(kicad_pcb
	(version 20260206)
	(generator "pcbnew")
	(generator_version "10.0")
	(general
		(thickness 1.6)
		(legacy_teardrops no)
	)
	(paper "A4")
	(layers
		(0 "F.Cu" signal "TOP")
		(4 "In1.Cu" signal "GND")
		(6 "In2.Cu" signal "IN1")
		(8 "In3.Cu" signal "GND1")
		(10 "In4.Cu" signal "IN2")
		(12 "In5.Cu" signal "GND2")
		(14 "In6.Cu" signal "IN3")
		(16 "In7.Cu" signal "GND3")
		(18 "In8.Cu" signal "VCC")
		(20 "In9.Cu" signal "VCC1")
		(22 "In10.Cu" signal "GND4")
		(24 "In11.Cu" signal "IN4")
		(26 "In12.Cu" signal "GND5")
		(28 "In13.Cu" signal "IN5")
		(30 "In14.Cu" signal "GND6")
		(32 "In15.Cu" signal "IN6")
		(34 "In16.Cu" signal "GND7")
		(2 "B.Cu" signal "BOTTOM")
		(9 "F.Adhes" user "F.Adhesive")
		(11 "B.Adhes" user "B.Adhesive")
		(13 "F.Paste" user "Package Geometry/Pastemask Top")
		(15 "B.Paste" user "Package Geometry/Pastemask Bottom")
		(5 "F.SilkS" user "Ref Des/Silkscreen Top")
		(7 "B.SilkS" user "Ref Des/Silkscreen Bottom")
		(1 "F.Mask" user "Board Geometry/Soldermask Top")
		(3 "B.Mask" user "Board Geometry/Soldermask Bottom")
		(17 "Dwgs.User" user "User.Drawings")
		(19 "Cmts.User" user "User.Comments")
		(21 "Eco1.User" user "User.Eco1")
		(23 "Eco2.User" user "User.Eco2")
		(25 "Edge.Cuts" user "Board Geometry/Outline")
		(27 "Margin" user)
		(31 "F.CrtYd" user "Package Geometry/Place Bound Top")
		(29 "B.CrtYd" user "Package Geometry/Place Bound Bottom")
		(35 "F.Fab" user "Ref Des/Assembly Top")
		(33 "B.Fab" user "Ref Des/Assembly Bottom")
	)
	(setup
		(pad_to_mask_clearance 0)
		(allow_soldermask_bridges_in_footprints no)
		(tenting
			(front yes)
			(back yes)
		)
		(covering
			(front no)
			(back no)
		)
		(plugging
			(front no)
			(back no)
		)
		(capping no)
		(filling no)
		(pcbplotparams
			(layerselection 0x00000000_00000000_55555555_5755f5ff)
			(plot_on_all_layers_selection 0x00000000_00000000_00000000_00000000)
			(disableapertmacros no)
			(usegerberextensions no)
			(usegerberattributes yes)
			(usegerberadvancedattributes yes)
			(creategerberjobfile yes)
			(dashed_line_dash_ratio 12)
			(dashed_line_gap_ratio 3)
			(svgprecision 4)
			(plotframeref no)
			(mode 1)
			(useauxorigin no)
			(pdf_front_fp_property_popups yes)
			(pdf_back_fp_property_popups yes)
			(pdf_metadata yes)
			(pdf_single_document no)
			(dxfpolygonmode yes)
			(dxfimperialunits yes)
			(dxfusepcbnewfont yes)
			(psnegative no)
			(psa4output no)
			(plot_black_and_white yes)
			(sketchpadsonfab no)
			(plotpadnumbers no)
			(hidednponfab no)
			(sketchdnponfab yes)
			(crossoutdnponfab yes)
			(subtractmaskfromsilk no)
			(outputformat 1)
			(mirror no)
			(drillshape 1)
			(scaleselection 1)
			(outputdirectory "")
		)
	)
	(gr_poly
		(pts
			(xy 390.64438 -264.965942) (xy 390.680194 -264.929874) (xy 390.494266 -264.743946) (xy 390.458452 -264.780014)
			(xy 390.412224 -264.877296) (xy 390.546844 -265.01217)
		)
		(stroke
			(width 0)
			(type solid)
		)
		(fill yes)
		(layer "F.Cu")
		(net "M_E_CPU0_SA_CB<2>")
	)
	(gr_poly
		(pts
			(xy 390.646666 -257.35534) (xy 390.682734 -257.319526) (xy 390.496806 -257.133598) (xy 390.460992 -257.169412)
			(xy 390.41451 -257.266948) (xy 390.549384 -257.401568)
		)
		(stroke
			(width 0)
			(type solid)
		)
		(fill yes)
		(layer "F.Cu")
		(net "M_E_CPU0_SA_CA<0>")
	)
	(gr_poly
		(pts
			(xy 390.652762 -228.73589) (xy 390.606534 -228.638354) (xy 390.57072 -228.60254) (xy 390.384792 -228.788468)
			(xy 390.420606 -228.824282) (xy 390.518142 -228.87051)
		)
		(stroke
			(width 0)
			(type solid)
		)
		(fill yes)
		(layer "F.Cu")
		(net "M_E_CPU0_SB_DQ<23>")
	)
	(gr_poly
		(pts
			(xy 390.653524 -264.112502) (xy 390.689592 -264.076688) (xy 390.503664 -263.89076) (xy 390.467596 -263.926574)
			(xy 390.421368 -264.02411) (xy 390.555988 -264.15873)
		)
		(stroke
			(width 0)
			(type solid)
		)
		(fill yes)
		(layer "F.Cu")
		(net "M_E_CPU0_SA_CB<3>")
	)
	(gr_poly
		(pts
			(xy 390.656064 -256.502154) (xy 390.691878 -256.466086) (xy 390.50595 -256.280158) (xy 390.470136 -256.316226)
			(xy 390.423908 -256.413508) (xy 390.558528 -256.548382)
		)
		(stroke
			(width 0)
			(type solid)
		)
		(fill yes)
		(layer "F.Cu")
		(net "M_E_CPU0_SA_CA<2>")
	)
	(gr_poly
		(pts
			(xy 390.66216 -229.58933) (xy 390.615932 -229.491794) (xy 390.579864 -229.45598) (xy 390.393936 -229.641908)
			(xy 390.430004 -229.677722) (xy 390.527286 -229.72395)
		)
		(stroke
			(width 0)
			(type solid)
		)
		(fill yes)
		(layer "F.Cu")
		(net "M_E_CPU0_SB_DQ<22>")
	)
	(gr_poly
		(pts
			(xy 390.665208 -255.648714) (xy 390.701022 -255.612646) (xy 390.515348 -255.426972) (xy 390.47928 -255.462786)
			(xy 390.433052 -255.560322) (xy 390.567672 -255.694942)
		)
		(stroke
			(width 0)
			(type solid)
		)
		(fill yes)
		(layer "F.Cu")
		(net "M_E_CPU0_SA_CA<4>")
	)
	(gr_poly
		(pts
			(xy 390.66851 -267.474192) (xy 390.704324 -267.438124) (xy 390.518396 -267.252196) (xy 390.482582 -267.288264)
			(xy 390.436354 -267.385546) (xy 390.570974 -267.52042)
		)
		(stroke
			(width 0)
			(type solid)
		)
		(fill yes)
		(layer "F.Cu")
		(net "M_E_CPU0_SA_DQ<28>")
	)
	(gr_poly
		(pts
			(xy 390.674352 -254.795274) (xy 390.71042 -254.75946) (xy 390.524492 -254.573532) (xy 390.488424 -254.609346)
			(xy 390.442196 -254.706882) (xy 390.57707 -254.841502)
		)
		(stroke
			(width 0)
			(type solid)
		)
		(fill yes)
		(layer "F.Cu")
		(net "M_E_CPU0_SA_CA<6>")
	)
	(gr_poly
		(pts
			(xy 390.677908 -266.620752) (xy 390.713722 -266.584684) (xy 390.527794 -266.398756) (xy 390.49198 -266.434824)
			(xy 390.445752 -266.532106) (xy 390.580372 -266.66698)
		)
		(stroke
			(width 0)
			(type solid)
		)
		(fill yes)
		(layer "F.Cu")
		(net "M_E_CPU0_SA_DQ<29>")
	)
	(gr_poly
		(pts
			(xy 390.68248 -278.53132) (xy 390.774936 -278.475948) (xy 390.737598 -278.289004) (xy 390.630918 -278.27351)
			(xy 390.581134 -278.283416) (xy 390.632696 -278.541226)
		)
		(stroke
			(width 0)
			(type solid)
		)
		(fill yes)
		(layer "F.Cu")
		(net "M_E_CPU0_SA_DQ<16>")
	)
	(gr_poly
		(pts
			(xy 390.689084 -232.150666) (xy 390.642602 -232.05313) (xy 390.606788 -232.017316) (xy 390.42086 -232.203244)
			(xy 390.456928 -232.239058) (xy 390.55421 -232.285286)
		)
		(stroke
			(width 0)
			(type solid)
		)
		(fill yes)
		(layer "F.Cu")
		(net "M_E_CPU0_SB_DQ<19>")
	)
	(gr_poly
		(pts
			(xy 390.690862 -273.122136) (xy 390.726676 -273.086322) (xy 390.540748 -272.900394) (xy 390.504934 -272.936208)
			(xy 390.458706 -273.033744) (xy 390.593326 -273.168364)
		)
		(stroke
			(width 0)
			(type solid)
		)
		(fill yes)
		(layer "F.Cu")
		(net "M_E_CPU0_SA_DQ<20>")
	)
	(gr_poly
		(pts
			(xy 390.691116 -278.833834) (xy 390.639554 -278.576024) (xy 390.58977 -278.586184) (xy 390.497314 -278.641556)
			(xy 390.534652 -278.828246) (xy 390.641332 -278.843994)
		)
		(stroke
			(width 0)
			(type solid)
		)
		(fill yes)
		(layer "F.Cu")
		(net "M_E_CPU0_SA_DQ<16>")
	)
	(gr_poly
		(pts
			(xy 390.69518 -225.009456) (xy 390.64438 -225.009456) (xy 390.54278 -225.045778) (xy 390.54278 -225.236278)
			(xy 390.64438 -225.272346) (xy 390.69518 -225.272346)
		)
		(stroke
			(width 0)
			(type solid)
		)
		(fill yes)
		(layer "F.Cu")
		(net "M_E_CPU0_SB_DQ<26>")
	)
	(gr_poly
		(pts
			(xy 390.69518 -224.412556) (xy 390.64438 -224.412556) (xy 390.54278 -224.448878) (xy 390.54278 -224.639378)
			(xy 390.64438 -224.675446) (xy 390.69518 -224.675446)
		)
		(stroke
			(width 0)
			(type solid)
		)
		(fill yes)
		(layer "F.Cu")
		(net "M_E_CPU0_SB_DQ<26>")
	)
	(gr_poly
		(pts
			(xy 390.69518 -223.815656) (xy 390.64438 -223.815656) (xy 390.54278 -223.851978) (xy 390.54278 -224.042478)
			(xy 390.64438 -224.078546) (xy 390.69518 -224.078546)
		)
		(stroke
			(width 0)
			(type solid)
		)
		(fill yes)
		(layer "F.Cu")
		(net "M_E_CPU0_SB_DQ<26>")
	)
	(gr_poly
		(pts
			(xy 390.69518 -223.218756) (xy 390.64438 -223.218756) (xy 390.54278 -223.255078) (xy 390.54278 -223.445578)
			(xy 390.64438 -223.481646) (xy 390.69518 -223.481646)
		)
		(stroke
			(width 0)
			(type solid)
		)
		(fill yes)
		(layer "F.Cu")
		(net "M_E_CPU0_SB_DQ<26>")
	)
	(gr_poly
		(pts
			(xy 390.69518 -222.621856) (xy 390.64438 -222.621856) (xy 390.54278 -222.658178) (xy 390.54278 -222.848678)
			(xy 390.64438 -222.884746) (xy 390.69518 -222.884746)
		)
		(stroke
			(width 0)
			(type solid)
		)
		(fill yes)
		(layer "F.Cu")
		(net "M_E_CPU0_SB_DQ<26>")
	)
	(gr_poly
		(pts
			(xy 390.69518 -222.024956) (xy 390.64438 -222.024956) (xy 390.54278 -222.061278) (xy 390.54278 -222.251778)
			(xy 390.64438 -222.287846) (xy 390.69518 -222.287846)
		)
		(stroke
			(width 0)
			(type solid)
		)
		(fill yes)
		(layer "F.Cu")
		(net "M_E_CPU0_SB_DQ<26>")
	)
	(gr_poly
		(pts
			(xy 390.69518 -221.428056) (xy 390.64438 -221.428056) (xy 390.54278 -221.464378) (xy 390.54278 -221.654878)
			(xy 390.64438 -221.690946) (xy 390.69518 -221.690946)
		)
		(stroke
			(width 0)
			(type solid)
		)
		(fill yes)
		(layer "F.Cu")
		(net "M_E_CPU0_SB_DQ<26>")
	)
	(gr_poly
		(pts
			(xy 390.69518 -220.831156) (xy 390.64438 -220.831156) (xy 390.54278 -220.867478) (xy 390.54278 -221.057978)
			(xy 390.64438 -221.094046) (xy 390.69518 -221.094046)
		)
		(stroke
			(width 0)
			(type solid)
		)
		(fill yes)
		(layer "F.Cu")
		(net "M_E_CPU0_SB_DQ<26>")
	)
	(gr_poly
		(pts
			(xy 390.69518 -220.234256) (xy 390.64438 -220.234256) (xy 390.54278 -220.270578) (xy 390.54278 -220.461078)
			(xy 390.64438 -220.497146) (xy 390.69518 -220.497146)
		)
		(stroke
			(width 0)
			(type solid)
		)
		(fill yes)
		(layer "F.Cu")
		(net "M_E_CPU0_SB_DQ<26>")
	)
	(gr_poly
		(pts
			(xy 390.69518 -219.637356) (xy 390.64438 -219.637356) (xy 390.54278 -219.673678) (xy 390.54278 -219.864178)
			(xy 390.64438 -219.900246) (xy 390.69518 -219.900246)
		)
		(stroke
			(width 0)
			(type solid)
		)
		(fill yes)
		(layer "F.Cu")
		(net "M_E_CPU0_SB_DQ<26>")
	)
	(gr_poly
		(pts
			(xy 390.69518 -219.040456) (xy 390.64438 -219.040456) (xy 390.54278 -219.076778) (xy 390.54278 -219.267278)
			(xy 390.64438 -219.303346) (xy 390.69518 -219.303346)
		)
		(stroke
			(width 0)
			(type solid)
		)
		(fill yes)
		(layer "F.Cu")
		(net "M_E_CPU0_SB_DQ<26>")
	)
	(gr_poly
		(pts
			(xy 390.69518 -218.443556) (xy 390.64438 -218.443556) (xy 390.54278 -218.479878) (xy 390.54278 -218.670378)
			(xy 390.64438 -218.706446) (xy 390.69518 -218.706446)
		)
		(stroke
			(width 0)
			(type solid)
		)
		(fill yes)
		(layer "F.Cu")
		(net "M_E_CPU0_SB_DQ<26>")
	)
	(gr_poly
		(pts
			(xy 390.69518 -217.846656) (xy 390.64438 -217.846656) (xy 390.54278 -217.882978) (xy 390.54278 -218.073478)
			(xy 390.64438 -218.109546) (xy 390.69518 -218.109546)
		)
		(stroke
			(width 0)
			(type solid)
		)
		(fill yes)
		(layer "F.Cu")
		(net "M_E_CPU0_SB_DQ<26>")
	)
	(gr_poly
		(pts
			(xy 390.69518 -217.249756) (xy 390.64438 -217.249756) (xy 390.54278 -217.286078) (xy 390.54278 -217.476578)
			(xy 390.64438 -217.512646) (xy 390.69518 -217.512646)
		)
		(stroke
			(width 0)
			(type solid)
		)
		(fill yes)
		(layer "F.Cu")
		(net "M_E_CPU0_SB_DQ<26>")
	)
	(gr_poly
		(pts
			(xy 390.69518 -216.652856) (xy 390.64438 -216.652856) (xy 390.54278 -216.689178) (xy 390.54278 -216.879678)
			(xy 390.64438 -216.915746) (xy 390.69518 -216.915746)
		)
		(stroke
			(width 0)
			(type solid)
		)
		(fill yes)
		(layer "F.Cu")
		(net "M_E_CPU0_SB_DQ<26>")
	)
	(gr_poly
		(pts
			(xy 390.69518 -216.055956) (xy 390.64438 -216.055956) (xy 390.54278 -216.092278) (xy 390.54278 -216.282778)
			(xy 390.64438 -216.318846) (xy 390.69518 -216.318846)
		)
		(stroke
			(width 0)
			(type solid)
		)
		(fill yes)
		(layer "F.Cu")
		(net "M_E_CPU0_SB_DQ<26>")
	)
	(gr_poly
		(pts
			(xy 390.698228 -233.004106) (xy 390.652 -232.90657) (xy 390.615932 -232.870756) (xy 390.430004 -233.056684)
			(xy 390.466072 -233.092498) (xy 390.563354 -233.138726)
		)
		(stroke
			(width 0)
			(type solid)
		)
		(fill yes)
		(layer "F.Cu")
		(net "M_E_CPU0_SB_DQ<18>")
	)
	(gr_poly
		(pts
			(xy 390.70026 -272.268442) (xy 390.736074 -272.232374) (xy 390.5504 -272.0467) (xy 390.514332 -272.082514)
			(xy 390.468104 -272.18005) (xy 390.602724 -272.31467)
		)
		(stroke
			(width 0)
			(type solid)
		)
		(fill yes)
		(layer "F.Cu")
		(net "M_E_CPU0_SA_DQ<21>")
	)
	(gr_poly
		(pts
			(xy 390.70153 -261.571994) (xy 390.737598 -261.53618) (xy 390.55167 -261.350252) (xy 390.515602 -261.386066)
			(xy 390.469374 -261.483602) (xy 390.604248 -261.618222)
		)
		(stroke
			(width 0)
			(type solid)
		)
		(fill yes)
		(layer "F.Cu")
		(net "M_E_CPU0_SA_CB<6>")
	)
	(gr_poly
		(pts
			(xy 390.704832 -258.563618) (xy 390.75106 -258.466082) (xy 390.61644 -258.331462) (xy 390.518904 -258.37769)
			(xy 390.48309 -258.413758) (xy 390.668764 -258.599432)
		)
		(stroke
			(width 0)
			(type solid)
		)
		(fill yes)
		(layer "F.Cu")
		(net "M_E_CPU0_SA_CS_N<2>")
	)
	(gr_poly
		(pts
			(xy 390.706864 -234.70108) (xy 390.660636 -234.603544) (xy 390.624822 -234.56773) (xy 390.438894 -234.753658)
			(xy 390.474708 -234.789472) (xy 390.572244 -234.8357)
		)
		(stroke
			(width 0)
			(type solid)
		)
		(fill yes)
		(layer "F.Cu")
		(net "M_E_CPU0_SB_DQ<13>")
	)
	(gr_poly
		(pts
			(xy 390.70915 -270.57096) (xy 390.745218 -270.535146) (xy 390.55929 -270.349218) (xy 390.523222 -270.385032)
			(xy 390.476994 -270.482568) (xy 390.611614 -270.617188)
		)
		(stroke
			(width 0)
			(type solid)
		)
		(fill yes)
		(layer "F.Cu")
		(net "M_E_CPU0_SA_DQ<26>")
	)
	(gr_poly
		(pts
			(xy 390.710928 -260.718554) (xy 390.746742 -260.68274) (xy 390.560814 -260.496812) (xy 390.525 -260.53288)
			(xy 390.478772 -260.630162) (xy 390.613392 -260.765036)
		)
		(stroke
			(width 0)
			(type solid)
		)
		(fill yes)
		(layer "F.Cu")
		(net "M_E_CPU0_SA_CB<7>")
	)
	(gr_poly
		(pts
			(xy 390.711436 -265.32078) (xy 390.757918 -265.223244) (xy 390.623044 -265.088624) (xy 390.525762 -265.134852)
			(xy 390.489694 -265.170666) (xy 390.675622 -265.356594)
		)
		(stroke
			(width 0)
			(type solid)
		)
		(fill yes)
		(layer "F.Cu")
		(net "M_E_CPU0_SA_CB<0>")
	)
	(gr_poly
		(pts
			(xy 390.713976 -257.710178) (xy 390.760204 -257.612896) (xy 390.625584 -257.478022) (xy 390.528048 -257.52425)
			(xy 390.492234 -257.560318) (xy 390.678162 -257.746246)
		)
		(stroke
			(width 0)
			(type solid)
		)
		(fill yes)
		(layer "F.Cu")
		(net "M_E_CPU0_SA_CS_N<3>")
	)
	(gr_poly
		(pts
			(xy 390.716262 -235.55452) (xy 390.670034 -235.456984) (xy 390.633966 -235.42117) (xy 390.448038 -235.607098)
			(xy 390.484106 -235.642912) (xy 390.581388 -235.68914)
		)
		(stroke
			(width 0)
			(type solid)
		)
		(fill yes)
		(layer "F.Cu")
		(net "M_E_CPU0_SB_DQ<12>")
	)
	(gr_poly
		(pts
			(xy 390.718294 -269.71752) (xy 390.754362 -269.681706) (xy 390.568434 -269.495778) (xy 390.532366 -269.531592)
			(xy 390.486138 -269.629128) (xy 390.620758 -269.763748)
		)
		(stroke
			(width 0)
			(type solid)
		)
		(fill yes)
		(layer "F.Cu")
		(net "M_E_CPU0_SA_DQ<27>")
	)
	(gr_poly
		(pts
			(xy 390.720834 -264.46734) (xy 390.767062 -264.369804) (xy 390.632442 -264.235184) (xy 390.534906 -264.281412)
			(xy 390.499092 -264.31748) (xy 390.684766 -264.503154)
		)
		(stroke
			(width 0)
			(type solid)
		)
		(fill yes)
		(layer "F.Cu")
		(net "M_E_CPU0_SA_CB<1>")
	)
	(gr_poly
		(pts
			(xy 390.72312 -256.856992) (xy 390.769348 -256.759456) (xy 390.634728 -256.624836) (xy 390.537446 -256.671064)
			(xy 390.501378 -256.706878) (xy 390.687306 -256.892806)
		)
		(stroke
			(width 0)
			(type solid)
		)
		(fill yes)
		(layer "F.Cu")
		(net "M_E_CPU0_SA_CA<1>")
	)
	(gr_poly
		(pts
			(xy 390.732518 -256.003552) (xy 390.778746 -255.906016) (xy 390.643872 -255.771396) (xy 390.54659 -255.817624)
			(xy 390.510522 -255.853438) (xy 390.69645 -256.039366)
		)
		(stroke
			(width 0)
			(type solid)
		)
		(fill yes)
		(layer "F.Cu")
		(net "M_E_CPU0_SA_CA<3>")
	)
	(gr_poly
		(pts
			(xy 390.741662 -255.150112) (xy 390.78789 -255.05283) (xy 390.65327 -254.917956) (xy 390.555734 -254.964184)
			(xy 390.51992 -255.000252) (xy 390.705848 -255.18618)
		)
		(stroke
			(width 0)
			(type solid)
		)
		(fill yes)
		(layer "F.Cu")
		(net "M_E_CPU0_SA_CA<5>")
	)
	(gr_poly
		(pts
			(xy 390.744964 -266.97559) (xy 390.791192 -266.878054) (xy 390.656572 -266.743434) (xy 390.559036 -266.789662)
			(xy 390.523222 -266.82573) (xy 390.708896 -267.011404)
		)
		(stroke
			(width 0)
			(type solid)
		)
		(fill yes)
		(layer "F.Cu")
		(net "M_E_CPU0_SA_DQ<30>")
	)
	(gr_poly
		(pts
			(xy 390.748266 -277.30069) (xy 390.840722 -277.245318) (xy 390.803384 -277.058628) (xy 390.696704 -277.043134)
			(xy 390.64692 -277.05304) (xy 390.698482 -277.31085)
		)
		(stroke
			(width 0)
			(type solid)
		)
		(fill yes)
		(layer "F.Cu")
		(net "M_E_CPU0_SA_DQ<18>")
	)
	(gr_poly
		(pts
			(xy 390.750806 -254.296672) (xy 390.797034 -254.19939) (xy 390.662414 -254.06477) (xy 390.564878 -254.110998)
			(xy 390.529064 -254.146812) (xy 390.714992 -254.33274)
		)
		(stroke
			(width 0)
			(type solid)
		)
		(fill yes)
		(layer "F.Cu")
		(net "M_E_CPU0_SA_PAR")
	)
	(gr_poly
		(pts
			(xy 390.754362 -266.121896) (xy 390.80059 -266.024614) (xy 390.66597 -265.88974) (xy 390.568434 -265.935968)
			(xy 390.53262 -265.972036) (xy 390.718548 -266.157964)
		)
		(stroke
			(width 0)
			(type solid)
		)
		(fill yes)
		(layer "F.Cu")
		(net "M_E_CPU0_SA_DQ<31>")
	)
	(gr_poly
		(pts
			(xy 390.756902 -277.603458) (xy 390.70534 -277.345648) (xy 390.655556 -277.355554) (xy 390.5631 -277.410926)
			(xy 390.600438 -277.59787) (xy 390.707118 -277.613364)
		)
		(stroke
			(width 0)
			(type solid)
		)
		(fill yes)
		(layer "F.Cu")
		(net "M_E_CPU0_SA_DQ<18>")
	)
	(gr_poly
		(pts
			(xy 390.76757 -272.62328) (xy 390.813798 -272.525744) (xy 390.679178 -272.391124) (xy 390.581642 -272.437352)
			(xy 390.545828 -272.47342) (xy 390.731502 -272.659094)
		)
		(stroke
			(width 0)
			(type solid)
		)
		(fill yes)
		(layer "F.Cu")
		(net "M_E_CPU0_SA_DQ<22>")
	)
	(gr_poly
		(pts
			(xy 390.76884 -261.926832) (xy 390.815068 -261.82955) (xy 390.680448 -261.694676) (xy 390.582912 -261.740904)
			(xy 390.547098 -261.776972) (xy 390.733026 -261.9629)
		)
		(stroke
			(width 0)
			(type solid)
		)
		(fill yes)
		(layer "F.Cu")
		(net "M_E_CPU0_SA_CB<4>")
	)
	(gr_poly
		(pts
			(xy 390.77646 -270.925798) (xy 390.822688 -270.828262) (xy 390.688068 -270.693642) (xy 390.590532 -270.73987)
			(xy 390.554718 -270.775938) (xy 390.740392 -270.961612)
		)
		(stroke
			(width 0)
			(type solid)
		)
		(fill yes)
		(layer "F.Cu")
		(net "M_E_CPU0_SA_DQ<24>")
	)
	(gr_poly
		(pts
			(xy 390.776714 -271.76984) (xy 390.822942 -271.672304) (xy 390.688322 -271.537684) (xy 390.59104 -271.583912)
			(xy 390.554972 -271.619726) (xy 390.7409 -271.805654)
		)
		(stroke
			(width 0)
			(type solid)
		)
		(fill yes)
		(layer "F.Cu")
		(net "M_E_CPU0_SA_DQ<23>")
	)
	(gr_poly
		(pts
			(xy 390.777984 -261.073392) (xy 390.824212 -260.97611) (xy 390.689592 -260.84149) (xy 390.592056 -260.887718)
			(xy 390.556242 -260.923532) (xy 390.74217 -261.10946)
		)
		(stroke
			(width 0)
			(type solid)
		)
		(fill yes)
		(layer "F.Cu")
		(net "M_E_CPU0_SA_CB<5>")
	)
	(gr_poly
		(pts
			(xy 390.785604 -270.072358) (xy 390.831832 -269.974822) (xy 390.697212 -269.840202) (xy 390.599676 -269.88643)
			(xy 390.563862 -269.922498) (xy 390.74979 -270.108426)
		)
		(stroke
			(width 0)
			(type solid)
		)
		(fill yes)
		(layer "F.Cu")
		(net "M_E_CPU0_SA_DQ<25>")
	)
	(gr_poly
		(pts
			(xy 390.790938 -229.244906) (xy 390.755124 -229.209092) (xy 390.657588 -229.16261) (xy 390.522968 -229.297484)
			(xy 390.569196 -229.394766) (xy 390.60501 -229.430834)
		)
		(stroke
			(width 0)
			(type solid)
		)
		(fill yes)
		(layer "F.Cu")
		(net "M_E_CPU0_SB_DQ<22>")
	)
	(gr_poly
		(pts
			(xy 390.79932 -279.116536) (xy 390.89203 -279.061164) (xy 390.854438 -278.874474) (xy 390.747758 -278.858726)
			(xy 390.697974 -278.868886) (xy 390.749536 -279.126696)
		)
		(stroke
			(width 0)
			(type solid)
		)
		(fill yes)
		(layer "F.Cu")
		(net "M_E_CPU0_SA_DQ<16>")
	)
	(gr_poly
		(pts
			(xy 390.79932 -249.069352) (xy 390.79932 -249.018552) (xy 390.536176 -249.018552) (xy 390.536176 -249.069352)
			(xy 390.572498 -249.170952) (xy 390.762998 -249.170952)
		)
		(stroke
			(width 0)
			(type solid)
		)
		(fill yes)
		(layer "F.Cu")
		(net "M_E_CPU0_SB_CA<0>")
	)
	(gr_poly
		(pts
			(xy 390.79932 -248.764552) (xy 390.79932 -248.713752) (xy 390.536176 -248.713752) (xy 390.536176 -248.764552)
			(xy 390.572498 -248.866152) (xy 390.762998 -248.866152)
		)
		(stroke
			(width 0)
			(type solid)
		)
		(fill yes)
		(layer "F.Cu")
		(net "M_E_CPU0_SB_CA<1>")
	)
	(gr_poly
		(pts
			(xy 390.79932 -248.459752) (xy 390.79932 -248.408952) (xy 390.536176 -248.408952) (xy 390.536176 -248.459752)
			(xy 390.572498 -248.561352) (xy 390.762998 -248.561352)
		)
		(stroke
			(width 0)
			(type solid)
		)
		(fill yes)
		(layer "F.Cu")
		(net "M_E_CPU0_SB_CA<2>")
	)
	(gr_poly
		(pts
			(xy 390.79932 -248.154952) (xy 390.79932 -248.104152) (xy 390.536176 -248.104152) (xy 390.536176 -248.154952)
			(xy 390.572498 -248.256552) (xy 390.762998 -248.256552)
		)
		(stroke
			(width 0)
			(type solid)
		)
		(fill yes)
		(layer "F.Cu")
		(net "M_E_CPU0_SB_CA<3>")
	)
	(gr_poly
		(pts
			(xy 390.79932 -247.850152) (xy 390.79932 -247.799352) (xy 390.536176 -247.799352) (xy 390.536176 -247.850152)
			(xy 390.572498 -247.951752) (xy 390.762998 -247.951752)
		)
		(stroke
			(width 0)
			(type solid)
		)
		(fill yes)
		(layer "F.Cu")
		(net "M_E_CPU0_SB_CA<4>")
	)
	(gr_poly
		(pts
			(xy 390.79932 -247.545352) (xy 390.79932 -247.494552) (xy 390.536176 -247.494552) (xy 390.536176 -247.545352)
			(xy 390.572498 -247.646952) (xy 390.762998 -247.646952)
		)
		(stroke
			(width 0)
			(type solid)
		)
		(fill yes)
		(layer "F.Cu")
		(net "M_E_CPU0_SB_CA<5>")
	)
	(gr_poly
		(pts
			(xy 390.79932 -247.240552) (xy 390.79932 -247.189752) (xy 390.536176 -247.189752) (xy 390.536176 -247.240552)
			(xy 390.572498 -247.342152) (xy 390.762998 -247.342152)
		)
		(stroke
			(width 0)
			(type solid)
		)
		(fill yes)
		(layer "F.Cu")
		(net "M_E_CPU0_SB_CA<6>")
	)
	(gr_poly
		(pts
			(xy 390.79932 -246.935752) (xy 390.79932 -246.884952) (xy 390.536176 -246.884952) (xy 390.536176 -246.935752)
			(xy 390.572498 -247.037352) (xy 390.762998 -247.037352)
		)
		(stroke
			(width 0)
			(type solid)
		)
		(fill yes)
		(layer "F.Cu")
		(net "M_E_CPU0_SB_PAR")
	)
	(gr_poly
		(pts
			(xy 390.79932 -246.630952) (xy 390.79932 -246.580152) (xy 390.536176 -246.580152) (xy 390.536176 -246.630952)
			(xy 390.572498 -246.732552) (xy 390.762998 -246.732552)
		)
		(stroke
			(width 0)
			(type solid)
		)
		(fill yes)
		(layer "F.Cu")
		(net "M_E_CPU0_SB_CS_N<0>")
	)
	(gr_poly
		(pts
			(xy 390.79932 -246.326152) (xy 390.79932 -246.275352) (xy 390.536176 -246.275352) (xy 390.536176 -246.326152)
			(xy 390.572498 -246.427752) (xy 390.762998 -246.427752)
		)
		(stroke
			(width 0)
			(type solid)
		)
		(fill yes)
		(layer "F.Cu")
		(net "M_E_CPU0_SB_CS_N<2>")
	)
	(gr_poly
		(pts
			(xy 390.79932 -246.021352) (xy 390.79932 -245.970552) (xy 390.536176 -245.970552) (xy 390.536176 -246.021352)
			(xy 390.572498 -246.122952) (xy 390.762998 -246.122952)
		)
		(stroke
			(width 0)
			(type solid)
		)
		(fill yes)
		(layer "F.Cu")
		(net "M_E_CPU0_SB_CS_N<1>")
	)
	(gr_poly
		(pts
			(xy 390.807956 -279.419304) (xy 390.756394 -279.161494) (xy 390.70661 -279.1714) (xy 390.614154 -279.226772)
			(xy 390.651492 -279.413716) (xy 390.758172 -279.42921)
		)
		(stroke
			(width 0)
			(type solid)
		)
		(fill yes)
		(layer "F.Cu")
		(net "M_E_CPU0_SA_DQ<16>")
	)
	(gr_poly
		(pts
			(xy 390.813544 -276.070314) (xy 390.906254 -276.014942) (xy 390.868916 -275.828252) (xy 390.762236 -275.812504)
			(xy 390.712198 -275.82241) (xy 390.76376 -276.08022)
		)
		(stroke
			(width 0)
			(type solid)
		)
		(fill yes)
		(layer "F.Cu")
		(net "M_E_CPU0_SA_DQ<17>")
	)
	(gr_poly
		(pts
			(xy 390.817862 -231.806242) (xy 390.781794 -231.770428) (xy 390.684512 -231.7242) (xy 390.549892 -231.85882)
			(xy 390.59612 -231.956356) (xy 390.631934 -231.99217)
		)
		(stroke
			(width 0)
			(type solid)
		)
		(fill yes)
		(layer "F.Cu")
		(net "M_E_CPU0_SB_DQ<19>")
	)
	(gr_poly
		(pts
			(xy 390.822434 -276.373082) (xy 390.770872 -276.115272) (xy 390.721088 -276.125178) (xy 390.628378 -276.18055)
			(xy 390.665716 -276.367494) (xy 390.77265 -276.382988)
		)
		(stroke
			(width 0)
			(type solid)
		)
		(fill yes)
		(layer "F.Cu")
		(net "M_E_CPU0_SA_DQ<17>")
	)
	(gr_poly
		(pts
			(xy 390.827006 -232.659682) (xy 390.791192 -232.623614) (xy 390.693656 -232.577386) (xy 390.559036 -232.71226)
			(xy 390.605264 -232.809542) (xy 390.641078 -232.84561)
		)
		(stroke
			(width 0)
			(type solid)
		)
		(fill yes)
		(layer "F.Cu")
		(net "M_E_CPU0_SB_DQ<18>")
	)
	(gr_poly
		(pts
			(xy 390.835896 -234.356656) (xy 390.799828 -234.320842) (xy 390.702546 -234.274614) (xy 390.567672 -234.409234)
			(xy 390.6139 -234.50677) (xy 390.649968 -234.542584)
		)
		(stroke
			(width 0)
			(type solid)
		)
		(fill yes)
		(layer "F.Cu")
		(net "M_E_CPU0_SB_DQ<13>")
	)
	(gr_poly
		(pts
			(xy 390.844024 -258.846574) (xy 390.879838 -258.810506) (xy 390.69391 -258.624578) (xy 390.658096 -258.660646)
			(xy 390.611868 -258.757928) (xy 390.746488 -258.892802)
		)
		(stroke
			(width 0)
			(type solid)
		)
		(fill yes)
		(layer "F.Cu")
		(net "M_E_CPU0_SA_CS_N<2>")
	)
	(gr_poly
		(pts
			(xy 390.84504 -235.210096) (xy 390.809226 -235.174282) (xy 390.71169 -235.1278) (xy 390.57707 -235.262674)
			(xy 390.623298 -235.359956) (xy 390.659112 -235.396024)
		)
		(stroke
			(width 0)
			(type solid)
		)
		(fill yes)
		(layer "F.Cu")
		(net "M_E_CPU0_SB_DQ<12>")
	)
	(gr_poly
		(pts
			(xy 390.84758 -224.937574) (xy 390.84758 -224.747074) (xy 390.74598 -224.711006) (xy 390.69518 -224.711006)
			(xy 390.69518 -224.973896) (xy 390.74598 -224.973896)
		)
		(stroke
			(width 0)
			(type solid)
		)
		(fill yes)
		(layer "F.Cu")
		(net "M_E_CPU0_SB_DQ<26>")
	)
	(gr_poly
		(pts
			(xy 390.84758 -224.340674) (xy 390.84758 -224.150174) (xy 390.74598 -224.114106) (xy 390.69518 -224.114106)
			(xy 390.69518 -224.376996) (xy 390.74598 -224.376996)
		)
		(stroke
			(width 0)
			(type solid)
		)
		(fill yes)
		(layer "F.Cu")
		(net "M_E_CPU0_SB_DQ<26>")
	)
	(gr_poly
		(pts
			(xy 390.84758 -223.743774) (xy 390.84758 -223.553274) (xy 390.74598 -223.517206) (xy 390.69518 -223.517206)
			(xy 390.69518 -223.780096) (xy 390.74598 -223.780096)
		)
		(stroke
			(width 0)
			(type solid)
		)
		(fill yes)
		(layer "F.Cu")
		(net "M_E_CPU0_SB_DQ<26>")
	)
	(gr_poly
		(pts
			(xy 390.84758 -223.146874) (xy 390.84758 -222.956374) (xy 390.74598 -222.920306) (xy 390.69518 -222.920306)
			(xy 390.69518 -223.183196) (xy 390.74598 -223.183196)
		)
		(stroke
			(width 0)
			(type solid)
		)
		(fill yes)
		(layer "F.Cu")
		(net "M_E_CPU0_SB_DQ<26>")
	)
	(gr_poly
		(pts
			(xy 390.84758 -222.549974) (xy 390.84758 -222.359474) (xy 390.74598 -222.323406) (xy 390.69518 -222.323406)
			(xy 390.69518 -222.586296) (xy 390.74598 -222.586296)
		)
		(stroke
			(width 0)
			(type solid)
		)
		(fill yes)
		(layer "F.Cu")
		(net "M_E_CPU0_SB_DQ<26>")
	)
	(gr_poly
		(pts
			(xy 390.84758 -221.953074) (xy 390.84758 -221.762574) (xy 390.74598 -221.726506) (xy 390.69518 -221.726506)
			(xy 390.69518 -221.989396) (xy 390.74598 -221.989396)
		)
		(stroke
			(width 0)
			(type solid)
		)
		(fill yes)
		(layer "F.Cu")
		(net "M_E_CPU0_SB_DQ<26>")
	)
	(gr_poly
		(pts
			(xy 390.84758 -221.356174) (xy 390.84758 -221.165674) (xy 390.74598 -221.129606) (xy 390.69518 -221.129606)
			(xy 390.69518 -221.392496) (xy 390.74598 -221.392496)
		)
		(stroke
			(width 0)
			(type solid)
		)
		(fill yes)
		(layer "F.Cu")
		(net "M_E_CPU0_SB_DQ<26>")
	)
	(gr_poly
		(pts
			(xy 390.84758 -220.759274) (xy 390.84758 -220.568774) (xy 390.74598 -220.532706) (xy 390.69518 -220.532706)
			(xy 390.69518 -220.795596) (xy 390.74598 -220.795596)
		)
		(stroke
			(width 0)
			(type solid)
		)
		(fill yes)
		(layer "F.Cu")
		(net "M_E_CPU0_SB_DQ<26>")
	)
	(gr_poly
		(pts
			(xy 390.84758 -220.162374) (xy 390.84758 -219.971874) (xy 390.74598 -219.935806) (xy 390.69518 -219.935806)
			(xy 390.69518 -220.198696) (xy 390.74598 -220.198696)
		)
		(stroke
			(width 0)
			(type solid)
		)
		(fill yes)
		(layer "F.Cu")
		(net "M_E_CPU0_SB_DQ<26>")
	)
	(gr_poly
		(pts
			(xy 390.84758 -219.565474) (xy 390.84758 -219.374974) (xy 390.74598 -219.338906) (xy 390.69518 -219.338906)
			(xy 390.69518 -219.601796) (xy 390.74598 -219.601796)
		)
		(stroke
			(width 0)
			(type solid)
		)
		(fill yes)
		(layer "F.Cu")
		(net "M_E_CPU0_SB_DQ<26>")
	)
	(gr_poly
		(pts
			(xy 390.84758 -218.968574) (xy 390.84758 -218.778074) (xy 390.74598 -218.742006) (xy 390.69518 -218.742006)
			(xy 390.69518 -219.004896) (xy 390.74598 -219.004896)
		)
		(stroke
			(width 0)
			(type solid)
		)
		(fill yes)
		(layer "F.Cu")
		(net "M_E_CPU0_SB_DQ<26>")
	)
	(gr_poly
		(pts
			(xy 390.84758 -218.371674) (xy 390.84758 -218.181174) (xy 390.74598 -218.145106) (xy 390.69518 -218.145106)
			(xy 390.69518 -218.407996) (xy 390.74598 -218.407996)
		)
		(stroke
			(width 0)
			(type solid)
		)
		(fill yes)
		(layer "F.Cu")
		(net "M_E_CPU0_SB_DQ<26>")
	)
	(gr_poly
		(pts
			(xy 390.84758 -217.774774) (xy 390.84758 -217.584274) (xy 390.74598 -217.548206) (xy 390.69518 -217.548206)
			(xy 390.69518 -217.811096) (xy 390.74598 -217.811096)
		)
		(stroke
			(width 0)
			(type solid)
		)
		(fill yes)
		(layer "F.Cu")
		(net "M_E_CPU0_SB_DQ<26>")
	)
	(gr_poly
		(pts
			(xy 390.84758 -217.177874) (xy 390.84758 -216.987374) (xy 390.74598 -216.951306) (xy 390.69518 -216.951306)
			(xy 390.69518 -217.214196) (xy 390.74598 -217.214196)
		)
		(stroke
			(width 0)
			(type solid)
		)
		(fill yes)
		(layer "F.Cu")
		(net "M_E_CPU0_SB_DQ<26>")
	)
	(gr_poly
		(pts
			(xy 390.84758 -216.580974) (xy 390.84758 -216.390474) (xy 390.74598 -216.354406) (xy 390.69518 -216.354406)
			(xy 390.69518 -216.617296) (xy 390.74598 -216.617296)
		)
		(stroke
			(width 0)
			(type solid)
		)
		(fill yes)
		(layer "F.Cu")
		(net "M_E_CPU0_SB_DQ<26>")
	)
	(gr_poly
		(pts
			(xy 390.84758 -215.984074) (xy 390.84758 -215.793574) (xy 390.74598 -215.757506) (xy 390.69518 -215.757506)
			(xy 390.69518 -216.020396) (xy 390.74598 -216.020396)
		)
		(stroke
			(width 0)
			(type solid)
		)
		(fill yes)
		(layer "F.Cu")
		(net "M_E_CPU0_SB_DQ<26>")
	)
	(gr_poly
		(pts
			(xy 390.850882 -265.603482) (xy 390.886696 -265.567668) (xy 390.700768 -265.38174) (xy 390.664954 -265.417554)
			(xy 390.618726 -265.51509) (xy 390.753346 -265.64971)
		)
		(stroke
			(width 0)
			(type solid)
		)
		(fill yes)
		(layer "F.Cu")
		(net "M_E_CPU0_SA_CB<0>")
	)
	(gr_poly
		(pts
			(xy 390.853168 -257.993134) (xy 390.889236 -257.95732) (xy 390.703308 -257.771392) (xy 390.66724 -257.807206)
			(xy 390.621012 -257.904742) (xy 390.755886 -258.039362)
		)
		(stroke
			(width 0)
			(type solid)
		)
		(fill yes)
		(layer "F.Cu")
		(net "M_E_CPU0_SA_CS_N<3>")
	)
	(gr_poly
		(pts
			(xy 390.860026 -264.750296) (xy 390.89584 -264.714228) (xy 390.709912 -264.5283) (xy 390.674098 -264.564368)
			(xy 390.62787 -264.66165) (xy 390.76249 -264.796524)
		)
		(stroke
			(width 0)
			(type solid)
		)
		(fill yes)
		(layer "F.Cu")
		(net "M_E_CPU0_SA_CB<1>")
	)
	(gr_poly
		(pts
			(xy 390.862058 -275.312632) (xy 390.908286 -275.215096) (xy 390.773666 -275.080476) (xy 390.67613 -275.126704)
			(xy 390.640316 -275.162772) (xy 390.82599 -275.348446)
		)
		(stroke
			(width 0)
			(type solid)
		)
		(fill yes)
		(layer "F.Cu")
		(net "M_E_CPU0_SA_DQ<19>")
	)
	(gr_poly
		(pts
			(xy 390.862312 -257.139694) (xy 390.89838 -257.10388) (xy 390.712452 -256.917952) (xy 390.676638 -256.953766)
			(xy 390.630156 -257.051302) (xy 390.76503 -257.185922)
		)
		(stroke
			(width 0)
			(type solid)
		)
		(fill yes)
		(layer "F.Cu")
		(net "M_E_CPU0_SA_CA<1>")
	)
	(gr_poly
		(pts
			(xy 390.86536 -277.88616) (xy 390.957816 -277.830788) (xy 390.920478 -277.643844) (xy 390.813798 -277.62835)
			(xy 390.764014 -277.638256) (xy 390.815576 -277.896066)
		)
		(stroke
			(width 0)
			(type solid)
		)
		(fill yes)
		(layer "F.Cu")
		(net "M_E_CPU0_SA_DQ<18>")
	)
	(gr_poly
		(pts
			(xy 390.868408 -228.951536) (xy 390.82218 -228.854) (xy 390.786366 -228.818186) (xy 390.600438 -229.004114)
			(xy 390.636252 -229.039928) (xy 390.733788 -229.086156)
		)
		(stroke
			(width 0)
			(type solid)
		)
		(fill yes)
		(layer "F.Cu")
		(net "M_E_CPU0_SB_DQ<21>")
	)
	(gr_poly
		(pts
			(xy 390.869932 -237.772956) (xy 390.834118 -237.737142) (xy 390.736582 -237.690914) (xy 390.601962 -237.825534)
			(xy 390.64819 -237.92307) (xy 390.684004 -237.958884)
		)
		(stroke
			(width 0)
			(type solid)
		)
		(fill yes)
		(layer "F.Cu")
		(net "M_E_CPU0_SB_DQ<9>")
	)
	(gr_poly
		(pts
			(xy 390.87171 -256.286508) (xy 390.907524 -256.25044) (xy 390.721596 -256.064512) (xy 390.685782 -256.10058)
			(xy 390.639554 -256.197862) (xy 390.774174 -256.332736)
		)
		(stroke
			(width 0)
			(type solid)
		)
		(fill yes)
		(layer "F.Cu")
		(net "M_E_CPU0_SA_CA<3>")
	)
	(gr_poly
		(pts
			(xy 390.873996 -278.188674) (xy 390.822434 -277.930864) (xy 390.77265 -277.941024) (xy 390.680194 -277.996396)
			(xy 390.717532 -278.183086) (xy 390.824212 -278.19858)
		)
		(stroke
			(width 0)
			(type solid)
		)
		(fill yes)
		(layer "F.Cu")
		(net "M_E_CPU0_SA_DQ<18>")
	)
	(gr_poly
		(pts
			(xy 390.877806 -229.804976) (xy 390.831578 -229.70744) (xy 390.79551 -229.671626) (xy 390.609582 -229.857554)
			(xy 390.64565 -229.893368) (xy 390.742932 -229.939596)
		)
		(stroke
			(width 0)
			(type solid)
		)
		(fill yes)
		(layer "F.Cu")
		(net "M_E_CPU0_SB_DQ<20>")
	)
	(gr_poly
		(pts
			(xy 390.880854 -255.433068) (xy 390.916668 -255.397) (xy 390.730994 -255.211326) (xy 390.694926 -255.24714)
			(xy 390.648698 -255.344676) (xy 390.783318 -255.479296)
		)
		(stroke
			(width 0)
			(type solid)
		)
		(fill yes)
		(layer "F.Cu")
		(net "M_E_CPU0_SA_CA<5>")
	)
	(gr_poly
		(pts
			(xy 390.884156 -267.258546) (xy 390.91997 -267.222478) (xy 390.734042 -267.03655) (xy 390.698228 -267.072618)
			(xy 390.652 -267.1699) (xy 390.78662 -267.304774)
		)
		(stroke
			(width 0)
			(type solid)
		)
		(fill yes)
		(layer "F.Cu")
		(net "M_E_CPU0_SA_DQ<30>")
	)
	(gr_poly
		(pts
			(xy 390.889998 -254.579628) (xy 390.926066 -254.543814) (xy 390.740138 -254.357886) (xy 390.70407 -254.3937)
			(xy 390.657842 -254.491236) (xy 390.792716 -254.625856)
		)
		(stroke
			(width 0)
			(type solid)
		)
		(fill yes)
		(layer "F.Cu")
		(net "M_E_CPU0_SA_PAR")
	)
	(gr_poly
		(pts
			(xy 390.893554 -266.404852) (xy 390.929622 -266.369038) (xy 390.743694 -266.18311) (xy 390.707626 -266.218924)
			(xy 390.661398 -266.31646) (xy 390.796272 -266.45108)
		)
		(stroke
			(width 0)
			(type solid)
		)
		(fill yes)
		(layer "F.Cu")
		(net "M_E_CPU0_SA_DQ<31>")
	)
	(gr_poly
		(pts
			(xy 390.89838 -240.26114) (xy 390.89838 -240.21034) (xy 390.63549 -240.21034) (xy 390.63549 -240.26114)
			(xy 390.671812 -240.36274) (xy 390.862312 -240.36274)
		)
		(stroke
			(width 0)
			(type solid)
		)
		(fill yes)
		(layer "F.Cu")
		(net "M_E_CPU0_SB_CB<0>")
	)
	(gr_poly
		(pts
			(xy 390.89838 -239.95634) (xy 390.89838 -239.90554) (xy 390.63549 -239.90554) (xy 390.63549 -239.95634)
			(xy 390.671812 -240.05794) (xy 390.862312 -240.05794)
		)
		(stroke
			(width 0)
			(type solid)
		)
		(fill yes)
		(layer "F.Cu")
		(net "M_E_CPU0_SB_CB<2>")
	)
	(gr_poly
		(pts
			(xy 390.89838 -239.65154) (xy 390.89838 -239.60074) (xy 390.63549 -239.60074) (xy 390.63549 -239.65154)
			(xy 390.671812 -239.75314) (xy 390.862312 -239.75314)
		)
		(stroke
			(width 0)
			(type solid)
		)
		(fill yes)
		(layer "F.Cu")
		(net "M_E_CPU0_SB_CB<1>")
	)
	(gr_poly
		(pts
			(xy 390.89838 -239.34674) (xy 390.89838 -239.29594) (xy 390.63549 -239.29594) (xy 390.63549 -239.34674)
			(xy 390.671812 -239.44834) (xy 390.862312 -239.44834)
		)
		(stroke
			(width 0)
			(type solid)
		)
		(fill yes)
		(layer "F.Cu")
		(net "M_E_CPU0_SB_CB<3>")
	)
	(gr_poly
		(pts
			(xy 390.90473 -232.366312) (xy 390.858248 -232.268776) (xy 390.822434 -232.232962) (xy 390.636506 -232.41889)
			(xy 390.672574 -232.454704) (xy 390.769856 -232.500932)
		)
		(stroke
			(width 0)
			(type solid)
		)
		(fill yes)
		(layer "F.Cu")
		(net "M_E_CPU0_SB_DQ<17>")
	)
	(gr_poly
		(pts
			(xy 390.906762 -272.906236) (xy 390.942576 -272.870168) (xy 390.756648 -272.68424) (xy 390.720834 -272.720308)
			(xy 390.674606 -272.81759) (xy 390.809226 -272.952464)
		)
		(stroke
			(width 0)
			(type solid)
		)
		(fill yes)
		(layer "F.Cu")
		(net "M_E_CPU0_SA_DQ<22>")
	)
	(gr_poly
		(pts
			(xy 390.908032 -262.209788) (xy 390.943846 -262.17372) (xy 390.758172 -261.988046) (xy 390.722104 -262.02386)
			(xy 390.675876 -262.121396) (xy 390.810496 -262.256016)
		)
		(stroke
			(width 0)
			(type solid)
		)
		(fill yes)
		(layer "F.Cu")
		(net "M_E_CPU0_SA_CB<4>")
	)
	(gr_poly
		(pts
			(xy 390.91108 -259.201412) (xy 390.957308 -259.10413) (xy 390.822688 -258.969256) (xy 390.725152 -259.015484)
			(xy 390.689338 -259.051552) (xy 390.875266 -259.23748)
		)
		(stroke
			(width 0)
			(type solid)
		)
		(fill yes)
		(layer "F.Cu")
		(net "M_E_CPU0_SA_CS_N<0>")
	)
	(gr_poly
		(pts
			(xy 390.913366 -234.063286) (xy 390.867138 -233.966004) (xy 390.831324 -233.929936) (xy 390.645396 -234.115864)
			(xy 390.68121 -234.151932) (xy 390.778746 -234.19816)
		)
		(stroke
			(width 0)
			(type solid)
		)
		(fill yes)
		(layer "F.Cu")
		(net "M_E_CPU0_SB_DQ<15>")
	)
	(gr_poly
		(pts
			(xy 390.913874 -233.219752) (xy 390.867646 -233.122216) (xy 390.831578 -233.086402) (xy 390.64565 -233.27233)
			(xy 390.681718 -233.308144) (xy 390.779 -233.354372)
		)
		(stroke
			(width 0)
			(type solid)
		)
		(fill yes)
		(layer "F.Cu")
		(net "M_E_CPU0_SB_DQ<16>")
	)
	(gr_poly
		(pts
			(xy 390.915652 -271.208754) (xy 390.951466 -271.172686) (xy 390.765538 -270.986758) (xy 390.729724 -271.022826)
			(xy 390.683496 -271.120362) (xy 390.818116 -271.254982)
		)
		(stroke
			(width 0)
			(type solid)
		)
		(fill yes)
		(layer "F.Cu")
		(net "M_E_CPU0_SA_DQ<24>")
	)
	(gr_poly
		(pts
			(xy 390.915906 -272.052542) (xy 390.951974 -272.016728) (xy 390.766046 -271.8308) (xy 390.730232 -271.866614)
			(xy 390.68375 -271.96415) (xy 390.818624 -272.09877)
		)
		(stroke
			(width 0)
			(type solid)
		)
		(fill yes)
		(layer "F.Cu")
		(net "M_E_CPU0_SA_DQ<23>")
	)
	(gr_poly
		(pts
			(xy 390.91616 -279.702006) (xy 391.00887 -279.646634) (xy 390.971532 -279.45969) (xy 390.864598 -279.444196)
			(xy 390.814814 -279.454102) (xy 390.866376 -279.711912)
		)
		(stroke
			(width 0)
			(type solid)
		)
		(fill yes)
		(layer "F.Cu")
		(net "M_E_CPU0_SA_DQ<16>")
	)
	(gr_poly
		(pts
			(xy 390.917176 -261.356348) (xy 390.953244 -261.320534) (xy 390.767316 -261.134606) (xy 390.731248 -261.17042)
			(xy 390.68502 -261.267956) (xy 390.819894 -261.402576)
		)
		(stroke
			(width 0)
			(type solid)
		)
		(fill yes)
		(layer "F.Cu")
		(net "M_E_CPU0_SA_CB<5>")
	)
	(gr_poly
		(pts
			(xy 390.920478 -258.347972) (xy 390.966706 -258.250436) (xy 390.832086 -258.115816) (xy 390.73455 -258.162044)
			(xy 390.698736 -258.198112) (xy 390.88441 -258.383786)
		)
		(stroke
			(width 0)
			(type solid)
		)
		(fill yes)
		(layer "F.Cu")
		(net "M_E_CPU0_SA_CS_N<1>")
	)
	(gr_poly
		(pts
			(xy 390.92251 -234.916726) (xy 390.876282 -234.81919) (xy 390.840468 -234.783376) (xy 390.65454 -234.969304)
			(xy 390.690354 -235.005118) (xy 390.78789 -235.051346)
		)
		(stroke
			(width 0)
			(type solid)
		)
		(fill yes)
		(layer "F.Cu")
		(net "M_E_CPU0_SB_DQ<14>")
	)
	(gr_poly
		(pts
			(xy 390.924796 -280.00452) (xy 390.873234 -279.74671) (xy 390.82345 -279.75687) (xy 390.730994 -279.812242)
			(xy 390.768332 -279.998932) (xy 390.875012 -280.01468)
		)
		(stroke
			(width 0)
			(type solid)
		)
		(fill yes)
		(layer "F.Cu")
		(net "M_E_CPU0_SA_DQ<16>")
	)
	(gr_poly
		(pts
			(xy 390.924796 -270.355314) (xy 390.96061 -270.319246) (xy 390.774936 -270.133572) (xy 390.738868 -270.169386)
			(xy 390.69264 -270.266922) (xy 390.82726 -270.401542)
		)
		(stroke
			(width 0)
			(type solid)
		)
		(fill yes)
		(layer "F.Cu")
		(net "M_E_CPU0_SA_DQ<25>")
	)
	(gr_poly
		(pts
			(xy 390.927082 -265.105134) (xy 390.973564 -265.007598) (xy 390.83869 -264.872978) (xy 390.741408 -264.919206)
			(xy 390.70534 -264.95502) (xy 390.891268 -265.140948)
		)
		(stroke
			(width 0)
			(type solid)
		)
		(fill yes)
		(layer "F.Cu")
		(net "M_E_CPU0_SA_CB<2>")
	)
	(gr_poly
		(pts
			(xy 390.927082 -242.598956) (xy 390.89076 -242.497356) (xy 390.70026 -242.497356) (xy 390.664192 -242.598956)
			(xy 390.664192 -242.649756) (xy 390.927082 -242.649756)
		)
		(stroke
			(width 0)
			(type solid)
		)
		(fill yes)
		(layer "F.Cu")
		(net "M_E_CPU0_SB_CB<4>")
	)
	(gr_poly
		(pts
			(xy 390.927082 -242.294156) (xy 390.89076 -242.192556) (xy 390.70026 -242.192556) (xy 390.664192 -242.294156)
			(xy 390.664192 -242.344956) (xy 390.927082 -242.344956)
		)
		(stroke
			(width 0)
			(type solid)
		)
		(fill yes)
		(layer "F.Cu")
		(net "M_E_CPU0_SB_CB<6>")
	)
	(gr_poly
		(pts
			(xy 390.927082 -241.989356) (xy 390.89076 -241.887756) (xy 390.70026 -241.887756) (xy 390.664192 -241.989356)
			(xy 390.664192 -242.040156) (xy 390.927082 -242.040156)
		)
		(stroke
			(width 0)
			(type solid)
		)
		(fill yes)
		(layer "F.Cu")
		(net "M_E_CPU0_SB_CB<5>")
	)
	(gr_poly
		(pts
			(xy 390.927082 -241.684556) (xy 390.89076 -241.582956) (xy 390.70026 -241.582956) (xy 390.664192 -241.684556)
			(xy 390.664192 -241.735356) (xy 390.927082 -241.735356)
		)
		(stroke
			(width 0)
			(type solid)
		)
		(fill yes)
		(layer "F.Cu")
		(net "M_E_CPU0_SB_CB<7>")
	)
	(gr_poly
		(pts
			(xy 390.929622 -257.494532) (xy 390.97585 -257.39725) (xy 390.84123 -257.262376) (xy 390.743694 -257.308604)
			(xy 390.70788 -257.344672) (xy 390.893808 -257.5306)
		)
		(stroke
			(width 0)
			(type solid)
		)
		(fill yes)
		(layer "F.Cu")
		(net "M_E_CPU0_SA_CA<0>")
	)
	(gr_poly
		(pts
			(xy 390.930638 -276.655784) (xy 391.023094 -276.600412) (xy 390.985756 -276.413468) (xy 390.879076 -276.397974)
			(xy 390.829292 -276.40788) (xy 390.880854 -276.66569)
		)
		(stroke
			(width 0)
			(type solid)
		)
		(fill yes)
		(layer "F.Cu")
		(net "M_E_CPU0_SA_DQ<17>")
	)
	(gr_poly
		(pts
			(xy 390.93648 -264.251694) (xy 390.982708 -264.154158) (xy 390.848088 -264.019538) (xy 390.750552 -264.065766)
			(xy 390.714738 -264.101834) (xy 390.900412 -264.287508)
		)
		(stroke
			(width 0)
			(type solid)
		)
		(fill yes)
		(layer "F.Cu")
		(net "M_E_CPU0_SA_CB<3>")
	)
	(gr_poly
		(pts
			(xy 390.938766 -256.641346) (xy 390.984994 -256.54381) (xy 390.850374 -256.40919) (xy 390.753092 -256.455418)
			(xy 390.717024 -256.491232) (xy 390.902952 -256.67716)
		)
		(stroke
			(width 0)
			(type solid)
		)
		(fill yes)
		(layer "F.Cu")
		(net "M_E_CPU0_SA_CA<2>")
	)
	(gr_poly
		(pts
			(xy 390.939274 -276.958298) (xy 390.887712 -276.700488) (xy 390.837928 -276.710394) (xy 390.745472 -276.765766)
			(xy 390.78281 -276.95271) (xy 390.88949 -276.968204)
		)
		(stroke
			(width 0)
			(type solid)
		)
		(fill yes)
		(layer "F.Cu")
		(net "M_E_CPU0_SA_DQ<17>")
	)
	(gr_poly
		(pts
			(xy 390.947402 -237.479586) (xy 390.901174 -237.382304) (xy 390.86536 -237.346236) (xy 390.679432 -237.532164)
			(xy 390.715246 -237.567978) (xy 390.812782 -237.61446)
		)
		(stroke
			(width 0)
			(type solid)
		)
		(fill yes)
		(layer "F.Cu")
		(net "M_E_CPU0_SB_DQ<11>")
	)
	(gr_poly
		(pts
			(xy 390.948164 -255.787906) (xy 390.994392 -255.69037) (xy 390.859518 -255.55575) (xy 390.762236 -255.601978)
			(xy 390.726168 -255.637792) (xy 390.912096 -255.82372)
		)
		(stroke
			(width 0)
			(type solid)
		)
		(fill yes)
		(layer "F.Cu")
		(net "M_E_CPU0_SA_CA<4>")
	)
	(gr_poly
		(pts
			(xy 390.951466 -267.613384) (xy 390.997694 -267.515848) (xy 390.86282 -267.381228) (xy 390.765538 -267.427456)
			(xy 390.72947 -267.46327) (xy 390.915398 -267.649198)
		)
		(stroke
			(width 0)
			(type solid)
		)
		(fill yes)
		(layer "F.Cu")
		(net "M_E_CPU0_SA_DQ<28>")
	)
	(gr_poly
		(pts
			(xy 390.957308 -254.934466) (xy 391.003536 -254.837184) (xy 390.868916 -254.70231) (xy 390.77138 -254.748538)
			(xy 390.735566 -254.784606) (xy 390.921494 -254.970534)
		)
		(stroke
			(width 0)
			(type solid)
		)
		(fill yes)
		(layer "F.Cu")
		(net "M_E_CPU0_SA_CA<6>")
	)
	(gr_poly
		(pts
			(xy 390.96061 -266.759944) (xy 391.006838 -266.662408) (xy 390.872218 -266.527788) (xy 390.774936 -266.574016)
			(xy 390.738868 -266.60983) (xy 390.924796 -266.795758)
		)
		(stroke
			(width 0)
			(type solid)
		)
		(fill yes)
		(layer "F.Cu")
		(net "M_E_CPU0_SA_DQ<29>")
	)
	(gr_poly
		(pts
			(xy 390.973818 -273.261328) (xy 391.020046 -273.163792) (xy 390.885172 -273.029172) (xy 390.78789 -273.0754)
			(xy 390.751822 -273.111214) (xy 390.93775 -273.297142)
		)
		(stroke
			(width 0)
			(type solid)
		)
		(fill yes)
		(layer "F.Cu")
		(net "M_E_CPU0_SA_DQ<20>")
	)
	(gr_poly
		(pts
			(xy 390.982454 -278.471376) (xy 391.07491 -278.416004) (xy 391.037572 -278.229314) (xy 390.930892 -278.213566)
			(xy 390.881108 -278.223472) (xy 390.93267 -278.481282)
		)
		(stroke
			(width 0)
			(type solid)
		)
		(fill yes)
		(layer "F.Cu")
		(net "M_E_CPU0_SA_DQ<18>")
	)
	(gr_poly
		(pts
			(xy 390.983216 -272.407634) (xy 391.029444 -272.310098) (xy 390.89457 -272.175478) (xy 390.797288 -272.221706)
			(xy 390.76122 -272.25752) (xy 390.947148 -272.443448)
		)
		(stroke
			(width 0)
			(type solid)
		)
		(fill yes)
		(layer "F.Cu")
		(net "M_E_CPU0_SA_DQ<21>")
	)
	(gr_poly
		(pts
			(xy 390.984486 -261.711186) (xy 391.030714 -261.613904) (xy 390.896094 -261.47903) (xy 390.798558 -261.525258)
			(xy 390.762744 -261.561326) (xy 390.948672 -261.747254)
		)
		(stroke
			(width 0)
			(type solid)
		)
		(fill yes)
		(layer "F.Cu")
		(net "M_E_CPU0_SA_CB<6>")
	)
	(gr_poly
		(pts
			(xy 390.99109 -278.774144) (xy 390.939528 -278.516334) (xy 390.889744 -278.52624) (xy 390.797288 -278.581612)
			(xy 390.834626 -278.768302) (xy 390.941306 -278.78405)
		)
		(stroke
			(width 0)
			(type solid)
		)
		(fill yes)
		(layer "F.Cu")
		(net "M_E_CPU0_SA_DQ<18>")
	)
	(gr_poly
		(pts
			(xy 390.992106 -270.710152) (xy 391.038334 -270.612616) (xy 390.903714 -270.477996) (xy 390.806178 -270.524224)
			(xy 390.770364 -270.560292) (xy 390.956038 -270.745966)
		)
		(stroke
			(width 0)
			(type solid)
		)
		(fill yes)
		(layer "F.Cu")
		(net "M_E_CPU0_SA_DQ<26>")
	)
	(gr_poly
		(pts
			(xy 390.99363 -260.857746) (xy 391.039858 -260.760464) (xy 390.905238 -260.625844) (xy 390.807702 -260.672072)
			(xy 390.771888 -260.707886) (xy 390.957816 -260.893814)
		)
		(stroke
			(width 0)
			(type solid)
		)
		(fill yes)
		(layer "F.Cu")
		(net "M_E_CPU0_SA_CB<7>")
	)
	(gr_poly
		(pts
			(xy 390.99744 -228.607112) (xy 390.961372 -228.571298) (xy 390.86409 -228.52507) (xy 390.729216 -228.65969)
			(xy 390.775698 -228.757226) (xy 390.811512 -228.79304)
		)
		(stroke
			(width 0)
			(type solid)
		)
		(fill yes)
		(layer "F.Cu")
		(net "M_E_CPU0_SB_DQ<21>")
	)
	(gr_poly
		(pts
			(xy 390.99998 -225.009456) (xy 390.94918 -225.009456) (xy 390.84758 -225.045778) (xy 390.84758 -225.236278)
			(xy 390.94918 -225.272346) (xy 390.99998 -225.272346)
		)
		(stroke
			(width 0)
			(type solid)
		)
		(fill yes)
		(layer "F.Cu")
		(net "M_E_CPU0_SB_DQ<24>")
	)
	(gr_poly
		(pts
			(xy 390.99998 -224.412556) (xy 390.94918 -224.412556) (xy 390.84758 -224.448878) (xy 390.84758 -224.639378)
			(xy 390.94918 -224.675446) (xy 390.99998 -224.675446)
		)
		(stroke
			(width 0)
			(type solid)
		)
		(fill yes)
		(layer "F.Cu")
		(net "M_E_CPU0_SB_DQ<24>")
	)
	(gr_poly
		(pts
			(xy 390.99998 -223.815656) (xy 390.94918 -223.815656) (xy 390.84758 -223.851978) (xy 390.84758 -224.042478)
			(xy 390.94918 -224.078546) (xy 390.99998 -224.078546)
		)
		(stroke
			(width 0)
			(type solid)
		)
		(fill yes)
		(layer "F.Cu")
		(net "M_E_CPU0_SB_DQ<24>")
	)
	(gr_poly
		(pts
			(xy 390.99998 -223.218756) (xy 390.94918 -223.218756) (xy 390.84758 -223.255078) (xy 390.84758 -223.445578)
			(xy 390.94918 -223.481646) (xy 390.99998 -223.481646)
		)
		(stroke
			(width 0)
			(type solid)
		)
		(fill yes)
		(layer "F.Cu")
		(net "M_E_CPU0_SB_DQ<24>")
	)
	(gr_poly
		(pts
			(xy 390.99998 -222.621856) (xy 390.94918 -222.621856) (xy 390.84758 -222.658178) (xy 390.84758 -222.848678)
			(xy 390.94918 -222.884746) (xy 390.99998 -222.884746)
		)
		(stroke
			(width 0)
			(type solid)
		)
		(fill yes)
		(layer "F.Cu")
		(net "M_E_CPU0_SB_DQ<24>")
	)
	(gr_poly
		(pts
			(xy 390.99998 -222.024956) (xy 390.94918 -222.024956) (xy 390.84758 -222.061278) (xy 390.84758 -222.251778)
			(xy 390.94918 -222.287846) (xy 390.99998 -222.287846)
		)
		(stroke
			(width 0)
			(type solid)
		)
		(fill yes)
		(layer "F.Cu")
		(net "M_E_CPU0_SB_DQ<24>")
	)
	(gr_poly
		(pts
			(xy 390.99998 -221.428056) (xy 390.94918 -221.428056) (xy 390.84758 -221.464378) (xy 390.84758 -221.654878)
			(xy 390.94918 -221.690946) (xy 390.99998 -221.690946)
		)
		(stroke
			(width 0)
			(type solid)
		)
		(fill yes)
		(layer "F.Cu")
		(net "M_E_CPU0_SB_DQ<24>")
	)
	(gr_poly
		(pts
			(xy 390.99998 -220.831156) (xy 390.94918 -220.831156) (xy 390.84758 -220.867478) (xy 390.84758 -221.057978)
			(xy 390.94918 -221.094046) (xy 390.99998 -221.094046)
		)
		(stroke
			(width 0)
			(type solid)
		)
		(fill yes)
		(layer "F.Cu")
		(net "M_E_CPU0_SB_DQ<24>")
	)
	(gr_poly
		(pts
			(xy 390.99998 -220.234256) (xy 390.94918 -220.234256) (xy 390.84758 -220.270578) (xy 390.84758 -220.461078)
			(xy 390.94918 -220.497146) (xy 390.99998 -220.497146)
		)
		(stroke
			(width 0)
			(type solid)
		)
		(fill yes)
		(layer "F.Cu")
		(net "M_E_CPU0_SB_DQ<24>")
	)
	(gr_poly
		(pts
			(xy 390.99998 -219.637356) (xy 390.94918 -219.637356) (xy 390.84758 -219.673678) (xy 390.84758 -219.864178)
			(xy 390.94918 -219.900246) (xy 390.99998 -219.900246)
		)
		(stroke
			(width 0)
			(type solid)
		)
		(fill yes)
		(layer "F.Cu")
		(net "M_E_CPU0_SB_DQ<24>")
	)
	(gr_poly
		(pts
			(xy 390.99998 -219.040456) (xy 390.94918 -219.040456) (xy 390.84758 -219.076778) (xy 390.84758 -219.267278)
			(xy 390.94918 -219.303346) (xy 390.99998 -219.303346)
		)
		(stroke
			(width 0)
			(type solid)
		)
		(fill yes)
		(layer "F.Cu")
		(net "M_E_CPU0_SB_DQ<24>")
	)
	(gr_poly
		(pts
			(xy 390.99998 -218.443556) (xy 390.94918 -218.443556) (xy 390.84758 -218.479878) (xy 390.84758 -218.670378)
			(xy 390.94918 -218.706446) (xy 390.99998 -218.706446)
		)
		(stroke
			(width 0)
			(type solid)
		)
		(fill yes)
		(layer "F.Cu")
		(net "M_E_CPU0_SB_DQ<24>")
	)
	(gr_poly
		(pts
			(xy 390.99998 -217.846656) (xy 390.94918 -217.846656) (xy 390.84758 -217.882978) (xy 390.84758 -218.073478)
			(xy 390.94918 -218.109546) (xy 390.99998 -218.109546)
		)
		(stroke
			(width 0)
			(type solid)
		)
		(fill yes)
		(layer "F.Cu")
		(net "M_E_CPU0_SB_DQ<24>")
	)
	(gr_poly
		(pts
			(xy 390.99998 -217.249756) (xy 390.94918 -217.249756) (xy 390.84758 -217.286078) (xy 390.84758 -217.476578)
			(xy 390.94918 -217.512646) (xy 390.99998 -217.512646)
		)
		(stroke
			(width 0)
			(type solid)
		)
		(fill yes)
		(layer "F.Cu")
		(net "M_E_CPU0_SB_DQ<24>")
	)
	(gr_poly
		(pts
			(xy 390.99998 -216.652856) (xy 390.94918 -216.652856) (xy 390.84758 -216.689178) (xy 390.84758 -216.879678)
			(xy 390.94918 -216.915746) (xy 390.99998 -216.915746)
		)
		(stroke
			(width 0)
			(type solid)
		)
		(fill yes)
		(layer "F.Cu")
		(net "M_E_CPU0_SB_DQ<24>")
	)
	(gr_poly
		(pts
			(xy 390.99998 -216.055956) (xy 390.94918 -216.055956) (xy 390.84758 -216.092278) (xy 390.84758 -216.282778)
			(xy 390.94918 -216.318846) (xy 390.99998 -216.318846)
		)
		(stroke
			(width 0)
			(type solid)
		)
		(fill yes)
		(layer "F.Cu")
		(net "M_E_CPU0_SB_DQ<24>")
	)
	(gr_poly
		(pts
			(xy 391.00125 -269.856712) (xy 391.047478 -269.759176) (xy 390.912858 -269.624556) (xy 390.815322 -269.670784)
			(xy 390.779508 -269.706852) (xy 390.965182 -269.892526)
		)
		(stroke
			(width 0)
			(type solid)
		)
		(fill yes)
		(layer "F.Cu")
		(net "M_E_CPU0_SA_DQ<27>")
	)
	(gr_poly
		(pts
			(xy 391.006584 -229.460552) (xy 390.97077 -229.424738) (xy 390.873234 -229.378256) (xy 390.738614 -229.51313)
			(xy 390.784842 -229.610412) (xy 390.820656 -229.64648)
		)
		(stroke
			(width 0)
			(type solid)
		)
		(fill yes)
		(layer "F.Cu")
		(net "M_E_CPU0_SB_DQ<20>")
	)
	(gr_poly
		(pts
			(xy 391.024618 -289.844226) (xy 390.973818 -289.844226) (xy 390.872218 -289.880548) (xy 390.872218 -290.071048)
			(xy 390.973818 -290.10737) (xy 391.024618 -290.10737)
		)
		(stroke
			(width 0)
			(type solid)
		)
		(fill yes)
		(layer "F.Cu")
		(net "M_E_CPU0_SA_DQ<16>")
	)
	(gr_poly
		(pts
			(xy 391.024618 -289.247326) (xy 390.973818 -289.247326) (xy 390.872218 -289.283648) (xy 390.872218 -289.474148)
			(xy 390.973818 -289.51047) (xy 391.024618 -289.51047)
		)
		(stroke
			(width 0)
			(type solid)
		)
		(fill yes)
		(layer "F.Cu")
		(net "M_E_CPU0_SA_DQ<16>")
	)
	(gr_poly
		(pts
			(xy 391.024618 -288.650426) (xy 390.973818 -288.650426) (xy 390.872218 -288.686748) (xy 390.872218 -288.877248)
			(xy 390.973818 -288.91357) (xy 391.024618 -288.91357)
		)
		(stroke
			(width 0)
			(type solid)
		)
		(fill yes)
		(layer "F.Cu")
		(net "M_E_CPU0_SA_DQ<16>")
	)
	(gr_poly
		(pts
			(xy 391.024618 -288.053526) (xy 390.973818 -288.053526) (xy 390.872218 -288.089848) (xy 390.872218 -288.280348)
			(xy 390.973818 -288.31667) (xy 391.024618 -288.31667)
		)
		(stroke
			(width 0)
			(type solid)
		)
		(fill yes)
		(layer "F.Cu")
		(net "M_E_CPU0_SA_DQ<16>")
	)
	(gr_poly
		(pts
			(xy 391.024618 -287.456626) (xy 390.973818 -287.456626) (xy 390.872218 -287.492948) (xy 390.872218 -287.683448)
			(xy 390.973818 -287.71977) (xy 391.024618 -287.71977)
		)
		(stroke
			(width 0)
			(type solid)
		)
		(fill yes)
		(layer "F.Cu")
		(net "M_E_CPU0_SA_DQ<16>")
	)
	(gr_poly
		(pts
			(xy 391.024618 -286.859726) (xy 390.973818 -286.859726) (xy 390.872218 -286.896048) (xy 390.872218 -287.086548)
			(xy 390.973818 -287.12287) (xy 391.024618 -287.12287)
		)
		(stroke
			(width 0)
			(type solid)
		)
		(fill yes)
		(layer "F.Cu")
		(net "M_E_CPU0_SA_DQ<16>")
	)
	(gr_poly
		(pts
			(xy 391.024618 -286.262826) (xy 390.973818 -286.262826) (xy 390.872218 -286.299148) (xy 390.872218 -286.489648)
			(xy 390.973818 -286.52597) (xy 391.024618 -286.52597)
		)
		(stroke
			(width 0)
			(type solid)
		)
		(fill yes)
		(layer "F.Cu")
		(net "M_E_CPU0_SA_DQ<16>")
	)
	(gr_poly
		(pts
			(xy 391.024618 -285.665926) (xy 390.973818 -285.665926) (xy 390.872218 -285.702248) (xy 390.872218 -285.892748)
			(xy 390.973818 -285.92907) (xy 391.024618 -285.92907)
		)
		(stroke
			(width 0)
			(type solid)
		)
		(fill yes)
		(layer "F.Cu")
		(net "M_E_CPU0_SA_DQ<16>")
	)
	(gr_poly
		(pts
			(xy 391.024618 -285.069026) (xy 390.973818 -285.069026) (xy 390.872218 -285.105348) (xy 390.872218 -285.295848)
			(xy 390.973818 -285.33217) (xy 391.024618 -285.33217)
		)
		(stroke
			(width 0)
			(type solid)
		)
		(fill yes)
		(layer "F.Cu")
		(net "M_E_CPU0_SA_DQ<16>")
	)
	(gr_poly
		(pts
			(xy 391.024618 -284.472126) (xy 390.973818 -284.472126) (xy 390.872218 -284.508448) (xy 390.872218 -284.698948)
			(xy 390.973818 -284.73527) (xy 391.024618 -284.73527)
		)
		(stroke
			(width 0)
			(type solid)
		)
		(fill yes)
		(layer "F.Cu")
		(net "M_E_CPU0_SA_DQ<16>")
	)
	(gr_poly
		(pts
			(xy 391.024618 -283.875226) (xy 390.973818 -283.875226) (xy 390.872218 -283.911548) (xy 390.872218 -284.102048)
			(xy 390.973818 -284.13837) (xy 391.024618 -284.13837)
		)
		(stroke
			(width 0)
			(type solid)
		)
		(fill yes)
		(layer "F.Cu")
		(net "M_E_CPU0_SA_DQ<16>")
	)
	(gr_poly
		(pts
			(xy 391.024618 -283.278326) (xy 390.973818 -283.278326) (xy 390.872218 -283.314648) (xy 390.872218 -283.505148)
			(xy 390.973818 -283.54147) (xy 391.024618 -283.54147)
		)
		(stroke
			(width 0)
			(type solid)
		)
		(fill yes)
		(layer "F.Cu")
		(net "M_E_CPU0_SA_DQ<16>")
	)
	(gr_poly
		(pts
			(xy 391.024618 -282.681426) (xy 390.973818 -282.681426) (xy 390.872218 -282.717748) (xy 390.872218 -282.908248)
			(xy 390.973818 -282.94457) (xy 391.024618 -282.94457)
		)
		(stroke
			(width 0)
			(type solid)
		)
		(fill yes)
		(layer "F.Cu")
		(net "M_E_CPU0_SA_DQ<16>")
	)
	(gr_poly
		(pts
			(xy 391.024618 -282.084526) (xy 390.973818 -282.084526) (xy 390.872218 -282.120848) (xy 390.872218 -282.311348)
			(xy 390.973818 -282.34767) (xy 391.024618 -282.34767)
		)
		(stroke
			(width 0)
			(type solid)
		)
		(fill yes)
		(layer "F.Cu")
		(net "M_E_CPU0_SA_DQ<16>")
	)
	(gr_poly
		(pts
			(xy 391.024618 -281.487626) (xy 390.973818 -281.487626) (xy 390.872218 -281.523948) (xy 390.872218 -281.714448)
			(xy 390.973818 -281.75077) (xy 391.024618 -281.75077)
		)
		(stroke
			(width 0)
			(type solid)
		)
		(fill yes)
		(layer "F.Cu")
		(net "M_E_CPU0_SA_DQ<16>")
	)
	(gr_poly
		(pts
			(xy 391.024618 -280.890726) (xy 390.973818 -280.890726) (xy 390.872218 -280.927048) (xy 390.872218 -281.117548)
			(xy 390.973818 -281.15387) (xy 391.024618 -281.15387)
		)
		(stroke
			(width 0)
			(type solid)
		)
		(fill yes)
		(layer "F.Cu")
		(net "M_E_CPU0_SA_DQ<16>")
	)
	(gr_poly
		(pts
			(xy 391.033254 -280.287222) (xy 391.12571 -280.23185) (xy 391.088372 -280.04516) (xy 390.981692 -280.029666)
			(xy 390.931908 -280.039572) (xy 390.98347 -280.297382)
		)
		(stroke
			(width 0)
			(type solid)
		)
		(fill yes)
		(layer "F.Cu")
		(net "M_E_CPU0_SA_DQ<16>")
	)
	(gr_poly
		(pts
			(xy 391.033508 -232.021888) (xy 390.99744 -231.986074) (xy 390.900158 -231.939846) (xy 390.765538 -232.074466)
			(xy 390.811766 -232.172002) (xy 390.84758 -232.207816)
		)
		(stroke
			(width 0)
			(type solid)
		)
		(fill yes)
		(layer "F.Cu")
		(net "M_E_CPU0_SB_DQ<17>")
	)
	(gr_poly
		(pts
			(xy 391.042144 -233.719116) (xy 391.00633 -233.683048) (xy 390.908794 -233.63682) (xy 390.774174 -233.77144)
			(xy 390.820402 -233.868976) (xy 390.85647 -233.90479)
		)
		(stroke
			(width 0)
			(type solid)
		)
		(fill yes)
		(layer "F.Cu")
		(net "M_E_CPU0_SB_DQ<15>")
	)
	(gr_poly
		(pts
			(xy 391.042652 -232.875328) (xy 391.006838 -232.83926) (xy 390.909302 -232.793032) (xy 390.774682 -232.927906)
			(xy 390.82091 -233.025188) (xy 390.856724 -233.061256)
		)
		(stroke
			(width 0)
			(type solid)
		)
		(fill yes)
		(layer "F.Cu")
		(net "M_E_CPU0_SB_DQ<16>")
	)
	(gr_poly
		(pts
			(xy 391.047732 -277.241) (xy 391.140188 -277.185628) (xy 391.10285 -276.998938) (xy 390.99617 -276.98319)
			(xy 390.946386 -276.993096) (xy 390.997948 -277.250906)
		)
		(stroke
			(width 0)
			(type solid)
		)
		(fill yes)
		(layer "F.Cu")
		(net "M_E_CPU0_SA_DQ<17>")
	)
	(gr_poly
		(pts
			(xy 391.050272 -259.484368) (xy 391.086086 -259.4483) (xy 390.900412 -259.262626) (xy 390.864344 -259.29844)
			(xy 390.818116 -259.395976) (xy 390.952736 -259.530596)
		)
		(stroke
			(width 0)
			(type solid)
		)
		(fill yes)
		(layer "F.Cu")
		(net "M_E_CPU0_SA_CS_N<0>")
	)
	(gr_poly
		(pts
			(xy 391.051542 -234.572302) (xy 391.015474 -234.536488) (xy 390.918192 -234.49026) (xy 390.783318 -234.62488)
			(xy 390.829546 -234.722416) (xy 390.865614 -234.75823)
		)
		(stroke
			(width 0)
			(type solid)
		)
		(fill yes)
		(layer "F.Cu")
		(net "M_E_CPU0_SB_DQ<14>")
	)
	(gr_poly
		(pts
			(xy 391.056368 -277.543514) (xy 391.004806 -277.285958) (xy 390.955022 -277.295864) (xy 390.862566 -277.351236)
			(xy 390.899904 -277.537926) (xy 391.006584 -277.553674)
		)
		(stroke
			(width 0)
			(type solid)
		)
		(fill yes)
		(layer "F.Cu")
		(net "M_E_CPU0_SA_DQ<17>")
	)
	(gr_poly
		(pts
			(xy 391.05967 -258.630928) (xy 391.095484 -258.59486) (xy 390.909556 -258.408932) (xy 390.873742 -258.445)
			(xy 390.827514 -258.542282) (xy 390.962134 -258.677156)
		)
		(stroke
			(width 0)
			(type solid)
		)
		(fill yes)
		(layer "F.Cu")
		(net "M_E_CPU0_SA_CS_N<1>")
	)
	(gr_poly
		(pts
			(xy 391.066528 -265.387836) (xy 391.102342 -265.352022) (xy 390.916414 -265.166094) (xy 390.8806 -265.201908)
			(xy 390.834372 -265.299444) (xy 390.968992 -265.434064)
		)
		(stroke
			(width 0)
			(type solid)
		)
		(fill yes)
		(layer "F.Cu")
		(net "M_E_CPU0_SA_CB<2>")
	)
	(gr_poly
		(pts
			(xy 391.068814 -257.777488) (xy 391.104882 -257.741674) (xy 390.918954 -257.555746) (xy 390.882886 -257.59156)
			(xy 390.836658 -257.689096) (xy 390.971532 -257.823716)
		)
		(stroke
			(width 0)
			(type solid)
		)
		(fill yes)
		(layer "F.Cu")
		(net "M_E_CPU0_SA_CA<0>")
	)
	(gr_poly
		(pts
			(xy 391.07491 -228.313742) (xy 391.028682 -228.21646) (xy 390.992868 -228.180392) (xy 390.80694 -228.36632)
			(xy 390.842754 -228.402388) (xy 390.94029 -228.448616)
		)
		(stroke
			(width 0)
			(type solid)
		)
		(fill yes)
		(layer "F.Cu")
		(net "M_E_CPU0_SB_DQ<23>")
	)
	(gr_poly
		(pts
			(xy 391.075672 -264.53465) (xy 391.111486 -264.498582) (xy 390.925558 -264.312654) (xy 390.889744 -264.348722)
			(xy 390.843516 -264.446004) (xy 390.978136 -264.580878)
		)
		(stroke
			(width 0)
			(type solid)
		)
		(fill yes)
		(layer "F.Cu")
		(net "M_E_CPU0_SA_CB<3>")
	)
	(gr_poly
		(pts
			(xy 391.076434 -237.135162) (xy 391.040366 -237.099348) (xy 390.943084 -237.05312) (xy 390.80821 -237.18774)
			(xy 390.854438 -237.285276) (xy 390.890506 -237.32109)
		)
		(stroke
			(width 0)
			(type solid)
		)
		(fill yes)
		(layer "F.Cu")
		(net "M_E_CPU0_SB_DQ<11>")
	)
	(gr_poly
		(pts
			(xy 391.077958 -256.924048) (xy 391.114026 -256.888234) (xy 390.928098 -256.702306) (xy 390.892284 -256.73812)
			(xy 390.845802 -256.835656) (xy 390.980676 -256.970276)
		)
		(stroke
			(width 0)
			(type solid)
		)
		(fill yes)
		(layer "F.Cu")
		(net "M_E_CPU0_SA_CA<2>")
	)
	(gr_poly
		(pts
			(xy 391.084054 -229.167182) (xy 391.037826 -229.069646) (xy 391.002012 -229.033832) (xy 390.816084 -229.21976)
			(xy 390.851898 -229.255574) (xy 390.949434 -229.301802)
		)
		(stroke
			(width 0)
			(type solid)
		)
		(fill yes)
		(layer "F.Cu")
		(net "M_E_CPU0_SB_DQ<22>")
	)
	(gr_poly
		(pts
			(xy 391.08634 -237.989364) (xy 391.050526 -237.95355) (xy 390.95299 -237.907322) (xy 390.81837 -238.041942)
			(xy 390.864598 -238.139224) (xy 390.900412 -238.175292)
		)
		(stroke
			(width 0)
			(type solid)
		)
		(fill yes)
		(layer "F.Cu")
		(net "M_E_CPU0_SB_DQ<10>")
	)
	(gr_poly
		(pts
			(xy 391.087356 -256.070862) (xy 391.12317 -256.034794) (xy 390.937242 -255.848866) (xy 390.901428 -255.884934)
			(xy 390.8552 -255.982216) (xy 390.98982 -256.11709)
		)
		(stroke
			(width 0)
			(type solid)
		)
		(fill yes)
		(layer "F.Cu")
		(net "M_E_CPU0_SA_CA<4>")
	)
	(gr_poly
		(pts
			(xy 391.090658 -267.896086) (xy 391.126472 -267.860272) (xy 390.940544 -267.674344) (xy 390.90473 -267.710412)
			(xy 390.858502 -267.807694) (xy 390.993122 -267.942568)
		)
		(stroke
			(width 0)
			(type solid)
		)
		(fill yes)
		(layer "F.Cu")
		(net "M_E_CPU0_SA_DQ<28>")
	)
	(gr_poly
		(pts
			(xy 391.0965 -255.217422) (xy 391.132314 -255.181354) (xy 390.94664 -254.99568) (xy 390.910572 -255.031494)
			(xy 390.864344 -255.12903) (xy 390.998964 -255.26365)
		)
		(stroke
			(width 0)
			(type solid)
		)
		(fill yes)
		(layer "F.Cu")
		(net "M_E_CPU0_SA_CA<6>")
	)
	(gr_poly
		(pts
			(xy 391.097516 -248.967752) (xy 391.061448 -248.866152) (xy 390.870948 -248.866152) (xy 390.83488 -248.967752)
			(xy 390.83488 -249.018552) (xy 391.097516 -249.018552)
		)
		(stroke
			(width 0)
			(type solid)
		)
		(fill yes)
		(layer "F.Cu")
		(net "M_E_CPU0_SB_CA<0>")
	)
	(gr_poly
		(pts
			(xy 391.097516 -248.662952) (xy 391.061448 -248.561352) (xy 390.870948 -248.561352) (xy 390.83488 -248.662952)
			(xy 390.83488 -248.713752) (xy 391.097516 -248.713752)
		)
		(stroke
			(width 0)
			(type solid)
		)
		(fill yes)
		(layer "F.Cu")
		(net "M_E_CPU0_SB_CA<1>")
	)
	(gr_poly
		(pts
			(xy 391.097516 -248.358152) (xy 391.061448 -248.256552) (xy 390.870948 -248.256552) (xy 390.83488 -248.358152)
			(xy 390.83488 -248.408952) (xy 391.097516 -248.408952)
		)
		(stroke
			(width 0)
			(type solid)
		)
		(fill yes)
		(layer "F.Cu")
		(net "M_E_CPU0_SB_CA<2>")
	)
	(gr_poly
		(pts
			(xy 391.097516 -248.053352) (xy 391.061448 -247.951752) (xy 390.870948 -247.951752) (xy 390.83488 -248.053352)
			(xy 390.83488 -248.104152) (xy 391.097516 -248.104152)
		)
		(stroke
			(width 0)
			(type solid)
		)
		(fill yes)
		(layer "F.Cu")
		(net "M_E_CPU0_SB_CA<3>")
	)
	(gr_poly
		(pts
			(xy 391.097516 -247.748552) (xy 391.061448 -247.646952) (xy 390.870948 -247.646952) (xy 390.83488 -247.748552)
			(xy 390.83488 -247.799352) (xy 391.097516 -247.799352)
		)
		(stroke
			(width 0)
			(type solid)
		)
		(fill yes)
		(layer "F.Cu")
		(net "M_E_CPU0_SB_CA<4>")
	)
	(gr_poly
		(pts
			(xy 391.097516 -247.443752) (xy 391.061448 -247.342152) (xy 390.870948 -247.342152) (xy 390.83488 -247.443752)
			(xy 390.83488 -247.494552) (xy 391.097516 -247.494552)
		)
		(stroke
			(width 0)
			(type solid)
		)
		(fill yes)
		(layer "F.Cu")
		(net "M_E_CPU0_SB_CA<5>")
	)
	(gr_poly
		(pts
			(xy 391.097516 -247.138952) (xy 391.061448 -247.037352) (xy 390.870948 -247.037352) (xy 390.83488 -247.138952)
			(xy 390.83488 -247.189752) (xy 391.097516 -247.189752)
		)
		(stroke
			(width 0)
			(type solid)
		)
		(fill yes)
		(layer "F.Cu")
		(net "M_E_CPU0_SB_CA<6>")
	)
	(gr_poly
		(pts
			(xy 391.097516 -246.834152) (xy 391.061448 -246.732552) (xy 390.870948 -246.732552) (xy 390.83488 -246.834152)
			(xy 390.83488 -246.884952) (xy 391.097516 -246.884952)
		)
		(stroke
			(width 0)
			(type solid)
		)
		(fill yes)
		(layer "F.Cu")
		(net "M_E_CPU0_SB_PAR")
	)
	(gr_poly
		(pts
			(xy 391.097516 -246.529352) (xy 391.061448 -246.427752) (xy 390.870948 -246.427752) (xy 390.83488 -246.529352)
			(xy 390.83488 -246.580152) (xy 391.097516 -246.580152)
		)
		(stroke
			(width 0)
			(type solid)
		)
		(fill yes)
		(layer "F.Cu")
		(net "M_E_CPU0_SB_CS_N<0>")
	)
	(gr_poly
		(pts
			(xy 391.097516 -246.224552) (xy 391.061448 -246.122952) (xy 390.870948 -246.122952) (xy 390.83488 -246.224552)
			(xy 390.83488 -246.275352) (xy 391.097516 -246.275352)
		)
		(stroke
			(width 0)
			(type solid)
		)
		(fill yes)
		(layer "F.Cu")
		(net "M_E_CPU0_SB_CS_N<2>")
	)
	(gr_poly
		(pts
			(xy 391.099548 -279.056592) (xy 391.192004 -279.00122) (xy 391.154666 -278.81453) (xy 391.047986 -278.799036)
			(xy 390.998202 -278.808942) (xy 391.049764 -279.066752)
		)
		(stroke
			(width 0)
			(type solid)
		)
		(fill yes)
		(layer "F.Cu")
		(net "M_E_CPU0_SA_DQ<18>")
	)
	(gr_poly
		(pts
			(xy 391.099802 -267.042646) (xy 391.13587 -267.006832) (xy 390.949942 -266.820904) (xy 390.914128 -266.856718)
			(xy 390.867646 -266.954254) (xy 391.00252 -267.088874)
		)
		(stroke
			(width 0)
			(type solid)
		)
		(fill yes)
		(layer "F.Cu")
		(net "M_E_CPU0_SA_DQ<29>")
	)
	(gr_poly
		(pts
			(xy 391.108184 -279.35936) (xy 391.056622 -279.10155) (xy 391.006838 -279.111456) (xy 390.914382 -279.166828)
			(xy 390.95172 -279.353772) (xy 391.0584 -279.369266)
		)
		(stroke
			(width 0)
			(type solid)
		)
		(fill yes)
		(layer "F.Cu")
		(net "M_E_CPU0_SA_DQ<18>")
	)
	(gr_poly
		(pts
			(xy 391.110978 -231.728518) (xy 391.06475 -231.631236) (xy 391.028936 -231.595168) (xy 390.843008 -231.781096)
			(xy 390.878822 -231.817164) (xy 390.976358 -231.863392)
		)
		(stroke
			(width 0)
			(type solid)
		)
		(fill yes)
		(layer "F.Cu")
		(net "M_E_CPU0_SB_DQ<19>")
	)
	(gr_poly
		(pts
			(xy 391.11301 -273.54403) (xy 391.148824 -273.508216) (xy 390.962896 -273.322288) (xy 390.927082 -273.358356)
			(xy 390.880854 -273.455638) (xy 391.015474 -273.590258)
		)
		(stroke
			(width 0)
			(type solid)
		)
		(fill yes)
		(layer "F.Cu")
		(net "M_E_CPU0_SA_DQ<20>")
	)
	(gr_poly
		(pts
			(xy 391.113264 -276.010624) (xy 391.205974 -275.955252) (xy 391.168636 -275.768308) (xy 391.061702 -275.752814)
			(xy 391.011918 -275.76272) (xy 391.06348 -276.02053)
		)
		(stroke
			(width 0)
			(type solid)
		)
		(fill yes)
		(layer "F.Cu")
		(net "M_E_CPU0_SA_DQ<19>")
	)
	(gr_poly
		(pts
			(xy 391.120376 -232.581958) (xy 391.073894 -232.484422) (xy 391.03808 -232.448608) (xy 390.852152 -232.634536)
			(xy 390.88822 -232.67035) (xy 390.985502 -232.716578)
		)
		(stroke
			(width 0)
			(type solid)
		)
		(fill yes)
		(layer "F.Cu")
		(net "M_E_CPU0_SB_DQ<18>")
	)
	(gr_poly
		(pts
			(xy 391.1219 -276.313138) (xy 391.070592 -276.055328) (xy 391.020554 -276.065234) (xy 390.928098 -276.120606)
			(xy 390.965436 -276.30755) (xy 391.072116 -276.323044)
		)
		(stroke
			(width 0)
			(type solid)
		)
		(fill yes)
		(layer "F.Cu")
		(net "M_E_CPU0_SA_DQ<19>")
	)
	(gr_poly
		(pts
			(xy 391.122408 -272.69059) (xy 391.158222 -272.654522) (xy 390.972294 -272.468594) (xy 390.93648 -272.504662)
			(xy 390.890252 -272.601944) (xy 391.024872 -272.736818)
		)
		(stroke
			(width 0)
			(type solid)
		)
		(fill yes)
		(layer "F.Cu")
		(net "M_E_CPU0_SA_DQ<21>")
	)
	(gr_poly
		(pts
			(xy 391.123678 -261.994142) (xy 391.159492 -261.958074) (xy 390.973818 -261.7724) (xy 390.93775 -261.808214)
			(xy 390.891522 -261.90575) (xy 391.026142 -262.04037)
		)
		(stroke
			(width 0)
			(type solid)
		)
		(fill yes)
		(layer "F.Cu")
		(net "M_E_CPU0_SA_CB<6>")
	)
	(gr_poly
		(pts
			(xy 391.12698 -258.985766) (xy 391.173208 -258.88823) (xy 391.038334 -258.75361) (xy 390.941052 -258.799838)
			(xy 390.904984 -258.835652) (xy 391.090912 -259.02158)
		)
		(stroke
			(width 0)
			(type solid)
		)
		(fill yes)
		(layer "F.Cu")
		(net "M_E_CPU0_SA_CS_N<2>")
	)
	(gr_poly
		(pts
			(xy 391.129012 -234.278932) (xy 391.082784 -234.18165) (xy 391.04697 -234.145582) (xy 390.861042 -234.33151)
			(xy 390.896856 -234.367578) (xy 390.994392 -234.413806)
		)
		(stroke
			(width 0)
			(type solid)
		)
		(fill yes)
		(layer "F.Cu")
		(net "M_E_CPU0_SB_DQ<13>")
	)
	(gr_poly
		(pts
			(xy 391.131298 -270.993108) (xy 391.167112 -270.95704) (xy 390.981184 -270.771112) (xy 390.94537 -270.80718)
			(xy 390.899142 -270.904462) (xy 391.033762 -271.039336)
		)
		(stroke
			(width 0)
			(type solid)
		)
		(fill yes)
		(layer "F.Cu")
		(net "M_E_CPU0_SA_DQ<26>")
	)
	(gr_poly
		(pts
			(xy 391.132822 -261.140702) (xy 391.16889 -261.104888) (xy 390.982962 -260.91896) (xy 390.946894 -260.954774)
			(xy 390.900666 -261.05231) (xy 391.03554 -261.18693)
		)
		(stroke
			(width 0)
			(type solid)
		)
		(fill yes)
		(layer "F.Cu")
		(net "M_E_CPU0_SA_CB<7>")
	)
	(gr_poly
		(pts
			(xy 391.133584 -265.742674) (xy 391.179812 -265.645392) (xy 391.045192 -265.510518) (xy 390.947656 -265.556746)
			(xy 390.911842 -265.592814) (xy 391.09777 -265.778742)
		)
		(stroke
			(width 0)
			(type solid)
		)
		(fill yes)
		(layer "F.Cu")
		(net "M_E_CPU0_SA_CB<0>")
	)
	(gr_poly
		(pts
			(xy 391.136124 -258.132326) (xy 391.182352 -258.03479) (xy 391.047732 -257.90017) (xy 390.950196 -257.946398)
			(xy 390.914382 -257.982466) (xy 391.100056 -258.16814)
		)
		(stroke
			(width 0)
			(type solid)
		)
		(fill yes)
		(layer "F.Cu")
		(net "M_E_CPU0_SA_CS_N<3>")
	)
	(gr_poly
		(pts
			(xy 391.138156 -235.132372) (xy 391.091928 -235.034836) (xy 391.056114 -234.999022) (xy 390.870186 -235.18495)
			(xy 390.906 -235.220764) (xy 391.003536 -235.266992)
		)
		(stroke
			(width 0)
			(type solid)
		)
		(fill yes)
		(layer "F.Cu")
		(net "M_E_CPU0_SB_DQ<12>")
	)
	(gr_poly
		(pts
			(xy 391.140442 -270.139668) (xy 391.176256 -270.1036) (xy 390.990328 -269.917672) (xy 390.954514 -269.95374)
			(xy 390.908286 -270.051022) (xy 391.042906 -270.185896)
		)
		(stroke
			(width 0)
			(type solid)
		)
		(fill yes)
		(layer "F.Cu")
		(net "M_E_CPU0_SA_DQ<27>")
	)
	(gr_poly
		(pts
			(xy 391.142728 -264.889488) (xy 391.18921 -264.791952) (xy 391.054336 -264.657332) (xy 390.957054 -264.70356)
			(xy 390.920986 -264.739374) (xy 391.106914 -264.925302)
		)
		(stroke
			(width 0)
			(type solid)
		)
		(fill yes)
		(layer "F.Cu")
		(net "M_E_CPU0_SA_CB<1>")
	)
	(gr_poly
		(pts
			(xy 391.145268 -257.278886) (xy 391.191496 -257.181604) (xy 391.056876 -257.04673) (xy 390.95934 -257.092958)
			(xy 390.923526 -257.129026) (xy 391.109454 -257.314954)
		)
		(stroke
			(width 0)
			(type solid)
		)
		(fill yes)
		(layer "F.Cu")
		(net "M_E_CPU0_SA_CA<1>")
	)
	(gr_poly
		(pts
			(xy 391.15238 -224.937574) (xy 391.15238 -224.747074) (xy 391.05078 -224.711006) (xy 390.99998 -224.711006)
			(xy 390.99998 -224.973896) (xy 391.05078 -224.973896)
		)
		(stroke
			(width 0)
			(type solid)
		)
		(fill yes)
		(layer "F.Cu")
		(net "M_E_CPU0_SB_DQ<24>")
	)
	(gr_poly
		(pts
			(xy 391.15238 -224.340674) (xy 391.15238 -224.150174) (xy 391.05078 -224.114106) (xy 390.99998 -224.114106)
			(xy 390.99998 -224.376996) (xy 391.05078 -224.376996)
		)
		(stroke
			(width 0)
			(type solid)
		)
		(fill yes)
		(layer "F.Cu")
		(net "M_E_CPU0_SB_DQ<24>")
	)
	(gr_poly
		(pts
			(xy 391.15238 -223.743774) (xy 391.15238 -223.553274) (xy 391.05078 -223.517206) (xy 390.99998 -223.517206)
			(xy 390.99998 -223.780096) (xy 391.05078 -223.780096)
		)
		(stroke
			(width 0)
			(type solid)
		)
		(fill yes)
		(layer "F.Cu")
		(net "M_E_CPU0_SB_DQ<24>")
	)
	(gr_poly
		(pts
			(xy 391.15238 -223.146874) (xy 391.15238 -222.956374) (xy 391.05078 -222.920306) (xy 390.99998 -222.920306)
			(xy 390.99998 -223.183196) (xy 391.05078 -223.183196)
		)
		(stroke
			(width 0)
			(type solid)
		)
		(fill yes)
		(layer "F.Cu")
		(net "M_E_CPU0_SB_DQ<24>")
	)
	(gr_poly
		(pts
			(xy 391.15238 -222.549974) (xy 391.15238 -222.359474) (xy 391.05078 -222.323406) (xy 390.99998 -222.323406)
			(xy 390.99998 -222.586296) (xy 391.05078 -222.586296)
		)
		(stroke
			(width 0)
			(type solid)
		)
		(fill yes)
		(layer "F.Cu")
		(net "M_E_CPU0_SB_DQ<24>")
	)
	(gr_poly
		(pts
			(xy 391.15238 -221.953074) (xy 391.15238 -221.762574) (xy 391.05078 -221.726506) (xy 390.99998 -221.726506)
			(xy 390.99998 -221.989396) (xy 391.05078 -221.989396)
		)
		(stroke
			(width 0)
			(type solid)
		)
		(fill yes)
		(layer "F.Cu")
		(net "M_E_CPU0_SB_DQ<24>")
	)
	(gr_poly
		(pts
			(xy 391.15238 -221.356174) (xy 391.15238 -221.165674) (xy 391.05078 -221.129606) (xy 390.99998 -221.129606)
			(xy 390.99998 -221.392496) (xy 391.05078 -221.392496)
		)
		(stroke
			(width 0)
			(type solid)
		)
		(fill yes)
		(layer "F.Cu")
		(net "M_E_CPU0_SB_DQ<24>")
	)
	(gr_poly
		(pts
			(xy 391.15238 -220.759274) (xy 391.15238 -220.568774) (xy 391.05078 -220.532706) (xy 390.99998 -220.532706)
			(xy 390.99998 -220.795596) (xy 391.05078 -220.795596)
		)
		(stroke
			(width 0)
			(type solid)
		)
		(fill yes)
		(layer "F.Cu")
		(net "M_E_CPU0_SB_DQ<24>")
	)
	(gr_poly
		(pts
			(xy 391.15238 -220.162374) (xy 391.15238 -219.971874) (xy 391.05078 -219.935806) (xy 390.99998 -219.935806)
			(xy 390.99998 -220.198696) (xy 391.05078 -220.198696)
		)
		(stroke
			(width 0)
			(type solid)
		)
		(fill yes)
		(layer "F.Cu")
		(net "M_E_CPU0_SB_DQ<24>")
	)
	(gr_poly
		(pts
			(xy 391.15238 -219.565474) (xy 391.15238 -219.374974) (xy 391.05078 -219.338906) (xy 390.99998 -219.338906)
			(xy 390.99998 -219.601796) (xy 391.05078 -219.601796)
		)
		(stroke
			(width 0)
			(type solid)
		)
		(fill yes)
		(layer "F.Cu")
		(net "M_E_CPU0_SB_DQ<24>")
	)
	(gr_poly
		(pts
			(xy 391.15238 -218.968574) (xy 391.15238 -218.778074) (xy 391.05078 -218.742006) (xy 390.99998 -218.742006)
			(xy 390.99998 -219.004896) (xy 391.05078 -219.004896)
		)
		(stroke
			(width 0)
			(type solid)
		)
		(fill yes)
		(layer "F.Cu")
		(net "M_E_CPU0_SB_DQ<24>")
	)
	(gr_poly
		(pts
			(xy 391.15238 -218.371674) (xy 391.15238 -218.181174) (xy 391.05078 -218.145106) (xy 390.99998 -218.145106)
			(xy 390.99998 -218.407996) (xy 391.05078 -218.407996)
		)
		(stroke
			(width 0)
			(type solid)
		)
		(fill yes)
		(layer "F.Cu")
		(net "M_E_CPU0_SB_DQ<24>")
	)
	(gr_poly
		(pts
			(xy 391.15238 -217.774774) (xy 391.15238 -217.584274) (xy 391.05078 -217.548206) (xy 390.99998 -217.548206)
			(xy 390.99998 -217.811096) (xy 391.05078 -217.811096)
		)
		(stroke
			(width 0)
			(type solid)
		)
		(fill yes)
		(layer "F.Cu")
		(net "M_E_CPU0_SB_DQ<24>")
	)
	(gr_poly
		(pts
			(xy 391.15238 -217.177874) (xy 391.15238 -216.987374) (xy 391.05078 -216.951306) (xy 390.99998 -216.951306)
			(xy 390.99998 -217.214196) (xy 391.05078 -217.214196)
		)
		(stroke
			(width 0)
			(type solid)
		)
		(fill yes)
		(layer "F.Cu")
		(net "M_E_CPU0_SB_DQ<24>")
	)
	(gr_poly
		(pts
			(xy 391.15238 -216.580974) (xy 391.15238 -216.390474) (xy 391.05078 -216.354406) (xy 390.99998 -216.354406)
			(xy 390.99998 -216.617296) (xy 391.05078 -216.617296)
		)
		(stroke
			(width 0)
			(type solid)
		)
		(fill yes)
		(layer "F.Cu")
		(net "M_E_CPU0_SB_DQ<24>")
	)
	(gr_poly
		(pts
			(xy 391.15238 -215.984074) (xy 391.15238 -215.793574) (xy 391.05078 -215.757506) (xy 390.99998 -215.757506)
			(xy 390.99998 -216.020396) (xy 391.05078 -216.020396)
		)
		(stroke
			(width 0)
			(type solid)
		)
		(fill yes)
		(layer "F.Cu")
		(net "M_E_CPU0_SB_DQ<24>")
	)
	(gr_poly
		(pts
			(xy 391.154412 -256.4257) (xy 391.20064 -256.328164) (xy 391.06602 -256.193544) (xy 390.968738 -256.239772)
			(xy 390.93267 -256.275586) (xy 391.118598 -256.461514)
		)
		(stroke
			(width 0)
			(type solid)
		)
		(fill yes)
		(layer "F.Cu")
		(net "M_E_CPU0_SA_CA<3>")
	)
	(gr_poly
		(pts
			(xy 391.163048 -237.695232) (xy 391.11682 -237.59795) (xy 391.081006 -237.561882) (xy 390.895078 -237.74781)
			(xy 390.931146 -237.783878) (xy 391.028428 -237.830106)
		)
		(stroke
			(width 0)
			(type solid)
		)
		(fill yes)
		(layer "F.Cu")
		(net "M_E_CPU0_SB_DQ<9>")
	)
	(gr_poly
		(pts
			(xy 391.16381 -255.57226) (xy 391.210038 -255.474724) (xy 391.075164 -255.340104) (xy 390.977882 -255.386332)
			(xy 390.941814 -255.422146) (xy 391.127742 -255.608074)
		)
		(stroke
			(width 0)
			(type solid)
		)
		(fill yes)
		(layer "F.Cu")
		(net "M_E_CPU0_SA_CA<5>")
	)
	(gr_poly
		(pts
			(xy 391.164572 -277.826216) (xy 391.257282 -277.770844) (xy 391.219944 -277.584154) (xy 391.113264 -277.56866)
			(xy 391.063226 -277.578566) (xy 391.114788 -277.836376)
		)
		(stroke
			(width 0)
			(type solid)
		)
		(fill yes)
		(layer "F.Cu")
		(net "M_E_CPU0_SA_DQ<17>")
	)
	(gr_poly
		(pts
			(xy 391.167112 -267.397738) (xy 391.21334 -267.300202) (xy 391.078466 -267.165582) (xy 390.981184 -267.21181)
			(xy 390.945116 -267.247624) (xy 391.131044 -267.433552)
		)
		(stroke
			(width 0)
			(type solid)
		)
		(fill yes)
		(layer "F.Cu")
		(net "M_E_CPU0_SA_DQ<30>")
	)
	(gr_poly
		(pts
			(xy 391.172954 -254.71882) (xy 391.219182 -254.621538) (xy 391.084562 -254.486664) (xy 390.987026 -254.532892)
			(xy 390.951212 -254.56896) (xy 391.13714 -254.754888)
		)
		(stroke
			(width 0)
			(type solid)
		)
		(fill yes)
		(layer "F.Cu")
		(net "M_E_CPU0_SA_PAR")
	)
	(gr_poly
		(pts
			(xy 391.173208 -238.549434) (xy 391.12698 -238.452152) (xy 391.091166 -238.416084) (xy 390.905238 -238.602012)
			(xy 390.941052 -238.63808) (xy 391.038588 -238.684308)
		)
		(stroke
			(width 0)
			(type solid)
		)
		(fill yes)
		(layer "F.Cu")
		(net "M_E_CPU0_SB_DQ<8>")
	)
	(gr_poly
		(pts
			(xy 391.173462 -278.128984) (xy 391.1219 -277.871174) (xy 391.072116 -277.88108) (xy 390.979406 -277.936452)
			(xy 391.016744 -278.123396) (xy 391.123678 -278.13889)
		)
		(stroke
			(width 0)
			(type solid)
		)
		(fill yes)
		(layer "F.Cu")
		(net "M_E_CPU0_SA_DQ<17>")
	)
	(gr_poly
		(pts
			(xy 391.17651 -266.544044) (xy 391.222738 -266.446508) (xy 391.088118 -266.311888) (xy 390.990582 -266.358116)
			(xy 390.954768 -266.394184) (xy 391.140442 -266.579858)
		)
		(stroke
			(width 0)
			(type solid)
		)
		(fill yes)
		(layer "F.Cu")
		(net "M_E_CPU0_SA_DQ<31>")
	)
	(gr_poly
		(pts
			(xy 391.177018 -289.772598) (xy 391.177018 -289.582098) (xy 391.075418 -289.54603) (xy 391.024618 -289.54603)
			(xy 391.024618 -289.80892) (xy 391.075418 -289.80892)
		)
		(stroke
			(width 0)
			(type solid)
		)
		(fill yes)
		(layer "F.Cu")
		(net "M_E_CPU0_SA_DQ<16>")
	)
	(gr_poly
		(pts
			(xy 391.177018 -289.175698) (xy 391.177018 -288.985198) (xy 391.075418 -288.94913) (xy 391.024618 -288.94913)
			(xy 391.024618 -289.21202) (xy 391.075418 -289.21202)
		)
		(stroke
			(width 0)
			(type solid)
		)
		(fill yes)
		(layer "F.Cu")
		(net "M_E_CPU0_SA_DQ<16>")
	)
	(gr_poly
		(pts
			(xy 391.177018 -288.578798) (xy 391.177018 -288.388298) (xy 391.075418 -288.35223) (xy 391.024618 -288.35223)
			(xy 391.024618 -288.61512) (xy 391.075418 -288.61512)
		)
		(stroke
			(width 0)
			(type solid)
		)
		(fill yes)
		(layer "F.Cu")
		(net "M_E_CPU0_SA_DQ<16>")
	)
	(gr_poly
		(pts
			(xy 391.177018 -287.981898) (xy 391.177018 -287.791398) (xy 391.075418 -287.75533) (xy 391.024618 -287.75533)
			(xy 391.024618 -288.01822) (xy 391.075418 -288.01822)
		)
		(stroke
			(width 0)
			(type solid)
		)
		(fill yes)
		(layer "F.Cu")
		(net "M_E_CPU0_SA_DQ<16>")
	)
	(gr_poly
		(pts
			(xy 391.177018 -287.384998) (xy 391.177018 -287.194498) (xy 391.075418 -287.15843) (xy 391.024618 -287.15843)
			(xy 391.024618 -287.42132) (xy 391.075418 -287.42132)
		)
		(stroke
			(width 0)
			(type solid)
		)
		(fill yes)
		(layer "F.Cu")
		(net "M_E_CPU0_SA_DQ<16>")
	)
	(gr_poly
		(pts
			(xy 391.177018 -286.788098) (xy 391.177018 -286.597598) (xy 391.075418 -286.56153) (xy 391.024618 -286.56153)
			(xy 391.024618 -286.82442) (xy 391.075418 -286.82442)
		)
		(stroke
			(width 0)
			(type solid)
		)
		(fill yes)
		(layer "F.Cu")
		(net "M_E_CPU0_SA_DQ<16>")
	)
	(gr_poly
		(pts
			(xy 391.177018 -286.191198) (xy 391.177018 -286.000698) (xy 391.075418 -285.96463) (xy 391.024618 -285.96463)
			(xy 391.024618 -286.22752) (xy 391.075418 -286.22752)
		)
		(stroke
			(width 0)
			(type solid)
		)
		(fill yes)
		(layer "F.Cu")
		(net "M_E_CPU0_SA_DQ<16>")
	)
	(gr_poly
		(pts
			(xy 391.177018 -285.594298) (xy 391.177018 -285.403798) (xy 391.075418 -285.36773) (xy 391.024618 -285.36773)
			(xy 391.024618 -285.63062) (xy 391.075418 -285.63062)
		)
		(stroke
			(width 0)
			(type solid)
		)
		(fill yes)
		(layer "F.Cu")
		(net "M_E_CPU0_SA_DQ<16>")
	)
	(gr_poly
		(pts
			(xy 391.177018 -284.997398) (xy 391.177018 -284.806898) (xy 391.075418 -284.77083) (xy 391.024618 -284.77083)
			(xy 391.024618 -285.03372) (xy 391.075418 -285.03372)
		)
		(stroke
			(width 0)
			(type solid)
		)
		(fill yes)
		(layer "F.Cu")
		(net "M_E_CPU0_SA_DQ<16>")
	)
	(gr_poly
		(pts
			(xy 391.177018 -284.400498) (xy 391.177018 -284.209998) (xy 391.075418 -284.17393) (xy 391.024618 -284.17393)
			(xy 391.024618 -284.43682) (xy 391.075418 -284.43682)
		)
		(stroke
			(width 0)
			(type solid)
		)
		(fill yes)
		(layer "F.Cu")
		(net "M_E_CPU0_SA_DQ<16>")
	)
	(gr_poly
		(pts
			(xy 391.177018 -283.803598) (xy 391.177018 -283.613098) (xy 391.075418 -283.57703) (xy 391.024618 -283.57703)
			(xy 391.024618 -283.83992) (xy 391.075418 -283.83992)
		)
		(stroke
			(width 0)
			(type solid)
		)
		(fill yes)
		(layer "F.Cu")
		(net "M_E_CPU0_SA_DQ<16>")
	)
	(gr_poly
		(pts
			(xy 391.177018 -283.206698) (xy 391.177018 -283.016198) (xy 391.075418 -282.98013) (xy 391.024618 -282.98013)
			(xy 391.024618 -283.24302) (xy 391.075418 -283.24302)
		)
		(stroke
			(width 0)
			(type solid)
		)
		(fill yes)
		(layer "F.Cu")
		(net "M_E_CPU0_SA_DQ<16>")
	)
	(gr_poly
		(pts
			(xy 391.177018 -282.609798) (xy 391.177018 -282.419298) (xy 391.075418 -282.38323) (xy 391.024618 -282.38323)
			(xy 391.024618 -282.64612) (xy 391.075418 -282.64612)
		)
		(stroke
			(width 0)
			(type solid)
		)
		(fill yes)
		(layer "F.Cu")
		(net "M_E_CPU0_SA_DQ<16>")
	)
	(gr_poly
		(pts
			(xy 391.177018 -282.012898) (xy 391.177018 -281.822398) (xy 391.075418 -281.78633) (xy 391.024618 -281.78633)
			(xy 391.024618 -282.04922) (xy 391.075418 -282.04922)
		)
		(stroke
			(width 0)
			(type solid)
		)
		(fill yes)
		(layer "F.Cu")
		(net "M_E_CPU0_SA_DQ<16>")
	)
	(gr_poly
		(pts
			(xy 391.177018 -281.415998) (xy 391.177018 -281.225498) (xy 391.075418 -281.18943) (xy 391.024618 -281.18943)
			(xy 391.024618 -281.45232) (xy 391.075418 -281.45232)
		)
		(stroke
			(width 0)
			(type solid)
		)
		(fill yes)
		(layer "F.Cu")
		(net "M_E_CPU0_SA_DQ<16>")
	)
	(gr_poly
		(pts
			(xy 391.189718 -273.045428) (xy 391.235946 -272.947892) (xy 391.101072 -272.813272) (xy 391.00379 -272.8595)
			(xy 390.967722 -272.895314) (xy 391.15365 -273.081242)
		)
		(stroke
			(width 0)
			(type solid)
		)
		(fill yes)
		(layer "F.Cu")
		(net "M_E_CPU0_SA_DQ<22>")
	)
	(gr_poly
		(pts
			(xy 391.190988 -262.34898) (xy 391.237216 -262.251444) (xy 391.102342 -262.116824) (xy 391.00506 -262.163052)
			(xy 390.968992 -262.198866) (xy 391.15492 -262.384794)
		)
		(stroke
			(width 0)
			(type solid)
		)
		(fill yes)
		(layer "F.Cu")
		(net "M_E_CPU0_SA_CB<4>")
	)
	(gr_poly
		(pts
			(xy 391.19683 -240.15954) (xy 391.160508 -240.05794) (xy 390.970008 -240.05794) (xy 390.93394 -240.15954)
			(xy 390.93394 -240.21034) (xy 391.19683 -240.21034)
		)
		(stroke
			(width 0)
			(type solid)
		)
		(fill yes)
		(layer "F.Cu")
		(net "M_E_CPU0_SB_CB<0>")
	)
	(gr_poly
		(pts
			(xy 391.198608 -271.347946) (xy 391.244836 -271.25041) (xy 391.109962 -271.11579) (xy 391.01268 -271.162018)
			(xy 390.976612 -271.197832) (xy 391.16254 -271.38376)
		)
		(stroke
			(width 0)
			(type solid)
		)
		(fill yes)
		(layer "F.Cu")
		(net "M_E_CPU0_SA_DQ<24>")
	)
	(gr_poly
		(pts
			(xy 391.198862 -272.191734) (xy 391.24509 -272.094452) (xy 391.11047 -271.959578) (xy 391.012934 -272.005806)
			(xy 390.97712 -272.041874) (xy 391.163048 -272.227802)
		)
		(stroke
			(width 0)
			(type solid)
		)
		(fill yes)
		(layer "F.Cu")
		(net "M_E_CPU0_SA_DQ<23>")
	)
	(gr_poly
		(pts
			(xy 391.200132 -261.49554) (xy 391.24636 -261.398258) (xy 391.11174 -261.263384) (xy 391.014204 -261.309612)
			(xy 390.97839 -261.34568) (xy 391.164318 -261.531608)
		)
		(stroke
			(width 0)
			(type solid)
		)
		(fill yes)
		(layer "F.Cu")
		(net "M_E_CPU0_SA_CB<5>")
	)
	(gr_poly
		(pts
			(xy 391.207752 -270.494506) (xy 391.25398 -270.39697) (xy 391.119106 -270.26235) (xy 391.021824 -270.308578)
			(xy 390.985756 -270.344392) (xy 391.171684 -270.53032)
		)
		(stroke
			(width 0)
			(type solid)
		)
		(fill yes)
		(layer "F.Cu")
		(net "M_E_CPU0_SA_DQ<25>")
	)
	(gr_poly
		(pts
			(xy 391.213086 -228.822758) (xy 391.177018 -228.786944) (xy 391.079736 -228.740716) (xy 390.944862 -228.875336)
			(xy 390.991344 -228.972872) (xy 391.027158 -229.008686)
		)
		(stroke
			(width 0)
			(type solid)
		)
		(fill yes)
		(layer "F.Cu")
		(net "M_E_CPU0_SB_DQ<22>")
	)
	(gr_poly
		(pts
			(xy 391.216642 -279.642062) (xy 391.309098 -279.58669) (xy 391.27176 -279.399746) (xy 391.16508 -279.384252)
			(xy 391.115296 -279.394158) (xy 391.166858 -279.651968)
		)
		(stroke
			(width 0)
			(type solid)
		)
		(fill yes)
		(layer "F.Cu")
		(net "M_E_CPU0_SA_DQ<18>")
	)
	(gr_poly
		(pts
			(xy 391.225278 -279.944576) (xy 391.173716 -279.686766) (xy 391.123932 -279.696926) (xy 391.031476 -279.752298)
			(xy 391.068814 -279.938988) (xy 391.175494 -279.954482)
		)
		(stroke
			(width 0)
			(type solid)
		)
		(fill yes)
		(layer "F.Cu")
		(net "M_E_CPU0_SA_DQ<18>")
	)
	(gr_poly
		(pts
			(xy 391.225532 -242.700556) (xy 391.225532 -242.649756) (xy 390.962642 -242.649756) (xy 390.962642 -242.700556)
			(xy 390.998964 -242.802156) (xy 391.189464 -242.802156)
		)
		(stroke
			(width 0)
			(type solid)
		)
		(fill yes)
		(layer "F.Cu")
		(net "M_E_CPU0_SB_CB<4>")
	)
	(gr_poly
		(pts
			(xy 391.225532 -242.395756) (xy 391.225532 -242.344956) (xy 390.962642 -242.344956) (xy 390.962642 -242.395756)
			(xy 390.998964 -242.497356) (xy 391.189464 -242.497356)
		)
		(stroke
			(width 0)
			(type solid)
		)
		(fill yes)
		(layer "F.Cu")
		(net "M_E_CPU0_SB_CB<6>")
	)
	(gr_poly
		(pts
			(xy 391.225532 -242.090956) (xy 391.225532 -242.040156) (xy 390.962642 -242.040156) (xy 390.962642 -242.090956)
			(xy 390.998964 -242.192556) (xy 391.189464 -242.192556)
		)
		(stroke
			(width 0)
			(type solid)
		)
		(fill yes)
		(layer "F.Cu")
		(net "M_E_CPU0_SB_CB<5>")
	)
	(gr_poly
		(pts
			(xy 391.225532 -241.786156) (xy 391.225532 -241.735356) (xy 390.962642 -241.735356) (xy 390.962642 -241.786156)
			(xy 390.998964 -241.887756) (xy 391.189464 -241.887756)
		)
		(stroke
			(width 0)
			(type solid)
		)
		(fill yes)
		(layer "F.Cu")
		(net "M_E_CPU0_SB_CB<7>")
	)
	(gr_poly
		(pts
			(xy 391.230358 -276.59584) (xy 391.322814 -276.540468) (xy 391.285476 -276.353778) (xy 391.178796 -276.33803)
			(xy 391.129012 -276.347936) (xy 391.18032 -276.605746)
		)
		(stroke
			(width 0)
			(type solid)
		)
		(fill yes)
		(layer "F.Cu")
		(net "M_E_CPU0_SA_DQ<19>")
	)
	(gr_poly
		(pts
			(xy 391.238994 -276.898608) (xy 391.187432 -276.640798) (xy 391.137648 -276.650704) (xy 391.044938 -276.706076)
			(xy 391.082276 -276.892766) (xy 391.18921 -276.908514)
		)
		(stroke
			(width 0)
			(type solid)
		)
		(fill yes)
		(layer "F.Cu")
		(net "M_E_CPU0_SA_DQ<19>")
	)
	(gr_poly
		(pts
			(xy 391.24001 -231.384094) (xy 391.203942 -231.34828) (xy 391.10666 -231.302052) (xy 390.971786 -231.436672)
			(xy 391.018014 -231.534208) (xy 391.054082 -231.570022)
		)
		(stroke
			(width 0)
			(type solid)
		)
		(fill yes)
		(layer "F.Cu")
		(net "M_E_CPU0_SB_DQ<19>")
	)
	(gr_poly
		(pts
			(xy 391.249154 -232.237534) (xy 391.213086 -232.20172) (xy 391.115804 -232.155492) (xy 390.981184 -232.290112)
			(xy 391.027412 -232.387648) (xy 391.063226 -232.423462)
		)
		(stroke
			(width 0)
			(type solid)
		)
		(fill yes)
		(layer "F.Cu")
		(net "M_E_CPU0_SB_DQ<18>")
	)
	(gr_poly
		(pts
			(xy 391.25779 -233.934762) (xy 391.221976 -233.898694) (xy 391.12444 -233.852466) (xy 390.98982 -233.987086)
			(xy 391.036048 -234.084622) (xy 391.072116 -234.120436)
		)
		(stroke
			(width 0)
			(type solid)
		)
		(fill yes)
		(layer "F.Cu")
		(net "M_E_CPU0_SB_DQ<13>")
	)
	(gr_poly
		(pts
			(xy 391.267188 -234.787948) (xy 391.23112 -234.752134) (xy 391.133838 -234.705906) (xy 390.998964 -234.840526)
			(xy 391.045192 -234.938062) (xy 391.08126 -234.973876)
		)
		(stroke
			(width 0)
			(type solid)
		)
		(fill yes)
		(layer "F.Cu")
		(net "M_E_CPU0_SB_DQ<12>")
	)
	(gr_poly
		(pts
			(xy 391.272776 -266.02563) (xy 391.308844 -265.989816) (xy 391.122916 -265.803888) (xy 391.086848 -265.839702)
			(xy 391.04062 -265.937238) (xy 391.175494 -266.071858)
		)
		(stroke
			(width 0)
			(type solid)
		)
		(fill yes)
		(layer "F.Cu")
		(net "M_E_CPU0_SA_CB<0>")
	)
	(gr_poly
		(pts
			(xy 391.275316 -258.415282) (xy 391.31113 -258.379214) (xy 391.125202 -258.193286) (xy 391.089388 -258.229354)
			(xy 391.04316 -258.326636) (xy 391.17778 -258.46151)
		)
		(stroke
			(width 0)
			(type solid)
		)
		(fill yes)
		(layer "F.Cu")
		(net "M_E_CPU0_SA_CS_N<3>")
	)
	(gr_poly
		(pts
			(xy 391.281666 -278.411686) (xy 391.374122 -278.356314) (xy 391.336784 -278.16937) (xy 391.230104 -278.153876)
			(xy 391.18032 -278.163782) (xy 391.231882 -278.421592)
		)
		(stroke
			(width 0)
			(type solid)
		)
		(fill yes)
		(layer "F.Cu")
		(net "M_E_CPU0_SA_DQ<17>")
	)
	(gr_poly
		(pts
			(xy 391.282174 -265.17219) (xy 391.317988 -265.136376) (xy 391.13206 -264.950448) (xy 391.096246 -264.986262)
			(xy 391.050018 -265.083798) (xy 391.184638 -265.218418)
		)
		(stroke
			(width 0)
			(type solid)
		)
		(fill yes)
		(layer "F.Cu")
		(net "M_E_CPU0_SA_CB<1>")
	)
	(gr_poly
		(pts
			(xy 391.28446 -257.561842) (xy 391.320528 -257.526028) (xy 391.1346 -257.3401) (xy 391.098532 -257.375914)
			(xy 391.052304 -257.47345) (xy 391.187178 -257.60807)
		)
		(stroke
			(width 0)
			(type solid)
		)
		(fill yes)
		(layer "F.Cu")
		(net "M_E_CPU0_SA_CA<1>")
	)
	(gr_poly
		(pts
			(xy 391.290302 -278.7142) (xy 391.23874 -278.45639) (xy 391.188956 -278.46655) (xy 391.0965 -278.521922)
			(xy 391.133838 -278.708612) (xy 391.240518 -278.724106)
		)
		(stroke
			(width 0)
			(type solid)
		)
		(fill yes)
		(layer "F.Cu")
		(net "M_E_CPU0_SA_DQ<17>")
	)
	(gr_poly
		(pts
			(xy 391.290556 -228.529388) (xy 391.244328 -228.432106) (xy 391.208514 -228.396038) (xy 391.022586 -228.581966)
			(xy 391.0584 -228.618034) (xy 391.155936 -228.664262)
		)
		(stroke
			(width 0)
			(type solid)
		)
		(fill yes)
		(layer "F.Cu")
		(net "M_E_CPU0_SB_DQ<21>")
	)
	(gr_poly
		(pts
			(xy 391.29208 -237.351062) (xy 391.256266 -237.314994) (xy 391.15873 -237.268766) (xy 391.02411 -237.403386)
			(xy 391.070338 -237.500922) (xy 391.106152 -237.536736)
		)
		(stroke
			(width 0)
			(type solid)
		)
		(fill yes)
		(layer "F.Cu")
		(net "M_E_CPU0_SB_DQ<9>")
	)
	(gr_poly
		(pts
			(xy 391.293604 -256.708402) (xy 391.329672 -256.672588) (xy 391.143744 -256.48666) (xy 391.10793 -256.522474)
			(xy 391.061448 -256.62001) (xy 391.196322 -256.75463)
		)
		(stroke
			(width 0)
			(type solid)
		)
		(fill yes)
		(layer "F.Cu")
		(net "M_E_CPU0_SA_CA<3>")
	)
	(gr_poly
		(pts
			(xy 391.2997 -229.382828) (xy 391.253472 -229.285292) (xy 391.217658 -229.249478) (xy 391.03173 -229.435406)
			(xy 391.067544 -229.47122) (xy 391.16508 -229.517448)
		)
		(stroke
			(width 0)
			(type solid)
		)
		(fill yes)
		(layer "F.Cu")
		(net "M_E_CPU0_SB_DQ<20>")
	)
	(gr_poly
		(pts
			(xy 391.301986 -238.205264) (xy 391.266172 -238.169196) (xy 391.168636 -238.122968) (xy 391.034016 -238.257588)
			(xy 391.080244 -238.355124) (xy 391.116312 -238.390938)
		)
		(stroke
			(width 0)
			(type solid)
		)
		(fill yes)
		(layer "F.Cu")
		(net "M_E_CPU0_SB_DQ<8>")
	)
	(gr_poly
		(pts
			(xy 391.303002 -255.855216) (xy 391.338816 -255.819148) (xy 391.152888 -255.63322) (xy 391.117074 -255.669288)
			(xy 391.070846 -255.76657) (xy 391.205466 -255.901444)
		)
		(stroke
			(width 0)
			(type solid)
		)
		(fill yes)
		(layer "F.Cu")
		(net "M_E_CPU0_SA_CA<5>")
	)
	(gr_poly
		(pts
			(xy 391.306304 -267.68044) (xy 391.342118 -267.644626) (xy 391.15619 -267.458698) (xy 391.120376 -267.494766)
			(xy 391.074148 -267.592048) (xy 391.208768 -267.726922)
		)
		(stroke
			(width 0)
			(type solid)
		)
		(fill yes)
		(layer "F.Cu")
		(net "M_E_CPU0_SA_DQ<30>")
	)
	(gr_poly
		(pts
			(xy 391.312146 -255.001776) (xy 391.34796 -254.965708) (xy 391.162286 -254.780034) (xy 391.126218 -254.815848)
			(xy 391.07999 -254.913384) (xy 391.21461 -255.048004)
		)
		(stroke
			(width 0)
			(type solid)
		)
		(fill yes)
		(layer "F.Cu")
		(net "M_E_CPU0_SA_PAR")
	)
	(gr_poly
		(pts
			(xy 391.315702 -266.827) (xy 391.351516 -266.790932) (xy 391.165588 -266.605004) (xy 391.129774 -266.641072)
			(xy 391.083546 -266.738354) (xy 391.218166 -266.873228)
		)
		(stroke
			(width 0)
			(type solid)
		)
		(fill yes)
		(layer "F.Cu")
		(net "M_E_CPU0_SA_DQ<31>")
	)
	(gr_poly
		(pts
			(xy 391.326624 -231.944164) (xy 391.280396 -231.846882) (xy 391.244582 -231.810814) (xy 391.058654 -231.996742)
			(xy 391.094468 -232.03281) (xy 391.192004 -232.079038)
		)
		(stroke
			(width 0)
			(type solid)
		)
		(fill yes)
		(layer "F.Cu")
		(net "M_E_CPU0_SB_DQ<17>")
	)
	(gr_poly
		(pts
			(xy 391.32891 -273.32813) (xy 391.364724 -273.292316) (xy 391.178796 -273.106388) (xy 391.142982 -273.142456)
			(xy 391.096754 -273.239738) (xy 391.231374 -273.374612)
		)
		(stroke
			(width 0)
			(type solid)
		)
		(fill yes)
		(layer "F.Cu")
		(net "M_E_CPU0_SA_DQ<22>")
	)
	(gr_poly
		(pts
			(xy 391.329418 -289.247326) (xy 391.278618 -289.247326) (xy 391.177018 -289.283648) (xy 391.177018 -289.474148)
			(xy 391.278618 -289.51047) (xy 391.329418 -289.51047)
		)
		(stroke
			(width 0)
			(type solid)
		)
		(fill yes)
		(layer "F.Cu")
		(net "M_E_CPU0_SA_DQ<18>")
	)
	(gr_poly
		(pts
			(xy 391.329418 -288.650426) (xy 391.278618 -288.650426) (xy 391.177018 -288.686748) (xy 391.177018 -288.877248)
			(xy 391.278618 -288.91357) (xy 391.329418 -288.91357)
		)
		(stroke
			(width 0)
			(type solid)
		)
		(fill yes)
		(layer "F.Cu")
		(net "M_E_CPU0_SA_DQ<18>")
	)
	(gr_poly
		(pts
			(xy 391.329418 -288.053526) (xy 391.278618 -288.053526) (xy 391.177018 -288.089848) (xy 391.177018 -288.280348)
			(xy 391.278618 -288.31667) (xy 391.329418 -288.31667)
		)
		(stroke
			(width 0)
			(type solid)
		)
		(fill yes)
		(layer "F.Cu")
		(net "M_E_CPU0_SA_DQ<18>")
	)
	(gr_poly
		(pts
			(xy 391.329418 -287.456626) (xy 391.278618 -287.456626) (xy 391.177018 -287.492948) (xy 391.177018 -287.683448)
			(xy 391.278618 -287.71977) (xy 391.329418 -287.71977)
		)
		(stroke
			(width 0)
			(type solid)
		)
		(fill yes)
		(layer "F.Cu")
		(net "M_E_CPU0_SA_DQ<18>")
	)
	(gr_poly
		(pts
			(xy 391.329418 -286.859726) (xy 391.278618 -286.859726) (xy 391.177018 -286.896048) (xy 391.177018 -287.086548)
			(xy 391.278618 -287.12287) (xy 391.329418 -287.12287)
		)
		(stroke
			(width 0)
			(type solid)
		)
		(fill yes)
		(layer "F.Cu")
		(net "M_E_CPU0_SA_DQ<18>")
	)
	(gr_poly
		(pts
			(xy 391.329418 -286.262826) (xy 391.278618 -286.262826) (xy 391.177018 -286.299148) (xy 391.177018 -286.489648)
			(xy 391.278618 -286.52597) (xy 391.329418 -286.52597)
		)
		(stroke
			(width 0)
			(type solid)
		)
		(fill yes)
		(layer "F.Cu")
		(net "M_E_CPU0_SA_DQ<18>")
	)
	(gr_poly
		(pts
			(xy 391.329418 -285.665926) (xy 391.278618 -285.665926) (xy 391.177018 -285.702248) (xy 391.177018 -285.892748)
			(xy 391.278618 -285.92907) (xy 391.329418 -285.92907)
		)
		(stroke
			(width 0)
			(type solid)
		)
		(fill yes)
		(layer "F.Cu")
		(net "M_E_CPU0_SA_DQ<18>")
	)
	(gr_poly
		(pts
			(xy 391.329418 -285.069026) (xy 391.278618 -285.069026) (xy 391.177018 -285.105348) (xy 391.177018 -285.295848)
			(xy 391.278618 -285.33217) (xy 391.329418 -285.33217)
		)
		(stroke
			(width 0)
			(type solid)
		)
		(fill yes)
		(layer "F.Cu")
		(net "M_E_CPU0_SA_DQ<18>")
	)
	(gr_poly
		(pts
			(xy 391.329418 -284.472126) (xy 391.278618 -284.472126) (xy 391.177018 -284.508448) (xy 391.177018 -284.698948)
			(xy 391.278618 -284.73527) (xy 391.329418 -284.73527)
		)
		(stroke
			(width 0)
			(type solid)
		)
		(fill yes)
		(layer "F.Cu")
		(net "M_E_CPU0_SA_DQ<18>")
	)
	(gr_poly
		(pts
			(xy 391.329418 -283.875226) (xy 391.278618 -283.875226) (xy 391.177018 -283.911548) (xy 391.177018 -284.102048)
			(xy 391.278618 -284.13837) (xy 391.329418 -284.13837)
		)
		(stroke
			(width 0)
			(type solid)
		)
		(fill yes)
		(layer "F.Cu")
		(net "M_E_CPU0_SA_DQ<18>")
	)
	(gr_poly
		(pts
			(xy 391.329418 -283.278326) (xy 391.278618 -283.278326) (xy 391.177018 -283.314648) (xy 391.177018 -283.505148)
			(xy 391.278618 -283.54147) (xy 391.329418 -283.54147)
		)
		(stroke
			(width 0)
			(type solid)
		)
		(fill yes)
		(layer "F.Cu")
		(net "M_E_CPU0_SA_DQ<18>")
	)
	(gr_poly
		(pts
			(xy 391.329418 -282.681426) (xy 391.278618 -282.681426) (xy 391.177018 -282.717748) (xy 391.177018 -282.908248)
			(xy 391.278618 -282.94457) (xy 391.329418 -282.94457)
		)
		(stroke
			(width 0)
			(type solid)
		)
		(fill yes)
		(layer "F.Cu")
		(net "M_E_CPU0_SA_DQ<18>")
	)
	(gr_poly
		(pts
			(xy 391.329418 -282.084526) (xy 391.278618 -282.084526) (xy 391.177018 -282.120848) (xy 391.177018 -282.311348)
			(xy 391.278618 -282.34767) (xy 391.329418 -282.34767)
		)
		(stroke
			(width 0)
			(type solid)
		)
		(fill yes)
		(layer "F.Cu")
		(net "M_E_CPU0_SA_DQ<18>")
	)
	(gr_poly
		(pts
			(xy 391.329418 -281.487626) (xy 391.278618 -281.487626) (xy 391.177018 -281.523948) (xy 391.177018 -281.714448)
			(xy 391.278618 -281.75077) (xy 391.329418 -281.75077)
		)
		(stroke
			(width 0)
			(type solid)
		)
		(fill yes)
		(layer "F.Cu")
		(net "M_E_CPU0_SA_DQ<18>")
	)
	(gr_poly
		(pts
			(xy 391.329418 -280.890726) (xy 391.278618 -280.890726) (xy 391.177018 -280.927048) (xy 391.177018 -281.117548)
			(xy 391.278618 -281.15387) (xy 391.329418 -281.15387)
		)
		(stroke
			(width 0)
			(type solid)
		)
		(fill yes)
		(layer "F.Cu")
		(net "M_E_CPU0_SA_DQ<18>")
	)
	(gr_poly
		(pts
			(xy 391.33018 -262.631936) (xy 391.365994 -262.595868) (xy 391.180066 -262.40994) (xy 391.144252 -262.446008)
			(xy 391.098024 -262.54329) (xy 391.232644 -262.678164)
		)
		(stroke
			(width 0)
			(type solid)
		)
		(fill yes)
		(layer "F.Cu")
		(net "M_E_CPU0_SA_CB<4>")
	)
	(gr_poly
		(pts
			(xy 391.333736 -280.227278) (xy 391.426192 -280.171906) (xy 391.388854 -279.985216) (xy 391.282174 -279.969468)
			(xy 391.23239 -279.979374) (xy 391.283952 -280.237184)
		)
		(stroke
			(width 0)
			(type solid)
		)
		(fill yes)
		(layer "F.Cu")
		(net "M_E_CPU0_SA_DQ<18>")
	)
	(gr_poly
		(pts
			(xy 391.335514 -233.641392) (xy 391.289286 -233.543856) (xy 391.253218 -233.508042) (xy 391.06729 -233.69397)
			(xy 391.103358 -233.729784) (xy 391.20064 -233.776012)
		)
		(stroke
			(width 0)
			(type solid)
		)
		(fill yes)
		(layer "F.Cu")
		(net "M_E_CPU0_SB_DQ<15>")
	)
	(gr_poly
		(pts
			(xy 391.336022 -232.797604) (xy 391.28954 -232.700068) (xy 391.253726 -232.664254) (xy 391.067798 -232.850182)
			(xy 391.103866 -232.885996) (xy 391.201148 -232.932224)
		)
		(stroke
			(width 0)
			(type solid)
		)
		(fill yes)
		(layer "F.Cu")
		(net "M_E_CPU0_SB_DQ<16>")
	)
	(gr_poly
		(pts
			(xy 391.3378 -271.630648) (xy 391.373614 -271.594834) (xy 391.187686 -271.408906) (xy 391.151872 -271.444974)
			(xy 391.105644 -271.542256) (xy 391.240264 -271.67713)
		)
		(stroke
			(width 0)
			(type solid)
		)
		(fill yes)
		(layer "F.Cu")
		(net "M_E_CPU0_SA_DQ<24>")
	)
	(gr_poly
		(pts
			(xy 391.338054 -272.47469) (xy 391.374122 -272.438876) (xy 391.188194 -272.252948) (xy 391.152126 -272.288762)
			(xy 391.105898 -272.386298) (xy 391.240518 -272.520918)
		)
		(stroke
			(width 0)
			(type solid)
		)
		(fill yes)
		(layer "F.Cu")
		(net "M_E_CPU0_SA_DQ<23>")
	)
	(gr_poly
		(pts
			(xy 391.339324 -261.778496) (xy 391.375138 -261.742428) (xy 391.189464 -261.556754) (xy 391.153396 -261.592568)
			(xy 391.107168 -261.690104) (xy 391.241788 -261.824724)
		)
		(stroke
			(width 0)
			(type solid)
		)
		(fill yes)
		(layer "F.Cu")
		(net "M_E_CPU0_SA_CB<5>")
	)
	(gr_poly
		(pts
			(xy 391.342626 -258.77012) (xy 391.388854 -258.672584) (xy 391.25398 -258.537964) (xy 391.156698 -258.584192)
			(xy 391.12063 -258.620006) (xy 391.306558 -258.805934)
		)
		(stroke
			(width 0)
			(type solid)
		)
		(fill yes)
		(layer "F.Cu")
		(net "M_E_CPU0_SA_CS_N<1>")
	)
	(gr_poly
		(pts
			(xy 391.344658 -234.494578) (xy 391.29843 -234.397296) (xy 391.262616 -234.361228) (xy 391.076688 -234.547156)
			(xy 391.112502 -234.583224) (xy 391.210038 -234.629452)
		)
		(stroke
			(width 0)
			(type solid)
		)
		(fill yes)
		(layer "F.Cu")
		(net "M_E_CPU0_SB_DQ<14>")
	)
	(gr_poly
		(pts
			(xy 391.346944 -270.777208) (xy 391.382758 -270.741394) (xy 391.19683 -270.555466) (xy 391.161016 -270.591534)
			(xy 391.114788 -270.688816) (xy 391.249408 -270.82369)
		)
		(stroke
			(width 0)
			(type solid)
		)
		(fill yes)
		(layer "F.Cu")
		(net "M_E_CPU0_SA_DQ<25>")
	)
	(gr_poly
		(pts
			(xy 391.347198 -277.18131) (xy 391.439654 -277.125684) (xy 391.402316 -276.938994) (xy 391.295636 -276.9235)
			(xy 391.245852 -276.933406) (xy 391.297414 -277.191216)
		)
		(stroke
			(width 0)
			(type solid)
		)
		(fill yes)
		(layer "F.Cu")
		(net "M_E_CPU0_SA_DQ<19>")
	)
	(gr_poly
		(pts
			(xy 391.34923 -265.527028) (xy 391.395458 -265.429746) (xy 391.260838 -265.294872) (xy 391.163302 -265.3411)
			(xy 391.127488 -265.377168) (xy 391.313416 -265.563096)
		)
		(stroke
			(width 0)
			(type solid)
		)
		(fill yes)
		(layer "F.Cu")
		(net "M_E_CPU0_SA_CB<2>")
	)
	(gr_poly
		(pts
			(xy 391.35177 -257.91668) (xy 391.397998 -257.819144) (xy 391.263378 -257.684524) (xy 391.165842 -257.730752)
			(xy 391.130028 -257.76682) (xy 391.315702 -257.952494)
		)
		(stroke
			(width 0)
			(type solid)
		)
		(fill yes)
		(layer "F.Cu")
		(net "M_E_CPU0_SA_CA<0>")
	)
	(gr_poly
		(pts
			(xy 391.355834 -277.483824) (xy 391.304272 -277.226014) (xy 391.254488 -277.23592) (xy 391.162032 -277.291292)
			(xy 391.19937 -277.478236) (xy 391.30605 -277.49373)
		)
		(stroke
			(width 0)
			(type solid)
		)
		(fill yes)
		(layer "F.Cu")
		(net "M_E_CPU0_SA_DQ<19>")
	)
	(gr_poly
		(pts
			(xy 391.358374 -264.673842) (xy 391.404856 -264.576306) (xy 391.269982 -264.441686) (xy 391.1727 -264.487914)
			(xy 391.136632 -264.523728) (xy 391.32256 -264.709656)
		)
		(stroke
			(width 0)
			(type solid)
		)
		(fill yes)
		(layer "F.Cu")
		(net "M_E_CPU0_SA_CB<3>")
	)
	(gr_poly
		(pts
			(xy 391.360914 -257.06324) (xy 391.407142 -256.965958) (xy 391.272522 -256.831084) (xy 391.174986 -256.877312)
			(xy 391.139172 -256.91338) (xy 391.3251 -257.099308)
		)
		(stroke
			(width 0)
			(type solid)
		)
		(fill yes)
		(layer "F.Cu")
		(net "M_E_CPU0_SA_CA<2>")
	)
	(gr_poly
		(pts
			(xy 391.36955 -237.057692) (xy 391.323322 -236.960156) (xy 391.287508 -236.924342) (xy 391.10158 -237.110016)
			(xy 391.137394 -237.146084) (xy 391.23493 -237.192312)
		)
		(stroke
			(width 0)
			(type solid)
		)
		(fill yes)
		(layer "F.Cu")
		(net "M_E_CPU0_SB_DQ<11>")
	)
	(gr_poly
		(pts
			(xy 391.370058 -256.210054) (xy 391.416286 -256.112518) (xy 391.281666 -255.977898) (xy 391.184384 -256.024126)
			(xy 391.148316 -256.05994) (xy 391.334244 -256.245868)
		)
		(stroke
			(width 0)
			(type solid)
		)
		(fill yes)
		(layer "F.Cu")
		(net "M_E_CPU0_SA_CA<4>")
	)
	(gr_poly
		(pts
			(xy 391.37336 -268.035278) (xy 391.419588 -267.937996) (xy 391.284968 -267.803376) (xy 391.187432 -267.849604)
			(xy 391.151618 -267.885418) (xy 391.337546 -268.071346)
		)
		(stroke
			(width 0)
			(type solid)
		)
		(fill yes)
		(layer "F.Cu")
		(net "M_E_CPU0_SA_DQ<28>")
	)
	(gr_poly
		(pts
			(xy 391.379456 -255.356614) (xy 391.425684 -255.259078) (xy 391.29081 -255.124458) (xy 391.193528 -255.170686)
			(xy 391.15746 -255.2065) (xy 391.343388 -255.392428)
		)
		(stroke
			(width 0)
			(type solid)
		)
		(fill yes)
		(layer "F.Cu")
		(net "M_E_CPU0_SA_CA<6>")
	)
	(gr_poly
		(pts
			(xy 391.379456 -237.91164) (xy 391.333228 -237.814358) (xy 391.297414 -237.77829) (xy 391.111486 -237.964218)
			(xy 391.1473 -238.000032) (xy 391.244836 -238.046514)
		)
		(stroke
			(width 0)
			(type solid)
		)
		(fill yes)
		(layer "F.Cu")
		(net "M_E_CPU0_SB_DQ<10>")
	)
	(gr_poly
		(pts
			(xy 391.382758 -267.181838) (xy 391.428986 -267.084556) (xy 391.294366 -266.949682) (xy 391.19683 -266.99591)
			(xy 391.161016 -267.031978) (xy 391.346944 -267.217906)
		)
		(stroke
			(width 0)
			(type solid)
		)
		(fill yes)
		(layer "F.Cu")
		(net "M_E_CPU0_SA_DQ<29>")
	)
	(gr_poly
		(pts
			(xy 391.395966 -273.683222) (xy 391.442194 -273.58594) (xy 391.30732 -273.451066) (xy 391.210038 -273.497294)
			(xy 391.17397 -273.533362) (xy 391.359898 -273.71929)
		)
		(stroke
			(width 0)
			(type solid)
		)
		(fill yes)
		(layer "F.Cu")
		(net "M_E_CPU0_SA_DQ<20>")
	)
	(gr_poly
		(pts
			(xy 391.39622 -249.069352) (xy 391.39622 -249.018552) (xy 391.133076 -249.018552) (xy 391.133076 -249.069352)
			(xy 391.169398 -249.170952) (xy 391.359898 -249.170952)
		)
		(stroke
			(width 0)
			(type solid)
		)
		(fill yes)
		(layer "F.Cu")
		(net "M_E_CPU0_SB_CA<0>")
	)
	(gr_poly
		(pts
			(xy 391.39622 -248.764552) (xy 391.39622 -248.713752) (xy 391.133076 -248.713752) (xy 391.133076 -248.764552)
			(xy 391.169398 -248.866152) (xy 391.359898 -248.866152)
		)
		(stroke
			(width 0)
			(type solid)
		)
		(fill yes)
		(layer "F.Cu")
		(net "M_E_CPU0_SB_CA<1>")
	)
	(gr_poly
		(pts
			(xy 391.39622 -248.459752) (xy 391.39622 -248.408952) (xy 391.133076 -248.408952) (xy 391.133076 -248.459752)
			(xy 391.169398 -248.561352) (xy 391.359898 -248.561352)
		)
		(stroke
			(width 0)
			(type solid)
		)
		(fill yes)
		(layer "F.Cu")
		(net "M_E_CPU0_SB_CA<2>")
	)
	(gr_poly
		(pts
			(xy 391.39622 -248.154952) (xy 391.39622 -248.104152) (xy 391.133076 -248.104152) (xy 391.133076 -248.154952)
			(xy 391.169398 -248.256552) (xy 391.359898 -248.256552)
		)
		(stroke
			(width 0)
			(type solid)
		)
		(fill yes)
		(layer "F.Cu")
		(net "M_E_CPU0_SB_CA<3>")
	)
	(gr_poly
		(pts
			(xy 391.39622 -247.850152) (xy 391.39622 -247.799352) (xy 391.133076 -247.799352) (xy 391.133076 -247.850152)
			(xy 391.169398 -247.951752) (xy 391.359898 -247.951752)
		)
		(stroke
			(width 0)
			(type solid)
		)
		(fill yes)
		(layer "F.Cu")
		(net "M_E_CPU0_SB_CA<4>")
	)
	(gr_poly
		(pts
			(xy 391.39622 -247.545352) (xy 391.39622 -247.494552) (xy 391.133076 -247.494552) (xy 391.133076 -247.545352)
			(xy 391.169398 -247.646952) (xy 391.359898 -247.646952)
		)
		(stroke
			(width 0)
			(type solid)
		)
		(fill yes)
		(layer "F.Cu")
		(net "M_E_CPU0_SB_CA<5>")
	)
	(gr_poly
		(pts
			(xy 391.39622 -247.240552) (xy 391.39622 -247.189752) (xy 391.133076 -247.189752) (xy 391.133076 -247.240552)
			(xy 391.169398 -247.342152) (xy 391.359898 -247.342152)
		)
		(stroke
			(width 0)
			(type solid)
		)
		(fill yes)
		(layer "F.Cu")
		(net "M_E_CPU0_SB_CA<6>")
	)
	(gr_poly
		(pts
			(xy 391.39622 -246.935752) (xy 391.39622 -246.884952) (xy 391.133076 -246.884952) (xy 391.133076 -246.935752)
			(xy 391.169398 -247.037352) (xy 391.359898 -247.037352)
		)
		(stroke
			(width 0)
			(type solid)
		)
		(fill yes)
		(layer "F.Cu")
		(net "M_E_CPU0_SB_PAR")
	)
	(gr_poly
		(pts
			(xy 391.39622 -246.630952) (xy 391.39622 -246.580152) (xy 391.133076 -246.580152) (xy 391.133076 -246.630952)
			(xy 391.169398 -246.732552) (xy 391.359898 -246.732552)
		)
		(stroke
			(width 0)
			(type solid)
		)
		(fill yes)
		(layer "F.Cu")
		(net "M_E_CPU0_SB_CS_N<0>")
	)
	(gr_poly
		(pts
			(xy 391.39622 -246.326152) (xy 391.39622 -246.275352) (xy 391.133076 -246.275352) (xy 391.133076 -246.326152)
			(xy 391.169398 -246.427752) (xy 391.359898 -246.427752)
		)
		(stroke
			(width 0)
			(type solid)
		)
		(fill yes)
		(layer "F.Cu")
		(net "M_E_CPU0_SB_CS_N<2>")
	)
	(gr_poly
		(pts
			(xy 391.39876 -278.996902) (xy 391.491216 -278.94153) (xy 391.453878 -278.75484) (xy 391.347198 -278.739092)
			(xy 391.297414 -278.749252) (xy 391.348976 -279.006808)
		)
		(stroke
			(width 0)
			(type solid)
		)
		(fill yes)
		(layer "F.Cu")
		(net "M_E_CPU0_SA_DQ<17>")
	)
	(gr_poly
		(pts
			(xy 391.40511 -272.829782) (xy 391.451592 -272.732246) (xy 391.316718 -272.597626) (xy 391.219436 -272.643854)
			(xy 391.183368 -272.679668) (xy 391.369296 -272.865596)
		)
		(stroke
			(width 0)
			(type solid)
		)
		(fill yes)
		(layer "F.Cu")
		(net "M_E_CPU0_SA_DQ<21>")
	)
	(gr_poly
		(pts
			(xy 391.406634 -262.133334) (xy 391.452862 -262.035798) (xy 391.317988 -261.901178) (xy 391.220706 -261.947406)
			(xy 391.184638 -261.98322) (xy 391.370566 -262.169148)
		)
		(stroke
			(width 0)
			(type solid)
		)
		(fill yes)
		(layer "F.Cu")
		(net "M_E_CPU0_SA_CB<6>")
	)
	(gr_poly
		(pts
			(xy 391.407396 -279.29967) (xy 391.355834 -279.04186) (xy 391.30605 -279.051766) (xy 391.213594 -279.107138)
			(xy 391.250932 -279.294082) (xy 391.357612 -279.309576)
		)
		(stroke
			(width 0)
			(type solid)
		)
		(fill yes)
		(layer "F.Cu")
		(net "M_E_CPU0_SA_DQ<17>")
	)
	(gr_poly
		(pts
			(xy 391.414 -271.1323) (xy 391.460482 -271.034764) (xy 391.325608 -270.900144) (xy 391.228326 -270.946372)
			(xy 391.192258 -270.982186) (xy 391.378186 -271.168114)
		)
		(stroke
			(width 0)
			(type solid)
		)
		(fill yes)
		(layer "F.Cu")
		(net "M_E_CPU0_SA_DQ<26>")
	)
	(gr_poly
		(pts
			(xy 391.415778 -261.279894) (xy 391.462006 -261.182612) (xy 391.327386 -261.047738) (xy 391.22985 -261.093966)
			(xy 391.194036 -261.130034) (xy 391.379964 -261.315962)
		)
		(stroke
			(width 0)
			(type solid)
		)
		(fill yes)
		(layer "F.Cu")
		(net "M_E_CPU0_SA_CB<7>")
	)
	(gr_poly
		(pts
			(xy 391.419334 -228.185218) (xy 391.38352 -228.14915) (xy 391.285984 -228.102922) (xy 391.151364 -228.237542)
			(xy 391.197592 -228.335078) (xy 391.23366 -228.370892)
		)
		(stroke
			(width 0)
			(type solid)
		)
		(fill yes)
		(layer "F.Cu")
		(net "M_E_CPU0_SB_DQ<21>")
	)
	(gr_poly
		(pts
			(xy 391.423144 -270.27886) (xy 391.469626 -270.181324) (xy 391.334752 -270.046704) (xy 391.23747 -270.092932)
			(xy 391.201402 -270.128746) (xy 391.38733 -270.314674)
		)
		(stroke
			(width 0)
			(type solid)
		)
		(fill yes)
		(layer "F.Cu")
		(net "M_E_CPU0_SA_DQ<27>")
	)
	(gr_poly
		(pts
			(xy 391.428732 -229.038404) (xy 391.392664 -229.00259) (xy 391.295382 -228.956362) (xy 391.160508 -229.090982)
			(xy 391.20699 -229.188518) (xy 391.242804 -229.224332)
		)
		(stroke
			(width 0)
			(type solid)
		)
		(fill yes)
		(layer "F.Cu")
		(net "M_E_CPU0_SB_DQ<20>")
	)
	(gr_poly
		(pts
			(xy 391.455656 -231.59974) (xy 391.419588 -231.563926) (xy 391.322306 -231.517698) (xy 391.187432 -231.652318)
			(xy 391.23366 -231.749854) (xy 391.269728 -231.785668)
		)
		(stroke
			(width 0)
			(type solid)
		)
		(fill yes)
		(layer "F.Cu")
		(net "M_E_CPU0_SB_DQ<17>")
	)
	(gr_poly
		(pts
			(xy 391.464038 -277.766526) (xy 391.556748 -277.711154) (xy 391.51941 -277.52421) (xy 391.41273 -277.508716)
			(xy 391.362692 -277.518622) (xy 391.414254 -277.776432)
		)
		(stroke
			(width 0)
			(type solid)
		)
		(fill yes)
		(layer "F.Cu")
		(net "M_E_CPU0_SA_DQ<19>")
	)
	(gr_poly
		(pts
			(xy 391.464292 -233.296968) (xy 391.428478 -233.2609) (xy 391.330942 -233.214672) (xy 391.196322 -233.349546)
			(xy 391.24255 -233.446828) (xy 391.278364 -233.482896)
		)
		(stroke
			(width 0)
			(type solid)
		)
		(fill yes)
		(layer "F.Cu")
		(net "M_E_CPU0_SB_DQ<15>")
	)
	(gr_poly
		(pts
			(xy 391.4648 -232.45318) (xy 391.428732 -232.417366) (xy 391.33145 -232.371138) (xy 391.19683 -232.505758)
			(xy 391.243058 -232.603294) (xy 391.278872 -232.639108)
		)
		(stroke
			(width 0)
			(type solid)
		)
		(fill yes)
		(layer "F.Cu")
		(net "M_E_CPU0_SB_DQ<16>")
	)
	(gr_poly
		(pts
			(xy 391.472674 -278.06904) (xy 391.421366 -277.811484) (xy 391.371328 -277.82139) (xy 391.278872 -277.876762)
			(xy 391.31621 -278.063452) (xy 391.42289 -278.0792)
		)
		(stroke
			(width 0)
			(type solid)
		)
		(fill yes)
		(layer "F.Cu")
		(net "M_E_CPU0_SA_DQ<19>")
	)
	(gr_poly
		(pts
			(xy 391.473436 -234.150408) (xy 391.437622 -234.11434) (xy 391.340086 -234.068112) (xy 391.205466 -234.202732)
			(xy 391.251694 -234.300268) (xy 391.287762 -234.336082)
		)
		(stroke
			(width 0)
			(type solid)
		)
		(fill yes)
		(layer "F.Cu")
		(net "M_E_CPU0_SB_DQ<14>")
	)
	(gr_poly
		(pts
			(xy 391.481818 -289.175698) (xy 391.481818 -288.985198) (xy 391.380218 -288.94913) (xy 391.329418 -288.94913)
			(xy 391.329418 -289.21202) (xy 391.380218 -289.21202)
		)
		(stroke
			(width 0)
			(type solid)
		)
		(fill yes)
		(layer "F.Cu")
		(net "M_E_CPU0_SA_DQ<18>")
	)
	(gr_poly
		(pts
			(xy 391.481818 -288.578798) (xy 391.481818 -288.388298) (xy 391.380218 -288.35223) (xy 391.329418 -288.35223)
			(xy 391.329418 -288.61512) (xy 391.380218 -288.61512)
		)
		(stroke
			(width 0)
			(type solid)
		)
		(fill yes)
		(layer "F.Cu")
		(net "M_E_CPU0_SA_DQ<18>")
	)
	(gr_poly
		(pts
			(xy 391.481818 -287.981898) (xy 391.481818 -287.791398) (xy 391.380218 -287.75533) (xy 391.329418 -287.75533)
			(xy 391.329418 -288.01822) (xy 391.380218 -288.01822)
		)
		(stroke
			(width 0)
			(type solid)
		)
		(fill yes)
		(layer "F.Cu")
		(net "M_E_CPU0_SA_DQ<18>")
	)
	(gr_poly
		(pts
			(xy 391.481818 -287.384998) (xy 391.481818 -287.194498) (xy 391.380218 -287.15843) (xy 391.329418 -287.15843)
			(xy 391.329418 -287.42132) (xy 391.380218 -287.42132)
		)
		(stroke
			(width 0)
			(type solid)
		)
		(fill yes)
		(layer "F.Cu")
		(net "M_E_CPU0_SA_DQ<18>")
	)
	(gr_poly
		(pts
			(xy 391.481818 -286.788098) (xy 391.481818 -286.597598) (xy 391.380218 -286.56153) (xy 391.329418 -286.56153)
			(xy 391.329418 -286.82442) (xy 391.380218 -286.82442)
		)
		(stroke
			(width 0)
			(type solid)
		)
		(fill yes)
		(layer "F.Cu")
		(net "M_E_CPU0_SA_DQ<18>")
	)
	(gr_poly
		(pts
			(xy 391.481818 -286.191198) (xy 391.481818 -286.000698) (xy 391.380218 -285.96463) (xy 391.329418 -285.96463)
			(xy 391.329418 -286.22752) (xy 391.380218 -286.22752)
		)
		(stroke
			(width 0)
			(type solid)
		)
		(fill yes)
		(layer "F.Cu")
		(net "M_E_CPU0_SA_DQ<18>")
	)
	(gr_poly
		(pts
			(xy 391.481818 -285.594298) (xy 391.481818 -285.403798) (xy 391.380218 -285.36773) (xy 391.329418 -285.36773)
			(xy 391.329418 -285.63062) (xy 391.380218 -285.63062)
		)
		(stroke
			(width 0)
			(type solid)
		)
		(fill yes)
		(layer "F.Cu")
		(net "M_E_CPU0_SA_DQ<18>")
	)
	(gr_poly
		(pts
			(xy 391.481818 -284.997398) (xy 391.481818 -284.806898) (xy 391.380218 -284.77083) (xy 391.329418 -284.77083)
			(xy 391.329418 -285.03372) (xy 391.380218 -285.03372)
		)
		(stroke
			(width 0)
			(type solid)
		)
		(fill yes)
		(layer "F.Cu")
		(net "M_E_CPU0_SA_DQ<18>")
	)
	(gr_poly
		(pts
			(xy 391.481818 -284.400498) (xy 391.481818 -284.209998) (xy 391.380218 -284.17393) (xy 391.329418 -284.17393)
			(xy 391.329418 -284.43682) (xy 391.380218 -284.43682)
		)
		(stroke
			(width 0)
			(type solid)
		)
		(fill yes)
		(layer "F.Cu")
		(net "M_E_CPU0_SA_DQ<18>")
	)
	(gr_poly
		(pts
			(xy 391.481818 -283.803598) (xy 391.481818 -283.613098) (xy 391.380218 -283.57703) (xy 391.329418 -283.57703)
			(xy 391.329418 -283.83992) (xy 391.380218 -283.83992)
		)
		(stroke
			(width 0)
			(type solid)
		)
		(fill yes)
		(layer "F.Cu")
		(net "M_E_CPU0_SA_DQ<18>")
	)
	(gr_poly
		(pts
			(xy 391.481818 -283.206698) (xy 391.481818 -283.016198) (xy 391.380218 -282.98013) (xy 391.329418 -282.98013)
			(xy 391.329418 -283.24302) (xy 391.380218 -283.24302)
		)
		(stroke
			(width 0)
			(type solid)
		)
		(fill yes)
		(layer "F.Cu")
		(net "M_E_CPU0_SA_DQ<18>")
	)
	(gr_poly
		(pts
			(xy 391.481818 -282.609798) (xy 391.481818 -282.419298) (xy 391.380218 -282.38323) (xy 391.329418 -282.38323)
			(xy 391.329418 -282.64612) (xy 391.380218 -282.64612)
		)
		(stroke
			(width 0)
			(type solid)
		)
		(fill yes)
		(layer "F.Cu")
		(net "M_E_CPU0_SA_DQ<18>")
	)
	(gr_poly
		(pts
			(xy 391.481818 -282.012898) (xy 391.481818 -281.822398) (xy 391.380218 -281.78633) (xy 391.329418 -281.78633)
			(xy 391.329418 -282.04922) (xy 391.380218 -282.04922)
		)
		(stroke
			(width 0)
			(type solid)
		)
		(fill yes)
		(layer "F.Cu")
		(net "M_E_CPU0_SA_DQ<18>")
	)
	(gr_poly
		(pts
			(xy 391.481818 -281.415998) (xy 391.481818 -281.225498) (xy 391.380218 -281.18943) (xy 391.329418 -281.18943)
			(xy 391.329418 -281.45232) (xy 391.380218 -281.45232)
		)
		(stroke
			(width 0)
			(type solid)
		)
		(fill yes)
		(layer "F.Cu")
		(net "M_E_CPU0_SA_DQ<18>")
	)
	(gr_poly
		(pts
			(xy 391.488422 -265.809984) (xy 391.52449 -265.77417) (xy 391.338562 -265.588242) (xy 391.302494 -265.624056)
			(xy 391.256266 -265.721592) (xy 391.39114 -265.856212)
		)
		(stroke
			(width 0)
			(type solid)
		)
		(fill yes)
		(layer "F.Cu")
		(net "M_E_CPU0_SA_CB<2>")
	)
	(gr_poly
		(pts
			(xy 391.497058 -227.891848) (xy 391.45083 -227.794312) (xy 391.414762 -227.758498) (xy 391.228834 -227.944426)
			(xy 391.264902 -227.98024) (xy 391.362438 -228.026468)
		)
		(stroke
			(width 0)
			(type solid)
		)
		(fill yes)
		(layer "F.Cu")
		(net "M_E_CPU0_SB_DQ<23>")
	)
	(gr_poly
		(pts
			(xy 391.49782 -264.956544) (xy 391.533634 -264.92073) (xy 391.347706 -264.734802) (xy 391.311892 -264.770616)
			(xy 391.265664 -264.868152) (xy 391.400284 -265.002772)
		)
		(stroke
			(width 0)
			(type solid)
		)
		(fill yes)
		(layer "F.Cu")
		(net "M_E_CPU0_SA_CB<3>")
	)
	(gr_poly
		(pts
			(xy 391.498328 -236.713268) (xy 391.462514 -236.6772) (xy 391.364978 -236.630972) (xy 391.230358 -236.765592)
			(xy 391.276586 -236.863128) (xy 391.3124 -236.898942)
		)
		(stroke
			(width 0)
			(type solid)
		)
		(fill yes)
		(layer "F.Cu")
		(net "M_E_CPU0_SB_DQ<11>")
	)
	(gr_poly
		(pts
			(xy 391.500106 -257.346196) (xy 391.536174 -257.310382) (xy 391.350246 -257.124454) (xy 391.314178 -257.160268)
			(xy 391.26795 -257.257804) (xy 391.402824 -257.392424)
		)
		(stroke
			(width 0)
			(type solid)
		)
		(fill yes)
		(layer "F.Cu")
		(net "M_E_CPU0_SA_CA<2>")
	)
	(gr_poly
		(pts
			(xy 391.506202 -228.745034) (xy 391.459974 -228.647752) (xy 391.42416 -228.611684) (xy 391.238232 -228.797612)
			(xy 391.274046 -228.83368) (xy 391.371582 -228.879908)
		)
		(stroke
			(width 0)
			(type solid)
		)
		(fill yes)
		(layer "F.Cu")
		(net "M_E_CPU0_SB_DQ<22>")
	)
	(gr_poly
		(pts
			(xy 391.508488 -237.567216) (xy 391.47242 -237.531402) (xy 391.375138 -237.485174) (xy 391.240264 -237.619794)
			(xy 391.286492 -237.71733) (xy 391.32256 -237.753144)
		)
		(stroke
			(width 0)
			(type solid)
		)
		(fill yes)
		(layer "F.Cu")
		(net "M_E_CPU0_SB_DQ<10>")
	)
	(gr_poly
		(pts
			(xy 391.50925 -256.492756) (xy 391.545318 -256.456942) (xy 391.35939 -256.271014) (xy 391.323576 -256.306828)
			(xy 391.277094 -256.404364) (xy 391.411968 -256.538984)
		)
		(stroke
			(width 0)
			(type solid)
		)
		(fill yes)
		(layer "F.Cu")
		(net "M_E_CPU0_SA_CA<4>")
	)
	(gr_poly
		(pts
			(xy 391.512552 -268.318234) (xy 391.54862 -268.28242) (xy 391.362692 -268.096492) (xy 391.326624 -268.132306)
			(xy 391.280396 -268.229842) (xy 391.41527 -268.364462)
		)
		(stroke
			(width 0)
			(type solid)
		)
		(fill yes)
		(layer "F.Cu")
		(net "M_E_CPU0_SA_DQ<28>")
	)
	(gr_poly
		(pts
			(xy 391.5156 -279.582372) (xy 391.60831 -279.527) (xy 391.570972 -279.340056) (xy 391.464292 -279.324562)
			(xy 391.414254 -279.334468) (xy 391.465816 -279.592278)
		)
		(stroke
			(width 0)
			(type solid)
		)
		(fill yes)
		(layer "F.Cu")
		(net "M_E_CPU0_SA_DQ<17>")
	)
	(gr_poly
		(pts
			(xy 391.516616 -239.263682) (xy 391.480548 -239.227868) (xy 391.383266 -239.18164) (xy 391.248392 -239.31626)
			(xy 391.29462 -239.413796) (xy 391.330688 -239.44961)
		)
		(stroke
			(width 0)
			(type solid)
		)
		(fill yes)
		(layer "F.Cu")
		(net "M_E_CPU0_SB_CB<1>")
	)
	(gr_poly
		(pts
			(xy 391.518648 -255.63957) (xy 391.554462 -255.603502) (xy 391.368534 -255.417574) (xy 391.33272 -255.453642)
			(xy 391.286492 -255.550924) (xy 391.421112 -255.685798)
		)
		(stroke
			(width 0)
			(type solid)
		)
		(fill yes)
		(layer "F.Cu")
		(net "M_E_CPU0_SA_CA<6>")
	)
	(gr_poly
		(pts
			(xy 391.52195 -267.464794) (xy 391.558018 -267.42898) (xy 391.37209 -267.243052) (xy 391.336022 -267.278866)
			(xy 391.289794 -267.376402) (xy 391.424414 -267.511022)
		)
		(stroke
			(width 0)
			(type solid)
		)
		(fill yes)
		(layer "F.Cu")
		(net "M_E_CPU0_SA_DQ<29>")
	)
	(gr_poly
		(pts
			(xy 391.523982 -242.598956) (xy 391.48766 -242.497356) (xy 391.29716 -242.497356) (xy 391.261092 -242.598956)
			(xy 391.261092 -242.649756) (xy 391.523982 -242.649756)
		)
		(stroke
			(width 0)
			(type solid)
		)
		(fill yes)
		(layer "F.Cu")
		(net "M_E_CPU0_SB_CB<4>")
	)
	(gr_poly
		(pts
			(xy 391.523982 -242.294156) (xy 391.48766 -242.192556) (xy 391.29716 -242.192556) (xy 391.261092 -242.294156)
			(xy 391.261092 -242.344956) (xy 391.523982 -242.344956)
		)
		(stroke
			(width 0)
			(type solid)
		)
		(fill yes)
		(layer "F.Cu")
		(net "M_E_CPU0_SB_CB<6>")
	)
	(gr_poly
		(pts
			(xy 391.523982 -241.989356) (xy 391.48766 -241.887756) (xy 391.29716 -241.887756) (xy 391.261092 -241.989356)
			(xy 391.261092 -242.040156) (xy 391.523982 -242.040156)
		)
		(stroke
			(width 0)
			(type solid)
		)
		(fill yes)
		(layer "F.Cu")
		(net "M_E_CPU0_SB_CB<5>")
	)
	(gr_poly
		(pts
			(xy 391.523982 -241.684556) (xy 391.48766 -241.582956) (xy 391.29716 -241.582956) (xy 391.261092 -241.684556)
			(xy 391.261092 -241.735356) (xy 391.523982 -241.735356)
		)
		(stroke
			(width 0)
			(type solid)
		)
		(fill yes)
		(layer "F.Cu")
		(net "M_E_CPU0_SB_CB<7>")
	)
	(gr_poly
		(pts
			(xy 391.52449 -279.884886) (xy 391.472928 -279.627076) (xy 391.423144 -279.636982) (xy 391.330434 -279.692608)
			(xy 391.367772 -279.879298) (xy 391.474706 -279.894792)
		)
		(stroke
			(width 0)
			(type solid)
		)
		(fill yes)
		(layer "F.Cu")
		(net "M_E_CPU0_SA_DQ<17>")
	)
	(gr_poly
		(pts
			(xy 391.533126 -231.306624) (xy 391.486898 -231.209088) (xy 391.45083 -231.173274) (xy 391.265156 -231.358948)
			(xy 391.30097 -231.395016) (xy 391.398506 -231.441244)
		)
		(stroke
			(width 0)
			(type solid)
		)
		(fill yes)
		(layer "F.Cu")
		(net "M_E_CPU0_SB_DQ<19>")
	)
	(gr_poly
		(pts
			(xy 391.535158 -273.966178) (xy 391.570972 -273.93011) (xy 391.385044 -273.744436) (xy 391.34923 -273.78025)
			(xy 391.303002 -273.877786) (xy 391.437622 -274.012406)
		)
		(stroke
			(width 0)
			(type solid)
		)
		(fill yes)
		(layer "F.Cu")
		(net "M_E_CPU0_SA_DQ<20>")
	)
	(gr_poly
		(pts
			(xy 391.54227 -232.15981) (xy 391.496042 -232.062528) (xy 391.460228 -232.02646) (xy 391.2743 -232.212388)
			(xy 391.310114 -232.248456) (xy 391.40765 -232.294684)
		)
		(stroke
			(width 0)
			(type solid)
		)
		(fill yes)
		(layer "F.Cu")
		(net "M_E_CPU0_SB_DQ<18>")
	)
	(gr_poly
		(pts
			(xy 391.544302 -273.112484) (xy 391.58037 -273.07667) (xy 391.394442 -272.890742) (xy 391.358628 -272.926556)
			(xy 391.3124 -273.024092) (xy 391.44702 -273.158712)
		)
		(stroke
			(width 0)
			(type solid)
		)
		(fill yes)
		(layer "F.Cu")
		(net "M_E_CPU0_SA_DQ<21>")
	)
	(gr_poly
		(pts
			(xy 391.545826 -262.41629) (xy 391.58164 -262.380222) (xy 391.395712 -262.194294) (xy 391.359898 -262.230362)
			(xy 391.31367 -262.327644) (xy 391.44829 -262.462518)
		)
		(stroke
			(width 0)
			(type solid)
		)
		(fill yes)
		(layer "F.Cu")
		(net "M_E_CPU0_SA_CB<6>")
	)
	(gr_poly
		(pts
			(xy 391.55116 -233.857038) (xy 391.504932 -233.759502) (xy 391.468864 -233.723688) (xy 391.282936 -233.909616)
			(xy 391.319004 -233.94543) (xy 391.416286 -233.991658)
		)
		(stroke
			(width 0)
			(type solid)
		)
		(fill yes)
		(layer "F.Cu")
		(net "M_E_CPU0_SB_DQ<13>")
	)
	(gr_poly
		(pts
			(xy 391.553192 -271.415002) (xy 391.58926 -271.379188) (xy 391.403332 -271.19326) (xy 391.367518 -271.229074)
			(xy 391.32129 -271.32661) (xy 391.45591 -271.46123)
		)
		(stroke
			(width 0)
			(type solid)
		)
		(fill yes)
		(layer "F.Cu")
		(net "M_E_CPU0_SA_DQ<26>")
	)
	(gr_poly
		(pts
			(xy 391.55497 -261.56285) (xy 391.590784 -261.526782) (xy 391.40511 -261.341108) (xy 391.369042 -261.376922)
			(xy 391.322814 -261.474458) (xy 391.457434 -261.609078)
		)
		(stroke
			(width 0)
			(type solid)
		)
		(fill yes)
		(layer "F.Cu")
		(net "M_E_CPU0_SA_CB<7>")
	)
	(gr_poly
		(pts
			(xy 391.555732 -266.164822) (xy 391.60196 -266.067286) (xy 391.46734 -265.932666) (xy 391.369804 -265.978894)
			(xy 391.33399 -266.014962) (xy 391.519664 -266.200636)
		)
		(stroke
			(width 0)
			(type solid)
		)
		(fill yes)
		(layer "F.Cu")
		(net "M_E_CPU0_SA_CB<0>")
	)
	(gr_poly
		(pts
			(xy 391.55878 -226.800156) (xy 391.50798 -226.800156) (xy 391.40638 -226.836478) (xy 391.40638 -227.026978)
			(xy 391.50798 -227.063046) (xy 391.55878 -227.063046)
		)
		(stroke
			(width 0)
			(type solid)
		)
		(fill yes)
		(layer "F.Cu")
		(net "M_E_CPU0_SB_DQ<23>")
	)
	(gr_poly
		(pts
			(xy 391.55878 -226.203256) (xy 391.50798 -226.203256) (xy 391.40638 -226.239578) (xy 391.40638 -226.430078)
			(xy 391.50798 -226.466146) (xy 391.55878 -226.466146)
		)
		(stroke
			(width 0)
			(type solid)
		)
		(fill yes)
		(layer "F.Cu")
		(net "M_E_CPU0_SB_DQ<23>")
	)
	(gr_poly
		(pts
			(xy 391.55878 -225.606356) (xy 391.50798 -225.606356) (xy 391.40638 -225.642678) (xy 391.40638 -225.833178)
			(xy 391.50798 -225.869246) (xy 391.55878 -225.869246)
		)
		(stroke
			(width 0)
			(type solid)
		)
		(fill yes)
		(layer "F.Cu")
		(net "M_E_CPU0_SB_DQ<23>")
	)
	(gr_poly
		(pts
			(xy 391.55878 -225.009456) (xy 391.50798 -225.009456) (xy 391.40638 -225.045778) (xy 391.40638 -225.236278)
			(xy 391.50798 -225.272346) (xy 391.55878 -225.272346)
		)
		(stroke
			(width 0)
			(type solid)
		)
		(fill yes)
		(layer "F.Cu")
		(net "M_E_CPU0_SB_DQ<23>")
	)
	(gr_poly
		(pts
			(xy 391.55878 -224.412556) (xy 391.50798 -224.412556) (xy 391.40638 -224.448878) (xy 391.40638 -224.639378)
			(xy 391.50798 -224.675446) (xy 391.55878 -224.675446)
		)
		(stroke
			(width 0)
			(type solid)
		)
		(fill yes)
		(layer "F.Cu")
		(net "M_E_CPU0_SB_DQ<23>")
	)
	(gr_poly
		(pts
			(xy 391.55878 -223.815656) (xy 391.50798 -223.815656) (xy 391.40638 -223.851978) (xy 391.40638 -224.042478)
			(xy 391.50798 -224.078546) (xy 391.55878 -224.078546)
		)
		(stroke
			(width 0)
			(type solid)
		)
		(fill yes)
		(layer "F.Cu")
		(net "M_E_CPU0_SB_DQ<23>")
	)
	(gr_poly
		(pts
			(xy 391.55878 -223.218756) (xy 391.50798 -223.218756) (xy 391.40638 -223.255078) (xy 391.40638 -223.445578)
			(xy 391.50798 -223.481646) (xy 391.55878 -223.481646)
		)
		(stroke
			(width 0)
			(type solid)
		)
		(fill yes)
		(layer "F.Cu")
		(net "M_E_CPU0_SB_DQ<23>")
	)
	(gr_poly
		(pts
			(xy 391.55878 -222.621856) (xy 391.50798 -222.621856) (xy 391.40638 -222.658178) (xy 391.40638 -222.848678)
			(xy 391.50798 -222.884746) (xy 391.55878 -222.884746)
		)
		(stroke
			(width 0)
			(type solid)
		)
		(fill yes)
		(layer "F.Cu")
		(net "M_E_CPU0_SB_DQ<23>")
	)
	(gr_poly
		(pts
			(xy 391.55878 -222.024956) (xy 391.50798 -222.024956) (xy 391.40638 -222.061278) (xy 391.40638 -222.251778)
			(xy 391.50798 -222.287846) (xy 391.55878 -222.287846)
		)
		(stroke
			(width 0)
			(type solid)
		)
		(fill yes)
		(layer "F.Cu")
		(net "M_E_CPU0_SB_DQ<23>")
	)
	(gr_poly
		(pts
			(xy 391.55878 -221.428056) (xy 391.50798 -221.428056) (xy 391.40638 -221.464378) (xy 391.40638 -221.654878)
			(xy 391.50798 -221.690946) (xy 391.55878 -221.690946)
		)
		(stroke
			(width 0)
			(type solid)
		)
		(fill yes)
		(layer "F.Cu")
		(net "M_E_CPU0_SB_DQ<23>")
	)
	(gr_poly
		(pts
			(xy 391.55878 -220.831156) (xy 391.50798 -220.831156) (xy 391.40638 -220.867478) (xy 391.40638 -221.057978)
			(xy 391.50798 -221.094046) (xy 391.55878 -221.094046)
		)
		(stroke
			(width 0)
			(type solid)
		)
		(fill yes)
		(layer "F.Cu")
		(net "M_E_CPU0_SB_DQ<23>")
	)
	(gr_poly
		(pts
			(xy 391.55878 -220.234256) (xy 391.50798 -220.234256) (xy 391.40638 -220.270578) (xy 391.40638 -220.461078)
			(xy 391.50798 -220.497146) (xy 391.55878 -220.497146)
		)
		(stroke
			(width 0)
			(type solid)
		)
		(fill yes)
		(layer "F.Cu")
		(net "M_E_CPU0_SB_DQ<23>")
	)
	(gr_poly
		(pts
			(xy 391.55878 -219.637356) (xy 391.50798 -219.637356) (xy 391.40638 -219.673678) (xy 391.40638 -219.864178)
			(xy 391.50798 -219.900246) (xy 391.55878 -219.900246)
		)
		(stroke
			(width 0)
			(type solid)
		)
		(fill yes)
		(layer "F.Cu")
		(net "M_E_CPU0_SB_DQ<23>")
	)
	(gr_poly
		(pts
			(xy 391.55878 -219.040456) (xy 391.50798 -219.040456) (xy 391.40638 -219.076778) (xy 391.40638 -219.267278)
			(xy 391.50798 -219.303346) (xy 391.55878 -219.303346)
		)
		(stroke
			(width 0)
			(type solid)
		)
		(fill yes)
		(layer "F.Cu")
		(net "M_E_CPU0_SB_DQ<23>")
	)
	(gr_poly
		(pts
			(xy 391.55878 -218.443556) (xy 391.50798 -218.443556) (xy 391.40638 -218.479878) (xy 391.40638 -218.670378)
			(xy 391.50798 -218.706446) (xy 391.55878 -218.706446)
		)
		(stroke
			(width 0)
			(type solid)
		)
		(fill yes)
		(layer "F.Cu")
		(net "M_E_CPU0_SB_DQ<23>")
	)
	(gr_poly
		(pts
			(xy 391.55878 -217.846656) (xy 391.50798 -217.846656) (xy 391.40638 -217.882978) (xy 391.40638 -218.073478)
			(xy 391.50798 -218.109546) (xy 391.55878 -218.109546)
		)
		(stroke
			(width 0)
			(type solid)
		)
		(fill yes)
		(layer "F.Cu")
		(net "M_E_CPU0_SB_DQ<23>")
	)
	(gr_poly
		(pts
			(xy 391.55878 -217.249756) (xy 391.50798 -217.249756) (xy 391.40638 -217.286078) (xy 391.40638 -217.476578)
			(xy 391.50798 -217.512646) (xy 391.55878 -217.512646)
		)
		(stroke
			(width 0)
			(type solid)
		)
		(fill yes)
		(layer "F.Cu")
		(net "M_E_CPU0_SB_DQ<23>")
	)
	(gr_poly
		(pts
			(xy 391.55878 -216.652856) (xy 391.50798 -216.652856) (xy 391.40638 -216.689178) (xy 391.40638 -216.879678)
			(xy 391.50798 -216.915746) (xy 391.55878 -216.915746)
		)
		(stroke
			(width 0)
			(type solid)
		)
		(fill yes)
		(layer "F.Cu")
		(net "M_E_CPU0_SB_DQ<23>")
	)
	(gr_poly
		(pts
			(xy 391.55878 -216.055956) (xy 391.50798 -216.055956) (xy 391.40638 -216.092278) (xy 391.40638 -216.282778)
			(xy 391.50798 -216.318846) (xy 391.55878 -216.318846)
		)
		(stroke
			(width 0)
			(type solid)
		)
		(fill yes)
		(layer "F.Cu")
		(net "M_E_CPU0_SB_DQ<23>")
	)
	(gr_poly
		(pts
			(xy 391.55878 -215.459056) (xy 391.50798 -215.459056) (xy 391.40638 -215.495378) (xy 391.40638 -215.685878)
			(xy 391.50798 -215.721946) (xy 391.55878 -215.721946)
		)
		(stroke
			(width 0)
			(type solid)
		)
		(fill yes)
		(layer "F.Cu")
		(net "M_E_CPU0_SB_DQ<23>")
	)
	(gr_poly
		(pts
			(xy 391.55878 -214.862156) (xy 391.50798 -214.862156) (xy 391.40638 -214.898478) (xy 391.40638 -215.088978)
			(xy 391.50798 -215.125046) (xy 391.55878 -215.125046)
		)
		(stroke
			(width 0)
			(type solid)
		)
		(fill yes)
		(layer "F.Cu")
		(net "M_E_CPU0_SB_DQ<23>")
	)
	(gr_poly
		(pts
			(xy 391.560304 -234.710224) (xy 391.514076 -234.612942) (xy 391.478262 -234.576874) (xy 391.292334 -234.762802)
			(xy 391.328148 -234.79887) (xy 391.425684 -234.845098)
		)
		(stroke
			(width 0)
			(type solid)
		)
		(fill yes)
		(layer "F.Cu")
		(net "M_E_CPU0_SB_DQ<12>")
	)
	(gr_poly
		(pts
			(xy 391.56259 -270.561562) (xy 391.598404 -270.525748) (xy 391.412476 -270.33982) (xy 391.376662 -270.375634)
			(xy 391.330434 -270.47317) (xy 391.465054 -270.60779)
		)
		(stroke
			(width 0)
			(type solid)
		)
		(fill yes)
		(layer "F.Cu")
		(net "M_E_CPU0_SA_DQ<27>")
	)
	(gr_poly
		(pts
			(xy 391.564876 -265.311382) (xy 391.611104 -265.2141) (xy 391.476484 -265.079226) (xy 391.378948 -265.125454)
			(xy 391.343134 -265.161522) (xy 391.529062 -265.34745)
		)
		(stroke
			(width 0)
			(type solid)
		)
		(fill yes)
		(layer "F.Cu")
		(net "M_E_CPU0_SA_CB<1>")
	)
	(gr_poly
		(pts
			(xy 391.567416 -257.701034) (xy 391.613644 -257.603498) (xy 391.479024 -257.468878) (xy 391.381488 -257.515106)
			(xy 391.345674 -257.551174) (xy 391.531348 -257.736848)
		)
		(stroke
			(width 0)
			(type solid)
		)
		(fill yes)
		(layer "F.Cu")
		(net "M_E_CPU0_SA_CA<1>")
	)
	(gr_poly
		(pts
			(xy 391.57656 -256.847594) (xy 391.622788 -256.750312) (xy 391.488168 -256.615438) (xy 391.390632 -256.661666)
			(xy 391.354818 -256.697734) (xy 391.540746 -256.883662)
		)
		(stroke
			(width 0)
			(type solid)
		)
		(fill yes)
		(layer "F.Cu")
		(net "M_E_CPU0_SA_CA<3>")
	)
	(gr_poly
		(pts
			(xy 391.581132 -278.351996) (xy 391.673588 -278.29637) (xy 391.63625 -278.10968) (xy 391.52957 -278.094186)
			(xy 391.479786 -278.104092) (xy 391.531348 -278.361902)
		)
		(stroke
			(width 0)
			(type solid)
		)
		(fill yes)
		(layer "F.Cu")
		(net "M_E_CPU0_SA_DQ<19>")
	)
	(gr_poly
		(pts
			(xy 391.585196 -237.273338) (xy 391.538968 -237.175802) (xy 391.503154 -237.139988) (xy 391.317226 -237.325916)
			(xy 391.35304 -237.36173) (xy 391.450576 -237.407958)
		)
		(stroke
			(width 0)
			(type solid)
		)
		(fill yes)
		(layer "F.Cu")
		(net "M_E_CPU0_SB_DQ<9>")
	)
	(gr_poly
		(pts
			(xy 391.585704 -255.994408) (xy 391.631932 -255.896872) (xy 391.497312 -255.762252) (xy 391.40003 -255.80848)
			(xy 391.363962 -255.844294) (xy 391.54989 -256.030222)
		)
		(stroke
			(width 0)
			(type solid)
		)
		(fill yes)
		(layer "F.Cu")
		(net "M_E_CPU0_SA_CA<5>")
	)
	(gr_poly
		(pts
			(xy 391.589006 -267.819632) (xy 391.635234 -267.72235) (xy 391.500614 -267.58773) (xy 391.403078 -267.633958)
			(xy 391.367264 -267.669772) (xy 391.553192 -267.8557)
		)
		(stroke
			(width 0)
			(type solid)
		)
		(fill yes)
		(layer "F.Cu")
		(net "M_E_CPU0_SA_DQ<30>")
	)
	(gr_poly
		(pts
			(xy 391.589768 -278.65451) (xy 391.538206 -278.3967) (xy 391.488422 -278.406606) (xy 391.395966 -278.461978)
			(xy 391.43305 -278.648922) (xy 391.539984 -278.664416)
		)
		(stroke
			(width 0)
			(type solid)
		)
		(fill yes)
		(layer "F.Cu")
		(net "M_E_CPU0_SA_DQ<19>")
	)
	(gr_poly
		(pts
			(xy 391.594086 -238.970312) (xy 391.547858 -238.87303) (xy 391.512044 -238.836962) (xy 391.326116 -239.02289)
			(xy 391.36193 -239.058958) (xy 391.459466 -239.105186)
		)
		(stroke
			(width 0)
			(type solid)
		)
		(fill yes)
		(layer "F.Cu")
		(net "M_E_CPU0_SB_CB<3>")
	)
	(gr_poly
		(pts
			(xy 391.595102 -255.140968) (xy 391.64133 -255.043432) (xy 391.506456 -254.908812) (xy 391.409174 -254.95504)
			(xy 391.373106 -254.990854) (xy 391.559034 -255.176782)
		)
		(stroke
			(width 0)
			(type solid)
		)
		(fill yes)
		(layer "F.Cu")
		(net "M_E_CPU0_SA_PAR")
	)
	(gr_poly
		(pts
			(xy 391.595356 -238.12754) (xy 391.549128 -238.030004) (xy 391.51306 -237.99419) (xy 391.327132 -238.180118)
			(xy 391.3632 -238.215932) (xy 391.460482 -238.26216)
		)
		(stroke
			(width 0)
			(type solid)
		)
		(fill yes)
		(layer "F.Cu")
		(net "M_E_CPU0_SB_DQ<8>")
	)
	(gr_poly
		(pts
			(xy 391.598658 -266.966192) (xy 391.644886 -266.868656) (xy 391.510012 -266.734036) (xy 391.41273 -266.780264)
			(xy 391.376662 -266.816078) (xy 391.56259 -267.002006)
		)
		(stroke
			(width 0)
			(type solid)
		)
		(fill yes)
		(layer "F.Cu")
		(net "M_E_CPU0_SA_DQ<31>")
	)
	(gr_poly
		(pts
			(xy 391.611612 -273.467322) (xy 391.65784 -273.37004) (xy 391.52322 -273.235166) (xy 391.425684 -273.281648)
			(xy 391.38987 -273.317462) (xy 391.575798 -273.50339)
		)
		(stroke
			(width 0)
			(type solid)
		)
		(fill yes)
		(layer "F.Cu")
		(net "M_E_CPU0_SA_DQ<22>")
	)
	(gr_poly
		(pts
			(xy 391.612882 -262.771128) (xy 391.659364 -262.673592) (xy 391.52449 -262.538972) (xy 391.427208 -262.5852)
			(xy 391.39114 -262.621014) (xy 391.577068 -262.806942)
		)
		(stroke
			(width 0)
			(type solid)
		)
		(fill yes)
		(layer "F.Cu")
		(net "M_E_CPU0_SA_CB<4>")
	)
	(gr_poly
		(pts
			(xy 391.620502 -271.76984) (xy 391.66673 -271.672558) (xy 391.53211 -271.537938) (xy 391.434574 -271.584166)
			(xy 391.39876 -271.61998) (xy 391.584688 -271.805908)
		)
		(stroke
			(width 0)
			(type solid)
		)
		(fill yes)
		(layer "F.Cu")
		(net "M_E_CPU0_SA_DQ<24>")
	)
	(gr_poly
		(pts
			(xy 391.62101 -272.613882) (xy 391.667238 -272.516346) (xy 391.532618 -272.381726) (xy 391.435082 -272.427954)
			(xy 391.399268 -272.464022) (xy 391.584942 -272.649696)
		)
		(stroke
			(width 0)
			(type solid)
		)
		(fill yes)
		(layer "F.Cu")
		(net "M_E_CPU0_SA_DQ<23>")
	)
	(gr_poly
		(pts
			(xy 391.62228 -261.917688) (xy 391.668508 -261.820152) (xy 391.533634 -261.685532) (xy 391.436352 -261.73176)
			(xy 391.400284 -261.767574) (xy 391.586212 -261.953502)
		)
		(stroke
			(width 0)
			(type solid)
		)
		(fill yes)
		(layer "F.Cu")
		(net "M_E_CPU0_SA_CB<5>")
	)
	(gr_poly
		(pts
			(xy 391.629646 -270.9164) (xy 391.675874 -270.819118) (xy 391.541254 -270.684498) (xy 391.443718 -270.730726)
			(xy 391.407904 -270.76654) (xy 391.593832 -270.952468)
		)
		(stroke
			(width 0)
			(type solid)
		)
		(fill yes)
		(layer "F.Cu")
		(net "M_E_CPU0_SA_DQ<25>")
	)
	(gr_poly
		(pts
			(xy 391.632694 -280.167588) (xy 391.72515 -280.112216) (xy 391.687812 -279.925526) (xy 391.581132 -279.909778)
			(xy 391.531348 -279.919684) (xy 391.58291 -280.177494)
		)
		(stroke
			(width 0)
			(type solid)
		)
		(fill yes)
		(layer "F.Cu")
		(net "M_E_CPU0_SA_DQ<17>")
	)
	(gr_poly
		(pts
			(xy 391.634218 -289.247326) (xy 391.583418 -289.247326) (xy 391.481818 -289.283648) (xy 391.481818 -289.474148)
			(xy 391.583418 -289.51047) (xy 391.634218 -289.51047)
		)
		(stroke
			(width 0)
			(type solid)
		)
		(fill yes)
		(layer "F.Cu")
		(net "M_E_CPU0_SA_DQ<17>")
	)
	(gr_poly
		(pts
			(xy 391.634218 -288.650426) (xy 391.583418 -288.650426) (xy 391.481818 -288.686748) (xy 391.481818 -288.877248)
			(xy 391.583418 -288.91357) (xy 391.634218 -288.91357)
		)
		(stroke
			(width 0)
			(type solid)
		)
		(fill yes)
		(layer "F.Cu")
		(net "M_E_CPU0_SA_DQ<17>")
	)
	(gr_poly
		(pts
			(xy 391.634218 -288.053526) (xy 391.583418 -288.053526) (xy 391.481818 -288.089848) (xy 391.481818 -288.280348)
			(xy 391.583418 -288.31667) (xy 391.634218 -288.31667)
		)
		(stroke
			(width 0)
			(type solid)
		)
		(fill yes)
		(layer "F.Cu")
		(net "M_E_CPU0_SA_DQ<17>")
	)
	(gr_poly
		(pts
			(xy 391.634218 -287.456626) (xy 391.583418 -287.456626) (xy 391.481818 -287.492948) (xy 391.481818 -287.683448)
			(xy 391.583418 -287.71977) (xy 391.634218 -287.71977)
		)
		(stroke
			(width 0)
			(type solid)
		)
		(fill yes)
		(layer "F.Cu")
		(net "M_E_CPU0_SA_DQ<17>")
	)
	(gr_poly
		(pts
			(xy 391.634218 -286.859726) (xy 391.583418 -286.859726) (xy 391.481818 -286.896048) (xy 391.481818 -287.086548)
			(xy 391.583418 -287.12287) (xy 391.634218 -287.12287)
		)
		(stroke
			(width 0)
			(type solid)
		)
		(fill yes)
		(layer "F.Cu")
		(net "M_E_CPU0_SA_DQ<17>")
	)
	(gr_poly
		(pts
			(xy 391.634218 -286.262826) (xy 391.583418 -286.262826) (xy 391.481818 -286.299148) (xy 391.481818 -286.489648)
			(xy 391.583418 -286.52597) (xy 391.634218 -286.52597)
		)
		(stroke
			(width 0)
			(type solid)
		)
		(fill yes)
		(layer "F.Cu")
		(net "M_E_CPU0_SA_DQ<17>")
	)
	(gr_poly
		(pts
			(xy 391.634218 -285.665926) (xy 391.583418 -285.665926) (xy 391.481818 -285.702248) (xy 391.481818 -285.892748)
			(xy 391.583418 -285.92907) (xy 391.634218 -285.92907)
		)
		(stroke
			(width 0)
			(type solid)
		)
		(fill yes)
		(layer "F.Cu")
		(net "M_E_CPU0_SA_DQ<17>")
	)
	(gr_poly
		(pts
			(xy 391.634218 -285.069026) (xy 391.583418 -285.069026) (xy 391.481818 -285.105348) (xy 391.481818 -285.295848)
			(xy 391.583418 -285.33217) (xy 391.634218 -285.33217)
		)
		(stroke
			(width 0)
			(type solid)
		)
		(fill yes)
		(layer "F.Cu")
		(net "M_E_CPU0_SA_DQ<17>")
	)
	(gr_poly
		(pts
			(xy 391.634218 -284.472126) (xy 391.583418 -284.472126) (xy 391.481818 -284.508448) (xy 391.481818 -284.698948)
			(xy 391.583418 -284.73527) (xy 391.634218 -284.73527)
		)
		(stroke
			(width 0)
			(type solid)
		)
		(fill yes)
		(layer "F.Cu")
		(net "M_E_CPU0_SA_DQ<17>")
	)
	(gr_poly
		(pts
			(xy 391.634218 -283.875226) (xy 391.583418 -283.875226) (xy 391.481818 -283.911548) (xy 391.481818 -284.102048)
			(xy 391.583418 -284.13837) (xy 391.634218 -284.13837)
		)
		(stroke
			(width 0)
			(type solid)
		)
		(fill yes)
		(layer "F.Cu")
		(net "M_E_CPU0_SA_DQ<17>")
	)
	(gr_poly
		(pts
			(xy 391.634218 -283.278326) (xy 391.583418 -283.278326) (xy 391.481818 -283.314648) (xy 391.481818 -283.505148)
			(xy 391.583418 -283.54147) (xy 391.634218 -283.54147)
		)
		(stroke
			(width 0)
			(type solid)
		)
		(fill yes)
		(layer "F.Cu")
		(net "M_E_CPU0_SA_DQ<17>")
	)
	(gr_poly
		(pts
			(xy 391.634218 -282.681426) (xy 391.583418 -282.681426) (xy 391.481818 -282.717748) (xy 391.481818 -282.908248)
			(xy 391.583418 -282.94457) (xy 391.634218 -282.94457)
		)
		(stroke
			(width 0)
			(type solid)
		)
		(fill yes)
		(layer "F.Cu")
		(net "M_E_CPU0_SA_DQ<17>")
	)
	(gr_poly
		(pts
			(xy 391.634218 -282.084526) (xy 391.583418 -282.084526) (xy 391.481818 -282.120848) (xy 391.481818 -282.311348)
			(xy 391.583418 -282.34767) (xy 391.634218 -282.34767)
		)
		(stroke
			(width 0)
			(type solid)
		)
		(fill yes)
		(layer "F.Cu")
		(net "M_E_CPU0_SA_DQ<17>")
	)
	(gr_poly
		(pts
			(xy 391.634218 -281.487626) (xy 391.583418 -281.487626) (xy 391.481818 -281.523948) (xy 391.481818 -281.714448)
			(xy 391.583418 -281.75077) (xy 391.634218 -281.75077)
		)
		(stroke
			(width 0)
			(type solid)
		)
		(fill yes)
		(layer "F.Cu")
		(net "M_E_CPU0_SA_DQ<17>")
	)
	(gr_poly
		(pts
			(xy 391.634218 -280.890726) (xy 391.583418 -280.890726) (xy 391.481818 -280.927048) (xy 391.481818 -281.117548)
			(xy 391.583418 -281.15387) (xy 391.634218 -281.15387)
		)
		(stroke
			(width 0)
			(type solid)
		)
		(fill yes)
		(layer "F.Cu")
		(net "M_E_CPU0_SA_DQ<17>")
	)
	(gr_poly
		(pts
			(xy 391.63498 -228.400864) (xy 391.599166 -228.364796) (xy 391.50163 -228.318568) (xy 391.36701 -228.453188)
			(xy 391.413238 -228.550724) (xy 391.449306 -228.586538)
		)
		(stroke
			(width 0)
			(type solid)
		)
		(fill yes)
		(layer "F.Cu")
		(net "M_E_CPU0_SB_DQ<22>")
	)
	(gr_poly
		(pts
			(xy 391.661904 -230.9622) (xy 391.62609 -230.926132) (xy 391.528554 -230.879904) (xy 391.393934 -231.014778)
			(xy 391.440162 -231.11206) (xy 391.475976 -231.148128)
		)
		(stroke
			(width 0)
			(type solid)
		)
		(fill yes)
		(layer "F.Cu")
		(net "M_E_CPU0_SB_DQ<19>")
	)
	(gr_poly
		(pts
			(xy 391.671302 -231.815386) (xy 391.635234 -231.779572) (xy 391.537952 -231.733344) (xy 391.403078 -231.867964)
			(xy 391.449306 -231.9655) (xy 391.485374 -232.001314)
		)
		(stroke
			(width 0)
			(type solid)
		)
		(fill yes)
		(layer "F.Cu")
		(net "M_E_CPU0_SB_DQ<18>")
	)
	(gr_poly
		(pts
			(xy 391.679938 -233.512614) (xy 391.644124 -233.476546) (xy 391.546588 -233.430318) (xy 391.411968 -233.565192)
			(xy 391.458196 -233.662474) (xy 391.49401 -233.698542)
		)
		(stroke
			(width 0)
			(type solid)
		)
		(fill yes)
		(layer "F.Cu")
		(net "M_E_CPU0_SB_DQ<13>")
	)
	(gr_poly
		(pts
			(xy 391.689082 -234.366054) (xy 391.653268 -234.329986) (xy 391.555732 -234.283758) (xy 391.421112 -234.418378)
			(xy 391.46734 -234.515914) (xy 391.503408 -234.551728)
		)
		(stroke
			(width 0)
			(type solid)
		)
		(fill yes)
		(layer "F.Cu")
		(net "M_E_CPU0_SB_DQ<12>")
	)
	(gr_poly
		(pts
			(xy 391.694416 -248.967752) (xy 391.658348 -248.866152) (xy 391.467848 -248.866152) (xy 391.43178 -248.967752)
			(xy 391.43178 -249.018552) (xy 391.694416 -249.018552)
		)
		(stroke
			(width 0)
			(type solid)
		)
		(fill yes)
		(layer "F.Cu")
		(net "M_E_CPU0_SB_CA<0>")
	)
	(gr_poly
		(pts
			(xy 391.694416 -248.662952) (xy 391.658348 -248.561352) (xy 391.467848 -248.561352) (xy 391.43178 -248.662952)
			(xy 391.43178 -248.713752) (xy 391.694416 -248.713752)
		)
		(stroke
			(width 0)
			(type solid)
		)
		(fill yes)
		(layer "F.Cu")
		(net "M_E_CPU0_SB_CA<1>")
	)
	(gr_poly
		(pts
			(xy 391.694416 -248.358152) (xy 391.658348 -248.256552) (xy 391.467848 -248.256552) (xy 391.43178 -248.358152)
			(xy 391.43178 -248.408952) (xy 391.694416 -248.408952)
		)
		(stroke
			(width 0)
			(type solid)
		)
		(fill yes)
		(layer "F.Cu")
		(net "M_E_CPU0_SB_CA<2>")
	)
	(gr_poly
		(pts
			(xy 391.694416 -248.053352) (xy 391.658348 -247.951752) (xy 391.467848 -247.951752) (xy 391.43178 -248.053352)
			(xy 391.43178 -248.104152) (xy 391.694416 -248.104152)
		)
		(stroke
			(width 0)
			(type solid)
		)
		(fill yes)
		(layer "F.Cu")
		(net "M_E_CPU0_SB_CA<3>")
	)
	(gr_poly
		(pts
			(xy 391.694416 -247.748552) (xy 391.658348 -247.646952) (xy 391.467848 -247.646952) (xy 391.43178 -247.748552)
			(xy 391.43178 -247.799352) (xy 391.694416 -247.799352)
		)
		(stroke
			(width 0)
			(type solid)
		)
		(fill yes)
		(layer "F.Cu")
		(net "M_E_CPU0_SB_CA<4>")
	)
	(gr_poly
		(pts
			(xy 391.694416 -247.443752) (xy 391.658348 -247.342152) (xy 391.467848 -247.342152) (xy 391.43178 -247.443752)
			(xy 391.43178 -247.494552) (xy 391.694416 -247.494552)
		)
		(stroke
			(width 0)
			(type solid)
		)
		(fill yes)
		(layer "F.Cu")
		(net "M_E_CPU0_SB_CA<5>")
	)
	(gr_poly
		(pts
			(xy 391.694416 -247.138952) (xy 391.658348 -247.037352) (xy 391.467848 -247.037352) (xy 391.43178 -247.138952)
			(xy 391.43178 -247.189752) (xy 391.694416 -247.189752)
		)
		(stroke
			(width 0)
			(type solid)
		)
		(fill yes)
		(layer "F.Cu")
		(net "M_E_CPU0_SB_CA<6>")
	)
	(gr_poly
		(pts
			(xy 391.694416 -246.834152) (xy 391.658348 -246.732552) (xy 391.467848 -246.732552) (xy 391.43178 -246.834152)
			(xy 391.43178 -246.884952) (xy 391.694416 -246.884952)
		)
		(stroke
			(width 0)
			(type solid)
		)
		(fill yes)
		(layer "F.Cu")
		(net "M_E_CPU0_SB_PAR")
	)
	(gr_poly
		(pts
			(xy 391.694416 -246.529352) (xy 391.658348 -246.427752) (xy 391.467848 -246.427752) (xy 391.43178 -246.529352)
			(xy 391.43178 -246.580152) (xy 391.694416 -246.580152)
		)
		(stroke
			(width 0)
			(type solid)
		)
		(fill yes)
		(layer "F.Cu")
		(net "M_E_CPU0_SB_CS_N<0>")
	)
	(gr_poly
		(pts
			(xy 391.694924 -266.447778) (xy 391.730738 -266.41171) (xy 391.54481 -266.225782) (xy 391.508996 -266.26185)
			(xy 391.462768 -266.359132) (xy 391.597388 -266.494006)
		)
		(stroke
			(width 0)
			(type solid)
		)
		(fill yes)
		(layer "F.Cu")
		(net "M_E_CPU0_SA_CB<0>")
	)
	(gr_poly
		(pts
			(xy 391.697972 -278.937212) (xy 391.790428 -278.88184) (xy 391.75309 -278.694896) (xy 391.64641 -278.679402)
			(xy 391.596626 -278.689308) (xy 391.648188 -278.947118)
		)
		(stroke
			(width 0)
			(type solid)
		)
		(fill yes)
		(layer "F.Cu")
		(net "M_E_CPU0_SA_DQ<19>")
	)
	(gr_poly
		(pts
			(xy 391.704068 -265.594338) (xy 391.740136 -265.558524) (xy 391.554208 -265.372596) (xy 391.51814 -265.40841)
			(xy 391.471912 -265.505946) (xy 391.606786 -265.640566)
		)
		(stroke
			(width 0)
			(type solid)
		)
		(fill yes)
		(layer "F.Cu")
		(net "M_E_CPU0_SA_CB<1>")
	)
	(gr_poly
		(pts
			(xy 391.706608 -279.239726) (xy 391.655046 -278.981916) (xy 391.605262 -278.992076) (xy 391.512806 -279.047448)
			(xy 391.550144 -279.234138) (xy 391.656824 -279.249886)
		)
		(stroke
			(width 0)
			(type solid)
		)
		(fill yes)
		(layer "F.Cu")
		(net "M_E_CPU0_SA_DQ<19>")
	)
	(gr_poly
		(pts
			(xy 391.71118 -227.325174) (xy 391.71118 -227.134674) (xy 391.60958 -227.098606) (xy 391.55878 -227.098606)
			(xy 391.55878 -227.361496) (xy 391.60958 -227.361496)
		)
		(stroke
			(width 0)
			(type solid)
		)
		(fill yes)
		(layer "F.Cu")
		(net "M_E_CPU0_SB_DQ<23>")
	)
	(gr_poly
		(pts
			(xy 391.71118 -226.728274) (xy 391.71118 -226.537774) (xy 391.60958 -226.501706) (xy 391.55878 -226.501706)
			(xy 391.55878 -226.764596) (xy 391.60958 -226.764596)
		)
		(stroke
			(width 0)
			(type solid)
		)
		(fill yes)
		(layer "F.Cu")
		(net "M_E_CPU0_SB_DQ<23>")
	)
	(gr_poly
		(pts
			(xy 391.71118 -226.131374) (xy 391.71118 -225.940874) (xy 391.60958 -225.904806) (xy 391.55878 -225.904806)
			(xy 391.55878 -226.167696) (xy 391.60958 -226.167696)
		)
		(stroke
			(width 0)
			(type solid)
		)
		(fill yes)
		(layer "F.Cu")
		(net "M_E_CPU0_SB_DQ<23>")
	)
	(gr_poly
		(pts
			(xy 391.71118 -225.534474) (xy 391.71118 -225.343974) (xy 391.60958 -225.307906) (xy 391.55878 -225.307906)
			(xy 391.55878 -225.570796) (xy 391.60958 -225.570796)
		)
		(stroke
			(width 0)
			(type solid)
		)
		(fill yes)
		(layer "F.Cu")
		(net "M_E_CPU0_SB_DQ<23>")
	)
	(gr_poly
		(pts
			(xy 391.71118 -224.937574) (xy 391.71118 -224.747074) (xy 391.60958 -224.711006) (xy 391.55878 -224.711006)
			(xy 391.55878 -224.973896) (xy 391.60958 -224.973896)
		)
		(stroke
			(width 0)
			(type solid)
		)
		(fill yes)
		(layer "F.Cu")
		(net "M_E_CPU0_SB_DQ<23>")
	)
	(gr_poly
		(pts
			(xy 391.71118 -224.340674) (xy 391.71118 -224.150174) (xy 391.60958 -224.114106) (xy 391.55878 -224.114106)
			(xy 391.55878 -224.376996) (xy 391.60958 -224.376996)
		)
		(stroke
			(width 0)
			(type solid)
		)
		(fill yes)
		(layer "F.Cu")
		(net "M_E_CPU0_SB_DQ<23>")
	)
	(gr_poly
		(pts
			(xy 391.71118 -223.743774) (xy 391.71118 -223.553274) (xy 391.60958 -223.517206) (xy 391.55878 -223.517206)
			(xy 391.55878 -223.780096) (xy 391.60958 -223.780096)
		)
		(stroke
			(width 0)
			(type solid)
		)
		(fill yes)
		(layer "F.Cu")
		(net "M_E_CPU0_SB_DQ<23>")
	)
	(gr_poly
		(pts
			(xy 391.71118 -223.146874) (xy 391.71118 -222.956374) (xy 391.60958 -222.920306) (xy 391.55878 -222.920306)
			(xy 391.55878 -223.183196) (xy 391.60958 -223.183196)
		)
		(stroke
			(width 0)
			(type solid)
		)
		(fill yes)
		(layer "F.Cu")
		(net "M_E_CPU0_SB_DQ<23>")
	)
	(gr_poly
		(pts
			(xy 391.71118 -222.549974) (xy 391.71118 -222.359474) (xy 391.60958 -222.323406) (xy 391.55878 -222.323406)
			(xy 391.55878 -222.586296) (xy 391.60958 -222.586296)
		)
		(stroke
			(width 0)
			(type solid)
		)
		(fill yes)
		(layer "F.Cu")
		(net "M_E_CPU0_SB_DQ<23>")
	)
	(gr_poly
		(pts
			(xy 391.71118 -221.953074) (xy 391.71118 -221.762574) (xy 391.60958 -221.726506) (xy 391.55878 -221.726506)
			(xy 391.55878 -221.989396) (xy 391.60958 -221.989396)
		)
		(stroke
			(width 0)
			(type solid)
		)
		(fill yes)
		(layer "F.Cu")
		(net "M_E_CPU0_SB_DQ<23>")
	)
	(gr_poly
		(pts
			(xy 391.71118 -221.356174) (xy 391.71118 -221.165674) (xy 391.60958 -221.129606) (xy 391.55878 -221.129606)
			(xy 391.55878 -221.392496) (xy 391.60958 -221.392496)
		)
		(stroke
			(width 0)
			(type solid)
		)
		(fill yes)
		(layer "F.Cu")
		(net "M_E_CPU0_SB_DQ<23>")
	)
	(gr_poly
		(pts
			(xy 391.71118 -220.759274) (xy 391.71118 -220.568774) (xy 391.60958 -220.532706) (xy 391.55878 -220.532706)
			(xy 391.55878 -220.795596) (xy 391.60958 -220.795596)
		)
		(stroke
			(width 0)
			(type solid)
		)
		(fill yes)
		(layer "F.Cu")
		(net "M_E_CPU0_SB_DQ<23>")
	)
	(gr_poly
		(pts
			(xy 391.71118 -220.162374) (xy 391.71118 -219.971874) (xy 391.60958 -219.935806) (xy 391.55878 -219.935806)
			(xy 391.55878 -220.198696) (xy 391.60958 -220.198696)
		)
		(stroke
			(width 0)
			(type solid)
		)
		(fill yes)
		(layer "F.Cu")
		(net "M_E_CPU0_SB_DQ<23>")
	)
	(gr_poly
		(pts
			(xy 391.71118 -219.565474) (xy 391.71118 -219.374974) (xy 391.60958 -219.338906) (xy 391.55878 -219.338906)
			(xy 391.55878 -219.601796) (xy 391.60958 -219.601796)
		)
		(stroke
			(width 0)
			(type solid)
		)
		(fill yes)
		(layer "F.Cu")
		(net "M_E_CPU0_SB_DQ<23>")
	)
	(gr_poly
		(pts
			(xy 391.71118 -218.968574) (xy 391.71118 -218.778074) (xy 391.60958 -218.742006) (xy 391.55878 -218.742006)
			(xy 391.55878 -219.004896) (xy 391.60958 -219.004896)
		)
		(stroke
			(width 0)
			(type solid)
		)
		(fill yes)
		(layer "F.Cu")
		(net "M_E_CPU0_SB_DQ<23>")
	)
	(gr_poly
		(pts
			(xy 391.71118 -218.371674) (xy 391.71118 -218.181174) (xy 391.60958 -218.145106) (xy 391.55878 -218.145106)
			(xy 391.55878 -218.407996) (xy 391.60958 -218.407996)
		)
		(stroke
			(width 0)
			(type solid)
		)
		(fill yes)
		(layer "F.Cu")
		(net "M_E_CPU0_SB_DQ<23>")
	)
	(gr_poly
		(pts
			(xy 391.71118 -217.774774) (xy 391.71118 -217.584274) (xy 391.60958 -217.548206) (xy 391.55878 -217.548206)
			(xy 391.55878 -217.811096) (xy 391.60958 -217.811096)
		)
		(stroke
			(width 0)
			(type solid)
		)
		(fill yes)
		(layer "F.Cu")
		(net "M_E_CPU0_SB_DQ<23>")
	)
	(gr_poly
		(pts
			(xy 391.71118 -217.177874) (xy 391.71118 -216.987374) (xy 391.60958 -216.951306) (xy 391.55878 -216.951306)
			(xy 391.55878 -217.214196) (xy 391.60958 -217.214196)
		)
		(stroke
			(width 0)
			(type solid)
		)
		(fill yes)
		(layer "F.Cu")
		(net "M_E_CPU0_SB_DQ<23>")
	)
	(gr_poly
		(pts
			(xy 391.71118 -216.580974) (xy 391.71118 -216.390474) (xy 391.60958 -216.354406) (xy 391.55878 -216.354406)
			(xy 391.55878 -216.617296) (xy 391.60958 -216.617296)
		)
		(stroke
			(width 0)
			(type solid)
		)
		(fill yes)
		(layer "F.Cu")
		(net "M_E_CPU0_SB_DQ<23>")
	)
	(gr_poly
		(pts
			(xy 391.71118 -215.984074) (xy 391.71118 -215.793574) (xy 391.60958 -215.757506) (xy 391.55878 -215.757506)
			(xy 391.55878 -216.020396) (xy 391.60958 -216.020396)
		)
		(stroke
			(width 0)
			(type solid)
		)
		(fill yes)
		(layer "F.Cu")
		(net "M_E_CPU0_SB_DQ<23>")
	)
	(gr_poly
		(pts
			(xy 391.71118 -215.387174) (xy 391.71118 -215.196674) (xy 391.60958 -215.160606) (xy 391.55878 -215.160606)
			(xy 391.55878 -215.423496) (xy 391.60958 -215.423496)
		)
		(stroke
			(width 0)
			(type solid)
		)
		(fill yes)
		(layer "F.Cu")
		(net "M_E_CPU0_SB_DQ<23>")
	)
	(gr_poly
		(pts
			(xy 391.712704 -228.107494) (xy 391.666476 -228.009958) (xy 391.630408 -227.974144) (xy 391.44448 -228.160072)
			(xy 391.480548 -228.195886) (xy 391.578084 -228.242114)
		)
		(stroke
			(width 0)
			(type solid)
		)
		(fill yes)
		(layer "F.Cu")
		(net "M_E_CPU0_SB_DQ<21>")
	)
	(gr_poly
		(pts
			(xy 391.714228 -236.928914) (xy 391.67816 -236.8931) (xy 391.580878 -236.846618) (xy 391.446004 -236.981492)
			(xy 391.492232 -237.078774) (xy 391.5283 -237.114842)
		)
		(stroke
			(width 0)
			(type solid)
		)
		(fill yes)
		(layer "F.Cu")
		(net "M_E_CPU0_SB_DQ<9>")
	)
	(gr_poly
		(pts
			(xy 391.715752 -257.13055) (xy 391.75182 -257.094736) (xy 391.565892 -256.908808) (xy 391.529824 -256.944622)
			(xy 391.483596 -257.042158) (xy 391.61847 -257.176778)
		)
		(stroke
			(width 0)
			(type solid)
		)
		(fill yes)
		(layer "F.Cu")
		(net "M_E_CPU0_SA_CA<3>")
	)
	(gr_poly
		(pts
			(xy 391.721848 -228.96068) (xy 391.67562 -228.863398) (xy 391.639806 -228.82733) (xy 391.453878 -229.013258)
			(xy 391.489692 -229.049326) (xy 391.587228 -229.095554)
		)
		(stroke
			(width 0)
			(type solid)
		)
		(fill yes)
		(layer "F.Cu")
		(net "M_E_CPU0_SB_DQ<20>")
	)
	(gr_poly
		(pts
			(xy 391.722864 -238.626142) (xy 391.68705 -238.590074) (xy 391.589514 -238.543846) (xy 391.454894 -238.678466)
			(xy 391.501122 -238.776002) (xy 391.53719 -238.811816)
		)
		(stroke
			(width 0)
			(type solid)
		)
		(fill yes)
		(layer "F.Cu")
		(net "M_E_CPU0_SB_CB<3>")
	)
	(gr_poly
		(pts
			(xy 391.724134 -237.783116) (xy 391.68832 -237.747048) (xy 391.590784 -237.70082) (xy 391.456164 -237.835694)
			(xy 391.502392 -237.932976) (xy 391.538206 -237.969044)
		)
		(stroke
			(width 0)
			(type solid)
		)
		(fill yes)
		(layer "F.Cu")
		(net "M_E_CPU0_SB_DQ<8>")
	)
	(gr_poly
		(pts
			(xy 391.724896 -256.27711) (xy 391.760964 -256.241296) (xy 391.575036 -256.055368) (xy 391.539222 -256.091182)
			(xy 391.49274 -256.188718) (xy 391.627614 -256.323338)
		)
		(stroke
			(width 0)
			(type solid)
		)
		(fill yes)
		(layer "F.Cu")
		(net "M_E_CPU0_SA_CA<5>")
	)
	(gr_poly
		(pts
			(xy 391.728198 -268.102588) (xy 391.764266 -268.066774) (xy 391.578338 -267.880846) (xy 391.54227 -267.91666)
			(xy 391.496042 -268.014196) (xy 391.630916 -268.148816)
		)
		(stroke
			(width 0)
			(type solid)
		)
		(fill yes)
		(layer "F.Cu")
		(net "M_E_CPU0_SA_DQ<30>")
	)
	(gr_poly
		(pts
			(xy 391.732262 -239.479328) (xy 391.696194 -239.443514) (xy 391.598912 -239.397286) (xy 391.464038 -239.531906)
			(xy 391.510266 -239.629442) (xy 391.546334 -239.665256)
		)
		(stroke
			(width 0)
			(type solid)
		)
		(fill yes)
		(layer "F.Cu")
		(net "M_E_CPU0_SB_CB<2>")
	)
	(gr_poly
		(pts
			(xy 391.734294 -255.423924) (xy 391.770108 -255.387856) (xy 391.58418 -255.201928) (xy 391.548366 -255.237996)
			(xy 391.502138 -255.335278) (xy 391.636758 -255.470152)
		)
		(stroke
			(width 0)
			(type solid)
		)
		(fill yes)
		(layer "F.Cu")
		(net "M_E_CPU0_SA_PAR")
	)
	(gr_poly
		(pts
			(xy 391.73785 -267.248894) (xy 391.773664 -267.21308) (xy 391.587736 -267.027152) (xy 391.551922 -267.06322)
			(xy 391.505694 -267.160502) (xy 391.640314 -267.295376)
		)
		(stroke
			(width 0)
			(type solid)
		)
		(fill yes)
		(layer "F.Cu")
		(net "M_E_CPU0_SA_DQ<31>")
	)
	(gr_poly
		(pts
			(xy 391.748772 -231.52227) (xy 391.702544 -231.424734) (xy 391.666476 -231.38892) (xy 391.480802 -231.574594)
			(xy 391.516616 -231.610662) (xy 391.614152 -231.65689)
		)
		(stroke
			(width 0)
			(type solid)
		)
		(fill yes)
		(layer "F.Cu")
		(net "M_E_CPU0_SB_DQ<17>")
	)
	(gr_poly
		(pts
			(xy 391.750804 -273.750278) (xy 391.786872 -273.714464) (xy 391.600944 -273.528536) (xy 391.564876 -273.56435)
			(xy 391.518648 -273.661886) (xy 391.653522 -273.796506)
		)
		(stroke
			(width 0)
			(type solid)
		)
		(fill yes)
		(layer "F.Cu")
		(net "M_E_CPU0_SA_DQ<22>")
	)
	(gr_poly
		(pts
			(xy 391.752074 -263.05383) (xy 391.788142 -263.018016) (xy 391.602214 -262.832088) (xy 391.5664 -262.867902)
			(xy 391.520172 -262.965438) (xy 391.654792 -263.100058)
		)
		(stroke
			(width 0)
			(type solid)
		)
		(fill yes)
		(layer "F.Cu")
		(net "M_E_CPU0_SA_CB<4>")
	)
	(gr_poly
		(pts
			(xy 391.757662 -233.219244) (xy 391.71118 -233.121708) (xy 391.675366 -233.085894) (xy 391.489438 -233.271822)
			(xy 391.525506 -233.307636) (xy 391.622788 -233.353864)
		)
		(stroke
			(width 0)
			(type solid)
		)
		(fill yes)
		(layer "F.Cu")
		(net "M_E_CPU0_SB_DQ<15>")
	)
	(gr_poly
		(pts
			(xy 391.757916 -232.375456) (xy 391.711688 -232.278174) (xy 391.675874 -232.242106) (xy 391.489946 -232.428034)
			(xy 391.52576 -232.464102) (xy 391.623296 -232.51033)
		)
		(stroke
			(width 0)
			(type solid)
		)
		(fill yes)
		(layer "F.Cu")
		(net "M_E_CPU0_SB_DQ<16>")
	)
	(gr_poly
		(pts
			(xy 391.759694 -272.052796) (xy 391.795762 -272.016982) (xy 391.609834 -271.831054) (xy 391.573766 -271.866868)
			(xy 391.527538 -271.964404) (xy 391.662412 -272.099024)
		)
		(stroke
			(width 0)
			(type solid)
		)
		(fill yes)
		(layer "F.Cu")
		(net "M_E_CPU0_SA_DQ<24>")
	)
	(gr_poly
		(pts
			(xy 391.760202 -272.896838) (xy 391.796016 -272.86077) (xy 391.610088 -272.674842) (xy 391.574274 -272.71091)
			(xy 391.528046 -272.808192) (xy 391.662666 -272.943066)
		)
		(stroke
			(width 0)
			(type solid)
		)
		(fill yes)
		(layer "F.Cu")
		(net "M_E_CPU0_SA_DQ<23>")
	)
	(gr_poly
		(pts
			(xy 391.761472 -262.200644) (xy 391.797286 -262.164576) (xy 391.611358 -261.978648) (xy 391.575544 -262.014716)
			(xy 391.529316 -262.111998) (xy 391.663936 -262.246872)
		)
		(stroke
			(width 0)
			(type solid)
		)
		(fill yes)
		(layer "F.Cu")
		(net "M_E_CPU0_SA_CB<5>")
	)
	(gr_poly
		(pts
			(xy 391.766806 -234.072684) (xy 391.720578 -233.975148) (xy 391.68451 -233.939334) (xy 391.498582 -234.125262)
			(xy 391.53465 -234.161076) (xy 391.631932 -234.207304)
		)
		(stroke
			(width 0)
			(type solid)
		)
		(fill yes)
		(layer "F.Cu")
		(net "M_E_CPU0_SB_DQ<14>")
	)
	(gr_poly
		(pts
			(xy 391.768838 -271.199356) (xy 391.804906 -271.163542) (xy 391.618978 -270.977614) (xy 391.58291 -271.013428)
			(xy 391.536682 -271.110964) (xy 391.671556 -271.245584)
		)
		(stroke
			(width 0)
			(type solid)
		)
		(fill yes)
		(layer "F.Cu")
		(net "M_E_CPU0_SA_DQ<25>")
	)
	(gr_poly
		(pts
			(xy 391.771378 -265.949176) (xy 391.817606 -265.85164) (xy 391.682986 -265.71702) (xy 391.58545 -265.763248)
			(xy 391.549636 -265.799316) (xy 391.73531 -265.98499)
		)
		(stroke
			(width 0)
			(type solid)
		)
		(fill yes)
		(layer "F.Cu")
		(net "M_E_CPU0_SA_CB<2>")
	)
	(gr_poly
		(pts
			(xy 391.780522 -265.095736) (xy 391.82675 -264.998454) (xy 391.69213 -264.86358) (xy 391.594594 -264.909808)
			(xy 391.55878 -264.945876) (xy 391.744708 -265.131804)
		)
		(stroke
			(width 0)
			(type solid)
		)
		(fill yes)
		(layer "F.Cu")
		(net "M_E_CPU0_SA_CB<3>")
	)
	(gr_poly
		(pts
			(xy 391.786618 -289.175698) (xy 391.786618 -288.985198) (xy 391.685018 -288.94913) (xy 391.634218 -288.94913)
			(xy 391.634218 -289.21202) (xy 391.685018 -289.21202)
		)
		(stroke
			(width 0)
			(type solid)
		)
		(fill yes)
		(layer "F.Cu")
		(net "M_E_CPU0_SA_DQ<17>")
	)
	(gr_poly
		(pts
			(xy 391.786618 -288.578798) (xy 391.786618 -288.388298) (xy 391.685018 -288.35223) (xy 391.634218 -288.35223)
			(xy 391.634218 -288.61512) (xy 391.685018 -288.61512)
		)
		(stroke
			(width 0)
			(type solid)
		)
		(fill yes)
		(layer "F.Cu")
		(net "M_E_CPU0_SA_DQ<17>")
	)
	(gr_poly
		(pts
			(xy 391.786618 -287.981898) (xy 391.786618 -287.791398) (xy 391.685018 -287.75533) (xy 391.634218 -287.75533)
			(xy 391.634218 -288.01822) (xy 391.685018 -288.01822)
		)
		(stroke
			(width 0)
			(type solid)
		)
		(fill yes)
		(layer "F.Cu")
		(net "M_E_CPU0_SA_DQ<17>")
	)
	(gr_poly
		(pts
			(xy 391.786618 -287.384998) (xy 391.786618 -287.194498) (xy 391.685018 -287.15843) (xy 391.634218 -287.15843)
			(xy 391.634218 -287.42132) (xy 391.685018 -287.42132)
		)
		(stroke
			(width 0)
			(type solid)
		)
		(fill yes)
		(layer "F.Cu")
		(net "M_E_CPU0_SA_DQ<17>")
	)
	(gr_poly
		(pts
			(xy 391.786618 -286.788098) (xy 391.786618 -286.597598) (xy 391.685018 -286.56153) (xy 391.634218 -286.56153)
			(xy 391.634218 -286.82442) (xy 391.685018 -286.82442)
		)
		(stroke
			(width 0)
			(type solid)
		)
		(fill yes)
		(layer "F.Cu")
		(net "M_E_CPU0_SA_DQ<17>")
	)
	(gr_poly
		(pts
			(xy 391.786618 -286.191198) (xy 391.786618 -286.000698) (xy 391.685018 -285.96463) (xy 391.634218 -285.96463)
			(xy 391.634218 -286.22752) (xy 391.685018 -286.22752)
		)
		(stroke
			(width 0)
			(type solid)
		)
		(fill yes)
		(layer "F.Cu")
		(net "M_E_CPU0_SA_DQ<17>")
	)
	(gr_poly
		(pts
			(xy 391.786618 -285.594298) (xy 391.786618 -285.403798) (xy 391.685018 -285.36773) (xy 391.634218 -285.36773)
			(xy 391.634218 -285.63062) (xy 391.685018 -285.63062)
		)
		(stroke
			(width 0)
			(type solid)
		)
		(fill yes)
		(layer "F.Cu")
		(net "M_E_CPU0_SA_DQ<17>")
	)
	(gr_poly
		(pts
			(xy 391.786618 -284.997398) (xy 391.786618 -284.806898) (xy 391.685018 -284.77083) (xy 391.634218 -284.77083)
			(xy 391.634218 -285.03372) (xy 391.685018 -285.03372)
		)
		(stroke
			(width 0)
			(type solid)
		)
		(fill yes)
		(layer "F.Cu")
		(net "M_E_CPU0_SA_DQ<17>")
	)
	(gr_poly
		(pts
			(xy 391.786618 -284.400498) (xy 391.786618 -284.209998) (xy 391.685018 -284.17393) (xy 391.634218 -284.17393)
			(xy 391.634218 -284.43682) (xy 391.685018 -284.43682)
		)
		(stroke
			(width 0)
			(type solid)
		)
		(fill yes)
		(layer "F.Cu")
		(net "M_E_CPU0_SA_DQ<17>")
	)
	(gr_poly
		(pts
			(xy 391.786618 -283.803598) (xy 391.786618 -283.613098) (xy 391.685018 -283.57703) (xy 391.634218 -283.57703)
			(xy 391.634218 -283.83992) (xy 391.685018 -283.83992)
		)
		(stroke
			(width 0)
			(type solid)
		)
		(fill yes)
		(layer "F.Cu")
		(net "M_E_CPU0_SA_DQ<17>")
	)
	(gr_poly
		(pts
			(xy 391.786618 -283.206698) (xy 391.786618 -283.016198) (xy 391.685018 -282.98013) (xy 391.634218 -282.98013)
			(xy 391.634218 -283.24302) (xy 391.685018 -283.24302)
		)
		(stroke
			(width 0)
			(type solid)
		)
		(fill yes)
		(layer "F.Cu")
		(net "M_E_CPU0_SA_DQ<17>")
	)
	(gr_poly
		(pts
			(xy 391.786618 -282.609798) (xy 391.786618 -282.419298) (xy 391.685018 -282.38323) (xy 391.634218 -282.38323)
			(xy 391.634218 -282.64612) (xy 391.685018 -282.64612)
		)
		(stroke
			(width 0)
			(type solid)
		)
		(fill yes)
		(layer "F.Cu")
		(net "M_E_CPU0_SA_DQ<17>")
	)
	(gr_poly
		(pts
			(xy 391.786618 -282.012898) (xy 391.786618 -281.822398) (xy 391.685018 -281.78633) (xy 391.634218 -281.78633)
			(xy 391.634218 -282.04922) (xy 391.685018 -282.04922)
		)
		(stroke
			(width 0)
			(type solid)
		)
		(fill yes)
		(layer "F.Cu")
		(net "M_E_CPU0_SA_DQ<17>")
	)
	(gr_poly
		(pts
			(xy 391.786618 -281.415998) (xy 391.786618 -281.225498) (xy 391.685018 -281.18943) (xy 391.634218 -281.18943)
			(xy 391.634218 -281.45232) (xy 391.685018 -281.45232)
		)
		(stroke
			(width 0)
			(type solid)
		)
		(fill yes)
		(layer "F.Cu")
		(net "M_E_CPU0_SA_DQ<17>")
	)
	(gr_poly
		(pts
			(xy 391.791698 -236.635544) (xy 391.74547 -236.538008) (xy 391.709402 -236.502194) (xy 391.523474 -236.688122)
			(xy 391.559542 -236.723936) (xy 391.656824 -236.770164)
		)
		(stroke
			(width 0)
			(type solid)
		)
		(fill yes)
		(layer "F.Cu")
		(net "M_E_CPU0_SB_DQ<11>")
	)
	(gr_poly
		(pts
			(xy 391.792206 -256.631948) (xy 391.838434 -256.534666) (xy 391.703814 -256.399792) (xy 391.606278 -256.44602)
			(xy 391.570464 -256.482088) (xy 391.756392 -256.668016)
		)
		(stroke
			(width 0)
			(type solid)
		)
		(fill yes)
		(layer "F.Cu")
		(net "M_E_CPU0_SA_CA<4>")
	)
	(gr_poly
		(pts
			(xy 391.795508 -268.457426) (xy 391.841736 -268.360144) (xy 391.707116 -268.22527) (xy 391.60958 -268.271498)
			(xy 391.573766 -268.307566) (xy 391.759694 -268.493494)
		)
		(stroke
			(width 0)
			(type solid)
		)
		(fill yes)
		(layer "F.Cu")
		(net "M_E_CPU0_SA_DQ<28>")
	)
	(gr_poly
		(pts
			(xy 391.80135 -255.778762) (xy 391.847578 -255.681226) (xy 391.712958 -255.546606) (xy 391.615676 -255.592834)
			(xy 391.579608 -255.628648) (xy 391.765536 -255.814576)
		)
		(stroke
			(width 0)
			(type solid)
		)
		(fill yes)
		(layer "F.Cu")
		(net "M_E_CPU0_SA_CA<6>")
	)
	(gr_poly
		(pts
			(xy 391.801604 -237.489746) (xy 391.755376 -237.39221) (xy 391.719562 -237.356142) (xy 391.533634 -237.54207)
			(xy 391.569448 -237.578138) (xy 391.666984 -237.624366)
		)
		(stroke
			(width 0)
			(type solid)
		)
		(fill yes)
		(layer "F.Cu")
		(net "M_E_CPU0_SB_DQ<10>")
	)
	(gr_poly
		(pts
			(xy 391.804906 -267.603986) (xy 391.851134 -267.50645) (xy 391.716514 -267.37183) (xy 391.618978 -267.418058)
			(xy 391.583164 -267.454126) (xy 391.768838 -267.6398)
		)
		(stroke
			(width 0)
			(type solid)
		)
		(fill yes)
		(layer "F.Cu")
		(net "M_E_CPU0_SA_DQ<29>")
	)
	(gr_poly
		(pts
			(xy 391.809732 -239.185958) (xy 391.763504 -239.088676) (xy 391.72769 -239.052608) (xy 391.541762 -239.238536)
			(xy 391.577576 -239.274604) (xy 391.675112 -239.320832)
		)
		(stroke
			(width 0)
			(type solid)
		)
		(fill yes)
		(layer "F.Cu")
		(net "M_E_CPU0_SB_CB<1>")
	)
	(gr_poly
		(pts
			(xy 391.814812 -279.522428) (xy 391.907522 -279.467056) (xy 391.870184 -279.280366) (xy 391.763504 -279.264872)
			(xy 391.71372 -279.274778) (xy 391.765028 -279.532588)
		)
		(stroke
			(width 0)
			(type solid)
		)
		(fill yes)
		(layer "F.Cu")
		(net "M_E_CPU0_SA_DQ<19>")
	)
	(gr_poly
		(pts
			(xy 391.818114 -274.10537) (xy 391.864342 -274.007834) (xy 391.729468 -273.873214) (xy 391.632186 -273.919442)
			(xy 391.596118 -273.955256) (xy 391.782046 -274.141184)
		)
		(stroke
			(width 0)
			(type solid)
		)
		(fill yes)
		(layer "F.Cu")
		(net "M_E_CPU0_SA_DQ<20>")
	)
	(gr_poly
		(pts
			(xy 391.818876 -240.039398) (xy 391.772648 -239.942116) (xy 391.736834 -239.906048) (xy 391.550906 -240.091976)
			(xy 391.58672 -240.12779) (xy 391.684256 -240.174018)
		)
		(stroke
			(width 0)
			(type solid)
		)
		(fill yes)
		(layer "F.Cu")
		(net "M_E_CPU0_SB_CB<0>")
	)
	(gr_poly
		(pts
			(xy 391.822432 -242.700556) (xy 391.822432 -242.649756) (xy 391.559542 -242.649756) (xy 391.559542 -242.700556)
			(xy 391.595864 -242.802156) (xy 391.786364 -242.802156)
		)
		(stroke
			(width 0)
			(type solid)
		)
		(fill yes)
		(layer "F.Cu")
		(net "M_E_CPU0_SB_CB<4>")
	)
	(gr_poly
		(pts
			(xy 391.822432 -242.395756) (xy 391.822432 -242.344956) (xy 391.559542 -242.344956) (xy 391.559542 -242.395756)
			(xy 391.595864 -242.497356) (xy 391.786364 -242.497356)
		)
		(stroke
			(width 0)
			(type solid)
		)
		(fill yes)
		(layer "F.Cu")
		(net "M_E_CPU0_SB_CB<6>")
	)
	(gr_poly
		(pts
			(xy 391.822432 -242.090956) (xy 391.822432 -242.040156) (xy 391.559542 -242.040156) (xy 391.559542 -242.090956)
			(xy 391.595864 -242.192556) (xy 391.786364 -242.192556)
		)
		(stroke
			(width 0)
			(type solid)
		)
		(fill yes)
		(layer "F.Cu")
		(net "M_E_CPU0_SB_CB<5>")
	)
	(gr_poly
		(pts
			(xy 391.822432 -241.786156) (xy 391.822432 -241.735356) (xy 391.559542 -241.735356) (xy 391.559542 -241.786156)
			(xy 391.595864 -241.887756) (xy 391.786364 -241.887756)
		)
		(stroke
			(width 0)
			(type solid)
		)
		(fill yes)
		(layer "F.Cu")
		(net "M_E_CPU0_SB_CB<7>")
	)
	(gr_poly
		(pts
			(xy 391.823448 -279.825196) (xy 391.77214 -279.567386) (xy 391.722356 -279.577292) (xy 391.629646 -279.632664)
			(xy 391.666984 -279.819608) (xy 391.773664 -279.835102)
		)
		(stroke
			(width 0)
			(type solid)
		)
		(fill yes)
		(layer "F.Cu")
		(net "M_E_CPU0_SA_DQ<19>")
	)
	(gr_poly
		(pts
			(xy 391.827258 -273.251676) (xy 391.873486 -273.154394) (xy 391.738866 -273.01952) (xy 391.64133 -273.065748)
			(xy 391.605516 -273.101816) (xy 391.791444 -273.287744)
		)
		(stroke
			(width 0)
			(type solid)
		)
		(fill yes)
		(layer "F.Cu")
		(net "M_E_CPU0_SA_DQ<21>")
	)
	(gr_poly
		(pts
			(xy 391.828528 -262.555482) (xy 391.87501 -262.457946) (xy 391.740136 -262.323326) (xy 391.642854 -262.369554)
			(xy 391.606786 -262.405368) (xy 391.792714 -262.591296)
		)
		(stroke
			(width 0)
			(type solid)
		)
		(fill yes)
		(layer "F.Cu")
		(net "M_E_CPU0_SA_CB<6>")
	)
	(gr_poly
		(pts
			(xy 391.836148 -271.554194) (xy 391.882376 -271.456912) (xy 391.747756 -271.322038) (xy 391.65022 -271.368266)
			(xy 391.614406 -271.404334) (xy 391.800334 -271.590262)
		)
		(stroke
			(width 0)
			(type solid)
		)
		(fill yes)
		(layer "F.Cu")
		(net "M_E_CPU0_SA_DQ<26>")
	)
	(gr_poly
		(pts
			(xy 391.837926 -261.702042) (xy 391.884154 -261.604506) (xy 391.74928 -261.469886) (xy 391.651998 -261.516114)
			(xy 391.61593 -261.551928) (xy 391.801858 -261.737856)
		)
		(stroke
			(width 0)
			(type solid)
		)
		(fill yes)
		(layer "F.Cu")
		(net "M_E_CPU0_SA_CB<7>")
	)
	(gr_poly
		(pts
			(xy 391.845292 -270.700754) (xy 391.89152 -270.603472) (xy 391.7569 -270.468598) (xy 391.659364 -270.51508)
			(xy 391.62355 -270.550894) (xy 391.809478 -270.736822)
		)
		(stroke
			(width 0)
			(type solid)
		)
		(fill yes)
		(layer "F.Cu")
		(net "M_E_CPU0_SA_DQ<27>")
	)
	(gr_poly
		(pts
			(xy 391.850626 -228.61651) (xy 391.814812 -228.580442) (xy 391.717276 -228.534214) (xy 391.582656 -228.668834)
			(xy 391.628884 -228.76637) (xy 391.664952 -228.802184)
		)
		(stroke
			(width 0)
			(type solid)
		)
		(fill yes)
		(layer "F.Cu")
		(net "M_E_CPU0_SB_DQ<20>")
	)
	(gr_poly
		(pts
			(xy 391.86358 -226.800156) (xy 391.81278 -226.800156) (xy 391.71118 -226.836478) (xy 391.71118 -227.026978)
			(xy 391.81278 -227.063046) (xy 391.86358 -227.063046)
		)
		(stroke
			(width 0)
			(type solid)
		)
		(fill yes)
		(layer "F.Cu")
		(net "M_E_CPU0_SB_DQ<21>")
	)
	(gr_poly
		(pts
			(xy 391.86358 -226.203256) (xy 391.81278 -226.203256) (xy 391.71118 -226.239578) (xy 391.71118 -226.430078)
			(xy 391.81278 -226.466146) (xy 391.86358 -226.466146)
		)
		(stroke
			(width 0)
			(type solid)
		)
		(fill yes)
		(layer "F.Cu")
		(net "M_E_CPU0_SB_DQ<21>")
	)
	(gr_poly
		(pts
			(xy 391.86358 -225.606356) (xy 391.81278 -225.606356) (xy 391.71118 -225.642678) (xy 391.71118 -225.833178)
			(xy 391.81278 -225.869246) (xy 391.86358 -225.869246)
		)
		(stroke
			(width 0)
			(type solid)
		)
		(fill yes)
		(layer "F.Cu")
		(net "M_E_CPU0_SB_DQ<21>")
	)
	(gr_poly
		(pts
			(xy 391.86358 -225.009456) (xy 391.81278 -225.009456) (xy 391.71118 -225.045778) (xy 391.71118 -225.236278)
			(xy 391.81278 -225.272346) (xy 391.86358 -225.272346)
		)
		(stroke
			(width 0)
			(type solid)
		)
		(fill yes)
		(layer "F.Cu")
		(net "M_E_CPU0_SB_DQ<21>")
	)
	(gr_poly
		(pts
			(xy 391.86358 -224.412556) (xy 391.81278 -224.412556) (xy 391.71118 -224.448878) (xy 391.71118 -224.639378)
			(xy 391.81278 -224.675446) (xy 391.86358 -224.675446)
		)
		(stroke
			(width 0)
			(type solid)
		)
		(fill yes)
		(layer "F.Cu")
		(net "M_E_CPU0_SB_DQ<21>")
	)
	(gr_poly
		(pts
			(xy 391.86358 -223.815656) (xy 391.81278 -223.815656) (xy 391.71118 -223.851978) (xy 391.71118 -224.042478)
			(xy 391.81278 -224.078546) (xy 391.86358 -224.078546)
		)
		(stroke
			(width 0)
			(type solid)
		)
		(fill yes)
		(layer "F.Cu")
		(net "M_E_CPU0_SB_DQ<21>")
	)
	(gr_poly
		(pts
			(xy 391.86358 -223.218756) (xy 391.81278 -223.218756) (xy 391.71118 -223.255078) (xy 391.71118 -223.445578)
			(xy 391.81278 -223.481646) (xy 391.86358 -223.481646)
		)
		(stroke
			(width 0)
			(type solid)
		)
		(fill yes)
		(layer "F.Cu")
		(net "M_E_CPU0_SB_DQ<21>")
	)
	(gr_poly
		(pts
			(xy 391.86358 -222.621856) (xy 391.81278 -222.621856) (xy 391.71118 -222.658178) (xy 391.71118 -222.848678)
			(xy 391.81278 -222.884746) (xy 391.86358 -222.884746)
		)
		(stroke
			(width 0)
			(type solid)
		)
		(fill yes)
		(layer "F.Cu")
		(net "M_E_CPU0_SB_DQ<21>")
	)
	(gr_poly
		(pts
			(xy 391.86358 -222.024956) (xy 391.81278 -222.024956) (xy 391.71118 -222.061278) (xy 391.71118 -222.251778)
			(xy 391.81278 -222.287846) (xy 391.86358 -222.287846)
		)
		(stroke
			(width 0)
			(type solid)
		)
		(fill yes)
		(layer "F.Cu")
		(net "M_E_CPU0_SB_DQ<21>")
	)
	(gr_poly
		(pts
			(xy 391.86358 -221.428056) (xy 391.81278 -221.428056) (xy 391.71118 -221.464378) (xy 391.71118 -221.654878)
			(xy 391.81278 -221.690946) (xy 391.86358 -221.690946)
		)
		(stroke
			(width 0)
			(type solid)
		)
		(fill yes)
		(layer "F.Cu")
		(net "M_E_CPU0_SB_DQ<21>")
	)
	(gr_poly
		(pts
			(xy 391.86358 -220.831156) (xy 391.81278 -220.831156) (xy 391.71118 -220.867478) (xy 391.71118 -221.057978)
			(xy 391.81278 -221.094046) (xy 391.86358 -221.094046)
		)
		(stroke
			(width 0)
			(type solid)
		)
		(fill yes)
		(layer "F.Cu")
		(net "M_E_CPU0_SB_DQ<21>")
	)
	(gr_poly
		(pts
			(xy 391.86358 -220.234256) (xy 391.81278 -220.234256) (xy 391.71118 -220.270578) (xy 391.71118 -220.461078)
			(xy 391.81278 -220.497146) (xy 391.86358 -220.497146)
		)
		(stroke
			(width 0)
			(type solid)
		)
		(fill yes)
		(layer "F.Cu")
		(net "M_E_CPU0_SB_DQ<21>")
	)
	(gr_poly
		(pts
			(xy 391.86358 -219.637356) (xy 391.81278 -219.637356) (xy 391.71118 -219.673678) (xy 391.71118 -219.864178)
			(xy 391.81278 -219.900246) (xy 391.86358 -219.900246)
		)
		(stroke
			(width 0)
			(type solid)
		)
		(fill yes)
		(layer "F.Cu")
		(net "M_E_CPU0_SB_DQ<21>")
	)
	(gr_poly
		(pts
			(xy 391.86358 -219.040456) (xy 391.81278 -219.040456) (xy 391.71118 -219.076778) (xy 391.71118 -219.267278)
			(xy 391.81278 -219.303346) (xy 391.86358 -219.303346)
		)
		(stroke
			(width 0)
			(type solid)
		)
		(fill yes)
		(layer "F.Cu")
		(net "M_E_CPU0_SB_DQ<21>")
	)
	(gr_poly
		(pts
			(xy 391.86358 -218.443556) (xy 391.81278 -218.443556) (xy 391.71118 -218.479878) (xy 391.71118 -218.670378)
			(xy 391.81278 -218.706446) (xy 391.86358 -218.706446)
		)
		(stroke
			(width 0)
			(type solid)
		)
		(fill yes)
		(layer "F.Cu")
		(net "M_E_CPU0_SB_DQ<21>")
	)
	(gr_poly
		(pts
			(xy 391.86358 -217.846656) (xy 391.81278 -217.846656) (xy 391.71118 -217.882978) (xy 391.71118 -218.073478)
			(xy 391.81278 -218.109546) (xy 391.86358 -218.109546)
		)
		(stroke
			(width 0)
			(type solid)
		)
		(fill yes)
		(layer "F.Cu")
		(net "M_E_CPU0_SB_DQ<21>")
	)
	(gr_poly
		(pts
			(xy 391.86358 -217.249756) (xy 391.81278 -217.249756) (xy 391.71118 -217.286078) (xy 391.71118 -217.476578)
			(xy 391.81278 -217.512646) (xy 391.86358 -217.512646)
		)
		(stroke
			(width 0)
			(type solid)
		)
		(fill yes)
		(layer "F.Cu")
		(net "M_E_CPU0_SB_DQ<21>")
	)
	(gr_poly
		(pts
			(xy 391.86358 -216.652856) (xy 391.81278 -216.652856) (xy 391.71118 -216.689178) (xy 391.71118 -216.879678)
			(xy 391.81278 -216.915746) (xy 391.86358 -216.915746)
		)
		(stroke
			(width 0)
			(type solid)
		)
		(fill yes)
		(layer "F.Cu")
		(net "M_E_CPU0_SB_DQ<21>")
	)
	(gr_poly
		(pts
			(xy 391.86358 -216.055956) (xy 391.81278 -216.055956) (xy 391.71118 -216.092278) (xy 391.71118 -216.282778)
			(xy 391.81278 -216.318846) (xy 391.86358 -216.318846)
		)
		(stroke
			(width 0)
			(type solid)
		)
		(fill yes)
		(layer "F.Cu")
		(net "M_E_CPU0_SB_DQ<21>")
	)
	(gr_poly
		(pts
			(xy 391.86358 -215.459056) (xy 391.81278 -215.459056) (xy 391.71118 -215.495378) (xy 391.71118 -215.685878)
			(xy 391.81278 -215.721946) (xy 391.86358 -215.721946)
		)
		(stroke
			(width 0)
			(type solid)
		)
		(fill yes)
		(layer "F.Cu")
		(net "M_E_CPU0_SB_DQ<21>")
	)
	(gr_poly
		(pts
			(xy 391.87755 -231.177846) (xy 391.841736 -231.141778) (xy 391.7442 -231.09555) (xy 391.60958 -231.230424)
			(xy 391.655808 -231.327706) (xy 391.691622 -231.363774)
		)
		(stroke
			(width 0)
			(type solid)
		)
		(fill yes)
		(layer "F.Cu")
		(net "M_E_CPU0_SB_DQ<17>")
	)
	(gr_poly
		(pts
			(xy 391.88644 -232.87482) (xy 391.850372 -232.839006) (xy 391.75309 -232.792778) (xy 391.61847 -232.927398)
			(xy 391.664698 -233.024934) (xy 391.700512 -233.060748)
		)
		(stroke
			(width 0)
			(type solid)
		)
		(fill yes)
		(layer "F.Cu")
		(net "M_E_CPU0_SB_DQ<15>")
	)
	(gr_poly
		(pts
			(xy 391.886948 -232.031032) (xy 391.85088 -231.995218) (xy 391.753598 -231.94899) (xy 391.618724 -232.08361)
			(xy 391.664952 -232.181146) (xy 391.70102 -232.21696)
		)
		(stroke
			(width 0)
			(type solid)
		)
		(fill yes)
		(layer "F.Cu")
		(net "M_E_CPU0_SB_DQ<16>")
	)
	(gr_poly
		(pts
			(xy 391.895584 -233.72826) (xy 391.85977 -233.692192) (xy 391.762234 -233.645964) (xy 391.627614 -233.780838)
			(xy 391.673842 -233.87812) (xy 391.709656 -233.914188)
		)
		(stroke
			(width 0)
			(type solid)
		)
		(fill yes)
		(layer "F.Cu")
		(net "M_E_CPU0_SB_DQ<14>")
	)
	(gr_poly
		(pts
			(xy 391.91057 -266.232132) (xy 391.946384 -266.196064) (xy 391.760456 -266.010136) (xy 391.724642 -266.046204)
			(xy 391.678414 -266.143486) (xy 391.813034 -266.27836)
		)
		(stroke
			(width 0)
			(type solid)
		)
		(fill yes)
		(layer "F.Cu")
		(net "M_E_CPU0_SA_CB<2>")
	)
	(gr_poly
		(pts
			(xy 391.919714 -265.378692) (xy 391.955782 -265.342878) (xy 391.769854 -265.15695) (xy 391.733786 -265.192764)
			(xy 391.687558 -265.2903) (xy 391.822432 -265.42492)
		)
		(stroke
			(width 0)
			(type solid)
		)
		(fill yes)
		(layer "F.Cu")
		(net "M_E_CPU0_SA_CB<3>")
	)
	(gr_poly
		(pts
			(xy 391.920476 -236.29112) (xy 391.884662 -236.255306) (xy 391.787126 -236.208824) (xy 391.652506 -236.343698)
			(xy 391.698734 -236.44098) (xy 391.734548 -236.477048)
		)
		(stroke
			(width 0)
			(type solid)
		)
		(fill yes)
		(layer "F.Cu")
		(net "M_E_CPU0_SB_DQ<11>")
	)
	(gr_poly
		(pts
			(xy 391.92835 -228.32314) (xy 391.882122 -228.225604) (xy 391.846054 -228.18979) (xy 391.660126 -228.375718)
			(xy 391.696194 -228.411532) (xy 391.79373 -228.45776)
		)
		(stroke
			(width 0)
			(type solid)
		)
		(fill yes)
		(layer "F.Cu")
		(net "M_E_CPU0_SB_DQ<22>")
	)
	(gr_poly
		(pts
			(xy 391.930382 -237.145322) (xy 391.894568 -237.109254) (xy 391.797032 -237.063026) (xy 391.662412 -237.197646)
			(xy 391.70864 -237.295182) (xy 391.744708 -237.330996)
		)
		(stroke
			(width 0)
			(type solid)
		)
		(fill yes)
		(layer "F.Cu")
		(net "M_E_CPU0_SB_DQ<10>")
	)
	(gr_poly
		(pts
			(xy 391.931906 -280.107898) (xy 392.024362 -280.052526) (xy 391.987024 -279.865582) (xy 391.880344 -279.850088)
			(xy 391.83056 -279.859994) (xy 391.882122 -280.117804)
		)
		(stroke
			(width 0)
			(type solid)
		)
		(fill yes)
		(layer "F.Cu")
		(net "M_E_CPU0_SA_DQ<19>")
	)
	(gr_poly
		(pts
			(xy 391.9347 -268.740382) (xy 391.970514 -268.704314) (xy 391.78484 -268.51864) (xy 391.748772 -268.554454)
			(xy 391.702544 -268.65199) (xy 391.837164 -268.78661)
		)
		(stroke
			(width 0)
			(type solid)
		)
		(fill yes)
		(layer "F.Cu")
		(net "M_E_CPU0_SA_DQ<28>")
	)
	(gr_poly
		(pts
			(xy 391.93851 -238.841788) (xy 391.902696 -238.80572) (xy 391.80516 -238.759492) (xy 391.67054 -238.894112)
			(xy 391.716768 -238.991648) (xy 391.752836 -239.027462)
		)
		(stroke
			(width 0)
			(type solid)
		)
		(fill yes)
		(layer "F.Cu")
		(net "M_E_CPU0_SB_CB<1>")
	)
	(gr_poly
		(pts
			(xy 391.939018 -288.650426) (xy 391.888218 -288.650426) (xy 391.786618 -288.686748) (xy 391.786618 -288.877248)
			(xy 391.888218 -288.91357) (xy 391.939018 -288.91357)
		)
		(stroke
			(width 0)
			(type solid)
		)
		(fill yes)
		(layer "F.Cu")
		(net "M_E_CPU0_SA_DQ<19>")
	)
	(gr_poly
		(pts
			(xy 391.939018 -288.053526) (xy 391.888218 -288.053526) (xy 391.786618 -288.089848) (xy 391.786618 -288.280348)
			(xy 391.888218 -288.31667) (xy 391.939018 -288.31667)
		)
		(stroke
			(width 0)
			(type solid)
		)
		(fill yes)
		(layer "F.Cu")
		(net "M_E_CPU0_SA_DQ<19>")
	)
	(gr_poly
		(pts
			(xy 391.939018 -287.456626) (xy 391.888218 -287.456626) (xy 391.786618 -287.492948) (xy 391.786618 -287.683448)
			(xy 391.888218 -287.71977) (xy 391.939018 -287.71977)
		)
		(stroke
			(width 0)
			(type solid)
		)
		(fill yes)
		(layer "F.Cu")
		(net "M_E_CPU0_SA_DQ<19>")
	)
	(gr_poly
		(pts
			(xy 391.939018 -286.859726) (xy 391.888218 -286.859726) (xy 391.786618 -286.896048) (xy 391.786618 -287.086548)
			(xy 391.888218 -287.12287) (xy 391.939018 -287.12287)
		)
		(stroke
			(width 0)
			(type solid)
		)
		(fill yes)
		(layer "F.Cu")
		(net "M_E_CPU0_SA_DQ<19>")
	)
	(gr_poly
		(pts
			(xy 391.939018 -286.262826) (xy 391.888218 -286.262826) (xy 391.786618 -286.299148) (xy 391.786618 -286.489648)
			(xy 391.888218 -286.52597) (xy 391.939018 -286.52597)
		)
		(stroke
			(width 0)
			(type solid)
		)
		(fill yes)
		(layer "F.Cu")
		(net "M_E_CPU0_SA_DQ<19>")
	)
	(gr_poly
		(pts
			(xy 391.939018 -285.665926) (xy 391.888218 -285.665926) (xy 391.786618 -285.702248) (xy 391.786618 -285.892748)
			(xy 391.888218 -285.92907) (xy 391.939018 -285.92907)
		)
		(stroke
			(width 0)
			(type solid)
		)
		(fill yes)
		(layer "F.Cu")
		(net "M_E_CPU0_SA_DQ<19>")
	)
	(gr_poly
		(pts
			(xy 391.939018 -285.069026) (xy 391.888218 -285.069026) (xy 391.786618 -285.105348) (xy 391.786618 -285.295848)
			(xy 391.888218 -285.33217) (xy 391.939018 -285.33217)
		)
		(stroke
			(width 0)
			(type solid)
		)
		(fill yes)
		(layer "F.Cu")
		(net "M_E_CPU0_SA_DQ<19>")
	)
	(gr_poly
		(pts
			(xy 391.939018 -284.472126) (xy 391.888218 -284.472126) (xy 391.786618 -284.508448) (xy 391.786618 -284.698948)
			(xy 391.888218 -284.73527) (xy 391.939018 -284.73527)
		)
		(stroke
			(width 0)
			(type solid)
		)
		(fill yes)
		(layer "F.Cu")
		(net "M_E_CPU0_SA_DQ<19>")
	)
	(gr_poly
		(pts
			(xy 391.939018 -283.875226) (xy 391.888218 -283.875226) (xy 391.786618 -283.911548) (xy 391.786618 -284.102048)
			(xy 391.888218 -284.13837) (xy 391.939018 -284.13837)
		)
		(stroke
			(width 0)
			(type solid)
		)
		(fill yes)
		(layer "F.Cu")
		(net "M_E_CPU0_SA_DQ<19>")
	)
	(gr_poly
		(pts
			(xy 391.939018 -283.278326) (xy 391.888218 -283.278326) (xy 391.786618 -283.314648) (xy 391.786618 -283.505148)
			(xy 391.888218 -283.54147) (xy 391.939018 -283.54147)
		)
		(stroke
			(width 0)
			(type solid)
		)
		(fill yes)
		(layer "F.Cu")
		(net "M_E_CPU0_SA_DQ<19>")
	)
	(gr_poly
		(pts
			(xy 391.939018 -282.681426) (xy 391.888218 -282.681426) (xy 391.786618 -282.717748) (xy 391.786618 -282.908248)
			(xy 391.888218 -282.94457) (xy 391.939018 -282.94457)
		)
		(stroke
			(width 0)
			(type solid)
		)
		(fill yes)
		(layer "F.Cu")
		(net "M_E_CPU0_SA_DQ<19>")
	)
	(gr_poly
		(pts
			(xy 391.939018 -282.084526) (xy 391.888218 -282.084526) (xy 391.786618 -282.120848) (xy 391.786618 -282.311348)
			(xy 391.888218 -282.34767) (xy 391.939018 -282.34767)
		)
		(stroke
			(width 0)
			(type solid)
		)
		(fill yes)
		(layer "F.Cu")
		(net "M_E_CPU0_SA_DQ<19>")
	)
	(gr_poly
		(pts
			(xy 391.939018 -281.487626) (xy 391.888218 -281.487626) (xy 391.786618 -281.523948) (xy 391.786618 -281.714448)
			(xy 391.888218 -281.75077) (xy 391.939018 -281.75077)
		)
		(stroke
			(width 0)
			(type solid)
		)
		(fill yes)
		(layer "F.Cu")
		(net "M_E_CPU0_SA_DQ<19>")
	)
	(gr_poly
		(pts
			(xy 391.939018 -280.890726) (xy 391.888218 -280.890726) (xy 391.786618 -280.927048) (xy 391.786618 -281.117548)
			(xy 391.888218 -281.15387) (xy 391.939018 -281.15387)
		)
		(stroke
			(width 0)
			(type solid)
		)
		(fill yes)
		(layer "F.Cu")
		(net "M_E_CPU0_SA_DQ<19>")
	)
	(gr_poly
		(pts
			(xy 391.940542 -256.061464) (xy 391.97661 -256.02565) (xy 391.790682 -255.839722) (xy 391.754868 -255.875536)
			(xy 391.708386 -255.973072) (xy 391.84326 -256.107692)
		)
		(stroke
			(width 0)
			(type solid)
		)
		(fill yes)
		(layer "F.Cu")
		(net "M_E_CPU0_SA_CA<6>")
	)
	(gr_poly
		(pts
			(xy 391.944098 -267.886942) (xy 391.979912 -267.850874) (xy 391.793984 -267.664946) (xy 391.75817 -267.701014)
			(xy 391.711942 -267.798296) (xy 391.846562 -267.93317)
		)
		(stroke
			(width 0)
			(type solid)
		)
		(fill yes)
		(layer "F.Cu")
		(net "M_E_CPU0_SA_DQ<29>")
	)
	(gr_poly
		(pts
			(xy 391.947908 -239.694974) (xy 391.91184 -239.65916) (xy 391.814558 -239.612932) (xy 391.679684 -239.747552)
			(xy 391.725912 -239.845088) (xy 391.76198 -239.880902)
		)
		(stroke
			(width 0)
			(type solid)
		)
		(fill yes)
		(layer "F.Cu")
		(net "M_E_CPU0_SB_CB<0>")
	)
	(gr_poly
		(pts
			(xy 391.955274 -230.884476) (xy 391.909046 -230.78694) (xy 391.872978 -230.751126) (xy 391.68705 -230.937054)
			(xy 391.723118 -230.972868) (xy 391.8204 -231.019096)
		)
		(stroke
			(width 0)
			(type solid)
		)
		(fill yes)
		(layer "F.Cu")
		(net "M_E_CPU0_SB_DQ<19>")
	)
	(gr_poly
		(pts
			(xy 391.957306 -274.388072) (xy 391.99312 -274.352258) (xy 391.807192 -274.16633) (xy 391.771378 -274.202144)
			(xy 391.72515 -274.29968) (xy 391.85977 -274.4343)
		)
		(stroke
			(width 0)
			(type solid)
		)
		(fill yes)
		(layer "F.Cu")
		(net "M_E_CPU0_SA_DQ<20>")
	)
	(gr_poly
		(pts
			(xy 391.964418 -231.737916) (xy 391.91819 -231.64038) (xy 391.882122 -231.604566) (xy 391.696448 -231.79024)
			(xy 391.732262 -231.826308) (xy 391.829798 -231.872536)
		)
		(stroke
			(width 0)
			(type solid)
		)
		(fill yes)
		(layer "F.Cu")
		(net "M_E_CPU0_SB_DQ<18>")
	)
	(gr_poly
		(pts
			(xy 391.96645 -273.534632) (xy 392.002518 -273.498818) (xy 391.81659 -273.31289) (xy 391.780522 -273.348704)
			(xy 391.734294 -273.44624) (xy 391.869168 -273.58086)
		)
		(stroke
			(width 0)
			(type solid)
		)
		(fill yes)
		(layer "F.Cu")
		(net "M_E_CPU0_SA_DQ<21>")
	)
	(gr_poly
		(pts
			(xy 391.96772 -262.838184) (xy 392.003788 -262.80237) (xy 391.81786 -262.616442) (xy 391.782046 -262.652256)
			(xy 391.735818 -262.749792) (xy 391.870438 -262.884412)
		)
		(stroke
			(width 0)
			(type solid)
		)
		(fill yes)
		(layer "F.Cu")
		(net "M_E_CPU0_SA_CB<6>")
	)
	(gr_poly
		(pts
			(xy 391.973308 -233.43489) (xy 391.926826 -233.337354) (xy 391.891012 -233.30154) (xy 391.705084 -233.487468)
			(xy 391.741152 -233.523282) (xy 391.838434 -233.56951)
		)
		(stroke
			(width 0)
			(type solid)
		)
		(fill yes)
		(layer "F.Cu")
		(net "M_E_CPU0_SB_DQ<13>")
	)
	(gr_poly
		(pts
			(xy 391.97534 -271.83715) (xy 392.011408 -271.801336) (xy 391.82548 -271.615408) (xy 391.789412 -271.651222)
			(xy 391.743184 -271.748758) (xy 391.878058 -271.883378)
		)
		(stroke
			(width 0)
			(type solid)
		)
		(fill yes)
		(layer "F.Cu")
		(net "M_E_CPU0_SA_DQ<26>")
	)
	(gr_poly
		(pts
			(xy 391.977118 -261.984998) (xy 392.012932 -261.94893) (xy 391.827004 -261.763002) (xy 391.79119 -261.79907)
			(xy 391.744962 -261.896352) (xy 391.879582 -262.031226)
		)
		(stroke
			(width 0)
			(type solid)
		)
		(fill yes)
		(layer "F.Cu")
		(net "M_E_CPU0_SA_CB<7>")
	)
	(gr_poly
		(pts
			(xy 391.97788 -266.58697) (xy 392.024108 -266.489434) (xy 391.889234 -266.354814) (xy 391.791952 -266.401042)
			(xy 391.755884 -266.436856) (xy 391.941812 -266.622784)
		)
		(stroke
			(width 0)
			(type solid)
		)
		(fill yes)
		(layer "F.Cu")
		(net "M_E_CPU0_SA_CB<0>")
	)
	(gr_poly
		(pts
			(xy 391.982452 -234.28833) (xy 391.936224 -234.190794) (xy 391.900156 -234.15498) (xy 391.714228 -234.340908)
			(xy 391.750296 -234.376722) (xy 391.847578 -234.42295)
		)
		(stroke
			(width 0)
			(type solid)
		)
		(fill yes)
		(layer "F.Cu")
		(net "M_E_CPU0_SB_DQ<12>")
	)
	(gr_poly
		(pts
			(xy 391.984484 -270.98371) (xy 392.020552 -270.947896) (xy 391.834624 -270.761968) (xy 391.798556 -270.797782)
			(xy 391.752328 -270.895318) (xy 391.887202 -271.029938)
		)
		(stroke
			(width 0)
			(type solid)
		)
		(fill yes)
		(layer "F.Cu")
		(net "M_E_CPU0_SA_DQ<27>")
	)
	(gr_poly
		(pts
			(xy 391.987024 -265.73353) (xy 392.033252 -265.635994) (xy 391.898632 -265.501374) (xy 391.801096 -265.547602)
			(xy 391.765282 -265.58367) (xy 391.950956 -265.769344)
		)
		(stroke
			(width 0)
			(type solid)
		)
		(fill yes)
		(layer "F.Cu")
		(net "M_E_CPU0_SA_CB<1>")
	)
	(gr_poly
		(pts
			(xy 391.99312 -249.069352) (xy 391.99312 -249.018552) (xy 391.729976 -249.018552) (xy 391.729976 -249.069352)
			(xy 391.766298 -249.170952) (xy 391.956798 -249.170952)
		)
		(stroke
			(width 0)
			(type solid)
		)
		(fill yes)
		(layer "F.Cu")
		(net "M_E_CPU0_SB_CA<0>")
	)
	(gr_poly
		(pts
			(xy 391.99312 -248.764552) (xy 391.99312 -248.713752) (xy 391.729976 -248.713752) (xy 391.729976 -248.764552)
			(xy 391.766298 -248.866152) (xy 391.956798 -248.866152)
		)
		(stroke
			(width 0)
			(type solid)
		)
		(fill yes)
		(layer "F.Cu")
		(net "M_E_CPU0_SB_CA<1>")
	)
	(gr_poly
		(pts
			(xy 391.99312 -248.459752) (xy 391.99312 -248.408952) (xy 391.729976 -248.408952) (xy 391.729976 -248.459752)
			(xy 391.766298 -248.561352) (xy 391.956798 -248.561352)
		)
		(stroke
			(width 0)
			(type solid)
		)
		(fill yes)
		(layer "F.Cu")
		(net "M_E_CPU0_SB_CA<2>")
	)
	(gr_poly
		(pts
			(xy 391.99312 -248.154952) (xy 391.99312 -248.104152) (xy 391.729976 -248.104152) (xy 391.729976 -248.154952)
			(xy 391.766298 -248.256552) (xy 391.956798 -248.256552)
		)
		(stroke
			(width 0)
			(type solid)
		)
		(fill yes)
		(layer "F.Cu")
		(net "M_E_CPU0_SB_CA<3>")
	)
	(gr_poly
		(pts
			(xy 391.99312 -247.850152) (xy 391.99312 -247.799352) (xy 391.729976 -247.799352) (xy 391.729976 -247.850152)
			(xy 391.766298 -247.951752) (xy 391.956798 -247.951752)
		)
		(stroke
			(width 0)
			(type solid)
		)
		(fill yes)
		(layer "F.Cu")
		(net "M_E_CPU0_SB_CA<4>")
	)
	(gr_poly
		(pts
			(xy 391.99312 -247.545352) (xy 391.99312 -247.494552) (xy 391.729976 -247.494552) (xy 391.729976 -247.545352)
			(xy 391.766298 -247.646952) (xy 391.956798 -247.646952)
		)
		(stroke
			(width 0)
			(type solid)
		)
		(fill yes)
		(layer "F.Cu")
		(net "M_E_CPU0_SB_CA<5>")
	)
	(gr_poly
		(pts
			(xy 391.99312 -247.240552) (xy 391.99312 -247.189752) (xy 391.729976 -247.189752) (xy 391.729976 -247.240552)
			(xy 391.766298 -247.342152) (xy 391.956798 -247.342152)
		)
		(stroke
			(width 0)
			(type solid)
		)
		(fill yes)
		(layer "F.Cu")
		(net "M_E_CPU0_SB_CA<6>")
	)
	(gr_poly
		(pts
			(xy 391.99312 -246.935752) (xy 391.99312 -246.884952) (xy 391.729976 -246.884952) (xy 391.729976 -246.935752)
			(xy 391.766298 -247.037352) (xy 391.956798 -247.037352)
		)
		(stroke
			(width 0)
			(type solid)
		)
		(fill yes)
		(layer "F.Cu")
		(net "M_E_CPU0_SB_PAR")
	)
	(gr_poly
		(pts
			(xy 392.007344 -236.85119) (xy 391.961116 -236.753908) (xy 391.925302 -236.71784) (xy 391.739374 -236.903768)
			(xy 391.775188 -236.939582) (xy 391.872724 -236.986064)
		)
		(stroke
			(width 0)
			(type solid)
		)
		(fill yes)
		(layer "F.Cu")
		(net "M_E_CPU0_SB_DQ<9>")
	)
	(gr_poly
		(pts
			(xy 392.007852 -256.416302) (xy 392.05408 -256.31902) (xy 391.91946 -256.184146) (xy 391.821924 -256.230374)
			(xy 391.78611 -256.266442) (xy 391.972038 -256.45237)
		)
		(stroke
			(width 0)
			(type solid)
		)
		(fill yes)
		(layer "F.Cu")
		(net "M_E_CPU0_SA_CA<5>")
	)
	(gr_poly
		(pts
			(xy 392.011154 -268.24178) (xy 392.057382 -268.144498) (xy 391.922762 -268.009624) (xy 391.825226 -268.055852)
			(xy 391.789412 -268.09192) (xy 391.97534 -268.277848)
		)
		(stroke
			(width 0)
			(type solid)
		)
		(fill yes)
		(layer "F.Cu")
		(net "M_E_CPU0_SA_DQ<30>")
	)
	(gr_poly
		(pts
			(xy 392.01598 -227.325174) (xy 392.01598 -227.134674) (xy 391.91438 -227.098606) (xy 391.86358 -227.098606)
			(xy 391.86358 -227.361496) (xy 391.91438 -227.361496)
		)
		(stroke
			(width 0)
			(type solid)
		)
		(fill yes)
		(layer "F.Cu")
		(net "M_E_CPU0_SB_DQ<21>")
	)
	(gr_poly
		(pts
			(xy 392.01598 -226.728274) (xy 392.01598 -226.537774) (xy 391.91438 -226.501706) (xy 391.86358 -226.501706)
			(xy 391.86358 -226.764596) (xy 391.91438 -226.764596)
		)
		(stroke
			(width 0)
			(type solid)
		)
		(fill yes)
		(layer "F.Cu")
		(net "M_E_CPU0_SB_DQ<21>")
	)
	(gr_poly
		(pts
			(xy 392.01598 -226.131374) (xy 392.01598 -225.940874) (xy 391.91438 -225.904806) (xy 391.86358 -225.904806)
			(xy 391.86358 -226.167696) (xy 391.91438 -226.167696)
		)
		(stroke
			(width 0)
			(type solid)
		)
		(fill yes)
		(layer "F.Cu")
		(net "M_E_CPU0_SB_DQ<21>")
	)
	(gr_poly
		(pts
			(xy 392.01598 -225.534474) (xy 392.01598 -225.343974) (xy 391.91438 -225.307906) (xy 391.86358 -225.307906)
			(xy 391.86358 -225.570796) (xy 391.91438 -225.570796)
		)
		(stroke
			(width 0)
			(type solid)
		)
		(fill yes)
		(layer "F.Cu")
		(net "M_E_CPU0_SB_DQ<21>")
	)
	(gr_poly
		(pts
			(xy 392.01598 -224.937574) (xy 392.01598 -224.747074) (xy 391.91438 -224.711006) (xy 391.86358 -224.711006)
			(xy 391.86358 -224.973896) (xy 391.91438 -224.973896)
		)
		(stroke
			(width 0)
			(type solid)
		)
		(fill yes)
		(layer "F.Cu")
		(net "M_E_CPU0_SB_DQ<21>")
	)
	(gr_poly
		(pts
			(xy 392.01598 -224.340674) (xy 392.01598 -224.150174) (xy 391.91438 -224.114106) (xy 391.86358 -224.114106)
			(xy 391.86358 -224.376996) (xy 391.91438 -224.376996)
		)
		(stroke
			(width 0)
			(type solid)
		)
		(fill yes)
		(layer "F.Cu")
		(net "M_E_CPU0_SB_DQ<21>")
	)
	(gr_poly
		(pts
			(xy 392.01598 -223.743774) (xy 392.01598 -223.553274) (xy 391.91438 -223.517206) (xy 391.86358 -223.517206)
			(xy 391.86358 -223.780096) (xy 391.91438 -223.780096)
		)
		(stroke
			(width 0)
			(type solid)
		)
		(fill yes)
		(layer "F.Cu")
		(net "M_E_CPU0_SB_DQ<21>")
	)
	(gr_poly
		(pts
			(xy 392.01598 -223.146874) (xy 392.01598 -222.956374) (xy 391.91438 -222.920306) (xy 391.86358 -222.920306)
			(xy 391.86358 -223.183196) (xy 391.91438 -223.183196)
		)
		(stroke
			(width 0)
			(type solid)
		)
		(fill yes)
		(layer "F.Cu")
		(net "M_E_CPU0_SB_DQ<21>")
	)
	(gr_poly
		(pts
			(xy 392.01598 -222.549974) (xy 392.01598 -222.359474) (xy 391.91438 -222.323406) (xy 391.86358 -222.323406)
			(xy 391.86358 -222.586296) (xy 391.91438 -222.586296)
		)
		(stroke
			(width 0)
			(type solid)
		)
		(fill yes)
		(layer "F.Cu")
		(net "M_E_CPU0_SB_DQ<21>")
	)
	(gr_poly
		(pts
			(xy 392.01598 -221.953074) (xy 392.01598 -221.762574) (xy 391.91438 -221.726506) (xy 391.86358 -221.726506)
			(xy 391.86358 -221.989396) (xy 391.91438 -221.989396)
		)
		(stroke
			(width 0)
			(type solid)
		)
		(fill yes)
		(layer "F.Cu")
		(net "M_E_CPU0_SB_DQ<21>")
	)
	(gr_poly
		(pts
			(xy 392.01598 -221.356174) (xy 392.01598 -221.165674) (xy 391.91438 -221.129606) (xy 391.86358 -221.129606)
			(xy 391.86358 -221.392496) (xy 391.91438 -221.392496)
		)
		(stroke
			(width 0)
			(type solid)
		)
		(fill yes)
		(layer "F.Cu")
		(net "M_E_CPU0_SB_DQ<21>")
	)
	(gr_poly
		(pts
			(xy 392.01598 -220.759274) (xy 392.01598 -220.568774) (xy 391.91438 -220.532706) (xy 391.86358 -220.532706)
			(xy 391.86358 -220.795596) (xy 391.91438 -220.795596)
		)
		(stroke
			(width 0)
			(type solid)
		)
		(fill yes)
		(layer "F.Cu")
		(net "M_E_CPU0_SB_DQ<21>")
	)
	(gr_poly
		(pts
			(xy 392.01598 -220.162374) (xy 392.01598 -219.971874) (xy 391.91438 -219.935806) (xy 391.86358 -219.935806)
			(xy 391.86358 -220.198696) (xy 391.91438 -220.198696)
		)
		(stroke
			(width 0)
			(type solid)
		)
		(fill yes)
		(layer "F.Cu")
		(net "M_E_CPU0_SB_DQ<21>")
	)
	(gr_poly
		(pts
			(xy 392.01598 -219.565474) (xy 392.01598 -219.374974) (xy 391.91438 -219.338906) (xy 391.86358 -219.338906)
			(xy 391.86358 -219.601796) (xy 391.91438 -219.601796)
		)
		(stroke
			(width 0)
			(type solid)
		)
		(fill yes)
		(layer "F.Cu")
		(net "M_E_CPU0_SB_DQ<21>")
	)
	(gr_poly
		(pts
			(xy 392.01598 -218.968574) (xy 392.01598 -218.778074) (xy 391.91438 -218.742006) (xy 391.86358 -218.742006)
			(xy 391.86358 -219.004896) (xy 391.91438 -219.004896)
		)
		(stroke
			(width 0)
			(type solid)
		)
		(fill yes)
		(layer "F.Cu")
		(net "M_E_CPU0_SB_DQ<21>")
	)
	(gr_poly
		(pts
			(xy 392.01598 -218.371674) (xy 392.01598 -218.181174) (xy 391.91438 -218.145106) (xy 391.86358 -218.145106)
			(xy 391.86358 -218.407996) (xy 391.91438 -218.407996)
		)
		(stroke
			(width 0)
			(type solid)
		)
		(fill yes)
		(layer "F.Cu")
		(net "M_E_CPU0_SB_DQ<21>")
	)
	(gr_poly
		(pts
			(xy 392.01598 -217.774774) (xy 392.01598 -217.584274) (xy 391.91438 -217.548206) (xy 391.86358 -217.548206)
			(xy 391.86358 -217.811096) (xy 391.91438 -217.811096)
		)
		(stroke
			(width 0)
			(type solid)
		)
		(fill yes)
		(layer "F.Cu")
		(net "M_E_CPU0_SB_DQ<21>")
	)
	(gr_poly
		(pts
			(xy 392.01598 -217.177874) (xy 392.01598 -216.987374) (xy 391.91438 -216.951306) (xy 391.86358 -216.951306)
			(xy 391.86358 -217.214196) (xy 391.91438 -217.214196)
		)
		(stroke
			(width 0)
			(type solid)
		)
		(fill yes)
		(layer "F.Cu")
		(net "M_E_CPU0_SB_DQ<21>")
	)
	(gr_poly
		(pts
			(xy 392.01598 -216.580974) (xy 392.01598 -216.390474) (xy 391.91438 -216.354406) (xy 391.86358 -216.354406)
			(xy 391.86358 -216.617296) (xy 391.91438 -216.617296)
		)
		(stroke
			(width 0)
			(type solid)
		)
		(fill yes)
		(layer "F.Cu")
		(net "M_E_CPU0_SB_DQ<21>")
	)
	(gr_poly
		(pts
			(xy 392.01598 -215.984074) (xy 392.01598 -215.793574) (xy 391.91438 -215.757506) (xy 391.86358 -215.757506)
			(xy 391.86358 -216.020396) (xy 391.91438 -216.020396)
		)
		(stroke
			(width 0)
			(type solid)
		)
		(fill yes)
		(layer "F.Cu")
		(net "M_E_CPU0_SB_DQ<21>")
	)
	(gr_poly
		(pts
			(xy 392.016234 -238.548418) (xy 391.970006 -238.450882) (xy 391.933938 -238.415068) (xy 391.74801 -238.600996)
			(xy 391.784078 -238.63681) (xy 391.88136 -238.683038)
		)
		(stroke
			(width 0)
			(type solid)
		)
		(fill yes)
		(layer "F.Cu")
		(net "M_E_CPU0_SB_CB<3>")
	)
	(gr_poly
		(pts
			(xy 392.016996 -255.563116) (xy 392.063224 -255.46558) (xy 391.928604 -255.33096) (xy 391.831322 -255.377188)
			(xy 391.795254 -255.413002) (xy 391.981182 -255.59893)
		)
		(stroke
			(width 0)
			(type solid)
		)
		(fill yes)
		(layer "F.Cu")
		(net "M_E_CPU0_SA_PAR")
	)
	(gr_poly
		(pts
			(xy 392.017504 -237.705392) (xy 391.971022 -237.607856) (xy 391.935208 -237.572042) (xy 391.74928 -237.75797)
			(xy 391.785348 -237.793784) (xy 391.88263 -237.840012)
		)
		(stroke
			(width 0)
			(type solid)
		)
		(fill yes)
		(layer "F.Cu")
		(net "M_E_CPU0_SB_DQ<8>")
	)
	(gr_poly
		(pts
			(xy 392.020552 -267.388086) (xy 392.06678 -267.290804) (xy 391.93216 -267.156184) (xy 391.834624 -267.202412)
			(xy 391.79881 -267.238226) (xy 391.984738 -267.424154)
		)
		(stroke
			(width 0)
			(type solid)
		)
		(fill yes)
		(layer "F.Cu")
		(net "M_E_CPU0_SA_DQ<31>")
	)
	(gr_poly
		(pts
			(xy 392.025378 -239.401604) (xy 391.97915 -239.304322) (xy 391.943336 -239.268254) (xy 391.757408 -239.454182)
			(xy 391.793222 -239.49025) (xy 391.890758 -239.536478)
		)
		(stroke
			(width 0)
			(type solid)
		)
		(fill yes)
		(layer "F.Cu")
		(net "M_E_CPU0_SB_CB<2>")
	)
	(gr_poly
		(pts
			(xy 392.03376 -273.88947) (xy 392.079988 -273.792188) (xy 391.945368 -273.657314) (xy 391.847832 -273.703542)
			(xy 391.812018 -273.73961) (xy 391.997946 -273.925538)
		)
		(stroke
			(width 0)
			(type solid)
		)
		(fill yes)
		(layer "F.Cu")
		(net "M_E_CPU0_SA_DQ<22>")
	)
	(gr_poly
		(pts
			(xy 392.03503 -263.193022) (xy 392.081258 -263.09574) (xy 391.946638 -262.960866) (xy 391.849102 -263.007094)
			(xy 391.813288 -263.043162) (xy 391.999216 -263.22909)
		)
		(stroke
			(width 0)
			(type solid)
		)
		(fill yes)
		(layer "F.Cu")
		(net "M_E_CPU0_SA_CB<4>")
	)
	(gr_poly
		(pts
			(xy 392.04265 -272.191988) (xy 392.088878 -272.094706) (xy 391.954258 -271.959832) (xy 391.856722 -272.00606)
			(xy 391.820908 -272.042128) (xy 392.006836 -272.228056)
		)
		(stroke
			(width 0)
			(type solid)
		)
		(fill yes)
		(layer "F.Cu")
		(net "M_E_CPU0_SA_DQ<24>")
	)
	(gr_poly
		(pts
			(xy 392.042904 -273.03603) (xy 392.089386 -272.938494) (xy 391.954512 -272.803874) (xy 391.85723 -272.850102)
			(xy 391.821162 -272.885916) (xy 392.00709 -273.071844)
		)
		(stroke
			(width 0)
			(type solid)
		)
		(fill yes)
		(layer "F.Cu")
		(net "M_E_CPU0_SA_DQ<23>")
	)
	(gr_poly
		(pts
			(xy 392.044174 -262.339836) (xy 392.090656 -262.2423) (xy 391.955782 -262.10768) (xy 391.8585 -262.153908)
			(xy 391.822432 -262.189722) (xy 392.00836 -262.37565)
		)
		(stroke
			(width 0)
			(type solid)
		)
		(fill yes)
		(layer "F.Cu")
		(net "M_E_CPU0_SA_CB<5>")
	)
	(gr_poly
		(pts
			(xy 392.051794 -271.338548) (xy 392.098022 -271.241266) (xy 391.963402 -271.106392) (xy 391.865866 -271.15262)
			(xy 391.830052 -271.188688) (xy 392.01598 -271.374616)
		)
		(stroke
			(width 0)
			(type solid)
		)
		(fill yes)
		(layer "F.Cu")
		(net "M_E_CPU0_SA_DQ<25>")
	)
	(gr_poly
		(pts
			(xy 392.057128 -227.978716) (xy 392.021314 -227.942648) (xy 391.923778 -227.89642) (xy 391.789158 -228.031294)
			(xy 391.835386 -228.128576) (xy 391.8712 -228.164644)
		)
		(stroke
			(width 0)
			(type solid)
		)
		(fill yes)
		(layer "F.Cu")
		(net "M_E_CPU0_SB_DQ<22>")
	)
	(gr_poly
		(pts
			(xy 392.084052 -230.540052) (xy 392.048238 -230.504238) (xy 391.950702 -230.45801) (xy 391.816082 -230.59263)
			(xy 391.86231 -230.689912) (xy 391.898124 -230.72598)
		)
		(stroke
			(width 0)
			(type solid)
		)
		(fill yes)
		(layer "F.Cu")
		(net "M_E_CPU0_SB_DQ<19>")
	)
	(gr_poly
		(pts
			(xy 392.091418 -289.175698) (xy 392.091418 -288.985198) (xy 391.989818 -288.94913) (xy 391.939018 -288.94913)
			(xy 391.939018 -289.21202) (xy 391.989818 -289.21202)
		)
		(stroke
			(width 0)
			(type solid)
		)
		(fill yes)
		(layer "F.Cu")
		(net "M_E_CPU0_SA_DQ<19>")
	)
	(gr_poly
		(pts
			(xy 392.091418 -288.578798) (xy 392.091418 -288.388298) (xy 391.989818 -288.35223) (xy 391.939018 -288.35223)
			(xy 391.939018 -288.61512) (xy 391.989818 -288.61512)
		)
		(stroke
			(width 0)
			(type solid)
		)
		(fill yes)
		(layer "F.Cu")
		(net "M_E_CPU0_SA_DQ<19>")
	)
	(gr_poly
		(pts
			(xy 392.091418 -287.981898) (xy 392.091418 -287.791398) (xy 391.989818 -287.75533) (xy 391.939018 -287.75533)
			(xy 391.939018 -288.01822) (xy 391.989818 -288.01822)
		)
		(stroke
			(width 0)
			(type solid)
		)
		(fill yes)
		(layer "F.Cu")
		(net "M_E_CPU0_SA_DQ<19>")
	)
	(gr_poly
		(pts
			(xy 392.091418 -287.384998) (xy 392.091418 -287.194498) (xy 391.989818 -287.15843) (xy 391.939018 -287.15843)
			(xy 391.939018 -287.42132) (xy 391.989818 -287.42132)
		)
		(stroke
			(width 0)
			(type solid)
		)
		(fill yes)
		(layer "F.Cu")
		(net "M_E_CPU0_SA_DQ<19>")
	)
	(gr_poly
		(pts
			(xy 392.091418 -286.788098) (xy 392.091418 -286.597598) (xy 391.989818 -286.56153) (xy 391.939018 -286.56153)
			(xy 391.939018 -286.82442) (xy 391.989818 -286.82442)
		)
		(stroke
			(width 0)
			(type solid)
		)
		(fill yes)
		(layer "F.Cu")
		(net "M_E_CPU0_SA_DQ<19>")
	)
	(gr_poly
		(pts
			(xy 392.091418 -286.191198) (xy 392.091418 -286.000698) (xy 391.989818 -285.96463) (xy 391.939018 -285.96463)
			(xy 391.939018 -286.22752) (xy 391.989818 -286.22752)
		)
		(stroke
			(width 0)
			(type solid)
		)
		(fill yes)
		(layer "F.Cu")
		(net "M_E_CPU0_SA_DQ<19>")
	)
	(gr_poly
		(pts
			(xy 392.091418 -285.594298) (xy 392.091418 -285.403798) (xy 391.989818 -285.36773) (xy 391.939018 -285.36773)
			(xy 391.939018 -285.63062) (xy 391.989818 -285.63062)
		)
		(stroke
			(width 0)
			(type solid)
		)
		(fill yes)
		(layer "F.Cu")
		(net "M_E_CPU0_SA_DQ<19>")
	)
	(gr_poly
		(pts
			(xy 392.091418 -284.997398) (xy 392.091418 -284.806898) (xy 391.989818 -284.77083) (xy 391.939018 -284.77083)
			(xy 391.939018 -285.03372) (xy 391.989818 -285.03372)
		)
		(stroke
			(width 0)
			(type solid)
		)
		(fill yes)
		(layer "F.Cu")
		(net "M_E_CPU0_SA_DQ<19>")
	)
	(gr_poly
		(pts
			(xy 392.091418 -284.400498) (xy 392.091418 -284.209998) (xy 391.989818 -284.17393) (xy 391.939018 -284.17393)
			(xy 391.939018 -284.43682) (xy 391.989818 -284.43682)
		)
		(stroke
			(width 0)
			(type solid)
		)
		(fill yes)
		(layer "F.Cu")
		(net "M_E_CPU0_SA_DQ<19>")
	)
	(gr_poly
		(pts
			(xy 392.091418 -283.803598) (xy 392.091418 -283.613098) (xy 391.989818 -283.57703) (xy 391.939018 -283.57703)
			(xy 391.939018 -283.83992) (xy 391.989818 -283.83992)
		)
		(stroke
			(width 0)
			(type solid)
		)
		(fill yes)
		(layer "F.Cu")
		(net "M_E_CPU0_SA_DQ<19>")
	)
	(gr_poly
		(pts
			(xy 392.091418 -283.206698) (xy 392.091418 -283.016198) (xy 391.989818 -282.98013) (xy 391.939018 -282.98013)
			(xy 391.939018 -283.24302) (xy 391.989818 -283.24302)
		)
		(stroke
			(width 0)
			(type solid)
		)
		(fill yes)
		(layer "F.Cu")
		(net "M_E_CPU0_SA_DQ<19>")
	)
	(gr_poly
		(pts
			(xy 392.091418 -282.609798) (xy 392.091418 -282.419298) (xy 391.989818 -282.38323) (xy 391.939018 -282.38323)
			(xy 391.939018 -282.64612) (xy 391.989818 -282.64612)
		)
		(stroke
			(width 0)
			(type solid)
		)
		(fill yes)
		(layer "F.Cu")
		(net "M_E_CPU0_SA_DQ<19>")
	)
	(gr_poly
		(pts
			(xy 392.091418 -282.012898) (xy 392.091418 -281.822398) (xy 391.989818 -281.78633) (xy 391.939018 -281.78633)
			(xy 391.939018 -282.04922) (xy 391.989818 -282.04922)
		)
		(stroke
			(width 0)
			(type solid)
		)
		(fill yes)
		(layer "F.Cu")
		(net "M_E_CPU0_SA_DQ<19>")
	)
	(gr_poly
		(pts
			(xy 392.091418 -281.415998) (xy 392.091418 -281.225498) (xy 391.989818 -281.18943) (xy 391.939018 -281.18943)
			(xy 391.939018 -281.45232) (xy 391.989818 -281.45232)
		)
		(stroke
			(width 0)
			(type solid)
		)
		(fill yes)
		(layer "F.Cu")
		(net "M_E_CPU0_SA_DQ<19>")
	)
	(gr_poly
		(pts
			(xy 392.093196 -231.393492) (xy 392.057382 -231.357424) (xy 391.959846 -231.311196) (xy 391.825226 -231.44607)
			(xy 391.871454 -231.543352) (xy 391.907268 -231.57942)
		)
		(stroke
			(width 0)
			(type solid)
		)
		(fill yes)
		(layer "F.Cu")
		(net "M_E_CPU0_SB_DQ<18>")
	)
	(gr_poly
		(pts
			(xy 392.102086 -233.090466) (xy 392.066018 -233.054652) (xy 391.968736 -233.008424) (xy 391.834116 -233.143044)
			(xy 391.880344 -233.24058) (xy 391.916158 -233.276394)
		)
		(stroke
			(width 0)
			(type solid)
		)
		(fill yes)
		(layer "F.Cu")
		(net "M_E_CPU0_SB_DQ<13>")
	)
	(gr_poly
		(pts
			(xy 392.11123 -233.943906) (xy 392.075416 -233.907838) (xy 391.97788 -233.86161) (xy 391.84326 -233.996484)
			(xy 391.889488 -234.093766) (xy 391.925302 -234.129834)
		)
		(stroke
			(width 0)
			(type solid)
		)
		(fill yes)
		(layer "F.Cu")
		(net "M_E_CPU0_SB_DQ<12>")
	)
	(gr_poly
		(pts
			(xy 392.117072 -266.869672) (xy 392.152886 -266.833858) (xy 391.966958 -266.64793) (xy 391.931144 -266.683998)
			(xy 391.884916 -266.78128) (xy 392.019536 -266.916154)
		)
		(stroke
			(width 0)
			(type solid)
		)
		(fill yes)
		(layer "F.Cu")
		(net "M_E_CPU0_SA_CB<0>")
	)
	(gr_poly
		(pts
			(xy 392.120882 -242.598956) (xy 392.08456 -242.497356) (xy 391.89406 -242.497356) (xy 391.857992 -242.598956)
			(xy 391.857992 -242.649756) (xy 392.120882 -242.649756)
		)
		(stroke
			(width 0)
			(type solid)
		)
		(fill yes)
		(layer "F.Cu")
		(net "M_E_CPU0_SB_CB<4>")
	)
	(gr_poly
		(pts
			(xy 392.120882 -242.294156) (xy 392.08456 -242.192556) (xy 391.89406 -242.192556) (xy 391.857992 -242.294156)
			(xy 391.857992 -242.344956) (xy 392.120882 -242.344956)
		)
		(stroke
			(width 0)
			(type solid)
		)
		(fill yes)
		(layer "F.Cu")
		(net "M_E_CPU0_SB_CB<6>")
	)
	(gr_poly
		(pts
			(xy 392.126216 -266.016486) (xy 392.16203 -265.980418) (xy 391.976102 -265.79449) (xy 391.940288 -265.830558)
			(xy 391.89406 -265.92784) (xy 392.02868 -266.062714)
		)
		(stroke
			(width 0)
			(type solid)
		)
		(fill yes)
		(layer "F.Cu")
		(net "M_E_CPU0_SA_CB<1>")
	)
	(gr_poly
		(pts
			(xy 392.136376 -236.506766) (xy 392.100308 -236.470952) (xy 392.003026 -236.424724) (xy 391.868152 -236.559344)
			(xy 391.91438 -236.65688) (xy 391.950448 -236.692694)
		)
		(stroke
			(width 0)
			(type solid)
		)
		(fill yes)
		(layer "F.Cu")
		(net "M_E_CPU0_SB_DQ<9>")
	)
	(gr_poly
		(pts
			(xy 392.143996 -228.538786) (xy 392.097768 -228.44125) (xy 392.0617 -228.405436) (xy 391.875772 -228.591364)
			(xy 391.91184 -228.627178) (xy 392.009376 -228.673406)
		)
		(stroke
			(width 0)
			(type solid)
		)
		(fill yes)
		(layer "F.Cu")
		(net "M_E_CPU0_SB_DQ<20>")
	)
	(gr_poly
		(pts
			(xy 392.145012 -238.203994) (xy 392.109198 -238.167926) (xy 392.011662 -238.121698) (xy 391.877042 -238.256572)
			(xy 391.92327 -238.353854) (xy 391.959084 -238.389922)
		)
		(stroke
			(width 0)
			(type solid)
		)
		(fill yes)
		(layer "F.Cu")
		(net "M_E_CPU0_SB_CB<3>")
	)
	(gr_poly
		(pts
			(xy 392.146282 -237.360968) (xy 392.110214 -237.325154) (xy 392.012932 -237.278926) (xy 391.878312 -237.413546)
			(xy 391.92454 -237.511082) (xy 391.960354 -237.546896)
		)
		(stroke
			(width 0)
			(type solid)
		)
		(fill yes)
		(layer "F.Cu")
		(net "M_E_CPU0_SB_DQ<8>")
	)
	(gr_poly
		(pts
			(xy 392.150346 -268.524736) (xy 392.18616 -268.488668) (xy 392.000486 -268.302994) (xy 391.964418 -268.338808)
			(xy 391.91819 -268.436344) (xy 392.05281 -268.570964)
		)
		(stroke
			(width 0)
			(type solid)
		)
		(fill yes)
		(layer "F.Cu")
		(net "M_E_CPU0_SA_DQ<30>")
	)
	(gr_poly
		(pts
			(xy 392.154156 -239.057434) (xy 392.118342 -239.021366) (xy 392.020806 -238.975138) (xy 391.886186 -239.109758)
			(xy 391.932414 -239.207294) (xy 391.968482 -239.243108)
		)
		(stroke
			(width 0)
			(type solid)
		)
		(fill yes)
		(layer "F.Cu")
		(net "M_E_CPU0_SB_CB<2>")
	)
	(gr_poly
		(pts
			(xy 392.156188 -255.845818) (xy 392.192256 -255.810004) (xy 392.006328 -255.624076) (xy 391.970514 -255.65989)
			(xy 391.924032 -255.757426) (xy 392.058906 -255.892046)
		)
		(stroke
			(width 0)
			(type solid)
		)
		(fill yes)
		(layer "F.Cu")
		(net "M_E_CPU0_SA_PAR")
	)
	(gr_poly
		(pts
			(xy 392.159744 -267.671042) (xy 392.195812 -267.635228) (xy 392.009884 -267.4493) (xy 391.973816 -267.485114)
			(xy 391.927588 -267.58265) (xy 392.062462 -267.71727)
		)
		(stroke
			(width 0)
			(type solid)
		)
		(fill yes)
		(layer "F.Cu")
		(net "M_E_CPU0_SA_DQ<31>")
	)
	(gr_poly
		(pts
			(xy 392.16838 -227.397056) (xy 392.11758 -227.397056) (xy 392.01598 -227.433378) (xy 392.01598 -227.623878)
			(xy 392.11758 -227.659946) (xy 392.16838 -227.659946)
		)
		(stroke
			(width 0)
			(type solid)
		)
		(fill yes)
		(layer "F.Cu")
		(net "M_E_CPU0_SB_DQ<22>")
	)
	(gr_poly
		(pts
			(xy 392.16838 -226.800156) (xy 392.11758 -226.800156) (xy 392.01598 -226.836478) (xy 392.01598 -227.026978)
			(xy 392.11758 -227.063046) (xy 392.16838 -227.063046)
		)
		(stroke
			(width 0)
			(type solid)
		)
		(fill yes)
		(layer "F.Cu")
		(net "M_E_CPU0_SB_DQ<22>")
	)
	(gr_poly
		(pts
			(xy 392.16838 -226.203256) (xy 392.11758 -226.203256) (xy 392.01598 -226.239578) (xy 392.01598 -226.430078)
			(xy 392.11758 -226.466146) (xy 392.16838 -226.466146)
		)
		(stroke
			(width 0)
			(type solid)
		)
		(fill yes)
		(layer "F.Cu")
		(net "M_E_CPU0_SB_DQ<22>")
	)
	(gr_poly
		(pts
			(xy 392.16838 -225.606356) (xy 392.11758 -225.606356) (xy 392.01598 -225.642678) (xy 392.01598 -225.833178)
			(xy 392.11758 -225.869246) (xy 392.16838 -225.869246)
		)
		(stroke
			(width 0)
			(type solid)
		)
		(fill yes)
		(layer "F.Cu")
		(net "M_E_CPU0_SB_DQ<22>")
	)
	(gr_poly
		(pts
			(xy 392.16838 -225.009456) (xy 392.11758 -225.009456) (xy 392.01598 -225.045778) (xy 392.01598 -225.236278)
			(xy 392.11758 -225.272346) (xy 392.16838 -225.272346)
		)
		(stroke
			(width 0)
			(type solid)
		)
		(fill yes)
		(layer "F.Cu")
		(net "M_E_CPU0_SB_DQ<22>")
	)
	(gr_poly
		(pts
			(xy 392.16838 -224.412556) (xy 392.11758 -224.412556) (xy 392.01598 -224.448878) (xy 392.01598 -224.639378)
			(xy 392.11758 -224.675446) (xy 392.16838 -224.675446)
		)
		(stroke
			(width 0)
			(type solid)
		)
		(fill yes)
		(layer "F.Cu")
		(net "M_E_CPU0_SB_DQ<22>")
	)
	(gr_poly
		(pts
			(xy 392.16838 -223.815656) (xy 392.11758 -223.815656) (xy 392.01598 -223.851978) (xy 392.01598 -224.042478)
			(xy 392.11758 -224.078546) (xy 392.16838 -224.078546)
		)
		(stroke
			(width 0)
			(type solid)
		)
		(fill yes)
		(layer "F.Cu")
		(net "M_E_CPU0_SB_DQ<22>")
	)
	(gr_poly
		(pts
			(xy 392.16838 -223.218756) (xy 392.11758 -223.218756) (xy 392.01598 -223.255078) (xy 392.01598 -223.445578)
			(xy 392.11758 -223.481646) (xy 392.16838 -223.481646)
		)
		(stroke
			(width 0)
			(type solid)
		)
		(fill yes)
		(layer "F.Cu")
		(net "M_E_CPU0_SB_DQ<22>")
	)
	(gr_poly
		(pts
			(xy 392.16838 -222.621856) (xy 392.11758 -222.621856) (xy 392.01598 -222.658178) (xy 392.01598 -222.848678)
			(xy 392.11758 -222.884746) (xy 392.16838 -222.884746)
		)
		(stroke
			(width 0)
			(type solid)
		)
		(fill yes)
		(layer "F.Cu")
		(net "M_E_CPU0_SB_DQ<22>")
	)
	(gr_poly
		(pts
			(xy 392.16838 -222.024956) (xy 392.11758 -222.024956) (xy 392.01598 -222.061278) (xy 392.01598 -222.251778)
			(xy 392.11758 -222.287846) (xy 392.16838 -222.287846)
		)
		(stroke
			(width 0)
			(type solid)
		)
		(fill yes)
		(layer "F.Cu")
		(net "M_E_CPU0_SB_DQ<22>")
	)
	(gr_poly
		(pts
			(xy 392.16838 -221.428056) (xy 392.11758 -221.428056) (xy 392.01598 -221.464378) (xy 392.01598 -221.654878)
			(xy 392.11758 -221.690946) (xy 392.16838 -221.690946)
		)
		(stroke
			(width 0)
			(type solid)
		)
		(fill yes)
		(layer "F.Cu")
		(net "M_E_CPU0_SB_DQ<22>")
	)
	(gr_poly
		(pts
			(xy 392.16838 -220.831156) (xy 392.11758 -220.831156) (xy 392.01598 -220.867478) (xy 392.01598 -221.057978)
			(xy 392.11758 -221.094046) (xy 392.16838 -221.094046)
		)
		(stroke
			(width 0)
			(type solid)
		)
		(fill yes)
		(layer "F.Cu")
		(net "M_E_CPU0_SB_DQ<22>")
	)
	(gr_poly
		(pts
			(xy 392.16838 -220.234256) (xy 392.11758 -220.234256) (xy 392.01598 -220.270578) (xy 392.01598 -220.461078)
			(xy 392.11758 -220.497146) (xy 392.16838 -220.497146)
		)
		(stroke
			(width 0)
			(type solid)
		)
		(fill yes)
		(layer "F.Cu")
		(net "M_E_CPU0_SB_DQ<22>")
	)
	(gr_poly
		(pts
			(xy 392.16838 -219.637356) (xy 392.11758 -219.637356) (xy 392.01598 -219.673678) (xy 392.01598 -219.864178)
			(xy 392.11758 -219.900246) (xy 392.16838 -219.900246)
		)
		(stroke
			(width 0)
			(type solid)
		)
		(fill yes)
		(layer "F.Cu")
		(net "M_E_CPU0_SB_DQ<22>")
	)
	(gr_poly
		(pts
			(xy 392.16838 -219.040456) (xy 392.11758 -219.040456) (xy 392.01598 -219.076778) (xy 392.01598 -219.267278)
			(xy 392.11758 -219.303346) (xy 392.16838 -219.303346)
		)
		(stroke
			(width 0)
			(type solid)
		)
		(fill yes)
		(layer "F.Cu")
		(net "M_E_CPU0_SB_DQ<22>")
	)
	(gr_poly
		(pts
			(xy 392.16838 -218.443556) (xy 392.11758 -218.443556) (xy 392.01598 -218.479878) (xy 392.01598 -218.670378)
			(xy 392.11758 -218.706446) (xy 392.16838 -218.706446)
		)
		(stroke
			(width 0)
			(type solid)
		)
		(fill yes)
		(layer "F.Cu")
		(net "M_E_CPU0_SB_DQ<22>")
	)
	(gr_poly
		(pts
			(xy 392.16838 -217.846656) (xy 392.11758 -217.846656) (xy 392.01598 -217.882978) (xy 392.01598 -218.073478)
			(xy 392.11758 -218.109546) (xy 392.16838 -218.109546)
		)
		(stroke
			(width 0)
			(type solid)
		)
		(fill yes)
		(layer "F.Cu")
		(net "M_E_CPU0_SB_DQ<22>")
	)
	(gr_poly
		(pts
			(xy 392.16838 -217.249756) (xy 392.11758 -217.249756) (xy 392.01598 -217.286078) (xy 392.01598 -217.476578)
			(xy 392.11758 -217.512646) (xy 392.16838 -217.512646)
		)
		(stroke
			(width 0)
			(type solid)
		)
		(fill yes)
		(layer "F.Cu")
		(net "M_E_CPU0_SB_DQ<22>")
	)
	(gr_poly
		(pts
			(xy 392.16838 -216.652856) (xy 392.11758 -216.652856) (xy 392.01598 -216.689178) (xy 392.01598 -216.879678)
			(xy 392.11758 -216.915746) (xy 392.16838 -216.915746)
		)
		(stroke
			(width 0)
			(type solid)
		)
		(fill yes)
		(layer "F.Cu")
		(net "M_E_CPU0_SB_DQ<22>")
	)
	(gr_poly
		(pts
			(xy 392.16838 -216.055956) (xy 392.11758 -216.055956) (xy 392.01598 -216.092278) (xy 392.01598 -216.282778)
			(xy 392.11758 -216.318846) (xy 392.16838 -216.318846)
		)
		(stroke
			(width 0)
			(type solid)
		)
		(fill yes)
		(layer "F.Cu")
		(net "M_E_CPU0_SB_DQ<22>")
	)
	(gr_poly
		(pts
			(xy 392.17092 -231.100122) (xy 392.124692 -231.002586) (xy 392.088624 -230.966772) (xy 391.902696 -231.1527)
			(xy 391.938764 -231.188514) (xy 392.036046 -231.234742)
		)
		(stroke
			(width 0)
			(type solid)
		)
		(fill yes)
		(layer "F.Cu")
		(net "M_E_CPU0_SB_DQ<17>")
	)
	(gr_poly
		(pts
			(xy 392.172952 -274.172426) (xy 392.208766 -274.136358) (xy 392.023092 -273.950684) (xy 391.987024 -273.986498)
			(xy 391.940796 -274.084034) (xy 392.075416 -274.218654)
		)
		(stroke
			(width 0)
			(type solid)
		)
		(fill yes)
		(layer "F.Cu")
		(net "M_E_CPU0_SA_DQ<22>")
	)
	(gr_poly
		(pts
			(xy 392.174222 -263.475978) (xy 392.21029 -263.440164) (xy 392.024362 -263.254236) (xy 391.988294 -263.29005)
			(xy 391.942066 -263.387586) (xy 392.07694 -263.522206)
		)
		(stroke
			(width 0)
			(type solid)
		)
		(fill yes)
		(layer "F.Cu")
		(net "M_E_CPU0_SA_CB<4>")
	)
	(gr_poly
		(pts
			(xy 392.179556 -232.797096) (xy 392.133328 -232.699814) (xy 392.097514 -232.663746) (xy 391.911586 -232.849674)
			(xy 391.9474 -232.885742) (xy 392.044936 -232.93197)
		)
		(stroke
			(width 0)
			(type solid)
		)
		(fill yes)
		(layer "F.Cu")
		(net "M_E_CPU0_SB_DQ<15>")
	)
	(gr_poly
		(pts
			(xy 392.180064 -231.953562) (xy 392.133836 -231.856026) (xy 392.097768 -231.820212) (xy 391.912094 -232.005886)
			(xy 391.947908 -232.041954) (xy 392.045444 -232.088182)
		)
		(stroke
			(width 0)
			(type solid)
		)
		(fill yes)
		(layer "F.Cu")
		(net "M_E_CPU0_SB_DQ<16>")
	)
	(gr_poly
		(pts
			(xy 392.181842 -272.474944) (xy 392.217656 -272.438876) (xy 392.031982 -272.253202) (xy 391.995914 -272.289016)
			(xy 391.949686 -272.386552) (xy 392.084306 -272.521172)
		)
		(stroke
			(width 0)
			(type solid)
		)
		(fill yes)
		(layer "F.Cu")
		(net "M_E_CPU0_SA_DQ<24>")
	)
	(gr_poly
		(pts
			(xy 392.18235 -273.318732) (xy 392.218164 -273.282918) (xy 392.032236 -273.09699) (xy 391.996422 -273.132804)
			(xy 391.950194 -273.23034) (xy 392.084814 -273.36496)
		)
		(stroke
			(width 0)
			(type solid)
		)
		(fill yes)
		(layer "F.Cu")
		(net "M_E_CPU0_SA_DQ<23>")
	)
	(gr_poly
		(pts
			(xy 392.183366 -262.622538) (xy 392.219434 -262.586724) (xy 392.033506 -262.400796) (xy 391.997692 -262.43661)
			(xy 391.951464 -262.534146) (xy 392.086084 -262.668766)
		)
		(stroke
			(width 0)
			(type solid)
		)
		(fill yes)
		(layer "F.Cu")
		(net "M_E_CPU0_SA_CB<5>")
	)
	(gr_poly
		(pts
			(xy 392.188954 -233.650536) (xy 392.142472 -233.553) (xy 392.106658 -233.517186) (xy 391.92073 -233.703114)
			(xy 391.956798 -233.738928) (xy 392.05408 -233.785156)
		)
		(stroke
			(width 0)
			(type solid)
		)
		(fill yes)
		(layer "F.Cu")
		(net "M_E_CPU0_SB_DQ<14>")
	)
	(gr_poly
		(pts
			(xy 392.190986 -271.621504) (xy 392.2268 -271.585436) (xy 392.041126 -271.399762) (xy 392.005058 -271.435576)
			(xy 391.95883 -271.533112) (xy 392.09345 -271.667732)
		)
		(stroke
			(width 0)
			(type solid)
		)
		(fill yes)
		(layer "F.Cu")
		(net "M_E_CPU0_SA_DQ<25>")
	)
	(gr_poly
		(pts
			(xy 392.193526 -266.371324) (xy 392.239754 -266.273788) (xy 392.10488 -266.139168) (xy 392.007598 -266.185396)
			(xy 391.97153 -266.22121) (xy 392.157458 -266.407138)
		)
		(stroke
			(width 0)
			(type solid)
		)
		(fill yes)
		(layer "F.Cu")
		(net "M_E_CPU0_SA_CB<2>")
	)
	(gr_poly
		(pts
			(xy 392.20267 -265.517884) (xy 392.248898 -265.420348) (xy 392.114278 -265.285728) (xy 392.016742 -265.331956)
			(xy 391.980928 -265.368024) (xy 392.166602 -265.553698)
		)
		(stroke
			(width 0)
			(type solid)
		)
		(fill yes)
		(layer "F.Cu")
		(net "M_E_CPU0_SA_CB<3>")
	)
	(gr_poly
		(pts
			(xy 392.213592 -236.213396) (xy 392.167364 -236.116114) (xy 392.13155 -236.080046) (xy 391.945622 -236.265974)
			(xy 391.981436 -236.301788) (xy 392.078972 -236.348016)
		)
		(stroke
			(width 0)
			(type solid)
		)
		(fill yes)
		(layer "F.Cu")
		(net "M_E_CPU0_SB_DQ<11>")
	)
	(gr_poly
		(pts
			(xy 392.217656 -268.879574) (xy 392.263884 -268.782038) (xy 392.12901 -268.647418) (xy 392.031728 -268.693646)
			(xy 391.99566 -268.72946) (xy 392.181588 -268.915388)
		)
		(stroke
			(width 0)
			(type solid)
		)
		(fill yes)
		(layer "F.Cu")
		(net "M_E_CPU0_SA_DQ<28>")
	)
	(gr_poly
		(pts
			(xy 392.223498 -256.200656) (xy 392.269726 -256.103374) (xy 392.135106 -255.9685) (xy 392.03757 -256.014728)
			(xy 392.001756 -256.050796) (xy 392.187684 -256.236724)
		)
		(stroke
			(width 0)
			(type solid)
		)
		(fill yes)
		(layer "F.Cu")
		(net "M_E_CPU0_SA_CA<6>")
	)
	(gr_poly
		(pts
			(xy 392.223752 -237.067598) (xy 392.177524 -236.970062) (xy 392.141456 -236.934248) (xy 391.955528 -237.120176)
			(xy 391.991596 -237.15599) (xy 392.088878 -237.202218)
		)
		(stroke
			(width 0)
			(type solid)
		)
		(fill yes)
		(layer "F.Cu")
		(net "M_E_CPU0_SB_DQ<10>")
	)
	(gr_poly
		(pts
			(xy 392.2268 -268.026134) (xy 392.273282 -267.928598) (xy 392.138408 -267.793978) (xy 392.041126 -267.840206)
			(xy 392.005058 -267.87602) (xy 392.190986 -268.061948)
		)
		(stroke
			(width 0)
			(type solid)
		)
		(fill yes)
		(layer "F.Cu")
		(net "M_E_CPU0_SA_DQ<29>")
	)
	(gr_poly
		(pts
			(xy 392.23188 -238.764064) (xy 392.185652 -238.666528) (xy 392.149584 -238.630714) (xy 391.963656 -238.816642)
			(xy 391.999724 -238.852456) (xy 392.097006 -238.898684)
		)
		(stroke
			(width 0)
			(type solid)
		)
		(fill yes)
		(layer "F.Cu")
		(net "M_E_CPU0_SB_CB<1>")
	)
	(gr_poly
		(pts
			(xy 392.240262 -274.527264) (xy 392.28649 -274.429982) (xy 392.151616 -274.295108) (xy 392.054334 -274.341336)
			(xy 392.018266 -274.377404) (xy 392.204194 -274.563332)
		)
		(stroke
			(width 0)
			(type solid)
		)
		(fill yes)
		(layer "F.Cu")
		(net "M_E_CPU0_SA_DQ<20>")
	)
	(gr_poly
		(pts
			(xy 392.241024 -239.61725) (xy 392.194796 -239.519968) (xy 392.158982 -239.4839) (xy 391.973054 -239.669828)
			(xy 392.008868 -239.705896) (xy 392.106404 -239.752124)
		)
		(stroke
			(width 0)
			(type solid)
		)
		(fill yes)
		(layer "F.Cu")
		(net "M_E_CPU0_SB_CB<0>")
	)
	(gr_poly
		(pts
			(xy 392.249406 -273.673824) (xy 392.295634 -273.576288) (xy 392.161014 -273.441668) (xy 392.063478 -273.487896)
			(xy 392.027664 -273.523964) (xy 392.213338 -273.709638)
		)
		(stroke
			(width 0)
			(type solid)
		)
		(fill yes)
		(layer "F.Cu")
		(net "M_E_CPU0_SA_DQ<21>")
	)
	(gr_poly
		(pts
			(xy 392.250676 -262.977376) (xy 392.296904 -262.880094) (xy 392.162284 -262.74522) (xy 392.064748 -262.791448)
			(xy 392.028934 -262.827516) (xy 392.214862 -263.013444)
		)
		(stroke
			(width 0)
			(type solid)
		)
		(fill yes)
		(layer "F.Cu")
		(net "M_E_CPU0_SA_CB<6>")
	)
	(gr_poly
		(pts
			(xy 392.258296 -271.976342) (xy 392.304524 -271.878806) (xy 392.169904 -271.744186) (xy 392.072368 -271.790414)
			(xy 392.036554 -271.826482) (xy 392.222228 -272.012156)
		)
		(stroke
			(width 0)
			(type solid)
		)
		(fill yes)
		(layer "F.Cu")
		(net "M_E_CPU0_SA_DQ<26>")
	)
	(gr_poly
		(pts
			(xy 392.25982 -262.12419) (xy 392.306302 -262.026654) (xy 392.171428 -261.892034) (xy 392.074146 -261.938262)
			(xy 392.038078 -261.974076) (xy 392.224006 -262.160004)
		)
		(stroke
			(width 0)
			(type solid)
		)
		(fill yes)
		(layer "F.Cu")
		(net "M_E_CPU0_SA_CB<7>")
	)
	(gr_poly
		(pts
			(xy 392.26744 -271.122902) (xy 392.313668 -271.025366) (xy 392.179048 -270.890746) (xy 392.081512 -270.936974)
			(xy 392.045698 -270.973042) (xy 392.231372 -271.158716)
		)
		(stroke
			(width 0)
			(type solid)
		)
		(fill yes)
		(layer "F.Cu")
		(net "M_E_CPU0_SA_DQ<27>")
	)
	(gr_poly
		(pts
			(xy 392.272774 -228.194362) (xy 392.23696 -228.158294) (xy 392.139424 -228.112066) (xy 392.004804 -228.24694)
			(xy 392.051032 -228.344222) (xy 392.086846 -228.38029)
		)
		(stroke
			(width 0)
			(type solid)
		)
		(fill yes)
		(layer "F.Cu")
		(net "M_E_CPU0_SB_DQ<20>")
	)
	(gr_poly
		(pts
			(xy 392.291316 -248.967752) (xy 392.255248 -248.866152) (xy 392.064748 -248.866152) (xy 392.02868 -248.967752)
			(xy 392.02868 -249.018552) (xy 392.291316 -249.018552)
		)
		(stroke
			(width 0)
			(type solid)
		)
		(fill yes)
		(layer "F.Cu")
		(net "M_E_CPU0_SB_CA<0>")
	)
	(gr_poly
		(pts
			(xy 392.291316 -248.662952) (xy 392.255248 -248.561352) (xy 392.064748 -248.561352) (xy 392.02868 -248.662952)
			(xy 392.02868 -248.713752) (xy 392.291316 -248.713752)
		)
		(stroke
			(width 0)
			(type solid)
		)
		(fill yes)
		(layer "F.Cu")
		(net "M_E_CPU0_SB_CA<1>")
	)
	(gr_poly
		(pts
			(xy 392.291316 -248.358152) (xy 392.255248 -248.256552) (xy 392.064748 -248.256552) (xy 392.02868 -248.358152)
			(xy 392.02868 -248.408952) (xy 392.291316 -248.408952)
		)
		(stroke
			(width 0)
			(type solid)
		)
		(fill yes)
		(layer "F.Cu")
		(net "M_E_CPU0_SB_CA<2>")
	)
	(gr_poly
		(pts
			(xy 392.291316 -248.053352) (xy 392.255248 -247.951752) (xy 392.064748 -247.951752) (xy 392.02868 -248.053352)
			(xy 392.02868 -248.104152) (xy 392.291316 -248.104152)
		)
		(stroke
			(width 0)
			(type solid)
		)
		(fill yes)
		(layer "F.Cu")
		(net "M_E_CPU0_SB_CA<3>")
	)
	(gr_poly
		(pts
			(xy 392.291316 -247.748552) (xy 392.255248 -247.646952) (xy 392.064748 -247.646952) (xy 392.02868 -247.748552)
			(xy 392.02868 -247.799352) (xy 392.291316 -247.799352)
		)
		(stroke
			(width 0)
			(type solid)
		)
		(fill yes)
		(layer "F.Cu")
		(net "M_E_CPU0_SB_CA<4>")
	)
	(gr_poly
		(pts
			(xy 392.291316 -247.443752) (xy 392.255248 -247.342152) (xy 392.064748 -247.342152) (xy 392.02868 -247.443752)
			(xy 392.02868 -247.494552) (xy 392.291316 -247.494552)
		)
		(stroke
			(width 0)
			(type solid)
		)
		(fill yes)
		(layer "F.Cu")
		(net "M_E_CPU0_SB_CA<5>")
	)
	(gr_poly
		(pts
			(xy 392.299698 -230.755698) (xy 392.263884 -230.719884) (xy 392.166348 -230.673656) (xy 392.031728 -230.808276)
			(xy 392.077956 -230.905558) (xy 392.11377 -230.941626)
		)
		(stroke
			(width 0)
			(type solid)
		)
		(fill yes)
		(layer "F.Cu")
		(net "M_E_CPU0_SB_DQ<17>")
	)
	(gr_poly
		(pts
			(xy 392.308588 -232.452672) (xy 392.27252 -232.416858) (xy 392.175238 -232.37063) (xy 392.040364 -232.50525)
			(xy 392.086592 -232.602786) (xy 392.12266 -232.6386)
		)
		(stroke
			(width 0)
			(type solid)
		)
		(fill yes)
		(layer "F.Cu")
		(net "M_E_CPU0_SB_DQ<15>")
	)
	(gr_poly
		(pts
			(xy 392.308842 -231.609138) (xy 392.273028 -231.57307) (xy 392.175492 -231.526842) (xy 392.040872 -231.661716)
			(xy 392.0871 -231.758998) (xy 392.122914 -231.795066)
		)
		(stroke
			(width 0)
			(type solid)
		)
		(fill yes)
		(layer "F.Cu")
		(net "M_E_CPU0_SB_DQ<16>")
	)
	(gr_poly
		(pts
			(xy 392.317732 -233.306112) (xy 392.281664 -233.270298) (xy 392.184382 -233.22407) (xy 392.049762 -233.35869)
			(xy 392.09599 -233.456226) (xy 392.131804 -233.49204)
		)
		(stroke
			(width 0)
			(type solid)
		)
		(fill yes)
		(layer "F.Cu")
		(net "M_E_CPU0_SB_DQ<14>")
	)
	(gr_poly
		(pts
			(xy 392.32078 -227.325174) (xy 392.32078 -227.134674) (xy 392.21918 -227.098606) (xy 392.16838 -227.098606)
			(xy 392.16838 -227.361496) (xy 392.21918 -227.361496)
		)
		(stroke
			(width 0)
			(type solid)
		)
		(fill yes)
		(layer "F.Cu")
		(net "M_E_CPU0_SB_DQ<22>")
	)
	(gr_poly
		(pts
			(xy 392.32078 -226.728274) (xy 392.32078 -226.537774) (xy 392.21918 -226.501706) (xy 392.16838 -226.501706)
			(xy 392.16838 -226.764596) (xy 392.21918 -226.764596)
		)
		(stroke
			(width 0)
			(type solid)
		)
		(fill yes)
		(layer "F.Cu")
		(net "M_E_CPU0_SB_DQ<22>")
	)
	(gr_poly
		(pts
			(xy 392.32078 -226.131374) (xy 392.32078 -225.940874) (xy 392.21918 -225.904806) (xy 392.16838 -225.904806)
			(xy 392.16838 -226.167696) (xy 392.21918 -226.167696)
		)
		(stroke
			(width 0)
			(type solid)
		)
		(fill yes)
		(layer "F.Cu")
		(net "M_E_CPU0_SB_DQ<22>")
	)
	(gr_poly
		(pts
			(xy 392.32078 -225.534474) (xy 392.32078 -225.343974) (xy 392.21918 -225.307906) (xy 392.16838 -225.307906)
			(xy 392.16838 -225.570796) (xy 392.21918 -225.570796)
		)
		(stroke
			(width 0)
			(type solid)
		)
		(fill yes)
		(layer "F.Cu")
		(net "M_E_CPU0_SB_DQ<22>")
	)
	(gr_poly
		(pts
			(xy 392.32078 -224.937574) (xy 392.32078 -224.747074) (xy 392.21918 -224.711006) (xy 392.16838 -224.711006)
			(xy 392.16838 -224.973896) (xy 392.21918 -224.973896)
		)
		(stroke
			(width 0)
			(type solid)
		)
		(fill yes)
		(layer "F.Cu")
		(net "M_E_CPU0_SB_DQ<22>")
	)
	(gr_poly
		(pts
			(xy 392.32078 -224.340674) (xy 392.32078 -224.150174) (xy 392.21918 -224.114106) (xy 392.16838 -224.114106)
			(xy 392.16838 -224.376996) (xy 392.21918 -224.376996)
		)
		(stroke
			(width 0)
			(type solid)
		)
		(fill yes)
		(layer "F.Cu")
		(net "M_E_CPU0_SB_DQ<22>")
	)
	(gr_poly
		(pts
			(xy 392.32078 -223.743774) (xy 392.32078 -223.553274) (xy 392.21918 -223.517206) (xy 392.16838 -223.517206)
			(xy 392.16838 -223.780096) (xy 392.21918 -223.780096)
		)
		(stroke
			(width 0)
			(type solid)
		)
		(fill yes)
		(layer "F.Cu")
		(net "M_E_CPU0_SB_DQ<22>")
	)
	(gr_poly
		(pts
			(xy 392.32078 -223.146874) (xy 392.32078 -222.956374) (xy 392.21918 -222.920306) (xy 392.16838 -222.920306)
			(xy 392.16838 -223.183196) (xy 392.21918 -223.183196)
		)
		(stroke
			(width 0)
			(type solid)
		)
		(fill yes)
		(layer "F.Cu")
		(net "M_E_CPU0_SB_DQ<22>")
	)
	(gr_poly
		(pts
			(xy 392.32078 -222.549974) (xy 392.32078 -222.359474) (xy 392.21918 -222.323406) (xy 392.16838 -222.323406)
			(xy 392.16838 -222.586296) (xy 392.21918 -222.586296)
		)
		(stroke
			(width 0)
			(type solid)
		)
		(fill yes)
		(layer "F.Cu")
		(net "M_E_CPU0_SB_DQ<22>")
	)
	(gr_poly
		(pts
			(xy 392.32078 -221.953074) (xy 392.32078 -221.762574) (xy 392.21918 -221.726506) (xy 392.16838 -221.726506)
			(xy 392.16838 -221.989396) (xy 392.21918 -221.989396)
		)
		(stroke
			(width 0)
			(type solid)
		)
		(fill yes)
		(layer "F.Cu")
		(net "M_E_CPU0_SB_DQ<22>")
	)
	(gr_poly
		(pts
			(xy 392.32078 -221.356174) (xy 392.32078 -221.165674) (xy 392.21918 -221.129606) (xy 392.16838 -221.129606)
			(xy 392.16838 -221.392496) (xy 392.21918 -221.392496)
		)
		(stroke
			(width 0)
			(type solid)
		)
		(fill yes)
		(layer "F.Cu")
		(net "M_E_CPU0_SB_DQ<22>")
	)
	(gr_poly
		(pts
			(xy 392.32078 -220.759274) (xy 392.32078 -220.568774) (xy 392.21918 -220.532706) (xy 392.16838 -220.532706)
			(xy 392.16838 -220.795596) (xy 392.21918 -220.795596)
		)
		(stroke
			(width 0)
			(type solid)
		)
		(fill yes)
		(layer "F.Cu")
		(net "M_E_CPU0_SB_DQ<22>")
	)
	(gr_poly
		(pts
			(xy 392.32078 -220.162374) (xy 392.32078 -219.971874) (xy 392.21918 -219.935806) (xy 392.16838 -219.935806)
			(xy 392.16838 -220.198696) (xy 392.21918 -220.198696)
		)
		(stroke
			(width 0)
			(type solid)
		)
		(fill yes)
		(layer "F.Cu")
		(net "M_E_CPU0_SB_DQ<22>")
	)
	(gr_poly
		(pts
			(xy 392.32078 -219.565474) (xy 392.32078 -219.374974) (xy 392.21918 -219.338906) (xy 392.16838 -219.338906)
			(xy 392.16838 -219.601796) (xy 392.21918 -219.601796)
		)
		(stroke
			(width 0)
			(type solid)
		)
		(fill yes)
		(layer "F.Cu")
		(net "M_E_CPU0_SB_DQ<22>")
	)
	(gr_poly
		(pts
			(xy 392.32078 -218.968574) (xy 392.32078 -218.778074) (xy 392.21918 -218.742006) (xy 392.16838 -218.742006)
			(xy 392.16838 -219.004896) (xy 392.21918 -219.004896)
		)
		(stroke
			(width 0)
			(type solid)
		)
		(fill yes)
		(layer "F.Cu")
		(net "M_E_CPU0_SB_DQ<22>")
	)
	(gr_poly
		(pts
			(xy 392.32078 -218.371674) (xy 392.32078 -218.181174) (xy 392.21918 -218.145106) (xy 392.16838 -218.145106)
			(xy 392.16838 -218.407996) (xy 392.21918 -218.407996)
		)
		(stroke
			(width 0)
			(type solid)
		)
		(fill yes)
		(layer "F.Cu")
		(net "M_E_CPU0_SB_DQ<22>")
	)
	(gr_poly
		(pts
			(xy 392.32078 -217.774774) (xy 392.32078 -217.584274) (xy 392.21918 -217.548206) (xy 392.16838 -217.548206)
			(xy 392.16838 -217.811096) (xy 392.21918 -217.811096)
		)
		(stroke
			(width 0)
			(type solid)
		)
		(fill yes)
		(layer "F.Cu")
		(net "M_E_CPU0_SB_DQ<22>")
	)
	(gr_poly
		(pts
			(xy 392.32078 -217.177874) (xy 392.32078 -216.987374) (xy 392.21918 -216.951306) (xy 392.16838 -216.951306)
			(xy 392.16838 -217.214196) (xy 392.21918 -217.214196)
		)
		(stroke
			(width 0)
			(type solid)
		)
		(fill yes)
		(layer "F.Cu")
		(net "M_E_CPU0_SB_DQ<22>")
	)
	(gr_poly
		(pts
			(xy 392.32078 -216.580974) (xy 392.32078 -216.390474) (xy 392.21918 -216.354406) (xy 392.16838 -216.354406)
			(xy 392.16838 -216.617296) (xy 392.21918 -216.617296)
		)
		(stroke
			(width 0)
			(type solid)
		)
		(fill yes)
		(layer "F.Cu")
		(net "M_E_CPU0_SB_DQ<22>")
	)
	(gr_poly
		(pts
			(xy 392.332718 -266.654026) (xy 392.368532 -266.618212) (xy 392.182604 -266.432284) (xy 392.14679 -266.468352)
			(xy 392.100562 -266.565634) (xy 392.235182 -266.700508)
		)
		(stroke
			(width 0)
			(type solid)
		)
		(fill yes)
		(layer "F.Cu")
		(net "M_E_CPU0_SA_CB<2>")
	)
	(gr_poly
		(pts
			(xy 392.341862 -265.80084) (xy 392.377676 -265.764772) (xy 392.191748 -265.578844) (xy 392.155934 -265.614912)
			(xy 392.109706 -265.712194) (xy 392.244326 -265.847068)
		)
		(stroke
			(width 0)
			(type solid)
		)
		(fill yes)
		(layer "F.Cu")
		(net "M_E_CPU0_SA_CB<3>")
	)
	(gr_poly
		(pts
			(xy 392.342624 -235.868972) (xy 392.306556 -235.833158) (xy 392.209274 -235.78693) (xy 392.0744 -235.92155)
			(xy 392.120628 -236.019086) (xy 392.156696 -236.0549)
		)
		(stroke
			(width 0)
			(type solid)
		)
		(fill yes)
		(layer "F.Cu")
		(net "M_E_CPU0_SB_DQ<11>")
	)
	(gr_poly
		(pts
			(xy 392.35253 -236.723174) (xy 392.316716 -236.68736) (xy 392.21918 -236.640878) (xy 392.08456 -236.775752)
			(xy 392.130788 -236.873034) (xy 392.166602 -236.909102)
		)
		(stroke
			(width 0)
			(type solid)
		)
		(fill yes)
		(layer "F.Cu")
		(net "M_E_CPU0_SB_DQ<10>")
	)
	(gr_poly
		(pts
			(xy 392.356848 -269.16253) (xy 392.392662 -269.126462) (xy 392.206734 -268.940534) (xy 392.17092 -268.976602)
			(xy 392.124692 -269.073884) (xy 392.259312 -269.208758)
		)
		(stroke
			(width 0)
			(type solid)
		)
		(fill yes)
		(layer "F.Cu")
		(net "M_E_CPU0_SA_DQ<28>")
	)
	(gr_poly
		(pts
			(xy 392.360658 -238.41964) (xy 392.324844 -238.383572) (xy 392.227308 -238.337344) (xy 392.092688 -238.472218)
			(xy 392.138916 -238.5695) (xy 392.17473 -238.605568)
		)
		(stroke
			(width 0)
			(type solid)
		)
		(fill yes)
		(layer "F.Cu")
		(net "M_E_CPU0_SB_CB<1>")
	)
	(gr_poly
		(pts
			(xy 392.366246 -268.308836) (xy 392.40206 -268.273022) (xy 392.216132 -268.087094) (xy 392.180318 -268.122908)
			(xy 392.13409 -268.220444) (xy 392.26871 -268.355064)
		)
		(stroke
			(width 0)
			(type solid)
		)
		(fill yes)
		(layer "F.Cu")
		(net "M_E_CPU0_SA_DQ<29>")
	)
	(gr_poly
		(pts
			(xy 392.369802 -239.27308) (xy 392.333988 -239.237012) (xy 392.236452 -239.190784) (xy 392.101832 -239.325404)
			(xy 392.14806 -239.42294) (xy 392.184128 -239.458754)
		)
		(stroke
			(width 0)
			(type solid)
		)
		(fill yes)
		(layer "F.Cu")
		(net "M_E_CPU0_SB_CB<0>")
	)
	(gr_poly
		(pts
			(xy 392.377168 -230.462328) (xy 392.33094 -230.365046) (xy 392.295126 -230.328978) (xy 392.109198 -230.514906)
			(xy 392.145012 -230.55072) (xy 392.242548 -230.597202)
		)
		(stroke
			(width 0)
			(type solid)
		)
		(fill yes)
		(layer "F.Cu")
		(net "M_E_CPU0_SB_DQ<19>")
	)
	(gr_poly
		(pts
			(xy 392.386566 -231.315768) (xy 392.340338 -231.218232) (xy 392.30427 -231.182418) (xy 392.118342 -231.368346)
			(xy 392.15441 -231.40416) (xy 392.251692 -231.450388)
		)
		(stroke
			(width 0)
			(type solid)
		)
		(fill yes)
		(layer "F.Cu")
		(net "M_E_CPU0_SB_DQ<18>")
	)
	(gr_poly
		(pts
			(xy 392.388598 -273.95678) (xy 392.424412 -273.920712) (xy 392.238484 -273.734784) (xy 392.20267 -273.770852)
			(xy 392.156442 -273.868134) (xy 392.291062 -274.003008)
		)
		(stroke
			(width 0)
			(type solid)
		)
		(fill yes)
		(layer "F.Cu")
		(net "M_E_CPU0_SA_DQ<21>")
	)
	(gr_poly
		(pts
			(xy 392.389868 -263.260332) (xy 392.425936 -263.224518) (xy 392.240008 -263.03859) (xy 392.20394 -263.074404)
			(xy 392.157712 -263.17194) (xy 392.292586 -263.30656)
		)
		(stroke
			(width 0)
			(type solid)
		)
		(fill yes)
		(layer "F.Cu")
		(net "M_E_CPU0_SA_CB<6>")
	)
	(gr_poly
		(pts
			(xy 392.395202 -233.012742) (xy 392.348974 -232.91546) (xy 392.31316 -232.879392) (xy 392.127232 -233.06532)
			(xy 392.163046 -233.101388) (xy 392.260582 -233.147616)
		)
		(stroke
			(width 0)
			(type solid)
		)
		(fill yes)
		(layer "F.Cu")
		(net "M_E_CPU0_SB_DQ<13>")
	)
	(gr_poly
		(pts
			(xy 392.397488 -272.259298) (xy 392.433302 -272.22323) (xy 392.247374 -272.037302) (xy 392.21156 -272.07337)
			(xy 392.165332 -272.170652) (xy 392.299952 -272.305526)
		)
		(stroke
			(width 0)
			(type solid)
		)
		(fill yes)
		(layer "F.Cu")
		(net "M_E_CPU0_SA_DQ<26>")
	)
	(gr_poly
		(pts
			(xy 392.399012 -262.406892) (xy 392.43508 -262.371078) (xy 392.249152 -262.18515) (xy 392.213338 -262.220964)
			(xy 392.16711 -262.3185) (xy 392.30173 -262.45312)
		)
		(stroke
			(width 0)
			(type solid)
		)
		(fill yes)
		(layer "F.Cu")
		(net "M_E_CPU0_SA_CB<7>")
	)
	(gr_poly
		(pts
			(xy 392.399774 -267.008864) (xy 392.446002 -266.911582) (xy 392.311382 -266.776962) (xy 392.213846 -266.82319)
			(xy 392.178032 -266.859004) (xy 392.36396 -267.044932)
		)
		(stroke
			(width 0)
			(type solid)
		)
		(fill yes)
		(layer "F.Cu")
		(net "M_E_CPU0_SA_CB<0>")
	)
	(gr_poly
		(pts
			(xy 392.4046 -233.866182) (xy 392.358118 -233.768646) (xy 392.322304 -233.732832) (xy 392.136376 -233.91876)
			(xy 392.172444 -233.954574) (xy 392.269726 -234.000802)
		)
		(stroke
			(width 0)
			(type solid)
		)
		(fill yes)
		(layer "F.Cu")
		(net "M_E_CPU0_SB_DQ<12>")
	)
	(gr_poly
		(pts
			(xy 392.406632 -271.405858) (xy 392.442446 -271.36979) (xy 392.256518 -271.183862) (xy 392.220704 -271.21993)
			(xy 392.174476 -271.317466) (xy 392.309096 -271.452086)
		)
		(stroke
			(width 0)
			(type solid)
		)
		(fill yes)
		(layer "F.Cu")
		(net "M_E_CPU0_SA_DQ<27>")
	)
	(gr_poly
		(pts
			(xy 392.409172 -266.155678) (xy 392.4554 -266.058142) (xy 392.320526 -265.923522) (xy 392.223244 -265.96975)
			(xy 392.187176 -266.005564) (xy 392.373104 -266.191492)
		)
		(stroke
			(width 0)
			(type solid)
		)
		(fill yes)
		(layer "F.Cu")
		(net "M_E_CPU0_SA_CB<1>")
	)
	(gr_poly
		(pts
			(xy 392.429492 -236.429296) (xy 392.383264 -236.33176) (xy 392.347196 -236.295946) (xy 392.161522 -236.48162)
			(xy 392.197336 -236.517688) (xy 392.294872 -236.563916)
		)
		(stroke
			(width 0)
			(type solid)
		)
		(fill yes)
		(layer "F.Cu")
		(net "M_E_CPU0_SB_DQ<9>")
	)
	(gr_poly
		(pts
			(xy 392.433302 -268.663928) (xy 392.47953 -268.566392) (xy 392.344656 -268.431772) (xy 392.247374 -268.478)
			(xy 392.211306 -268.513814) (xy 392.397234 -268.699742)
		)
		(stroke
			(width 0)
			(type solid)
		)
		(fill yes)
		(layer "F.Cu")
		(net "M_E_CPU0_SA_DQ<30>")
	)
	(gr_poly
		(pts
			(xy 392.438382 -238.12627) (xy 392.3919 -238.028734) (xy 392.356086 -237.99292) (xy 392.170158 -238.178848)
			(xy 392.206226 -238.214662) (xy 392.303508 -238.26089)
		)
		(stroke
			(width 0)
			(type solid)
		)
		(fill yes)
		(layer "F.Cu")
		(net "M_E_CPU0_SB_CB<3>")
	)
	(gr_poly
		(pts
			(xy 392.439398 -237.283244) (xy 392.39317 -237.185962) (xy 392.357356 -237.149894) (xy 392.171428 -237.335822)
			(xy 392.207242 -237.37189) (xy 392.304778 -237.418118)
		)
		(stroke
			(width 0)
			(type solid)
		)
		(fill yes)
		(layer "F.Cu")
		(net "M_E_CPU0_SB_DQ<8>")
	)
	(gr_poly
		(pts
			(xy 392.4427 -267.810234) (xy 392.488928 -267.712952) (xy 392.354308 -267.578078) (xy 392.256772 -267.624306)
			(xy 392.220958 -267.660374) (xy 392.406886 -267.846302)
		)
		(stroke
			(width 0)
			(type solid)
		)
		(fill yes)
		(layer "F.Cu")
		(net "M_E_CPU0_SA_DQ<31>")
	)
	(gr_poly
		(pts
			(xy 392.447526 -238.97971) (xy 392.401298 -238.882174) (xy 392.36523 -238.84636) (xy 392.179302 -239.032288)
			(xy 392.21537 -239.068102) (xy 392.312652 -239.11433)
		)
		(stroke
			(width 0)
			(type solid)
		)
		(fill yes)
		(layer "F.Cu")
		(net "M_E_CPU0_SB_CB<2>")
	)
	(gr_poly
		(pts
			(xy 392.455908 -274.311618) (xy 392.502136 -274.214082) (xy 392.367262 -274.079462) (xy 392.26998 -274.12569)
			(xy 392.233912 -274.161504) (xy 392.41984 -274.347432)
		)
		(stroke
			(width 0)
			(type solid)
		)
		(fill yes)
		(layer "F.Cu")
		(net "M_E_CPU0_SA_DQ<22>")
	)
	(gr_poly
		(pts
			(xy 392.457178 -263.61517) (xy 392.503406 -263.517634) (xy 392.368786 -263.383014) (xy 392.27125 -263.429242)
			(xy 392.235436 -263.46531) (xy 392.42111 -263.650984)
		)
		(stroke
			(width 0)
			(type solid)
		)
		(fill yes)
		(layer "F.Cu")
		(net "M_E_CPU0_SA_CB<4>")
	)
	(gr_poly
		(pts
			(xy 392.464798 -272.614136) (xy 392.511026 -272.5166) (xy 392.376152 -272.38198) (xy 392.27887 -272.428208)
			(xy 392.242802 -272.464022) (xy 392.42873 -272.64995)
		)
		(stroke
			(width 0)
			(type solid)
		)
		(fill yes)
		(layer "F.Cu")
		(net "M_E_CPU0_SA_DQ<24>")
	)
	(gr_poly
		(pts
			(xy 392.465052 -273.457924) (xy 392.51128 -273.360642) (xy 392.37666 -273.225768) (xy 392.279124 -273.271996)
			(xy 392.24331 -273.308064) (xy 392.429238 -273.493992)
		)
		(stroke
			(width 0)
			(type solid)
		)
		(fill yes)
		(layer "F.Cu")
		(net "M_E_CPU0_SA_DQ<23>")
	)
	(gr_poly
		(pts
			(xy 392.466322 -262.76173) (xy 392.51255 -262.664448) (xy 392.37793 -262.529574) (xy 392.280394 -262.575802)
			(xy 392.24458 -262.61187) (xy 392.430508 -262.797798)
		)
		(stroke
			(width 0)
			(type solid)
		)
		(fill yes)
		(layer "F.Cu")
		(net "M_E_CPU0_SA_CB<5>")
	)
	(gr_poly
		(pts
			(xy 392.47318 -227.397056) (xy 392.42238 -227.397056) (xy 392.32078 -227.433378) (xy 392.32078 -227.623878)
			(xy 392.42238 -227.659946) (xy 392.47318 -227.659946)
		)
		(stroke
			(width 0)
			(type solid)
		)
		(fill yes)
		(layer "F.Cu")
		(net "M_E_CPU0_SB_DQ<20>")
	)
	(gr_poly
		(pts
			(xy 392.47318 -226.800156) (xy 392.42238 -226.800156) (xy 392.32078 -226.836478) (xy 392.32078 -227.026978)
			(xy 392.42238 -227.063046) (xy 392.47318 -227.063046)
		)
		(stroke
			(width 0)
			(type solid)
		)
		(fill yes)
		(layer "F.Cu")
		(net "M_E_CPU0_SB_DQ<20>")
	)
	(gr_poly
		(pts
			(xy 392.47318 -226.203256) (xy 392.42238 -226.203256) (xy 392.32078 -226.239578) (xy 392.32078 -226.430078)
			(xy 392.42238 -226.466146) (xy 392.47318 -226.466146)
		)
		(stroke
			(width 0)
			(type solid)
		)
		(fill yes)
		(layer "F.Cu")
		(net "M_E_CPU0_SB_DQ<20>")
	)
	(gr_poly
		(pts
			(xy 392.47318 -225.606356) (xy 392.42238 -225.606356) (xy 392.32078 -225.642678) (xy 392.32078 -225.833178)
			(xy 392.42238 -225.869246) (xy 392.47318 -225.869246)
		)
		(stroke
			(width 0)
			(type solid)
		)
		(fill yes)
		(layer "F.Cu")
		(net "M_E_CPU0_SB_DQ<20>")
	)
	(gr_poly
		(pts
			(xy 392.47318 -225.009456) (xy 392.42238 -225.009456) (xy 392.32078 -225.045778) (xy 392.32078 -225.236278)
			(xy 392.42238 -225.272346) (xy 392.47318 -225.272346)
		)
		(stroke
			(width 0)
			(type solid)
		)
		(fill yes)
		(layer "F.Cu")
		(net "M_E_CPU0_SB_DQ<20>")
	)
	(gr_poly
		(pts
			(xy 392.47318 -224.412556) (xy 392.42238 -224.412556) (xy 392.32078 -224.448878) (xy 392.32078 -224.639378)
			(xy 392.42238 -224.675446) (xy 392.47318 -224.675446)
		)
		(stroke
			(width 0)
			(type solid)
		)
		(fill yes)
		(layer "F.Cu")
		(net "M_E_CPU0_SB_DQ<20>")
	)
	(gr_poly
		(pts
			(xy 392.47318 -223.815656) (xy 392.42238 -223.815656) (xy 392.32078 -223.851978) (xy 392.32078 -224.042478)
			(xy 392.42238 -224.078546) (xy 392.47318 -224.078546)
		)
		(stroke
			(width 0)
			(type solid)
		)
		(fill yes)
		(layer "F.Cu")
		(net "M_E_CPU0_SB_DQ<20>")
	)
	(gr_poly
		(pts
			(xy 392.47318 -223.218756) (xy 392.42238 -223.218756) (xy 392.32078 -223.255078) (xy 392.32078 -223.445578)
			(xy 392.42238 -223.481646) (xy 392.47318 -223.481646)
		)
		(stroke
			(width 0)
			(type solid)
		)
		(fill yes)
		(layer "F.Cu")
		(net "M_E_CPU0_SB_DQ<20>")
	)
	(gr_poly
		(pts
			(xy 392.47318 -222.621856) (xy 392.42238 -222.621856) (xy 392.32078 -222.658178) (xy 392.32078 -222.848678)
			(xy 392.42238 -222.884746) (xy 392.47318 -222.884746)
		)
		(stroke
			(width 0)
			(type solid)
		)
		(fill yes)
		(layer "F.Cu")
		(net "M_E_CPU0_SB_DQ<20>")
	)
	(gr_poly
		(pts
			(xy 392.47318 -222.024956) (xy 392.42238 -222.024956) (xy 392.32078 -222.061278) (xy 392.32078 -222.251778)
			(xy 392.42238 -222.287846) (xy 392.47318 -222.287846)
		)
		(stroke
			(width 0)
			(type solid)
		)
		(fill yes)
		(layer "F.Cu")
		(net "M_E_CPU0_SB_DQ<20>")
	)
	(gr_poly
		(pts
			(xy 392.47318 -221.428056) (xy 392.42238 -221.428056) (xy 392.32078 -221.464378) (xy 392.32078 -221.654878)
			(xy 392.42238 -221.690946) (xy 392.47318 -221.690946)
		)
		(stroke
			(width 0)
			(type solid)
		)
		(fill yes)
		(layer "F.Cu")
		(net "M_E_CPU0_SB_DQ<20>")
	)
	(gr_poly
		(pts
			(xy 392.47318 -220.831156) (xy 392.42238 -220.831156) (xy 392.32078 -220.867478) (xy 392.32078 -221.057978)
			(xy 392.42238 -221.094046) (xy 392.47318 -221.094046)
		)
		(stroke
			(width 0)
			(type solid)
		)
		(fill yes)
		(layer "F.Cu")
		(net "M_E_CPU0_SB_DQ<20>")
	)
	(gr_poly
		(pts
			(xy 392.47318 -220.234256) (xy 392.42238 -220.234256) (xy 392.32078 -220.270578) (xy 392.32078 -220.461078)
			(xy 392.42238 -220.497146) (xy 392.47318 -220.497146)
		)
		(stroke
			(width 0)
			(type solid)
		)
		(fill yes)
		(layer "F.Cu")
		(net "M_E_CPU0_SB_DQ<20>")
	)
	(gr_poly
		(pts
			(xy 392.47318 -219.637356) (xy 392.42238 -219.637356) (xy 392.32078 -219.673678) (xy 392.32078 -219.864178)
			(xy 392.42238 -219.900246) (xy 392.47318 -219.900246)
		)
		(stroke
			(width 0)
			(type solid)
		)
		(fill yes)
		(layer "F.Cu")
		(net "M_E_CPU0_SB_DQ<20>")
	)
	(gr_poly
		(pts
			(xy 392.47318 -219.040456) (xy 392.42238 -219.040456) (xy 392.32078 -219.076778) (xy 392.32078 -219.267278)
			(xy 392.42238 -219.303346) (xy 392.47318 -219.303346)
		)
		(stroke
			(width 0)
			(type solid)
		)
		(fill yes)
		(layer "F.Cu")
		(net "M_E_CPU0_SB_DQ<20>")
	)
	(gr_poly
		(pts
			(xy 392.47318 -218.443556) (xy 392.42238 -218.443556) (xy 392.32078 -218.479878) (xy 392.32078 -218.670378)
			(xy 392.42238 -218.706446) (xy 392.47318 -218.706446)
		)
		(stroke
			(width 0)
			(type solid)
		)
		(fill yes)
		(layer "F.Cu")
		(net "M_E_CPU0_SB_DQ<20>")
	)
	(gr_poly
		(pts
			(xy 392.47318 -217.846656) (xy 392.42238 -217.846656) (xy 392.32078 -217.882978) (xy 392.32078 -218.073478)
			(xy 392.42238 -218.109546) (xy 392.47318 -218.109546)
		)
		(stroke
			(width 0)
			(type solid)
		)
		(fill yes)
		(layer "F.Cu")
		(net "M_E_CPU0_SB_DQ<20>")
	)
	(gr_poly
		(pts
			(xy 392.47318 -217.249756) (xy 392.42238 -217.249756) (xy 392.32078 -217.286078) (xy 392.32078 -217.476578)
			(xy 392.42238 -217.512646) (xy 392.47318 -217.512646)
		)
		(stroke
			(width 0)
			(type solid)
		)
		(fill yes)
		(layer "F.Cu")
		(net "M_E_CPU0_SB_DQ<20>")
	)
	(gr_poly
		(pts
			(xy 392.47318 -216.652856) (xy 392.42238 -216.652856) (xy 392.32078 -216.689178) (xy 392.32078 -216.879678)
			(xy 392.42238 -216.915746) (xy 392.47318 -216.915746)
		)
		(stroke
			(width 0)
			(type solid)
		)
		(fill yes)
		(layer "F.Cu")
		(net "M_E_CPU0_SB_DQ<20>")
	)
	(gr_poly
		(pts
			(xy 392.473942 -271.760696) (xy 392.52017 -271.66316) (xy 392.385296 -271.52854) (xy 392.288014 -271.574768)
			(xy 392.251946 -271.610582) (xy 392.437874 -271.79651)
		)
		(stroke
			(width 0)
			(type solid)
		)
		(fill yes)
		(layer "F.Cu")
		(net "M_E_CPU0_SA_DQ<25>")
	)
	(gr_poly
		(pts
			(xy 392.5062 -230.117904) (xy 392.470132 -230.08209) (xy 392.37285 -230.035862) (xy 392.237976 -230.170482)
			(xy 392.284204 -230.268018) (xy 392.320272 -230.303832)
		)
		(stroke
			(width 0)
			(type solid)
		)
		(fill yes)
		(layer "F.Cu")
		(net "M_E_CPU0_SB_DQ<19>")
	)
	(gr_poly
		(pts
			(xy 392.515344 -230.971344) (xy 392.47953 -230.93553) (xy 392.381994 -230.889302) (xy 392.247374 -231.023922)
			(xy 392.293602 -231.121204) (xy 392.329416 -231.157272)
		)
		(stroke
			(width 0)
			(type solid)
		)
		(fill yes)
		(layer "F.Cu")
		(net "M_E_CPU0_SB_DQ<18>")
	)
	(gr_poly
		(pts
			(xy 392.516614 -241.49939) (xy 392.470132 -241.401854) (xy 392.434318 -241.36604) (xy 392.24839 -241.551968)
			(xy 392.284458 -241.587782) (xy 392.38174 -241.63401)
		)
		(stroke
			(width 0)
			(type solid)
		)
		(fill yes)
		(layer "F.Cu")
		(net "M_E_CPU0_SB_CB<7>")
	)
	(gr_poly
		(pts
			(xy 392.524234 -232.668318) (xy 392.488166 -232.632504) (xy 392.390884 -232.586276) (xy 392.25601 -232.720896)
			(xy 392.302238 -232.818432) (xy 392.338306 -232.854246)
		)
		(stroke
			(width 0)
			(type solid)
		)
		(fill yes)
		(layer "F.Cu")
		(net "M_E_CPU0_SB_DQ<13>")
	)
	(gr_poly
		(pts
			(xy 392.53033 -275.23821) (xy 392.622786 -275.182838) (xy 392.585448 -274.995894) (xy 392.478768 -274.9804)
			(xy 392.428984 -274.990306) (xy 392.480546 -275.248116)
		)
		(stroke
			(width 0)
			(type solid)
		)
		(fill yes)
		(layer "F.Cu")
		(net "M_E_CPU0_SA_DQ<20>")
	)
	(gr_poly
		(pts
			(xy 392.533378 -233.521758) (xy 392.49731 -233.485944) (xy 392.400028 -233.439716) (xy 392.265408 -233.574336)
			(xy 392.311636 -233.671872) (xy 392.34745 -233.707686)
		)
		(stroke
			(width 0)
			(type solid)
		)
		(fill yes)
		(layer "F.Cu")
		(net "M_E_CPU0_SB_DQ<12>")
	)
	(gr_poly
		(pts
			(xy 392.538966 -275.540724) (xy 392.487404 -275.283168) (xy 392.43762 -275.293074) (xy 392.345164 -275.348446)
			(xy 392.382502 -275.535136) (xy 392.489182 -275.550884)
		)
		(stroke
			(width 0)
			(type solid)
		)
		(fill yes)
		(layer "F.Cu")
		(net "M_E_CPU0_SA_DQ<20>")
	)
	(gr_poly
		(pts
			(xy 392.538966 -267.29182) (xy 392.575034 -267.256006) (xy 392.389106 -267.070078) (xy 392.353038 -267.105892)
			(xy 392.30681 -267.203428) (xy 392.441684 -267.338048)
		)
		(stroke
			(width 0)
			(type solid)
		)
		(fill yes)
		(layer "F.Cu")
		(net "M_E_CPU0_SA_CB<0>")
	)
	(gr_poly
		(pts
			(xy 392.548364 -266.43838) (xy 392.584178 -266.402566) (xy 392.39825 -266.216638) (xy 392.362436 -266.252706)
			(xy 392.316208 -266.349988) (xy 392.450828 -266.484862)
		)
		(stroke
			(width 0)
			(type solid)
		)
		(fill yes)
		(layer "F.Cu")
		(net "M_E_CPU0_SA_CB<1>")
	)
	(gr_poly
		(pts
			(xy 392.55827 -236.084872) (xy 392.522456 -236.048804) (xy 392.42492 -236.002576) (xy 392.2903 -236.13745)
			(xy 392.336528 -236.234732) (xy 392.372596 -236.2708)
		)
		(stroke
			(width 0)
			(type solid)
		)
		(fill yes)
		(layer "F.Cu")
		(net "M_E_CPU0_SB_DQ<9>")
	)
	(gr_poly
		(pts
			(xy 392.56716 -237.781846) (xy 392.531092 -237.746032) (xy 392.43381 -237.699804) (xy 392.29919 -237.834424)
			(xy 392.345418 -237.93196) (xy 392.381232 -237.967774)
		)
		(stroke
			(width 0)
			(type solid)
		)
		(fill yes)
		(layer "F.Cu")
		(net "M_E_CPU0_SB_CB<3>")
	)
	(gr_poly
		(pts
			(xy 392.56843 -236.93882) (xy 392.532362 -236.903006) (xy 392.43508 -236.856778) (xy 392.300206 -236.991398)
			(xy 392.346434 -237.088934) (xy 392.382502 -237.124748)
		)
		(stroke
			(width 0)
			(type solid)
		)
		(fill yes)
		(layer "F.Cu")
		(net "M_E_CPU0_SB_DQ<8>")
	)
	(gr_poly
		(pts
			(xy 392.572494 -268.946884) (xy 392.608308 -268.910816) (xy 392.42238 -268.724888) (xy 392.386566 -268.760956)
			(xy 392.340338 -268.858238) (xy 392.474958 -268.993112)
		)
		(stroke
			(width 0)
			(type solid)
		)
		(fill yes)
		(layer "F.Cu")
		(net "M_E_CPU0_SA_DQ<30>")
	)
	(gr_poly
		(pts
			(xy 392.576304 -238.635286) (xy 392.54049 -238.599218) (xy 392.442954 -238.55299) (xy 392.308334 -238.687864)
			(xy 392.354562 -238.785146) (xy 392.390376 -238.821214)
		)
		(stroke
			(width 0)
			(type solid)
		)
		(fill yes)
		(layer "F.Cu")
		(net "M_E_CPU0_SB_CB<2>")
	)
	(gr_poly
		(pts
			(xy 392.581892 -268.09319) (xy 392.617706 -268.057122) (xy 392.432032 -267.871448) (xy 392.395964 -267.907262)
			(xy 392.349736 -268.004798) (xy 392.484356 -268.139418)
		)
		(stroke
			(width 0)
			(type solid)
		)
		(fill yes)
		(layer "F.Cu")
		(net "M_E_CPU0_SA_DQ<31>")
	)
	(gr_poly
		(pts
			(xy 392.59002 -249.069352) (xy 392.59002 -249.018552) (xy 392.326876 -249.018552) (xy 392.326876 -249.069352)
			(xy 392.363198 -249.170952) (xy 392.553698 -249.170952)
		)
		(stroke
			(width 0)
			(type solid)
		)
		(fill yes)
		(layer "F.Cu")
		(net "M_E_CPU0_SB_CA<0>")
	)
	(gr_poly
		(pts
			(xy 392.59002 -248.764552) (xy 392.59002 -248.713752) (xy 392.326876 -248.713752) (xy 392.326876 -248.764552)
			(xy 392.363198 -248.866152) (xy 392.553698 -248.866152)
		)
		(stroke
			(width 0)
			(type solid)
		)
		(fill yes)
		(layer "F.Cu")
		(net "M_E_CPU0_SB_CA<1>")
	)
	(gr_poly
		(pts
			(xy 392.59002 -248.459752) (xy 392.59002 -248.408952) (xy 392.326876 -248.408952) (xy 392.326876 -248.459752)
			(xy 392.363198 -248.561352) (xy 392.553698 -248.561352)
		)
		(stroke
			(width 0)
			(type solid)
		)
		(fill yes)
		(layer "F.Cu")
		(net "M_E_CPU0_SB_CA<2>")
	)
	(gr_poly
		(pts
			(xy 392.59002 -248.154952) (xy 392.59002 -248.104152) (xy 392.326876 -248.104152) (xy 392.326876 -248.154952)
			(xy 392.363198 -248.256552) (xy 392.553698 -248.256552)
		)
		(stroke
			(width 0)
			(type solid)
		)
		(fill yes)
		(layer "F.Cu")
		(net "M_E_CPU0_SB_CA<3>")
	)
	(gr_poly
		(pts
			(xy 392.592814 -230.677974) (xy 392.546586 -230.580692) (xy 392.510772 -230.544624) (xy 392.324844 -230.730552)
			(xy 392.360658 -230.766366) (xy 392.458194 -230.812848)
		)
		(stroke
			(width 0)
			(type solid)
		)
		(fill yes)
		(layer "F.Cu")
		(net "M_E_CPU0_SB_DQ<17>")
	)
	(gr_poly
		(pts
			(xy 392.59637 -263.898126) (xy 392.632184 -263.862058) (xy 392.446256 -263.67613) (xy 392.410442 -263.712198)
			(xy 392.364214 -263.80948) (xy 392.498834 -263.944354)
		)
		(stroke
			(width 0)
			(type solid)
		)
		(fill yes)
		(layer "F.Cu")
		(net "M_E_CPU0_SA_CB<4>")
	)
	(gr_poly
		(pts
			(xy 392.601704 -232.375202) (xy 392.555476 -232.277666) (xy 392.519408 -232.241852) (xy 392.333734 -232.427526)
			(xy 392.369548 -232.463594) (xy 392.467084 -232.509822)
		)
		(stroke
			(width 0)
			(type solid)
		)
		(fill yes)
		(layer "F.Cu")
		(net "M_E_CPU0_SB_DQ<15>")
	)
	(gr_poly
		(pts
			(xy 392.602212 -231.531414) (xy 392.555984 -231.433878) (xy 392.519916 -231.398064) (xy 392.333988 -231.583992)
			(xy 392.370056 -231.619806) (xy 392.467338 -231.666034)
		)
		(stroke
			(width 0)
			(type solid)
		)
		(fill yes)
		(layer "F.Cu")
		(net "M_E_CPU0_SB_DQ<16>")
	)
	(gr_poly
		(pts
			(xy 392.60399 -272.897092) (xy 392.639804 -272.861024) (xy 392.453876 -272.675096) (xy 392.418062 -272.711164)
			(xy 392.371834 -272.808446) (xy 392.506454 -272.94332)
		)
		(stroke
			(width 0)
			(type solid)
		)
		(fill yes)
		(layer "F.Cu")
		(net "M_E_CPU0_SA_DQ<24>")
	)
	(gr_poly
		(pts
			(xy 392.604244 -273.74088) (xy 392.640312 -273.705066) (xy 392.454384 -273.519138) (xy 392.418316 -273.554952)
			(xy 392.372088 -273.652488) (xy 392.506962 -273.787108)
		)
		(stroke
			(width 0)
			(type solid)
		)
		(fill yes)
		(layer "F.Cu")
		(net "M_E_CPU0_SA_DQ<23>")
	)
	(gr_poly
		(pts
			(xy 392.605514 -263.044686) (xy 392.641582 -263.008872) (xy 392.455654 -262.822944) (xy 392.419586 -262.858758)
			(xy 392.373358 -262.956294) (xy 392.508232 -263.090914)
		)
		(stroke
			(width 0)
			(type solid)
		)
		(fill yes)
		(layer "F.Cu")
		(net "M_E_CPU0_SA_CB<5>")
	)
	(gr_poly
		(pts
			(xy 392.610848 -233.228388) (xy 392.56462 -233.131106) (xy 392.528806 -233.095038) (xy 392.342878 -233.280966)
			(xy 392.378692 -233.317034) (xy 392.476228 -233.363262)
		)
		(stroke
			(width 0)
			(type solid)
		)
		(fill yes)
		(layer "F.Cu")
		(net "M_E_CPU0_SB_DQ<14>")
	)
	(gr_poly
		(pts
			(xy 392.613134 -272.043652) (xy 392.648948 -272.007584) (xy 392.46302 -271.821656) (xy 392.427206 -271.857724)
			(xy 392.380978 -271.955006) (xy 392.515598 -272.08988)
		)
		(stroke
			(width 0)
			(type solid)
		)
		(fill yes)
		(layer "F.Cu")
		(net "M_E_CPU0_SA_DQ<25>")
	)
	(gr_poly
		(pts
			(xy 392.61542 -266.793218) (xy 392.661648 -266.695936) (xy 392.527028 -266.561316) (xy 392.429492 -266.607544)
			(xy 392.393678 -266.643358) (xy 392.579606 -266.829286)
		)
		(stroke
			(width 0)
			(type solid)
		)
		(fill yes)
		(layer "F.Cu")
		(net "M_E_CPU0_SA_CB<2>")
	)
	(gr_poly
		(pts
			(xy 392.624818 -265.940032) (xy 392.671046 -265.842496) (xy 392.536172 -265.707876) (xy 392.43889 -265.754104)
			(xy 392.402822 -265.789918) (xy 392.58875 -265.975846)
		)
		(stroke
			(width 0)
			(type solid)
		)
		(fill yes)
		(layer "F.Cu")
		(net "M_E_CPU0_SA_CB<3>")
	)
	(gr_poly
		(pts
			(xy 392.62558 -227.325174) (xy 392.62558 -227.134674) (xy 392.52398 -227.098606) (xy 392.47318 -227.098606)
			(xy 392.47318 -227.361496) (xy 392.52398 -227.361496)
		)
		(stroke
			(width 0)
			(type solid)
		)
		(fill yes)
		(layer "F.Cu")
		(net "M_E_CPU0_SB_DQ<20>")
	)
	(gr_poly
		(pts
			(xy 392.62558 -226.728274) (xy 392.62558 -226.537774) (xy 392.52398 -226.501706) (xy 392.47318 -226.501706)
			(xy 392.47318 -226.764596) (xy 392.52398 -226.764596)
		)
		(stroke
			(width 0)
			(type solid)
		)
		(fill yes)
		(layer "F.Cu")
		(net "M_E_CPU0_SB_DQ<20>")
	)
	(gr_poly
		(pts
			(xy 392.62558 -226.131374) (xy 392.62558 -225.940874) (xy 392.52398 -225.904806) (xy 392.47318 -225.904806)
			(xy 392.47318 -226.167696) (xy 392.52398 -226.167696)
		)
		(stroke
			(width 0)
			(type solid)
		)
		(fill yes)
		(layer "F.Cu")
		(net "M_E_CPU0_SB_DQ<20>")
	)
	(gr_poly
		(pts
			(xy 392.62558 -225.534474) (xy 392.62558 -225.343974) (xy 392.52398 -225.307906) (xy 392.47318 -225.307906)
			(xy 392.47318 -225.570796) (xy 392.52398 -225.570796)
		)
		(stroke
			(width 0)
			(type solid)
		)
		(fill yes)
		(layer "F.Cu")
		(net "M_E_CPU0_SB_DQ<20>")
	)
	(gr_poly
		(pts
			(xy 392.62558 -224.937574) (xy 392.62558 -224.747074) (xy 392.52398 -224.711006) (xy 392.47318 -224.711006)
			(xy 392.47318 -224.973896) (xy 392.52398 -224.973896)
		)
		(stroke
			(width 0)
			(type solid)
		)
		(fill yes)
		(layer "F.Cu")
		(net "M_E_CPU0_SB_DQ<20>")
	)
	(gr_poly
		(pts
			(xy 392.62558 -224.340674) (xy 392.62558 -224.150174) (xy 392.52398 -224.114106) (xy 392.47318 -224.114106)
			(xy 392.47318 -224.376996) (xy 392.52398 -224.376996)
		)
		(stroke
			(width 0)
			(type solid)
		)
		(fill yes)
		(layer "F.Cu")
		(net "M_E_CPU0_SB_DQ<20>")
	)
	(gr_poly
		(pts
			(xy 392.62558 -223.743774) (xy 392.62558 -223.553274) (xy 392.52398 -223.517206) (xy 392.47318 -223.517206)
			(xy 392.47318 -223.780096) (xy 392.52398 -223.780096)
		)
		(stroke
			(width 0)
			(type solid)
		)
		(fill yes)
		(layer "F.Cu")
		(net "M_E_CPU0_SB_DQ<20>")
	)
	(gr_poly
		(pts
			(xy 392.62558 -223.146874) (xy 392.62558 -222.956374) (xy 392.52398 -222.920306) (xy 392.47318 -222.920306)
			(xy 392.47318 -223.183196) (xy 392.52398 -223.183196)
		)
		(stroke
			(width 0)
			(type solid)
		)
		(fill yes)
		(layer "F.Cu")
		(net "M_E_CPU0_SB_DQ<20>")
	)
	(gr_poly
		(pts
			(xy 392.62558 -222.549974) (xy 392.62558 -222.359474) (xy 392.52398 -222.323406) (xy 392.47318 -222.323406)
			(xy 392.47318 -222.586296) (xy 392.52398 -222.586296)
		)
		(stroke
			(width 0)
			(type solid)
		)
		(fill yes)
		(layer "F.Cu")
		(net "M_E_CPU0_SB_DQ<20>")
	)
	(gr_poly
		(pts
			(xy 392.62558 -221.953074) (xy 392.62558 -221.762574) (xy 392.52398 -221.726506) (xy 392.47318 -221.726506)
			(xy 392.47318 -221.989396) (xy 392.52398 -221.989396)
		)
		(stroke
			(width 0)
			(type solid)
		)
		(fill yes)
		(layer "F.Cu")
		(net "M_E_CPU0_SB_DQ<20>")
	)
	(gr_poly
		(pts
			(xy 392.62558 -221.356174) (xy 392.62558 -221.165674) (xy 392.52398 -221.129606) (xy 392.47318 -221.129606)
			(xy 392.47318 -221.392496) (xy 392.52398 -221.392496)
		)
		(stroke
			(width 0)
			(type solid)
		)
		(fill yes)
		(layer "F.Cu")
		(net "M_E_CPU0_SB_DQ<20>")
	)
	(gr_poly
		(pts
			(xy 392.62558 -220.759274) (xy 392.62558 -220.568774) (xy 392.52398 -220.532706) (xy 392.47318 -220.532706)
			(xy 392.47318 -220.795596) (xy 392.52398 -220.795596)
		)
		(stroke
			(width 0)
			(type solid)
		)
		(fill yes)
		(layer "F.Cu")
		(net "M_E_CPU0_SB_DQ<20>")
	)
	(gr_poly
		(pts
			(xy 392.62558 -220.162374) (xy 392.62558 -219.971874) (xy 392.52398 -219.935806) (xy 392.47318 -219.935806)
			(xy 392.47318 -220.198696) (xy 392.52398 -220.198696)
		)
		(stroke
			(width 0)
			(type solid)
		)
		(fill yes)
		(layer "F.Cu")
		(net "M_E_CPU0_SB_DQ<20>")
	)
	(gr_poly
		(pts
			(xy 392.62558 -219.565474) (xy 392.62558 -219.374974) (xy 392.52398 -219.338906) (xy 392.47318 -219.338906)
			(xy 392.47318 -219.601796) (xy 392.52398 -219.601796)
		)
		(stroke
			(width 0)
			(type solid)
		)
		(fill yes)
		(layer "F.Cu")
		(net "M_E_CPU0_SB_DQ<20>")
	)
	(gr_poly
		(pts
			(xy 392.62558 -218.968574) (xy 392.62558 -218.778074) (xy 392.52398 -218.742006) (xy 392.47318 -218.742006)
			(xy 392.47318 -219.004896) (xy 392.52398 -219.004896)
		)
		(stroke
			(width 0)
			(type solid)
		)
		(fill yes)
		(layer "F.Cu")
		(net "M_E_CPU0_SB_DQ<20>")
	)
	(gr_poly
		(pts
			(xy 392.62558 -218.371674) (xy 392.62558 -218.181174) (xy 392.52398 -218.145106) (xy 392.47318 -218.145106)
			(xy 392.47318 -218.407996) (xy 392.52398 -218.407996)
		)
		(stroke
			(width 0)
			(type solid)
		)
		(fill yes)
		(layer "F.Cu")
		(net "M_E_CPU0_SB_DQ<20>")
	)
	(gr_poly
		(pts
			(xy 392.62558 -217.774774) (xy 392.62558 -217.584274) (xy 392.52398 -217.548206) (xy 392.47318 -217.548206)
			(xy 392.47318 -217.811096) (xy 392.52398 -217.811096)
		)
		(stroke
			(width 0)
			(type solid)
		)
		(fill yes)
		(layer "F.Cu")
		(net "M_E_CPU0_SB_DQ<20>")
	)
	(gr_poly
		(pts
			(xy 392.62558 -217.177874) (xy 392.62558 -216.987374) (xy 392.52398 -216.951306) (xy 392.47318 -216.951306)
			(xy 392.47318 -217.214196) (xy 392.52398 -217.214196)
		)
		(stroke
			(width 0)
			(type solid)
		)
		(fill yes)
		(layer "F.Cu")
		(net "M_E_CPU0_SB_DQ<20>")
	)
	(gr_poly
		(pts
			(xy 392.62558 -216.580974) (xy 392.62558 -216.390474) (xy 392.52398 -216.354406) (xy 392.47318 -216.354406)
			(xy 392.47318 -216.617296) (xy 392.52398 -216.617296)
		)
		(stroke
			(width 0)
			(type solid)
		)
		(fill yes)
		(layer "F.Cu")
		(net "M_E_CPU0_SB_DQ<20>")
	)
	(gr_poly
		(pts
			(xy 392.63574 -235.791248) (xy 392.589512 -235.693966) (xy 392.553698 -235.657898) (xy 392.36777 -235.843826)
			(xy 392.403584 -235.879894) (xy 392.50112 -235.926122)
		)
		(stroke
			(width 0)
			(type solid)
		)
		(fill yes)
		(layer "F.Cu")
		(net "M_E_CPU0_SB_DQ<11>")
	)
	(gr_poly
		(pts
			(xy 392.63955 -269.301722) (xy 392.685778 -269.204186) (xy 392.551158 -269.069566) (xy 392.453876 -269.115794)
			(xy 392.417808 -269.151608) (xy 392.603736 -269.337536)
		)
		(stroke
			(width 0)
			(type solid)
		)
		(fill yes)
		(layer "F.Cu")
		(net "M_E_CPU0_SA_DQ<28>")
	)
	(gr_poly
		(pts
			(xy 392.645392 -241.154966) (xy 392.609578 -241.119152) (xy 392.512042 -241.072924) (xy 392.377422 -241.207544)
			(xy 392.42365 -241.30508) (xy 392.459464 -241.340894)
		)
		(stroke
			(width 0)
			(type solid)
		)
		(fill yes)
		(layer "F.Cu")
		(net "M_E_CPU0_SB_CB<7>")
	)
	(gr_poly
		(pts
			(xy 392.645646 -236.64545) (xy 392.599418 -236.547914) (xy 392.563604 -236.5121) (xy 392.377676 -236.698028)
			(xy 392.41349 -236.733842) (xy 392.511026 -236.78007)
		)
		(stroke
			(width 0)
			(type solid)
		)
		(fill yes)
		(layer "F.Cu")
		(net "M_E_CPU0_SB_DQ<10>")
	)
	(gr_poly
		(pts
			(xy 392.647424 -275.823426) (xy 392.73988 -275.768054) (xy 392.702542 -275.581364) (xy 392.595862 -275.56587)
			(xy 392.546078 -275.575776) (xy 392.597386 -275.833586)
		)
		(stroke
			(width 0)
			(type solid)
		)
		(fill yes)
		(layer "F.Cu")
		(net "M_E_CPU0_SA_DQ<20>")
	)
	(gr_poly
		(pts
			(xy 392.648948 -268.448028) (xy 392.695176 -268.350746) (xy 392.560556 -268.215872) (xy 392.46302 -268.262354)
			(xy 392.427206 -268.298168) (xy 392.613134 -268.484096)
		)
		(stroke
			(width 0)
			(type solid)
		)
		(fill yes)
		(layer "F.Cu")
		(net "M_E_CPU0_SA_DQ<29>")
	)
	(gr_poly
		(pts
			(xy 392.654028 -238.341916) (xy 392.607546 -238.24438) (xy 392.571732 -238.208566) (xy 392.385804 -238.394494)
			(xy 392.421872 -238.430308) (xy 392.519154 -238.476536)
		)
		(stroke
			(width 0)
			(type solid)
		)
		(fill yes)
		(layer "F.Cu")
		(net "M_E_CPU0_SB_CB<1>")
	)
	(gr_poly
		(pts
			(xy 392.654536 -242.008406) (xy 392.618722 -241.972338) (xy 392.521186 -241.92611) (xy 392.386566 -242.060984)
			(xy 392.432794 -242.158266) (xy 392.468608 -242.194334)
		)
		(stroke
			(width 0)
			(type solid)
		)
		(fill yes)
		(layer "F.Cu")
		(net "M_E_CPU0_SB_CB<6>")
	)
	(gr_poly
		(pts
			(xy 392.65606 -276.126194) (xy 392.604498 -275.868384) (xy 392.554714 -275.87829) (xy 392.462004 -275.933662)
			(xy 392.499342 -276.120606) (xy 392.606276 -276.1361)
		)
		(stroke
			(width 0)
			(type solid)
		)
		(fill yes)
		(layer "F.Cu")
		(net "M_E_CPU0_SA_DQ<20>")
	)
	(gr_poly
		(pts
			(xy 392.663172 -239.195356) (xy 392.616944 -239.09782) (xy 392.580876 -239.062006) (xy 392.394948 -239.247934)
			(xy 392.431016 -239.283748) (xy 392.528298 -239.329976)
		)
		(stroke
			(width 0)
			(type solid)
		)
		(fill yes)
		(layer "F.Cu")
		(net "M_E_CPU0_SB_CB<0>")
	)
	(gr_poly
		(pts
			(xy 392.671554 -274.095972) (xy 392.717782 -273.998436) (xy 392.582908 -273.863816) (xy 392.485626 -273.910044)
			(xy 392.449558 -273.945858) (xy 392.635486 -274.131786)
		)
		(stroke
			(width 0)
			(type solid)
		)
		(fill yes)
		(layer "F.Cu")
		(net "M_E_CPU0_SA_DQ<21>")
	)
	(gr_poly
		(pts
			(xy 392.672824 -263.399524) (xy 392.719052 -263.301988) (xy 392.584432 -263.167368) (xy 392.486896 -263.213596)
			(xy 392.451082 -263.249664) (xy 392.636756 -263.435338)
		)
		(stroke
			(width 0)
			(type solid)
		)
		(fill yes)
		(layer "F.Cu")
		(net "M_E_CPU0_SA_CB<6>")
	)
	(gr_poly
		(pts
			(xy 392.680444 -272.39849) (xy 392.726672 -272.300954) (xy 392.591798 -272.166334) (xy 392.494516 -272.212562)
			(xy 392.458448 -272.248376) (xy 392.644376 -272.434304)
		)
		(stroke
			(width 0)
			(type solid)
		)
		(fill yes)
		(layer "F.Cu")
		(net "M_E_CPU0_SA_DQ<26>")
	)
	(gr_poly
		(pts
			(xy 392.681968 -262.546084) (xy 392.728196 -262.448802) (xy 392.593576 -262.313928) (xy 392.49604 -262.360156)
			(xy 392.460226 -262.396224) (xy 392.646154 -262.582152)
		)
		(stroke
			(width 0)
			(type solid)
		)
		(fill yes)
		(layer "F.Cu")
		(net "M_E_CPU0_SA_CB<7>")
	)
	(gr_poly
		(pts
			(xy 392.689588 -271.54505) (xy 392.735816 -271.447514) (xy 392.600942 -271.312894) (xy 392.50366 -271.359122)
			(xy 392.467592 -271.394936) (xy 392.65352 -271.580864)
		)
		(stroke
			(width 0)
			(type solid)
		)
		(fill yes)
		(layer "F.Cu")
		(net "M_E_CPU0_SA_DQ<27>")
	)
	(gr_poly
		(pts
			(xy 392.721846 -230.33355) (xy 392.685778 -230.297736) (xy 392.588496 -230.251508) (xy 392.453622 -230.386128)
			(xy 392.49985 -230.483664) (xy 392.535918 -230.519478)
		)
		(stroke
			(width 0)
			(type solid)
		)
		(fill yes)
		(layer "F.Cu")
		(net "M_E_CPU0_SB_DQ<17>")
	)
	(gr_poly
		(pts
			(xy 392.730482 -232.030778) (xy 392.694668 -231.99471) (xy 392.597132 -231.948482) (xy 392.462512 -232.083356)
			(xy 392.50874 -232.180638) (xy 392.544554 -232.216706)
		)
		(stroke
			(width 0)
			(type solid)
		)
		(fill yes)
		(layer "F.Cu")
		(net "M_E_CPU0_SB_DQ<15>")
	)
	(gr_poly
		(pts
			(xy 392.73099 -231.18699) (xy 392.695176 -231.151176) (xy 392.59764 -231.104948) (xy 392.46302 -231.239568)
			(xy 392.509248 -231.33685) (xy 392.545062 -231.372918)
		)
		(stroke
			(width 0)
			(type solid)
		)
		(fill yes)
		(layer "F.Cu")
		(net "M_E_CPU0_SB_DQ<16>")
	)
	(gr_poly
		(pts
			(xy 392.73226 -241.715036) (xy 392.685778 -241.6175) (xy 392.649964 -241.581686) (xy 392.464036 -241.767614)
			(xy 392.500104 -241.803428) (xy 392.597386 -241.849656)
		)
		(stroke
			(width 0)
			(type solid)
		)
		(fill yes)
		(layer "F.Cu")
		(net "M_E_CPU0_SB_CB<5>")
	)
	(gr_poly
		(pts
			(xy 392.73988 -232.883964) (xy 392.703812 -232.84815) (xy 392.60653 -232.801922) (xy 392.471656 -232.936542)
			(xy 392.517884 -233.034078) (xy 392.553952 -233.069892)
		)
		(stroke
			(width 0)
			(type solid)
		)
		(fill yes)
		(layer "F.Cu")
		(net "M_E_CPU0_SB_DQ<14>")
	)
	(gr_poly
		(pts
			(xy 392.754612 -267.076174) (xy 392.79068 -267.04036) (xy 392.604752 -266.854432) (xy 392.568684 -266.890246)
			(xy 392.522456 -266.987782) (xy 392.65733 -267.122402)
		)
		(stroke
			(width 0)
			(type solid)
		)
		(fill yes)
		(layer "F.Cu")
		(net "M_E_CPU0_SA_CB<2>")
	)
	(gr_poly
		(pts
			(xy 392.76401 -266.222734) (xy 392.799824 -266.18692) (xy 392.613896 -266.000992) (xy 392.578082 -266.03706)
			(xy 392.531854 -266.134342) (xy 392.666474 -266.269216)
		)
		(stroke
			(width 0)
			(type solid)
		)
		(fill yes)
		(layer "F.Cu")
		(net "M_E_CPU0_SA_CB<3>")
	)
	(gr_poly
		(pts
			(xy 392.764264 -276.408896) (xy 392.85672 -276.353524) (xy 392.819382 -276.16658) (xy 392.712702 -276.151086)
			(xy 392.662918 -276.160992) (xy 392.71448 -276.418802)
		)
		(stroke
			(width 0)
			(type solid)
		)
		(fill yes)
		(layer "F.Cu")
		(net "M_E_CPU0_SA_DQ<20>")
	)
	(gr_poly
		(pts
			(xy 392.764772 -235.447078) (xy 392.728704 -235.41101) (xy 392.631422 -235.364782) (xy 392.496548 -235.499402)
			(xy 392.542776 -235.596938) (xy 392.578844 -235.632752)
		)
		(stroke
			(width 0)
			(type solid)
		)
		(fill yes)
		(layer "F.Cu")
		(net "M_E_CPU0_SB_DQ<11>")
	)
	(gr_poly
		(pts
			(xy 392.7729 -276.71141) (xy 392.721338 -276.4536) (xy 392.671554 -276.46376) (xy 392.579098 -276.519132)
			(xy 392.616436 -276.705822) (xy 392.723116 -276.72157)
		)
		(stroke
			(width 0)
			(type solid)
		)
		(fill yes)
		(layer "F.Cu")
		(net "M_E_CPU0_SA_DQ<20>")
	)
	(gr_poly
		(pts
			(xy 392.774678 -236.301026) (xy 392.73861 -236.265212) (xy 392.641328 -236.218984) (xy 392.506454 -236.353604)
			(xy 392.552682 -236.45114) (xy 392.58875 -236.486954)
		)
		(stroke
			(width 0)
			(type solid)
		)
		(fill yes)
		(layer "F.Cu")
		(net "M_E_CPU0_SB_DQ<10>")
	)
	(gr_poly
		(pts
			(xy 392.778742 -269.584424) (xy 392.81481 -269.54861) (xy 392.628882 -269.362682) (xy 392.593068 -269.398496)
			(xy 392.546586 -269.496032) (xy 392.68146 -269.630652)
		)
		(stroke
			(width 0)
			(type solid)
		)
		(fill yes)
		(layer "F.Cu")
		(net "M_E_CPU0_SA_DQ<28>")
	)
	(gr_poly
		(pts
			(xy 392.782806 -237.997492) (xy 392.746738 -237.961678) (xy 392.649456 -237.91545) (xy 392.514836 -238.05007)
			(xy 392.561064 -238.147606) (xy 392.596878 -238.18342)
		)
		(stroke
			(width 0)
			(type solid)
		)
		(fill yes)
		(layer "F.Cu")
		(net "M_E_CPU0_SB_CB<1>")
	)
	(gr_poly
		(pts
			(xy 392.78814 -268.730984) (xy 392.824208 -268.69517) (xy 392.63828 -268.509242) (xy 392.602212 -268.545056)
			(xy 392.555984 -268.642592) (xy 392.690858 -268.777212)
		)
		(stroke
			(width 0)
			(type solid)
		)
		(fill yes)
		(layer "F.Cu")
		(net "M_E_CPU0_SA_DQ<29>")
	)
	(gr_poly
		(pts
			(xy 392.79195 -238.850932) (xy 392.756136 -238.814864) (xy 392.6586 -238.768636) (xy 392.52398 -238.90351)
			(xy 392.570208 -239.000792) (xy 392.606022 -239.03686)
		)
		(stroke
			(width 0)
			(type solid)
		)
		(fill yes)
		(layer "F.Cu")
		(net "M_E_CPU0_SB_CB<0>")
	)
	(gr_poly
		(pts
			(xy 392.799316 -230.04018) (xy 392.753088 -229.942898) (xy 392.717274 -229.90683) (xy 392.531346 -230.092758)
			(xy 392.56716 -230.128826) (xy 392.664696 -230.175054)
		)
		(stroke
			(width 0)
			(type solid)
		)
		(fill yes)
		(layer "F.Cu")
		(net "M_E_CPU0_SB_DQ<19>")
	)
	(gr_poly
		(pts
			(xy 392.80846 -230.89362) (xy 392.762232 -230.796338) (xy 392.726418 -230.76027) (xy 392.54049 -230.946198)
			(xy 392.576304 -230.982012) (xy 392.67384 -231.028494)
		)
		(stroke
			(width 0)
			(type solid)
		)
		(fill yes)
		(layer "F.Cu")
		(net "M_E_CPU0_SB_DQ<18>")
	)
	(gr_poly
		(pts
			(xy 392.812016 -263.68248) (xy 392.84783 -263.646412) (xy 392.661902 -263.460484) (xy 392.626088 -263.496552)
			(xy 392.57986 -263.593834) (xy 392.71448 -263.728708)
		)
		(stroke
			(width 0)
			(type solid)
		)
		(fill yes)
		(layer "F.Cu")
		(net "M_E_CPU0_SA_CB<6>")
	)
	(gr_poly
		(pts
			(xy 392.81735 -232.590848) (xy 392.771122 -232.493312) (xy 392.735054 -232.457498) (xy 392.54938 -232.643172)
			(xy 392.585194 -232.67924) (xy 392.68273 -232.725468)
		)
		(stroke
			(width 0)
			(type solid)
		)
		(fill yes)
		(layer "F.Cu")
		(net "M_E_CPU0_SB_DQ<13>")
	)
	(gr_poly
		(pts
			(xy 392.819636 -272.681192) (xy 392.85545 -272.645378) (xy 392.669522 -272.45945) (xy 392.633708 -272.495518)
			(xy 392.58748 -272.5928) (xy 392.7221 -272.727674)
		)
		(stroke
			(width 0)
			(type solid)
		)
		(fill yes)
		(layer "F.Cu")
		(net "M_E_CPU0_SA_DQ<26>")
	)
	(gr_poly
		(pts
			(xy 392.82116 -262.82904) (xy 392.857228 -262.793226) (xy 392.6713 -262.607298) (xy 392.635232 -262.643112)
			(xy 392.589004 -262.740648) (xy 392.723878 -262.875268)
		)
		(stroke
			(width 0)
			(type solid)
		)
		(fill yes)
		(layer "F.Cu")
		(net "M_E_CPU0_SA_CB<7>")
	)
	(gr_poly
		(pts
			(xy 392.821922 -267.431012) (xy 392.86815 -267.33373) (xy 392.73353 -267.198856) (xy 392.635994 -267.245084)
			(xy 392.60018 -267.281152) (xy 392.786108 -267.46708)
		)
		(stroke
			(width 0)
			(type solid)
		)
		(fill yes)
		(layer "F.Cu")
		(net "M_E_CPU0_SA_CB<0>")
	)
	(gr_poly
		(pts
			(xy 392.826494 -233.444034) (xy 392.780266 -233.346752) (xy 392.744452 -233.310684) (xy 392.558524 -233.496612)
			(xy 392.594338 -233.53268) (xy 392.691874 -233.578908)
		)
		(stroke
			(width 0)
			(type solid)
		)
		(fill yes)
		(layer "F.Cu")
		(net "M_E_CPU0_SB_DQ<12>")
	)
	(gr_poly
		(pts
			(xy 392.82878 -271.827752) (xy 392.864594 -271.791938) (xy 392.678666 -271.60601) (xy 392.642852 -271.642078)
			(xy 392.596624 -271.73936) (xy 392.731244 -271.874234)
		)
		(stroke
			(width 0)
			(type solid)
		)
		(fill yes)
		(layer "F.Cu")
		(net "M_E_CPU0_SA_DQ<27>")
	)
	(gr_poly
		(pts
			(xy 392.829542 -275.178266) (xy 392.921998 -275.122894) (xy 392.88466 -274.936204) (xy 392.77798 -274.92071)
			(xy 392.728196 -274.930616) (xy 392.779758 -275.188426)
		)
		(stroke
			(width 0)
			(type solid)
		)
		(fill yes)
		(layer "F.Cu")
		(net "M_E_CPU0_SA_DQ<22>")
	)
	(gr_poly
		(pts
			(xy 392.831066 -266.577572) (xy 392.877294 -266.48029) (xy 392.742674 -266.34567) (xy 392.645138 -266.391898)
			(xy 392.609324 -266.427712) (xy 392.795252 -266.61364)
		)
		(stroke
			(width 0)
			(type solid)
		)
		(fill yes)
		(layer "F.Cu")
		(net "M_E_CPU0_SA_CB<1>")
	)
	(gr_poly
		(pts
			(xy 392.838178 -275.481034) (xy 392.786616 -275.223224) (xy 392.736832 -275.23313) (xy 392.644376 -275.288502)
			(xy 392.681714 -275.475446) (xy 392.788394 -275.49094)
		)
		(stroke
			(width 0)
			(type solid)
		)
		(fill yes)
		(layer "F.Cu")
		(net "M_E_CPU0_SA_DQ<22>")
	)
	(gr_poly
		(pts
			(xy 392.85164 -236.007148) (xy 392.805412 -235.909612) (xy 392.769344 -235.873798) (xy 392.583416 -236.059726)
			(xy 392.619484 -236.09554) (xy 392.716766 -236.141768)
		)
		(stroke
			(width 0)
			(type solid)
		)
		(fill yes)
		(layer "F.Cu")
		(net "M_E_CPU0_SB_DQ<9>")
	)
	(gr_poly
		(pts
			(xy 392.855196 -269.086076) (xy 392.901424 -268.98854) (xy 392.766804 -268.85392) (xy 392.669522 -268.900148)
			(xy 392.633454 -268.935962) (xy 392.819382 -269.12189)
		)
		(stroke
			(width 0)
			(type solid)
		)
		(fill yes)
		(layer "F.Cu")
		(net "M_E_CPU0_SA_DQ<30>")
	)
	(gr_poly
		(pts
			(xy 392.860276 -237.704122) (xy 392.814048 -237.60684) (xy 392.778234 -237.570772) (xy 392.592306 -237.7567)
			(xy 392.62812 -237.792768) (xy 392.725656 -237.838996)
		)
		(stroke
			(width 0)
			(type solid)
		)
		(fill yes)
		(layer "F.Cu")
		(net "M_E_CPU0_SB_CB<3>")
	)
	(gr_poly
		(pts
			(xy 392.861038 -241.370612) (xy 392.825224 -241.334798) (xy 392.727688 -241.28857) (xy 392.593068 -241.42319)
			(xy 392.639296 -241.520726) (xy 392.67511 -241.55654)
		)
		(stroke
			(width 0)
			(type solid)
		)
		(fill yes)
		(layer "F.Cu")
		(net "M_E_CPU0_SB_CB<5>")
	)
	(gr_poly
		(pts
			(xy 392.861546 -236.86135) (xy 392.815318 -236.763814) (xy 392.77925 -236.728) (xy 392.593576 -236.913674)
			(xy 392.62939 -236.949742) (xy 392.726926 -236.99597)
		)
		(stroke
			(width 0)
			(type solid)
		)
		(fill yes)
		(layer "F.Cu")
		(net "M_E_CPU0_SB_DQ<8>")
	)
	(gr_poly
		(pts
			(xy 392.864848 -268.232382) (xy 392.911076 -268.134846) (xy 392.776202 -268.000226) (xy 392.67892 -268.046454)
			(xy 392.642852 -268.082268) (xy 392.82878 -268.268196)
		)
		(stroke
			(width 0)
			(type solid)
		)
		(fill yes)
		(layer "F.Cu")
		(net "M_E_CPU0_SA_DQ<31>")
	)
	(gr_poly
		(pts
			(xy 392.869674 -238.557562) (xy 392.823192 -238.460026) (xy 392.787378 -238.424212) (xy 392.60145 -238.61014)
			(xy 392.637518 -238.645954) (xy 392.7348 -238.692182)
		)
		(stroke
			(width 0)
			(type solid)
		)
		(fill yes)
		(layer "F.Cu")
		(net "M_E_CPU0_SB_CB<2>")
	)
	(gr_poly
		(pts
			(xy 392.870182 -242.224052) (xy 392.834368 -242.187984) (xy 392.736832 -242.141756) (xy 392.602212 -242.27663)
			(xy 392.64844 -242.373912) (xy 392.684254 -242.40998)
		)
		(stroke
			(width 0)
			(type solid)
		)
		(fill yes)
		(layer "F.Cu")
		(net "M_E_CPU0_SB_CB<4>")
	)
	(gr_poly
		(pts
			(xy 392.879326 -264.037318) (xy 392.925554 -263.939782) (xy 392.79068 -263.805162) (xy 392.693398 -263.85139)
			(xy 392.65733 -263.887204) (xy 392.843258 -264.073132)
		)
		(stroke
			(width 0)
			(type solid)
		)
		(fill yes)
		(layer "F.Cu")
		(net "M_E_CPU0_SA_CB<4>")
	)
	(gr_poly
		(pts
			(xy 392.881358 -276.994112) (xy 392.973814 -276.93874) (xy 392.936476 -276.75205) (xy 392.829796 -276.736302)
			(xy 392.780012 -276.746462) (xy 392.83132 -277.004272)
		)
		(stroke
			(width 0)
			(type solid)
		)
		(fill yes)
		(layer "F.Cu")
		(net "M_E_CPU0_SA_DQ<20>")
	)
	(gr_poly
		(pts
			(xy 392.886692 -273.036284) (xy 392.933174 -272.938748) (xy 392.7983 -272.804128) (xy 392.701018 -272.850356)
			(xy 392.66495 -272.88617) (xy 392.850878 -273.072098)
		)
		(stroke
			(width 0)
			(type solid)
		)
		(fill yes)
		(layer "F.Cu")
		(net "M_E_CPU0_SA_DQ<24>")
	)
	(gr_poly
		(pts
			(xy 392.8872 -273.880072) (xy 392.933428 -273.782536) (xy 392.798808 -273.647916) (xy 392.701272 -273.694144)
			(xy 392.665458 -273.730212) (xy 392.851132 -273.915886)
		)
		(stroke
			(width 0)
			(type solid)
		)
		(fill yes)
		(layer "F.Cu")
		(net "M_E_CPU0_SA_DQ<23>")
	)
	(gr_poly
		(pts
			(xy 392.888216 -248.967752) (xy 392.852148 -248.866152) (xy 392.661648 -248.866152) (xy 392.62558 -248.967752)
			(xy 392.62558 -249.018552) (xy 392.888216 -249.018552)
		)
		(stroke
			(width 0)
			(type solid)
		)
		(fill yes)
		(layer "F.Cu")
		(net "M_E_CPU0_SB_CA<0>")
	)
	(gr_poly
		(pts
			(xy 392.88847 -263.183878) (xy 392.934698 -263.086342) (xy 392.800078 -262.951722) (xy 392.702542 -262.99795)
			(xy 392.666728 -263.034018) (xy 392.852402 -263.219692)
		)
		(stroke
			(width 0)
			(type solid)
		)
		(fill yes)
		(layer "F.Cu")
		(net "M_E_CPU0_SA_CB<5>")
	)
	(gr_poly
		(pts
			(xy 392.889994 -277.29688) (xy 392.838432 -277.03907) (xy 392.788648 -277.048976) (xy 392.695938 -277.104348)
			(xy 392.733276 -277.291292) (xy 392.84021 -277.306786)
		)
		(stroke
			(width 0)
			(type solid)
		)
		(fill yes)
		(layer "F.Cu")
		(net "M_E_CPU0_SA_DQ<20>")
	)
	(gr_poly
		(pts
			(xy 392.895836 -272.182844) (xy 392.942318 -272.085308) (xy 392.807444 -271.950688) (xy 392.710162 -271.996916)
			(xy 392.674094 -272.03273) (xy 392.860022 -272.218658)
		)
		(stroke
			(width 0)
			(type solid)
		)
		(fill yes)
		(layer "F.Cu")
		(net "M_E_CPU0_SA_DQ<25>")
	)
	(gr_poly
		(pts
			(xy 392.928094 -229.69601) (xy 392.89228 -229.659942) (xy 392.794744 -229.613714) (xy 392.660124 -229.748334)
			(xy 392.706352 -229.84587) (xy 392.74242 -229.881684)
		)
		(stroke
			(width 0)
			(type solid)
		)
		(fill yes)
		(layer "F.Cu")
		(net "M_E_CPU0_SB_DQ<19>")
	)
	(gr_poly
		(pts
			(xy 392.937492 -230.549196) (xy 392.901424 -230.513382) (xy 392.804142 -230.467154) (xy 392.669268 -230.601774)
			(xy 392.715496 -230.69931) (xy 392.751564 -230.735124)
		)
		(stroke
			(width 0)
			(type solid)
		)
		(fill yes)
		(layer "F.Cu")
		(net "M_E_CPU0_SB_DQ<18>")
	)
	(gr_poly
		(pts
			(xy 392.938508 -241.077242) (xy 392.89228 -240.97996) (xy 392.856466 -240.943892) (xy 392.670538 -241.12982)
			(xy 392.706352 -241.165634) (xy 392.803888 -241.212116)
		)
		(stroke
			(width 0)
			(type solid)
		)
		(fill yes)
		(layer "F.Cu")
		(net "M_E_CPU0_SB_CB<7>")
	)
	(gr_poly
		(pts
			(xy 392.946128 -232.246424) (xy 392.910314 -232.210356) (xy 392.812778 -232.164128) (xy 392.678158 -232.299002)
			(xy 392.724386 -232.396284) (xy 392.7602 -232.432352)
		)
		(stroke
			(width 0)
			(type solid)
		)
		(fill yes)
		(layer "F.Cu")
		(net "M_E_CPU0_SB_DQ<13>")
	)
	(gr_poly
		(pts
			(xy 392.946636 -275.763736) (xy 393.039092 -275.708364) (xy 393.001754 -275.52142) (xy 392.89482 -275.505926)
			(xy 392.845036 -275.515832) (xy 392.896598 -275.773642)
		)
		(stroke
			(width 0)
			(type solid)
		)
		(fill yes)
		(layer "F.Cu")
		(net "M_E_CPU0_SA_DQ<22>")
	)
	(gr_poly
		(pts
			(xy 392.947906 -241.930682) (xy 392.901424 -241.833146) (xy 392.86561 -241.797332) (xy 392.679682 -241.98326)
			(xy 392.71575 -242.019074) (xy 392.813032 -242.065302)
		)
		(stroke
			(width 0)
			(type solid)
		)
		(fill yes)
		(layer "F.Cu")
		(net "M_E_CPU0_SB_CB<6>")
	)
	(gr_poly
		(pts
			(xy 392.955272 -276.06625) (xy 392.90371 -275.80844) (xy 392.853926 -275.8186) (xy 392.761216 -275.873972)
			(xy 392.798554 -276.060662) (xy 392.905488 -276.076156)
		)
		(stroke
			(width 0)
			(type solid)
		)
		(fill yes)
		(layer "F.Cu")
		(net "M_E_CPU0_SA_DQ<22>")
	)
	(gr_poly
		(pts
			(xy 392.955526 -233.09961) (xy 392.919458 -233.063796) (xy 392.822176 -233.017568) (xy 392.687302 -233.152188)
			(xy 392.73353 -233.249724) (xy 392.769598 -233.285538)
		)
		(stroke
			(width 0)
			(type solid)
		)
		(fill yes)
		(layer "F.Cu")
		(net "M_E_CPU0_SB_DQ<12>")
	)
	(gr_poly
		(pts
			(xy 392.961114 -267.713968) (xy 392.996928 -267.6779) (xy 392.811254 -267.492226) (xy 392.775186 -267.52804)
			(xy 392.728958 -267.625576) (xy 392.863578 -267.760196)
		)
		(stroke
			(width 0)
			(type solid)
		)
		(fill yes)
		(layer "F.Cu")
		(net "M_E_CPU0_SA_CB<0>")
	)
	(gr_poly
		(pts
			(xy 392.970258 -266.860528) (xy 393.006326 -266.824714) (xy 392.820398 -266.638786) (xy 392.78433 -266.6746)
			(xy 392.738102 -266.772136) (xy 392.872976 -266.906756)
		)
		(stroke
			(width 0)
			(type solid)
		)
		(fill yes)
		(layer "F.Cu")
		(net "M_E_CPU0_SA_CB<1>")
	)
	(gr_poly
		(pts
			(xy 392.980418 -235.662724) (xy 392.944604 -235.62691) (xy 392.847068 -235.580682) (xy 392.712448 -235.715302)
			(xy 392.758676 -235.812838) (xy 392.79449 -235.848652)
		)
		(stroke
			(width 0)
			(type solid)
		)
		(fill yes)
		(layer "F.Cu")
		(net "M_E_CPU0_SB_DQ<9>")
	)
	(gr_poly
		(pts
			(xy 392.989308 -237.359698) (xy 392.95324 -237.323884) (xy 392.855958 -237.277656) (xy 392.721084 -237.412276)
			(xy 392.767312 -237.509812) (xy 392.80338 -237.545626)
		)
		(stroke
			(width 0)
			(type solid)
		)
		(fill yes)
		(layer "F.Cu")
		(net "M_E_CPU0_SB_CB<3>")
	)
	(gr_poly
		(pts
			(xy 392.990324 -236.516926) (xy 392.95451 -236.480858) (xy 392.856974 -236.43463) (xy 392.722354 -236.569504)
			(xy 392.768582 -236.666786) (xy 392.804396 -236.702854)
		)
		(stroke
			(width 0)
			(type solid)
		)
		(fill yes)
		(layer "F.Cu")
		(net "M_E_CPU0_SB_DQ<8>")
	)
	(gr_poly
		(pts
			(xy 392.994388 -269.368778) (xy 393.030456 -269.332964) (xy 392.844528 -269.147036) (xy 392.808714 -269.18285)
			(xy 392.762232 -269.280386) (xy 392.897106 -269.415006)
		)
		(stroke
			(width 0)
			(type solid)
		)
		(fill yes)
		(layer "F.Cu")
		(net "M_E_CPU0_SA_DQ<30>")
	)
	(gr_poly
		(pts
			(xy 392.998198 -277.579582) (xy 393.090654 -277.52421) (xy 393.053316 -277.337266) (xy 392.946636 -277.321772)
			(xy 392.896852 -277.331678) (xy 392.948414 -277.589488)
		)
		(stroke
			(width 0)
			(type solid)
		)
		(fill yes)
		(layer "F.Cu")
		(net "M_E_CPU0_SA_DQ<20>")
	)
	(gr_poly
		(pts
			(xy 392.998452 -238.213138) (xy 392.962384 -238.177324) (xy 392.865102 -238.131096) (xy 392.730482 -238.265716)
			(xy 392.77671 -238.363252) (xy 392.812524 -238.399066)
		)
		(stroke
			(width 0)
			(type solid)
		)
		(fill yes)
		(layer "F.Cu")
		(net "M_E_CPU0_SB_CB<2>")
	)
	(gr_poly
		(pts
			(xy 393.00404 -268.515338) (xy 393.039854 -268.47927) (xy 392.853926 -268.293342) (xy 392.818112 -268.32941)
			(xy 392.771884 -268.426692) (xy 392.906504 -268.561566)
		)
		(stroke
			(width 0)
			(type solid)
		)
		(fill yes)
		(layer "F.Cu")
		(net "M_E_CPU0_SA_DQ<31>")
	)
	(gr_poly
		(pts
			(xy 393.006834 -277.882096) (xy 392.955272 -277.624286) (xy 392.905488 -277.634192) (xy 392.813032 -277.689818)
			(xy 392.85037 -277.876508) (xy 392.95705 -277.892002)
		)
		(stroke
			(width 0)
			(type solid)
		)
		(fill yes)
		(layer "F.Cu")
		(net "M_E_CPU0_SA_DQ<20>")
	)
	(gr_poly
		(pts
			(xy 393.014962 -230.255826) (xy 392.968734 -230.158544) (xy 392.93292 -230.122476) (xy 392.746992 -230.308404)
			(xy 392.782806 -230.344472) (xy 392.880342 -230.3907)
		)
		(stroke
			(width 0)
			(type solid)
		)
		(fill yes)
		(layer "F.Cu")
		(net "M_E_CPU0_SB_DQ<17>")
	)
	(gr_poly
		(pts
			(xy 393.018518 -264.32002) (xy 393.054332 -264.284206) (xy 392.868404 -264.098278) (xy 392.83259 -264.134346)
			(xy 392.786362 -264.231628) (xy 392.920982 -264.366248)
		)
		(stroke
			(width 0)
			(type solid)
		)
		(fill yes)
		(layer "F.Cu")
		(net "M_E_CPU0_SA_CB<4>")
	)
	(gr_poly
		(pts
			(xy 393.020296 -274.835874) (xy 392.968734 -274.578064) (xy 392.91895 -274.58797) (xy 392.826494 -274.643342)
			(xy 392.863832 -274.830286) (xy 392.970512 -274.84578)
		)
		(stroke
			(width 0)
			(type solid)
		)
		(fill yes)
		(layer "F.Cu")
		(net "M_E_CPU0_SA_DQ<21>")
	)
	(gr_poly
		(pts
			(xy 393.023852 -231.953054) (xy 392.977624 -231.855518) (xy 392.941556 -231.819704) (xy 392.755628 -232.005632)
			(xy 392.791696 -232.041446) (xy 392.888978 -232.087674)
		)
		(stroke
			(width 0)
			(type solid)
		)
		(fill yes)
		(layer "F.Cu")
		(net "M_E_CPU0_SB_DQ<15>")
	)
	(gr_poly
		(pts
			(xy 393.024106 -231.109266) (xy 392.977878 -231.011984) (xy 392.942064 -230.975916) (xy 392.756136 -231.161844)
			(xy 392.79195 -231.197658) (xy 392.889486 -231.24414)
		)
		(stroke
			(width 0)
			(type solid)
		)
		(fill yes)
		(layer "F.Cu")
		(net "M_E_CPU0_SB_DQ<16>")
	)
	(gr_poly
		(pts
			(xy 393.025884 -273.318986) (xy 393.061952 -273.283172) (xy 392.876024 -273.097244) (xy 392.84021 -273.133058)
			(xy 392.793728 -273.230594) (xy 392.928602 -273.365214)
		)
		(stroke
			(width 0)
			(type solid)
		)
		(fill yes)
		(layer "F.Cu")
		(net "M_E_CPU0_SA_DQ<24>")
	)
	(gr_poly
		(pts
			(xy 393.026392 -274.163028) (xy 393.062206 -274.12696) (xy 392.876278 -273.941032) (xy 392.840464 -273.9771)
			(xy 392.794236 -274.074382) (xy 392.928856 -274.209256)
		)
		(stroke
			(width 0)
			(type solid)
		)
		(fill yes)
		(layer "F.Cu")
		(net "M_E_CPU0_SA_DQ<23>")
	)
	(gr_poly
		(pts
			(xy 393.027662 -263.466834) (xy 393.063476 -263.430766) (xy 392.877548 -263.244838) (xy 392.841734 -263.280906)
			(xy 392.795506 -263.378188) (xy 392.930126 -263.513062)
		)
		(stroke
			(width 0)
			(type solid)
		)
		(fill yes)
		(layer "F.Cu")
		(net "M_E_CPU0_SA_CB<5>")
	)
	(gr_poly
		(pts
			(xy 393.032996 -232.806494) (xy 392.986768 -232.708958) (xy 392.9507 -232.673144) (xy 392.765026 -232.858818)
			(xy 392.80084 -232.894886) (xy 392.898376 -232.941114)
		)
		(stroke
			(width 0)
			(type solid)
		)
		(fill yes)
		(layer "F.Cu")
		(net "M_E_CPU0_SB_DQ<14>")
	)
	(gr_poly
		(pts
			(xy 393.035028 -272.465546) (xy 393.071096 -272.429732) (xy 392.885168 -272.243804) (xy 392.849354 -272.279618)
			(xy 392.803126 -272.377154) (xy 392.937746 -272.511774)
		)
		(stroke
			(width 0)
			(type solid)
		)
		(fill yes)
		(layer "F.Cu")
		(net "M_E_CPU0_SA_DQ<25>")
	)
	(gr_poly
		(pts
			(xy 393.037568 -267.215366) (xy 393.083796 -267.118084) (xy 392.949176 -266.98321) (xy 392.85164 -267.029438)
			(xy 392.815826 -267.065506) (xy 393.001754 -267.251434)
		)
		(stroke
			(width 0)
			(type solid)
		)
		(fill yes)
		(layer "F.Cu")
		(net "M_E_CPU0_SA_CB<2>")
	)
	(gr_poly
		(pts
			(xy 393.046712 -266.361926) (xy 393.09294 -266.264644) (xy 392.95832 -266.130024) (xy 392.860784 -266.176252)
			(xy 392.82497 -266.212066) (xy 393.010898 -266.397994)
		)
		(stroke
			(width 0)
			(type solid)
		)
		(fill yes)
		(layer "F.Cu")
		(net "M_E_CPU0_SA_CB<3>")
	)
	(gr_poly
		(pts
			(xy 393.057888 -235.369354) (xy 393.01166 -235.271818) (xy 392.975592 -235.236004) (xy 392.789664 -235.421678)
			(xy 392.825732 -235.457746) (xy 392.923014 -235.503974)
		)
		(stroke
			(width 0)
			(type solid)
		)
		(fill yes)
		(layer "F.Cu")
		(net "M_E_CPU0_SB_DQ<11>")
	)
	(gr_poly
		(pts
			(xy 393.061698 -269.723616) (xy 393.107926 -269.626334) (xy 392.973306 -269.49146) (xy 392.87577 -269.537688)
			(xy 392.839956 -269.573756) (xy 393.025884 -269.759684)
		)
		(stroke
			(width 0)
			(type solid)
		)
		(fill yes)
		(layer "F.Cu")
		(net "M_E_CPU0_SA_DQ<28>")
	)
	(gr_poly
		(pts
			(xy 393.063476 -276.348952) (xy 393.156186 -276.29358) (xy 393.118848 -276.10689) (xy 393.011914 -276.091142)
			(xy 392.96213 -276.101302) (xy 393.013692 -276.358858)
		)
		(stroke
			(width 0)
			(type solid)
		)
		(fill yes)
		(layer "F.Cu")
		(net "M_E_CPU0_SA_DQ<22>")
	)
	(gr_poly
		(pts
			(xy 393.06754 -240.732818) (xy 393.031472 -240.697004) (xy 392.93419 -240.650776) (xy 392.799316 -240.785396)
			(xy 392.845544 -240.882932) (xy 392.881612 -240.918746)
		)
		(stroke
			(width 0)
			(type solid)
		)
		(fill yes)
		(layer "F.Cu")
		(net "M_E_CPU0_SB_CB<7>")
	)
	(gr_poly
		(pts
			(xy 393.067794 -236.223302) (xy 393.021566 -236.12602) (xy 392.985752 -236.089952) (xy 392.799824 -236.27588)
			(xy 392.835638 -236.311948) (xy 392.933174 -236.358176)
		)
		(stroke
			(width 0)
			(type solid)
		)
		(fill yes)
		(layer "F.Cu")
		(net "M_E_CPU0_SB_DQ<10>")
	)
	(gr_poly
		(pts
			(xy 393.071096 -268.870176) (xy 393.117324 -268.77264) (xy 392.982704 -268.63802) (xy 392.885168 -268.684248)
			(xy 392.849354 -268.720316) (xy 393.035028 -268.90599)
		)
		(stroke
			(width 0)
			(type solid)
		)
		(fill yes)
		(layer "F.Cu")
		(net "M_E_CPU0_SA_DQ<29>")
	)
	(gr_poly
		(pts
			(xy 393.072366 -276.65172) (xy 393.020804 -276.39391) (xy 392.97102 -276.403816) (xy 392.87831 -276.459188)
			(xy 392.915648 -276.646132) (xy 393.022582 -276.661626)
		)
		(stroke
			(width 0)
			(type solid)
		)
		(fill yes)
		(layer "F.Cu")
		(net "M_E_CPU0_SA_DQ<22>")
	)
	(gr_poly
		(pts
			(xy 393.075922 -237.919768) (xy 393.029694 -237.822486) (xy 392.99388 -237.786418) (xy 392.807952 -237.972346)
			(xy 392.843766 -238.008414) (xy 392.941302 -238.054642)
		)
		(stroke
			(width 0)
			(type solid)
		)
		(fill yes)
		(layer "F.Cu")
		(net "M_E_CPU0_SB_CB<1>")
	)
	(gr_poly
		(pts
			(xy 393.076684 -241.586258) (xy 393.04087 -241.550444) (xy 392.943334 -241.504216) (xy 392.808714 -241.638836)
			(xy 392.854942 -241.736372) (xy 392.890756 -241.772186)
		)
		(stroke
			(width 0)
			(type solid)
		)
		(fill yes)
		(layer "F.Cu")
		(net "M_E_CPU0_SB_CB<6>")
	)
	(gr_poly
		(pts
			(xy 393.08532 -238.773208) (xy 393.038838 -238.675672) (xy 393.003024 -238.639858) (xy 392.817096 -238.825786)
			(xy 392.853164 -238.8616) (xy 392.950446 -238.907828)
		)
		(stroke
			(width 0)
			(type solid)
		)
		(fill yes)
		(layer "F.Cu")
		(net "M_E_CPU0_SB_CB<0>")
	)
	(gr_poly
		(pts
			(xy 393.094972 -263.821672) (xy 393.1412 -263.724136) (xy 393.006326 -263.589516) (xy 392.909044 -263.635744)
			(xy 392.872976 -263.671558) (xy 393.058904 -263.857486)
		)
		(stroke
			(width 0)
			(type solid)
		)
		(fill yes)
		(layer "F.Cu")
		(net "M_E_CPU0_SA_CB<6>")
	)
	(gr_poly
		(pts
			(xy 393.102338 -272.820384) (xy 393.148566 -272.723102) (xy 393.013946 -272.588482) (xy 392.91641 -272.63471)
			(xy 392.880596 -272.670524) (xy 393.066524 -272.856452)
		)
		(stroke
			(width 0)
			(type solid)
		)
		(fill yes)
		(layer "F.Cu")
		(net "M_E_CPU0_SA_DQ<26>")
	)
	(gr_poly
		(pts
			(xy 393.104116 -262.968232) (xy 393.150344 -262.870696) (xy 393.015724 -262.736076) (xy 392.918188 -262.782304)
			(xy 392.882374 -262.818372) (xy 393.068048 -263.004046)
		)
		(stroke
			(width 0)
			(type solid)
		)
		(fill yes)
		(layer "F.Cu")
		(net "M_E_CPU0_SA_CB<7>")
	)
	(gr_poly
		(pts
			(xy 393.111482 -271.966944) (xy 393.15771 -271.869662) (xy 393.02309 -271.735042) (xy 392.925554 -271.78127)
			(xy 392.88974 -271.817084) (xy 393.075668 -272.003012)
		)
		(stroke
			(width 0)
			(type solid)
		)
		(fill yes)
		(layer "F.Cu")
		(net "M_E_CPU0_SA_DQ<27>")
	)
	(gr_poly
		(pts
			(xy 393.115292 -278.164798) (xy 393.207748 -278.109426) (xy 393.17041 -277.922736) (xy 393.06373 -277.906988)
			(xy 393.013946 -277.916894) (xy 393.065254 -278.174704)
		)
		(stroke
			(width 0)
			(type solid)
		)
		(fill yes)
		(layer "F.Cu")
		(net "M_E_CPU0_SA_DQ<20>")
	)
	(gr_poly
		(pts
			(xy 393.123928 -278.467566) (xy 393.072366 -278.209756) (xy 393.022582 -278.219662) (xy 392.929872 -278.275034)
			(xy 392.96721 -278.461978) (xy 393.074144 -278.477472)
		)
		(stroke
			(width 0)
			(type solid)
		)
		(fill yes)
		(layer "F.Cu")
		(net "M_E_CPU0_SA_DQ<20>")
	)
	(gr_poly
		(pts
			(xy 393.128754 -275.118576) (xy 393.22121 -275.063204) (xy 393.183872 -274.87626) (xy 393.077192 -274.860766)
			(xy 393.027408 -274.870672) (xy 393.07897 -275.128482)
		)
		(stroke
			(width 0)
			(type solid)
		)
		(fill yes)
		(layer "F.Cu")
		(net "M_E_CPU0_SA_DQ<21>")
	)
	(gr_poly
		(pts
			(xy 393.13739 -275.42109) (xy 393.085828 -275.16328) (xy 393.036044 -275.17344) (xy 392.943588 -275.228812)
			(xy 392.980926 -275.415502) (xy 393.087606 -275.430996)
		)
		(stroke
			(width 0)
			(type solid)
		)
		(fill yes)
		(layer "F.Cu")
		(net "M_E_CPU0_SA_DQ<21>")
	)
	(gr_poly
		(pts
			(xy 393.14374 -229.911656) (xy 393.107926 -229.875588) (xy 393.01039 -229.82936) (xy 392.87577 -229.96398)
			(xy 392.921998 -230.061516) (xy 392.958066 -230.09733)
		)
		(stroke
			(width 0)
			(type solid)
		)
		(fill yes)
		(layer "F.Cu")
		(net "M_E_CPU0_SB_DQ<17>")
	)
	(gr_poly
		(pts
			(xy 393.15263 -231.60863) (xy 393.116816 -231.572816) (xy 393.01928 -231.526588) (xy 392.88466 -231.661208)
			(xy 392.930888 -231.75849) (xy 392.966702 -231.794558)
		)
		(stroke
			(width 0)
			(type solid)
		)
		(fill yes)
		(layer "F.Cu")
		(net "M_E_CPU0_SB_DQ<15>")
	)
	(gr_poly
		(pts
			(xy 393.153138 -230.764842) (xy 393.11707 -230.729028) (xy 393.019788 -230.6828) (xy 392.884914 -230.81742)
			(xy 392.931142 -230.914956) (xy 392.96721 -230.95077)
		)
		(stroke
			(width 0)
			(type solid)
		)
		(fill yes)
		(layer "F.Cu")
		(net "M_E_CPU0_SB_DQ<16>")
	)
	(gr_poly
		(pts
			(xy 393.154154 -241.292888) (xy 393.107926 -241.195606) (xy 393.072112 -241.159538) (xy 392.886184 -241.345466)
			(xy 392.921998 -241.38128) (xy 393.019534 -241.427762)
		)
		(stroke
			(width 0)
			(type solid)
		)
		(fill yes)
		(layer "F.Cu")
		(net "M_E_CPU0_SB_CB<5>")
	)
	(gr_poly
		(pts
			(xy 393.161774 -232.46207) (xy 393.12596 -232.426002) (xy 393.028424 -232.379774) (xy 392.893804 -232.514648)
			(xy 392.940032 -232.61193) (xy 392.975846 -232.647998)
		)
		(stroke
			(width 0)
			(type solid)
		)
		(fill yes)
		(layer "F.Cu")
		(net "M_E_CPU0_SB_DQ<14>")
	)
	(gr_poly
		(pts
			(xy 393.163552 -242.146328) (xy 393.11707 -242.048792) (xy 393.081256 -242.012978) (xy 392.895328 -242.198906)
			(xy 392.931396 -242.23472) (xy 393.028678 -242.280948)
		)
		(stroke
			(width 0)
			(type solid)
		)
		(fill yes)
		(layer "F.Cu")
		(net "M_E_CPU0_SB_CB<4>")
	)
	(gr_poly
		(pts
			(xy 393.17676 -267.498322) (xy 393.212574 -267.462254) (xy 393.0269 -267.27658) (xy 392.990832 -267.312394)
			(xy 392.944604 -267.40993) (xy 393.079224 -267.54455)
		)
		(stroke
			(width 0)
			(type solid)
		)
		(fill yes)
		(layer "F.Cu")
		(net "M_E_CPU0_SA_CB<2>")
	)
	(gr_poly
		(pts
			(xy 393.18057 -276.934422) (xy 393.273026 -276.878796) (xy 393.235688 -276.692106) (xy 393.129008 -276.676612)
			(xy 393.079224 -276.686518) (xy 393.130786 -276.944328)
		)
		(stroke
			(width 0)
			(type solid)
		)
		(fill yes)
		(layer "F.Cu")
		(net "M_E_CPU0_SA_DQ<22>")
	)
	(gr_poly
		(pts
			(xy 393.185904 -266.644882) (xy 393.221972 -266.609068) (xy 393.036044 -266.42314) (xy 392.999976 -266.458954)
			(xy 392.953748 -266.55649) (xy 393.088622 -266.69111)
		)
		(stroke
			(width 0)
			(type solid)
		)
		(fill yes)
		(layer "F.Cu")
		(net "M_E_CPU0_SA_CB<3>")
	)
	(gr_poly
		(pts
			(xy 393.186666 -235.02493) (xy 393.150852 -234.988862) (xy 393.053316 -234.942634) (xy 392.918696 -235.077508)
			(xy 392.964924 -235.17479) (xy 393.000738 -235.210858)
		)
		(stroke
			(width 0)
			(type solid)
		)
		(fill yes)
		(layer "F.Cu")
		(net "M_E_CPU0_SB_DQ<11>")
	)
	(gr_poly
		(pts
			(xy 393.189206 -277.236936) (xy 393.137898 -276.979126) (xy 393.08786 -276.989032) (xy 392.995404 -277.044404)
			(xy 393.032742 -277.231348) (xy 393.139422 -277.246842)
		)
		(stroke
			(width 0)
			(type solid)
		)
		(fill yes)
		(layer "F.Cu")
		(net "M_E_CPU0_SA_DQ<22>")
	)
	(gr_poly
		(pts
			(xy 393.196572 -235.879132) (xy 393.160758 -235.843064) (xy 393.063222 -235.796836) (xy 392.928602 -235.931456)
			(xy 392.97483 -236.028992) (xy 393.010898 -236.064806)
		)
		(stroke
			(width 0)
			(type solid)
		)
		(fill yes)
		(layer "F.Cu")
		(net "M_E_CPU0_SB_DQ<10>")
	)
	(gr_poly
		(pts
			(xy 393.20089 -270.006572) (xy 393.236958 -269.970758) (xy 393.05103 -269.78483) (xy 393.014962 -269.820644)
			(xy 392.968734 -269.91818) (xy 393.103608 -270.0528)
		)
		(stroke
			(width 0)
			(type solid)
		)
		(fill yes)
		(layer "F.Cu")
		(net "M_E_CPU0_SA_DQ<28>")
	)
	(gr_poly
		(pts
			(xy 393.204954 -237.575344) (xy 393.168886 -237.53953) (xy 393.071604 -237.493302) (xy 392.93673 -237.627922)
			(xy 392.982958 -237.725458) (xy 393.019026 -237.761272)
		)
		(stroke
			(width 0)
			(type solid)
		)
		(fill yes)
		(layer "F.Cu")
		(net "M_E_CPU0_SB_CB<1>")
	)
	(gr_poly
		(pts
			(xy 393.210288 -269.153132) (xy 393.246102 -269.117064) (xy 393.060174 -268.931136) (xy 393.02436 -268.967204)
			(xy 392.978132 -269.06474) (xy 393.112752 -269.19936)
		)
		(stroke
			(width 0)
			(type solid)
		)
		(fill yes)
		(layer "F.Cu")
		(net "M_E_CPU0_SA_DQ<29>")
	)
	(gr_poly
		(pts
			(xy 393.214098 -238.428784) (xy 393.17803 -238.39297) (xy 393.080748 -238.346742) (xy 392.946128 -238.481362)
			(xy 392.992356 -238.578898) (xy 393.02817 -238.614712)
		)
		(stroke
			(width 0)
			(type solid)
		)
		(fill yes)
		(layer "F.Cu")
		(net "M_E_CPU0_SB_CB<0>")
	)
	(gr_poly
		(pts
			(xy 393.221464 -229.618286) (xy 393.175236 -229.52075) (xy 393.139168 -229.484936) (xy 392.95324 -229.670864)
			(xy 392.989308 -229.706678) (xy 393.08659 -229.752906)
		)
		(stroke
			(width 0)
			(type solid)
		)
		(fill yes)
		(layer "F.Cu")
		(net "M_E_CPU0_SB_DQ<19>")
	)
	(gr_poly
		(pts
			(xy 393.230608 -230.471472) (xy 393.18438 -230.37419) (xy 393.148566 -230.338122) (xy 392.962638 -230.52405)
			(xy 392.998452 -230.560118) (xy 393.095988 -230.606346)
		)
		(stroke
			(width 0)
			(type solid)
		)
		(fill yes)
		(layer "F.Cu")
		(net "M_E_CPU0_SB_DQ<18>")
	)
	(gr_poly
		(pts
			(xy 393.232132 -278.750268) (xy 393.324588 -278.694642) (xy 393.28725 -278.507952) (xy 393.18057 -278.492458)
			(xy 393.130786 -278.502364) (xy 393.182348 -278.760174)
		)
		(stroke
			(width 0)
			(type solid)
		)
		(fill yes)
		(layer "F.Cu")
		(net "M_E_CPU0_SA_DQ<20>")
	)
	(gr_poly
		(pts
			(xy 393.234164 -264.104374) (xy 393.269978 -264.06856) (xy 393.08405 -263.882632) (xy 393.048236 -263.9187)
			(xy 393.002008 -264.015982) (xy 393.136628 -264.150602)
		)
		(stroke
			(width 0)
			(type solid)
		)
		(fill yes)
		(layer "F.Cu")
		(net "M_E_CPU0_SA_CB<6>")
	)
	(gr_poly
		(pts
			(xy 393.239498 -232.1687) (xy 393.19327 -232.071164) (xy 393.157202 -232.03535) (xy 392.971274 -232.221278)
			(xy 393.007342 -232.257092) (xy 393.104624 -232.30332)
		)
		(stroke
			(width 0)
			(type solid)
		)
		(fill yes)
		(layer "F.Cu")
		(net "M_E_CPU0_SB_DQ<13>")
	)
	(gr_poly
		(pts
			(xy 393.240768 -279.052782) (xy 393.189206 -278.794972) (xy 393.139422 -278.804878) (xy 393.046966 -278.860504)
			(xy 393.084304 -279.047194) (xy 393.190984 -279.062688)
		)
		(stroke
			(width 0)
			(type solid)
		)
		(fill yes)
		(layer "F.Cu")
		(net "M_E_CPU0_SA_DQ<20>")
	)
	(gr_poly
		(pts
			(xy 393.24153 -273.10334) (xy 393.277598 -273.067526) (xy 393.09167 -272.881598) (xy 393.055602 -272.917412)
			(xy 393.009374 -273.014948) (xy 393.144248 -273.149568)
		)
		(stroke
			(width 0)
			(type solid)
		)
		(fill yes)
		(layer "F.Cu")
		(net "M_E_CPU0_SA_DQ<26>")
	)
	(gr_poly
		(pts
			(xy 393.243308 -263.251188) (xy 393.279122 -263.21512) (xy 393.093194 -263.029192) (xy 393.05738 -263.06526)
			(xy 393.011152 -263.162542) (xy 393.145772 -263.297416)
		)
		(stroke
			(width 0)
			(type solid)
		)
		(fill yes)
		(layer "F.Cu")
		(net "M_E_CPU0_SA_CB<7>")
	)
	(gr_poly
		(pts
			(xy 393.24407 -267.85316) (xy 393.290298 -267.755624) (xy 393.155424 -267.621004) (xy 393.058142 -267.667232)
			(xy 393.022074 -267.703046) (xy 393.208002 -267.888974)
		)
		(stroke
			(width 0)
			(type solid)
		)
		(fill yes)
		(layer "F.Cu")
		(net "M_E_CPU0_SA_CB<0>")
	)
	(gr_poly
		(pts
			(xy 393.245848 -275.703792) (xy 393.338304 -275.64842) (xy 393.300966 -275.461476) (xy 393.194286 -275.445982)
			(xy 393.144502 -275.455888) (xy 393.196064 -275.713698)
		)
		(stroke
			(width 0)
			(type solid)
		)
		(fill yes)
		(layer "F.Cu")
		(net "M_E_CPU0_SA_DQ<21>")
	)
	(gr_poly
		(pts
			(xy 393.248642 -233.02214) (xy 393.202414 -232.924604) (xy 393.166346 -232.88879) (xy 392.980672 -233.074464)
			(xy 393.016486 -233.110532) (xy 393.114022 -233.15676)
		)
		(stroke
			(width 0)
			(type solid)
		)
		(fill yes)
		(layer "F.Cu")
		(net "M_E_CPU0_SB_DQ<12>")
	)
	(gr_poly
		(pts
			(xy 393.250674 -272.2499) (xy 393.286742 -272.214086) (xy 393.100814 -272.028158) (xy 393.064746 -272.063972)
			(xy 393.018518 -272.161508) (xy 393.153392 -272.296128)
		)
		(stroke
			(width 0)
			(type solid)
		)
		(fill yes)
		(layer "F.Cu")
		(net "M_E_CPU0_SA_DQ<27>")
	)
	(gr_poly
		(pts
			(xy 393.253214 -266.99972) (xy 393.299442 -266.902438) (xy 393.164822 -266.767564) (xy 393.067286 -266.813792)
			(xy 393.031472 -266.84986) (xy 393.2174 -267.035788)
		)
		(stroke
			(width 0)
			(type solid)
		)
		(fill yes)
		(layer "F.Cu")
		(net "M_E_CPU0_SA_CB<1>")
	)
	(gr_poly
		(pts
			(xy 393.254484 -276.00656) (xy 393.202922 -275.74875) (xy 393.153138 -275.758656) (xy 393.060682 -275.814028)
			(xy 393.09802 -276.000718) (xy 393.2047 -276.016466)
		)
		(stroke
			(width 0)
			(type solid)
		)
		(fill yes)
		(layer "F.Cu")
		(net "M_E_CPU0_SA_DQ<21>")
	)
	(gr_poly
		(pts
			(xy 393.273788 -235.585254) (xy 393.22756 -235.487718) (xy 393.191492 -235.451904) (xy 393.005564 -235.637578)
			(xy 393.041632 -235.673646) (xy 393.138914 -235.719874)
		)
		(stroke
			(width 0)
			(type solid)
		)
		(fill yes)
		(layer "F.Cu")
		(net "M_E_CPU0_SB_DQ<9>")
	)
	(gr_poly
		(pts
			(xy 393.277344 -269.50797) (xy 393.323572 -269.410688) (xy 393.188952 -269.275814) (xy 393.091416 -269.322042)
			(xy 393.055602 -269.35811) (xy 393.24153 -269.544038)
		)
		(stroke
			(width 0)
			(type solid)
		)
		(fill yes)
		(layer "F.Cu")
		(net "M_E_CPU0_SA_DQ<30>")
	)
	(gr_poly
		(pts
			(xy 393.282424 -237.282228) (xy 393.236196 -237.184692) (xy 393.200128 -237.148878) (xy 393.014454 -237.334552)
			(xy 393.050268 -237.37062) (xy 393.147804 -237.416848)
		)
		(stroke
			(width 0)
			(type solid)
		)
		(fill yes)
		(layer "F.Cu")
		(net "M_E_CPU0_SB_CB<3>")
	)
	(gr_poly
		(pts
			(xy 393.283186 -240.948464) (xy 393.247118 -240.91265) (xy 393.149836 -240.866422) (xy 393.014962 -241.001042)
			(xy 393.06119 -241.098578) (xy 393.097258 -241.134392)
		)
		(stroke
			(width 0)
			(type solid)
		)
		(fill yes)
		(layer "F.Cu")
		(net "M_E_CPU0_SB_CB<5>")
	)
	(gr_poly
		(pts
			(xy 393.283694 -236.439202) (xy 393.237466 -236.341666) (xy 393.201398 -236.305852) (xy 393.01547 -236.49178)
			(xy 393.051538 -236.527594) (xy 393.14882 -236.573822)
		)
		(stroke
			(width 0)
			(type solid)
		)
		(fill yes)
		(layer "F.Cu")
		(net "M_E_CPU0_SB_DQ<8>")
	)
	(gr_poly
		(pts
			(xy 393.286742 -268.65453) (xy 393.33297 -268.556994) (xy 393.19835 -268.422374) (xy 393.101068 -268.468602)
			(xy 393.065 -268.504416) (xy 393.250928 -268.690344)
		)
		(stroke
			(width 0)
			(type solid)
		)
		(fill yes)
		(layer "F.Cu")
		(net "M_E_CPU0_SA_DQ<31>")
	)
	(gr_poly
		(pts
			(xy 393.291568 -238.135414) (xy 393.24534 -238.038132) (xy 393.209526 -238.002064) (xy 393.023598 -238.187992)
			(xy 393.059412 -238.22406) (xy 393.156948 -238.270288)
		)
		(stroke
			(width 0)
			(type solid)
		)
		(fill yes)
		(layer "F.Cu")
		(net "M_E_CPU0_SB_CB<2>")
	)
	(gr_poly
		(pts
			(xy 393.29233 -241.801904) (xy 393.256516 -241.76609) (xy 393.15898 -241.719862) (xy 393.02436 -241.854482)
			(xy 393.070588 -241.952018) (xy 393.106402 -241.987832)
		)
		(stroke
			(width 0)
			(type solid)
		)
		(fill yes)
		(layer "F.Cu")
		(net "M_E_CPU0_SB_CB<4>")
	)
	(gr_poly
		(pts
			(xy 393.297664 -277.519638) (xy 393.39012 -277.464266) (xy 393.352782 -277.277322) (xy 393.246102 -277.261828)
			(xy 393.196318 -277.271734) (xy 393.24788 -277.529544)
		)
		(stroke
			(width 0)
			(type solid)
		)
		(fill yes)
		(layer "F.Cu")
		(net "M_E_CPU0_SA_DQ<22>")
	)
	(gr_poly
		(pts
			(xy 393.30122 -264.459212) (xy 393.347448 -264.36193) (xy 393.212828 -264.227056) (xy 393.115292 -264.273538)
			(xy 393.079478 -264.309352) (xy 393.265406 -264.49528)
		)
		(stroke
			(width 0)
			(type solid)
		)
		(fill yes)
		(layer "F.Cu")
		(net "M_E_CPU0_SA_CB<4>")
	)
	(gr_poly
		(pts
			(xy 393.3063 -277.822152) (xy 393.254738 -277.564342) (xy 393.204954 -277.574502) (xy 393.112498 -277.629874)
			(xy 393.149836 -277.816564) (xy 393.256516 -277.832312)
		)
		(stroke
			(width 0)
			(type solid)
		)
		(fill yes)
		(layer "F.Cu")
		(net "M_E_CPU0_SA_DQ<22>")
	)
	(gr_poly
		(pts
			(xy 393.30884 -273.458178) (xy 393.355068 -273.360896) (xy 393.220448 -273.226022) (xy 393.122912 -273.27225)
			(xy 393.087098 -273.308318) (xy 393.273026 -273.494246)
		)
		(stroke
			(width 0)
			(type solid)
		)
		(fill yes)
		(layer "F.Cu")
		(net "M_E_CPU0_SA_DQ<24>")
	)
	(gr_poly
		(pts
			(xy 393.310618 -263.606026) (xy 393.356846 -263.50849) (xy 393.221972 -263.37387) (xy 393.12469 -263.420098)
			(xy 393.088622 -263.455912) (xy 393.27455 -263.64184)
		)
		(stroke
			(width 0)
			(type solid)
		)
		(fill yes)
		(layer "F.Cu")
		(net "M_E_CPU0_SA_CB<5>")
	)
	(gr_poly
		(pts
			(xy 393.317984 -272.604738) (xy 393.364212 -272.507456) (xy 393.229592 -272.372582) (xy 393.132056 -272.41881)
			(xy 393.096242 -272.454878) (xy 393.28217 -272.640806)
		)
		(stroke
			(width 0)
			(type solid)
		)
		(fill yes)
		(layer "F.Cu")
		(net "M_E_CPU0_SA_DQ<25>")
	)
	(gr_poly
		(pts
			(xy 393.319508 -274.77593) (xy 393.267946 -274.51812) (xy 393.218162 -274.528026) (xy 393.125706 -274.583652)
			(xy 393.163044 -274.770342) (xy 393.269724 -274.785836)
		)
		(stroke
			(width 0)
			(type solid)
		)
		(fill yes)
		(layer "F.Cu")
		(net "M_E_CPU0_SA_DQ<23>")
	)
	(gr_poly
		(pts
			(xy 393.349226 -279.335484) (xy 393.441682 -279.280112) (xy 393.404344 -279.093168) (xy 393.297664 -279.077674)
			(xy 393.24788 -279.08758) (xy 393.299188 -279.34539)
		)
		(stroke
			(width 0)
			(type solid)
		)
		(fill yes)
		(layer "F.Cu")
		(net "M_E_CPU0_SA_DQ<20>")
	)
	(gr_poly
		(pts
			(xy 393.350242 -229.273862) (xy 393.314428 -229.237794) (xy 393.216892 -229.191566) (xy 393.082272 -229.32644)
			(xy 393.1285 -229.423722) (xy 393.164314 -229.45979)
		)
		(stroke
			(width 0)
			(type solid)
		)
		(fill yes)
		(layer "F.Cu")
		(net "M_E_CPU0_SB_DQ<19>")
	)
	(gr_poly
		(pts
			(xy 393.357862 -279.637998) (xy 393.3063 -279.380442) (xy 393.256516 -279.390348) (xy 393.163806 -279.44572)
			(xy 393.201144 -279.63241) (xy 393.308078 -279.648158)
		)
		(stroke
			(width 0)
			(type solid)
		)
		(fill yes)
		(layer "F.Cu")
		(net "M_E_CPU0_SA_DQ<20>")
	)
	(gr_poly
		(pts
			(xy 393.359386 -230.127302) (xy 393.323572 -230.091234) (xy 393.226036 -230.045006) (xy 393.091416 -230.179626)
			(xy 393.137644 -230.277162) (xy 393.173712 -230.312976)
		)
		(stroke
			(width 0)
			(type solid)
		)
		(fill yes)
		(layer "F.Cu")
		(net "M_E_CPU0_SB_DQ<18>")
	)
	(gr_poly
		(pts
			(xy 393.360656 -240.655348) (xy 393.314428 -240.557812) (xy 393.27836 -240.521998) (xy 393.092686 -240.707672)
			(xy 393.1285 -240.74374) (xy 393.226036 -240.789968)
		)
		(stroke
			(width 0)
			(type solid)
		)
		(fill yes)
		(layer "F.Cu")
		(net "M_E_CPU0_SB_CB<7>")
	)
	(gr_poly
		(pts
			(xy 393.362942 -276.289008) (xy 393.455398 -276.233636) (xy 393.41806 -276.046946) (xy 393.31138 -276.031452)
			(xy 393.261596 -276.041358) (xy 393.313158 -276.299168)
		)
		(stroke
			(width 0)
			(type solid)
		)
		(fill yes)
		(layer "F.Cu")
		(net "M_E_CPU0_SA_DQ<21>")
	)
	(gr_poly
		(pts
			(xy 393.368276 -231.824276) (xy 393.332462 -231.788462) (xy 393.234926 -231.742234) (xy 393.100306 -231.876854)
			(xy 393.146534 -231.974136) (xy 393.182348 -232.010204)
		)
		(stroke
			(width 0)
			(type solid)
		)
		(fill yes)
		(layer "F.Cu")
		(net "M_E_CPU0_SB_DQ<13>")
	)
	(gr_poly
		(pts
			(xy 393.3698 -241.508534) (xy 393.323572 -241.411252) (xy 393.287758 -241.375184) (xy 393.10183 -241.561112)
			(xy 393.137644 -241.596926) (xy 393.23518 -241.643408)
		)
		(stroke
			(width 0)
			(type solid)
		)
		(fill yes)
		(layer "F.Cu")
		(net "M_E_CPU0_SB_CB<6>")
	)
	(gr_poly
		(pts
			(xy 393.371578 -276.591776) (xy 393.320016 -276.333966) (xy 393.270232 -276.343872) (xy 393.177776 -276.399244)
			(xy 393.215114 -276.586188) (xy 393.321794 -276.601682)
		)
		(stroke
			(width 0)
			(type solid)
		)
		(fill yes)
		(layer "F.Cu")
		(net "M_E_CPU0_SA_DQ<21>")
	)
	(gr_poly
		(pts
			(xy 393.37742 -232.677716) (xy 393.341606 -232.641648) (xy 393.24407 -232.59542) (xy 393.10945 -232.730294)
			(xy 393.155678 -232.827576) (xy 393.191492 -232.863644)
		)
		(stroke
			(width 0)
			(type solid)
		)
		(fill yes)
		(layer "F.Cu")
		(net "M_E_CPU0_SB_DQ<12>")
	)
	(gr_poly
		(pts
			(xy 393.383262 -268.136116) (xy 393.419076 -268.100048) (xy 393.233148 -267.91412) (xy 393.197334 -267.950188)
			(xy 393.151106 -268.04747) (xy 393.285726 -268.182344)
		)
		(stroke
			(width 0)
			(type solid)
		)
		(fill yes)
		(layer "F.Cu")
		(net "M_E_CPU0_SA_CB<0>")
	)
	(gr_poly
		(pts
			(xy 393.392406 -267.282676) (xy 393.42822 -267.246608) (xy 393.242546 -267.060934) (xy 393.206478 -267.096748)
			(xy 393.16025 -267.194284) (xy 393.29487 -267.328904)
		)
		(stroke
			(width 0)
			(type solid)
		)
		(fill yes)
		(layer "F.Cu")
		(net "M_E_CPU0_SA_CB<1>")
	)
	(gr_poly
		(pts
			(xy 393.402566 -235.24083) (xy 393.366752 -235.204762) (xy 393.269216 -235.158534) (xy 393.134596 -235.293408)
			(xy 393.180824 -235.39069) (xy 393.216638 -235.426758)
		)
		(stroke
			(width 0)
			(type solid)
		)
		(fill yes)
		(layer "F.Cu")
		(net "M_E_CPU0_SB_DQ<9>")
	)
	(gr_poly
		(pts
			(xy 393.411202 -236.937804) (xy 393.375388 -236.901736) (xy 393.277852 -236.855508) (xy 393.143232 -236.990382)
			(xy 393.18946 -237.087664) (xy 393.225274 -237.123732)
		)
		(stroke
			(width 0)
			(type solid)
		)
		(fill yes)
		(layer "F.Cu")
		(net "M_E_CPU0_SB_CB<3>")
	)
	(gr_poly
		(pts
			(xy 393.412472 -236.094778) (xy 393.376658 -236.058964) (xy 393.279122 -236.012736) (xy 393.144502 -236.147356)
			(xy 393.19073 -236.244638) (xy 393.226544 -236.280706)
		)
		(stroke
			(width 0)
			(type solid)
		)
		(fill yes)
		(layer "F.Cu")
		(net "M_E_CPU0_SB_DQ<8>")
	)
	(gr_poly
		(pts
			(xy 393.414758 -278.104854) (xy 393.507214 -278.049482) (xy 393.469876 -277.862792) (xy 393.363196 -277.847044)
			(xy 393.313412 -277.857204) (xy 393.364974 -278.115014)
		)
		(stroke
			(width 0)
			(type solid)
		)
		(fill yes)
		(layer "F.Cu")
		(net "M_E_CPU0_SA_DQ<22>")
	)
	(gr_poly
		(pts
			(xy 393.416536 -269.790926) (xy 393.452604 -269.755112) (xy 393.266676 -269.569184) (xy 393.230608 -269.604998)
			(xy 393.18438 -269.702534) (xy 393.319254 -269.837154)
		)
		(stroke
			(width 0)
			(type solid)
		)
		(fill yes)
		(layer "F.Cu")
		(net "M_E_CPU0_SA_DQ<30>")
	)
	(gr_poly
		(pts
			(xy 393.4206 -237.79099) (xy 393.384532 -237.755176) (xy 393.28725 -237.708948) (xy 393.152376 -237.843568)
			(xy 393.198604 -237.941104) (xy 393.234672 -237.976918)
		)
		(stroke
			(width 0)
			(type solid)
		)
		(fill yes)
		(layer "F.Cu")
		(net "M_E_CPU0_SB_CB<2>")
	)
	(gr_poly
		(pts
			(xy 393.423394 -278.407622) (xy 393.371832 -278.149812) (xy 393.322048 -278.159718) (xy 393.229592 -278.21509)
			(xy 393.26693 -278.402034) (xy 393.37361 -278.417528)
		)
		(stroke
			(width 0)
			(type solid)
		)
		(fill yes)
		(layer "F.Cu")
		(net "M_E_CPU0_SA_DQ<22>")
	)
	(gr_poly
		(pts
			(xy 393.425934 -268.937232) (xy 393.462002 -268.901418) (xy 393.276074 -268.71549) (xy 393.24026 -268.751304)
			(xy 393.193778 -268.84884) (xy 393.328652 -268.98346)
		)
		(stroke
			(width 0)
			(type solid)
		)
		(fill yes)
		(layer "F.Cu")
		(net "M_E_CPU0_SA_DQ<31>")
	)
	(gr_poly
		(pts
			(xy 393.427966 -275.058632) (xy 393.520422 -275.00326) (xy 393.483084 -274.816316) (xy 393.376404 -274.800822)
			(xy 393.32662 -274.810728) (xy 393.378182 -275.068538)
		)
		(stroke
			(width 0)
			(type solid)
		)
		(fill yes)
		(layer "F.Cu")
		(net "M_E_CPU0_SA_DQ<23>")
	)
	(gr_poly
		(pts
			(xy 393.436602 -275.3614) (xy 393.38504 -275.10359) (xy 393.335256 -275.113496) (xy 393.2428 -275.168868)
			(xy 393.280138 -275.355558) (xy 393.386818 -275.371306)
		)
		(stroke
			(width 0)
			(type solid)
		)
		(fill yes)
		(layer "F.Cu")
		(net "M_E_CPU0_SA_DQ<23>")
	)
	(gr_poly
		(pts
			(xy 393.43711 -229.833932) (xy 393.390882 -229.736396) (xy 393.354814 -229.700582) (xy 393.168886 -229.88651)
			(xy 393.204954 -229.922324) (xy 393.302236 -229.968552)
		)
		(stroke
			(width 0)
			(type solid)
		)
		(fill yes)
		(layer "F.Cu")
		(net "M_E_CPU0_SB_DQ<17>")
	)
	(gr_poly
		(pts
			(xy 393.440412 -264.742168) (xy 393.47648 -264.706354) (xy 393.290552 -264.520426) (xy 393.254484 -264.55624)
			(xy 393.208256 -264.653776) (xy 393.34313 -264.788396)
		)
		(stroke
			(width 0)
			(type solid)
		)
		(fill yes)
		(layer "F.Cu")
		(net "M_E_CPU0_SA_CB<4>")
	)
	(gr_poly
		(pts
			(xy 393.445746 -231.530906) (xy 393.399518 -231.433624) (xy 393.363704 -231.397556) (xy 393.177776 -231.583484)
			(xy 393.21359 -231.619298) (xy 393.311126 -231.66578)
		)
		(stroke
			(width 0)
			(type solid)
		)
		(fill yes)
		(layer "F.Cu")
		(net "M_E_CPU0_SB_DQ<15>")
	)
	(gr_poly
		(pts
			(xy 393.446254 -230.687118) (xy 393.400026 -230.589836) (xy 393.364212 -230.553768) (xy 393.178284 -230.739696)
			(xy 393.214098 -230.775764) (xy 393.311634 -230.821992)
		)
		(stroke
			(width 0)
			(type solid)
		)
		(fill yes)
		(layer "F.Cu")
		(net "M_E_CPU0_SB_DQ<16>")
	)
	(gr_poly
		(pts
			(xy 393.448032 -273.741134) (xy 393.4841 -273.70532) (xy 393.298172 -273.519392) (xy 393.262104 -273.555206)
			(xy 393.215876 -273.652742) (xy 393.35075 -273.787362)
		)
		(stroke
			(width 0)
			(type solid)
		)
		(fill yes)
		(layer "F.Cu")
		(net "M_E_CPU0_SA_DQ<24>")
	)
	(gr_poly
		(pts
			(xy 393.44981 -263.888728) (xy 393.485624 -263.852914) (xy 393.299696 -263.666986) (xy 393.263882 -263.703054)
			(xy 393.217654 -263.800336) (xy 393.352274 -263.934956)
		)
		(stroke
			(width 0)
			(type solid)
		)
		(fill yes)
		(layer "F.Cu")
		(net "M_E_CPU0_SA_CB<5>")
	)
	(gr_poly
		(pts
			(xy 393.455144 -232.384346) (xy 393.408916 -232.28681) (xy 393.372848 -232.250996) (xy 393.18692 -232.436924)
			(xy 393.222988 -232.472738) (xy 393.32027 -232.518966)
		)
		(stroke
			(width 0)
			(type solid)
		)
		(fill yes)
		(layer "F.Cu")
		(net "M_E_CPU0_SB_DQ<14>")
	)
	(gr_poly
		(pts
			(xy 393.457176 -272.887694) (xy 393.493244 -272.85188) (xy 393.307316 -272.665952) (xy 393.271248 -272.701766)
			(xy 393.22502 -272.799302) (xy 393.359894 -272.933922)
		)
		(stroke
			(width 0)
			(type solid)
		)
		(fill yes)
		(layer "F.Cu")
		(net "M_E_CPU0_SA_DQ<25>")
	)
	(gr_poly
		(pts
			(xy 393.459716 -267.637514) (xy 393.505944 -267.539978) (xy 393.37107 -267.405358) (xy 393.273788 -267.451586)
			(xy 393.23772 -267.4874) (xy 393.423648 -267.673328)
		)
		(stroke
			(width 0)
			(type solid)
		)
		(fill yes)
		(layer "F.Cu")
		(net "M_E_CPU0_SA_CB<2>")
	)
	(gr_poly
		(pts
			(xy 393.466066 -279.9207) (xy 393.558522 -279.865328) (xy 393.521184 -279.678638) (xy 393.414504 -279.663144)
			(xy 393.36472 -279.67305) (xy 393.416282 -279.93086)
		)
		(stroke
			(width 0)
			(type solid)
		)
		(fill yes)
		(layer "F.Cu")
		(net "M_E_CPU0_SA_DQ<20>")
	)
	(gr_poly
		(pts
			(xy 393.466828 -285.143448) (xy 393.416028 -285.143448) (xy 393.314428 -285.17977) (xy 393.314428 -285.37027)
			(xy 393.416028 -285.406338) (xy 393.466828 -285.406338)
		)
		(stroke
			(width 0)
			(type solid)
		)
		(fill yes)
		(layer "F.Cu")
		(net "M_E_CPU0_SA_DQ<20>")
	)
	(gr_poly
		(pts
			(xy 393.466828 -284.546548) (xy 393.416028 -284.546548) (xy 393.314428 -284.58287) (xy 393.314428 -284.77337)
			(xy 393.416028 -284.809438) (xy 393.466828 -284.809438)
		)
		(stroke
			(width 0)
			(type solid)
		)
		(fill yes)
		(layer "F.Cu")
		(net "M_E_CPU0_SA_DQ<20>")
	)
	(gr_poly
		(pts
			(xy 393.466828 -283.949648) (xy 393.416028 -283.949648) (xy 393.314428 -283.98597) (xy 393.314428 -284.17647)
			(xy 393.416028 -284.212538) (xy 393.466828 -284.212538)
		)
		(stroke
			(width 0)
			(type solid)
		)
		(fill yes)
		(layer "F.Cu")
		(net "M_E_CPU0_SA_DQ<20>")
	)
	(gr_poly
		(pts
			(xy 393.466828 -283.352748) (xy 393.416028 -283.352748) (xy 393.314428 -283.38907) (xy 393.314428 -283.57957)
			(xy 393.416028 -283.615638) (xy 393.466828 -283.615638)
		)
		(stroke
			(width 0)
			(type solid)
		)
		(fill yes)
		(layer "F.Cu")
		(net "M_E_CPU0_SA_DQ<20>")
	)
	(gr_poly
		(pts
			(xy 393.466828 -282.755848) (xy 393.416028 -282.755848) (xy 393.314428 -282.79217) (xy 393.314428 -282.98267)
			(xy 393.416028 -283.018738) (xy 393.466828 -283.018738)
		)
		(stroke
			(width 0)
			(type solid)
		)
		(fill yes)
		(layer "F.Cu")
		(net "M_E_CPU0_SA_DQ<20>")
	)
	(gr_poly
		(pts
			(xy 393.466828 -282.158948) (xy 393.416028 -282.158948) (xy 393.314428 -282.19527) (xy 393.314428 -282.38577)
			(xy 393.416028 -282.421838) (xy 393.466828 -282.421838)
		)
		(stroke
			(width 0)
			(type solid)
		)
		(fill yes)
		(layer "F.Cu")
		(net "M_E_CPU0_SA_DQ<20>")
	)
	(gr_poly
		(pts
			(xy 393.466828 -281.562048) (xy 393.416028 -281.562048) (xy 393.314428 -281.59837) (xy 393.314428 -281.78887)
			(xy 393.416028 -281.824938) (xy 393.466828 -281.824938)
		)
		(stroke
			(width 0)
			(type solid)
		)
		(fill yes)
		(layer "F.Cu")
		(net "M_E_CPU0_SA_DQ<20>")
	)
	(gr_poly
		(pts
			(xy 393.466828 -280.965148) (xy 393.416028 -280.965148) (xy 393.314428 -281.00147) (xy 393.314428 -281.19197)
			(xy 393.416028 -281.228038) (xy 393.466828 -281.228038)
		)
		(stroke
			(width 0)
			(type solid)
		)
		(fill yes)
		(layer "F.Cu")
		(net "M_E_CPU0_SA_DQ<20>")
	)
	(gr_poly
		(pts
			(xy 393.46886 -266.784074) (xy 393.515088 -266.686792) (xy 393.380468 -266.551918) (xy 393.282932 -266.598146)
			(xy 393.247118 -266.634214) (xy 393.433046 -266.820142)
		)
		(stroke
			(width 0)
			(type solid)
		)
		(fill yes)
		(layer "F.Cu")
		(net "M_E_CPU0_SA_CB<3>")
	)
	(gr_poly
		(pts
			(xy 393.480036 -276.874478) (xy 393.572492 -276.819106) (xy 393.535154 -276.632162) (xy 393.428474 -276.616668)
			(xy 393.37869 -276.626574) (xy 393.430252 -276.884384)
		)
		(stroke
			(width 0)
			(type solid)
		)
		(fill yes)
		(layer "F.Cu")
		(net "M_E_CPU0_SA_DQ<21>")
	)
	(gr_poly
		(pts
			(xy 393.480036 -234.947206) (xy 393.433554 -234.84967) (xy 393.39774 -234.813856) (xy 393.211812 -234.999784)
			(xy 393.24788 -235.035598) (xy 393.345162 -235.081826)
		)
		(stroke
			(width 0)
			(type solid)
		)
		(fill yes)
		(layer "F.Cu")
		(net "M_E_CPU0_SB_DQ<11>")
	)
	(gr_poly
		(pts
			(xy 393.483846 -270.145764) (xy 393.530074 -270.048228) (xy 393.395454 -269.913608) (xy 393.297918 -269.959836)
			(xy 393.262104 -269.995904) (xy 393.447778 -270.181578)
		)
		(stroke
			(width 0)
			(type solid)
		)
		(fill yes)
		(layer "F.Cu")
		(net "M_E_CPU0_SA_DQ<28>")
	)
	(gr_poly
		(pts
			(xy 393.488672 -277.176992) (xy 393.43711 -276.919182) (xy 393.387326 -276.929342) (xy 393.29487 -276.984714)
			(xy 393.332208 -277.171404) (xy 393.438888 -277.186898)
		)
		(stroke
			(width 0)
			(type solid)
		)
		(fill yes)
		(layer "F.Cu")
		(net "M_E_CPU0_SA_DQ<21>")
	)
	(gr_poly
		(pts
			(xy 393.489434 -240.310924) (xy 393.45362 -240.274856) (xy 393.356084 -240.228628) (xy 393.221464 -240.363248)
			(xy 393.267692 -240.460784) (xy 393.303506 -240.496852)
		)
		(stroke
			(width 0)
			(type solid)
		)
		(fill yes)
		(layer "F.Cu")
		(net "M_E_CPU0_SB_CB<7>")
	)
	(gr_poly
		(pts
			(xy 393.489942 -235.801408) (xy 393.443714 -235.703872) (xy 393.407646 -235.668058) (xy 393.221718 -235.853986)
			(xy 393.257786 -235.8898) (xy 393.355068 -235.936028)
		)
		(stroke
			(width 0)
			(type solid)
		)
		(fill yes)
		(layer "F.Cu")
		(net "M_E_CPU0_SB_DQ<10>")
	)
	(gr_poly
		(pts
			(xy 393.493244 -269.292324) (xy 393.539472 -269.194788) (xy 393.404598 -269.060168) (xy 393.307316 -269.106396)
			(xy 393.271248 -269.14221) (xy 393.457176 -269.328138)
		)
		(stroke
			(width 0)
			(type solid)
		)
		(fill yes)
		(layer "F.Cu")
		(net "M_E_CPU0_SA_DQ<29>")
	)
	(gr_poly
		(pts
			(xy 393.49807 -237.497874) (xy 393.451842 -237.400338) (xy 393.415774 -237.364524) (xy 393.2301 -237.550198)
			(xy 393.265914 -237.586266) (xy 393.36345 -237.632494)
		)
		(stroke
			(width 0)
			(type solid)
		)
		(fill yes)
		(layer "F.Cu")
		(net "M_E_CPU0_SB_CB<1>")
	)
	(gr_poly
		(pts
			(xy 393.498832 -241.16411) (xy 393.462764 -241.128296) (xy 393.365482 -241.082068) (xy 393.230608 -241.216688)
			(xy 393.276836 -241.314224) (xy 393.312904 -241.350038)
		)
		(stroke
			(width 0)
			(type solid)
		)
		(fill yes)
		(layer "F.Cu")
		(net "M_E_CPU0_SB_CB<6>")
	)
	(gr_poly
		(pts
			(xy 393.507214 -238.35106) (xy 393.460986 -238.253778) (xy 393.425172 -238.21771) (xy 393.239244 -238.403638)
			(xy 393.275058 -238.439706) (xy 393.372594 -238.485934)
		)
		(stroke
			(width 0)
			(type solid)
		)
		(fill yes)
		(layer "F.Cu")
		(net "M_E_CPU0_SB_CB<0>")
	)
	(gr_poly
		(pts
			(xy 393.516866 -264.243566) (xy 393.563094 -264.146284) (xy 393.428474 -264.01141) (xy 393.330938 -264.057892)
			(xy 393.295124 -264.093706) (xy 393.481052 -264.279634)
		)
		(stroke
			(width 0)
			(type solid)
		)
		(fill yes)
		(layer "F.Cu")
		(net "M_E_CPU0_SA_CB<6>")
	)
	(gr_poly
		(pts
			(xy 393.524486 -273.242532) (xy 393.570714 -273.14525) (xy 393.436094 -273.010376) (xy 393.338558 -273.056604)
			(xy 393.302744 -273.092672) (xy 393.488672 -273.2786)
		)
		(stroke
			(width 0)
			(type solid)
		)
		(fill yes)
		(layer "F.Cu")
		(net "M_E_CPU0_SA_DQ<26>")
	)
	(gr_poly
		(pts
			(xy 393.526264 -263.39038) (xy 393.572492 -263.292844) (xy 393.437618 -263.158224) (xy 393.340336 -263.204452)
			(xy 393.304268 -263.240266) (xy 393.490196 -263.426194)
		)
		(stroke
			(width 0)
			(type solid)
		)
		(fill yes)
		(layer "F.Cu")
		(net "M_E_CPU0_SA_CB<7>")
	)
	(gr_poly
		(pts
			(xy 393.531852 -278.690324) (xy 393.624308 -278.634698) (xy 393.58697 -278.448008) (xy 393.48029 -278.432514)
			(xy 393.430506 -278.44242) (xy 393.482068 -278.70023)
		)
		(stroke
			(width 0)
			(type solid)
		)
		(fill yes)
		(layer "F.Cu")
		(net "M_E_CPU0_SA_DQ<22>")
	)
	(gr_poly
		(pts
			(xy 393.53363 -272.389092) (xy 393.579858 -272.29181) (xy 393.445238 -272.156936) (xy 393.347702 -272.203164)
			(xy 393.311888 -272.239232) (xy 393.497816 -272.42516)
		)
		(stroke
			(width 0)
			(type solid)
		)
		(fill yes)
		(layer "F.Cu")
		(net "M_E_CPU0_SA_DQ<27>")
	)
	(gr_poly
		(pts
			(xy 393.540488 -278.992838) (xy 393.488926 -278.735028) (xy 393.439142 -278.744934) (xy 393.346686 -278.80056)
			(xy 393.384024 -278.98725) (xy 393.490704 -279.002744)
		)
		(stroke
			(width 0)
			(type solid)
		)
		(fill yes)
		(layer "F.Cu")
		(net "M_E_CPU0_SA_DQ<22>")
	)
	(gr_poly
		(pts
			(xy 393.54506 -275.643848) (xy 393.637516 -275.588476) (xy 393.600178 -275.401786) (xy 393.493498 -275.386292)
			(xy 393.443714 -275.396198) (xy 393.495276 -275.654008)
		)
		(stroke
			(width 0)
			(type solid)
		)
		(fill yes)
		(layer "F.Cu")
		(net "M_E_CPU0_SA_DQ<23>")
	)
	(gr_poly
		(pts
			(xy 393.553696 -275.946616) (xy 393.502134 -275.688806) (xy 393.45235 -275.698712) (xy 393.359894 -275.754084)
			(xy 393.397232 -275.941028) (xy 393.503912 -275.956522)
		)
		(stroke
			(width 0)
			(type solid)
		)
		(fill yes)
		(layer "F.Cu")
		(net "M_E_CPU0_SA_DQ<23>")
	)
	(gr_poly
		(pts
			(xy 393.565888 -229.489508) (xy 393.530074 -229.45344) (xy 393.432538 -229.407212) (xy 393.297918 -229.542086)
			(xy 393.344146 -229.639368) (xy 393.37996 -229.675436)
		)
		(stroke
			(width 0)
			(type solid)
		)
		(fill yes)
		(layer "F.Cu")
		(net "M_E_CPU0_SB_DQ<17>")
	)
	(gr_poly
		(pts
			(xy 393.574778 -231.186482) (xy 393.53871 -231.150668) (xy 393.441428 -231.10444) (xy 393.306554 -231.23906)
			(xy 393.352782 -231.336596) (xy 393.38885 -231.37241)
		)
		(stroke
			(width 0)
			(type solid)
		)
		(fill yes)
		(layer "F.Cu")
		(net "M_E_CPU0_SB_DQ<15>")
	)
	(gr_poly
		(pts
			(xy 393.575032 -230.342948) (xy 393.539218 -230.30688) (xy 393.441682 -230.260652) (xy 393.307062 -230.395272)
			(xy 393.35329 -230.492808) (xy 393.389358 -230.528622)
		)
		(stroke
			(width 0)
			(type solid)
		)
		(fill yes)
		(layer "F.Cu")
		(net "M_E_CPU0_SB_DQ<16>")
	)
	(gr_poly
		(pts
			(xy 393.576302 -240.870994) (xy 393.530074 -240.773458) (xy 393.494006 -240.737644) (xy 393.308332 -240.923318)
			(xy 393.344146 -240.959386) (xy 393.441682 -241.005614)
		)
		(stroke
			(width 0)
			(type solid)
		)
		(fill yes)
		(layer "F.Cu")
		(net "M_E_CPU0_SB_CB<5>")
	)
	(gr_poly
		(pts
			(xy 393.583922 -232.039922) (xy 393.548108 -232.004108) (xy 393.450572 -231.95788) (xy 393.315952 -232.0925)
			(xy 393.36218 -232.189782) (xy 393.397994 -232.22585)
		)
		(stroke
			(width 0)
			(type solid)
		)
		(fill yes)
		(layer "F.Cu")
		(net "M_E_CPU0_SB_DQ<14>")
	)
	(gr_poly
		(pts
			(xy 393.585446 -241.72418) (xy 393.539218 -241.626898) (xy 393.503404 -241.59083) (xy 393.317476 -241.776758)
			(xy 393.35329 -241.812572) (xy 393.450826 -241.859054)
		)
		(stroke
			(width 0)
			(type solid)
		)
		(fill yes)
		(layer "F.Cu")
		(net "M_E_CPU0_SB_CB<4>")
	)
	(gr_poly
		(pts
			(xy 393.59713 -277.459694) (xy 393.689586 -277.404322) (xy 393.652248 -277.217632) (xy 393.545568 -277.201884)
			(xy 393.495784 -277.21179) (xy 393.547346 -277.4696)
		)
		(stroke
			(width 0)
			(type solid)
		)
		(fill yes)
		(layer "F.Cu")
		(net "M_E_CPU0_SA_DQ<21>")
	)
	(gr_poly
		(pts
			(xy 393.598908 -267.92047) (xy 393.634722 -267.884402) (xy 393.448794 -267.698474) (xy 393.41298 -267.734542)
			(xy 393.366752 -267.831824) (xy 393.501372 -267.966698)
		)
		(stroke
			(width 0)
			(type solid)
		)
		(fill yes)
		(layer "F.Cu")
		(net "M_E_CPU0_SA_CB<2>")
	)
	(gr_poly
		(pts
			(xy 393.605766 -277.762462) (xy 393.554204 -277.504652) (xy 393.50442 -277.514558) (xy 393.411964 -277.56993)
			(xy 393.449302 -277.75662) (xy 393.555982 -277.772368)
		)
		(stroke
			(width 0)
			(type solid)
		)
		(fill yes)
		(layer "F.Cu")
		(net "M_E_CPU0_SA_DQ<21>")
	)
	(gr_poly
		(pts
			(xy 393.608052 -267.06703) (xy 393.643866 -267.030962) (xy 393.458192 -266.845288) (xy 393.422124 -266.881102)
			(xy 393.375896 -266.978638) (xy 393.510516 -267.113258)
		)
		(stroke
			(width 0)
			(type solid)
		)
		(fill yes)
		(layer "F.Cu")
		(net "M_E_CPU0_SA_CB<3>")
	)
	(gr_poly
		(pts
			(xy 393.608814 -234.602782) (xy 393.572746 -234.566968) (xy 393.475464 -234.52074) (xy 393.340844 -234.65536)
			(xy 393.387072 -234.752896) (xy 393.422886 -234.78871)
		)
		(stroke
			(width 0)
			(type solid)
		)
		(fill yes)
		(layer "F.Cu")
		(net "M_E_CPU0_SB_DQ<11>")
	)
	(gr_poly
		(pts
			(xy 393.61872 -235.456984) (xy 393.582906 -235.420916) (xy 393.48537 -235.374688) (xy 393.35075 -235.509562)
			(xy 393.396978 -235.606844) (xy 393.432792 -235.642912)
		)
		(stroke
			(width 0)
			(type solid)
		)
		(fill yes)
		(layer "F.Cu")
		(net "M_E_CPU0_SB_DQ<10>")
	)
	(gr_poly
		(pts
			(xy 393.619228 -285.07182) (xy 393.619228 -284.88132) (xy 393.517628 -284.844998) (xy 393.466828 -284.844998)
			(xy 393.466828 -285.108142) (xy 393.517628 -285.108142)
		)
		(stroke
			(width 0)
			(type solid)
		)
		(fill yes)
		(layer "F.Cu")
		(net "M_E_CPU0_SA_DQ<20>")
	)
	(gr_poly
		(pts
			(xy 393.619228 -284.47492) (xy 393.619228 -284.28442) (xy 393.517628 -284.248098) (xy 393.466828 -284.248098)
			(xy 393.466828 -284.511242) (xy 393.517628 -284.511242)
		)
		(stroke
			(width 0)
			(type solid)
		)
		(fill yes)
		(layer "F.Cu")
		(net "M_E_CPU0_SA_DQ<20>")
	)
	(gr_poly
		(pts
			(xy 393.619228 -283.87802) (xy 393.619228 -283.68752) (xy 393.517628 -283.651198) (xy 393.466828 -283.651198)
			(xy 393.466828 -283.914342) (xy 393.517628 -283.914342)
		)
		(stroke
			(width 0)
			(type solid)
		)
		(fill yes)
		(layer "F.Cu")
		(net "M_E_CPU0_SA_DQ<20>")
	)
	(gr_poly
		(pts
			(xy 393.619228 -283.28112) (xy 393.619228 -283.09062) (xy 393.517628 -283.054298) (xy 393.466828 -283.054298)
			(xy 393.466828 -283.317442) (xy 393.517628 -283.317442)
		)
		(stroke
			(width 0)
			(type solid)
		)
		(fill yes)
		(layer "F.Cu")
		(net "M_E_CPU0_SA_DQ<20>")
	)
	(gr_poly
		(pts
			(xy 393.619228 -282.68422) (xy 393.619228 -282.49372) (xy 393.517628 -282.457398) (xy 393.466828 -282.457398)
			(xy 393.466828 -282.720542) (xy 393.517628 -282.720542)
		)
		(stroke
			(width 0)
			(type solid)
		)
		(fill yes)
		(layer "F.Cu")
		(net "M_E_CPU0_SA_DQ<20>")
	)
	(gr_poly
		(pts
			(xy 393.619228 -282.08732) (xy 393.619228 -281.89682) (xy 393.517628 -281.860498) (xy 393.466828 -281.860498)
			(xy 393.466828 -282.123642) (xy 393.517628 -282.123642)
		)
		(stroke
			(width 0)
			(type solid)
		)
		(fill yes)
		(layer "F.Cu")
		(net "M_E_CPU0_SA_DQ<20>")
	)
	(gr_poly
		(pts
			(xy 393.619228 -281.49042) (xy 393.619228 -281.29992) (xy 393.517628 -281.263598) (xy 393.466828 -281.263598)
			(xy 393.466828 -281.526742) (xy 393.517628 -281.526742)
		)
		(stroke
			(width 0)
			(type solid)
		)
		(fill yes)
		(layer "F.Cu")
		(net "M_E_CPU0_SA_DQ<20>")
	)
	(gr_poly
		(pts
			(xy 393.619228 -280.89352) (xy 393.619228 -280.70302) (xy 393.517628 -280.666698) (xy 393.466828 -280.666698)
			(xy 393.466828 -280.929842) (xy 393.517628 -280.929842)
		)
		(stroke
			(width 0)
			(type solid)
		)
		(fill yes)
		(layer "F.Cu")
		(net "M_E_CPU0_SA_DQ<20>")
	)
	(gr_poly
		(pts
			(xy 393.623038 -270.42872) (xy 393.658852 -270.392652) (xy 393.472924 -270.206724) (xy 393.43711 -270.242792)
			(xy 393.390882 -270.340074) (xy 393.525502 -270.474948)
		)
		(stroke
			(width 0)
			(type solid)
		)
		(fill yes)
		(layer "F.Cu")
		(net "M_E_CPU0_SA_DQ<28>")
	)
	(gr_poly
		(pts
			(xy 393.626848 -237.15345) (xy 393.591034 -237.117382) (xy 393.493498 -237.071154) (xy 393.358878 -237.206028)
			(xy 393.405106 -237.30331) (xy 393.44092 -237.339378)
		)
		(stroke
			(width 0)
			(type solid)
		)
		(fill yes)
		(layer "F.Cu")
		(net "M_E_CPU0_SB_CB<1>")
	)
	(gr_poly
		(pts
			(xy 393.632436 -269.575026) (xy 393.66825 -269.539212) (xy 393.482322 -269.353284) (xy 393.446508 -269.389352)
			(xy 393.40028 -269.486634) (xy 393.5349 -269.621508)
		)
		(stroke
			(width 0)
			(type solid)
		)
		(fill yes)
		(layer "F.Cu")
		(net "M_E_CPU0_SA_DQ<29>")
	)
	(gr_poly
		(pts
			(xy 393.636246 -238.006636) (xy 393.600178 -237.970822) (xy 393.502896 -237.924594) (xy 393.368022 -238.059214)
			(xy 393.41425 -238.15675) (xy 393.450318 -238.192564)
		)
		(stroke
			(width 0)
			(type solid)
		)
		(fill yes)
		(layer "F.Cu")
		(net "M_E_CPU0_SB_CB<0>")
	)
	(gr_poly
		(pts
			(xy 393.643358 -229.196138) (xy 393.59713 -229.098602) (xy 393.561316 -229.062788) (xy 393.375388 -229.248716)
			(xy 393.411202 -229.28453) (xy 393.508738 -229.330758)
		)
		(stroke
			(width 0)
			(type solid)
		)
		(fill yes)
		(layer "F.Cu")
		(net "M_E_CPU0_SB_DQ<19>")
	)
	(gr_poly
		(pts
			(xy 393.648946 -279.27554) (xy 393.741402 -279.220168) (xy 393.704064 -279.033224) (xy 393.597384 -279.01773)
			(xy 393.547346 -279.027636) (xy 393.599162 -279.285446)
		)
		(stroke
			(width 0)
			(type solid)
		)
		(fill yes)
		(layer "F.Cu")
		(net "M_E_CPU0_SA_DQ<22>")
	)
	(gr_poly
		(pts
			(xy 393.652756 -230.049578) (xy 393.606528 -229.952042) (xy 393.57046 -229.916228) (xy 393.384532 -230.102156)
			(xy 393.4206 -230.13797) (xy 393.517882 -230.184198)
		)
		(stroke
			(width 0)
			(type solid)
		)
		(fill yes)
		(layer "F.Cu")
		(net "M_E_CPU0_SB_DQ<18>")
	)
	(gr_poly
		(pts
			(xy 393.656058 -264.526522) (xy 393.692126 -264.490708) (xy 393.506198 -264.30478) (xy 393.47013 -264.340594)
			(xy 393.423902 -264.43813) (xy 393.558776 -264.57275)
		)
		(stroke
			(width 0)
			(type solid)
		)
		(fill yes)
		(layer "F.Cu")
		(net "M_E_CPU0_SA_CB<6>")
	)
	(gr_poly
		(pts
			(xy 393.657582 -279.578054) (xy 393.60602 -279.320498) (xy 393.556236 -279.330404) (xy 393.46378 -279.385776)
			(xy 393.501118 -279.572466) (xy 393.607798 -279.588214)
		)
		(stroke
			(width 0)
			(type solid)
		)
		(fill yes)
		(layer "F.Cu")
		(net "M_E_CPU0_SA_DQ<22>")
	)
	(gr_poly
		(pts
			(xy 393.661392 -231.746552) (xy 393.615164 -231.64927) (xy 393.57935 -231.613202) (xy 393.393422 -231.79913)
			(xy 393.429236 -231.834944) (xy 393.526772 -231.881426)
		)
		(stroke
			(width 0)
			(type solid)
		)
		(fill yes)
		(layer "F.Cu")
		(net "M_E_CPU0_SB_DQ<13>")
	)
	(gr_poly
		(pts
			(xy 393.662154 -276.229318) (xy 393.75461 -276.173946) (xy 393.717272 -275.987002) (xy 393.610592 -275.971508)
			(xy 393.560808 -275.981414) (xy 393.61237 -276.239224)
		)
		(stroke
			(width 0)
			(type solid)
		)
		(fill yes)
		(layer "F.Cu")
		(net "M_E_CPU0_SA_DQ<23>")
	)
	(gr_poly
		(pts
			(xy 393.663678 -273.525488) (xy 393.699492 -273.48942) (xy 393.513818 -273.303746) (xy 393.47775 -273.33956)
			(xy 393.431522 -273.437096) (xy 393.566142 -273.571716)
		)
		(stroke
			(width 0)
			(type solid)
		)
		(fill yes)
		(layer "F.Cu")
		(net "M_E_CPU0_SA_DQ<26>")
	)
	(gr_poly
		(pts
			(xy 393.665456 -263.673082) (xy 393.70127 -263.637268) (xy 393.515342 -263.45134) (xy 393.479528 -263.487408)
			(xy 393.4333 -263.58469) (xy 393.56792 -263.71931)
		)
		(stroke
			(width 0)
			(type solid)
		)
		(fill yes)
		(layer "F.Cu")
		(net "M_E_CPU0_SA_CB<7>")
	)
	(gr_poly
		(pts
			(xy 393.665964 -268.275308) (xy 393.712192 -268.177772) (xy 393.577572 -268.043152) (xy 393.48029 -268.08938)
			(xy 393.444222 -268.125194) (xy 393.63015 -268.311122)
		)
		(stroke
			(width 0)
			(type solid)
		)
		(fill yes)
		(layer "F.Cu")
		(net "M_E_CPU0_SA_CB<0>")
	)
	(gr_poly
		(pts
			(xy 393.67079 -276.531832) (xy 393.619228 -276.274022) (xy 393.569444 -276.284182) (xy 393.476988 -276.339554)
			(xy 393.514326 -276.526244) (xy 393.621006 -276.541738)
		)
		(stroke
			(width 0)
			(type solid)
		)
		(fill yes)
		(layer "F.Cu")
		(net "M_E_CPU0_SA_DQ<23>")
	)
	(gr_poly
		(pts
			(xy 393.67079 -232.599992) (xy 393.624562 -232.502456) (xy 393.588494 -232.466642) (xy 393.402566 -232.65257)
			(xy 393.438634 -232.688384) (xy 393.535916 -232.734612)
		)
		(stroke
			(width 0)
			(type solid)
		)
		(fill yes)
		(layer "F.Cu")
		(net "M_E_CPU0_SB_DQ<12>")
	)
	(gr_poly
		(pts
			(xy 393.672822 -272.672048) (xy 393.708636 -272.63598) (xy 393.522962 -272.450306) (xy 393.486894 -272.48612)
			(xy 393.440666 -272.583656) (xy 393.575286 -272.718276)
		)
		(stroke
			(width 0)
			(type solid)
		)
		(fill yes)
		(layer "F.Cu")
		(net "M_E_CPU0_SA_DQ<27>")
	)
	(gr_poly
		(pts
			(xy 393.675362 -267.421868) (xy 393.72159 -267.324332) (xy 393.586716 -267.189712) (xy 393.489434 -267.23594)
			(xy 393.453366 -267.271754) (xy 393.639294 -267.457682)
		)
		(stroke
			(width 0)
			(type solid)
		)
		(fill yes)
		(layer "F.Cu")
		(net "M_E_CPU0_SA_CB<1>")
	)
	(gr_poly
		(pts
			(xy 393.695936 -235.163106) (xy 393.649454 -235.06557) (xy 393.61364 -235.029756) (xy 393.427712 -235.215684)
			(xy 393.46378 -235.251498) (xy 393.561062 -235.297726)
		)
		(stroke
			(width 0)
			(type solid)
		)
		(fill yes)
		(layer "F.Cu")
		(net "M_E_CPU0_SB_DQ<9>")
	)
	(gr_poly
		(pts
			(xy 393.699492 -269.930118) (xy 393.74572 -269.832582) (xy 393.6111 -269.697962) (xy 393.513564 -269.74419)
			(xy 393.47775 -269.780258) (xy 393.663424 -269.965932)
		)
		(stroke
			(width 0)
			(type solid)
		)
		(fill yes)
		(layer "F.Cu")
		(net "M_E_CPU0_SA_DQ<30>")
	)
	(gr_poly
		(pts
			(xy 393.704572 -236.86008) (xy 393.658344 -236.762544) (xy 393.622276 -236.72673) (xy 393.436348 -236.912658)
			(xy 393.472416 -236.948472) (xy 393.569698 -236.9947)
		)
		(stroke
			(width 0)
			(type solid)
		)
		(fill yes)
		(layer "F.Cu")
		(net "M_E_CPU0_SB_CB<3>")
	)
	(gr_poly
		(pts
			(xy 393.70508 -240.52657) (xy 393.669266 -240.490502) (xy 393.57173 -240.444274) (xy 393.43711 -240.578894)
			(xy 393.483338 -240.67643) (xy 393.519152 -240.712498)
		)
		(stroke
			(width 0)
			(type solid)
		)
		(fill yes)
		(layer "F.Cu")
		(net "M_E_CPU0_SB_CB<5>")
	)
	(gr_poly
		(pts
			(xy 393.705588 -236.017054) (xy 393.65936 -235.919772) (xy 393.623546 -235.883704) (xy 393.437618 -236.069632)
			(xy 393.473432 -236.105446) (xy 393.570968 -236.151928)
		)
		(stroke
			(width 0)
			(type solid)
		)
		(fill yes)
		(layer "F.Cu")
		(net "M_E_CPU0_SB_DQ<8>")
	)
	(gr_poly
		(pts
			(xy 393.70889 -269.076424) (xy 393.755118 -268.979142) (xy 393.620498 -268.844268) (xy 393.522962 -268.890496)
			(xy 393.487148 -268.926564) (xy 393.673076 -269.112492)
		)
		(stroke
			(width 0)
			(type solid)
		)
		(fill yes)
		(layer "F.Cu")
		(net "M_E_CPU0_SA_DQ<31>")
	)
	(gr_poly
		(pts
			(xy 393.713716 -237.71352) (xy 393.667488 -237.615984) (xy 393.63142 -237.58017) (xy 393.445746 -237.765844)
			(xy 393.48156 -237.801912) (xy 393.579096 -237.84814)
		)
		(stroke
			(width 0)
			(type solid)
		)
		(fill yes)
		(layer "F.Cu")
		(net "M_E_CPU0_SB_CB<2>")
	)
	(gr_poly
		(pts
			(xy 393.714224 -278.04491) (xy 393.80668 -277.989538) (xy 393.769342 -277.802848) (xy 393.662662 -277.787354)
			(xy 393.612878 -277.79726) (xy 393.66444 -278.05507)
		)
		(stroke
			(width 0)
			(type solid)
		)
		(fill yes)
		(layer "F.Cu")
		(net "M_E_CPU0_SA_DQ<21>")
	)
	(gr_poly
		(pts
			(xy 393.714478 -241.379756) (xy 393.67841 -241.343942) (xy 393.581128 -241.297714) (xy 393.446254 -241.432334)
			(xy 393.492482 -241.52987) (xy 393.52855 -241.565684)
		)
		(stroke
			(width 0)
			(type solid)
		)
		(fill yes)
		(layer "F.Cu")
		(net "M_E_CPU0_SB_CB<4>")
	)
	(gr_poly
		(pts
			(xy 393.72286 -278.347678) (xy 393.671298 -278.089868) (xy 393.621514 -278.099774) (xy 393.529058 -278.155146)
			(xy 393.566396 -278.34209) (xy 393.673076 -278.357584)
		)
		(stroke
			(width 0)
			(type solid)
		)
		(fill yes)
		(layer "F.Cu")
		(net "M_E_CPU0_SA_DQ<21>")
	)
	(gr_poly
		(pts
			(xy 393.723368 -264.88136) (xy 393.769596 -264.783824) (xy 393.634976 -264.649204) (xy 393.53744 -264.695432)
			(xy 393.501626 -264.7315) (xy 393.687554 -264.917428)
		)
		(stroke
			(width 0)
			(type solid)
		)
		(fill yes)
		(layer "F.Cu")
		(net "M_E_CPU0_SA_CB<4>")
	)
	(gr_poly
		(pts
			(xy 393.732512 -264.02792) (xy 393.77874 -263.930638) (xy 393.64412 -263.795764) (xy 393.546584 -263.842246)
			(xy 393.51077 -263.87806) (xy 393.696698 -264.063988)
		)
		(stroke
			(width 0)
			(type solid)
		)
		(fill yes)
		(layer "F.Cu")
		(net "M_E_CPU0_SA_CB<5>")
	)
	(gr_poly
		(pts
			(xy 393.740132 -273.026886) (xy 393.78636 -272.92935) (xy 393.65174 -272.79473) (xy 393.554204 -272.840958)
			(xy 393.51839 -272.877026) (xy 393.704064 -273.0627)
		)
		(stroke
			(width 0)
			(type solid)
		)
		(fill yes)
		(layer "F.Cu")
		(net "M_E_CPU0_SA_DQ<25>")
	)
	(gr_poly
		(pts
			(xy 393.765786 -279.860756) (xy 393.858496 -279.805384) (xy 393.821158 -279.618694) (xy 393.714224 -279.602946)
			(xy 393.66444 -279.613106) (xy 393.716002 -279.870916)
		)
		(stroke
			(width 0)
			(type solid)
		)
		(fill yes)
		(layer "F.Cu")
		(net "M_E_CPU0_SA_DQ<22>")
	)
	(gr_poly
		(pts
			(xy 393.771628 -285.143448) (xy 393.720828 -285.143448) (xy 393.619228 -285.17977) (xy 393.619228 -285.37027)
			(xy 393.720828 -285.406338) (xy 393.771628 -285.406338)
		)
		(stroke
			(width 0)
			(type solid)
		)
		(fill yes)
		(layer "F.Cu")
		(net "M_E_CPU0_SA_DQ<22>")
	)
	(gr_poly
		(pts
			(xy 393.771628 -284.546548) (xy 393.720828 -284.546548) (xy 393.619228 -284.58287) (xy 393.619228 -284.77337)
			(xy 393.720828 -284.809438) (xy 393.771628 -284.809438)
		)
		(stroke
			(width 0)
			(type solid)
		)
		(fill yes)
		(layer "F.Cu")
		(net "M_E_CPU0_SA_DQ<22>")
	)
	(gr_poly
		(pts
			(xy 393.771628 -283.949648) (xy 393.720828 -283.949648) (xy 393.619228 -283.98597) (xy 393.619228 -284.17647)
			(xy 393.720828 -284.212538) (xy 393.771628 -284.212538)
		)
		(stroke
			(width 0)
			(type solid)
		)
		(fill yes)
		(layer "F.Cu")
		(net "M_E_CPU0_SA_DQ<22>")
	)
	(gr_poly
		(pts
			(xy 393.771628 -283.352748) (xy 393.720828 -283.352748) (xy 393.619228 -283.38907) (xy 393.619228 -283.57957)
			(xy 393.720828 -283.615638) (xy 393.771628 -283.615638)
		)
		(stroke
			(width 0)
			(type solid)
		)
		(fill yes)
		(layer "F.Cu")
		(net "M_E_CPU0_SA_DQ<22>")
	)
	(gr_poly
		(pts
			(xy 393.771628 -282.755848) (xy 393.720828 -282.755848) (xy 393.619228 -282.79217) (xy 393.619228 -282.98267)
			(xy 393.720828 -283.018738) (xy 393.771628 -283.018738)
		)
		(stroke
			(width 0)
			(type solid)
		)
		(fill yes)
		(layer "F.Cu")
		(net "M_E_CPU0_SA_DQ<22>")
	)
	(gr_poly
		(pts
			(xy 393.771628 -282.158948) (xy 393.720828 -282.158948) (xy 393.619228 -282.19527) (xy 393.619228 -282.38577)
			(xy 393.720828 -282.421838) (xy 393.771628 -282.421838)
		)
		(stroke
			(width 0)
			(type solid)
		)
		(fill yes)
		(layer "F.Cu")
		(net "M_E_CPU0_SA_DQ<22>")
	)
	(gr_poly
		(pts
			(xy 393.771628 -281.562048) (xy 393.720828 -281.562048) (xy 393.619228 -281.59837) (xy 393.619228 -281.78887)
			(xy 393.720828 -281.824938) (xy 393.771628 -281.824938)
		)
		(stroke
			(width 0)
			(type solid)
		)
		(fill yes)
		(layer "F.Cu")
		(net "M_E_CPU0_SA_DQ<22>")
	)
	(gr_poly
		(pts
			(xy 393.771628 -280.965148) (xy 393.720828 -280.965148) (xy 393.619228 -281.00147) (xy 393.619228 -281.19197)
			(xy 393.720828 -281.228038) (xy 393.771628 -281.228038)
		)
		(stroke
			(width 0)
			(type solid)
		)
		(fill yes)
		(layer "F.Cu")
		(net "M_E_CPU0_SA_DQ<22>")
	)
	(gr_poly
		(pts
			(xy 393.77239 -228.851714) (xy 393.736322 -228.8159) (xy 393.63904 -228.769672) (xy 393.504166 -228.904292)
			(xy 393.550648 -229.001828) (xy 393.586462 -229.037642)
		)
		(stroke
			(width 0)
			(type solid)
		)
		(fill yes)
		(layer "F.Cu")
		(net "M_E_CPU0_SB_DQ<19>")
	)
	(gr_poly
		(pts
			(xy 393.779248 -276.814534) (xy 393.871704 -276.759162) (xy 393.834366 -276.572472) (xy 393.727686 -276.556724)
			(xy 393.677902 -276.566884) (xy 393.729464 -276.82444)
		)
		(stroke
			(width 0)
			(type solid)
		)
		(fill yes)
		(layer "F.Cu")
		(net "M_E_CPU0_SA_DQ<23>")
	)
	(gr_poly
		(pts
			(xy 393.781534 -229.705154) (xy 393.74572 -229.669086) (xy 393.648184 -229.622858) (xy 393.513564 -229.757732)
			(xy 393.559792 -229.855014) (xy 393.595606 -229.891082)
		)
		(stroke
			(width 0)
			(type solid)
		)
		(fill yes)
		(layer "F.Cu")
		(net "M_E_CPU0_SB_DQ<18>")
	)
	(gr_poly
		(pts
			(xy 393.782804 -240.2332) (xy 393.736576 -240.135664) (xy 393.700508 -240.09985) (xy 393.51458 -240.285778)
			(xy 393.550648 -240.321592) (xy 393.64793 -240.36782)
		)
		(stroke
			(width 0)
			(type solid)
		)
		(fill yes)
		(layer "F.Cu")
		(net "M_E_CPU0_SB_CB<7>")
	)
	(gr_poly
		(pts
			(xy 393.787884 -277.117302) (xy 393.736322 -276.859492) (xy 393.686538 -276.869398) (xy 393.594082 -276.92477)
			(xy 393.63142 -277.111714) (xy 393.7381 -277.127208)
		)
		(stroke
			(width 0)
			(type solid)
		)
		(fill yes)
		(layer "F.Cu")
		(net "M_E_CPU0_SA_DQ<23>")
	)
	(gr_poly
		(pts
			(xy 393.790424 -231.402128) (xy 393.754356 -231.366314) (xy 393.657074 -231.320086) (xy 393.5222 -231.454706)
			(xy 393.568428 -231.552242) (xy 393.604496 -231.588056)
		)
		(stroke
			(width 0)
			(type solid)
		)
		(fill yes)
		(layer "F.Cu")
		(net "M_E_CPU0_SB_DQ<13>")
	)
	(gr_poly
		(pts
			(xy 393.791948 -241.08664) (xy 393.74572 -240.989104) (xy 393.709652 -240.95329) (xy 393.523978 -241.138964)
			(xy 393.559792 -241.175032) (xy 393.657328 -241.22126)
		)
		(stroke
			(width 0)
			(type solid)
		)
		(fill yes)
		(layer "F.Cu")
		(net "M_E_CPU0_SB_CB<6>")
	)
	(gr_poly
		(pts
			(xy 393.799568 -232.255568) (xy 393.763754 -232.219754) (xy 393.666218 -232.173526) (xy 393.531598 -232.308146)
			(xy 393.577826 -232.405428) (xy 393.61364 -232.441496)
		)
		(stroke
			(width 0)
			(type solid)
		)
		(fill yes)
		(layer "F.Cu")
		(net "M_E_CPU0_SB_DQ<12>")
	)
	(gr_poly
		(pts
			(xy 393.805156 -268.55801) (xy 393.841224 -268.522196) (xy 393.655296 -268.336268) (xy 393.619482 -268.372082)
			(xy 393.573 -268.469618) (xy 393.707874 -268.604238)
		)
		(stroke
			(width 0)
			(type solid)
		)
		(fill yes)
		(layer "F.Cu")
		(net "M_E_CPU0_SA_CB<0>")
	)
	(gr_poly
		(pts
			(xy 393.814554 -267.704824) (xy 393.850368 -267.668756) (xy 393.66444 -267.482828) (xy 393.628626 -267.518896)
			(xy 393.582398 -267.616178) (xy 393.717018 -267.751052)
		)
		(stroke
			(width 0)
			(type solid)
		)
		(fill yes)
		(layer "F.Cu")
		(net "M_E_CPU0_SA_CB<1>")
	)
	(gr_poly
		(pts
			(xy 393.824714 -234.818682) (xy 393.7889 -234.782868) (xy 393.691364 -234.73664) (xy 393.556744 -234.87126)
			(xy 393.602972 -234.968796) (xy 393.638786 -235.00461)
		)
		(stroke
			(width 0)
			(type solid)
		)
		(fill yes)
		(layer "F.Cu")
		(net "M_E_CPU0_SB_DQ<9>")
	)
	(gr_poly
		(pts
			(xy 393.831318 -278.63038) (xy 393.923774 -278.575008) (xy 393.886436 -278.388064) (xy 393.779756 -278.37257)
			(xy 393.729972 -278.382476) (xy 393.781534 -278.640286)
		)
		(stroke
			(width 0)
			(type solid)
		)
		(fill yes)
		(layer "F.Cu")
		(net "M_E_CPU0_SA_DQ<21>")
	)
	(gr_poly
		(pts
			(xy 393.83335 -236.515656) (xy 393.797536 -236.479842) (xy 393.7 -236.433614) (xy 393.56538 -236.568234)
			(xy 393.611608 -236.665516) (xy 393.647422 -236.701584)
		)
		(stroke
			(width 0)
			(type solid)
		)
		(fill yes)
		(layer "F.Cu")
		(net "M_E_CPU0_SB_CB<3>")
	)
	(gr_poly
		(pts
			(xy 393.83462 -235.67263) (xy 393.798552 -235.636816) (xy 393.70127 -235.590588) (xy 393.566396 -235.725208)
			(xy 393.612624 -235.822744) (xy 393.648692 -235.858558)
		)
		(stroke
			(width 0)
			(type solid)
		)
		(fill yes)
		(layer "F.Cu")
		(net "M_E_CPU0_SB_DQ<8>")
	)
	(gr_poly
		(pts
			(xy 393.838684 -270.213074) (xy 393.874498 -270.177006) (xy 393.68857 -269.991078) (xy 393.652756 -270.027146)
			(xy 393.606528 -270.124428) (xy 393.741148 -270.259302)
		)
		(stroke
			(width 0)
			(type solid)
		)
		(fill yes)
		(layer "F.Cu")
		(net "M_E_CPU0_SA_DQ<30>")
	)
	(gr_poly
		(pts
			(xy 393.839954 -278.932894) (xy 393.788392 -278.675084) (xy 393.738608 -278.685244) (xy 393.646152 -278.740616)
			(xy 393.68349 -278.927306) (xy 393.79017 -278.9428)
		)
		(stroke
			(width 0)
			(type solid)
		)
		(fill yes)
		(layer "F.Cu")
		(net "M_E_CPU0_SA_DQ<21>")
	)
	(gr_poly
		(pts
			(xy 393.842494 -237.369096) (xy 393.80668 -237.333028) (xy 393.709144 -237.2868) (xy 393.574524 -237.421674)
			(xy 393.620752 -237.518956) (xy 393.656566 -237.555024)
		)
		(stroke
			(width 0)
			(type solid)
		)
		(fill yes)
		(layer "F.Cu")
		(net "M_E_CPU0_SB_CB<2>")
	)
	(gr_poly
		(pts
			(xy 393.848082 -269.35938) (xy 393.88415 -269.323566) (xy 393.698222 -269.137638) (xy 393.662154 -269.173452)
			(xy 393.615926 -269.270988) (xy 393.7508 -269.405608)
		)
		(stroke
			(width 0)
			(type solid)
		)
		(fill yes)
		(layer "F.Cu")
		(net "M_E_CPU0_SA_DQ<31>")
	)
	(gr_poly
		(pts
			(xy 393.859004 -229.411784) (xy 393.812776 -229.314248) (xy 393.776962 -229.278434) (xy 393.591034 -229.464362)
			(xy 393.626848 -229.500176) (xy 393.724384 -229.546404)
		)
		(stroke
			(width 0)
			(type solid)
		)
		(fill yes)
		(layer "F.Cu")
		(net "M_E_CPU0_SB_DQ<17>")
	)
	(gr_poly
		(pts
			(xy 393.859258 -274.330414) (xy 393.951714 -274.275042) (xy 393.914376 -274.088098) (xy 393.807696 -274.072604)
			(xy 393.757912 -274.08251) (xy 393.809474 -274.34032)
		)
		(stroke
			(width 0)
			(type solid)
		)
		(fill yes)
		(layer "F.Cu")
		(net "M_E_CPU0_SA_DQ<24>")
	)
	(gr_poly
		(pts
			(xy 393.86256 -265.164316) (xy 393.898374 -265.128248) (xy 393.7127 -264.942574) (xy 393.676632 -264.978388)
			(xy 393.630404 -265.075924) (xy 393.765024 -265.210544)
		)
		(stroke
			(width 0)
			(type solid)
		)
		(fill yes)
		(layer "F.Cu")
		(net "M_E_CPU0_SA_CB<4>")
	)
	(gr_poly
		(pts
			(xy 393.867894 -274.632928) (xy 393.816332 -274.375118) (xy 393.766548 -274.385278) (xy 393.674092 -274.44065)
			(xy 393.71143 -274.62734) (xy 393.81811 -274.642834)
		)
		(stroke
			(width 0)
			(type solid)
		)
		(fill yes)
		(layer "F.Cu")
		(net "M_E_CPU0_SA_DQ<24>")
	)
	(gr_poly
		(pts
			(xy 393.867894 -231.108758) (xy 393.821666 -231.011476) (xy 393.785852 -230.975408) (xy 393.599924 -231.161336)
			(xy 393.635738 -231.197404) (xy 393.733274 -231.243632)
		)
		(stroke
			(width 0)
			(type solid)
		)
		(fill yes)
		(layer "F.Cu")
		(net "M_E_CPU0_SB_DQ<15>")
	)
	(gr_poly
		(pts
			(xy 393.868402 -230.265224) (xy 393.822174 -230.167688) (xy 393.786106 -230.131874) (xy 393.600178 -230.317802)
			(xy 393.636246 -230.353616) (xy 393.733528 -230.399844)
		)
		(stroke
			(width 0)
			(type solid)
		)
		(fill yes)
		(layer "F.Cu")
		(net "M_E_CPU0_SB_DQ<16>")
	)
	(gr_poly
		(pts
			(xy 393.871704 -264.310876) (xy 393.907772 -264.275062) (xy 393.721844 -264.089134) (xy 393.685776 -264.124948)
			(xy 393.639548 -264.222484) (xy 393.774422 -264.357104)
		)
		(stroke
			(width 0)
			(type solid)
		)
		(fill yes)
		(layer "F.Cu")
		(net "M_E_CPU0_SA_CB<5>")
	)
	(gr_poly
		(pts
			(xy 393.877038 -231.962198) (xy 393.83081 -231.864916) (xy 393.794996 -231.828848) (xy 393.609068 -232.014776)
			(xy 393.644882 -232.05059) (xy 393.742418 -232.097072)
		)
		(stroke
			(width 0)
			(type solid)
		)
		(fill yes)
		(layer "F.Cu")
		(net "M_E_CPU0_SB_DQ<14>")
	)
	(gr_poly
		(pts
			(xy 393.879324 -273.309842) (xy 393.915138 -273.273774) (xy 393.72921 -273.087846) (xy 393.693396 -273.123914)
			(xy 393.647168 -273.221196) (xy 393.781788 -273.35607)
		)
		(stroke
			(width 0)
			(type solid)
		)
		(fill yes)
		(layer "F.Cu")
		(net "M_E_CPU0_SA_DQ<25>")
	)
	(gr_poly
		(pts
			(xy 393.88161 -268.059662) (xy 393.927838 -267.962126) (xy 393.793218 -267.827506) (xy 393.695936 -267.873734)
			(xy 393.659868 -267.909548) (xy 393.845796 -268.095476)
		)
		(stroke
			(width 0)
			(type solid)
		)
		(fill yes)
		(layer "F.Cu")
		(net "M_E_CPU0_SA_CB<2>")
	)
	(gr_poly
		(pts
			(xy 393.891008 -267.206222) (xy 393.937236 -267.108686) (xy 393.802362 -266.974066) (xy 393.70508 -267.020294)
			(xy 393.669012 -267.056108) (xy 393.85494 -267.242036)
		)
		(stroke
			(width 0)
			(type solid)
		)
		(fill yes)
		(layer "F.Cu")
		(net "M_E_CPU0_SA_CB<3>")
	)
	(gr_poly
		(pts
			(xy 393.896342 -277.400004) (xy 393.988798 -277.344378) (xy 393.95146 -277.157688) (xy 393.84478 -277.142194)
			(xy 393.794996 -277.1521) (xy 393.846558 -277.40991)
		)
		(stroke
			(width 0)
			(type solid)
		)
		(fill yes)
		(layer "F.Cu")
		(net "M_E_CPU0_SA_DQ<23>")
	)
	(gr_poly
		(pts
			(xy 393.90193 -234.525058) (xy 393.855702 -234.427776) (xy 393.819888 -234.391708) (xy 393.63396 -234.577636)
			(xy 393.669774 -234.613704) (xy 393.76731 -234.659932)
		)
		(stroke
			(width 0)
			(type solid)
		)
		(fill yes)
		(layer "F.Cu")
		(net "M_E_CPU0_SB_DQ<11>")
	)
	(gr_poly
		(pts
			(xy 393.904978 -277.702518) (xy 393.853416 -277.444708) (xy 393.803632 -277.454614) (xy 393.711176 -277.509986)
			(xy 393.748514 -277.69693) (xy 393.855194 -277.712424)
		)
		(stroke
			(width 0)
			(type solid)
		)
		(fill yes)
		(layer "F.Cu")
		(net "M_E_CPU0_SA_DQ<23>")
	)
	(gr_poly
		(pts
			(xy 393.905994 -270.567912) (xy 393.952222 -270.470376) (xy 393.817348 -270.335756) (xy 393.720066 -270.381984)
			(xy 393.683998 -270.417798) (xy 393.869926 -270.603726)
		)
		(stroke
			(width 0)
			(type solid)
		)
		(fill yes)
		(layer "F.Cu")
		(net "M_E_CPU0_SA_DQ<28>")
	)
	(gr_poly
		(pts
			(xy 393.911582 -239.888776) (xy 393.875768 -239.852962) (xy 393.778232 -239.80648) (xy 393.643612 -239.941354)
			(xy 393.68984 -240.038636) (xy 393.725654 -240.074704)
		)
		(stroke
			(width 0)
			(type solid)
		)
		(fill yes)
		(layer "F.Cu")
		(net "M_E_CPU0_SB_CB<7>")
	)
	(gr_poly
		(pts
			(xy 393.91209 -235.37926) (xy 393.865608 -235.281724) (xy 393.829794 -235.24591) (xy 393.643866 -235.431838)
			(xy 393.679934 -235.467652) (xy 393.777216 -235.51388)
		)
		(stroke
			(width 0)
			(type solid)
		)
		(fill yes)
		(layer "F.Cu")
		(net "M_E_CPU0_SB_DQ<10>")
	)
	(gr_poly
		(pts
			(xy 393.915138 -269.714218) (xy 393.961366 -269.616936) (xy 393.826746 -269.482316) (xy 393.72921 -269.528544)
			(xy 393.693396 -269.564358) (xy 393.879324 -269.750286)
		)
		(stroke
			(width 0)
			(type solid)
		)
		(fill yes)
		(layer "F.Cu")
		(net "M_E_CPU0_SA_DQ<29>")
	)
	(gr_poly
		(pts
			(xy 393.920218 -237.075726) (xy 393.87399 -236.97819) (xy 393.837922 -236.942376) (xy 393.651994 -237.128304)
			(xy 393.688062 -237.164118) (xy 393.785344 -237.210346)
		)
		(stroke
			(width 0)
			(type solid)
		)
		(fill yes)
		(layer "F.Cu")
		(net "M_E_CPU0_SB_CB<1>")
	)
	(gr_poly
		(pts
			(xy 393.920726 -240.742216) (xy 393.884912 -240.706148) (xy 393.787376 -240.65992) (xy 393.652756 -240.79454)
			(xy 393.698984 -240.892076) (xy 393.734798 -240.928144)
		)
		(stroke
			(width 0)
			(type solid)
		)
		(fill yes)
		(layer "F.Cu")
		(net "M_E_CPU0_SB_CB<6>")
	)
	(gr_poly
		(pts
			(xy 393.924028 -285.07182) (xy 393.924028 -284.88132) (xy 393.822428 -284.844998) (xy 393.771628 -284.844998)
			(xy 393.771628 -285.108142) (xy 393.822428 -285.108142)
		)
		(stroke
			(width 0)
			(type solid)
		)
		(fill yes)
		(layer "F.Cu")
		(net "M_E_CPU0_SA_DQ<22>")
	)
	(gr_poly
		(pts
			(xy 393.924028 -284.47492) (xy 393.924028 -284.28442) (xy 393.822428 -284.248098) (xy 393.771628 -284.248098)
			(xy 393.771628 -284.511242) (xy 393.822428 -284.511242)
		)
		(stroke
			(width 0)
			(type solid)
		)
		(fill yes)
		(layer "F.Cu")
		(net "M_E_CPU0_SA_DQ<22>")
	)
	(gr_poly
		(pts
			(xy 393.924028 -283.87802) (xy 393.924028 -283.68752) (xy 393.822428 -283.651198) (xy 393.771628 -283.651198)
			(xy 393.771628 -283.914342) (xy 393.822428 -283.914342)
		)
		(stroke
			(width 0)
			(type solid)
		)
		(fill yes)
		(layer "F.Cu")
		(net "M_E_CPU0_SA_DQ<22>")
	)
	(gr_poly
		(pts
			(xy 393.924028 -283.28112) (xy 393.924028 -283.09062) (xy 393.822428 -283.054298) (xy 393.771628 -283.054298)
			(xy 393.771628 -283.317442) (xy 393.822428 -283.317442)
		)
		(stroke
			(width 0)
			(type solid)
		)
		(fill yes)
		(layer "F.Cu")
		(net "M_E_CPU0_SA_DQ<22>")
	)
	(gr_poly
		(pts
			(xy 393.924028 -282.68422) (xy 393.924028 -282.49372) (xy 393.822428 -282.457398) (xy 393.771628 -282.457398)
			(xy 393.771628 -282.720542) (xy 393.822428 -282.720542)
		)
		(stroke
			(width 0)
			(type solid)
		)
		(fill yes)
		(layer "F.Cu")
		(net "M_E_CPU0_SA_DQ<22>")
	)
	(gr_poly
		(pts
			(xy 393.924028 -282.08732) (xy 393.924028 -281.89682) (xy 393.822428 -281.860498) (xy 393.771628 -281.860498)
			(xy 393.771628 -282.123642) (xy 393.822428 -282.123642)
		)
		(stroke
			(width 0)
			(type solid)
		)
		(fill yes)
		(layer "F.Cu")
		(net "M_E_CPU0_SA_DQ<22>")
	)
	(gr_poly
		(pts
			(xy 393.924028 -281.49042) (xy 393.924028 -281.29992) (xy 393.822428 -281.263598) (xy 393.771628 -281.263598)
			(xy 393.771628 -281.526742) (xy 393.822428 -281.526742)
		)
		(stroke
			(width 0)
			(type solid)
		)
		(fill yes)
		(layer "F.Cu")
		(net "M_E_CPU0_SA_DQ<22>")
	)
	(gr_poly
		(pts
			(xy 393.924028 -280.89352) (xy 393.924028 -280.70302) (xy 393.822428 -280.666698) (xy 393.771628 -280.666698)
			(xy 393.771628 -280.929842) (xy 393.822428 -280.929842)
		)
		(stroke
			(width 0)
			(type solid)
		)
		(fill yes)
		(layer "F.Cu")
		(net "M_E_CPU0_SA_DQ<22>")
	)
	(gr_poly
		(pts
			(xy 393.929362 -237.929166) (xy 393.883134 -237.83163) (xy 393.847066 -237.795816) (xy 393.661392 -237.98149)
			(xy 393.697206 -238.017558) (xy 393.794742 -238.063786)
		)
		(stroke
			(width 0)
			(type solid)
		)
		(fill yes)
		(layer "F.Cu")
		(net "M_E_CPU0_SB_CB<0>")
	)
	(gr_poly
		(pts
			(xy 393.939014 -264.665714) (xy 393.985242 -264.568178) (xy 393.850622 -264.433558) (xy 393.753086 -264.479786)
			(xy 393.717272 -264.515854) (xy 393.9032 -264.701782)
		)
		(stroke
			(width 0)
			(type solid)
		)
		(fill yes)
		(layer "F.Cu")
		(net "M_E_CPU0_SA_CB<6>")
	)
	(gr_poly
		(pts
			(xy 393.946634 -273.66468) (xy 393.992862 -273.567144) (xy 393.857988 -273.432524) (xy 393.760706 -273.478752)
			(xy 393.724638 -273.514566) (xy 393.910566 -273.700494)
		)
		(stroke
			(width 0)
			(type solid)
		)
		(fill yes)
		(layer "F.Cu")
		(net "M_E_CPU0_SA_DQ<26>")
	)
	(gr_poly
		(pts
			(xy 393.948158 -263.812274) (xy 393.994386 -263.714992) (xy 393.859766 -263.580118) (xy 393.76223 -263.6266)
			(xy 393.726416 -263.662414) (xy 393.912344 -263.848342)
		)
		(stroke
			(width 0)
			(type solid)
		)
		(fill yes)
		(layer "F.Cu")
		(net "M_E_CPU0_SA_CB<7>")
	)
	(gr_poly
		(pts
			(xy 393.948412 -279.215596) (xy 394.040868 -279.160224) (xy 394.00353 -278.973534) (xy 393.89685 -278.957786)
			(xy 393.847066 -278.967692) (xy 393.898628 -279.225502)
		)
		(stroke
			(width 0)
			(type solid)
		)
		(fill yes)
		(layer "F.Cu")
		(net "M_E_CPU0_SA_DQ<21>")
	)
	(gr_poly
		(pts
			(xy 393.955778 -272.81124) (xy 394.002006 -272.713704) (xy 393.867132 -272.579084) (xy 393.76985 -272.625312)
			(xy 393.733782 -272.661126) (xy 393.91971 -272.847054)
		)
		(stroke
			(width 0)
			(type solid)
		)
		(fill yes)
		(layer "F.Cu")
		(net "M_E_CPU0_SA_DQ<27>")
	)
	(gr_poly
		(pts
			(xy 393.957048 -279.518364) (xy 393.905486 -279.260554) (xy 393.855702 -279.27046) (xy 393.763246 -279.325832)
			(xy 393.800584 -279.512522) (xy 393.907264 -279.52827)
		)
		(stroke
			(width 0)
			(type solid)
		)
		(fill yes)
		(layer "F.Cu")
		(net "M_E_CPU0_SA_DQ<21>")
	)
	(gr_poly
		(pts
			(xy 393.976352 -274.91563) (xy 394.068808 -274.860258) (xy 394.03147 -274.673568) (xy 393.92479 -274.65782)
			(xy 393.875006 -274.66798) (xy 393.926568 -274.925536)
		)
		(stroke
			(width 0)
			(type solid)
		)
		(fill yes)
		(layer "F.Cu")
		(net "M_E_CPU0_SA_DQ<24>")
	)
	(gr_poly
		(pts
			(xy 393.984988 -275.218398) (xy 393.933426 -274.960588) (xy 393.883642 -274.970494) (xy 393.791186 -275.025866)
			(xy 393.828524 -275.21281) (xy 393.935204 -275.228304)
		)
		(stroke
			(width 0)
			(type solid)
		)
		(fill yes)
		(layer "F.Cu")
		(net "M_E_CPU0_SA_DQ<24>")
	)
	(gr_poly
		(pts
			(xy 393.988036 -229.06736) (xy 393.951968 -229.031546) (xy 393.854686 -228.985318) (xy 393.719812 -229.119938)
			(xy 393.766294 -229.217474) (xy 393.802108 -229.253288)
		)
		(stroke
			(width 0)
			(type solid)
		)
		(fill yes)
		(layer "F.Cu")
		(net "M_E_CPU0_SB_DQ<17>")
	)
	(gr_poly
		(pts
			(xy 393.996672 -230.764588) (xy 393.960858 -230.72852) (xy 393.863322 -230.682292) (xy 393.728702 -230.816912)
			(xy 393.77493 -230.914448) (xy 393.810998 -230.950262)
		)
		(stroke
			(width 0)
			(type solid)
		)
		(fill yes)
		(layer "F.Cu")
		(net "M_E_CPU0_SB_DQ<15>")
	)
	(gr_poly
		(pts
			(xy 393.99718 -229.9208) (xy 393.961366 -229.884732) (xy 393.86383 -229.838504) (xy 393.72921 -229.973378)
			(xy 393.775438 -230.07066) (xy 393.811252 -230.106728)
		)
		(stroke
			(width 0)
			(type solid)
		)
		(fill yes)
		(layer "F.Cu")
		(net "M_E_CPU0_SB_DQ<16>")
	)
	(gr_poly
		(pts
			(xy 393.99718 -227.922074) (xy 393.94638 -227.922074) (xy 393.84478 -227.958142) (xy 393.84478 -228.148642)
			(xy 393.94638 -228.184964) (xy 393.99718 -228.184964)
		)
		(stroke
			(width 0)
			(type solid)
		)
		(fill yes)
		(layer "F.Cu")
		(net "M_E_CPU0_SB_DQ<19>")
	)
	(gr_poly
		(pts
			(xy 393.99718 -227.325174) (xy 393.94638 -227.325174) (xy 393.84478 -227.361242) (xy 393.84478 -227.551742)
			(xy 393.94638 -227.588064) (xy 393.99718 -227.588064)
		)
		(stroke
			(width 0)
			(type solid)
		)
		(fill yes)
		(layer "F.Cu")
		(net "M_E_CPU0_SB_DQ<19>")
	)
	(gr_poly
		(pts
			(xy 393.99718 -226.728274) (xy 393.94638 -226.728274) (xy 393.84478 -226.764342) (xy 393.84478 -226.954842)
			(xy 393.94638 -226.991164) (xy 393.99718 -226.991164)
		)
		(stroke
			(width 0)
			(type solid)
		)
		(fill yes)
		(layer "F.Cu")
		(net "M_E_CPU0_SB_DQ<19>")
	)
	(gr_poly
		(pts
			(xy 393.99718 -226.131374) (xy 393.94638 -226.131374) (xy 393.84478 -226.167442) (xy 393.84478 -226.357942)
			(xy 393.94638 -226.394264) (xy 393.99718 -226.394264)
		)
		(stroke
			(width 0)
			(type solid)
		)
		(fill yes)
		(layer "F.Cu")
		(net "M_E_CPU0_SB_DQ<19>")
	)
	(gr_poly
		(pts
			(xy 393.99718 -225.534474) (xy 393.94638 -225.534474) (xy 393.84478 -225.570542) (xy 393.84478 -225.761042)
			(xy 393.94638 -225.797364) (xy 393.99718 -225.797364)
		)
		(stroke
			(width 0)
			(type solid)
		)
		(fill yes)
		(layer "F.Cu")
		(net "M_E_CPU0_SB_DQ<19>")
	)
	(gr_poly
		(pts
			(xy 393.99718 -224.937574) (xy 393.94638 -224.937574) (xy 393.84478 -224.973642) (xy 393.84478 -225.164142)
			(xy 393.94638 -225.200464) (xy 393.99718 -225.200464)
		)
		(stroke
			(width 0)
			(type solid)
		)
		(fill yes)
		(layer "F.Cu")
		(net "M_E_CPU0_SB_DQ<19>")
	)
	(gr_poly
		(pts
			(xy 393.99718 -224.340674) (xy 393.94638 -224.340674) (xy 393.84478 -224.376742) (xy 393.84478 -224.567242)
			(xy 393.94638 -224.603564) (xy 393.99718 -224.603564)
		)
		(stroke
			(width 0)
			(type solid)
		)
		(fill yes)
		(layer "F.Cu")
		(net "M_E_CPU0_SB_DQ<19>")
	)
	(gr_poly
		(pts
			(xy 393.99718 -223.743774) (xy 393.94638 -223.743774) (xy 393.84478 -223.779842) (xy 393.84478 -223.970342)
			(xy 393.94638 -224.006664) (xy 393.99718 -224.006664)
		)
		(stroke
			(width 0)
			(type solid)
		)
		(fill yes)
		(layer "F.Cu")
		(net "M_E_CPU0_SB_DQ<19>")
	)
	(gr_poly
		(pts
			(xy 393.99718 -223.146874) (xy 393.94638 -223.146874) (xy 393.84478 -223.182942) (xy 393.84478 -223.373442)
			(xy 393.94638 -223.409764) (xy 393.99718 -223.409764)
		)
		(stroke
			(width 0)
			(type solid)
		)
		(fill yes)
		(layer "F.Cu")
		(net "M_E_CPU0_SB_DQ<19>")
	)
	(gr_poly
		(pts
			(xy 393.99718 -222.549974) (xy 393.94638 -222.549974) (xy 393.84478 -222.586042) (xy 393.84478 -222.776542)
			(xy 393.94638 -222.812864) (xy 393.99718 -222.812864)
		)
		(stroke
			(width 0)
			(type solid)
		)
		(fill yes)
		(layer "F.Cu")
		(net "M_E_CPU0_SB_DQ<19>")
	)
	(gr_poly
		(pts
			(xy 393.99718 -221.953074) (xy 393.94638 -221.953074) (xy 393.84478 -221.989142) (xy 393.84478 -222.179642)
			(xy 393.94638 -222.215964) (xy 393.99718 -222.215964)
		)
		(stroke
			(width 0)
			(type solid)
		)
		(fill yes)
		(layer "F.Cu")
		(net "M_E_CPU0_SB_DQ<19>")
	)
	(gr_poly
		(pts
			(xy 393.99718 -221.356174) (xy 393.94638 -221.356174) (xy 393.84478 -221.392242) (xy 393.84478 -221.582742)
			(xy 393.94638 -221.619064) (xy 393.99718 -221.619064)
		)
		(stroke
			(width 0)
			(type solid)
		)
		(fill yes)
		(layer "F.Cu")
		(net "M_E_CPU0_SB_DQ<19>")
	)
	(gr_poly
		(pts
			(xy 393.99718 -220.759274) (xy 393.94638 -220.759274) (xy 393.84478 -220.795342) (xy 393.84478 -220.985842)
			(xy 393.94638 -221.022164) (xy 393.99718 -221.022164)
		)
		(stroke
			(width 0)
			(type solid)
		)
		(fill yes)
		(layer "F.Cu")
		(net "M_E_CPU0_SB_DQ<19>")
	)
	(gr_poly
		(pts
			(xy 393.99718 -220.162374) (xy 393.94638 -220.162374) (xy 393.84478 -220.198442) (xy 393.84478 -220.388942)
			(xy 393.94638 -220.425264) (xy 393.99718 -220.425264)
		)
		(stroke
			(width 0)
			(type solid)
		)
		(fill yes)
		(layer "F.Cu")
		(net "M_E_CPU0_SB_DQ<19>")
	)
	(gr_poly
		(pts
			(xy 393.99718 -219.565474) (xy 393.94638 -219.565474) (xy 393.84478 -219.601542) (xy 393.84478 -219.792042)
			(xy 393.94638 -219.828364) (xy 393.99718 -219.828364)
		)
		(stroke
			(width 0)
			(type solid)
		)
		(fill yes)
		(layer "F.Cu")
		(net "M_E_CPU0_SB_DQ<19>")
	)
	(gr_poly
		(pts
			(xy 393.99845 -240.448846) (xy 393.952222 -240.35131) (xy 393.916154 -240.315496) (xy 393.730226 -240.501424)
			(xy 393.766294 -240.537238) (xy 393.863576 -240.583466)
		)
		(stroke
			(width 0)
			(type solid)
		)
		(fill yes)
		(layer "F.Cu")
		(net "M_E_CPU0_SB_CB<5>")
	)
	(gr_poly
		(pts
			(xy 394.00607 -231.617774) (xy 393.970002 -231.58196) (xy 393.87272 -231.535732) (xy 393.737846 -231.670352)
			(xy 393.784074 -231.767888) (xy 393.820142 -231.803702)
		)
		(stroke
			(width 0)
			(type solid)
		)
		(fill yes)
		(layer "F.Cu")
		(net "M_E_CPU0_SB_DQ<14>")
	)
	(gr_poly
		(pts
			(xy 394.013436 -277.98522) (xy 394.105892 -277.929848) (xy 394.068554 -277.742904) (xy 393.961874 -277.72741)
			(xy 393.911836 -277.737316) (xy 393.963398 -277.995126)
		)
		(stroke
			(width 0)
			(type solid)
		)
		(fill yes)
		(layer "F.Cu")
		(net "M_E_CPU0_SA_DQ<23>")
	)
	(gr_poly
		(pts
			(xy 394.020802 -268.342364) (xy 394.05687 -268.30655) (xy 393.870942 -268.120622) (xy 393.835128 -268.156436)
			(xy 393.788646 -268.253972) (xy 393.92352 -268.388592)
		)
		(stroke
			(width 0)
			(type solid)
		)
		(fill yes)
		(layer "F.Cu")
		(net "M_E_CPU0_SA_CB<2>")
	)
	(gr_poly
		(pts
			(xy 394.022072 -278.287734) (xy 393.97051 -278.029924) (xy 393.920726 -278.040084) (xy 393.82827 -278.095456)
			(xy 393.865608 -278.282146) (xy 393.972288 -278.297894)
		)
		(stroke
			(width 0)
			(type solid)
		)
		(fill yes)
		(layer "F.Cu")
		(net "M_E_CPU0_SA_DQ<23>")
	)
	(gr_poly
		(pts
			(xy 394.0302 -267.489178) (xy 394.066014 -267.45311) (xy 393.880086 -267.267182) (xy 393.844272 -267.30325)
			(xy 393.798044 -267.400532) (xy 393.932664 -267.535406)
		)
		(stroke
			(width 0)
			(type solid)
		)
		(fill yes)
		(layer "F.Cu")
		(net "M_E_CPU0_SA_CB<3>")
	)
	(gr_poly
		(pts
			(xy 394.030962 -234.180634) (xy 393.994894 -234.14482) (xy 393.897612 -234.098592) (xy 393.762738 -234.233212)
			(xy 393.808966 -234.330748) (xy 393.845034 -234.366562)
		)
		(stroke
			(width 0)
			(type solid)
		)
		(fill yes)
		(layer "F.Cu")
		(net "M_E_CPU0_SB_DQ<11>")
	)
	(gr_poly
		(pts
			(xy 394.040868 -235.034836) (xy 394.0048 -234.999022) (xy 393.907518 -234.952794) (xy 393.772898 -235.087414)
			(xy 393.819126 -235.18495) (xy 393.85494 -235.220764)
		)
		(stroke
			(width 0)
			(type solid)
		)
		(fill yes)
		(layer "F.Cu")
		(net "M_E_CPU0_SB_DQ<10>")
	)
	(gr_poly
		(pts
			(xy 394.045186 -270.850614) (xy 394.081 -270.8148) (xy 393.895072 -270.628872) (xy 393.859258 -270.664686)
			(xy 393.81303 -270.762222) (xy 393.94765 -270.896842)
		)
		(stroke
			(width 0)
			(type solid)
		)
		(fill yes)
		(layer "F.Cu")
		(net "M_E_CPU0_SA_DQ<28>")
	)
	(gr_poly
		(pts
			(xy 394.048996 -236.731302) (xy 394.013182 -236.695488) (xy 393.915646 -236.64926) (xy 393.781026 -236.78388)
			(xy 393.827254 -236.881162) (xy 393.863068 -236.91723)
		)
		(stroke
			(width 0)
			(type solid)
		)
		(fill yes)
		(layer "F.Cu")
		(net "M_E_CPU0_SB_CB<1>")
	)
	(gr_poly
		(pts
			(xy 394.05433 -269.997174) (xy 394.090398 -269.96136) (xy 393.90447 -269.775432) (xy 393.868402 -269.811246)
			(xy 393.822174 -269.908782) (xy 393.957048 -270.043402)
		)
		(stroke
			(width 0)
			(type solid)
		)
		(fill yes)
		(layer "F.Cu")
		(net "M_E_CPU0_SA_DQ<29>")
	)
	(gr_poly
		(pts
			(xy 394.05814 -237.584742) (xy 394.022326 -237.548674) (xy 393.92479 -237.502446) (xy 393.79017 -237.63732)
			(xy 393.836398 -237.734602) (xy 393.872212 -237.77067)
		)
		(stroke
			(width 0)
			(type solid)
		)
		(fill yes)
		(layer "F.Cu")
		(net "M_E_CPU0_SB_CB<0>")
	)
	(gr_poly
		(pts
			(xy 394.065506 -279.800812) (xy 394.157962 -279.74544) (xy 394.120624 -279.55875) (xy 394.013944 -279.543256)
			(xy 393.96416 -279.553162) (xy 394.015722 -279.810972)
		)
		(stroke
			(width 0)
			(type solid)
		)
		(fill yes)
		(layer "F.Cu")
		(net "M_E_CPU0_SA_DQ<21>")
	)
	(gr_poly
		(pts
			(xy 394.07465 -229.62743) (xy 394.028422 -229.529894) (xy 393.992608 -229.49408) (xy 393.80668 -229.680008)
			(xy 393.842494 -229.715822) (xy 393.94003 -229.76205)
		)
		(stroke
			(width 0)
			(type solid)
		)
		(fill yes)
		(layer "F.Cu")
		(net "M_E_CPU0_SB_DQ<18>")
	)
	(gr_poly
		(pts
			(xy 394.076428 -283.949648) (xy 394.025628 -283.949648) (xy 393.924028 -283.98597) (xy 393.924028 -284.17647)
			(xy 394.025628 -284.212538) (xy 394.076428 -284.212538)
		)
		(stroke
			(width 0)
			(type solid)
		)
		(fill yes)
		(layer "F.Cu")
		(net "M_E_CPU0_SA_DQ<21>")
	)
	(gr_poly
		(pts
			(xy 394.076428 -283.352748) (xy 394.025628 -283.352748) (xy 393.924028 -283.38907) (xy 393.924028 -283.57957)
			(xy 394.025628 -283.615638) (xy 394.076428 -283.615638)
		)
		(stroke
			(width 0)
			(type solid)
		)
		(fill yes)
		(layer "F.Cu")
		(net "M_E_CPU0_SA_DQ<21>")
	)
	(gr_poly
		(pts
			(xy 394.076428 -282.755848) (xy 394.025628 -282.755848) (xy 393.924028 -282.79217) (xy 393.924028 -282.98267)
			(xy 394.025628 -283.018738) (xy 394.076428 -283.018738)
		)
		(stroke
			(width 0)
			(type solid)
		)
		(fill yes)
		(layer "F.Cu")
		(net "M_E_CPU0_SA_DQ<21>")
	)
	(gr_poly
		(pts
			(xy 394.076428 -282.158948) (xy 394.025628 -282.158948) (xy 393.924028 -282.19527) (xy 393.924028 -282.38577)
			(xy 394.025628 -282.421838) (xy 394.076428 -282.421838)
		)
		(stroke
			(width 0)
			(type solid)
		)
		(fill yes)
		(layer "F.Cu")
		(net "M_E_CPU0_SA_DQ<21>")
	)
	(gr_poly
		(pts
			(xy 394.076428 -281.562048) (xy 394.025628 -281.562048) (xy 393.924028 -281.59837) (xy 393.924028 -281.78887)
			(xy 394.025628 -281.824938) (xy 394.076428 -281.824938)
		)
		(stroke
			(width 0)
			(type solid)
		)
		(fill yes)
		(layer "F.Cu")
		(net "M_E_CPU0_SA_DQ<21>")
	)
	(gr_poly
		(pts
			(xy 394.076428 -280.965148) (xy 394.025628 -280.965148) (xy 393.924028 -281.00147) (xy 393.924028 -281.19197)
			(xy 394.025628 -281.228038) (xy 394.076428 -281.228038)
		)
		(stroke
			(width 0)
			(type solid)
		)
		(fill yes)
		(layer "F.Cu")
		(net "M_E_CPU0_SA_DQ<21>")
	)
	(gr_poly
		(pts
			(xy 394.076428 -280.368248) (xy 394.025628 -280.368248) (xy 393.924028 -280.40457) (xy 393.924028 -280.59507)
			(xy 394.025628 -280.631138) (xy 394.076428 -280.631138)
		)
		(stroke
			(width 0)
			(type solid)
		)
		(fill yes)
		(layer "F.Cu")
		(net "M_E_CPU0_SA_DQ<21>")
	)
	(gr_poly
		(pts
			(xy 394.078206 -264.94867) (xy 394.11402 -264.912602) (xy 393.928346 -264.726928) (xy 393.892278 -264.762742)
			(xy 393.84605 -264.860278) (xy 393.98067 -264.994898)
		)
		(stroke
			(width 0)
			(type solid)
		)
		(fill yes)
		(layer "F.Cu")
		(net "M_E_CPU0_SA_CB<6>")
	)
	(gr_poly
		(pts
			(xy 394.08354 -231.324404) (xy 394.037312 -231.227122) (xy 394.001498 -231.191054) (xy 393.81557 -231.376982)
			(xy 393.851384 -231.41305) (xy 393.94892 -231.459278)
		)
		(stroke
			(width 0)
			(type solid)
		)
		(fill yes)
		(layer "F.Cu")
		(net "M_E_CPU0_SB_DQ<13>")
	)
	(gr_poly
		(pts
			(xy 394.08735 -264.09523) (xy 394.123418 -264.059416) (xy 393.93749 -263.873488) (xy 393.901422 -263.909302)
			(xy 393.855194 -264.006838) (xy 393.990068 -264.141458)
		)
		(stroke
			(width 0)
			(type solid)
		)
		(fill yes)
		(layer "F.Cu")
		(net "M_E_CPU0_SA_CB<7>")
	)
	(gr_poly
		(pts
			(xy 394.088112 -268.697202) (xy 394.13434 -268.59992) (xy 393.99972 -268.465046) (xy 393.902184 -268.511274)
			(xy 393.86637 -268.547342) (xy 394.052298 -268.73327)
		)
		(stroke
			(width 0)
			(type solid)
		)
		(fill yes)
		(layer "F.Cu")
		(net "M_E_CPU0_SA_CB<0>")
	)
	(gr_poly
		(pts
			(xy 394.092684 -232.177844) (xy 394.046456 -232.080562) (xy 394.010642 -232.044494) (xy 393.824714 -232.230422)
			(xy 393.860528 -232.266236) (xy 393.958064 -232.312718)
		)
		(stroke
			(width 0)
			(type solid)
		)
		(fill yes)
		(layer "F.Cu")
		(net "M_E_CPU0_SB_DQ<12>")
	)
	(gr_poly
		(pts
			(xy 394.093446 -275.5011) (xy 394.185902 -275.445474) (xy 394.148564 -275.258784) (xy 394.041884 -275.24329)
			(xy 393.9921 -275.253196) (xy 394.043662 -275.511006)
		)
		(stroke
			(width 0)
			(type solid)
		)
		(fill yes)
		(layer "F.Cu")
		(net "M_E_CPU0_SA_DQ<24>")
	)
	(gr_poly
		(pts
			(xy 394.09497 -273.094196) (xy 394.130784 -273.058128) (xy 393.944856 -272.8722) (xy 393.909042 -272.908268)
			(xy 393.862814 -273.00555) (xy 393.997434 -273.140424)
		)
		(stroke
			(width 0)
			(type solid)
		)
		(fill yes)
		(layer "F.Cu")
		(net "M_E_CPU0_SA_DQ<27>")
	)
	(gr_poly
		(pts
			(xy 394.097256 -267.844016) (xy 394.143484 -267.74648) (xy 394.008864 -267.61186) (xy 393.911582 -267.658088)
			(xy 393.875514 -267.693902) (xy 394.061442 -267.87983)
		)
		(stroke
			(width 0)
			(type solid)
		)
		(fill yes)
		(layer "F.Cu")
		(net "M_E_CPU0_SA_CB<1>")
	)
	(gr_poly
		(pts
			(xy 394.102082 -275.803614) (xy 394.05052 -275.545804) (xy 394.000736 -275.55571) (xy 393.90828 -275.611082)
			(xy 393.945618 -275.798026) (xy 394.052298 -275.81352)
		)
		(stroke
			(width 0)
			(type solid)
		)
		(fill yes)
		(layer "F.Cu")
		(net "M_E_CPU0_SA_DQ<24>")
	)
	(gr_poly
		(pts
			(xy 394.11783 -234.740958) (xy 394.071602 -234.643676) (xy 394.035788 -234.607608) (xy 393.84986 -234.793536)
			(xy 393.885674 -234.829604) (xy 393.98321 -234.875832)
		)
		(stroke
			(width 0)
			(type solid)
		)
		(fill yes)
		(layer "F.Cu")
		(net "M_E_CPU0_SB_DQ<9>")
	)
	(gr_poly
		(pts
			(xy 394.12164 -270.352266) (xy 394.167868 -270.25473) (xy 394.032994 -270.12011) (xy 393.935712 -270.166338)
			(xy 393.899644 -270.202152) (xy 394.085572 -270.38808)
		)
		(stroke
			(width 0)
			(type solid)
		)
		(fill yes)
		(layer "F.Cu")
		(net "M_E_CPU0_SA_DQ<30>")
	)
	(gr_poly
		(pts
			(xy 394.126466 -236.437932) (xy 394.080238 -236.34065) (xy 394.044424 -236.304582) (xy 393.858496 -236.49051)
			(xy 393.89431 -236.526324) (xy 393.991846 -236.572806)
		)
		(stroke
			(width 0)
			(type solid)
		)
		(fill yes)
		(layer "F.Cu")
		(net "M_E_CPU0_SB_CB<3>")
	)
	(gr_poly
		(pts
			(xy 394.127228 -240.104422) (xy 394.091414 -240.068608) (xy 393.993878 -240.022126) (xy 393.859258 -240.157)
			(xy 393.905486 -240.254282) (xy 393.9413 -240.29035)
		)
		(stroke
			(width 0)
			(type solid)
		)
		(fill yes)
		(layer "F.Cu")
		(net "M_E_CPU0_SB_CB<5>")
	)
	(gr_poly
		(pts
			(xy 394.127736 -235.59516) (xy 394.081508 -235.497624) (xy 394.045694 -235.461556) (xy 393.859766 -235.647484)
			(xy 393.89558 -235.683552) (xy 393.993116 -235.72978)
		)
		(stroke
			(width 0)
			(type solid)
		)
		(fill yes)
		(layer "F.Cu")
		(net "M_E_CPU0_SB_DQ<8>")
	)
	(gr_poly
		(pts
			(xy 394.13053 -278.570436) (xy 394.222986 -278.515064) (xy 394.185648 -278.328374) (xy 394.078968 -278.312626)
			(xy 394.02893 -278.322786) (xy 394.080492 -278.580342)
		)
		(stroke
			(width 0)
			(type solid)
		)
		(fill yes)
		(layer "F.Cu")
		(net "M_E_CPU0_SA_DQ<23>")
	)
	(gr_poly
		(pts
			(xy 394.131038 -269.498572) (xy 394.177266 -269.401036) (xy 394.042646 -269.266416) (xy 393.94511 -269.312644)
			(xy 393.909296 -269.348712) (xy 394.09497 -269.534386)
		)
		(stroke
			(width 0)
			(type solid)
		)
		(fill yes)
		(layer "F.Cu")
		(net "M_E_CPU0_SA_DQ<31>")
	)
	(gr_poly
		(pts
			(xy 394.135864 -237.291372) (xy 394.089636 -237.193836) (xy 394.053568 -237.158022) (xy 393.86764 -237.34395)
			(xy 393.903708 -237.379764) (xy 394.00099 -237.425992)
		)
		(stroke
			(width 0)
			(type solid)
		)
		(fill yes)
		(layer "F.Cu")
		(net "M_E_CPU0_SB_CB<2>")
	)
	(gr_poly
		(pts
			(xy 394.139166 -278.873204) (xy 394.087604 -278.615394) (xy 394.03782 -278.6253) (xy 393.94511 -278.680672)
			(xy 393.982702 -278.867616) (xy 394.089382 -278.88311)
		)
		(stroke
			(width 0)
			(type solid)
		)
		(fill yes)
		(layer "F.Cu")
		(net "M_E_CPU0_SA_DQ<23>")
	)
	(gr_poly
		(pts
			(xy 394.145516 -265.303508) (xy 394.191744 -265.205972) (xy 394.05687 -265.071352) (xy 393.959588 -265.11758)
			(xy 393.92352 -265.153394) (xy 394.109448 -265.339322)
		)
		(stroke
			(width 0)
			(type solid)
		)
		(fill yes)
		(layer "F.Cu")
		(net "M_E_CPU0_SA_CB<4>")
	)
	(gr_poly
		(pts
			(xy 394.14958 -228.447092) (xy 394.14958 -228.256592) (xy 394.04798 -228.220524) (xy 393.99718 -228.220524)
			(xy 393.99718 -228.483414) (xy 394.04798 -228.483414)
		)
		(stroke
			(width 0)
			(type solid)
		)
		(fill yes)
		(layer "F.Cu")
		(net "M_E_CPU0_SB_DQ<19>")
	)
	(gr_poly
		(pts
			(xy 394.14958 -227.850192) (xy 394.14958 -227.659692) (xy 394.04798 -227.623624) (xy 393.99718 -227.623624)
			(xy 393.99718 -227.886514) (xy 394.04798 -227.886514)
		)
		(stroke
			(width 0)
			(type solid)
		)
		(fill yes)
		(layer "F.Cu")
		(net "M_E_CPU0_SB_DQ<19>")
	)
	(gr_poly
		(pts
			(xy 394.14958 -227.253292) (xy 394.14958 -227.062792) (xy 394.04798 -227.026724) (xy 393.99718 -227.026724)
			(xy 393.99718 -227.289614) (xy 394.04798 -227.289614)
		)
		(stroke
			(width 0)
			(type solid)
		)
		(fill yes)
		(layer "F.Cu")
		(net "M_E_CPU0_SB_DQ<19>")
	)
	(gr_poly
		(pts
			(xy 394.14958 -226.656392) (xy 394.14958 -226.465892) (xy 394.04798 -226.429824) (xy 393.99718 -226.429824)
			(xy 393.99718 -226.692714) (xy 394.04798 -226.692714)
		)
		(stroke
			(width 0)
			(type solid)
		)
		(fill yes)
		(layer "F.Cu")
		(net "M_E_CPU0_SB_DQ<19>")
	)
	(gr_poly
		(pts
			(xy 394.14958 -226.059492) (xy 394.14958 -225.868992) (xy 394.04798 -225.832924) (xy 393.99718 -225.832924)
			(xy 393.99718 -226.095814) (xy 394.04798 -226.095814)
		)
		(stroke
			(width 0)
			(type solid)
		)
		(fill yes)
		(layer "F.Cu")
		(net "M_E_CPU0_SB_DQ<19>")
	)
	(gr_poly
		(pts
			(xy 394.14958 -225.462592) (xy 394.14958 -225.272092) (xy 394.04798 -225.236024) (xy 393.99718 -225.236024)
			(xy 393.99718 -225.498914) (xy 394.04798 -225.498914)
		)
		(stroke
			(width 0)
			(type solid)
		)
		(fill yes)
		(layer "F.Cu")
		(net "M_E_CPU0_SB_DQ<19>")
	)
	(gr_poly
		(pts
			(xy 394.14958 -224.865692) (xy 394.14958 -224.675192) (xy 394.04798 -224.639124) (xy 393.99718 -224.639124)
			(xy 393.99718 -224.902014) (xy 394.04798 -224.902014)
		)
		(stroke
			(width 0)
			(type solid)
		)
		(fill yes)
		(layer "F.Cu")
		(net "M_E_CPU0_SB_DQ<19>")
	)
	(gr_poly
		(pts
			(xy 394.14958 -224.268792) (xy 394.14958 -224.078292) (xy 394.04798 -224.042224) (xy 393.99718 -224.042224)
			(xy 393.99718 -224.305114) (xy 394.04798 -224.305114)
		)
		(stroke
			(width 0)
			(type solid)
		)
		(fill yes)
		(layer "F.Cu")
		(net "M_E_CPU0_SB_DQ<19>")
	)
	(gr_poly
		(pts
			(xy 394.14958 -223.671892) (xy 394.14958 -223.481392) (xy 394.04798 -223.445324) (xy 393.99718 -223.445324)
			(xy 393.99718 -223.708214) (xy 394.04798 -223.708214)
		)
		(stroke
			(width 0)
			(type solid)
		)
		(fill yes)
		(layer "F.Cu")
		(net "M_E_CPU0_SB_DQ<19>")
	)
	(gr_poly
		(pts
			(xy 394.14958 -223.074992) (xy 394.14958 -222.884492) (xy 394.04798 -222.848424) (xy 393.99718 -222.848424)
			(xy 393.99718 -223.111314) (xy 394.04798 -223.111314)
		)
		(stroke
			(width 0)
			(type solid)
		)
		(fill yes)
		(layer "F.Cu")
		(net "M_E_CPU0_SB_DQ<19>")
	)
	(gr_poly
		(pts
			(xy 394.14958 -222.478092) (xy 394.14958 -222.287592) (xy 394.04798 -222.251524) (xy 393.99718 -222.251524)
			(xy 393.99718 -222.514414) (xy 394.04798 -222.514414)
		)
		(stroke
			(width 0)
			(type solid)
		)
		(fill yes)
		(layer "F.Cu")
		(net "M_E_CPU0_SB_DQ<19>")
	)
	(gr_poly
		(pts
			(xy 394.14958 -221.881192) (xy 394.14958 -221.690692) (xy 394.04798 -221.654624) (xy 393.99718 -221.654624)
			(xy 393.99718 -221.917514) (xy 394.04798 -221.917514)
		)
		(stroke
			(width 0)
			(type solid)
		)
		(fill yes)
		(layer "F.Cu")
		(net "M_E_CPU0_SB_DQ<19>")
	)
	(gr_poly
		(pts
			(xy 394.14958 -221.284292) (xy 394.14958 -221.093792) (xy 394.04798 -221.057724) (xy 393.99718 -221.057724)
			(xy 393.99718 -221.320614) (xy 394.04798 -221.320614)
		)
		(stroke
			(width 0)
			(type solid)
		)
		(fill yes)
		(layer "F.Cu")
		(net "M_E_CPU0_SB_DQ<19>")
	)
	(gr_poly
		(pts
			(xy 394.14958 -220.687392) (xy 394.14958 -220.496892) (xy 394.04798 -220.460824) (xy 393.99718 -220.460824)
			(xy 393.99718 -220.723714) (xy 394.04798 -220.723714)
		)
		(stroke
			(width 0)
			(type solid)
		)
		(fill yes)
		(layer "F.Cu")
		(net "M_E_CPU0_SB_DQ<19>")
	)
	(gr_poly
		(pts
			(xy 394.14958 -220.090492) (xy 394.14958 -219.899992) (xy 394.04798 -219.863924) (xy 393.99718 -219.863924)
			(xy 393.99718 -220.126814) (xy 394.04798 -220.126814)
		)
		(stroke
			(width 0)
			(type solid)
		)
		(fill yes)
		(layer "F.Cu")
		(net "M_E_CPU0_SB_DQ<19>")
	)
	(gr_poly
		(pts
			(xy 394.15466 -264.450068) (xy 394.200888 -264.352532) (xy 394.066268 -264.217912) (xy 393.968732 -264.26414)
			(xy 393.932918 -264.300208) (xy 394.118846 -264.486136)
		)
		(stroke
			(width 0)
			(type solid)
		)
		(fill yes)
		(layer "F.Cu")
		(net "M_E_CPU0_SA_CB<5>")
	)
	(gr_poly
		(pts
			(xy 394.158216 -274.27047) (xy 394.250926 -274.215098) (xy 394.213334 -274.028408) (xy 394.106654 -274.01266)
			(xy 394.05687 -274.02282) (xy 394.108432 -274.28063)
		)
		(stroke
			(width 0)
			(type solid)
		)
		(fill yes)
		(layer "F.Cu")
		(net "M_E_CPU0_SA_DQ<26>")
	)
	(gr_poly
		(pts
			(xy 394.16228 -273.449034) (xy 394.208508 -273.351498) (xy 394.073634 -273.216878) (xy 393.976352 -273.263106)
			(xy 393.940284 -273.29892) (xy 394.126212 -273.484848)
		)
		(stroke
			(width 0)
			(type solid)
		)
		(fill yes)
		(layer "F.Cu")
		(net "M_E_CPU0_SA_DQ<25>")
	)
	(gr_poly
		(pts
			(xy 394.167106 -274.573238) (xy 394.115544 -274.315428) (xy 394.06576 -274.325334) (xy 393.97305 -274.380706)
			(xy 394.010388 -274.56765) (xy 394.117322 -274.583144)
		)
		(stroke
			(width 0)
			(type solid)
		)
		(fill yes)
		(layer "F.Cu")
		(net "M_E_CPU0_SA_DQ<26>")
	)
	(gr_poly
		(pts
			(xy 394.203682 -229.283006) (xy 394.167614 -229.247192) (xy 394.070332 -229.200964) (xy 393.935458 -229.335584)
			(xy 393.98194 -229.43312) (xy 394.017754 -229.468934)
		)
		(stroke
			(width 0)
			(type solid)
		)
		(fill yes)
		(layer "F.Cu")
		(net "M_E_CPU0_SB_DQ<18>")
	)
	(gr_poly
		(pts
			(xy 394.21054 -276.086316) (xy 394.302996 -276.030944) (xy 394.265658 -275.844) (xy 394.158978 -275.828506)
			(xy 394.109194 -275.838412) (xy 394.160756 -276.096222)
		)
		(stroke
			(width 0)
			(type solid)
		)
		(fill yes)
		(layer "F.Cu")
		(net "M_E_CPU0_SA_DQ<24>")
	)
	(gr_poly
		(pts
			(xy 394.212318 -230.980234) (xy 394.176504 -230.944166) (xy 394.078968 -230.897938) (xy 393.944348 -231.032558)
			(xy 393.990576 -231.130094) (xy 394.026644 -231.165908)
		)
		(stroke
			(width 0)
			(type solid)
		)
		(fill yes)
		(layer "F.Cu")
		(net "M_E_CPU0_SB_DQ<13>")
	)
	(gr_poly
		(pts
			(xy 394.219176 -276.38883) (xy 394.167614 -276.13102) (xy 394.11783 -276.14118) (xy 394.025374 -276.196552)
			(xy 394.062712 -276.383242) (xy 394.169392 -276.39899)
		)
		(stroke
			(width 0)
			(type solid)
		)
		(fill yes)
		(layer "F.Cu")
		(net "M_E_CPU0_SA_DQ<24>")
	)
	(gr_poly
		(pts
			(xy 394.221716 -231.83342) (xy 394.185648 -231.797606) (xy 394.088366 -231.751378) (xy 393.953492 -231.885998)
			(xy 393.99972 -231.983534) (xy 394.035788 -232.019348)
		)
		(stroke
			(width 0)
			(type solid)
		)
		(fill yes)
		(layer "F.Cu")
		(net "M_E_CPU0_SB_DQ<12>")
	)
	(gr_poly
		(pts
			(xy 394.227304 -268.980158) (xy 394.263372 -268.944344) (xy 394.077444 -268.758416) (xy 394.041376 -268.79423)
			(xy 393.995148 -268.891766) (xy 394.130022 -269.026386)
		)
		(stroke
			(width 0)
			(type solid)
		)
		(fill yes)
		(layer "F.Cu")
		(net "M_E_CPU0_SA_CB<0>")
	)
	(gr_poly
		(pts
			(xy 394.228828 -284.47492) (xy 394.228828 -284.28442) (xy 394.127228 -284.248098) (xy 394.076428 -284.248098)
			(xy 394.076428 -284.511242) (xy 394.127228 -284.511242)
		)
		(stroke
			(width 0)
			(type solid)
		)
		(fill yes)
		(layer "F.Cu")
		(net "M_E_CPU0_SA_DQ<21>")
	)
	(gr_poly
		(pts
			(xy 394.228828 -283.87802) (xy 394.228828 -283.68752) (xy 394.127228 -283.651198) (xy 394.076428 -283.651198)
			(xy 394.076428 -283.914342) (xy 394.127228 -283.914342)
		)
		(stroke
			(width 0)
			(type solid)
		)
		(fill yes)
		(layer "F.Cu")
		(net "M_E_CPU0_SA_DQ<21>")
	)
	(gr_poly
		(pts
			(xy 394.228828 -283.28112) (xy 394.228828 -283.09062) (xy 394.127228 -283.054298) (xy 394.076428 -283.054298)
			(xy 394.076428 -283.317442) (xy 394.127228 -283.317442)
		)
		(stroke
			(width 0)
			(type solid)
		)
		(fill yes)
		(layer "F.Cu")
		(net "M_E_CPU0_SA_DQ<21>")
	)
	(gr_poly
		(pts
			(xy 394.228828 -282.68422) (xy 394.228828 -282.49372) (xy 394.127228 -282.457398) (xy 394.076428 -282.457398)
			(xy 394.076428 -282.720542) (xy 394.127228 -282.720542)
		)
		(stroke
			(width 0)
			(type solid)
		)
		(fill yes)
		(layer "F.Cu")
		(net "M_E_CPU0_SA_DQ<21>")
	)
	(gr_poly
		(pts
			(xy 394.228828 -282.08732) (xy 394.228828 -281.89682) (xy 394.127228 -281.860498) (xy 394.076428 -281.860498)
			(xy 394.076428 -282.123642) (xy 394.127228 -282.123642)
		)
		(stroke
			(width 0)
			(type solid)
		)
		(fill yes)
		(layer "F.Cu")
		(net "M_E_CPU0_SA_DQ<21>")
	)
	(gr_poly
		(pts
			(xy 394.228828 -281.49042) (xy 394.228828 -281.29992) (xy 394.127228 -281.263598) (xy 394.076428 -281.263598)
			(xy 394.076428 -281.526742) (xy 394.127228 -281.526742)
		)
		(stroke
			(width 0)
			(type solid)
		)
		(fill yes)
		(layer "F.Cu")
		(net "M_E_CPU0_SA_DQ<21>")
	)
	(gr_poly
		(pts
			(xy 394.228828 -280.89352) (xy 394.228828 -280.70302) (xy 394.127228 -280.666698) (xy 394.076428 -280.666698)
			(xy 394.076428 -280.929842) (xy 394.127228 -280.929842)
		)
		(stroke
			(width 0)
			(type solid)
		)
		(fill yes)
		(layer "F.Cu")
		(net "M_E_CPU0_SA_DQ<21>")
	)
	(gr_poly
		(pts
			(xy 394.236448 -268.126718) (xy 394.272516 -268.090904) (xy 394.086588 -267.904976) (xy 394.050774 -267.94079)
			(xy 394.004292 -268.038326) (xy 394.139166 -268.172946)
		)
		(stroke
			(width 0)
			(type solid)
		)
		(fill yes)
		(layer "F.Cu")
		(net "M_E_CPU0_SA_CB<1>")
	)
	(gr_poly
		(pts
			(xy 394.246862 -234.396788) (xy 394.210794 -234.36072) (xy 394.113512 -234.314492) (xy 393.978638 -234.449112)
			(xy 394.024866 -234.546648) (xy 394.060934 -234.582462)
		)
		(stroke
			(width 0)
			(type solid)
		)
		(fill yes)
		(layer "F.Cu")
		(net "M_E_CPU0_SB_DQ<9>")
	)
	(gr_poly
		(pts
			(xy 394.24737 -279.155906) (xy 394.34008 -279.10028) (xy 394.302742 -278.91359) (xy 394.195808 -278.898096)
			(xy 394.146024 -278.908002) (xy 394.197586 -279.165812)
		)
		(stroke
			(width 0)
			(type solid)
		)
		(fill yes)
		(layer "F.Cu")
		(net "M_E_CPU0_SA_DQ<23>")
	)
	(gr_poly
		(pts
			(xy 394.255498 -236.093508) (xy 394.21943 -236.057694) (xy 394.122148 -236.011466) (xy 393.987274 -236.146086)
			(xy 394.033502 -236.243622) (xy 394.06957 -236.279436)
		)
		(stroke
			(width 0)
			(type solid)
		)
		(fill yes)
		(layer "F.Cu")
		(net "M_E_CPU0_SB_CB<3>")
	)
	(gr_poly
		(pts
			(xy 394.25626 -279.45842) (xy 394.204698 -279.20061) (xy 394.154914 -279.210516) (xy 394.062204 -279.266142)
			(xy 394.099542 -279.452832) (xy 394.206476 -279.468326)
		)
		(stroke
			(width 0)
			(type solid)
		)
		(fill yes)
		(layer "F.Cu")
		(net "M_E_CPU0_SA_DQ<23>")
	)
	(gr_poly
		(pts
			(xy 394.256514 -235.250736) (xy 394.2207 -235.214668) (xy 394.123164 -235.16844) (xy 393.988544 -235.30306)
			(xy 394.034772 -235.400596) (xy 394.07084 -235.43641)
		)
		(stroke
			(width 0)
			(type solid)
		)
		(fill yes)
		(layer "F.Cu")
		(net "M_E_CPU0_SB_DQ<8>")
	)
	(gr_poly
		(pts
			(xy 394.260832 -270.634968) (xy 394.296646 -270.599154) (xy 394.110718 -270.413226) (xy 394.074904 -270.44904)
			(xy 394.028676 -270.546576) (xy 394.163296 -270.681196)
		)
		(stroke
			(width 0)
			(type solid)
		)
		(fill yes)
		(layer "F.Cu")
		(net "M_E_CPU0_SA_DQ<30>")
	)
	(gr_poly
		(pts
			(xy 394.264642 -236.946948) (xy 394.228828 -236.911134) (xy 394.131292 -236.864906) (xy 393.996672 -236.999526)
			(xy 394.0429 -237.096808) (xy 394.078714 -237.132876)
		)
		(stroke
			(width 0)
			(type solid)
		)
		(fill yes)
		(layer "F.Cu")
		(net "M_E_CPU0_SB_CB<2>")
	)
	(gr_poly
		(pts
			(xy 394.27023 -269.781528) (xy 394.306044 -269.74546) (xy 394.120116 -269.559532) (xy 394.084302 -269.5956)
			(xy 394.038074 -269.692882) (xy 394.172694 -269.827756)
		)
		(stroke
			(width 0)
			(type solid)
		)
		(fill yes)
		(layer "F.Cu")
		(net "M_E_CPU0_SA_DQ<31>")
	)
	(gr_poly
		(pts
			(xy 394.27531 -274.85594) (xy 394.36802 -274.800314) (xy 394.330428 -274.613624) (xy 394.223748 -274.59813)
			(xy 394.173964 -274.608036) (xy 394.225526 -274.865846)
		)
		(stroke
			(width 0)
			(type solid)
		)
		(fill yes)
		(layer "F.Cu")
		(net "M_E_CPU0_SA_DQ<26>")
	)
	(gr_poly
		(pts
			(xy 394.281152 -228.989636) (xy 394.234924 -228.892354) (xy 394.19911 -228.856286) (xy 394.013182 -229.042214)
			(xy 394.048996 -229.078282) (xy 394.146532 -229.12451)
		)
		(stroke
			(width 0)
			(type solid)
		)
		(fill yes)
		(layer "F.Cu")
		(net "M_E_CPU0_SB_DQ<17>")
	)
	(gr_poly
		(pts
			(xy 394.2842 -275.158454) (xy 394.232638 -274.900644) (xy 394.1826 -274.91055) (xy 394.090144 -274.966176)
			(xy 394.127482 -275.152866) (xy 394.234162 -275.16836)
		)
		(stroke
			(width 0)
			(type solid)
		)
		(fill yes)
		(layer "F.Cu")
		(net "M_E_CPU0_SA_DQ<26>")
	)
	(gr_poly
		(pts
			(xy 394.284708 -265.58621) (xy 394.320522 -265.550396) (xy 394.134594 -265.364468) (xy 394.09878 -265.400536)
			(xy 394.052552 -265.497818) (xy 394.187172 -265.632692)
		)
		(stroke
			(width 0)
			(type solid)
		)
		(fill yes)
		(layer "F.Cu")
		(net "M_E_CPU0_SA_CB<4>")
	)
	(gr_poly
		(pts
			(xy 394.290042 -230.686864) (xy 394.243814 -230.589328) (xy 394.207746 -230.553514) (xy 394.021818 -230.739442)
			(xy 394.057886 -230.775256) (xy 394.155168 -230.821484)
		)
		(stroke
			(width 0)
			(type solid)
		)
		(fill yes)
		(layer "F.Cu")
		(net "M_E_CPU0_SB_DQ<15>")
	)
	(gr_poly
		(pts
			(xy 394.290296 -229.843076) (xy 394.244068 -229.74554) (xy 394.208254 -229.709726) (xy 394.022326 -229.895654)
			(xy 394.05814 -229.931468) (xy 394.155676 -229.977696)
		)
		(stroke
			(width 0)
			(type solid)
		)
		(fill yes)
		(layer "F.Cu")
		(net "M_E_CPU0_SB_DQ<16>")
	)
	(gr_poly
		(pts
			(xy 394.293852 -264.733024) (xy 394.329666 -264.696956) (xy 394.143992 -264.511282) (xy 394.107924 -264.547096)
			(xy 394.061696 -264.644632) (xy 394.196316 -264.779252)
		)
		(stroke
			(width 0)
			(type solid)
		)
		(fill yes)
		(layer "F.Cu")
		(net "M_E_CPU0_SA_CB<5>")
	)
	(gr_poly
		(pts
			(xy 394.299186 -231.54005) (xy 394.252958 -231.442768) (xy 394.217144 -231.4067) (xy 394.031216 -231.592628)
			(xy 394.06703 -231.628696) (xy 394.164566 -231.674924)
		)
		(stroke
			(width 0)
			(type solid)
		)
		(fill yes)
		(layer "F.Cu")
		(net "M_E_CPU0_SB_DQ<14>")
	)
	(gr_poly
		(pts
			(xy 394.30198 -227.922074) (xy 394.25118 -227.922074) (xy 394.14958 -227.958142) (xy 394.14958 -228.148642)
			(xy 394.25118 -228.184964) (xy 394.30198 -228.184964)
		)
		(stroke
			(width 0)
			(type solid)
		)
		(fill yes)
		(layer "F.Cu")
		(net "M_E_CPU0_SB_DQ<17>")
	)
	(gr_poly
		(pts
			(xy 394.30198 -227.325174) (xy 394.25118 -227.325174) (xy 394.14958 -227.361242) (xy 394.14958 -227.551742)
			(xy 394.25118 -227.588064) (xy 394.30198 -227.588064)
		)
		(stroke
			(width 0)
			(type solid)
		)
		(fill yes)
		(layer "F.Cu")
		(net "M_E_CPU0_SB_DQ<17>")
	)
	(gr_poly
		(pts
			(xy 394.30198 -226.728274) (xy 394.25118 -226.728274) (xy 394.14958 -226.764342) (xy 394.14958 -226.954842)
			(xy 394.25118 -226.991164) (xy 394.30198 -226.991164)
		)
		(stroke
			(width 0)
			(type solid)
		)
		(fill yes)
		(layer "F.Cu")
		(net "M_E_CPU0_SB_DQ<17>")
	)
	(gr_poly
		(pts
			(xy 394.30198 -226.131374) (xy 394.25118 -226.131374) (xy 394.14958 -226.167442) (xy 394.14958 -226.357942)
			(xy 394.25118 -226.394264) (xy 394.30198 -226.394264)
		)
		(stroke
			(width 0)
			(type solid)
		)
		(fill yes)
		(layer "F.Cu")
		(net "M_E_CPU0_SB_DQ<17>")
	)
	(gr_poly
		(pts
			(xy 394.30198 -225.534474) (xy 394.25118 -225.534474) (xy 394.14958 -225.570542) (xy 394.14958 -225.761042)
			(xy 394.25118 -225.797364) (xy 394.30198 -225.797364)
		)
		(stroke
			(width 0)
			(type solid)
		)
		(fill yes)
		(layer "F.Cu")
		(net "M_E_CPU0_SB_DQ<17>")
	)
	(gr_poly
		(pts
			(xy 394.30198 -224.937574) (xy 394.25118 -224.937574) (xy 394.14958 -224.973642) (xy 394.14958 -225.164142)
			(xy 394.25118 -225.200464) (xy 394.30198 -225.200464)
		)
		(stroke
			(width 0)
			(type solid)
		)
		(fill yes)
		(layer "F.Cu")
		(net "M_E_CPU0_SB_DQ<17>")
	)
	(gr_poly
		(pts
			(xy 394.30198 -224.340674) (xy 394.25118 -224.340674) (xy 394.14958 -224.376742) (xy 394.14958 -224.567242)
			(xy 394.25118 -224.603564) (xy 394.30198 -224.603564)
		)
		(stroke
			(width 0)
			(type solid)
		)
		(fill yes)
		(layer "F.Cu")
		(net "M_E_CPU0_SB_DQ<17>")
	)
	(gr_poly
		(pts
			(xy 394.30198 -223.743774) (xy 394.25118 -223.743774) (xy 394.14958 -223.779842) (xy 394.14958 -223.970342)
			(xy 394.25118 -224.006664) (xy 394.30198 -224.006664)
		)
		(stroke
			(width 0)
			(type solid)
		)
		(fill yes)
		(layer "F.Cu")
		(net "M_E_CPU0_SB_DQ<17>")
	)
	(gr_poly
		(pts
			(xy 394.30198 -223.146874) (xy 394.25118 -223.146874) (xy 394.14958 -223.182942) (xy 394.14958 -223.373442)
			(xy 394.25118 -223.409764) (xy 394.30198 -223.409764)
		)
		(stroke
			(width 0)
			(type solid)
		)
		(fill yes)
		(layer "F.Cu")
		(net "M_E_CPU0_SB_DQ<17>")
	)
	(gr_poly
		(pts
			(xy 394.30198 -222.549974) (xy 394.25118 -222.549974) (xy 394.14958 -222.586042) (xy 394.14958 -222.776542)
			(xy 394.25118 -222.812864) (xy 394.30198 -222.812864)
		)
		(stroke
			(width 0)
			(type solid)
		)
		(fill yes)
		(layer "F.Cu")
		(net "M_E_CPU0_SB_DQ<17>")
	)
	(gr_poly
		(pts
			(xy 394.30198 -221.953074) (xy 394.25118 -221.953074) (xy 394.14958 -221.989142) (xy 394.14958 -222.179642)
			(xy 394.25118 -222.215964) (xy 394.30198 -222.215964)
		)
		(stroke
			(width 0)
			(type solid)
		)
		(fill yes)
		(layer "F.Cu")
		(net "M_E_CPU0_SB_DQ<17>")
	)
	(gr_poly
		(pts
			(xy 394.30198 -221.356174) (xy 394.25118 -221.356174) (xy 394.14958 -221.392242) (xy 394.14958 -221.582742)
			(xy 394.25118 -221.619064) (xy 394.30198 -221.619064)
		)
		(stroke
			(width 0)
			(type solid)
		)
		(fill yes)
		(layer "F.Cu")
		(net "M_E_CPU0_SB_DQ<17>")
	)
	(gr_poly
		(pts
			(xy 394.30198 -220.759274) (xy 394.25118 -220.759274) (xy 394.14958 -220.795342) (xy 394.14958 -220.985842)
			(xy 394.25118 -221.022164) (xy 394.30198 -221.022164)
		)
		(stroke
			(width 0)
			(type solid)
		)
		(fill yes)
		(layer "F.Cu")
		(net "M_E_CPU0_SB_DQ<17>")
	)
	(gr_poly
		(pts
			(xy 394.30198 -220.162374) (xy 394.25118 -220.162374) (xy 394.14958 -220.198442) (xy 394.14958 -220.388942)
			(xy 394.25118 -220.425264) (xy 394.30198 -220.425264)
		)
		(stroke
			(width 0)
			(type solid)
		)
		(fill yes)
		(layer "F.Cu")
		(net "M_E_CPU0_SB_DQ<17>")
	)
	(gr_poly
		(pts
			(xy 394.303758 -268.481556) (xy 394.349986 -268.384274) (xy 394.215366 -268.2494) (xy 394.11783 -268.295628)
			(xy 394.082016 -268.331696) (xy 394.267944 -268.517624)
		)
		(stroke
			(width 0)
			(type solid)
		)
		(fill yes)
		(layer "F.Cu")
		(net "M_E_CPU0_SA_CB<2>")
	)
	(gr_poly
		(pts
			(xy 394.312902 -267.62837) (xy 394.35913 -267.530834) (xy 394.22451 -267.396214) (xy 394.127228 -267.442442)
			(xy 394.09116 -267.478256) (xy 394.277088 -267.664184)
		)
		(stroke
			(width 0)
			(type solid)
		)
		(fill yes)
		(layer "F.Cu")
		(net "M_E_CPU0_SA_CB<3>")
	)
	(gr_poly
		(pts
			(xy 394.324078 -234.103164) (xy 394.27785 -234.005628) (xy 394.241782 -233.969814) (xy 394.056108 -234.155488)
			(xy 394.091922 -234.191556) (xy 394.189458 -234.237784)
		)
		(stroke
			(width 0)
			(type solid)
		)
		(fill yes)
		(layer "F.Cu")
		(net "M_E_CPU0_SB_DQ<11>")
	)
	(gr_poly
		(pts
			(xy 394.327634 -276.671532) (xy 394.42009 -276.61616) (xy 394.382752 -276.42947) (xy 394.276072 -276.413722)
			(xy 394.226288 -276.423882) (xy 394.27785 -276.681438)
		)
		(stroke
			(width 0)
			(type solid)
		)
		(fill yes)
		(layer "F.Cu")
		(net "M_E_CPU0_SA_DQ<24>")
	)
	(gr_poly
		(pts
			(xy 394.327888 -270.989806) (xy 394.374116 -270.892524) (xy 394.239496 -270.75765) (xy 394.14196 -270.804132)
			(xy 394.106146 -270.839946) (xy 394.292074 -271.025874)
		)
		(stroke
			(width 0)
			(type solid)
		)
		(fill yes)
		(layer "F.Cu")
		(net "M_E_CPU0_SA_DQ<28>")
	)
	(gr_poly
		(pts
			(xy 394.333984 -234.957112) (xy 394.287756 -234.85983) (xy 394.251942 -234.823762) (xy 394.066014 -235.00969)
			(xy 394.101828 -235.045758) (xy 394.199364 -235.091986)
		)
		(stroke
			(width 0)
			(type solid)
		)
		(fill yes)
		(layer "F.Cu")
		(net "M_E_CPU0_SB_DQ<10>")
	)
	(gr_poly
		(pts
			(xy 394.33627 -276.9743) (xy 394.284708 -276.71649) (xy 394.234924 -276.726396) (xy 394.142468 -276.781768)
			(xy 394.179806 -276.968712) (xy 394.286486 -276.984206)
		)
		(stroke
			(width 0)
			(type solid)
		)
		(fill yes)
		(layer "F.Cu")
		(net "M_E_CPU0_SA_DQ<24>")
	)
	(gr_poly
		(pts
			(xy 394.337286 -270.136366) (xy 394.383514 -270.039084) (xy 394.248894 -269.90421) (xy 394.151358 -269.950438)
			(xy 394.115544 -269.986506) (xy 394.301472 -270.172434)
		)
		(stroke
			(width 0)
			(type solid)
		)
		(fill yes)
		(layer "F.Cu")
		(net "M_E_CPU0_SA_DQ<29>")
	)
	(gr_poly
		(pts
			(xy 394.342112 -236.653578) (xy 394.295884 -236.556296) (xy 394.26007 -236.520228) (xy 394.074142 -236.706156)
			(xy 394.109956 -236.74197) (xy 394.207492 -236.788452)
		)
		(stroke
			(width 0)
			(type solid)
		)
		(fill yes)
		(layer "F.Cu")
		(net "M_E_CPU0_SB_CB<1>")
	)
	(gr_poly
		(pts
			(xy 394.35151 -237.507018) (xy 394.305282 -237.409482) (xy 394.269214 -237.373668) (xy 394.083286 -237.559596)
			(xy 394.119354 -237.59541) (xy 394.216636 -237.641638)
		)
		(stroke
			(width 0)
			(type solid)
		)
		(fill yes)
		(layer "F.Cu")
		(net "M_E_CPU0_SB_CB<0>")
	)
	(gr_poly
		(pts
			(xy 394.361162 -265.087862) (xy 394.40739 -264.990326) (xy 394.272516 -264.855706) (xy 394.175234 -264.901934)
			(xy 394.139166 -264.937748) (xy 394.325094 -265.123676)
		)
		(stroke
			(width 0)
			(type solid)
		)
		(fill yes)
		(layer "F.Cu")
		(net "M_E_CPU0_SA_CB<6>")
	)
	(gr_poly
		(pts
			(xy 394.364464 -279.741122) (xy 394.457174 -279.68575) (xy 394.419836 -279.498806) (xy 394.312902 -279.483312)
			(xy 394.263118 -279.493218) (xy 394.31468 -279.751028)
		)
		(stroke
			(width 0)
			(type solid)
		)
		(fill yes)
		(layer "F.Cu")
		(net "M_E_CPU0_SA_DQ<23>")
	)
	(gr_poly
		(pts
			(xy 394.370306 -264.234422) (xy 394.416534 -264.136886) (xy 394.281914 -264.002266) (xy 394.184378 -264.048494)
			(xy 394.148564 -264.084562) (xy 394.334492 -264.27049)
		)
		(stroke
			(width 0)
			(type solid)
		)
		(fill yes)
		(layer "F.Cu")
		(net "M_E_CPU0_SA_CB<7>")
	)
	(gr_poly
		(pts
			(xy 394.377672 -273.233388) (xy 394.4239 -273.135852) (xy 394.28928 -273.001232) (xy 394.191998 -273.04746)
			(xy 394.15593 -273.083274) (xy 394.341858 -273.269202)
		)
		(stroke
			(width 0)
			(type solid)
		)
		(fill yes)
		(layer "F.Cu")
		(net "M_E_CPU0_SA_DQ<27>")
	)
	(gr_poly
		(pts
			(xy 394.381228 -283.949648) (xy 394.330428 -283.949648) (xy 394.228828 -283.98597) (xy 394.228828 -284.17647)
			(xy 394.330428 -284.212538) (xy 394.381228 -284.212538)
		)
		(stroke
			(width 0)
			(type solid)
		)
		(fill yes)
		(layer "F.Cu")
		(net "M_E_CPU0_SA_DQ<23>")
	)
	(gr_poly
		(pts
			(xy 394.381228 -283.352748) (xy 394.330428 -283.352748) (xy 394.228828 -283.38907) (xy 394.228828 -283.57957)
			(xy 394.330428 -283.615638) (xy 394.381228 -283.615638)
		)
		(stroke
			(width 0)
			(type solid)
		)
		(fill yes)
		(layer "F.Cu")
		(net "M_E_CPU0_SA_DQ<23>")
	)
	(gr_poly
		(pts
			(xy 394.381228 -282.755848) (xy 394.330428 -282.755848) (xy 394.228828 -282.79217) (xy 394.228828 -282.98267)
			(xy 394.330428 -283.018738) (xy 394.381228 -283.018738)
		)
		(stroke
			(width 0)
			(type solid)
		)
		(fill yes)
		(layer "F.Cu")
		(net "M_E_CPU0_SA_DQ<23>")
	)
	(gr_poly
		(pts
			(xy 394.381228 -282.158948) (xy 394.330428 -282.158948) (xy 394.228828 -282.19527) (xy 394.228828 -282.38577)
			(xy 394.330428 -282.421838) (xy 394.381228 -282.421838)
		)
		(stroke
			(width 0)
			(type solid)
		)
		(fill yes)
		(layer "F.Cu")
		(net "M_E_CPU0_SA_DQ<23>")
	)
	(gr_poly
		(pts
			(xy 394.381228 -281.562048) (xy 394.330428 -281.562048) (xy 394.228828 -281.59837) (xy 394.228828 -281.78887)
			(xy 394.330428 -281.824938) (xy 394.381228 -281.824938)
		)
		(stroke
			(width 0)
			(type solid)
		)
		(fill yes)
		(layer "F.Cu")
		(net "M_E_CPU0_SA_DQ<23>")
	)
	(gr_poly
		(pts
			(xy 394.381228 -280.965148) (xy 394.330428 -280.965148) (xy 394.228828 -281.00147) (xy 394.228828 -281.19197)
			(xy 394.330428 -281.228038) (xy 394.381228 -281.228038)
		)
		(stroke
			(width 0)
			(type solid)
		)
		(fill yes)
		(layer "F.Cu")
		(net "M_E_CPU0_SA_DQ<23>")
	)
	(gr_poly
		(pts
			(xy 394.381228 -280.368248) (xy 394.330428 -280.368248) (xy 394.228828 -280.40457) (xy 394.228828 -280.59507)
			(xy 394.330428 -280.631138) (xy 394.381228 -280.631138)
		)
		(stroke
			(width 0)
			(type solid)
		)
		(fill yes)
		(layer "F.Cu")
		(net "M_E_CPU0_SA_DQ<23>")
	)
	(gr_poly
		(pts
			(xy 394.392404 -275.441156) (xy 394.48486 -275.385784) (xy 394.447522 -275.19884) (xy 394.340842 -275.183346)
			(xy 394.291058 -275.193252) (xy 394.34262 -275.451062)
		)
		(stroke
			(width 0)
			(type solid)
		)
		(fill yes)
		(layer "F.Cu")
		(net "M_E_CPU0_SA_DQ<26>")
	)
	(gr_poly
		(pts
			(xy 394.401294 -275.74367) (xy 394.349732 -275.486114) (xy 394.299694 -275.49602) (xy 394.207238 -275.551392)
			(xy 394.244576 -275.738082) (xy 394.351256 -275.75383)
		)
		(stroke
			(width 0)
			(type solid)
		)
		(fill yes)
		(layer "F.Cu")
		(net "M_E_CPU0_SA_DQ<26>")
	)
	(gr_poly
		(pts
			(xy 394.41882 -230.34244) (xy 394.383006 -230.306372) (xy 394.28547 -230.260144) (xy 394.15085 -230.395018)
			(xy 394.197078 -230.4923) (xy 394.232892 -230.528368)
		)
		(stroke
			(width 0)
			(type solid)
		)
		(fill yes)
		(layer "F.Cu")
		(net "M_E_CPU0_SB_DQ<15>")
	)
	(gr_poly
		(pts
			(xy 394.419328 -229.498652) (xy 394.38326 -229.462838) (xy 394.285978 -229.41661) (xy 394.151104 -229.55123)
			(xy 394.197586 -229.648766) (xy 394.2334 -229.68458)
		)
		(stroke
			(width 0)
			(type solid)
		)
		(fill yes)
		(layer "F.Cu")
		(net "M_E_CPU0_SB_DQ<16>")
	)
	(gr_poly
		(pts
			(xy 394.427964 -231.19588) (xy 394.39215 -231.159812) (xy 394.294614 -231.113584) (xy 394.159994 -231.248204)
			(xy 394.206222 -231.34574) (xy 394.24229 -231.381554)
		)
		(stroke
			(width 0)
			(type solid)
		)
		(fill yes)
		(layer "F.Cu")
		(net "M_E_CPU0_SB_DQ<14>")
	)
	(gr_poly
		(pts
			(xy 394.44295 -268.764512) (xy 394.479018 -268.728698) (xy 394.29309 -268.54277) (xy 394.257022 -268.578584)
			(xy 394.210794 -268.67612) (xy 394.345668 -268.81074)
		)
		(stroke
			(width 0)
			(type solid)
		)
		(fill yes)
		(layer "F.Cu")
		(net "M_E_CPU0_SA_CB<2>")
	)
	(gr_poly
		(pts
			(xy 394.444728 -277.257002) (xy 394.537184 -277.201376) (xy 394.499846 -277.014686) (xy 394.393166 -276.999192)
			(xy 394.343128 -277.009098) (xy 394.394944 -277.266908)
		)
		(stroke
			(width 0)
			(type solid)
		)
		(fill yes)
		(layer "F.Cu")
		(net "M_E_CPU0_SA_DQ<24>")
	)
	(gr_poly
		(pts
			(xy 394.452094 -267.911072) (xy 394.488162 -267.875258) (xy 394.302234 -267.68933) (xy 394.26642 -267.725144)
			(xy 394.219938 -267.82268) (xy 394.354812 -267.9573)
		)
		(stroke
			(width 0)
			(type solid)
		)
		(fill yes)
		(layer "F.Cu")
		(net "M_E_CPU0_SA_CB<3>")
	)
	(gr_poly
		(pts
			(xy 394.452856 -233.75874) (xy 394.417042 -233.722672) (xy 394.319506 -233.676444) (xy 394.184886 -233.811064)
			(xy 394.231114 -233.9086) (xy 394.266928 -233.944668)
		)
		(stroke
			(width 0)
			(type solid)
		)
		(fill yes)
		(layer "F.Cu")
		(net "M_E_CPU0_SB_DQ<11>")
	)
	(gr_poly
		(pts
			(xy 394.453364 -277.559516) (xy 394.401802 -277.301706) (xy 394.352018 -277.311612) (xy 394.259562 -277.367238)
			(xy 394.2969 -277.553928) (xy 394.40358 -277.569422)
		)
		(stroke
			(width 0)
			(type solid)
		)
		(fill yes)
		(layer "F.Cu")
		(net "M_E_CPU0_SA_DQ<24>")
	)
	(gr_poly
		(pts
			(xy 394.45438 -228.447092) (xy 394.45438 -228.256592) (xy 394.35278 -228.220524) (xy 394.30198 -228.220524)
			(xy 394.30198 -228.483414) (xy 394.35278 -228.483414)
		)
		(stroke
			(width 0)
			(type solid)
		)
		(fill yes)
		(layer "F.Cu")
		(net "M_E_CPU0_SB_DQ<17>")
	)
	(gr_poly
		(pts
			(xy 394.45438 -227.850192) (xy 394.45438 -227.659692) (xy 394.35278 -227.623624) (xy 394.30198 -227.623624)
			(xy 394.30198 -227.886514) (xy 394.35278 -227.886514)
		)
		(stroke
			(width 0)
			(type solid)
		)
		(fill yes)
		(layer "F.Cu")
		(net "M_E_CPU0_SB_DQ<17>")
	)
	(gr_poly
		(pts
			(xy 394.45438 -227.253292) (xy 394.45438 -227.062792) (xy 394.35278 -227.026724) (xy 394.30198 -227.026724)
			(xy 394.30198 -227.289614) (xy 394.35278 -227.289614)
		)
		(stroke
			(width 0)
			(type solid)
		)
		(fill yes)
		(layer "F.Cu")
		(net "M_E_CPU0_SB_DQ<17>")
	)
	(gr_poly
		(pts
			(xy 394.45438 -226.656392) (xy 394.45438 -226.465892) (xy 394.35278 -226.429824) (xy 394.30198 -226.429824)
			(xy 394.30198 -226.692714) (xy 394.35278 -226.692714)
		)
		(stroke
			(width 0)
			(type solid)
		)
		(fill yes)
		(layer "F.Cu")
		(net "M_E_CPU0_SB_DQ<17>")
	)
	(gr_poly
		(pts
			(xy 394.45438 -226.059492) (xy 394.45438 -225.868992) (xy 394.35278 -225.832924) (xy 394.30198 -225.832924)
			(xy 394.30198 -226.095814) (xy 394.35278 -226.095814)
		)
		(stroke
			(width 0)
			(type solid)
		)
		(fill yes)
		(layer "F.Cu")
		(net "M_E_CPU0_SB_DQ<17>")
	)
	(gr_poly
		(pts
			(xy 394.45438 -225.462592) (xy 394.45438 -225.272092) (xy 394.35278 -225.236024) (xy 394.30198 -225.236024)
			(xy 394.30198 -225.498914) (xy 394.35278 -225.498914)
		)
		(stroke
			(width 0)
			(type solid)
		)
		(fill yes)
		(layer "F.Cu")
		(net "M_E_CPU0_SB_DQ<17>")
	)
	(gr_poly
		(pts
			(xy 394.45438 -224.865692) (xy 394.45438 -224.675192) (xy 394.35278 -224.639124) (xy 394.30198 -224.639124)
			(xy 394.30198 -224.902014) (xy 394.35278 -224.902014)
		)
		(stroke
			(width 0)
			(type solid)
		)
		(fill yes)
		(layer "F.Cu")
		(net "M_E_CPU0_SB_DQ<17>")
	)
	(gr_poly
		(pts
			(xy 394.45438 -224.268792) (xy 394.45438 -224.078292) (xy 394.35278 -224.042224) (xy 394.30198 -224.042224)
			(xy 394.30198 -224.305114) (xy 394.35278 -224.305114)
		)
		(stroke
			(width 0)
			(type solid)
		)
		(fill yes)
		(layer "F.Cu")
		(net "M_E_CPU0_SB_DQ<17>")
	)
	(gr_poly
		(pts
			(xy 394.45438 -223.671892) (xy 394.45438 -223.481392) (xy 394.35278 -223.445324) (xy 394.30198 -223.445324)
			(xy 394.30198 -223.708214) (xy 394.35278 -223.708214)
		)
		(stroke
			(width 0)
			(type solid)
		)
		(fill yes)
		(layer "F.Cu")
		(net "M_E_CPU0_SB_DQ<17>")
	)
	(gr_poly
		(pts
			(xy 394.45438 -223.074992) (xy 394.45438 -222.884492) (xy 394.35278 -222.848424) (xy 394.30198 -222.848424)
			(xy 394.30198 -223.111314) (xy 394.35278 -223.111314)
		)
		(stroke
			(width 0)
			(type solid)
		)
		(fill yes)
		(layer "F.Cu")
		(net "M_E_CPU0_SB_DQ<17>")
	)
	(gr_poly
		(pts
			(xy 394.45438 -222.478092) (xy 394.45438 -222.287592) (xy 394.35278 -222.251524) (xy 394.30198 -222.251524)
			(xy 394.30198 -222.514414) (xy 394.35278 -222.514414)
		)
		(stroke
			(width 0)
			(type solid)
		)
		(fill yes)
		(layer "F.Cu")
		(net "M_E_CPU0_SB_DQ<17>")
	)
	(gr_poly
		(pts
			(xy 394.45438 -221.881192) (xy 394.45438 -221.690692) (xy 394.35278 -221.654624) (xy 394.30198 -221.654624)
			(xy 394.30198 -221.917514) (xy 394.35278 -221.917514)
		)
		(stroke
			(width 0)
			(type solid)
		)
		(fill yes)
		(layer "F.Cu")
		(net "M_E_CPU0_SB_DQ<17>")
	)
	(gr_poly
		(pts
			(xy 394.45438 -221.284292) (xy 394.45438 -221.093792) (xy 394.35278 -221.057724) (xy 394.30198 -221.057724)
			(xy 394.30198 -221.320614) (xy 394.35278 -221.320614)
		)
		(stroke
			(width 0)
			(type solid)
		)
		(fill yes)
		(layer "F.Cu")
		(net "M_E_CPU0_SB_DQ<17>")
	)
	(gr_poly
		(pts
			(xy 394.45438 -220.687392) (xy 394.45438 -220.496892) (xy 394.35278 -220.460824) (xy 394.30198 -220.460824)
			(xy 394.30198 -220.723714) (xy 394.35278 -220.723714)
		)
		(stroke
			(width 0)
			(type solid)
		)
		(fill yes)
		(layer "F.Cu")
		(net "M_E_CPU0_SB_DQ<17>")
	)
	(gr_poly
		(pts
			(xy 394.457428 -274.21078) (xy 394.549884 -274.155408) (xy 394.512546 -273.968464) (xy 394.405866 -273.95297)
			(xy 394.356082 -273.962876) (xy 394.407644 -274.220686)
		)
		(stroke
			(width 0)
			(type solid)
		)
		(fill yes)
		(layer "F.Cu")
		(net "M_E_CPU0_SA_DQ<25>")
	)
	(gr_poly
		(pts
			(xy 394.463016 -234.612688) (xy 394.426948 -234.576874) (xy 394.329666 -234.530646) (xy 394.194792 -234.665266)
			(xy 394.24102 -234.762802) (xy 394.277088 -234.798616)
		)
		(stroke
			(width 0)
			(type solid)
		)
		(fill yes)
		(layer "F.Cu")
		(net "M_E_CPU0_SB_DQ<10>")
	)
	(gr_poly
		(pts
			(xy 394.466064 -274.513294) (xy 394.414502 -274.255484) (xy 394.364718 -274.265644) (xy 394.272262 -274.321016)
			(xy 394.3096 -274.507706) (xy 394.41628 -274.5232)
		)
		(stroke
			(width 0)
			(type solid)
		)
		(fill yes)
		(layer "F.Cu")
		(net "M_E_CPU0_SA_DQ<25>")
	)
	(gr_poly
		(pts
			(xy 394.46708 -271.272762) (xy 394.503148 -271.236948) (xy 394.31722 -271.05102) (xy 394.281152 -271.086834)
			(xy 394.234924 -271.18437) (xy 394.369798 -271.31899)
		)
		(stroke
			(width 0)
			(type solid)
		)
		(fill yes)
		(layer "F.Cu")
		(net "M_E_CPU0_SA_DQ<28>")
	)
	(gr_poly
		(pts
			(xy 394.471144 -236.309154) (xy 394.435076 -236.27334) (xy 394.337794 -236.227112) (xy 394.20292 -236.361732)
			(xy 394.249148 -236.459268) (xy 394.285216 -236.495082)
		)
		(stroke
			(width 0)
			(type solid)
		)
		(fill yes)
		(layer "F.Cu")
		(net "M_E_CPU0_SB_CB<1>")
	)
	(gr_poly
		(pts
			(xy 394.476478 -270.419322) (xy 394.512292 -270.383254) (xy 394.326618 -270.19758) (xy 394.29055 -270.233394)
			(xy 394.244322 -270.33093) (xy 394.378942 -270.46555)
		)
		(stroke
			(width 0)
			(type solid)
		)
		(fill yes)
		(layer "F.Cu")
		(net "M_E_CPU0_SA_DQ<29>")
	)
	(gr_poly
		(pts
			(xy 394.480288 -237.162594) (xy 394.444474 -237.12678) (xy 394.346938 -237.080552) (xy 394.212318 -237.215172)
			(xy 394.258546 -237.312454) (xy 394.29436 -237.348522)
		)
		(stroke
			(width 0)
			(type solid)
		)
		(fill yes)
		(layer "F.Cu")
		(net "M_E_CPU0_SB_CB<0>")
	)
	(gr_poly
		(pts
			(xy 394.496798 -229.205282) (xy 394.45057 -229.108) (xy 394.414756 -229.071932) (xy 394.228828 -229.25786)
			(xy 394.264642 -229.293928) (xy 394.362178 -229.340156)
		)
		(stroke
			(width 0)
			(type solid)
		)
		(fill yes)
		(layer "F.Cu")
		(net "M_E_CPU0_SB_DQ<18>")
	)
	(gr_poly
		(pts
			(xy 394.500354 -265.370564) (xy 394.536168 -265.33475) (xy 394.35024 -265.148822) (xy 394.314426 -265.18489)
			(xy 394.268198 -265.282172) (xy 394.402818 -265.417046)
		)
		(stroke
			(width 0)
			(type solid)
		)
		(fill yes)
		(layer "F.Cu")
		(net "M_E_CPU0_SA_CB<6>")
	)
	(gr_poly
		(pts
			(xy 394.505688 -230.90251) (xy 394.45946 -230.804974) (xy 394.423392 -230.76916) (xy 394.237464 -230.955088)
			(xy 394.273532 -230.990902) (xy 394.370814 -231.03713)
		)
		(stroke
			(width 0)
			(type solid)
		)
		(fill yes)
		(layer "F.Cu")
		(net "M_E_CPU0_SB_DQ<13>")
	)
	(gr_poly
		(pts
			(xy 394.509498 -276.026372) (xy 394.601954 -275.971) (xy 394.564616 -275.78431) (xy 394.457936 -275.768562)
			(xy 394.408152 -275.778722) (xy 394.459714 -276.036532)
		)
		(stroke
			(width 0)
			(type solid)
		)
		(fill yes)
		(layer "F.Cu")
		(net "M_E_CPU0_SA_DQ<26>")
	)
	(gr_poly
		(pts
			(xy 394.509498 -264.517378) (xy 394.545312 -264.48131) (xy 394.359638 -264.295636) (xy 394.32357 -264.33145)
			(xy 394.277342 -264.428986) (xy 394.411962 -264.563606)
		)
		(stroke
			(width 0)
			(type solid)
		)
		(fill yes)
		(layer "F.Cu")
		(net "M_E_CPU0_SA_CB<7>")
	)
	(gr_poly
		(pts
			(xy 394.51026 -269.11935) (xy 394.556488 -269.021814) (xy 394.421868 -268.887194) (xy 394.324332 -268.933422)
			(xy 394.288518 -268.96949) (xy 394.474192 -269.155164)
		)
		(stroke
			(width 0)
			(type solid)
		)
		(fill yes)
		(layer "F.Cu")
		(net "M_E_CPU0_SA_CB<0>")
	)
	(gr_poly
		(pts
			(xy 394.514832 -231.755696) (xy 394.468604 -231.658414) (xy 394.43279 -231.622346) (xy 394.246862 -231.808274)
			(xy 394.282676 -231.844342) (xy 394.380212 -231.89057)
		)
		(stroke
			(width 0)
			(type solid)
		)
		(fill yes)
		(layer "F.Cu")
		(net "M_E_CPU0_SB_DQ<12>")
	)
	(gr_poly
		(pts
			(xy 394.518134 -276.32914) (xy 394.466572 -276.07133) (xy 394.416788 -276.081236) (xy 394.324332 -276.136608)
			(xy 394.36167 -276.323552) (xy 394.46835 -276.339046)
		)
		(stroke
			(width 0)
			(type solid)
		)
		(fill yes)
		(layer "F.Cu")
		(net "M_E_CPU0_SA_DQ<26>")
	)
	(gr_poly
		(pts
			(xy 394.519404 -268.26591) (xy 394.565632 -268.168628) (xy 394.431012 -268.033754) (xy 394.333476 -268.079982)
			(xy 394.297662 -268.11605) (xy 394.48359 -268.301978)
		)
		(stroke
			(width 0)
			(type solid)
		)
		(fill yes)
		(layer "F.Cu")
		(net "M_E_CPU0_SA_CB<1>")
	)
	(gr_poly
		(pts
			(xy 394.533628 -283.87802) (xy 394.533628 -283.68752) (xy 394.432028 -283.651198) (xy 394.381228 -283.651198)
			(xy 394.381228 -283.914342) (xy 394.432028 -283.914342)
		)
		(stroke
			(width 0)
			(type solid)
		)
		(fill yes)
		(layer "F.Cu")
		(net "M_E_CPU0_SA_DQ<23>")
	)
	(gr_poly
		(pts
			(xy 394.533628 -283.28112) (xy 394.533628 -283.09062) (xy 394.432028 -283.054298) (xy 394.381228 -283.054298)
			(xy 394.381228 -283.317442) (xy 394.432028 -283.317442)
		)
		(stroke
			(width 0)
			(type solid)
		)
		(fill yes)
		(layer "F.Cu")
		(net "M_E_CPU0_SA_DQ<23>")
	)
	(gr_poly
		(pts
			(xy 394.533628 -282.68422) (xy 394.533628 -282.49372) (xy 394.432028 -282.457398) (xy 394.381228 -282.457398)
			(xy 394.381228 -282.720542) (xy 394.432028 -282.720542)
		)
		(stroke
			(width 0)
			(type solid)
		)
		(fill yes)
		(layer "F.Cu")
		(net "M_E_CPU0_SA_DQ<23>")
	)
	(gr_poly
		(pts
			(xy 394.533628 -282.08732) (xy 394.533628 -281.89682) (xy 394.432028 -281.860498) (xy 394.381228 -281.860498)
			(xy 394.381228 -282.123642) (xy 394.432028 -282.123642)
		)
		(stroke
			(width 0)
			(type solid)
		)
		(fill yes)
		(layer "F.Cu")
		(net "M_E_CPU0_SA_DQ<23>")
	)
	(gr_poly
		(pts
			(xy 394.533628 -281.49042) (xy 394.533628 -281.29992) (xy 394.432028 -281.263598) (xy 394.381228 -281.263598)
			(xy 394.381228 -281.526742) (xy 394.432028 -281.526742)
		)
		(stroke
			(width 0)
			(type solid)
		)
		(fill yes)
		(layer "F.Cu")
		(net "M_E_CPU0_SA_DQ<23>")
	)
	(gr_poly
		(pts
			(xy 394.533628 -280.89352) (xy 394.533628 -280.70302) (xy 394.432028 -280.666698) (xy 394.381228 -280.666698)
			(xy 394.381228 -280.929842) (xy 394.432028 -280.929842)
		)
		(stroke
			(width 0)
			(type solid)
		)
		(fill yes)
		(layer "F.Cu")
		(net "M_E_CPU0_SA_DQ<23>")
	)
	(gr_poly
		(pts
			(xy 394.539978 -234.319064) (xy 394.49375 -234.221528) (xy 394.457936 -234.185714) (xy 394.272008 -234.371642)
			(xy 394.307822 -234.407456) (xy 394.405358 -234.453684)
		)
		(stroke
			(width 0)
			(type solid)
		)
		(fill yes)
		(layer "F.Cu")
		(net "M_E_CPU0_SB_DQ<9>")
	)
	(gr_poly
		(pts
			(xy 394.543534 -270.77416) (xy 394.589762 -270.676878) (xy 394.455142 -270.542004) (xy 394.357606 -270.588486)
			(xy 394.321792 -270.6243) (xy 394.50772 -270.810228)
		)
		(stroke
			(width 0)
			(type solid)
		)
		(fill yes)
		(layer "F.Cu")
		(net "M_E_CPU0_SA_DQ<30>")
	)
	(gr_poly
		(pts
			(xy 394.548614 -236.016038) (xy 394.502386 -235.918502) (xy 394.466572 -235.882434) (xy 394.280644 -236.068362)
			(xy 394.316458 -236.10443) (xy 394.413994 -236.150658)
		)
		(stroke
			(width 0)
			(type solid)
		)
		(fill yes)
		(layer "F.Cu")
		(net "M_E_CPU0_SB_CB<3>")
	)
	(gr_poly
		(pts
			(xy 394.549884 -235.173012) (xy 394.503656 -235.075476) (xy 394.467588 -235.039662) (xy 394.28166 -235.22559)
			(xy 394.317728 -235.261404) (xy 394.41501 -235.307632)
		)
		(stroke
			(width 0)
			(type solid)
		)
		(fill yes)
		(layer "F.Cu")
		(net "M_E_CPU0_SB_DQ<8>")
	)
	(gr_poly
		(pts
			(xy 394.553186 -269.92072) (xy 394.599414 -269.823184) (xy 394.46454 -269.688564) (xy 394.367258 -269.734792)
			(xy 394.33119 -269.770606) (xy 394.517118 -269.956534)
		)
		(stroke
			(width 0)
			(type solid)
		)
		(fill yes)
		(layer "F.Cu")
		(net "M_E_CPU0_SA_DQ<31>")
	)
	(gr_poly
		(pts
			(xy 394.558012 -236.869224) (xy 394.511784 -236.771688) (xy 394.475716 -236.735874) (xy 394.289788 -236.921802)
			(xy 394.325856 -236.957616) (xy 394.423138 -237.003844)
		)
		(stroke
			(width 0)
			(type solid)
		)
		(fill yes)
		(layer "F.Cu")
		(net "M_E_CPU0_SB_CB<2>")
	)
	(gr_poly
		(pts
			(xy 394.561822 -277.842218) (xy 394.654278 -277.786846) (xy 394.61694 -277.599902) (xy 394.51026 -277.584408)
			(xy 394.460222 -277.594314) (xy 394.511784 -277.852124)
		)
		(stroke
			(width 0)
			(type solid)
		)
		(fill yes)
		(layer "F.Cu")
		(net "M_E_CPU0_SA_DQ<24>")
	)
	(gr_poly
		(pts
			(xy 394.56741 -265.725656) (xy 394.613638 -265.62812) (xy 394.479018 -265.4935) (xy 394.381482 -265.539728)
			(xy 394.345668 -265.575542) (xy 394.531596 -265.76147)
		)
		(stroke
			(width 0)
			(type solid)
		)
		(fill yes)
		(layer "F.Cu")
		(net "M_E_CPU0_SA_CB<4>")
	)
	(gr_poly
		(pts
			(xy 394.570458 -278.144732) (xy 394.518896 -277.886922) (xy 394.469112 -277.897082) (xy 394.376402 -277.952454)
			(xy 394.413994 -278.139144) (xy 394.520674 -278.154892)
		)
		(stroke
			(width 0)
			(type solid)
		)
		(fill yes)
		(layer "F.Cu")
		(net "M_E_CPU0_SA_DQ<24>")
	)
	(gr_poly
		(pts
			(xy 394.574522 -274.795996) (xy 394.666978 -274.740624) (xy 394.62964 -274.55368) (xy 394.52296 -274.538186)
			(xy 394.473176 -274.548092) (xy 394.524738 -274.805902)
		)
		(stroke
			(width 0)
			(type solid)
		)
		(fill yes)
		(layer "F.Cu")
		(net "M_E_CPU0_SA_DQ<25>")
	)
	(gr_poly
		(pts
			(xy 394.576808 -264.872216) (xy 394.623036 -264.77468) (xy 394.488162 -264.64006) (xy 394.39088 -264.686288)
			(xy 394.354812 -264.722102) (xy 394.54074 -264.90803)
		)
		(stroke
			(width 0)
			(type solid)
		)
		(fill yes)
		(layer "F.Cu")
		(net "M_E_CPU0_SA_CB<5>")
	)
	(gr_poly
		(pts
			(xy 394.583158 -275.098764) (xy 394.531596 -274.840954) (xy 394.481812 -274.85086) (xy 394.389356 -274.906232)
			(xy 394.426694 -275.093176) (xy 394.533374 -275.10867)
		)
		(stroke
			(width 0)
			(type solid)
		)
		(fill yes)
		(layer "F.Cu")
		(net "M_E_CPU0_SA_DQ<25>")
	)
	(gr_poly
		(pts
			(xy 394.60678 -227.922074) (xy 394.55598 -227.922074) (xy 394.45438 -227.958142) (xy 394.45438 -228.148642)
			(xy 394.55598 -228.184964) (xy 394.60678 -228.184964)
		)
		(stroke
			(width 0)
			(type solid)
		)
		(fill yes)
		(layer "F.Cu")
		(net "M_E_CPU0_SB_DQ<18>")
	)
	(gr_poly
		(pts
			(xy 394.60678 -227.325174) (xy 394.55598 -227.325174) (xy 394.45438 -227.361242) (xy 394.45438 -227.551742)
			(xy 394.55598 -227.588064) (xy 394.60678 -227.588064)
		)
		(stroke
			(width 0)
			(type solid)
		)
		(fill yes)
		(layer "F.Cu")
		(net "M_E_CPU0_SB_DQ<18>")
	)
	(gr_poly
		(pts
			(xy 394.60678 -226.728274) (xy 394.55598 -226.728274) (xy 394.45438 -226.764342) (xy 394.45438 -226.954842)
			(xy 394.55598 -226.991164) (xy 394.60678 -226.991164)
		)
		(stroke
			(width 0)
			(type solid)
		)
		(fill yes)
		(layer "F.Cu")
		(net "M_E_CPU0_SB_DQ<18>")
	)
	(gr_poly
		(pts
			(xy 394.60678 -226.131374) (xy 394.55598 -226.131374) (xy 394.45438 -226.167442) (xy 394.45438 -226.357942)
			(xy 394.55598 -226.394264) (xy 394.60678 -226.394264)
		)
		(stroke
			(width 0)
			(type solid)
		)
		(fill yes)
		(layer "F.Cu")
		(net "M_E_CPU0_SB_DQ<18>")
	)
	(gr_poly
		(pts
			(xy 394.60678 -225.534474) (xy 394.55598 -225.534474) (xy 394.45438 -225.570542) (xy 394.45438 -225.761042)
			(xy 394.55598 -225.797364) (xy 394.60678 -225.797364)
		)
		(stroke
			(width 0)
			(type solid)
		)
		(fill yes)
		(layer "F.Cu")
		(net "M_E_CPU0_SB_DQ<18>")
	)
	(gr_poly
		(pts
			(xy 394.60678 -224.937574) (xy 394.55598 -224.937574) (xy 394.45438 -224.973642) (xy 394.45438 -225.164142)
			(xy 394.55598 -225.200464) (xy 394.60678 -225.200464)
		)
		(stroke
			(width 0)
			(type solid)
		)
		(fill yes)
		(layer "F.Cu")
		(net "M_E_CPU0_SB_DQ<18>")
	)
	(gr_poly
		(pts
			(xy 394.60678 -224.340674) (xy 394.55598 -224.340674) (xy 394.45438 -224.376742) (xy 394.45438 -224.567242)
			(xy 394.55598 -224.603564) (xy 394.60678 -224.603564)
		)
		(stroke
			(width 0)
			(type solid)
		)
		(fill yes)
		(layer "F.Cu")
		(net "M_E_CPU0_SB_DQ<18>")
	)
	(gr_poly
		(pts
			(xy 394.60678 -223.743774) (xy 394.55598 -223.743774) (xy 394.45438 -223.779842) (xy 394.45438 -223.970342)
			(xy 394.55598 -224.006664) (xy 394.60678 -224.006664)
		)
		(stroke
			(width 0)
			(type solid)
		)
		(fill yes)
		(layer "F.Cu")
		(net "M_E_CPU0_SB_DQ<18>")
	)
	(gr_poly
		(pts
			(xy 394.60678 -223.146874) (xy 394.55598 -223.146874) (xy 394.45438 -223.182942) (xy 394.45438 -223.373442)
			(xy 394.55598 -223.409764) (xy 394.60678 -223.409764)
		)
		(stroke
			(width 0)
			(type solid)
		)
		(fill yes)
		(layer "F.Cu")
		(net "M_E_CPU0_SB_DQ<18>")
	)
	(gr_poly
		(pts
			(xy 394.60678 -222.549974) (xy 394.55598 -222.549974) (xy 394.45438 -222.586042) (xy 394.45438 -222.776542)
			(xy 394.55598 -222.812864) (xy 394.60678 -222.812864)
		)
		(stroke
			(width 0)
			(type solid)
		)
		(fill yes)
		(layer "F.Cu")
		(net "M_E_CPU0_SB_DQ<18>")
	)
	(gr_poly
		(pts
			(xy 394.60678 -221.953074) (xy 394.55598 -221.953074) (xy 394.45438 -221.989142) (xy 394.45438 -222.179642)
			(xy 394.55598 -222.215964) (xy 394.60678 -222.215964)
		)
		(stroke
			(width 0)
			(type solid)
		)
		(fill yes)
		(layer "F.Cu")
		(net "M_E_CPU0_SB_DQ<18>")
	)
	(gr_poly
		(pts
			(xy 394.60678 -221.356174) (xy 394.55598 -221.356174) (xy 394.45438 -221.392242) (xy 394.45438 -221.582742)
			(xy 394.55598 -221.619064) (xy 394.60678 -221.619064)
		)
		(stroke
			(width 0)
			(type solid)
		)
		(fill yes)
		(layer "F.Cu")
		(net "M_E_CPU0_SB_DQ<18>")
	)
	(gr_poly
		(pts
			(xy 394.60678 -220.759274) (xy 394.55598 -220.759274) (xy 394.45438 -220.795342) (xy 394.45438 -220.985842)
			(xy 394.55598 -221.022164) (xy 394.60678 -221.022164)
		)
		(stroke
			(width 0)
			(type solid)
		)
		(fill yes)
		(layer "F.Cu")
		(net "M_E_CPU0_SB_DQ<18>")
	)
	(gr_poly
		(pts
			(xy 394.60678 -220.162374) (xy 394.55598 -220.162374) (xy 394.45438 -220.198442) (xy 394.45438 -220.388942)
			(xy 394.55598 -220.425264) (xy 394.60678 -220.425264)
		)
		(stroke
			(width 0)
			(type solid)
		)
		(fill yes)
		(layer "F.Cu")
		(net "M_E_CPU0_SB_DQ<18>")
	)
	(gr_poly
		(pts
			(xy 394.626592 -276.611842) (xy 394.719048 -276.556216) (xy 394.68171 -276.369526) (xy 394.57503 -276.354032)
			(xy 394.525246 -276.363938) (xy 394.576808 -276.621748)
		)
		(stroke
			(width 0)
			(type solid)
		)
		(fill yes)
		(layer "F.Cu")
		(net "M_E_CPU0_SA_DQ<26>")
	)
	(gr_poly
		(pts
			(xy 394.634466 -230.558086) (xy 394.598652 -230.522018) (xy 394.501116 -230.47579) (xy 394.366496 -230.610664)
			(xy 394.412724 -230.707946) (xy 394.448538 -230.744014)
		)
		(stroke
			(width 0)
			(type solid)
		)
		(fill yes)
		(layer "F.Cu")
		(net "M_E_CPU0_SB_DQ<13>")
	)
	(gr_poly
		(pts
			(xy 394.635228 -276.914356) (xy 394.583666 -276.656546) (xy 394.533882 -276.666452) (xy 394.441426 -276.722078)
			(xy 394.478764 -276.908768) (xy 394.585444 -276.924262)
		)
		(stroke
			(width 0)
			(type solid)
		)
		(fill yes)
		(layer "F.Cu")
		(net "M_E_CPU0_SA_DQ<26>")
	)
	(gr_poly
		(pts
			(xy 394.64361 -231.411526) (xy 394.607796 -231.375458) (xy 394.51026 -231.32923) (xy 394.37564 -231.46385)
			(xy 394.421868 -231.561386) (xy 394.457936 -231.5972)
		)
		(stroke
			(width 0)
			(type solid)
		)
		(fill yes)
		(layer "F.Cu")
		(net "M_E_CPU0_SB_DQ<12>")
	)
	(gr_poly
		(pts
			(xy 394.649452 -269.402306) (xy 394.685266 -269.366238) (xy 394.499338 -269.18031) (xy 394.463524 -269.216378)
			(xy 394.417296 -269.31366) (xy 394.551916 -269.448534)
		)
		(stroke
			(width 0)
			(type solid)
		)
		(fill yes)
		(layer "F.Cu")
		(net "M_E_CPU0_SA_CB<0>")
	)
	(gr_poly
		(pts
			(xy 394.658596 -268.548866) (xy 394.694664 -268.513052) (xy 394.508736 -268.327124) (xy 394.472668 -268.362938)
			(xy 394.42644 -268.460474) (xy 394.561314 -268.595094)
		)
		(stroke
			(width 0)
			(type solid)
		)
		(fill yes)
		(layer "F.Cu")
		(net "M_E_CPU0_SA_CB<1>")
	)
	(gr_poly
		(pts
			(xy 394.66901 -233.97464) (xy 394.632942 -233.938826) (xy 394.53566 -233.892598) (xy 394.400786 -234.027218)
			(xy 394.447014 -234.1245) (xy 394.483082 -234.160568)
		)
		(stroke
			(width 0)
			(type solid)
		)
		(fill yes)
		(layer "F.Cu")
		(net "M_E_CPU0_SB_DQ<9>")
	)
	(gr_poly
		(pts
			(xy 394.678662 -278.427434) (xy 394.771372 -278.372062) (xy 394.734034 -278.185372) (xy 394.6271 -278.169624)
			(xy 394.577316 -278.179784) (xy 394.628878 -278.437594)
		)
		(stroke
			(width 0)
			(type solid)
		)
		(fill yes)
		(layer "F.Cu")
		(net "M_E_CPU0_SA_DQ<24>")
	)
	(gr_poly
		(pts
			(xy 394.678662 -234.828588) (xy 394.642848 -234.792774) (xy 394.545312 -234.746292) (xy 394.410692 -234.881166)
			(xy 394.45692 -234.978448) (xy 394.492734 -235.014516)
		)
		(stroke
			(width 0)
			(type solid)
		)
		(fill yes)
		(layer "F.Cu")
		(net "M_E_CPU0_SB_DQ<8>")
	)
	(gr_poly
		(pts
			(xy 394.682726 -271.057116) (xy 394.718794 -271.021302) (xy 394.532866 -270.835374) (xy 394.496798 -270.871188)
			(xy 394.45057 -270.968724) (xy 394.585444 -271.103344)
		)
		(stroke
			(width 0)
			(type solid)
		)
		(fill yes)
		(layer "F.Cu")
		(net "M_E_CPU0_SA_DQ<30>")
	)
	(gr_poly
		(pts
			(xy 394.68679 -236.5248) (xy 394.650976 -236.488986) (xy 394.55344 -236.442758) (xy 394.41882 -236.577378)
			(xy 394.465048 -236.67466) (xy 394.500862 -236.710728)
		)
		(stroke
			(width 0)
			(type solid)
		)
		(fill yes)
		(layer "F.Cu")
		(net "M_E_CPU0_SB_CB<2>")
	)
	(gr_poly
		(pts
			(xy 394.687552 -278.730202) (xy 394.63599 -278.472392) (xy 394.586206 -278.482298) (xy 394.493496 -278.53767)
			(xy 394.531088 -278.724614) (xy 394.637768 -278.740108)
		)
		(stroke
			(width 0)
			(type solid)
		)
		(fill yes)
		(layer "F.Cu")
		(net "M_E_CPU0_SA_DQ<24>")
	)
	(gr_poly
		(pts
			(xy 394.691616 -275.381212) (xy 394.784072 -275.32584) (xy 394.746734 -275.13915) (xy 394.640054 -275.123656)
			(xy 394.59027 -275.133562) (xy 394.641832 -275.391372)
		)
		(stroke
			(width 0)
			(type solid)
		)
		(fill yes)
		(layer "F.Cu")
		(net "M_E_CPU0_SA_DQ<25>")
	)
	(gr_poly
		(pts
			(xy 394.692378 -270.203422) (xy 394.728192 -270.167608) (xy 394.542264 -269.98168) (xy 394.50645 -270.017494)
			(xy 394.460222 -270.11503) (xy 394.594842 -270.24965)
		)
		(stroke
			(width 0)
			(type solid)
		)
		(fill yes)
		(layer "F.Cu")
		(net "M_E_CPU0_SA_DQ<31>")
	)
	(gr_poly
		(pts
			(xy 394.700506 -275.68398) (xy 394.64869 -275.42617) (xy 394.598906 -275.436076) (xy 394.50645 -275.491448)
			(xy 394.543788 -275.678392) (xy 394.650468 -275.693886)
		)
		(stroke
			(width 0)
			(type solid)
		)
		(fill yes)
		(layer "F.Cu")
		(net "M_E_CPU0_SA_DQ<25>")
	)
	(gr_poly
		(pts
			(xy 394.706602 -266.008358) (xy 394.74267 -265.972544) (xy 394.556742 -265.786616) (xy 394.520928 -265.82243)
			(xy 394.474446 -265.919966) (xy 394.60932 -266.054586)
		)
		(stroke
			(width 0)
			(type solid)
		)
		(fill yes)
		(layer "F.Cu")
		(net "M_E_CPU0_SA_CB<4>")
	)
	(gr_poly
		(pts
			(xy 394.711936 -230.264716) (xy 394.665708 -230.16718) (xy 394.629894 -230.131366) (xy 394.443966 -230.317294)
			(xy 394.47978 -230.353108) (xy 394.577316 -230.399336)
		)
		(stroke
			(width 0)
			(type solid)
		)
		(fill yes)
		(layer "F.Cu")
		(net "M_E_CPU0_SB_DQ<15>")
	)
	(gr_poly
		(pts
			(xy 394.712444 -229.420928) (xy 394.666216 -229.323646) (xy 394.630402 -229.287578) (xy 394.444474 -229.473506)
			(xy 394.480288 -229.509574) (xy 394.577824 -229.555802)
		)
		(stroke
			(width 0)
			(type solid)
		)
		(fill yes)
		(layer "F.Cu")
		(net "M_E_CPU0_SB_DQ<16>")
	)
	(gr_poly
		(pts
			(xy 394.716 -265.154918) (xy 394.751814 -265.119104) (xy 394.565886 -264.933176) (xy 394.530072 -264.969244)
			(xy 394.483844 -265.066526) (xy 394.618464 -265.2014)
		)
		(stroke
			(width 0)
			(type solid)
		)
		(fill yes)
		(layer "F.Cu")
		(net "M_E_CPU0_SA_CB<5>")
	)
	(gr_poly
		(pts
			(xy 394.721334 -231.118156) (xy 394.675106 -231.02062) (xy 394.639038 -230.984806) (xy 394.45311 -231.170734)
			(xy 394.489178 -231.206548) (xy 394.58646 -231.252776)
		)
		(stroke
			(width 0)
			(type solid)
		)
		(fill yes)
		(layer "F.Cu")
		(net "M_E_CPU0_SB_DQ<14>")
	)
	(gr_poly
		(pts
			(xy 394.725906 -268.903704) (xy 394.772134 -268.806168) (xy 394.637514 -268.671548) (xy 394.539978 -268.717776)
			(xy 394.504164 -268.753844) (xy 394.689838 -268.939518)
		)
		(stroke
			(width 0)
			(type solid)
		)
		(fill yes)
		(layer "F.Cu")
		(net "M_E_CPU0_SA_CB<2>")
	)
	(gr_poly
		(pts
			(xy 394.73505 -268.050264) (xy 394.781278 -267.952982) (xy 394.646658 -267.818108) (xy 394.549122 -267.864336)
			(xy 394.513308 -267.900404) (xy 394.699236 -268.086332)
		)
		(stroke
			(width 0)
			(type solid)
		)
		(fill yes)
		(layer "F.Cu")
		(net "M_E_CPU0_SA_CB<3>")
	)
	(gr_poly
		(pts
			(xy 394.743686 -277.197058) (xy 394.836142 -277.141686) (xy 394.798804 -276.954742) (xy 394.692124 -276.939248)
			(xy 394.64234 -276.949154) (xy 394.693902 -277.206964)
		)
		(stroke
			(width 0)
			(type solid)
		)
		(fill yes)
		(layer "F.Cu")
		(net "M_E_CPU0_SA_DQ<26>")
	)
	(gr_poly
		(pts
			(xy 394.746226 -233.681016) (xy 394.699998 -233.58348) (xy 394.66393 -233.547666) (xy 394.478002 -233.733594)
			(xy 394.51407 -233.769408) (xy 394.611352 -233.815636)
		)
		(stroke
			(width 0)
			(type solid)
		)
		(fill yes)
		(layer "F.Cu")
		(net "M_E_CPU0_SB_DQ<11>")
	)
	(gr_poly
		(pts
			(xy 394.750036 -271.411954) (xy 394.796264 -271.314418) (xy 394.661644 -271.179798) (xy 394.564108 -271.226026)
			(xy 394.528294 -271.262094) (xy 394.713968 -271.447768)
		)
		(stroke
			(width 0)
			(type solid)
		)
		(fill yes)
		(layer "F.Cu")
		(net "M_E_CPU0_SA_DQ<28>")
	)
	(gr_poly
		(pts
			(xy 394.752322 -277.499572) (xy 394.70076 -277.242016) (xy 394.650976 -277.251922) (xy 394.55852 -277.307294)
			(xy 394.595858 -277.493984) (xy 394.702538 -277.509732)
		)
		(stroke
			(width 0)
			(type solid)
		)
		(fill yes)
		(layer "F.Cu")
		(net "M_E_CPU0_SA_DQ<26>")
	)
	(gr_poly
		(pts
			(xy 394.756132 -234.535218) (xy 394.709904 -234.437682) (xy 394.673836 -234.401868) (xy 394.488162 -234.587542)
			(xy 394.523976 -234.62361) (xy 394.621512 -234.669838)
		)
		(stroke
			(width 0)
			(type solid)
		)
		(fill yes)
		(layer "F.Cu")
		(net "M_E_CPU0_SB_DQ<10>")
	)
	(gr_poly
		(pts
			(xy 394.756894 -274.150836) (xy 394.84935 -274.095464) (xy 394.812012 -273.90852) (xy 394.705078 -273.893026)
			(xy 394.655294 -273.902932) (xy 394.706856 -274.160742)
		)
		(stroke
			(width 0)
			(type solid)
		)
		(fill yes)
		(layer "F.Cu")
		(net "M_E_CPU0_SA_DQ<27>")
	)
	(gr_poly
		(pts
			(xy 394.75918 -228.447092) (xy 394.75918 -228.256592) (xy 394.65758 -228.220524) (xy 394.60678 -228.220524)
			(xy 394.60678 -228.483414) (xy 394.65758 -228.483414)
		)
		(stroke
			(width 0)
			(type solid)
		)
		(fill yes)
		(layer "F.Cu")
		(net "M_E_CPU0_SB_DQ<18>")
	)
	(gr_poly
		(pts
			(xy 394.75918 -227.850192) (xy 394.75918 -227.659692) (xy 394.65758 -227.623624) (xy 394.60678 -227.623624)
			(xy 394.60678 -227.886514) (xy 394.65758 -227.886514)
		)
		(stroke
			(width 0)
			(type solid)
		)
		(fill yes)
		(layer "F.Cu")
		(net "M_E_CPU0_SB_DQ<18>")
	)
	(gr_poly
		(pts
			(xy 394.75918 -227.253292) (xy 394.75918 -227.062792) (xy 394.65758 -227.026724) (xy 394.60678 -227.026724)
			(xy 394.60678 -227.289614) (xy 394.65758 -227.289614)
		)
		(stroke
			(width 0)
			(type solid)
		)
		(fill yes)
		(layer "F.Cu")
		(net "M_E_CPU0_SB_DQ<18>")
	)
	(gr_poly
		(pts
			(xy 394.75918 -226.656392) (xy 394.75918 -226.465892) (xy 394.65758 -226.429824) (xy 394.60678 -226.429824)
			(xy 394.60678 -226.692714) (xy 394.65758 -226.692714)
		)
		(stroke
			(width 0)
			(type solid)
		)
		(fill yes)
		(layer "F.Cu")
		(net "M_E_CPU0_SB_DQ<18>")
	)
	(gr_poly
		(pts
			(xy 394.75918 -226.059492) (xy 394.75918 -225.868992) (xy 394.65758 -225.832924) (xy 394.60678 -225.832924)
			(xy 394.60678 -226.095814) (xy 394.65758 -226.095814)
		)
		(stroke
			(width 0)
			(type solid)
		)
		(fill yes)
		(layer "F.Cu")
		(net "M_E_CPU0_SB_DQ<18>")
	)
	(gr_poly
		(pts
			(xy 394.75918 -225.462592) (xy 394.75918 -225.272092) (xy 394.65758 -225.236024) (xy 394.60678 -225.236024)
			(xy 394.60678 -225.498914) (xy 394.65758 -225.498914)
		)
		(stroke
			(width 0)
			(type solid)
		)
		(fill yes)
		(layer "F.Cu")
		(net "M_E_CPU0_SB_DQ<18>")
	)
	(gr_poly
		(pts
			(xy 394.75918 -224.865692) (xy 394.75918 -224.675192) (xy 394.65758 -224.639124) (xy 394.60678 -224.639124)
			(xy 394.60678 -224.902014) (xy 394.65758 -224.902014)
		)
		(stroke
			(width 0)
			(type solid)
		)
		(fill yes)
		(layer "F.Cu")
		(net "M_E_CPU0_SB_DQ<18>")
	)
	(gr_poly
		(pts
			(xy 394.75918 -224.268792) (xy 394.75918 -224.078292) (xy 394.65758 -224.042224) (xy 394.60678 -224.042224)
			(xy 394.60678 -224.305114) (xy 394.65758 -224.305114)
		)
		(stroke
			(width 0)
			(type solid)
		)
		(fill yes)
		(layer "F.Cu")
		(net "M_E_CPU0_SB_DQ<18>")
	)
	(gr_poly
		(pts
			(xy 394.75918 -223.671892) (xy 394.75918 -223.481392) (xy 394.65758 -223.445324) (xy 394.60678 -223.445324)
			(xy 394.60678 -223.708214) (xy 394.65758 -223.708214)
		)
		(stroke
			(width 0)
			(type solid)
		)
		(fill yes)
		(layer "F.Cu")
		(net "M_E_CPU0_SB_DQ<18>")
	)
	(gr_poly
		(pts
			(xy 394.75918 -223.074992) (xy 394.75918 -222.884492) (xy 394.65758 -222.848424) (xy 394.60678 -222.848424)
			(xy 394.60678 -223.111314) (xy 394.65758 -223.111314)
		)
		(stroke
			(width 0)
			(type solid)
		)
		(fill yes)
		(layer "F.Cu")
		(net "M_E_CPU0_SB_DQ<18>")
	)
	(gr_poly
		(pts
			(xy 394.75918 -222.478092) (xy 394.75918 -222.287592) (xy 394.65758 -222.251524) (xy 394.60678 -222.251524)
			(xy 394.60678 -222.514414) (xy 394.65758 -222.514414)
		)
		(stroke
			(width 0)
			(type solid)
		)
		(fill yes)
		(layer "F.Cu")
		(net "M_E_CPU0_SB_DQ<18>")
	)
	(gr_poly
		(pts
			(xy 394.75918 -221.881192) (xy 394.75918 -221.690692) (xy 394.65758 -221.654624) (xy 394.60678 -221.654624)
			(xy 394.60678 -221.917514) (xy 394.65758 -221.917514)
		)
		(stroke
			(width 0)
			(type solid)
		)
		(fill yes)
		(layer "F.Cu")
		(net "M_E_CPU0_SB_DQ<18>")
	)
	(gr_poly
		(pts
			(xy 394.75918 -221.284292) (xy 394.75918 -221.093792) (xy 394.65758 -221.057724) (xy 394.60678 -221.057724)
			(xy 394.60678 -221.320614) (xy 394.65758 -221.320614)
		)
		(stroke
			(width 0)
			(type solid)
		)
		(fill yes)
		(layer "F.Cu")
		(net "M_E_CPU0_SB_DQ<18>")
	)
	(gr_poly
		(pts
			(xy 394.75918 -220.687392) (xy 394.75918 -220.496892) (xy 394.65758 -220.460824) (xy 394.60678 -220.460824)
			(xy 394.60678 -220.723714) (xy 394.65758 -220.723714)
		)
		(stroke
			(width 0)
			(type solid)
		)
		(fill yes)
		(layer "F.Cu")
		(net "M_E_CPU0_SB_DQ<18>")
	)
	(gr_poly
		(pts
			(xy 394.759434 -270.558514) (xy 394.805662 -270.460978) (xy 394.670788 -270.326358) (xy 394.573506 -270.372586)
			(xy 394.537438 -270.4084) (xy 394.723366 -270.594328)
		)
		(stroke
			(width 0)
			(type solid)
		)
		(fill yes)
		(layer "F.Cu")
		(net "M_E_CPU0_SA_DQ<29>")
	)
	(gr_poly
		(pts
			(xy 394.76426 -236.231684) (xy 394.718032 -236.134148) (xy 394.682218 -236.09808) (xy 394.49629 -236.284008)
			(xy 394.532104 -236.320076) (xy 394.62964 -236.366304)
		)
		(stroke
			(width 0)
			(type solid)
		)
		(fill yes)
		(layer "F.Cu")
		(net "M_E_CPU0_SB_CB<1>")
	)
	(gr_poly
		(pts
			(xy 394.76553 -274.45335) (xy 394.713968 -274.195794) (xy 394.664184 -274.2057) (xy 394.571728 -274.261072)
			(xy 394.609066 -274.447762) (xy 394.715746 -274.46351)
		)
		(stroke
			(width 0)
			(type solid)
		)
		(fill yes)
		(layer "F.Cu")
		(net "M_E_CPU0_SA_DQ<27>")
	)
	(gr_poly
		(pts
			(xy 394.773404 -237.08487) (xy 394.727176 -236.987588) (xy 394.691362 -236.95152) (xy 394.505434 -237.137448)
			(xy 394.541248 -237.173262) (xy 394.638784 -237.219744)
		)
		(stroke
			(width 0)
			(type solid)
		)
		(fill yes)
		(layer "F.Cu")
		(net "M_E_CPU0_SB_CB<0>")
	)
	(gr_poly
		(pts
			(xy 394.783056 -265.51001) (xy 394.829284 -265.412474) (xy 394.694664 -265.277854) (xy 394.597128 -265.324082)
			(xy 394.561314 -265.359896) (xy 394.747242 -265.545824)
		)
		(stroke
			(width 0)
			(type solid)
		)
		(fill yes)
		(layer "F.Cu")
		(net "M_E_CPU0_SA_CB<6>")
	)
	(gr_poly
		(pts
			(xy 394.792454 -264.65657) (xy 394.838682 -264.559034) (xy 394.703808 -264.424414) (xy 394.606526 -264.470642)
			(xy 394.570458 -264.506456) (xy 394.756386 -264.692384)
		)
		(stroke
			(width 0)
			(type solid)
		)
		(fill yes)
		(layer "F.Cu")
		(net "M_E_CPU0_SA_CB<7>")
	)
	(gr_poly
		(pts
			(xy 394.795756 -279.012904) (xy 394.888466 -278.957278) (xy 394.851128 -278.770588) (xy 394.744194 -278.755094)
			(xy 394.69441 -278.765) (xy 394.745972 -279.02281)
		)
		(stroke
			(width 0)
			(type solid)
		)
		(fill yes)
		(layer "F.Cu")
		(net "M_E_CPU0_SA_DQ<24>")
	)
	(gr_poly
		(pts
			(xy 394.804646 -279.315418) (xy 394.753084 -279.057608) (xy 394.7033 -279.067514) (xy 394.61059 -279.12314)
			(xy 394.647928 -279.30983) (xy 394.754862 -279.325324)
		)
		(stroke
			(width 0)
			(type solid)
		)
		(fill yes)
		(layer "F.Cu")
		(net "M_E_CPU0_SA_DQ<24>")
	)
	(gr_poly
		(pts
			(xy 394.80871 -275.966682) (xy 394.901166 -275.91131) (xy 394.863828 -275.724366) (xy 394.757148 -275.708872)
			(xy 394.707364 -275.718778) (xy 394.758926 -275.976588)
		)
		(stroke
			(width 0)
			(type solid)
		)
		(fill yes)
		(layer "F.Cu")
		(net "M_E_CPU0_SA_DQ<25>")
	)
	(gr_poly
		(pts
			(xy 394.8176 -276.269196) (xy 394.766038 -276.011386) (xy 394.716254 -276.021292) (xy 394.623544 -276.076918)
			(xy 394.660882 -276.263608) (xy 394.767816 -276.279102)
		)
		(stroke
			(width 0)
			(type solid)
		)
		(fill yes)
		(layer "F.Cu")
		(net "M_E_CPU0_SA_DQ<25>")
	)
	(gr_poly
		(pts
			(xy 394.840968 -229.920292) (xy 394.8049 -229.884478) (xy 394.707618 -229.83825) (xy 394.572744 -229.97287)
			(xy 394.619226 -230.070406) (xy 394.65504 -230.10622)
		)
		(stroke
			(width 0)
			(type solid)
		)
		(fill yes)
		(layer "F.Cu")
		(net "M_E_CPU0_SB_DQ<15>")
	)
	(gr_poly
		(pts
			(xy 394.850112 -230.773732) (xy 394.814298 -230.737664) (xy 394.716762 -230.691436) (xy 394.582142 -230.82631)
			(xy 394.62837 -230.923592) (xy 394.664184 -230.95966)
		)
		(stroke
			(width 0)
			(type solid)
		)
		(fill yes)
		(layer "F.Cu")
		(net "M_E_CPU0_SB_DQ<14>")
	)
	(gr_poly
		(pts
			(xy 394.86078 -277.782274) (xy 394.953236 -277.726902) (xy 394.915898 -277.540212) (xy 394.809218 -277.524718)
			(xy 394.759434 -277.534624) (xy 394.810996 -277.792434)
		)
		(stroke
			(width 0)
			(type solid)
		)
		(fill yes)
		(layer "F.Cu")
		(net "M_E_CPU0_SA_DQ<26>")
	)
	(gr_poly
		(pts
			(xy 394.865098 -269.18666) (xy 394.900912 -269.150592) (xy 394.714984 -268.964664) (xy 394.67917 -269.000732)
			(xy 394.632942 -269.098014) (xy 394.767562 -269.232888)
		)
		(stroke
			(width 0)
			(type solid)
		)
		(fill yes)
		(layer "F.Cu")
		(net "M_E_CPU0_SA_CB<2>")
	)
	(gr_poly
		(pts
			(xy 394.869416 -278.085042) (xy 394.817854 -277.827232) (xy 394.76807 -277.837138) (xy 394.675614 -277.89251)
			(xy 394.712952 -278.079454) (xy 394.819632 -278.094948)
		)
		(stroke
			(width 0)
			(type solid)
		)
		(fill yes)
		(layer "F.Cu")
		(net "M_E_CPU0_SA_DQ<26>")
	)
	(gr_poly
		(pts
			(xy 394.873988 -274.736052) (xy 394.966444 -274.68068) (xy 394.929106 -274.49399) (xy 394.822426 -274.478242)
			(xy 394.772388 -274.488402) (xy 394.82395 -274.746212)
		)
		(stroke
			(width 0)
			(type solid)
		)
		(fill yes)
		(layer "F.Cu")
		(net "M_E_CPU0_SA_DQ<27>")
	)
	(gr_poly
		(pts
			(xy 394.874242 -268.33322) (xy 394.91031 -268.297406) (xy 394.724382 -268.111478) (xy 394.688314 -268.147292)
			(xy 394.642086 -268.244828) (xy 394.77696 -268.379448)
		)
		(stroke
			(width 0)
			(type solid)
		)
		(fill yes)
		(layer "F.Cu")
		(net "M_E_CPU0_SA_CB<3>")
	)
	(gr_poly
		(pts
			(xy 394.875004 -233.336592) (xy 394.83919 -233.300778) (xy 394.741654 -233.25455) (xy 394.607034 -233.38917)
			(xy 394.653262 -233.486452) (xy 394.689076 -233.52252)
		)
		(stroke
			(width 0)
			(type solid)
		)
		(fill yes)
		(layer "F.Cu")
		(net "M_E_CPU0_SB_DQ<11>")
	)
	(gr_poly
		(pts
			(xy 394.882624 -275.03882) (xy 394.831062 -274.78101) (xy 394.781278 -274.790916) (xy 394.688822 -274.846288)
			(xy 394.72616 -275.033232) (xy 394.83284 -275.048726)
		)
		(stroke
			(width 0)
			(type solid)
		)
		(fill yes)
		(layer "F.Cu")
		(net "M_E_CPU0_SA_DQ<27>")
	)
	(gr_poly
		(pts
			(xy 394.88491 -234.190794) (xy 394.849096 -234.154726) (xy 394.75156 -234.108498) (xy 394.61694 -234.243372)
			(xy 394.663168 -234.340654) (xy 394.698982 -234.376722)
		)
		(stroke
			(width 0)
			(type solid)
		)
		(fill yes)
		(layer "F.Cu")
		(net "M_E_CPU0_SB_DQ<10>")
	)
	(gr_poly
		(pts
			(xy 394.889228 -271.69491) (xy 394.925042 -271.658842) (xy 394.739114 -271.472914) (xy 394.7033 -271.508982)
			(xy 394.657072 -271.606518) (xy 394.791692 -271.741138)
		)
		(stroke
			(width 0)
			(type solid)
		)
		(fill yes)
		(layer "F.Cu")
		(net "M_E_CPU0_SA_DQ<28>")
	)
	(gr_poly
		(pts
			(xy 394.898626 -270.84147) (xy 394.93444 -270.805402) (xy 394.748512 -270.619474) (xy 394.712698 -270.655542)
			(xy 394.66647 -270.752824) (xy 394.80109 -270.887698)
		)
		(stroke
			(width 0)
			(type solid)
		)
		(fill yes)
		(layer "F.Cu")
		(net "M_E_CPU0_SA_DQ<29>")
	)
	(gr_poly
		(pts
			(xy 394.902436 -236.740446) (xy 394.866368 -236.704632) (xy 394.769086 -236.658404) (xy 394.634212 -236.793024)
			(xy 394.68044 -236.89056) (xy 394.716508 -236.926374)
		)
		(stroke
			(width 0)
			(type solid)
		)
		(fill yes)
		(layer "F.Cu")
		(net "M_E_CPU0_SB_CB<0>")
	)
	(gr_poly
		(pts
			(xy 394.91158 -228.518974) (xy 394.86078 -228.518974) (xy 394.75918 -228.555042) (xy 394.75918 -228.745542)
			(xy 394.86078 -228.781864) (xy 394.91158 -228.781864)
		)
		(stroke
			(width 0)
			(type solid)
		)
		(fill yes)
		(layer "F.Cu")
		(net "M_E_CPU0_SB_DQ<16>")
	)
	(gr_poly
		(pts
			(xy 394.91158 -227.922074) (xy 394.86078 -227.922074) (xy 394.75918 -227.958142) (xy 394.75918 -228.148642)
			(xy 394.86078 -228.184964) (xy 394.91158 -228.184964)
		)
		(stroke
			(width 0)
			(type solid)
		)
		(fill yes)
		(layer "F.Cu")
		(net "M_E_CPU0_SB_DQ<16>")
	)
	(gr_poly
		(pts
			(xy 394.91158 -227.325174) (xy 394.86078 -227.325174) (xy 394.75918 -227.361242) (xy 394.75918 -227.551742)
			(xy 394.86078 -227.588064) (xy 394.91158 -227.588064)
		)
		(stroke
			(width 0)
			(type solid)
		)
		(fill yes)
		(layer "F.Cu")
		(net "M_E_CPU0_SB_DQ<16>")
	)
	(gr_poly
		(pts
			(xy 394.91158 -226.728274) (xy 394.86078 -226.728274) (xy 394.75918 -226.764342) (xy 394.75918 -226.954842)
			(xy 394.86078 -226.991164) (xy 394.91158 -226.991164)
		)
		(stroke
			(width 0)
			(type solid)
		)
		(fill yes)
		(layer "F.Cu")
		(net "M_E_CPU0_SB_DQ<16>")
	)
	(gr_poly
		(pts
			(xy 394.91158 -226.131374) (xy 394.86078 -226.131374) (xy 394.75918 -226.167442) (xy 394.75918 -226.357942)
			(xy 394.86078 -226.394264) (xy 394.91158 -226.394264)
		)
		(stroke
			(width 0)
			(type solid)
		)
		(fill yes)
		(layer "F.Cu")
		(net "M_E_CPU0_SB_DQ<16>")
	)
	(gr_poly
		(pts
			(xy 394.91158 -225.534474) (xy 394.86078 -225.534474) (xy 394.75918 -225.570542) (xy 394.75918 -225.761042)
			(xy 394.86078 -225.797364) (xy 394.91158 -225.797364)
		)
		(stroke
			(width 0)
			(type solid)
		)
		(fill yes)
		(layer "F.Cu")
		(net "M_E_CPU0_SB_DQ<16>")
	)
	(gr_poly
		(pts
			(xy 394.91158 -224.937574) (xy 394.86078 -224.937574) (xy 394.75918 -224.973642) (xy 394.75918 -225.164142)
			(xy 394.86078 -225.200464) (xy 394.91158 -225.200464)
		)
		(stroke
			(width 0)
			(type solid)
		)
		(fill yes)
		(layer "F.Cu")
		(net "M_E_CPU0_SB_DQ<16>")
	)
	(gr_poly
		(pts
			(xy 394.91158 -224.340674) (xy 394.86078 -224.340674) (xy 394.75918 -224.376742) (xy 394.75918 -224.567242)
			(xy 394.86078 -224.603564) (xy 394.91158 -224.603564)
		)
		(stroke
			(width 0)
			(type solid)
		)
		(fill yes)
		(layer "F.Cu")
		(net "M_E_CPU0_SB_DQ<16>")
	)
	(gr_poly
		(pts
			(xy 394.91158 -223.743774) (xy 394.86078 -223.743774) (xy 394.75918 -223.779842) (xy 394.75918 -223.970342)
			(xy 394.86078 -224.006664) (xy 394.91158 -224.006664)
		)
		(stroke
			(width 0)
			(type solid)
		)
		(fill yes)
		(layer "F.Cu")
		(net "M_E_CPU0_SB_DQ<16>")
	)
	(gr_poly
		(pts
			(xy 394.91158 -223.146874) (xy 394.86078 -223.146874) (xy 394.75918 -223.182942) (xy 394.75918 -223.373442)
			(xy 394.86078 -223.409764) (xy 394.91158 -223.409764)
		)
		(stroke
			(width 0)
			(type solid)
		)
		(fill yes)
		(layer "F.Cu")
		(net "M_E_CPU0_SB_DQ<16>")
	)
	(gr_poly
		(pts
			(xy 394.91158 -222.549974) (xy 394.86078 -222.549974) (xy 394.75918 -222.586042) (xy 394.75918 -222.776542)
			(xy 394.86078 -222.812864) (xy 394.91158 -222.812864)
		)
		(stroke
			(width 0)
			(type solid)
		)
		(fill yes)
		(layer "F.Cu")
		(net "M_E_CPU0_SB_DQ<16>")
	)
	(gr_poly
		(pts
			(xy 394.91158 -221.953074) (xy 394.86078 -221.953074) (xy 394.75918 -221.989142) (xy 394.75918 -222.179642)
			(xy 394.86078 -222.215964) (xy 394.91158 -222.215964)
		)
		(stroke
			(width 0)
			(type solid)
		)
		(fill yes)
		(layer "F.Cu")
		(net "M_E_CPU0_SB_DQ<16>")
	)
	(gr_poly
		(pts
			(xy 394.91158 -221.356174) (xy 394.86078 -221.356174) (xy 394.75918 -221.392242) (xy 394.75918 -221.582742)
			(xy 394.86078 -221.619064) (xy 394.91158 -221.619064)
		)
		(stroke
			(width 0)
			(type solid)
		)
		(fill yes)
		(layer "F.Cu")
		(net "M_E_CPU0_SB_DQ<16>")
	)
	(gr_poly
		(pts
			(xy 394.91285 -279.59812) (xy 395.00556 -279.542748) (xy 394.968222 -279.355804) (xy 394.861288 -279.34031)
			(xy 394.811504 -279.350216) (xy 394.863066 -279.608026)
		)
		(stroke
			(width 0)
			(type solid)
		)
		(fill yes)
		(layer "F.Cu")
		(net "M_E_CPU0_SA_DQ<24>")
	)
	(gr_poly
		(pts
			(xy 394.92174 -279.900634) (xy 394.870178 -279.643078) (xy 394.820394 -279.652984) (xy 394.727684 -279.708356)
			(xy 394.765022 -279.895046) (xy 394.871956 -279.910794)
		)
		(stroke
			(width 0)
			(type solid)
		)
		(fill yes)
		(layer "F.Cu")
		(net "M_E_CPU0_SA_DQ<24>")
	)
	(gr_poly
		(pts
			(xy 394.922248 -265.792712) (xy 394.958316 -265.756898) (xy 394.772388 -265.57097) (xy 394.736574 -265.606784)
			(xy 394.690092 -265.70432) (xy 394.824966 -265.83894)
		)
		(stroke
			(width 0)
			(type solid)
		)
		(fill yes)
		(layer "F.Cu")
		(net "M_E_CPU0_SA_CB<6>")
	)
	(gr_poly
		(pts
			(xy 394.925804 -276.551898) (xy 395.018514 -276.496526) (xy 394.981176 -276.309582) (xy 394.874242 -276.294088)
			(xy 394.824458 -276.303994) (xy 394.87602 -276.561804)
		)
		(stroke
			(width 0)
			(type solid)
		)
		(fill yes)
		(layer "F.Cu")
		(net "M_E_CPU0_SA_DQ<25>")
	)
	(gr_poly
		(pts
			(xy 394.927582 -230.480362) (xy 394.881354 -230.382826) (xy 394.84554 -230.347012) (xy 394.659612 -230.53294)
			(xy 394.695426 -230.568754) (xy 394.792962 -230.614982)
		)
		(stroke
			(width 0)
			(type solid)
		)
		(fill yes)
		(layer "F.Cu")
		(net "M_E_CPU0_SB_DQ<13>")
	)
	(gr_poly
		(pts
			(xy 394.931646 -264.939272) (xy 394.96746 -264.903458) (xy 394.781532 -264.71753) (xy 394.745718 -264.753598)
			(xy 394.69949 -264.85088) (xy 394.83411 -264.985754)
		)
		(stroke
			(width 0)
			(type solid)
		)
		(fill yes)
		(layer "F.Cu")
		(net "M_E_CPU0_SA_CB<7>")
	)
	(gr_poly
		(pts
			(xy 394.932408 -269.541498) (xy 394.978636 -269.443962) (xy 394.843762 -269.309342) (xy 394.74648 -269.35557)
			(xy 394.710412 -269.391384) (xy 394.89634 -269.577312)
		)
		(stroke
			(width 0)
			(type solid)
		)
		(fill yes)
		(layer "F.Cu")
		(net "M_E_CPU0_SA_CB<0>")
	)
	(gr_poly
		(pts
			(xy 394.934694 -276.854412) (xy 394.883132 -276.596856) (xy 394.833348 -276.606762) (xy 394.740638 -276.662134)
			(xy 394.77823 -276.848824) (xy 394.88491 -276.864572)
		)
		(stroke
			(width 0)
			(type solid)
		)
		(fill yes)
		(layer "F.Cu")
		(net "M_E_CPU0_SA_DQ<25>")
	)
	(gr_poly
		(pts
			(xy 394.93698 -231.333802) (xy 394.890752 -231.236266) (xy 394.854684 -231.200452) (xy 394.668756 -231.38638)
			(xy 394.704824 -231.422194) (xy 394.802106 -231.468422)
		)
		(stroke
			(width 0)
			(type solid)
		)
		(fill yes)
		(layer "F.Cu")
		(net "M_E_CPU0_SB_DQ<12>")
	)
	(gr_poly
		(pts
			(xy 394.941552 -268.688058) (xy 394.98778 -268.590522) (xy 394.85316 -268.455902) (xy 394.755624 -268.50213)
			(xy 394.71981 -268.538198) (xy 394.905484 -268.723872)
		)
		(stroke
			(width 0)
			(type solid)
		)
		(fill yes)
		(layer "F.Cu")
		(net "M_E_CPU0_SA_CB<1>")
	)
	(gr_poly
		(pts
			(xy 394.962126 -233.896916) (xy 394.915898 -233.799634) (xy 394.880084 -233.763566) (xy 394.694156 -233.949494)
			(xy 394.72997 -233.985562) (xy 394.827506 -234.03179)
		)
		(stroke
			(width 0)
			(type solid)
		)
		(fill yes)
		(layer "F.Cu")
		(net "M_E_CPU0_SB_DQ<9>")
	)
	(gr_poly
		(pts
			(xy 394.965682 -271.196308) (xy 395.01191 -271.098772) (xy 394.87729 -270.964152) (xy 394.779754 -271.01038)
			(xy 394.74394 -271.046448) (xy 394.929614 -271.232122)
		)
		(stroke
			(width 0)
			(type solid)
		)
		(fill yes)
		(layer "F.Cu")
		(net "M_E_CPU0_SA_DQ<30>")
	)
	(gr_poly
		(pts
			(xy 394.971778 -234.750864) (xy 394.92555 -234.653328) (xy 394.889736 -234.617514) (xy 394.703808 -234.803442)
			(xy 394.739622 -234.839256) (xy 394.837158 -234.885484)
		)
		(stroke
			(width 0)
			(type solid)
		)
		(fill yes)
		(layer "F.Cu")
		(net "M_E_CPU0_SB_DQ<8>")
	)
	(gr_poly
		(pts
			(xy 394.97508 -270.342614) (xy 395.021308 -270.245332) (xy 394.886688 -270.110458) (xy 394.789152 -270.15694)
			(xy 394.753338 -270.192754) (xy 394.939266 -270.378682)
		)
		(stroke
			(width 0)
			(type solid)
		)
		(fill yes)
		(layer "F.Cu")
		(net "M_E_CPU0_SA_DQ<31>")
	)
	(gr_poly
		(pts
			(xy 394.977874 -278.367744) (xy 395.07033 -278.312372) (xy 395.032992 -278.125428) (xy 394.926312 -278.109934)
			(xy 394.876528 -278.11984) (xy 394.92809 -278.37765)
		)
		(stroke
			(width 0)
			(type solid)
		)
		(fill yes)
		(layer "F.Cu")
		(net "M_E_CPU0_SA_DQ<26>")
	)
	(gr_poly
		(pts
			(xy 394.98016 -236.447076) (xy 394.933932 -236.34954) (xy 394.897864 -236.313726) (xy 394.711936 -236.499654)
			(xy 394.748004 -236.535468) (xy 394.845286 -236.581696)
		)
		(stroke
			(width 0)
			(type solid)
		)
		(fill yes)
		(layer "F.Cu")
		(net "M_E_CPU0_SB_CB<2>")
	)
	(gr_poly
		(pts
			(xy 394.98651 -278.670258) (xy 394.934948 -278.412448) (xy 394.885164 -278.422608) (xy 394.792708 -278.47798)
			(xy 394.830046 -278.66467) (xy 394.936726 -278.680164)
		)
		(stroke
			(width 0)
			(type solid)
		)
		(fill yes)
		(layer "F.Cu")
		(net "M_E_CPU0_SA_DQ<26>")
	)
	(gr_poly
		(pts
			(xy 394.989558 -266.14755) (xy 395.035786 -266.050268) (xy 394.901166 -265.915394) (xy 394.80363 -265.961622)
			(xy 394.767816 -265.99769) (xy 394.953744 -266.183618)
		)
		(stroke
			(width 0)
			(type solid)
		)
		(fill yes)
		(layer "F.Cu")
		(net "M_E_CPU0_SA_CB<4>")
	)
	(gr_poly
		(pts
			(xy 394.991082 -275.321522) (xy 395.083538 -275.26615) (xy 395.0462 -275.079206) (xy 394.93952 -275.063712)
			(xy 394.889482 -275.073618) (xy 394.941044 -275.331428)
		)
		(stroke
			(width 0)
			(type solid)
		)
		(fill yes)
		(layer "F.Cu")
		(net "M_E_CPU0_SA_DQ<27>")
	)
	(gr_poly
		(pts
			(xy 394.998702 -265.294364) (xy 395.04493 -265.196828) (xy 394.91031 -265.062208) (xy 394.812774 -265.108436)
			(xy 394.77696 -265.14425) (xy 394.962888 -265.330178)
		)
		(stroke
			(width 0)
			(type solid)
		)
		(fill yes)
		(layer "F.Cu")
		(net "M_E_CPU0_SA_CB<5>")
	)
	(gr_poly
		(pts
			(xy 394.999718 -275.624036) (xy 394.948156 -275.366226) (xy 394.898372 -275.376132) (xy 394.805916 -275.431758)
			(xy 394.843254 -275.618448) (xy 394.949934 -275.633942)
		)
		(stroke
			(width 0)
			(type solid)
		)
		(fill yes)
		(layer "F.Cu")
		(net "M_E_CPU0_SA_DQ<27>")
	)
	(gr_poly
		(pts
			(xy 395.029944 -280.183336) (xy 395.122654 -280.127964) (xy 395.085062 -279.941274) (xy 394.978382 -279.925526)
			(xy 394.928598 -279.935686) (xy 394.98016 -280.193496)
		)
		(stroke
			(width 0)
			(type solid)
		)
		(fill yes)
		(layer "F.Cu")
		(net "M_E_CPU0_SA_DQ<24>")
	)
	(gr_poly
		(pts
			(xy 395.038834 -280.486104) (xy 394.987272 -280.228294) (xy 394.937234 -280.2382) (xy 394.844778 -280.293572)
			(xy 394.882116 -280.480516) (xy 394.98905 -280.49601)
		)
		(stroke
			(width 0)
			(type solid)
		)
		(fill yes)
		(layer "F.Cu")
		(net "M_E_CPU0_SA_DQ<24>")
	)
	(gr_poly
		(pts
			(xy 395.043152 -277.137114) (xy 395.135608 -277.081742) (xy 395.09827 -276.895052) (xy 394.991336 -276.879304)
			(xy 394.941552 -276.889464) (xy 394.993114 -277.147274)
		)
		(stroke
			(width 0)
			(type solid)
		)
		(fill yes)
		(layer "F.Cu")
		(net "M_E_CPU0_SA_DQ<25>")
	)
	(gr_poly
		(pts
			(xy 395.051788 -277.439882) (xy 395.000226 -277.182072) (xy 394.950442 -277.191978) (xy 394.857986 -277.24735)
			(xy 394.895324 -277.434294) (xy 395.002004 -277.449788)
		)
		(stroke
			(width 0)
			(type solid)
		)
		(fill yes)
		(layer "F.Cu")
		(net "M_E_CPU0_SA_DQ<25>")
	)
	(gr_poly
		(pts
			(xy 395.056614 -230.135938) (xy 395.020546 -230.100124) (xy 394.923264 -230.053896) (xy 394.78839 -230.188516)
			(xy 394.834872 -230.286052) (xy 394.870686 -230.321866)
		)
		(stroke
			(width 0)
			(type solid)
		)
		(fill yes)
		(layer "F.Cu")
		(net "M_E_CPU0_SB_DQ<13>")
	)
	(gr_poly
		(pts
			(xy 395.06398 -228.447092) (xy 395.06398 -228.256592) (xy 394.96238 -228.220524) (xy 394.91158 -228.220524)
			(xy 394.91158 -228.483414) (xy 394.96238 -228.483414)
		)
		(stroke
			(width 0)
			(type solid)
		)
		(fill yes)
		(layer "F.Cu")
		(net "M_E_CPU0_SB_DQ<16>")
	)
	(gr_poly
		(pts
			(xy 395.06398 -227.850192) (xy 395.06398 -227.659692) (xy 394.96238 -227.623624) (xy 394.91158 -227.623624)
			(xy 394.91158 -227.886514) (xy 394.96238 -227.886514)
		)
		(stroke
			(width 0)
			(type solid)
		)
		(fill yes)
		(layer "F.Cu")
		(net "M_E_CPU0_SB_DQ<16>")
	)
	(gr_poly
		(pts
			(xy 395.06398 -227.253292) (xy 395.06398 -227.062792) (xy 394.96238 -227.026724) (xy 394.91158 -227.026724)
			(xy 394.91158 -227.289614) (xy 394.96238 -227.289614)
		)
		(stroke
			(width 0)
			(type solid)
		)
		(fill yes)
		(layer "F.Cu")
		(net "M_E_CPU0_SB_DQ<16>")
	)
	(gr_poly
		(pts
			(xy 395.06398 -226.656392) (xy 395.06398 -226.465892) (xy 394.96238 -226.429824) (xy 394.91158 -226.429824)
			(xy 394.91158 -226.692714) (xy 394.96238 -226.692714)
		)
		(stroke
			(width 0)
			(type solid)
		)
		(fill yes)
		(layer "F.Cu")
		(net "M_E_CPU0_SB_DQ<16>")
	)
	(gr_poly
		(pts
			(xy 395.06398 -226.059492) (xy 395.06398 -225.868992) (xy 394.96238 -225.832924) (xy 394.91158 -225.832924)
			(xy 394.91158 -226.095814) (xy 394.96238 -226.095814)
		)
		(stroke
			(width 0)
			(type solid)
		)
		(fill yes)
		(layer "F.Cu")
		(net "M_E_CPU0_SB_DQ<16>")
	)
	(gr_poly
		(pts
			(xy 395.06398 -225.462592) (xy 395.06398 -225.272092) (xy 394.96238 -225.236024) (xy 394.91158 -225.236024)
			(xy 394.91158 -225.498914) (xy 394.96238 -225.498914)
		)
		(stroke
			(width 0)
			(type solid)
		)
		(fill yes)
		(layer "F.Cu")
		(net "M_E_CPU0_SB_DQ<16>")
	)
	(gr_poly
		(pts
			(xy 395.06398 -224.865692) (xy 395.06398 -224.675192) (xy 394.96238 -224.639124) (xy 394.91158 -224.639124)
			(xy 394.91158 -224.902014) (xy 394.96238 -224.902014)
		)
		(stroke
			(width 0)
			(type solid)
		)
		(fill yes)
		(layer "F.Cu")
		(net "M_E_CPU0_SB_DQ<16>")
	)
	(gr_poly
		(pts
			(xy 395.06398 -224.268792) (xy 395.06398 -224.078292) (xy 394.96238 -224.042224) (xy 394.91158 -224.042224)
			(xy 394.91158 -224.305114) (xy 394.96238 -224.305114)
		)
		(stroke
			(width 0)
			(type solid)
		)
		(fill yes)
		(layer "F.Cu")
		(net "M_E_CPU0_SB_DQ<16>")
	)
	(gr_poly
		(pts
			(xy 395.06398 -223.671892) (xy 395.06398 -223.481392) (xy 394.96238 -223.445324) (xy 394.91158 -223.445324)
			(xy 394.91158 -223.708214) (xy 394.96238 -223.708214)
		)
		(stroke
			(width 0)
			(type solid)
		)
		(fill yes)
		(layer "F.Cu")
		(net "M_E_CPU0_SB_DQ<16>")
	)
	(gr_poly
		(pts
			(xy 395.06398 -223.074992) (xy 395.06398 -222.884492) (xy 394.96238 -222.848424) (xy 394.91158 -222.848424)
			(xy 394.91158 -223.111314) (xy 394.96238 -223.111314)
		)
		(stroke
			(width 0)
			(type solid)
		)
		(fill yes)
		(layer "F.Cu")
		(net "M_E_CPU0_SB_DQ<16>")
	)
	(gr_poly
		(pts
			(xy 395.06398 -222.478092) (xy 395.06398 -222.287592) (xy 394.96238 -222.251524) (xy 394.91158 -222.251524)
			(xy 394.91158 -222.514414) (xy 394.96238 -222.514414)
		)
		(stroke
			(width 0)
			(type solid)
		)
		(fill yes)
		(layer "F.Cu")
		(net "M_E_CPU0_SB_DQ<16>")
	)
	(gr_poly
		(pts
			(xy 395.06398 -221.881192) (xy 395.06398 -221.690692) (xy 394.96238 -221.654624) (xy 394.91158 -221.654624)
			(xy 394.91158 -221.917514) (xy 394.96238 -221.917514)
		)
		(stroke
			(width 0)
			(type solid)
		)
		(fill yes)
		(layer "F.Cu")
		(net "M_E_CPU0_SB_DQ<16>")
	)
	(gr_poly
		(pts
			(xy 395.065758 -230.989378) (xy 395.029944 -230.95331) (xy 394.932408 -230.907082) (xy 394.797788 -231.041956)
			(xy 394.844016 -231.139238) (xy 394.87983 -231.175306)
		)
		(stroke
			(width 0)
			(type solid)
		)
		(fill yes)
		(layer "F.Cu")
		(net "M_E_CPU0_SB_DQ<12>")
	)
	(gr_poly
		(pts
			(xy 395.0716 -269.8242) (xy 395.107414 -269.788386) (xy 394.921486 -269.602458) (xy 394.885672 -269.638272)
			(xy 394.839444 -269.735808) (xy 394.974064 -269.870428)
		)
		(stroke
			(width 0)
			(type solid)
		)
		(fill yes)
		(layer "F.Cu")
		(net "M_E_CPU0_SA_CB<0>")
	)
	(gr_poly
		(pts
			(xy 395.080744 -268.971014) (xy 395.116558 -268.934946) (xy 394.93063 -268.749018) (xy 394.894816 -268.785086)
			(xy 394.848588 -268.882368) (xy 394.983208 -269.017242)
		)
		(stroke
			(width 0)
			(type solid)
		)
		(fill yes)
		(layer "F.Cu")
		(net "M_E_CPU0_SA_CB<1>")
	)
	(gr_poly
		(pts
			(xy 395.090904 -233.552746) (xy 395.05509 -233.516678) (xy 394.957554 -233.47045) (xy 394.822934 -233.60507)
			(xy 394.869162 -233.702606) (xy 394.90523 -233.73842)
		)
		(stroke
			(width 0)
			(type solid)
		)
		(fill yes)
		(layer "F.Cu")
		(net "M_E_CPU0_SB_DQ<9>")
	)
	(gr_poly
		(pts
			(xy 395.094968 -278.95296) (xy 395.187424 -278.897588) (xy 395.150086 -278.710644) (xy 395.043406 -278.69515)
			(xy 394.993622 -278.705056) (xy 395.045184 -278.962866)
		)
		(stroke
			(width 0)
			(type solid)
		)
		(fill yes)
		(layer "F.Cu")
		(net "M_E_CPU0_SA_DQ<26>")
	)
	(gr_poly
		(pts
			(xy 395.10081 -234.40644) (xy 395.064742 -234.370626) (xy 394.96746 -234.324398) (xy 394.832586 -234.459018)
			(xy 394.879068 -234.556554) (xy 394.914882 -234.592368)
		)
		(stroke
			(width 0)
			(type solid)
		)
		(fill yes)
		(layer "F.Cu")
		(net "M_E_CPU0_SB_DQ<8>")
	)
	(gr_poly
		(pts
			(xy 395.103604 -279.255728) (xy 395.052042 -278.997918) (xy 395.002258 -279.007824) (xy 394.909802 -279.063196)
			(xy 394.94714 -279.25014) (xy 395.05382 -279.265634)
		)
		(stroke
			(width 0)
			(type solid)
		)
		(fill yes)
		(layer "F.Cu")
		(net "M_E_CPU0_SA_DQ<26>")
	)
	(gr_poly
		(pts
			(xy 395.104874 -271.479264) (xy 395.140688 -271.443196) (xy 394.95476 -271.257268) (xy 394.918946 -271.293336)
			(xy 394.872718 -271.390872) (xy 395.007338 -271.525492)
		)
		(stroke
			(width 0)
			(type solid)
		)
		(fill yes)
		(layer "F.Cu")
		(net "M_E_CPU0_SA_DQ<30>")
	)
	(gr_poly
		(pts
			(xy 395.108176 -275.906738) (xy 395.200632 -275.851366) (xy 395.163294 -275.664422) (xy 395.056614 -275.648928)
			(xy 395.006576 -275.658834) (xy 395.058138 -275.916644)
		)
		(stroke
			(width 0)
			(type solid)
		)
		(fill yes)
		(layer "F.Cu")
		(net "M_E_CPU0_SA_DQ<27>")
	)
	(gr_poly
		(pts
			(xy 395.114272 -270.62557) (xy 395.15034 -270.589756) (xy 394.964412 -270.403828) (xy 394.928344 -270.439642)
			(xy 394.882116 -270.537178) (xy 395.01699 -270.671798)
		)
		(stroke
			(width 0)
			(type solid)
		)
		(fill yes)
		(layer "F.Cu")
		(net "M_E_CPU0_SA_DQ<31>")
	)
	(gr_poly
		(pts
			(xy 395.116812 -276.209252) (xy 395.06525 -275.951696) (xy 395.015466 -275.961602) (xy 394.92301 -276.016974)
			(xy 394.960348 -276.203664) (xy 395.067028 -276.219412)
		)
		(stroke
			(width 0)
			(type solid)
		)
		(fill yes)
		(layer "F.Cu")
		(net "M_E_CPU0_SA_DQ<27>")
	)
	(gr_poly
		(pts
			(xy 395.12875 -266.430506) (xy 395.164564 -266.394438) (xy 394.97889 -266.208764) (xy 394.942822 -266.244578)
			(xy 394.896594 -266.342114) (xy 395.031214 -266.476734)
		)
		(stroke
			(width 0)
			(type solid)
		)
		(fill yes)
		(layer "F.Cu")
		(net "M_E_CPU0_SA_CB<4>")
	)
	(gr_poly
		(pts
			(xy 395.134084 -229.842568) (xy 395.087856 -229.745286) (xy 395.052042 -229.709218) (xy 394.866114 -229.895146)
			(xy 394.901928 -229.931214) (xy 394.999464 -229.977442)
		)
		(stroke
			(width 0)
			(type solid)
		)
		(fill yes)
		(layer "F.Cu")
		(net "M_E_CPU0_SB_DQ<15>")
	)
	(gr_poly
		(pts
			(xy 395.137894 -265.577066) (xy 395.173962 -265.541252) (xy 394.988034 -265.355324) (xy 394.95222 -265.391138)
			(xy 394.905738 -265.488674) (xy 395.040612 -265.623294)
		)
		(stroke
			(width 0)
			(type solid)
		)
		(fill yes)
		(layer "F.Cu")
		(net "M_E_CPU0_SA_CB<5>")
	)
	(gr_poly
		(pts
			(xy 395.143228 -230.696008) (xy 395.097 -230.598472) (xy 395.061186 -230.562658) (xy 394.875258 -230.748586)
			(xy 394.911072 -230.7844) (xy 395.008608 -230.830628)
		)
		(stroke
			(width 0)
			(type solid)
		)
		(fill yes)
		(layer "F.Cu")
		(net "M_E_CPU0_SB_DQ<14>")
	)
	(gr_poly
		(pts
			(xy 395.147038 -280.768806) (xy 395.239494 -280.713434) (xy 395.202156 -280.52649) (xy 395.095476 -280.510996)
			(xy 395.045692 -280.520902) (xy 395.097254 -280.778712)
		)
		(stroke
			(width 0)
			(type solid)
		)
		(fill yes)
		(layer "F.Cu")
		(net "M_E_CPU0_SA_DQ<24>")
	)
	(gr_poly
		(pts
			(xy 395.148054 -269.325852) (xy 395.194282 -269.228316) (xy 395.059408 -269.093696) (xy 394.962126 -269.139924)
			(xy 394.926058 -269.175738) (xy 395.111986 -269.361666)
		)
		(stroke
			(width 0)
			(type solid)
		)
		(fill yes)
		(layer "F.Cu")
		(net "M_E_CPU0_SA_CB<2>")
	)
	(gr_poly
		(pts
			(xy 395.155928 -281.07132) (xy 395.104366 -280.81351) (xy 395.054328 -280.823416) (xy 394.961872 -280.879042)
			(xy 394.99921 -281.065732) (xy 395.10589 -281.081226)
		)
		(stroke
			(width 0)
			(type solid)
		)
		(fill yes)
		(layer "F.Cu")
		(net "M_E_CPU0_SA_DQ<24>")
	)
	(gr_poly
		(pts
			(xy 395.157198 -268.472412) (xy 395.203426 -268.374876) (xy 395.068806 -268.240256) (xy 394.97127 -268.286484)
			(xy 394.935456 -268.322552) (xy 395.12113 -268.508226)
		)
		(stroke
			(width 0)
			(type solid)
		)
		(fill yes)
		(layer "F.Cu")
		(net "M_E_CPU0_SA_CB<3>")
	)
	(gr_poly
		(pts
			(xy 395.160246 -277.722584) (xy 395.252702 -277.666958) (xy 395.215364 -277.480268) (xy 395.108684 -277.464774)
			(xy 395.0589 -277.47468) (xy 395.110462 -277.73249)
		)
		(stroke
			(width 0)
			(type solid)
		)
		(fill yes)
		(layer "F.Cu")
		(net "M_E_CPU0_SA_DQ<25>")
	)
	(gr_poly
		(pts
			(xy 395.16812 -233.258868) (xy 395.121892 -233.161586) (xy 395.086078 -233.125518) (xy 394.90015 -233.311446)
			(xy 394.935964 -233.34726) (xy 395.0335 -233.393742)
		)
		(stroke
			(width 0)
			(type solid)
		)
		(fill yes)
		(layer "F.Cu")
		(net "M_E_CPU0_SB_DQ<11>")
	)
	(gr_poly
		(pts
			(xy 395.168882 -278.025098) (xy 395.11732 -277.767288) (xy 395.067536 -277.777194) (xy 394.97508 -277.83282)
			(xy 395.012418 -278.01951) (xy 395.119098 -278.035004)
		)
		(stroke
			(width 0)
			(type solid)
		)
		(fill yes)
		(layer "F.Cu")
		(net "M_E_CPU0_SA_DQ<25>")
	)
	(gr_poly
		(pts
			(xy 395.172184 -271.834102) (xy 395.218412 -271.736566) (xy 395.083538 -271.601946) (xy 394.986256 -271.648174)
			(xy 394.950188 -271.683988) (xy 395.136116 -271.869916)
		)
		(stroke
			(width 0)
			(type solid)
		)
		(fill yes)
		(layer "F.Cu")
		(net "M_E_CPU0_SA_DQ<28>")
	)
	(gr_poly
		(pts
			(xy 395.17828 -234.11307) (xy 395.132052 -234.015534) (xy 395.095984 -233.97972) (xy 394.910056 -234.165648)
			(xy 394.946124 -234.201462) (xy 395.043406 -234.24769)
		)
		(stroke
			(width 0)
			(type solid)
		)
		(fill yes)
		(layer "F.Cu")
		(net "M_E_CPU0_SB_DQ<10>")
	)
	(gr_poly
		(pts
			(xy 395.181328 -270.980662) (xy 395.227556 -270.883126) (xy 395.092936 -270.748506) (xy 394.995654 -270.794734)
			(xy 394.959586 -270.830548) (xy 395.145514 -271.016476)
		)
		(stroke
			(width 0)
			(type solid)
		)
		(fill yes)
		(layer "F.Cu")
		(net "M_E_CPU0_SA_DQ<29>")
	)
	(gr_poly
		(pts
			(xy 395.205204 -265.931904) (xy 395.251432 -265.834622) (xy 395.116812 -265.699748) (xy 395.019276 -265.745976)
			(xy 394.983462 -265.782044) (xy 395.16939 -265.967972)
		)
		(stroke
			(width 0)
			(type solid)
		)
		(fill yes)
		(layer "F.Cu")
		(net "M_E_CPU0_SA_CB<6>")
	)
	(gr_poly
		(pts
			(xy 395.212062 -279.538176) (xy 395.304518 -279.482804) (xy 395.26718 -279.296114) (xy 395.1605 -279.28062)
			(xy 395.110716 -279.290526) (xy 395.162278 -279.548336)
		)
		(stroke
			(width 0)
			(type solid)
		)
		(fill yes)
		(layer "F.Cu")
		(net "M_E_CPU0_SA_DQ<26>")
	)
	(gr_poly
		(pts
			(xy 395.214348 -265.078718) (xy 395.260576 -264.981182) (xy 395.125956 -264.846562) (xy 395.02842 -264.89279)
			(xy 394.992606 -264.928604) (xy 395.178534 -265.114532)
		)
		(stroke
			(width 0)
			(type solid)
		)
		(fill yes)
		(layer "F.Cu")
		(net "M_E_CPU0_SA_CB<7>")
	)
	(gr_poly
		(pts
			(xy 395.220698 -279.840944) (xy 395.169136 -279.583134) (xy 395.119352 -279.59304) (xy 395.026896 -279.648412)
			(xy 395.064234 -279.835356) (xy 395.170914 -279.85085)
		)
		(stroke
			(width 0)
			(type solid)
		)
		(fill yes)
		(layer "F.Cu")
		(net "M_E_CPU0_SA_DQ<26>")
	)
	(gr_poly
		(pts
			(xy 395.22527 -276.491954) (xy 395.317726 -276.436582) (xy 395.280388 -276.249892) (xy 395.173708 -276.234144)
			(xy 395.12367 -276.244304) (xy 395.175232 -276.502114)
		)
		(stroke
			(width 0)
			(type solid)
		)
		(fill yes)
		(layer "F.Cu")
		(net "M_E_CPU0_SA_DQ<27>")
	)
	(gr_poly
		(pts
			(xy 395.233906 -276.794722) (xy 395.182344 -276.536912) (xy 395.13256 -276.546818) (xy 395.040104 -276.60219)
			(xy 395.077442 -276.789134) (xy 395.184122 -276.804628)
		)
		(stroke
			(width 0)
			(type solid)
		)
		(fill yes)
		(layer "F.Cu")
		(net "M_E_CPU0_SA_DQ<27>")
	)
	(gr_poly
		(pts
			(xy 395.262862 -229.498398) (xy 395.227048 -229.46233) (xy 395.129512 -229.416102) (xy 394.994892 -229.550722)
			(xy 395.04112 -229.648258) (xy 395.077188 -229.684072)
		)
		(stroke
			(width 0)
			(type solid)
		)
		(fill yes)
		(layer "F.Cu")
		(net "M_E_CPU0_SB_DQ<15>")
	)
	(gr_poly
		(pts
			(xy 395.264132 -281.354022) (xy 395.356588 -281.29865) (xy 395.31925 -281.111706) (xy 395.21257 -281.096212)
			(xy 395.162786 -281.106118) (xy 395.214348 -281.363928)
		)
		(stroke
			(width 0)
			(type solid)
		)
		(fill yes)
		(layer "F.Cu")
		(net "M_E_CPU0_SA_DQ<24>")
	)
	(gr_poly
		(pts
			(xy 395.27226 -230.351584) (xy 395.236192 -230.31577) (xy 395.13891 -230.269542) (xy 395.004036 -230.404162)
			(xy 395.050518 -230.501698) (xy 395.086332 -230.537512)
		)
		(stroke
			(width 0)
			(type solid)
		)
		(fill yes)
		(layer "F.Cu")
		(net "M_E_CPU0_SB_DQ<14>")
	)
	(gr_poly
		(pts
			(xy 395.27734 -278.3078) (xy 395.369796 -278.252428) (xy 395.332458 -278.065484) (xy 395.225778 -278.04999)
			(xy 395.175994 -278.059896) (xy 395.227556 -278.317706)
		)
		(stroke
			(width 0)
			(type solid)
		)
		(fill yes)
		(layer "F.Cu")
		(net "M_E_CPU0_SA_DQ<25>")
	)
	(gr_poly
		(pts
			(xy 395.285976 -278.610314) (xy 395.234414 -278.352504) (xy 395.18463 -278.362664) (xy 395.092174 -278.418036)
			(xy 395.129512 -278.604726) (xy 395.236192 -278.620474)
		)
		(stroke
			(width 0)
			(type solid)
		)
		(fill yes)
		(layer "F.Cu")
		(net "M_E_CPU0_SA_DQ<25>")
	)
	(gr_poly
		(pts
			(xy 395.287246 -269.608554) (xy 395.32306 -269.57274) (xy 395.137132 -269.386812) (xy 395.101318 -269.422626)
			(xy 395.05509 -269.520162) (xy 395.18971 -269.654782)
		)
		(stroke
			(width 0)
			(type solid)
		)
		(fill yes)
		(layer "F.Cu")
		(net "M_E_CPU0_SA_CB<2>")
	)
	(gr_poly
		(pts
			(xy 395.29639 -268.755368) (xy 395.332204 -268.7193) (xy 395.146276 -268.533372) (xy 395.110462 -268.56944)
			(xy 395.064234 -268.666722) (xy 395.198854 -268.801596)
		)
		(stroke
			(width 0)
			(type solid)
		)
		(fill yes)
		(layer "F.Cu")
		(net "M_E_CPU0_SA_CB<3>")
	)
	(gr_poly
		(pts
			(xy 395.297152 -232.914444) (xy 395.261084 -232.87863) (xy 395.163802 -232.832402) (xy 395.028928 -232.967022)
			(xy 395.075156 -233.064558) (xy 395.111224 -233.100372)
		)
		(stroke
			(width 0)
			(type solid)
		)
		(fill yes)
		(layer "F.Cu")
		(net "M_E_CPU0_SB_DQ<11>")
	)
	(gr_poly
		(pts
			(xy 395.307058 -233.768646) (xy 395.271244 -233.732832) (xy 395.173708 -233.686604) (xy 395.039088 -233.821224)
			(xy 395.085316 -233.918506) (xy 395.12113 -233.954574)
		)
		(stroke
			(width 0)
			(type solid)
		)
		(fill yes)
		(layer "F.Cu")
		(net "M_E_CPU0_SB_DQ<10>")
	)
	(gr_poly
		(pts
			(xy 395.311376 -272.116804) (xy 395.34719 -272.08099) (xy 395.161262 -271.895062) (xy 395.125448 -271.93113)
			(xy 395.07922 -272.028412) (xy 395.21384 -272.163286)
		)
		(stroke
			(width 0)
			(type solid)
		)
		(fill yes)
		(layer "F.Cu")
		(net "M_E_CPU0_SA_DQ<28>")
	)
	(gr_poly
		(pts
			(xy 395.32052 -271.263364) (xy 395.356588 -271.22755) (xy 395.17066 -271.041622) (xy 395.134846 -271.077436)
			(xy 395.088364 -271.174972) (xy 395.223238 -271.309592)
		)
		(stroke
			(width 0)
			(type solid)
		)
		(fill yes)
		(layer "F.Cu")
		(net "M_E_CPU0_SA_DQ<29>")
	)
	(gr_poly
		(pts
			(xy 395.329156 -280.123646) (xy 395.421612 -280.068274) (xy 395.384274 -279.88133) (xy 395.277594 -279.865836)
			(xy 395.22781 -279.875742) (xy 395.279372 -280.133552)
		)
		(stroke
			(width 0)
			(type solid)
		)
		(fill yes)
		(layer "F.Cu")
		(net "M_E_CPU0_SA_DQ<26>")
	)
	(gr_poly
		(pts
			(xy 395.337792 -280.42616) (xy 395.28623 -280.16835) (xy 395.236446 -280.17851) (xy 395.14399 -280.233882)
			(xy 395.181328 -280.420572) (xy 395.288008 -280.436066)
		)
		(stroke
			(width 0)
			(type solid)
		)
		(fill yes)
		(layer "F.Cu")
		(net "M_E_CPU0_SA_DQ<26>")
	)
	(gr_poly
		(pts
			(xy 395.342364 -277.077424) (xy 395.43482 -277.022052) (xy 395.397482 -276.835108) (xy 395.290802 -276.819614)
			(xy 395.240764 -276.82952) (xy 395.292326 -277.08733)
		)
		(stroke
			(width 0)
			(type solid)
		)
		(fill yes)
		(layer "F.Cu")
		(net "M_E_CPU0_SA_DQ<27>")
	)
	(gr_poly
		(pts
			(xy 395.344396 -266.21486) (xy 395.38021 -266.178792) (xy 395.194536 -265.993118) (xy 395.158468 -266.028932)
			(xy 395.11224 -266.126468) (xy 395.24686 -266.261088)
		)
		(stroke
			(width 0)
			(type solid)
		)
		(fill yes)
		(layer "F.Cu")
		(net "M_E_CPU0_SA_CB<6>")
	)
	(gr_poly
		(pts
			(xy 395.34973 -230.058214) (xy 395.303502 -229.960932) (xy 395.267688 -229.924864) (xy 395.08176 -230.110792)
			(xy 395.117574 -230.14686) (xy 395.21511 -230.193088)
		)
		(stroke
			(width 0)
			(type solid)
		)
		(fill yes)
		(layer "F.Cu")
		(net "M_E_CPU0_SB_DQ<13>")
	)
	(gr_poly
		(pts
			(xy 395.351 -277.379938) (xy 395.299438 -277.122128) (xy 395.249654 -277.132034) (xy 395.157198 -277.18766)
			(xy 395.194536 -277.37435) (xy 395.301216 -277.389844)
		)
		(stroke
			(width 0)
			(type solid)
		)
		(fill yes)
		(layer "F.Cu")
		(net "M_E_CPU0_SA_DQ<27>")
	)
	(gr_poly
		(pts
			(xy 395.35354 -265.36142) (xy 395.389608 -265.325606) (xy 395.20368 -265.139678) (xy 395.167866 -265.175492)
			(xy 395.121384 -265.273028) (xy 395.256258 -265.407648)
		)
		(stroke
			(width 0)
			(type solid)
		)
		(fill yes)
		(layer "F.Cu")
		(net "M_E_CPU0_SA_CB<7>")
	)
	(gr_poly
		(pts
			(xy 395.354302 -269.963392) (xy 395.40053 -269.86611) (xy 395.26591 -269.731236) (xy 395.168374 -269.777718)
			(xy 395.13256 -269.813532) (xy 395.318488 -269.99946)
		)
		(stroke
			(width 0)
			(type solid)
		)
		(fill yes)
		(layer "F.Cu")
		(net "M_E_CPU0_SA_CB<0>")
	)
	(gr_poly
		(pts
			(xy 395.358874 -230.911654) (xy 395.312646 -230.814118) (xy 395.276832 -230.778304) (xy 395.090904 -230.964232)
			(xy 395.126718 -231.000046) (xy 395.224254 -231.046274)
		)
		(stroke
			(width 0)
			(type solid)
		)
		(fill yes)
		(layer "F.Cu")
		(net "M_E_CPU0_SB_DQ<12>")
	)
	(gr_poly
		(pts
			(xy 395.3637 -269.110206) (xy 395.409928 -269.01267) (xy 395.275054 -268.87805) (xy 395.177772 -268.924278)
			(xy 395.141704 -268.960092) (xy 395.327632 -269.14602)
		)
		(stroke
			(width 0)
			(type solid)
		)
		(fill yes)
		(layer "F.Cu")
		(net "M_E_CPU0_SA_CB<1>")
	)
	(gr_poly
		(pts
			(xy 395.384274 -233.475022) (xy 395.338046 -233.377486) (xy 395.301978 -233.341672) (xy 395.11605 -233.5276)
			(xy 395.152118 -233.563414) (xy 395.249654 -233.609642)
		)
		(stroke
			(width 0)
			(type solid)
		)
		(fill yes)
		(layer "F.Cu")
		(net "M_E_CPU0_SB_DQ<9>")
	)
	(gr_poly
		(pts
			(xy 395.38783 -271.618456) (xy 395.434058 -271.52092) (xy 395.299184 -271.3863) (xy 395.201902 -271.432528)
			(xy 395.165834 -271.468342) (xy 395.351762 -271.65427)
		)
		(stroke
			(width 0)
			(type solid)
		)
		(fill yes)
		(layer "F.Cu")
		(net "M_E_CPU0_SA_DQ<30>")
	)
	(gr_poly
		(pts
			(xy 395.393926 -234.328716) (xy 395.347698 -234.231434) (xy 395.311884 -234.195366) (xy 395.125956 -234.381294)
			(xy 395.16177 -234.417362) (xy 395.259306 -234.46359)
		)
		(stroke
			(width 0)
			(type solid)
		)
		(fill yes)
		(layer "F.Cu")
		(net "M_E_CPU0_SB_DQ<8>")
	)
	(gr_poly
		(pts
			(xy 395.394434 -278.893016) (xy 395.48689 -278.837644) (xy 395.449552 -278.650954) (xy 395.342872 -278.635206)
			(xy 395.293088 -278.645366) (xy 395.34465 -278.903176)
		)
		(stroke
			(width 0)
			(type solid)
		)
		(fill yes)
		(layer "F.Cu")
		(net "M_E_CPU0_SA_DQ<25>")
	)
	(gr_poly
		(pts
			(xy 395.397228 -270.764762) (xy 395.443456 -270.667226) (xy 395.308836 -270.532606) (xy 395.2113 -270.578834)
			(xy 395.175486 -270.614902) (xy 395.36116 -270.800576)
		)
		(stroke
			(width 0)
			(type solid)
		)
		(fill yes)
		(layer "F.Cu")
		(net "M_E_CPU0_SA_DQ<31>")
	)
	(gr_poly
		(pts
			(xy 395.40307 -279.195784) (xy 395.351508 -278.937974) (xy 395.301724 -278.94788) (xy 395.209268 -279.003252)
			(xy 395.246606 -279.190196) (xy 395.353286 -279.20569)
		)
		(stroke
			(width 0)
			(type solid)
		)
		(fill yes)
		(layer "F.Cu")
		(net "M_E_CPU0_SA_DQ<25>")
	)
	(gr_poly
		(pts
			(xy 395.411706 -266.569698) (xy 395.457934 -266.472162) (xy 395.323314 -266.337542) (xy 395.225778 -266.38377)
			(xy 395.18971 -266.419584) (xy 395.375638 -266.605512)
		)
		(stroke
			(width 0)
			(type solid)
		)
		(fill yes)
		(layer "F.Cu")
		(net "M_E_CPU0_SA_CB<4>")
	)
	(gr_poly
		(pts
			(xy 395.42085 -265.716258) (xy 395.467078 -265.618976) (xy 395.332458 -265.484102) (xy 395.234922 -265.53033)
			(xy 395.199108 -265.566398) (xy 395.385036 -265.752326)
		)
		(stroke
			(width 0)
			(type solid)
		)
		(fill yes)
		(layer "F.Cu")
		(net "M_E_CPU0_SA_CB<5>")
	)
	(gr_poly
		(pts
			(xy 395.44625 -280.708862) (xy 395.538706 -280.65349) (xy 395.501368 -280.4668) (xy 395.394688 -280.451052)
			(xy 395.34465 -280.461212) (xy 395.396466 -280.718768)
		)
		(stroke
			(width 0)
			(type solid)
		)
		(fill yes)
		(layer "F.Cu")
		(net "M_E_CPU0_SA_DQ<26>")
	)
	(gr_poly
		(pts
			(xy 395.459458 -277.66264) (xy 395.551914 -277.607268) (xy 395.514576 -277.420324) (xy 395.407896 -277.40483)
			(xy 395.357858 -277.414736) (xy 395.409674 -277.672546)
		)
		(stroke
			(width 0)
			(type solid)
		)
		(fill yes)
		(layer "F.Cu")
		(net "M_E_CPU0_SA_DQ<27>")
	)
	(gr_poly
		(pts
			(xy 395.468094 -277.965154) (xy 395.416532 -277.707598) (xy 395.366748 -277.717504) (xy 395.274292 -277.772876)
			(xy 395.31163 -277.959566) (xy 395.41831 -277.975314)
		)
		(stroke
			(width 0)
			(type solid)
		)
		(fill yes)
		(layer "F.Cu")
		(net "M_E_CPU0_SA_DQ<27>")
	)
	(gr_poly
		(pts
			(xy 395.47038 -228.768148) (xy 395.41958 -228.768148) (xy 395.31798 -228.80447) (xy 395.31798 -228.99497)
			(xy 395.41958 -229.031038) (xy 395.47038 -229.031038)
		)
		(stroke
			(width 0)
			(type solid)
		)
		(fill yes)
		(layer "F.Cu")
		(net "M_E_CPU0_SB_DQ<15>")
	)
	(gr_poly
		(pts
			(xy 395.47038 -228.171248) (xy 395.41958 -228.171248) (xy 395.31798 -228.20757) (xy 395.31798 -228.39807)
			(xy 395.41958 -228.434138) (xy 395.47038 -228.434138)
		)
		(stroke
			(width 0)
			(type solid)
		)
		(fill yes)
		(layer "F.Cu")
		(net "M_E_CPU0_SB_DQ<15>")
	)
	(gr_poly
		(pts
			(xy 395.47038 -227.574348) (xy 395.41958 -227.574348) (xy 395.31798 -227.61067) (xy 395.31798 -227.80117)
			(xy 395.41958 -227.837238) (xy 395.47038 -227.837238)
		)
		(stroke
			(width 0)
			(type solid)
		)
		(fill yes)
		(layer "F.Cu")
		(net "M_E_CPU0_SB_DQ<15>")
	)
	(gr_poly
		(pts
			(xy 395.47038 -226.977448) (xy 395.41958 -226.977448) (xy 395.31798 -227.01377) (xy 395.31798 -227.20427)
			(xy 395.41958 -227.240338) (xy 395.47038 -227.240338)
		)
		(stroke
			(width 0)
			(type solid)
		)
		(fill yes)
		(layer "F.Cu")
		(net "M_E_CPU0_SB_DQ<15>")
	)
	(gr_poly
		(pts
			(xy 395.47038 -226.380548) (xy 395.41958 -226.380548) (xy 395.31798 -226.41687) (xy 395.31798 -226.60737)
			(xy 395.41958 -226.643438) (xy 395.47038 -226.643438)
		)
		(stroke
			(width 0)
			(type solid)
		)
		(fill yes)
		(layer "F.Cu")
		(net "M_E_CPU0_SB_DQ<15>")
	)
	(gr_poly
		(pts
			(xy 395.478508 -229.714044) (xy 395.442694 -229.677976) (xy 395.345158 -229.631748) (xy 395.210538 -229.766368)
			(xy 395.256766 -229.863904) (xy 395.292834 -229.899718)
		)
		(stroke
			(width 0)
			(type solid)
		)
		(fill yes)
		(layer "F.Cu")
		(net "M_E_CPU0_SB_DQ<13>")
	)
	(gr_poly
		(pts
			(xy 395.487906 -230.56723) (xy 395.451838 -230.531416) (xy 395.354556 -230.485188) (xy 395.219682 -230.619808)
			(xy 395.266164 -230.717344) (xy 395.301978 -230.753158)
		)
		(stroke
			(width 0)
			(type solid)
		)
		(fill yes)
		(layer "F.Cu")
		(net "M_E_CPU0_SB_DQ<12>")
	)
	(gr_poly
		(pts
			(xy 395.493494 -270.246348) (xy 395.529562 -270.210534) (xy 395.343634 -270.024606) (xy 395.307566 -270.06042)
			(xy 395.261338 -270.157956) (xy 395.396212 -270.292576)
		)
		(stroke
			(width 0)
			(type solid)
		)
		(fill yes)
		(layer "F.Cu")
		(net "M_E_CPU0_SA_CB<0>")
	)
	(gr_poly
		(pts
			(xy 395.502892 -269.392908) (xy 395.538706 -269.357094) (xy 395.352778 -269.171166) (xy 395.316964 -269.20698)
			(xy 395.270736 -269.304516) (xy 395.405356 -269.439136)
		)
		(stroke
			(width 0)
			(type solid)
		)
		(fill yes)
		(layer "F.Cu")
		(net "M_E_CPU0_SA_CB<1>")
	)
	(gr_poly
		(pts
			(xy 395.511528 -279.478486) (xy 395.603984 -279.42286) (xy 395.566646 -279.23617) (xy 395.459966 -279.220676)
			(xy 395.410182 -279.230582) (xy 395.461744 -279.488392)
		)
		(stroke
			(width 0)
			(type solid)
		)
		(fill yes)
		(layer "F.Cu")
		(net "M_E_CPU0_SA_DQ<25>")
	)
	(gr_poly
		(pts
			(xy 395.513052 -233.130598) (xy 395.477238 -233.094784) (xy 395.379702 -233.048302) (xy 395.245082 -233.183176)
			(xy 395.29131 -233.280458) (xy 395.327124 -233.316526)
		)
		(stroke
			(width 0)
			(type solid)
		)
		(fill yes)
		(layer "F.Cu")
		(net "M_E_CPU0_SB_DQ<9>")
	)
	(gr_poly
		(pts
			(xy 395.520418 -279.781) (xy 395.468856 -279.52319) (xy 395.418818 -279.533096) (xy 395.326362 -279.588722)
			(xy 395.3637 -279.775412) (xy 395.470634 -279.790906)
		)
		(stroke
			(width 0)
			(type solid)
		)
		(fill yes)
		(layer "F.Cu")
		(net "M_E_CPU0_SA_DQ<25>")
	)
	(gr_poly
		(pts
			(xy 395.522704 -233.984546) (xy 395.48689 -233.948478) (xy 395.389354 -233.90225) (xy 395.254734 -234.03687)
			(xy 395.300962 -234.134406) (xy 395.33703 -234.17022)
		)
		(stroke
			(width 0)
			(type solid)
		)
		(fill yes)
		(layer "F.Cu")
		(net "M_E_CPU0_SB_DQ<8>")
	)
	(gr_poly
		(pts
			(xy 395.527022 -271.901158) (xy 395.562836 -271.865344) (xy 395.376908 -271.679416) (xy 395.341094 -271.715484)
			(xy 395.294866 -271.812766) (xy 395.429486 -271.94764)
		)
		(stroke
			(width 0)
			(type solid)
		)
		(fill yes)
		(layer "F.Cu")
		(net "M_E_CPU0_SA_DQ<30>")
	)
	(gr_poly
		(pts
			(xy 395.53642 -271.047718) (xy 395.572234 -271.01165) (xy 395.386306 -270.825722) (xy 395.350492 -270.86179)
			(xy 395.304264 -270.959326) (xy 395.438884 -271.093946)
		)
		(stroke
			(width 0)
			(type solid)
		)
		(fill yes)
		(layer "F.Cu")
		(net "M_E_CPU0_SA_DQ<31>")
	)
	(gr_poly
		(pts
			(xy 395.550898 -266.852654) (xy 395.586712 -266.816586) (xy 395.400784 -266.630658) (xy 395.36497 -266.666726)
			(xy 395.318742 -266.764008) (xy 395.453362 -266.898882)
		)
		(stroke
			(width 0)
			(type solid)
		)
		(fill yes)
		(layer "F.Cu")
		(net "M_E_CPU0_SA_CB<4>")
	)
	(gr_poly
		(pts
			(xy 395.560042 -265.999214) (xy 395.595856 -265.963146) (xy 395.410182 -265.777472) (xy 395.374114 -265.813286)
			(xy 395.327886 -265.910822) (xy 395.462506 -266.045442)
		)
		(stroke
			(width 0)
			(type solid)
		)
		(fill yes)
		(layer "F.Cu")
		(net "M_E_CPU0_SA_CB<5>")
	)
	(gr_poly
		(pts
			(xy 395.565376 -230.27386) (xy 395.519148 -230.176578) (xy 395.483334 -230.14051) (xy 395.297406 -230.326438)
			(xy 395.33322 -230.362506) (xy 395.430756 -230.408734)
		)
		(stroke
			(width 0)
			(type solid)
		)
		(fill yes)
		(layer "F.Cu")
		(net "M_E_CPU0_SB_DQ<14>")
	)
	(gr_poly
		(pts
			(xy 395.569948 -269.747746) (xy 395.616176 -269.650464) (xy 395.481556 -269.51559) (xy 395.38402 -269.562072)
			(xy 395.348206 -269.597886) (xy 395.534134 -269.783814)
		)
		(stroke
			(width 0)
			(type solid)
		)
		(fill yes)
		(layer "F.Cu")
		(net "M_E_CPU0_SA_CB<2>")
	)
	(gr_poly
		(pts
			(xy 395.576552 -278.247856) (xy 395.669008 -278.192484) (xy 395.63167 -278.005794) (xy 395.52499 -277.990046)
			(xy 395.474952 -278.000206) (xy 395.526768 -278.258016)
		)
		(stroke
			(width 0)
			(type solid)
		)
		(fill yes)
		(layer "F.Cu")
		(net "M_E_CPU0_SA_DQ<27>")
	)
	(gr_poly
		(pts
			(xy 395.579346 -268.89456) (xy 395.625574 -268.797024) (xy 395.4907 -268.662404) (xy 395.393418 -268.708632)
			(xy 395.35735 -268.744446) (xy 395.543278 -268.930374)
		)
		(stroke
			(width 0)
			(type solid)
		)
		(fill yes)
		(layer "F.Cu")
		(net "M_E_CPU0_SA_CB<3>")
	)
	(gr_poly
		(pts
			(xy 395.585188 -278.550624) (xy 395.533626 -278.292814) (xy 395.483842 -278.30272) (xy 395.391386 -278.358092)
			(xy 395.428724 -278.545036) (xy 395.535404 -278.56053)
		)
		(stroke
			(width 0)
			(type solid)
		)
		(fill yes)
		(layer "F.Cu")
		(net "M_E_CPU0_SA_DQ<27>")
	)
	(gr_poly
		(pts
			(xy 395.590268 -232.836974) (xy 395.54404 -232.739438) (xy 395.508226 -232.703624) (xy 395.322298 -232.889298)
			(xy 395.358112 -232.925366) (xy 395.455648 -232.971594)
		)
		(stroke
			(width 0)
			(type solid)
		)
		(fill yes)
		(layer "F.Cu")
		(net "M_E_CPU0_SB_DQ<11>")
	)
	(gr_poly
		(pts
			(xy 395.594078 -272.255996) (xy 395.640306 -272.158714) (xy 395.505686 -272.024094) (xy 395.40815 -272.070322)
			(xy 395.372336 -272.106136) (xy 395.558264 -272.292064)
		)
		(stroke
			(width 0)
			(type solid)
		)
		(fill yes)
		(layer "F.Cu")
		(net "M_E_CPU0_SA_DQ<28>")
	)
	(gr_poly
		(pts
			(xy 395.600174 -233.690922) (xy 395.553946 -233.59364) (xy 395.518132 -233.557572) (xy 395.332204 -233.7435)
			(xy 395.368018 -233.779314) (xy 395.465554 -233.825796)
		)
		(stroke
			(width 0)
			(type solid)
		)
		(fill yes)
		(layer "F.Cu")
		(net "M_E_CPU0_SB_DQ<10>")
	)
	(gr_poly
		(pts
			(xy 395.603476 -271.402556) (xy 395.649704 -271.305274) (xy 395.515084 -271.1704) (xy 395.417548 -271.216628)
			(xy 395.381734 -271.252696) (xy 395.567662 -271.438624)
		)
		(stroke
			(width 0)
			(type solid)
		)
		(fill yes)
		(layer "F.Cu")
		(net "M_E_CPU0_SA_DQ<29>")
	)
	(gr_poly
		(pts
			(xy 395.62278 -228.696266) (xy 395.62278 -228.505766) (xy 395.52118 -228.469698) (xy 395.47038 -228.469698)
			(xy 395.47038 -228.732588) (xy 395.52118 -228.732588)
		)
		(stroke
			(width 0)
			(type solid)
		)
		(fill yes)
		(layer "F.Cu")
		(net "M_E_CPU0_SB_DQ<15>")
	)
	(gr_poly
		(pts
			(xy 395.62278 -228.099366) (xy 395.62278 -227.908866) (xy 395.52118 -227.872798) (xy 395.47038 -227.872798)
			(xy 395.47038 -228.135688) (xy 395.52118 -228.135688)
		)
		(stroke
			(width 0)
			(type solid)
		)
		(fill yes)
		(layer "F.Cu")
		(net "M_E_CPU0_SB_DQ<15>")
	)
	(gr_poly
		(pts
			(xy 395.62278 -227.502466) (xy 395.62278 -227.311966) (xy 395.52118 -227.275898) (xy 395.47038 -227.275898)
			(xy 395.47038 -227.538788) (xy 395.52118 -227.538788)
		)
		(stroke
			(width 0)
			(type solid)
		)
		(fill yes)
		(layer "F.Cu")
		(net "M_E_CPU0_SB_DQ<15>")
	)
	(gr_poly
		(pts
			(xy 395.62278 -226.905566) (xy 395.62278 -226.715066) (xy 395.52118 -226.678998) (xy 395.47038 -226.678998)
			(xy 395.47038 -226.941888) (xy 395.52118 -226.941888)
		)
		(stroke
			(width 0)
			(type solid)
		)
		(fill yes)
		(layer "F.Cu")
		(net "M_E_CPU0_SB_DQ<15>")
	)
	(gr_poly
		(pts
			(xy 395.627352 -266.354052) (xy 395.67358 -266.256516) (xy 395.53896 -266.121896) (xy 395.441424 -266.168124)
			(xy 395.405356 -266.203938) (xy 395.591284 -266.389866)
		)
		(stroke
			(width 0)
			(type solid)
		)
		(fill yes)
		(layer "F.Cu")
		(net "M_E_CPU0_SA_CB<6>")
	)
	(gr_poly
		(pts
			(xy 395.628622 -280.063702) (xy 395.721332 -280.00833) (xy 395.68374 -279.821386) (xy 395.57706 -279.805892)
			(xy 395.527276 -279.815798) (xy 395.578838 -280.073608)
		)
		(stroke
			(width 0)
			(type solid)
		)
		(fill yes)
		(layer "F.Cu")
		(net "M_E_CPU0_SA_DQ<25>")
	)
	(gr_poly
		(pts
			(xy 395.636496 -265.500612) (xy 395.682724 -265.40333) (xy 395.548104 -265.268456) (xy 395.450568 -265.314684)
			(xy 395.414754 -265.350752) (xy 395.600682 -265.53668)
		)
		(stroke
			(width 0)
			(type solid)
		)
		(fill yes)
		(layer "F.Cu")
		(net "M_E_CPU0_SA_CB<7>")
	)
	(gr_poly
		(pts
			(xy 395.637512 -280.366216) (xy 395.58595 -280.108406) (xy 395.536166 -280.118566) (xy 395.443456 -280.173938)
			(xy 395.480794 -280.360628) (xy 395.587728 -280.376376)
		)
		(stroke
			(width 0)
			(type solid)
		)
		(fill yes)
		(layer "F.Cu")
		(net "M_E_CPU0_SA_DQ<25>")
	)
	(gr_poly
		(pts
			(xy 395.693646 -278.833326) (xy 395.786102 -278.777954) (xy 395.748764 -278.59101) (xy 395.642084 -278.575516)
			(xy 395.5923 -278.585422) (xy 395.643862 -278.843232)
		)
		(stroke
			(width 0)
			(type solid)
		)
		(fill yes)
		(layer "F.Cu")
		(net "M_E_CPU0_SA_DQ<27>")
	)
	(gr_poly
		(pts
			(xy 395.694154 -229.92969) (xy 395.65834 -229.893622) (xy 395.560804 -229.847394) (xy 395.426184 -229.982014)
			(xy 395.472412 -230.07955) (xy 395.50848 -230.115364)
		)
		(stroke
			(width 0)
			(type solid)
		)
		(fill yes)
		(layer "F.Cu")
		(net "M_E_CPU0_SB_DQ<14>")
	)
	(gr_poly
		(pts
			(xy 395.702282 -279.13584) (xy 395.65072 -278.87803) (xy 395.600936 -278.887936) (xy 395.50848 -278.943562)
			(xy 395.545818 -279.130252) (xy 395.652498 -279.145746)
		)
		(stroke
			(width 0)
			(type solid)
		)
		(fill yes)
		(layer "F.Cu")
		(net "M_E_CPU0_SA_DQ<27>")
	)
	(gr_poly
		(pts
			(xy 395.70914 -270.030702) (xy 395.745208 -269.994888) (xy 395.55928 -269.80896) (xy 395.523212 -269.844774)
			(xy 395.476984 -269.94231) (xy 395.611858 -270.07693)
		)
		(stroke
			(width 0)
			(type solid)
		)
		(fill yes)
		(layer "F.Cu")
		(net "M_E_CPU0_SA_CB<2>")
	)
	(gr_poly
		(pts
			(xy 395.718538 -269.177262) (xy 395.754352 -269.141448) (xy 395.568424 -268.95552) (xy 395.53261 -268.991334)
			(xy 395.486382 -269.08887) (xy 395.621002 -269.22349)
		)
		(stroke
			(width 0)
			(type solid)
		)
		(fill yes)
		(layer "F.Cu")
		(net "M_E_CPU0_SA_CB<3>")
	)
	(gr_poly
		(pts
			(xy 395.719046 -232.49255) (xy 395.683232 -232.456482) (xy 395.585696 -232.410254) (xy 395.451076 -232.544874)
			(xy 395.497304 -232.64241) (xy 395.533118 -232.678224)
		)
		(stroke
			(width 0)
			(type solid)
		)
		(fill yes)
		(layer "F.Cu")
		(net "M_E_CPU0_SB_DQ<11>")
	)
	(gr_poly
		(pts
			(xy 395.729206 -233.346498) (xy 395.693138 -233.310684) (xy 395.595856 -233.264456) (xy 395.460982 -233.399076)
			(xy 395.50721 -233.496612) (xy 395.543278 -233.532426)
		)
		(stroke
			(width 0)
			(type solid)
		)
		(fill yes)
		(layer "F.Cu")
		(net "M_E_CPU0_SB_DQ<10>")
	)
	(gr_poly
		(pts
			(xy 395.73327 -272.538952) (xy 395.769338 -272.503138) (xy 395.58341 -272.31721) (xy 395.547342 -272.353024)
			(xy 395.501114 -272.45056) (xy 395.635988 -272.58518)
		)
		(stroke
			(width 0)
			(type solid)
		)
		(fill yes)
		(layer "F.Cu")
		(net "M_E_CPU0_SA_DQ<28>")
	)
	(gr_poly
		(pts
			(xy 395.742668 -271.685512) (xy 395.778736 -271.649698) (xy 395.592808 -271.46377) (xy 395.55674 -271.499584)
			(xy 395.510512 -271.59712) (xy 395.645386 -271.73174)
		)
		(stroke
			(width 0)
			(type solid)
		)
		(fill yes)
		(layer "F.Cu")
		(net "M_E_CPU0_SA_DQ<29>")
	)
	(gr_poly
		(pts
			(xy 395.766544 -266.637008) (xy 395.802358 -266.60094) (xy 395.61643 -266.415012) (xy 395.580616 -266.45108)
			(xy 395.534388 -266.548362) (xy 395.669008 -266.683236)
		)
		(stroke
			(width 0)
			(type solid)
		)
		(fill yes)
		(layer "F.Cu")
		(net "M_E_CPU0_SA_CB<6>")
	)
	(gr_poly
		(pts
			(xy 395.77518 -228.768148) (xy 395.72438 -228.768148) (xy 395.62278 -228.80447) (xy 395.62278 -228.99497)
			(xy 395.72438 -229.031038) (xy 395.77518 -229.031038)
		)
		(stroke
			(width 0)
			(type solid)
		)
		(fill yes)
		(layer "F.Cu")
		(net "M_E_CPU0_SB_DQ<13>")
	)
	(gr_poly
		(pts
			(xy 395.77518 -228.171248) (xy 395.72438 -228.171248) (xy 395.62278 -228.20757) (xy 395.62278 -228.39807)
			(xy 395.72438 -228.434138) (xy 395.77518 -228.434138)
		)
		(stroke
			(width 0)
			(type solid)
		)
		(fill yes)
		(layer "F.Cu")
		(net "M_E_CPU0_SB_DQ<13>")
	)
	(gr_poly
		(pts
			(xy 395.77518 -227.574348) (xy 395.72438 -227.574348) (xy 395.62278 -227.61067) (xy 395.62278 -227.80117)
			(xy 395.72438 -227.837238) (xy 395.77518 -227.837238)
		)
		(stroke
			(width 0)
			(type solid)
		)
		(fill yes)
		(layer "F.Cu")
		(net "M_E_CPU0_SB_DQ<13>")
	)
	(gr_poly
		(pts
			(xy 395.77518 -226.977448) (xy 395.72438 -226.977448) (xy 395.62278 -227.01377) (xy 395.62278 -227.20427)
			(xy 395.72438 -227.240338) (xy 395.77518 -227.240338)
		)
		(stroke
			(width 0)
			(type solid)
		)
		(fill yes)
		(layer "F.Cu")
		(net "M_E_CPU0_SB_DQ<13>")
	)
	(gr_poly
		(pts
			(xy 395.77518 -226.380548) (xy 395.72438 -226.380548) (xy 395.62278 -226.41687) (xy 395.62278 -226.60737)
			(xy 395.72438 -226.643438) (xy 395.77518 -226.643438)
		)
		(stroke
			(width 0)
			(type solid)
		)
		(fill yes)
		(layer "F.Cu")
		(net "M_E_CPU0_SB_DQ<13>")
	)
	(gr_poly
		(pts
			(xy 395.775688 -265.783568) (xy 395.811502 -265.7475) (xy 395.625828 -265.561826) (xy 395.58976 -265.59764)
			(xy 395.543532 -265.695176) (xy 395.678152 -265.829796)
		)
		(stroke
			(width 0)
			(type solid)
		)
		(fill yes)
		(layer "F.Cu")
		(net "M_E_CPU0_SA_CB<7>")
	)
	(gr_poly
		(pts
			(xy 395.77645 -270.38554) (xy 395.822678 -270.288004) (xy 395.688058 -270.153384) (xy 395.590522 -270.199612)
			(xy 395.554708 -270.23568) (xy 395.740382 -270.421354)
		)
		(stroke
			(width 0)
			(type solid)
		)
		(fill yes)
		(layer "F.Cu")
		(net "M_E_CPU0_SA_CB<0>")
	)
	(gr_poly
		(pts
			(xy 395.781022 -230.489506) (xy 395.734794 -230.392224) (xy 395.69898 -230.356156) (xy 395.513052 -230.542084)
			(xy 395.548866 -230.578152) (xy 395.646402 -230.62438)
		)
		(stroke
			(width 0)
			(type solid)
		)
		(fill yes)
		(layer "F.Cu")
		(net "M_E_CPU0_SB_DQ<12>")
	)
	(gr_poly
		(pts
			(xy 395.785594 -269.5321) (xy 395.831822 -269.434818) (xy 395.697202 -269.299944) (xy 395.599666 -269.346426)
			(xy 395.563852 -269.38224) (xy 395.74978 -269.568168)
		)
		(stroke
			(width 0)
			(type solid)
		)
		(fill yes)
		(layer "F.Cu")
		(net "M_E_CPU0_SA_CB<1>")
	)
	(gr_poly
		(pts
			(xy 395.806422 -233.052874) (xy 395.760194 -232.955592) (xy 395.724126 -232.919524) (xy 395.538198 -233.105452)
			(xy 395.574266 -233.141266) (xy 395.671548 -233.187494)
		)
		(stroke
			(width 0)
			(type solid)
		)
		(fill yes)
		(layer "F.Cu")
		(net "M_E_CPU0_SB_DQ<9>")
	)
	(gr_poly
		(pts
			(xy 395.809724 -272.04035) (xy 395.855952 -271.943068) (xy 395.721332 -271.808448) (xy 395.623796 -271.854676)
			(xy 395.587982 -271.89049) (xy 395.77391 -272.076418)
		)
		(stroke
			(width 0)
			(type solid)
		)
		(fill yes)
		(layer "F.Cu")
		(net "M_E_CPU0_SA_DQ<30>")
	)
	(gr_poly
		(pts
			(xy 395.81074 -279.418542) (xy 395.903196 -279.36317) (xy 395.865858 -279.176226) (xy 395.759178 -279.160732)
			(xy 395.709394 -279.170638) (xy 395.760956 -279.428448)
		)
		(stroke
			(width 0)
			(type solid)
		)
		(fill yes)
		(layer "F.Cu")
		(net "M_E_CPU0_SA_DQ<27>")
	)
	(gr_poly
		(pts
			(xy 395.816074 -233.906822) (xy 395.769846 -233.809286) (xy 395.733778 -233.773472) (xy 395.54785 -233.9594)
			(xy 395.583918 -233.995214) (xy 395.681454 -234.041442)
		)
		(stroke
			(width 0)
			(type solid)
		)
		(fill yes)
		(layer "F.Cu")
		(net "M_E_CPU0_SB_DQ<8>")
	)
	(gr_poly
		(pts
			(xy 395.819376 -279.721056) (xy 395.767814 -279.4635) (xy 395.71803 -279.473406) (xy 395.625574 -279.528778)
			(xy 395.662912 -279.715468) (xy 395.769592 -279.731216)
		)
		(stroke
			(width 0)
			(type solid)
		)
		(fill yes)
		(layer "F.Cu")
		(net "M_E_CPU0_SA_DQ<27>")
	)
	(gr_poly
		(pts
			(xy 395.819376 -271.18691) (xy 395.865604 -271.089374) (xy 395.73073 -270.954754) (xy 395.633448 -271.000982)
			(xy 395.59738 -271.036796) (xy 395.783308 -271.222724)
		)
		(stroke
			(width 0)
			(type solid)
		)
		(fill yes)
		(layer "F.Cu")
		(net "M_E_CPU0_SA_DQ<31>")
	)
	(gr_poly
		(pts
			(xy 395.8336 -266.991846) (xy 395.880082 -266.89431) (xy 395.745208 -266.75969) (xy 395.647926 -266.805918)
			(xy 395.611858 -266.841732) (xy 395.797786 -267.02766)
		)
		(stroke
			(width 0)
			(type solid)
		)
		(fill yes)
		(layer "F.Cu")
		(net "M_E_CPU0_SA_CB<4>")
	)
	(gr_poly
		(pts
			(xy 395.842998 -266.138406) (xy 395.889226 -266.04087) (xy 395.754606 -265.90625) (xy 395.65707 -265.952478)
			(xy 395.621002 -265.988292) (xy 395.80693 -266.17422)
		)
		(stroke
			(width 0)
			(type solid)
		)
		(fill yes)
		(layer "F.Cu")
		(net "M_E_CPU0_SA_CB<5>")
	)
	(gr_poly
		(pts
			(xy 395.9098 -230.145336) (xy 395.873986 -230.109268) (xy 395.77645 -230.06304) (xy 395.64183 -230.19766)
			(xy 395.688058 -230.295196) (xy 395.724126 -230.33101)
		)
		(stroke
			(width 0)
			(type solid)
		)
		(fill yes)
		(layer "F.Cu")
		(net "M_E_CPU0_SB_DQ<12>")
	)
	(gr_poly
		(pts
			(xy 395.915642 -270.668496) (xy 395.951456 -270.632428) (xy 395.765528 -270.4465) (xy 395.729714 -270.482568)
			(xy 395.683486 -270.580104) (xy 395.818106 -270.714724)
		)
		(stroke
			(width 0)
			(type solid)
		)
		(fill yes)
		(layer "F.Cu")
		(net "M_E_CPU0_SA_CB<0>")
	)
	(gr_poly
		(pts
			(xy 395.924786 -269.815056) (xy 395.960854 -269.779242) (xy 395.774926 -269.593314) (xy 395.738858 -269.629128)
			(xy 395.69263 -269.726664) (xy 395.827504 -269.861284)
		)
		(stroke
			(width 0)
			(type solid)
		)
		(fill yes)
		(layer "F.Cu")
		(net "M_E_CPU0_SA_CB<1>")
	)
	(gr_poly
		(pts
			(xy 395.92758 -228.696266) (xy 395.92758 -228.505766) (xy 395.82598 -228.469698) (xy 395.77518 -228.469698)
			(xy 395.77518 -228.732588) (xy 395.82598 -228.732588)
		)
		(stroke
			(width 0)
			(type solid)
		)
		(fill yes)
		(layer "F.Cu")
		(net "M_E_CPU0_SB_DQ<13>")
	)
	(gr_poly
		(pts
			(xy 395.92758 -228.099366) (xy 395.92758 -227.908866) (xy 395.82598 -227.872798) (xy 395.77518 -227.872798)
			(xy 395.77518 -228.135688) (xy 395.82598 -228.135688)
		)
		(stroke
			(width 0)
			(type solid)
		)
		(fill yes)
		(layer "F.Cu")
		(net "M_E_CPU0_SB_DQ<13>")
	)
	(gr_poly
		(pts
			(xy 395.92758 -227.502466) (xy 395.92758 -227.311966) (xy 395.82598 -227.275898) (xy 395.77518 -227.275898)
			(xy 395.77518 -227.538788) (xy 395.82598 -227.538788)
		)
		(stroke
			(width 0)
			(type solid)
		)
		(fill yes)
		(layer "F.Cu")
		(net "M_E_CPU0_SB_DQ<13>")
	)
	(gr_poly
		(pts
			(xy 395.92758 -226.905566) (xy 395.92758 -226.715066) (xy 395.82598 -226.678998) (xy 395.77518 -226.678998)
			(xy 395.77518 -226.941888) (xy 395.82598 -226.941888)
		)
		(stroke
			(width 0)
			(type solid)
		)
		(fill yes)
		(layer "F.Cu")
		(net "M_E_CPU0_SB_DQ<13>")
	)
	(gr_poly
		(pts
			(xy 395.927834 -280.003758) (xy 396.02029 -279.948386) (xy 395.982952 -279.761696) (xy 395.876272 -279.745948)
			(xy 395.826488 -279.756108) (xy 395.87805 -280.013918)
		)
		(stroke
			(width 0)
			(type solid)
		)
		(fill yes)
		(layer "F.Cu")
		(net "M_E_CPU0_SA_DQ<27>")
	)
	(gr_poly
		(pts
			(xy 395.9352 -232.70845) (xy 395.899386 -232.672636) (xy 395.80185 -232.626408) (xy 395.66723 -232.761028)
			(xy 395.713458 -232.858564) (xy 395.749272 -232.894378)
		)
		(stroke
			(width 0)
			(type solid)
		)
		(fill yes)
		(layer "F.Cu")
		(net "M_E_CPU0_SB_DQ<9>")
	)
	(gr_poly
		(pts
			(xy 395.93647 -280.306526) (xy 395.884908 -280.048716) (xy 395.835124 -280.058622) (xy 395.742668 -280.113994)
			(xy 395.780006 -280.300938) (xy 395.886686 -280.316432)
		)
		(stroke
			(width 0)
			(type solid)
		)
		(fill yes)
		(layer "F.Cu")
		(net "M_E_CPU0_SA_DQ<27>")
	)
	(gr_poly
		(pts
			(xy 395.944852 -233.562398) (xy 395.909038 -233.52633) (xy 395.811502 -233.480102) (xy 395.676882 -233.614976)
			(xy 395.72311 -233.712258) (xy 395.758924 -233.748326)
		)
		(stroke
			(width 0)
			(type solid)
		)
		(fill yes)
		(layer "F.Cu")
		(net "M_E_CPU0_SB_DQ<8>")
	)
	(gr_poly
		(pts
			(xy 395.948916 -272.323306) (xy 395.984984 -272.287492) (xy 395.799056 -272.101564) (xy 395.762988 -272.137378)
			(xy 395.71676 -272.234914) (xy 395.851634 -272.369534)
		)
		(stroke
			(width 0)
			(type solid)
		)
		(fill yes)
		(layer "F.Cu")
		(net "M_E_CPU0_SA_DQ<30>")
	)
	(gr_poly
		(pts
			(xy 395.958568 -271.469612) (xy 395.994382 -271.433798) (xy 395.808454 -271.24787) (xy 395.77264 -271.283938)
			(xy 395.726412 -271.38122) (xy 395.861032 -271.516094)
		)
		(stroke
			(width 0)
			(type solid)
		)
		(fill yes)
		(layer "F.Cu")
		(net "M_E_CPU0_SA_DQ<31>")
	)
	(gr_poly
		(pts
			(xy 395.972792 -267.274548) (xy 396.00886 -267.238734) (xy 395.822932 -267.052806) (xy 395.787118 -267.08862)
			(xy 395.74089 -267.186156) (xy 395.87551 -267.320776)
		)
		(stroke
			(width 0)
			(type solid)
		)
		(fill yes)
		(layer "F.Cu")
		(net "M_E_CPU0_SA_CB<4>")
	)
	(gr_poly
		(pts
			(xy 395.98219 -266.421362) (xy 396.018004 -266.385294) (xy 395.832076 -266.199366) (xy 395.796262 -266.235434)
			(xy 395.750034 -266.332716) (xy 395.884654 -266.46759)
		)
		(stroke
			(width 0)
			(type solid)
		)
		(fill yes)
		(layer "F.Cu")
		(net "M_E_CPU0_SA_CB<5>")
	)
	(gr_poly
		(pts
			(xy 395.987524 -229.851966) (xy 395.941296 -229.75443) (xy 395.905228 -229.718616) (xy 395.7193 -229.904544)
			(xy 395.755368 -229.940358) (xy 395.852904 -229.986586)
		)
		(stroke
			(width 0)
			(type solid)
		)
		(fill yes)
		(layer "F.Cu")
		(net "M_E_CPU0_SB_DQ<14>")
	)
	(gr_poly
		(pts
			(xy 395.992096 -270.169894) (xy 396.038324 -270.072358) (xy 395.903704 -269.937738) (xy 395.806168 -269.983966)
			(xy 395.770354 -270.020034) (xy 395.956028 -270.205708)
		)
		(stroke
			(width 0)
			(type solid)
		)
		(fill yes)
		(layer "F.Cu")
		(net "M_E_CPU0_SA_CB<2>")
	)
	(gr_poly
		(pts
			(xy 396.00124 -269.316454) (xy 396.047468 -269.219172) (xy 395.912848 -269.084298) (xy 395.815312 -269.13078)
			(xy 395.779498 -269.166594) (xy 395.965426 -269.352522)
		)
		(stroke
			(width 0)
			(type solid)
		)
		(fill yes)
		(layer "F.Cu")
		(net "M_E_CPU0_SA_CB<3>")
	)
	(gr_poly
		(pts
			(xy 396.012416 -232.414826) (xy 395.966188 -232.31729) (xy 395.93012 -232.281476) (xy 395.744192 -232.467404)
			(xy 395.78026 -232.503218) (xy 395.877542 -232.549446)
		)
		(stroke
			(width 0)
			(type solid)
		)
		(fill yes)
		(layer "F.Cu")
		(net "M_E_CPU0_SB_DQ<11>")
	)
	(gr_poly
		(pts
			(xy 396.022322 -233.268774) (xy 395.976094 -233.171492) (xy 395.94028 -233.135424) (xy 395.754352 -233.321352)
			(xy 395.790166 -233.35742) (xy 395.887702 -233.403648)
		)
		(stroke
			(width 0)
			(type solid)
		)
		(fill yes)
		(layer "F.Cu")
		(net "M_E_CPU0_SB_DQ<10>")
	)
	(gr_poly
		(pts
			(xy 396.025624 -271.824704) (xy 396.071852 -271.727168) (xy 395.937232 -271.592548) (xy 395.839696 -271.638776)
			(xy 395.803882 -271.674844) (xy 395.989556 -271.860518)
		)
		(stroke
			(width 0)
			(type solid)
		)
		(fill yes)
		(layer "F.Cu")
		(net "M_E_CPU0_SA_DQ<29>")
	)
	(gr_poly
		(pts
			(xy 396.044928 -280.589228) (xy 396.137384 -280.533856) (xy 396.100046 -280.346912) (xy 395.993366 -280.331418)
			(xy 395.943582 -280.341324) (xy 395.995144 -280.599134)
		)
		(stroke
			(width 0)
			(type solid)
		)
		(fill yes)
		(layer "F.Cu")
		(net "M_E_CPU0_SA_DQ<27>")
	)
	(gr_poly
		(pts
			(xy 396.049246 -266.7762) (xy 396.095728 -266.678664) (xy 395.960854 -266.544044) (xy 395.863572 -266.590272)
			(xy 395.827504 -266.626086) (xy 396.013432 -266.812014)
		)
		(stroke
			(width 0)
			(type solid)
		)
		(fill yes)
		(layer "F.Cu")
		(net "M_E_CPU0_SA_CB<6>")
	)
	(gr_poly
		(pts
			(xy 396.058644 -265.92276) (xy 396.104872 -265.825224) (xy 395.970252 -265.690604) (xy 395.872716 -265.736832)
			(xy 395.836648 -265.772646) (xy 396.022576 -265.958574)
		)
		(stroke
			(width 0)
			(type solid)
		)
		(fill yes)
		(layer "F.Cu")
		(net "M_E_CPU0_SA_CB<7>")
	)
	(gr_poly
		(pts
			(xy 396.07998 -228.768148) (xy 396.02918 -228.768148) (xy 395.92758 -228.80447) (xy 395.92758 -228.99497)
			(xy 396.02918 -229.031038) (xy 396.07998 -229.031038)
		)
		(stroke
			(width 0)
			(type solid)
		)
		(fill yes)
		(layer "F.Cu")
		(net "M_E_CPU0_SB_DQ<14>")
	)
	(gr_poly
		(pts
			(xy 396.07998 -228.171248) (xy 396.02918 -228.171248) (xy 395.92758 -228.20757) (xy 395.92758 -228.39807)
			(xy 396.02918 -228.434138) (xy 396.07998 -228.434138)
		)
		(stroke
			(width 0)
			(type solid)
		)
		(fill yes)
		(layer "F.Cu")
		(net "M_E_CPU0_SB_DQ<14>")
	)
	(gr_poly
		(pts
			(xy 396.07998 -227.574348) (xy 396.02918 -227.574348) (xy 395.92758 -227.61067) (xy 395.92758 -227.80117)
			(xy 396.02918 -227.837238) (xy 396.07998 -227.837238)
		)
		(stroke
			(width 0)
			(type solid)
		)
		(fill yes)
		(layer "F.Cu")
		(net "M_E_CPU0_SB_DQ<14>")
	)
	(gr_poly
		(pts
			(xy 396.119096 -273.376644) (xy 396.067534 -273.118834) (xy 396.01775 -273.12874) (xy 395.92504 -273.184112)
			(xy 395.962378 -273.371056) (xy 396.069312 -273.38655)
		)
		(stroke
			(width 0)
			(type solid)
		)
		(fill yes)
		(layer "F.Cu")
		(net "M_E_CPU0_SA_DQ<28>")
	)
	(gr_poly
		(pts
			(xy 396.131288 -270.45285) (xy 396.167102 -270.416782) (xy 395.981174 -270.230854) (xy 395.94536 -270.266922)
			(xy 395.899132 -270.364458) (xy 396.033752 -270.499078)
		)
		(stroke
			(width 0)
			(type solid)
		)
		(fill yes)
		(layer "F.Cu")
		(net "M_E_CPU0_SA_CB<2>")
	)
	(gr_poly
		(pts
			(xy 396.140432 -269.59941) (xy 396.1765 -269.563596) (xy 395.990572 -269.377668) (xy 395.954504 -269.413482)
			(xy 395.908276 -269.511018) (xy 396.04315 -269.645638)
		)
		(stroke
			(width 0)
			(type solid)
		)
		(fill yes)
		(layer "F.Cu")
		(net "M_E_CPU0_SA_CB<3>")
	)
	(gr_poly
		(pts
			(xy 396.141194 -232.070402) (xy 396.10538 -232.034588) (xy 396.007844 -231.988106) (xy 395.873224 -232.12298)
			(xy 395.919452 -232.220262) (xy 395.955266 -232.25633)
		)
		(stroke
			(width 0)
			(type solid)
		)
		(fill yes)
		(layer "F.Cu")
		(net "M_E_CPU0_SB_DQ<11>")
	)
	(gr_poly
		(pts
			(xy 396.1511 -232.924604) (xy 396.115286 -232.888536) (xy 396.01775 -232.842308) (xy 395.88313 -232.976928)
			(xy 395.929358 -233.074464) (xy 395.965426 -233.110278)
		)
		(stroke
			(width 0)
			(type solid)
		)
		(fill yes)
		(layer "F.Cu")
		(net "M_E_CPU0_SB_DQ<10>")
	)
	(gr_poly
		(pts
			(xy 396.164816 -272.10766) (xy 396.20063 -272.071592) (xy 396.014702 -271.885664) (xy 395.978888 -271.921732)
			(xy 395.93266 -272.019014) (xy 396.06728 -272.153888)
		)
		(stroke
			(width 0)
			(type solid)
		)
		(fill yes)
		(layer "F.Cu")
		(net "M_E_CPU0_SA_DQ<29>")
	)
	(gr_poly
		(pts
			(xy 396.188438 -267.058902) (xy 396.224506 -267.023088) (xy 396.038578 -266.83716) (xy 396.002764 -266.872974)
			(xy 395.956536 -266.97051) (xy 396.091156 -267.10513)
		)
		(stroke
			(width 0)
			(type solid)
		)
		(fill yes)
		(layer "F.Cu")
		(net "M_E_CPU0_SA_CB<6>")
	)
	(gr_poly
		(pts
			(xy 396.197836 -266.205716) (xy 396.23365 -266.169648) (xy 396.047722 -265.98372) (xy 396.011908 -266.019788)
			(xy 395.96568 -266.11707) (xy 396.1003 -266.251944)
		)
		(stroke
			(width 0)
			(type solid)
		)
		(fill yes)
		(layer "F.Cu")
		(net "M_E_CPU0_SA_CB<7>")
	)
	(gr_poly
		(pts
			(xy 396.198598 -270.807688) (xy 396.244826 -270.710152) (xy 396.109952 -270.575532) (xy 396.01267 -270.62176)
			(xy 395.976602 -270.657574) (xy 396.16253 -270.843502)
		)
		(stroke
			(width 0)
			(type solid)
		)
		(fill yes)
		(layer "F.Cu")
		(net "M_E_CPU0_SA_CB<0>")
	)
	(gr_poly
		(pts
			(xy 396.20317 -230.067612) (xy 396.156942 -229.970076) (xy 396.120874 -229.934262) (xy 395.934946 -230.12019)
			(xy 395.971014 -230.156004) (xy 396.06855 -230.202232)
		)
		(stroke
			(width 0)
			(type solid)
		)
		(fill yes)
		(layer "F.Cu")
		(net "M_E_CPU0_SB_DQ<12>")
	)
	(gr_poly
		(pts
			(xy 396.207742 -269.954248) (xy 396.25397 -269.856712) (xy 396.11935 -269.722092) (xy 396.021814 -269.76832)
			(xy 395.986 -269.804388) (xy 396.171674 -269.990062)
		)
		(stroke
			(width 0)
			(type solid)
		)
		(fill yes)
		(layer "F.Cu")
		(net "M_E_CPU0_SA_CB<1>")
	)
	(gr_poly
		(pts
			(xy 396.2273 -273.659092) (xy 396.32001 -273.60372) (xy 396.282672 -273.41703) (xy 396.175738 -273.401536)
			(xy 396.125954 -273.411442) (xy 396.177516 -273.669252)
		)
		(stroke
			(width 0)
			(type solid)
		)
		(fill yes)
		(layer "F.Cu")
		(net "M_E_CPU0_SA_DQ<28>")
	)
	(gr_poly
		(pts
			(xy 396.22857 -232.63098) (xy 396.182088 -232.533444) (xy 396.146274 -232.49763) (xy 395.960346 -232.683304)
			(xy 395.996414 -232.719372) (xy 396.093696 -232.7656)
		)
		(stroke
			(width 0)
			(type solid)
		)
		(fill yes)
		(layer "F.Cu")
		(net "M_E_CPU0_SB_DQ<9>")
	)
	(gr_poly
		(pts
			(xy 396.23238 -229.293166) (xy 396.23238 -229.102666) (xy 396.13078 -229.066598) (xy 396.07998 -229.066598)
			(xy 396.07998 -229.329488) (xy 396.13078 -229.329488)
		)
		(stroke
			(width 0)
			(type solid)
		)
		(fill yes)
		(layer "F.Cu")
		(net "M_E_CPU0_SB_DQ<14>")
	)
	(gr_poly
		(pts
			(xy 396.23238 -228.696266) (xy 396.23238 -228.505766) (xy 396.13078 -228.469698) (xy 396.07998 -228.469698)
			(xy 396.07998 -228.732588) (xy 396.13078 -228.732588)
		)
		(stroke
			(width 0)
			(type solid)
		)
		(fill yes)
		(layer "F.Cu")
		(net "M_E_CPU0_SB_DQ<14>")
	)
	(gr_poly
		(pts
			(xy 396.23238 -228.099366) (xy 396.23238 -227.908866) (xy 396.13078 -227.872798) (xy 396.07998 -227.872798)
			(xy 396.07998 -228.135688) (xy 396.13078 -228.135688)
		)
		(stroke
			(width 0)
			(type solid)
		)
		(fill yes)
		(layer "F.Cu")
		(net "M_E_CPU0_SB_DQ<14>")
	)
	(gr_poly
		(pts
			(xy 396.23238 -227.502466) (xy 396.23238 -227.311966) (xy 396.13078 -227.275898) (xy 396.07998 -227.275898)
			(xy 396.07998 -227.538788) (xy 396.13078 -227.538788)
		)
		(stroke
			(width 0)
			(type solid)
		)
		(fill yes)
		(layer "F.Cu")
		(net "M_E_CPU0_SB_DQ<14>")
	)
	(gr_poly
		(pts
			(xy 396.23619 -273.96186) (xy 396.184628 -273.70405) (xy 396.134844 -273.713956) (xy 396.042134 -273.769328)
			(xy 396.079726 -273.956272) (xy 396.186406 -273.971766)
		)
		(stroke
			(width 0)
			(type solid)
		)
		(fill yes)
		(layer "F.Cu")
		(net "M_E_CPU0_SA_DQ<28>")
	)
	(gr_poly
		(pts
			(xy 396.238222 -233.484674) (xy 396.19174 -233.387138) (xy 396.155926 -233.351324) (xy 395.969998 -233.537252)
			(xy 396.006066 -233.573066) (xy 396.103348 -233.619294)
		)
		(stroke
			(width 0)
			(type solid)
		)
		(fill yes)
		(layer "F.Cu")
		(net "M_E_CPU0_SB_DQ<8>")
	)
	(gr_poly
		(pts
			(xy 396.24127 -271.608804) (xy 396.287498 -271.511522) (xy 396.152878 -271.376902) (xy 396.055342 -271.42313)
			(xy 396.019528 -271.458944) (xy 396.205456 -271.644872)
		)
		(stroke
			(width 0)
			(type solid)
		)
		(fill yes)
		(layer "F.Cu")
		(net "M_E_CPU0_SA_DQ<31>")
	)
	(gr_poly
		(pts
			(xy 396.255748 -267.41374) (xy 396.301976 -267.316458) (xy 396.167356 -267.181584) (xy 396.06982 -267.227812)
			(xy 396.034006 -267.26388) (xy 396.219934 -267.449808)
		)
		(stroke
			(width 0)
			(type solid)
		)
		(fill yes)
		(layer "F.Cu")
		(net "M_E_CPU0_SA_CB<4>")
	)
	(gr_poly
		(pts
			(xy 396.264892 -266.560554) (xy 396.311374 -266.463018) (xy 396.1765 -266.328398) (xy 396.079218 -266.374626)
			(xy 396.04315 -266.41044) (xy 396.229078 -266.596368)
		)
		(stroke
			(width 0)
			(type solid)
		)
		(fill yes)
		(layer "F.Cu")
		(net "M_E_CPU0_SA_CB<5>")
	)
	(gr_poly
		(pts
			(xy 396.33779 -271.09039) (xy 396.373604 -271.054576) (xy 396.187676 -270.868648) (xy 396.151862 -270.904716)
			(xy 396.105634 -271.001998) (xy 396.240254 -271.136872)
		)
		(stroke
			(width 0)
			(type solid)
		)
		(fill yes)
		(layer "F.Cu")
		(net "M_E_CPU0_SA_CB<0>")
	)
	(gr_poly
		(pts
			(xy 396.344648 -274.244562) (xy 396.437104 -274.18919) (xy 396.399766 -274.002246) (xy 396.293086 -273.986752)
			(xy 396.243048 -273.996658) (xy 396.29461 -274.254468)
		)
		(stroke
			(width 0)
			(type solid)
		)
		(fill yes)
		(layer "F.Cu")
		(net "M_E_CPU0_SA_DQ<28>")
	)
	(gr_poly
		(pts
			(xy 396.346934 -270.237204) (xy 396.382748 -270.201136) (xy 396.19682 -270.015208) (xy 396.161006 -270.051276)
			(xy 396.114778 -270.148812) (xy 396.249398 -270.283432)
		)
		(stroke
			(width 0)
			(type solid)
		)
		(fill yes)
		(layer "F.Cu")
		(net "M_E_CPU0_SA_CB<1>")
	)
	(gr_poly
		(pts
			(xy 396.353284 -274.547076) (xy 396.301722 -274.289266) (xy 396.251938 -274.299426) (xy 396.159482 -274.354798)
			(xy 396.19682 -274.541488) (xy 396.3035 -274.556982)
		)
		(stroke
			(width 0)
			(type solid)
		)
		(fill yes)
		(layer "F.Cu")
		(net "M_E_CPU0_SA_DQ<28>")
	)
	(gr_poly
		(pts
			(xy 396.357348 -232.286556) (xy 396.321534 -232.250488) (xy 396.223998 -232.20426) (xy 396.089378 -232.339134)
			(xy 396.135606 -232.436416) (xy 396.17142 -232.472484)
		)
		(stroke
			(width 0)
			(type solid)
		)
		(fill yes)
		(layer "F.Cu")
		(net "M_E_CPU0_SB_DQ<9>")
	)
	(gr_poly
		(pts
			(xy 396.367 -233.14025) (xy 396.330932 -233.104436) (xy 396.23365 -233.058208) (xy 396.09903 -233.192828)
			(xy 396.145258 -233.290364) (xy 396.181072 -233.326178)
		)
		(stroke
			(width 0)
			(type solid)
		)
		(fill yes)
		(layer "F.Cu")
		(net "M_E_CPU0_SB_DQ<8>")
	)
	(gr_poly
		(pts
			(xy 396.380462 -271.89176) (xy 396.41653 -271.855946) (xy 396.230602 -271.670018) (xy 396.194534 -271.705832)
			(xy 396.148306 -271.803368) (xy 396.28318 -271.937988)
		)
		(stroke
			(width 0)
			(type solid)
		)
		(fill yes)
		(layer "F.Cu")
		(net "M_E_CPU0_SA_DQ<31>")
	)
	(gr_poly
		(pts
			(xy 396.38478 -228.768148) (xy 396.33398 -228.768148) (xy 396.23238 -228.80447) (xy 396.23238 -228.99497)
			(xy 396.33398 -229.031038) (xy 396.38478 -229.031038)
		)
		(stroke
			(width 0)
			(type solid)
		)
		(fill yes)
		(layer "F.Cu")
		(net "M_E_CPU0_SB_DQ<12>")
	)
	(gr_poly
		(pts
			(xy 396.38478 -228.171248) (xy 396.33398 -228.171248) (xy 396.23238 -228.20757) (xy 396.23238 -228.39807)
			(xy 396.33398 -228.434138) (xy 396.38478 -228.434138)
		)
		(stroke
			(width 0)
			(type solid)
		)
		(fill yes)
		(layer "F.Cu")
		(net "M_E_CPU0_SB_DQ<12>")
	)
	(gr_poly
		(pts
			(xy 396.38478 -227.574348) (xy 396.33398 -227.574348) (xy 396.23238 -227.61067) (xy 396.23238 -227.80117)
			(xy 396.33398 -227.837238) (xy 396.38478 -227.837238)
		)
		(stroke
			(width 0)
			(type solid)
		)
		(fill yes)
		(layer "F.Cu")
		(net "M_E_CPU0_SB_DQ<12>")
	)
	(gr_poly
		(pts
			(xy 396.38478 -226.977448) (xy 396.33398 -226.977448) (xy 396.23238 -227.01377) (xy 396.23238 -227.20427)
			(xy 396.33398 -227.240338) (xy 396.38478 -227.240338)
		)
		(stroke
			(width 0)
			(type solid)
		)
		(fill yes)
		(layer "F.Cu")
		(net "M_E_CPU0_SB_DQ<12>")
	)
	(gr_poly
		(pts
			(xy 396.39494 -267.696696) (xy 396.431008 -267.660882) (xy 396.24508 -267.474954) (xy 396.209012 -267.510768)
			(xy 396.162784 -267.608304) (xy 396.297658 -267.742924)
		)
		(stroke
			(width 0)
			(type solid)
		)
		(fill yes)
		(layer "F.Cu")
		(net "M_E_CPU0_SA_CB<4>")
	)
	(gr_poly
		(pts
			(xy 396.404084 -266.843256) (xy 396.440152 -266.807442) (xy 396.254224 -266.621514) (xy 396.21841 -266.657328)
			(xy 396.172182 -266.754864) (xy 396.306802 -266.889484)
		)
		(stroke
			(width 0)
			(type solid)
		)
		(fill yes)
		(layer "F.Cu")
		(net "M_E_CPU0_SA_CB<5>")
	)
	(gr_poly
		(pts
			(xy 396.409418 -273.013932) (xy 396.502128 -272.95856) (xy 396.46479 -272.77187) (xy 396.357856 -272.756376)
			(xy 396.308072 -272.766282) (xy 396.359634 -273.024092)
		)
		(stroke
			(width 0)
			(type solid)
		)
		(fill yes)
		(layer "F.Cu")
		(net "M_E_CPU0_SA_DQ<30>")
	)
	(gr_poly
		(pts
			(xy 396.414244 -270.592042) (xy 396.460472 -270.494506) (xy 396.325598 -270.359886) (xy 396.228316 -270.406114)
			(xy 396.192248 -270.441928) (xy 396.378176 -270.627856)
		)
		(stroke
			(width 0)
			(type solid)
		)
		(fill yes)
		(layer "F.Cu")
		(net "M_E_CPU0_SA_CB<2>")
	)
	(gr_poly
		(pts
			(xy 396.418308 -273.3167) (xy 396.366746 -273.05889) (xy 396.316962 -273.068796) (xy 396.224252 -273.124168)
			(xy 396.261844 -273.311112) (xy 396.368524 -273.326606)
		)
		(stroke
			(width 0)
			(type solid)
		)
		(fill yes)
		(layer "F.Cu")
		(net "M_E_CPU0_SA_DQ<30>")
	)
	(gr_poly
		(pts
			(xy 396.423388 -269.738602) (xy 396.469616 -269.641066) (xy 396.334996 -269.506446) (xy 396.23746 -269.552674)
			(xy 396.201646 -269.588742) (xy 396.38732 -269.774416)
		)
		(stroke
			(width 0)
			(type solid)
		)
		(fill yes)
		(layer "F.Cu")
		(net "M_E_CPU0_SA_CB<3>")
	)
	(gr_poly
		(pts
			(xy 396.43431 -231.992678) (xy 396.388082 -231.895396) (xy 396.352268 -231.859328) (xy 396.16634 -232.045256)
			(xy 396.202154 -232.08107) (xy 396.29969 -232.127298)
		)
		(stroke
			(width 0)
			(type solid)
		)
		(fill yes)
		(layer "F.Cu")
		(net "M_E_CPU0_SB_DQ<11>")
	)
	(gr_poly
		(pts
			(xy 396.44447 -232.84688) (xy 396.398242 -232.749344) (xy 396.362174 -232.71353) (xy 396.176246 -232.899458)
			(xy 396.212314 -232.935272) (xy 396.309596 -232.9815)
		)
		(stroke
			(width 0)
			(type solid)
		)
		(fill yes)
		(layer "F.Cu")
		(net "M_E_CPU0_SB_DQ<10>")
	)
	(gr_poly
		(pts
			(xy 396.447772 -272.246852) (xy 396.494 -272.149316) (xy 396.359126 -272.014696) (xy 396.261844 -272.060924)
			(xy 396.225776 -272.096738) (xy 396.411704 -272.282666)
		)
		(stroke
			(width 0)
			(type solid)
		)
		(fill yes)
		(layer "F.Cu")
		(net "M_E_CPU0_SA_DQ<29>")
	)
	(gr_poly
		(pts
			(xy 396.461742 -274.829778) (xy 396.554198 -274.774406) (xy 396.51686 -274.587462) (xy 396.41018 -274.571968)
			(xy 396.360396 -274.581874) (xy 396.411958 -274.839684)
		)
		(stroke
			(width 0)
			(type solid)
		)
		(fill yes)
		(layer "F.Cu")
		(net "M_E_CPU0_SA_DQ<28>")
	)
	(gr_poly
		(pts
			(xy 396.470378 -275.132292) (xy 396.418816 -274.874736) (xy 396.369032 -274.884642) (xy 396.276576 -274.940014)
			(xy 396.313914 -275.126704) (xy 396.420594 -275.142452)
		)
		(stroke
			(width 0)
			(type solid)
		)
		(fill yes)
		(layer "F.Cu")
		(net "M_E_CPU0_SA_DQ<28>")
	)
	(gr_poly
		(pts
			(xy 396.471394 -267.198094) (xy 396.517622 -267.100812) (xy 396.383002 -266.965938) (xy 396.285466 -267.012166)
			(xy 396.249652 -267.048234) (xy 396.43558 -267.234162)
		)
		(stroke
			(width 0)
			(type solid)
		)
		(fill yes)
		(layer "F.Cu")
		(net "M_E_CPU0_SA_CB<6>")
	)
	(gr_poly
		(pts
			(xy 396.480538 -266.344908) (xy 396.52702 -266.247372) (xy 396.392146 -266.112752) (xy 396.294864 -266.15898)
			(xy 396.258796 -266.194794) (xy 396.444724 -266.380722)
		)
		(stroke
			(width 0)
			(type solid)
		)
		(fill yes)
		(layer "F.Cu")
		(net "M_E_CPU0_SA_CB<7>")
	)
	(gr_poly
		(pts
			(xy 396.526512 -273.599402) (xy 396.619222 -273.54403) (xy 396.581884 -273.357086) (xy 396.47495 -273.341592)
			(xy 396.425166 -273.351498) (xy 396.476728 -273.609308)
		)
		(stroke
			(width 0)
			(type solid)
		)
		(fill yes)
		(layer "F.Cu")
		(net "M_E_CPU0_SA_DQ<30>")
	)
	(gr_poly
		(pts
			(xy 396.535402 -273.901916) (xy 396.48384 -273.644106) (xy 396.434056 -273.654266) (xy 396.341346 -273.709638)
			(xy 396.378938 -273.896328) (xy 396.485618 -273.911822)
		)
		(stroke
			(width 0)
			(type solid)
		)
		(fill yes)
		(layer "F.Cu")
		(net "M_E_CPU0_SA_DQ<30>")
	)
	(gr_poly
		(pts
			(xy 396.53718 -229.293166) (xy 396.53718 -229.102666) (xy 396.43558 -229.066598) (xy 396.38478 -229.066598)
			(xy 396.38478 -229.329488) (xy 396.43558 -229.329488)
		)
		(stroke
			(width 0)
			(type solid)
		)
		(fill yes)
		(layer "F.Cu")
		(net "M_E_CPU0_SB_DQ<12>")
	)
	(gr_poly
		(pts
			(xy 396.53718 -228.696266) (xy 396.53718 -228.505766) (xy 396.43558 -228.469698) (xy 396.38478 -228.469698)
			(xy 396.38478 -228.732588) (xy 396.43558 -228.732588)
		)
		(stroke
			(width 0)
			(type solid)
		)
		(fill yes)
		(layer "F.Cu")
		(net "M_E_CPU0_SB_DQ<12>")
	)
	(gr_poly
		(pts
			(xy 396.53718 -228.099366) (xy 396.53718 -227.908866) (xy 396.43558 -227.872798) (xy 396.38478 -227.872798)
			(xy 396.38478 -228.135688) (xy 396.43558 -228.135688)
		)
		(stroke
			(width 0)
			(type solid)
		)
		(fill yes)
		(layer "F.Cu")
		(net "M_E_CPU0_SB_DQ<12>")
	)
	(gr_poly
		(pts
			(xy 396.53718 -227.502466) (xy 396.53718 -227.311966) (xy 396.43558 -227.275898) (xy 396.38478 -227.275898)
			(xy 396.38478 -227.538788) (xy 396.43558 -227.538788)
		)
		(stroke
			(width 0)
			(type solid)
		)
		(fill yes)
		(layer "F.Cu")
		(net "M_E_CPU0_SB_DQ<12>")
	)
	(gr_poly
		(pts
			(xy 396.553436 -270.874744) (xy 396.58925 -270.83893) (xy 396.403322 -270.653002) (xy 396.367508 -270.68907)
			(xy 396.32128 -270.786352) (xy 396.4559 -270.921226)
		)
		(stroke
			(width 0)
			(type solid)
		)
		(fill yes)
		(layer "F.Cu")
		(net "M_E_CPU0_SA_CB<2>")
	)
	(gr_poly
		(pts
			(xy 396.56258 -270.021558) (xy 396.598394 -269.98549) (xy 396.412466 -269.799562) (xy 396.376652 -269.83563)
			(xy 396.330424 -269.933166) (xy 396.465044 -270.067786)
		)
		(stroke
			(width 0)
			(type solid)
		)
		(fill yes)
		(layer "F.Cu")
		(net "M_E_CPU0_SA_CB<3>")
	)
	(gr_poly
		(pts
			(xy 396.563342 -231.648254) (xy 396.527274 -231.61244) (xy 396.429992 -231.566212) (xy 396.295118 -231.700832)
			(xy 396.341346 -231.798368) (xy 396.377414 -231.834182)
		)
		(stroke
			(width 0)
			(type solid)
		)
		(fill yes)
		(layer "F.Cu")
		(net "M_E_CPU0_SB_DQ<11>")
	)
	(gr_poly
		(pts
			(xy 396.573248 -232.502456) (xy 396.537434 -232.466388) (xy 396.439898 -232.42016) (xy 396.305278 -232.555034)
			(xy 396.351506 -232.652316) (xy 396.38732 -232.688384)
		)
		(stroke
			(width 0)
			(type solid)
		)
		(fill yes)
		(layer "F.Cu")
		(net "M_E_CPU0_SB_DQ<10>")
	)
	(gr_poly
		(pts
			(xy 396.578836 -275.414994) (xy 396.671292 -275.359622) (xy 396.633954 -275.172932) (xy 396.527274 -275.157438)
			(xy 396.47749 -275.167344) (xy 396.529052 -275.425154)
		)
		(stroke
			(width 0)
			(type solid)
		)
		(fill yes)
		(layer "F.Cu")
		(net "M_E_CPU0_SA_DQ<28>")
	)
	(gr_poly
		(pts
			(xy 396.587472 -275.717762) (xy 396.53591 -275.459952) (xy 396.486126 -275.469858) (xy 396.39367 -275.52523)
			(xy 396.431008 -275.712174) (xy 396.537688 -275.727668)
		)
		(stroke
			(width 0)
			(type solid)
		)
		(fill yes)
		(layer "F.Cu")
		(net "M_E_CPU0_SA_DQ<28>")
	)
	(gr_poly
		(pts
			(xy 396.610586 -267.48105) (xy 396.646654 -267.445236) (xy 396.460726 -267.259308) (xy 396.424658 -267.295122)
			(xy 396.37843 -267.392658) (xy 396.513304 -267.527278)
		)
		(stroke
			(width 0)
			(type solid)
		)
		(fill yes)
		(layer "F.Cu")
		(net "M_E_CPU0_SA_CB<6>")
	)
	(gr_poly
		(pts
			(xy 396.61973 -266.62761) (xy 396.655798 -266.591796) (xy 396.46987 -266.405868) (xy 396.434056 -266.441682)
			(xy 396.387828 -266.539218) (xy 396.522448 -266.673838)
		)
		(stroke
			(width 0)
			(type solid)
		)
		(fill yes)
		(layer "F.Cu")
		(net "M_E_CPU0_SA_CB<7>")
	)
	(gr_poly
		(pts
			(xy 396.620492 -271.229582) (xy 396.66672 -271.1323) (xy 396.5321 -270.99768) (xy 396.434564 -271.043908)
			(xy 396.39875 -271.079722) (xy 396.584678 -271.26565)
		)
		(stroke
			(width 0)
			(type solid)
		)
		(fill yes)
		(layer "F.Cu")
		(net "M_E_CPU0_SA_CB<0>")
	)
	(gr_poly
		(pts
			(xy 396.62989 -270.376396) (xy 396.676118 -270.27886) (xy 396.541244 -270.14424) (xy 396.443962 -270.190468)
			(xy 396.407894 -270.226282) (xy 396.593822 -270.41221)
		)
		(stroke
			(width 0)
			(type solid)
		)
		(fill yes)
		(layer "F.Cu")
		(net "M_E_CPU0_SA_CB<1>")
	)
	(gr_poly
		(pts
			(xy 396.643606 -274.184618) (xy 396.736316 -274.129246) (xy 396.698978 -273.942302) (xy 396.592044 -273.926808)
			(xy 396.54226 -273.936714) (xy 396.593822 -274.194524)
		)
		(stroke
			(width 0)
			(type solid)
		)
		(fill yes)
		(layer "F.Cu")
		(net "M_E_CPU0_SA_DQ<30>")
	)
	(gr_poly
		(pts
			(xy 396.650464 -232.208832) (xy 396.604236 -232.111296) (xy 396.568422 -232.075482) (xy 396.382494 -232.26141)
			(xy 396.418308 -232.297224) (xy 396.515844 -232.343452)
		)
		(stroke
			(width 0)
			(type solid)
		)
		(fill yes)
		(layer "F.Cu")
		(net "M_E_CPU0_SB_DQ<9>")
	)
	(gr_poly
		(pts
			(xy 396.652496 -274.487132) (xy 396.600934 -274.229576) (xy 396.55115 -274.239482) (xy 396.45844 -274.294854)
			(xy 396.496032 -274.481544) (xy 396.602712 -274.497292)
		)
		(stroke
			(width 0)
			(type solid)
		)
		(fill yes)
		(layer "F.Cu")
		(net "M_E_CPU0_SA_DQ<30>")
	)
	(gr_poly
		(pts
			(xy 396.660116 -233.062526) (xy 396.613888 -232.965244) (xy 396.578074 -232.929176) (xy 396.392146 -233.115104)
			(xy 396.42796 -233.151172) (xy 396.525496 -233.1974)
		)
		(stroke
			(width 0)
			(type solid)
		)
		(fill yes)
		(layer "F.Cu")
		(net "M_E_CPU0_SB_DQ<8>")
	)
	(gr_poly
		(pts
			(xy 396.663418 -272.030952) (xy 396.709646 -271.93367) (xy 396.575026 -271.798796) (xy 396.47749 -271.845024)
			(xy 396.441676 -271.881092) (xy 396.627604 -272.06702)
		)
		(stroke
			(width 0)
			(type solid)
		)
		(fill yes)
		(layer "F.Cu")
		(net "M_E_CPU0_SA_DQ<31>")
	)
	(gr_poly
		(pts
			(xy 396.677896 -267.835888) (xy 396.724124 -267.738352) (xy 396.589504 -267.603732) (xy 396.491968 -267.64996)
			(xy 396.456154 -267.686028) (xy 396.641828 -267.871702)
		)
		(stroke
			(width 0)
			(type solid)
		)
		(fill yes)
		(layer "F.Cu")
		(net "M_E_CPU0_SA_CB<4>")
	)
	(gr_poly
		(pts
			(xy 396.68704 -266.982448) (xy 396.733268 -266.885166) (xy 396.598648 -266.750292) (xy 396.501112 -266.79652)
			(xy 396.465298 -266.832588) (xy 396.651226 -267.018516)
		)
		(stroke
			(width 0)
			(type solid)
		)
		(fill yes)
		(layer "F.Cu")
		(net "M_E_CPU0_SA_CB<5>")
	)
	(gr_poly
		(pts
			(xy 396.69593 -276.000464) (xy 396.788386 -275.945092) (xy 396.751048 -275.758148) (xy 396.644368 -275.742654)
			(xy 396.594584 -275.75256) (xy 396.646146 -276.01037)
		)
		(stroke
			(width 0)
			(type solid)
		)
		(fill yes)
		(layer "F.Cu")
		(net "M_E_CPU0_SA_DQ<28>")
	)
	(gr_poly
		(pts
			(xy 396.704566 -276.302978) (xy 396.653004 -276.045168) (xy 396.60322 -276.055074) (xy 396.510764 -276.1107)
			(xy 396.548102 -276.29739) (xy 396.654782 -276.312884)
		)
		(stroke
			(width 0)
			(type solid)
		)
		(fill yes)
		(layer "F.Cu")
		(net "M_E_CPU0_SA_DQ<28>")
	)
	(gr_poly
		(pts
			(xy 396.70863 -272.954242) (xy 396.801086 -272.89887) (xy 396.763748 -272.711926) (xy 396.657068 -272.696432)
			(xy 396.607284 -272.706338) (xy 396.658846 -272.964148)
		)
		(stroke
			(width 0)
			(type solid)
		)
		(fill yes)
		(layer "F.Cu")
		(net "M_E_CPU0_SA_DQ<29>")
	)
	(gr_poly
		(pts
			(xy 396.717266 -273.256756) (xy 396.665704 -272.998946) (xy 396.61592 -273.009106) (xy 396.523464 -273.064478)
			(xy 396.560802 -273.251168) (xy 396.667482 -273.266662)
		)
		(stroke
			(width 0)
			(type solid)
		)
		(fill yes)
		(layer "F.Cu")
		(net "M_E_CPU0_SA_DQ<29>")
	)
	(gr_poly
		(pts
			(xy 396.759684 -271.512538) (xy 396.795752 -271.476724) (xy 396.609824 -271.290796) (xy 396.573756 -271.32661)
			(xy 396.527528 -271.424146) (xy 396.662402 -271.558766)
		)
		(stroke
			(width 0)
			(type solid)
		)
		(fill yes)
		(layer "F.Cu")
		(net "M_E_CPU0_SA_CB<0>")
	)
	(gr_poly
		(pts
			(xy 396.760954 -274.769834) (xy 396.85341 -274.714462) (xy 396.816072 -274.527772) (xy 396.709138 -274.512278)
			(xy 396.659354 -274.522184) (xy 396.710916 -274.779994)
		)
		(stroke
			(width 0)
			(type solid)
		)
		(fill yes)
		(layer "F.Cu")
		(net "M_E_CPU0_SA_DQ<30>")
	)
	(gr_poly
		(pts
			(xy 396.769082 -270.659098) (xy 396.804896 -270.623284) (xy 396.618968 -270.437356) (xy 396.583154 -270.473424)
			(xy 396.536926 -270.570706) (xy 396.671546 -270.70558)
		)
		(stroke
			(width 0)
			(type solid)
		)
		(fill yes)
		(layer "F.Cu")
		(net "M_E_CPU0_SA_CB<1>")
	)
	(gr_poly
		(pts
			(xy 396.76959 -275.072602) (xy 396.718028 -274.814792) (xy 396.668244 -274.824698) (xy 396.575788 -274.88007)
			(xy 396.613126 -275.067014) (xy 396.719806 -275.082508)
		)
		(stroke
			(width 0)
			(type solid)
		)
		(fill yes)
		(layer "F.Cu")
		(net "M_E_CPU0_SA_DQ<30>")
	)
	(gr_poly
		(pts
			(xy 396.779496 -231.864408) (xy 396.743428 -231.828594) (xy 396.646146 -231.782366) (xy 396.511272 -231.916986)
			(xy 396.5575 -232.014522) (xy 396.593568 -232.050336)
		)
		(stroke
			(width 0)
			(type solid)
		)
		(fill yes)
		(layer "F.Cu")
		(net "M_E_CPU0_SB_DQ<9>")
	)
	(gr_poly
		(pts
			(xy 396.789148 -232.718102) (xy 396.75308 -232.682288) (xy 396.655798 -232.63606) (xy 396.520924 -232.77068)
			(xy 396.567152 -232.868216) (xy 396.60322 -232.90403)
		)
		(stroke
			(width 0)
			(type solid)
		)
		(fill yes)
		(layer "F.Cu")
		(net "M_E_CPU0_SB_DQ<8>")
	)
	(gr_poly
		(pts
			(xy 396.813024 -276.58568) (xy 396.90548 -276.530308) (xy 396.868142 -276.343364) (xy 396.761462 -276.32787)
			(xy 396.711678 -276.337776) (xy 396.76324 -276.595586)
		)
		(stroke
			(width 0)
			(type solid)
		)
		(fill yes)
		(layer "F.Cu")
		(net "M_E_CPU0_SA_DQ<28>")
	)
	(gr_poly
		(pts
			(xy 396.817088 -268.118844) (xy 396.852902 -268.082776) (xy 396.666974 -267.896848) (xy 396.63116 -267.932916)
			(xy 396.584932 -268.030198) (xy 396.719552 -268.165072)
		)
		(stroke
			(width 0)
			(type solid)
		)
		(fill yes)
		(layer "F.Cu")
		(net "M_E_CPU0_SA_CB<4>")
	)
	(gr_poly
		(pts
			(xy 396.821914 -276.888194) (xy 396.770352 -276.630638) (xy 396.720314 -276.640544) (xy 396.627858 -276.695916)
			(xy 396.665196 -276.882606) (xy 396.771876 -276.898354)
		)
		(stroke
			(width 0)
			(type solid)
		)
		(fill yes)
		(layer "F.Cu")
		(net "M_E_CPU0_SA_DQ<28>")
	)
	(gr_poly
		(pts
			(xy 396.825724 -273.539458) (xy 396.91818 -273.484086) (xy 396.880842 -273.297396) (xy 396.774162 -273.281648)
			(xy 396.724378 -273.291554) (xy 396.77594 -273.549364)
		)
		(stroke
			(width 0)
			(type solid)
		)
		(fill yes)
		(layer "F.Cu")
		(net "M_E_CPU0_SA_DQ<29>")
	)
	(gr_poly
		(pts
			(xy 396.826232 -267.265404) (xy 396.8623 -267.22959) (xy 396.676372 -267.043662) (xy 396.640304 -267.079476)
			(xy 396.594076 -267.177012) (xy 396.72895 -267.311632)
		)
		(stroke
			(width 0)
			(type solid)
		)
		(fill yes)
		(layer "F.Cu")
		(net "M_E_CPU0_SA_CB<5>")
	)
	(gr_poly
		(pts
			(xy 396.83436 -273.842226) (xy 396.782798 -273.584416) (xy 396.733014 -273.594322) (xy 396.640558 -273.649694)
			(xy 396.677896 -273.836638) (xy 396.784576 -273.852132)
		)
		(stroke
			(width 0)
			(type solid)
		)
		(fill yes)
		(layer "F.Cu")
		(net "M_E_CPU0_SA_DQ<29>")
	)
	(gr_poly
		(pts
			(xy 396.845536 -270.16075) (xy 396.891764 -270.063214) (xy 396.75689 -269.928594) (xy 396.659608 -269.974822)
			(xy 396.62354 -270.010636) (xy 396.809468 -270.196564)
		)
		(stroke
			(width 0)
			(type solid)
		)
		(fill yes)
		(layer "F.Cu")
		(net "M_E_CPU0_SA_CB<3>")
	)
	(gr_poly
		(pts
			(xy 396.856458 -231.57053) (xy 396.81023 -231.473248) (xy 396.774416 -231.43718) (xy 396.588488 -231.623108)
			(xy 396.624302 -231.659176) (xy 396.721838 -231.705404)
		)
		(stroke
			(width 0)
			(type solid)
		)
		(fill yes)
		(layer "F.Cu")
		(net "M_E_CPU0_SB_DQ<11>")
	)
	(gr_poly
		(pts
			(xy 396.866364 -232.424732) (xy 396.820136 -232.327196) (xy 396.784322 -232.291382) (xy 396.598394 -232.47731)
			(xy 396.634208 -232.513124) (xy 396.731744 -232.559352)
		)
		(stroke
			(width 0)
			(type solid)
		)
		(fill yes)
		(layer "F.Cu")
		(net "M_E_CPU0_SB_DQ<10>")
	)
	(gr_poly
		(pts
			(xy 396.878048 -275.355304) (xy 396.970504 -275.299932) (xy 396.933166 -275.112988) (xy 396.826486 -275.097494)
			(xy 396.776448 -275.1074) (xy 396.82801 -275.36521)
		)
		(stroke
			(width 0)
			(type solid)
		)
		(fill yes)
		(layer "F.Cu")
		(net "M_E_CPU0_SA_DQ<30>")
	)
	(gr_poly
		(pts
			(xy 396.886684 -275.657818) (xy 396.835122 -275.400008) (xy 396.785338 -275.409914) (xy 396.692882 -275.46554)
			(xy 396.73022 -275.65223) (xy 396.8369 -275.667724)
		)
		(stroke
			(width 0)
			(type solid)
		)
		(fill yes)
		(layer "F.Cu")
		(net "M_E_CPU0_SA_DQ<30>")
	)
	(gr_poly
		(pts
			(xy 396.893542 -267.620242) (xy 396.93977 -267.522706) (xy 396.80515 -267.388086) (xy 396.707614 -267.434314)
			(xy 396.6718 -267.470382) (xy 396.857474 -267.656056)
		)
		(stroke
			(width 0)
			(type solid)
		)
		(fill yes)
		(layer "F.Cu")
		(net "M_E_CPU0_SA_CB<6>")
	)
	(gr_poly
		(pts
			(xy 396.902686 -266.766802) (xy 396.948914 -266.66952) (xy 396.814294 -266.534646) (xy 396.716758 -266.580874)
			(xy 396.680944 -266.616942) (xy 396.866872 -266.80287)
		)
		(stroke
			(width 0)
			(type solid)
		)
		(fill yes)
		(layer "F.Cu")
		(net "M_E_CPU0_SA_CB<7>")
	)
	(gr_poly
		(pts
			(xy 396.930118 -277.170896) (xy 397.022828 -277.115524) (xy 396.985236 -276.928834) (xy 396.878556 -276.913086)
			(xy 396.828772 -276.923246) (xy 396.880334 -277.181056)
		)
		(stroke
			(width 0)
			(type solid)
		)
		(fill yes)
		(layer "F.Cu")
		(net "M_E_CPU0_SA_DQ<28>")
	)
	(gr_poly
		(pts
			(xy 396.939008 -277.473664) (xy 396.887446 -277.215854) (xy 396.837662 -277.22576) (xy 396.744952 -277.281132)
			(xy 396.78229 -277.468076) (xy 396.889224 -277.48357)
		)
		(stroke
			(width 0)
			(type solid)
		)
		(fill yes)
		(layer "F.Cu")
		(net "M_E_CPU0_SA_DQ<28>")
	)
	(gr_poly
		(pts
			(xy 396.942818 -274.124928) (xy 397.035274 -274.069302) (xy 396.997936 -273.882612) (xy 396.891256 -273.867118)
			(xy 396.841472 -273.877024) (xy 396.893034 -274.134834)
		)
		(stroke
			(width 0)
			(type solid)
		)
		(fill yes)
		(layer "F.Cu")
		(net "M_E_CPU0_SA_DQ<29>")
	)
	(gr_poly
		(pts
			(xy 396.951454 -274.427442) (xy 396.899892 -274.169632) (xy 396.850108 -274.179538) (xy 396.757652 -274.23491)
			(xy 396.79499 -274.421854) (xy 396.90167 -274.437348)
		)
		(stroke
			(width 0)
			(type solid)
		)
		(fill yes)
		(layer "F.Cu")
		(net "M_E_CPU0_SA_DQ<29>")
	)
	(gr_poly
		(pts
			(xy 396.984728 -270.443452) (xy 397.020542 -270.407638) (xy 396.834614 -270.22171) (xy 396.7988 -270.257778)
			(xy 396.752572 -270.35506) (xy 396.887192 -270.489934)
		)
		(stroke
			(width 0)
			(type solid)
		)
		(fill yes)
		(layer "F.Cu")
		(net "M_E_CPU0_SA_CB<3>")
	)
	(gr_poly
		(pts
			(xy 396.98549 -231.22636) (xy 396.949422 -231.190292) (xy 396.85214 -231.144064) (xy 396.717266 -231.278684)
			(xy 396.763494 -231.37622) (xy 396.799562 -231.412034)
		)
		(stroke
			(width 0)
			(type solid)
		)
		(fill yes)
		(layer "F.Cu")
		(net "M_E_CPU0_SB_DQ<11>")
	)
	(gr_poly
		(pts
			(xy 396.995142 -275.94052) (xy 397.087598 -275.885148) (xy 397.05026 -275.698204) (xy 396.94358 -275.68271)
			(xy 396.893542 -275.692616) (xy 396.945358 -275.950426)
		)
		(stroke
			(width 0)
			(type solid)
		)
		(fill yes)
		(layer "F.Cu")
		(net "M_E_CPU0_SA_DQ<30>")
	)
	(gr_poly
		(pts
			(xy 396.995396 -232.080308) (xy 396.959328 -232.044494) (xy 396.862046 -231.998266) (xy 396.727172 -232.132886)
			(xy 396.773654 -232.230422) (xy 396.809468 -232.266236)
		)
		(stroke
			(width 0)
			(type solid)
		)
		(fill yes)
		(layer "F.Cu")
		(net "M_E_CPU0_SB_DQ<10>")
	)
	(gr_poly
		(pts
			(xy 397.003778 -276.243034) (xy 396.952216 -275.985478) (xy 396.902432 -275.995384) (xy 396.809976 -276.050756)
			(xy 396.847314 -276.237446) (xy 396.953994 -276.253194)
		)
		(stroke
			(width 0)
			(type solid)
		)
		(fill yes)
		(layer "F.Cu")
		(net "M_E_CPU0_SA_DQ<30>")
	)
	(gr_poly
		(pts
			(xy 397.007842 -272.894298) (xy 397.100298 -272.838926) (xy 397.06296 -272.651982) (xy 396.95628 -272.636488)
			(xy 396.906496 -272.646394) (xy 396.958058 -272.904204)
		)
		(stroke
			(width 0)
			(type solid)
		)
		(fill yes)
		(layer "F.Cu")
		(net "M_E_CPU0_SA_DQ<31>")
	)
	(gr_poly
		(pts
			(xy 397.016478 -273.196812) (xy 396.964916 -272.939256) (xy 396.915132 -272.949162) (xy 396.822676 -273.004534)
			(xy 396.860014 -273.191224) (xy 396.966694 -273.206972)
		)
		(stroke
			(width 0)
			(type solid)
		)
		(fill yes)
		(layer "F.Cu")
		(net "M_E_CPU0_SA_DQ<31>")
	)
	(gr_poly
		(pts
			(xy 397.032734 -267.903198) (xy 397.068548 -267.86713) (xy 396.88262 -267.681202) (xy 396.846806 -267.71727)
			(xy 396.800578 -267.814552) (xy 396.935198 -267.949426)
		)
		(stroke
			(width 0)
			(type solid)
		)
		(fill yes)
		(layer "F.Cu")
		(net "M_E_CPU0_SA_CB<6>")
	)
	(gr_poly
		(pts
			(xy 397.041878 -267.049758) (xy 397.077946 -267.013944) (xy 396.892018 -266.828016) (xy 396.85595 -266.86383)
			(xy 396.809722 -266.961366) (xy 396.944596 -267.095986)
		)
		(stroke
			(width 0)
			(type solid)
		)
		(fill yes)
		(layer "F.Cu")
		(net "M_E_CPU0_SA_CB<7>")
	)
	(gr_poly
		(pts
			(xy 397.059912 -274.710144) (xy 397.152368 -274.654772) (xy 397.11503 -274.467828) (xy 397.00835 -274.452334)
			(xy 396.958566 -274.46224) (xy 397.010128 -274.72005)
		)
		(stroke
			(width 0)
			(type solid)
		)
		(fill yes)
		(layer "F.Cu")
		(net "M_E_CPU0_SA_DQ<29>")
	)
	(gr_poly
		(pts
			(xy 397.068548 -275.012658) (xy 397.016986 -274.754848) (xy 396.967202 -274.765008) (xy 396.874746 -274.82038)
			(xy 396.912084 -275.00707) (xy 397.018764 -275.022564)
		)
		(stroke
			(width 0)
			(type solid)
		)
		(fill yes)
		(layer "F.Cu")
		(net "M_E_CPU0_SA_DQ<29>")
	)
	(gr_poly
		(pts
			(xy 397.072612 -231.786684) (xy 397.026384 -231.689402) (xy 396.99057 -231.653334) (xy 396.804642 -231.839262)
			(xy 396.840456 -231.87533) (xy 396.937992 -231.921558)
		)
		(stroke
			(width 0)
			(type solid)
		)
		(fill yes)
		(layer "F.Cu")
		(net "M_E_CPU0_SB_DQ<9>")
	)
	(gr_poly
		(pts
			(xy 397.082264 -232.640632) (xy 397.036036 -232.543096) (xy 396.999968 -232.507282) (xy 396.814294 -232.692956)
			(xy 396.850108 -232.729024) (xy 396.947644 -232.775252)
		)
		(stroke
			(width 0)
			(type solid)
		)
		(fill yes)
		(layer "F.Cu")
		(net "M_E_CPU0_SB_DQ<8>")
	)
	(gr_poly
		(pts
			(xy 397.100044 -268.258036) (xy 397.146272 -268.1605) (xy 397.011398 -268.02588) (xy 396.914116 -268.072108)
			(xy 396.878048 -268.107922) (xy 397.063976 -268.29385)
		)
		(stroke
			(width 0)
			(type solid)
		)
		(fill yes)
		(layer "F.Cu")
		(net "M_E_CPU0_SA_CB<4>")
	)
	(gr_poly
		(pts
			(xy 397.109188 -267.404596) (xy 397.155416 -267.30706) (xy 397.020796 -267.17244) (xy 396.92326 -267.218668)
			(xy 396.887446 -267.254736) (xy 397.07312 -267.44041)
		)
		(stroke
			(width 0)
			(type solid)
		)
		(fill yes)
		(layer "F.Cu")
		(net "M_E_CPU0_SA_CB<5>")
	)
	(gr_poly
		(pts
			(xy 397.112236 -276.525736) (xy 397.204692 -276.470364) (xy 397.167354 -276.283674) (xy 397.060674 -276.26818)
			(xy 397.01089 -276.278086) (xy 397.062452 -276.535896)
		)
		(stroke
			(width 0)
			(type solid)
		)
		(fill yes)
		(layer "F.Cu")
		(net "M_E_CPU0_SA_DQ<30>")
	)
	(gr_poly
		(pts
			(xy 397.120872 -276.828504) (xy 397.06931 -276.570694) (xy 397.019526 -276.5806) (xy 396.92707 -276.635972)
			(xy 396.964408 -276.822916) (xy 397.071088 -276.83841)
		)
		(stroke
			(width 0)
			(type solid)
		)
		(fill yes)
		(layer "F.Cu")
		(net "M_E_CPU0_SA_DQ<30>")
	)
	(gr_poly
		(pts
			(xy 397.124936 -273.479514) (xy 397.217392 -273.424142) (xy 397.180054 -273.237452) (xy 397.073374 -273.221958)
			(xy 397.02359 -273.231864) (xy 397.075152 -273.489674)
		)
		(stroke
			(width 0)
			(type solid)
		)
		(fill yes)
		(layer "F.Cu")
		(net "M_E_CPU0_SA_DQ<31>")
	)
	(gr_poly
		(pts
			(xy 397.133572 -273.782282) (xy 397.08201 -273.524472) (xy 397.032226 -273.534378) (xy 396.93977 -273.58975)
			(xy 396.977108 -273.776694) (xy 397.083788 -273.792188)
		)
		(stroke
			(width 0)
			(type solid)
		)
		(fill yes)
		(layer "F.Cu")
		(net "M_E_CPU0_SA_DQ<31>")
	)
	(gr_poly
		(pts
			(xy 397.177006 -275.29536) (xy 397.269462 -275.239988) (xy 397.232124 -275.053298) (xy 397.125444 -275.03755)
			(xy 397.07566 -275.04771) (xy 397.127222 -275.305266)
		)
		(stroke
			(width 0)
			(type solid)
		)
		(fill yes)
		(layer "F.Cu")
		(net "M_E_CPU0_SA_DQ<29>")
	)
	(gr_poly
		(pts
			(xy 397.185642 -275.598128) (xy 397.13408 -275.340318) (xy 397.084296 -275.350224) (xy 396.99184 -275.405596)
			(xy 397.029178 -275.59254) (xy 397.135858 -275.608034)
		)
		(stroke
			(width 0)
			(type solid)
		)
		(fill yes)
		(layer "F.Cu")
		(net "M_E_CPU0_SA_DQ<29>")
	)
	(gr_poly
		(pts
			(xy 397.201644 -231.442514) (xy 397.165576 -231.406446) (xy 397.068294 -231.360218) (xy 396.93342 -231.494838)
			(xy 396.979648 -231.592374) (xy 397.015716 -231.628188)
		)
		(stroke
			(width 0)
			(type solid)
		)
		(fill yes)
		(layer "F.Cu")
		(net "M_E_CPU0_SB_DQ<9>")
	)
	(gr_poly
		(pts
			(xy 397.211042 -232.296208) (xy 397.175228 -232.26014) (xy 397.077692 -232.213912) (xy 396.943072 -232.348786)
			(xy 396.9893 -232.446068) (xy 397.025114 -232.482136)
		)
		(stroke
			(width 0)
			(type solid)
		)
		(fill yes)
		(layer "F.Cu")
		(net "M_E_CPU0_SB_DQ<8>")
	)
	(gr_poly
		(pts
			(xy 397.22933 -277.111206) (xy 397.321786 -277.055834) (xy 397.284448 -276.86889) (xy 397.177768 -276.853396)
			(xy 397.127984 -276.863302) (xy 397.179546 -277.121112)
		)
		(stroke
			(width 0)
			(type solid)
		)
		(fill yes)
		(layer "F.Cu")
		(net "M_E_CPU0_SA_DQ<30>")
	)
	(gr_poly
		(pts
			(xy 397.239236 -268.540738) (xy 397.27505 -268.504924) (xy 397.089122 -268.318996) (xy 397.053308 -268.355064)
			(xy 397.00708 -268.452346) (xy 397.1417 -268.586966)
		)
		(stroke
			(width 0)
			(type solid)
		)
		(fill yes)
		(layer "F.Cu")
		(net "M_E_CPU0_SA_CB<4>")
	)
	(gr_poly
		(pts
			(xy 397.24203 -274.064984) (xy 397.334486 -274.009612) (xy 397.297148 -273.822668) (xy 397.190468 -273.807174)
			(xy 397.14043 -273.81708) (xy 397.192246 -274.07489)
		)
		(stroke
			(width 0)
			(type solid)
		)
		(fill yes)
		(layer "F.Cu")
		(net "M_E_CPU0_SA_DQ<31>")
	)
	(gr_poly
		(pts
			(xy 397.24838 -267.687552) (xy 397.284194 -267.651484) (xy 397.098266 -267.465556) (xy 397.062452 -267.501624)
			(xy 397.016224 -267.598906) (xy 397.150844 -267.73378)
		)
		(stroke
			(width 0)
			(type solid)
		)
		(fill yes)
		(layer "F.Cu")
		(net "M_E_CPU0_SA_CB<5>")
	)
	(gr_poly
		(pts
			(xy 397.250666 -274.367498) (xy 397.199104 -274.109688) (xy 397.14932 -274.119848) (xy 397.056864 -274.17522)
			(xy 397.094202 -274.36191) (xy 397.200882 -274.377404)
		)
		(stroke
			(width 0)
			(type solid)
		)
		(fill yes)
		(layer "F.Cu")
		(net "M_E_CPU0_SA_DQ<31>")
	)
	(gr_poly
		(pts
			(xy 397.278606 -231.148636) (xy 397.232378 -231.0511) (xy 397.19631 -231.015286) (xy 397.010382 -231.20096)
			(xy 397.04645 -231.237028) (xy 397.143732 -231.283256)
		)
		(stroke
			(width 0)
			(type solid)
		)
		(fill yes)
		(layer "F.Cu")
		(net "M_E_CPU0_SB_DQ<11>")
	)
	(gr_poly
		(pts
			(xy 397.288512 -232.002584) (xy 397.242284 -231.905302) (xy 397.20647 -231.869234) (xy 397.020542 -232.055162)
			(xy 397.056356 -232.09123) (xy 397.153892 -232.137458)
		)
		(stroke
			(width 0)
			(type solid)
		)
		(fill yes)
		(layer "F.Cu")
		(net "M_E_CPU0_SB_DQ<10>")
	)
	(gr_poly
		(pts
			(xy 397.2941 -275.88083) (xy 397.386556 -275.825204) (xy 397.349218 -275.638514) (xy 397.242538 -275.62302)
			(xy 397.192754 -275.632926) (xy 397.244316 -275.890736)
		)
		(stroke
			(width 0)
			(type solid)
		)
		(fill yes)
		(layer "F.Cu")
		(net "M_E_CPU0_SA_DQ<29>")
	)
	(gr_poly
		(pts
			(xy 397.302736 -276.183344) (xy 397.251174 -275.925534) (xy 397.20139 -275.93544) (xy 397.108934 -275.990812)
			(xy 397.146272 -276.177756) (xy 397.252952 -276.19325)
		)
		(stroke
			(width 0)
			(type solid)
		)
		(fill yes)
		(layer "F.Cu")
		(net "M_E_CPU0_SA_DQ<29>")
	)
	(gr_poly
		(pts
			(xy 397.31569 -268.04239) (xy 397.361918 -267.944854) (xy 397.227044 -267.810234) (xy 397.129762 -267.856462)
			(xy 397.093694 -267.892276) (xy 397.279622 -268.078204)
		)
		(stroke
			(width 0)
			(type solid)
		)
		(fill yes)
		(layer "F.Cu")
		(net "M_E_CPU0_SA_CB<6>")
	)
	(gr_poly
		(pts
			(xy 397.324834 -267.18895) (xy 397.371062 -267.091414) (xy 397.236442 -266.956794) (xy 397.138906 -267.003022)
			(xy 397.103092 -267.03909) (xy 397.288766 -267.224764)
		)
		(stroke
			(width 0)
			(type solid)
		)
		(fill yes)
		(layer "F.Cu")
		(net "M_E_CPU0_SA_CB<7>")
	)
	(gr_poly
		(pts
			(xy 397.35887 -274.6502) (xy 397.45158 -274.594828) (xy 397.414242 -274.408138) (xy 397.307308 -274.39239)
			(xy 397.257524 -274.402296) (xy 397.309086 -274.660106)
		)
		(stroke
			(width 0)
			(type solid)
		)
		(fill yes)
		(layer "F.Cu")
		(net "M_E_CPU0_SA_DQ<31>")
	)
	(gr_poly
		(pts
			(xy 397.36776 -274.952968) (xy 397.316198 -274.695158) (xy 397.266414 -274.705064) (xy 397.173704 -274.760436)
			(xy 397.211042 -274.94738) (xy 397.317976 -274.962874)
		)
		(stroke
			(width 0)
			(type solid)
		)
		(fill yes)
		(layer "F.Cu")
		(net "M_E_CPU0_SA_DQ<31>")
	)
	(gr_poly
		(pts
			(xy 397.407384 -230.804212) (xy 397.37157 -230.768144) (xy 397.274034 -230.721916) (xy 397.139414 -230.85679)
			(xy 397.185642 -230.954072) (xy 397.221456 -230.99014)
		)
		(stroke
			(width 0)
			(type solid)
		)
		(fill yes)
		(layer "F.Cu")
		(net "M_E_CPU0_SB_DQ<11>")
	)
	(gr_poly
		(pts
			(xy 397.411194 -276.466046) (xy 397.50365 -276.410674) (xy 397.466312 -276.22373) (xy 397.359632 -276.208236)
			(xy 397.309848 -276.218142) (xy 397.36141 -276.475952)
		)
		(stroke
			(width 0)
			(type solid)
		)
		(fill yes)
		(layer "F.Cu")
		(net "M_E_CPU0_SA_DQ<29>")
	)
	(gr_poly
		(pts
			(xy 397.41729 -231.658414) (xy 397.381476 -231.622346) (xy 397.28394 -231.576118) (xy 397.14932 -231.710738)
			(xy 397.195548 -231.808274) (xy 397.231616 -231.844088)
		)
		(stroke
			(width 0)
			(type solid)
		)
		(fill yes)
		(layer "F.Cu")
		(net "M_E_CPU0_SB_DQ<10>")
	)
	(gr_poly
		(pts
			(xy 397.41983 -276.76856) (xy 397.368268 -276.51075) (xy 397.318484 -276.52091) (xy 397.226028 -276.576282)
			(xy 397.263366 -276.762972) (xy 397.370046 -276.778466)
		)
		(stroke
			(width 0)
			(type solid)
		)
		(fill yes)
		(layer "F.Cu")
		(net "M_E_CPU0_SA_DQ<29>")
	)
	(gr_poly
		(pts
			(xy 397.454882 -268.325092) (xy 397.490696 -268.289278) (xy 397.304768 -268.10335) (xy 397.268954 -268.139418)
			(xy 397.222726 -268.2367) (xy 397.357346 -268.37132)
		)
		(stroke
			(width 0)
			(type solid)
		)
		(fill yes)
		(layer "F.Cu")
		(net "M_E_CPU0_SA_CB<6>")
	)
	(gr_poly
		(pts
			(xy 397.464026 -267.471906) (xy 397.49984 -267.435838) (xy 397.313912 -267.24991) (xy 397.278098 -267.285978)
			(xy 397.23187 -267.38326) (xy 397.36649 -267.518134)
		)
		(stroke
			(width 0)
			(type solid)
		)
		(fill yes)
		(layer "F.Cu")
		(net "M_E_CPU0_SA_CB<7>")
	)
	(gr_poly
		(pts
			(xy 397.475964 -275.23567) (xy 397.568674 -275.180044) (xy 397.531082 -274.993354) (xy 397.424402 -274.97786)
			(xy 397.374618 -274.987766) (xy 397.42618 -275.245576)
		)
		(stroke
			(width 0)
			(type solid)
		)
		(fill yes)
		(layer "F.Cu")
		(net "M_E_CPU0_SA_DQ<31>")
	)
	(gr_poly
		(pts
			(xy 397.484854 -275.538184) (xy 397.433292 -275.280374) (xy 397.383254 -275.29028) (xy 397.290798 -275.345652)
			(xy 397.328136 -275.532596) (xy 397.434816 -275.54809)
		)
		(stroke
			(width 0)
			(type solid)
		)
		(fill yes)
		(layer "F.Cu")
		(net "M_E_CPU0_SA_DQ<31>")
	)
	(gr_poly
		(pts
			(xy 397.49476 -231.36479) (xy 397.448532 -231.267254) (xy 397.412718 -231.23144) (xy 397.22679 -231.417368)
			(xy 397.262604 -231.453182) (xy 397.36014 -231.49941)
		)
		(stroke
			(width 0)
			(type solid)
		)
		(fill yes)
		(layer "F.Cu")
		(net "M_E_CPU0_SB_DQ<9>")
	)
	(gr_poly
		(pts
			(xy 397.504412 -232.218484) (xy 397.458184 -232.120948) (xy 397.422116 -232.085134) (xy 397.236188 -232.271062)
			(xy 397.272256 -232.306876) (xy 397.369538 -232.353104)
		)
		(stroke
			(width 0)
			(type solid)
		)
		(fill yes)
		(layer "F.Cu")
		(net "M_E_CPU0_SB_DQ<8>")
	)
	(gr_poly
		(pts
			(xy 397.531336 -267.826744) (xy 397.577564 -267.729208) (xy 397.44269 -267.594588) (xy 397.345408 -267.640816)
			(xy 397.30934 -267.67663) (xy 397.495268 -267.862558)
		)
		(stroke
			(width 0)
			(type solid)
		)
		(fill yes)
		(layer "F.Cu")
		(net "M_E_CPU0_SA_CB<5>")
	)
	(gr_poly
		(pts
			(xy 397.593058 -275.820886) (xy 397.685514 -275.765514) (xy 397.648176 -275.57857) (xy 397.541496 -275.563076)
			(xy 397.491712 -275.572982) (xy 397.543274 -275.830792)
		)
		(stroke
			(width 0)
			(type solid)
		)
		(fill yes)
		(layer "F.Cu")
		(net "M_E_CPU0_SA_DQ<31>")
	)
	(gr_poly
		(pts
			(xy 397.601694 -276.1234) (xy 397.550132 -275.86559) (xy 397.500348 -275.87575) (xy 397.407892 -275.931122)
			(xy 397.44523 -276.117812) (xy 397.55191 -276.13356)
		)
		(stroke
			(width 0)
			(type solid)
		)
		(fill yes)
		(layer "F.Cu")
		(net "M_E_CPU0_SA_DQ<31>")
	)
	(gr_poly
		(pts
			(xy 397.623538 -231.020366) (xy 397.587724 -230.984552) (xy 397.490188 -230.938324) (xy 397.355568 -231.072944)
			(xy 397.401796 -231.170226) (xy 397.437864 -231.206294)
		)
		(stroke
			(width 0)
			(type solid)
		)
		(fill yes)
		(layer "F.Cu")
		(net "M_E_CPU0_SB_DQ<9>")
	)
	(gr_poly
		(pts
			(xy 397.670528 -268.109446) (xy 397.706342 -268.073632) (xy 397.520414 -267.887704) (xy 397.4846 -267.923772)
			(xy 397.438372 -268.021054) (xy 397.572992 -268.155674)
		)
		(stroke
			(width 0)
			(type solid)
		)
		(fill yes)
		(layer "F.Cu")
		(net "M_E_CPU0_SA_CB<5>")
	)
	(gr_poly
		(pts
			(xy 397.700754 -230.726488) (xy 397.654272 -230.628952) (xy 397.618458 -230.593138) (xy 397.43253 -230.779066)
			(xy 397.468598 -230.81488) (xy 397.56588 -230.861108)
		)
		(stroke
			(width 0)
			(type solid)
		)
		(fill yes)
		(layer "F.Cu")
		(net "M_E_CPU0_SB_DQ<11>")
	)
	(gr_poly
		(pts
			(xy 397.710152 -276.406102) (xy 397.802608 -276.35073) (xy 397.76527 -276.16404) (xy 397.65859 -276.148292)
			(xy 397.608806 -276.158452) (xy 397.660368 -276.416008)
		)
		(stroke
			(width 0)
			(type solid)
		)
		(fill yes)
		(layer "F.Cu")
		(net "M_E_CPU0_SA_DQ<31>")
	)
	(gr_poly
		(pts
			(xy 397.718788 -276.70887) (xy 397.667226 -276.45106) (xy 397.617442 -276.460966) (xy 397.524986 -276.516338)
			(xy 397.562324 -276.703282) (xy 397.669004 -276.718776)
		)
		(stroke
			(width 0)
			(type solid)
		)
		(fill yes)
		(layer "F.Cu")
		(net "M_E_CPU0_SA_DQ<31>")
	)
	(gr_poly
		(pts
			(xy 397.839438 -231.236266) (xy 397.803624 -231.200198) (xy 397.706088 -231.15397) (xy 397.571468 -231.288844)
			(xy 397.617696 -231.386126) (xy 397.65351 -231.422194)
		)
		(stroke
			(width 0)
			(type solid)
		)
		(fill yes)
		(layer "F.Cu")
		(net "M_E_CPU0_SB_DQ<10>")
	)
	(gr_poly
		(pts
			(xy 397.916908 -230.942642) (xy 397.87068 -230.84536) (xy 397.834612 -230.809292) (xy 397.648938 -230.99522)
			(xy 397.684752 -231.031288) (xy 397.782288 -231.077516)
		)
		(stroke
			(width 0)
			(type solid)
		)
		(fill yes)
		(layer "F.Cu")
		(net "M_E_CPU0_SB_DQ<9>")
	)
	(gr_poly
		(pts
			(xy 398.045686 -230.598472) (xy 398.009872 -230.562404) (xy 397.912336 -230.516176) (xy 397.777716 -230.650796)
			(xy 397.823944 -230.748332) (xy 397.859758 -230.784146)
		)
		(stroke
			(width 0)
			(type solid)
		)
		(fill yes)
		(layer "F.Cu")
		(net "M_E_CPU0_SB_DQ<9>")
	)
	(gr_poly
		(pts
			(xy 133.289294 -77.277214) (xy 133.048502 -77.036422) (xy 131.172712 -77.036422) (xy 130.8989 -77.310234)
			(xy 130.8989 -78.256384) (xy 130.94208 -78.299564) (xy 133.289294 -78.299564)
		)
		(stroke
			(width 0)
			(type solid)
		)
		(fill yes)
		(layer "F.Cu")
		(net "P3V3_AUX")
	)
	(gr_poly
		(pts
			(xy 19.78914 -113.147348) (xy 19.78914 -111.775748) (xy 19.61134 -111.597948) (xy 18.29054 -111.597948)
			(xy 18.18894 -111.699548) (xy 18.18894 -113.299748) (xy 18.36674 -113.477548) (xy 19.45894 -113.477548)
		)
		(stroke
			(width 0)
			(type solid)
		)
		(fill yes)
		(layer "F.Cu")
		(net "P3V3_AUX")
	)
	(gr_poly
		(pts
			(xy 27.00528 -103.393748) (xy 27.00528 -101.564948) (xy 26.87828 -101.437948) (xy 25.76068 -101.437948)
			(xy 25.45588 -101.742748) (xy 25.45588 -103.495348) (xy 25.55748 -103.596948) (xy 26.80208 -103.596948)
		)
		(stroke
			(width 0)
			(type solid)
		)
		(fill yes)
		(layer "F.Cu")
		(net "GND")
	)
	(gr_poly
		(pts
			(xy 40.0431 -183.411368) (xy 40.0431 -175.630078) (xy 38.846506 -174.433484) (xy 37.06368 -174.433484)
			(xy 36.964112 -174.533052) (xy 36.964112 -183.572912) (xy 37.01415 -183.622696) (xy 39.831772 -183.622696)
		)
		(stroke
			(width 0)
			(type solid)
		)
		(fill yes)
		(layer "F.Cu")
		(net "GND")
	)
	(gr_poly
		(pts
			(xy 43.765724 -350.957134) (xy 43.765724 -346.305378) (xy 43.626278 -346.165932) (xy 39.471092 -346.165932)
			(xy 39.359332 -346.277692) (xy 39.359332 -350.943926) (xy 39.410132 -350.994726) (xy 43.728132 -350.994726)
		)
		(stroke
			(width 0)
			(type solid)
		)
		(fill yes)
		(layer "F.Cu")
		(net "SW_PVCCFA_EHV_FIVRA_CPU1_SW4")
	)
	(gr_poly
		(pts
			(xy 53.454046 -350.957134) (xy 53.454046 -346.305378) (xy 53.3146 -346.165932) (xy 49.159414 -346.165932)
			(xy 49.047654 -346.277692) (xy 49.047654 -350.943926) (xy 49.098454 -350.994726) (xy 53.416454 -350.994726)
		)
		(stroke
			(width 0)
			(type solid)
		)
		(fill yes)
		(layer "F.Cu")
		(net "SW_PVCCFA_EHV_FIVRA_CPU1_SW2")
	)
	(gr_poly
		(pts
			(xy 61.08319 -167.23868) (xy 61.08319 -162.98037) (xy 61.03239 -162.92957) (xy 57.520078 -162.92957)
			(xy 57.469278 -162.98037) (xy 57.469278 -167.24757) (xy 57.520078 -167.29837) (xy 61.0235 -167.29837)
		)
		(stroke
			(width 0)
			(type solid)
		)
		(fill yes)
		(layer "F.Cu")
		(net "SW_PVCCD_HV_CPU1_SW1")
	)
	(gr_poly
		(pts
			(xy 61.08319 -158.61157) (xy 61.08319 -154.34437) (xy 61.03239 -154.29357) (xy 57.520078 -154.29357)
			(xy 57.469278 -154.34437) (xy 57.469278 -158.61157) (xy 57.520078 -158.66237) (xy 61.03239 -158.66237)
		)
		(stroke
			(width 0)
			(type solid)
		)
		(fill yes)
		(layer "F.Cu")
		(net "SW_PVCCINFAON_CPU1_SW1")
	)
	(gr_poly
		(pts
			(xy 61.08319 -149.97557) (xy 61.08319 -145.70837) (xy 61.03239 -145.65757) (xy 57.520078 -145.65757)
			(xy 57.469278 -145.70837) (xy 57.469278 -149.97557) (xy 57.520078 -150.02637) (xy 61.03239 -150.02637)
		)
		(stroke
			(width 0)
			(type solid)
		)
		(fill yes)
		(layer "F.Cu")
		(net "SW_PVCCINFAON_CPU1_SW2")
	)
	(gr_poly
		(pts
			(xy 64.388238 -26.680922) (xy 64.388238 -24.471122) (xy 64.261238 -24.344122) (xy 63.524638 -24.344122)
			(xy 63.474092 -24.394668) (xy 63.474092 -26.706576) (xy 63.600838 -26.833322) (xy 64.235838 -26.833322)
		)
		(stroke
			(width 0)
			(type solid)
		)
		(fill yes)
		(layer "F.Cu")
		(net "GND")
	)
	(gr_poly
		(pts
			(xy 65.78346 -29.655008) (xy 65.78346 -28.997148) (xy 65.68948 -28.903168) (xy 63.54064 -28.903168)
			(xy 63.3222 -29.121608) (xy 63.3222 -29.677868) (xy 63.39078 -29.746448) (xy 65.69202 -29.746448)
		)
		(stroke
			(width 0)
			(type solid)
		)
		(fill yes)
		(layer "F.Cu")
		(net "P12V_OCP_FLTB_2")
	)
	(gr_poly
		(pts
			(xy 82.30108 -45.082968) (xy 82.30108 -42.464228) (xy 81.534 -41.697148) (xy 77.3684 -41.697148)
			(xy 76.84008 -42.225468) (xy 76.84008 -44.981368) (xy 77.31506 -45.456348) (xy 81.9277 -45.456348)
		)
		(stroke
			(width 0)
			(type solid)
		)
		(fill yes)
		(layer "F.Cu")
		(net "P3V3_OCP_V3_2")
	)
	(gr_poly
		(pts
			(xy 82.94116 -340.204044) (xy 82.94116 -336.707988) (xy 82.89544 -336.662268) (xy 78.46568 -336.662268)
			(xy 78.41488 -336.713068) (xy 78.41488 -340.18728) (xy 78.55839 -340.33079) (xy 82.814414 -340.33079)
		)
		(stroke
			(width 0)
			(type solid)
		)
		(fill yes)
		(layer "F.Cu")
		(net "SW_PVCCIN_CPU1_SW7")
	)
	(gr_poly
		(pts
			(xy 104.766618 -239.97666) (xy 104.766618 -238.468916) (xy 104.624378 -238.326676) (xy 103.36911 -238.326676)
			(xy 102.707694 -238.988092) (xy 102.707694 -239.58804) (xy 103.274114 -240.15446) (xy 104.588818 -240.15446)
		)
		(stroke
			(width 0)
			(type solid)
		)
		(fill yes)
		(layer "F.Cu")
		(net "PVCCFA_EHV_FIVRA_CPU1")
	)
	(gr_poly
		(pts
			(xy 105.018586 -297.20286) (xy 105.018586 -292.81247) (xy 104.876346 -292.67023) (xy 103.521256 -292.67023)
			(xy 103.348536 -292.84295) (xy 103.348536 -297.17111) (xy 103.521256 -297.34383) (xy 104.877616 -297.34383)
		)
		(stroke
			(width 0)
			(type solid)
		)
		(fill yes)
		(layer "F.Cu")
		(net "GND")
	)
	(gr_poly
		(pts
			(xy 107.623356 -261.328154) (xy 107.623356 -260.528562) (xy 107.60837 -260.513576) (xy 104.072436 -260.513576)
			(xy 103.985568 -260.600444) (xy 103.985568 -261.661402) (xy 104.18953 -261.865364) (xy 107.086146 -261.865364)
		)
		(stroke
			(width 0)
			(type solid)
		)
		(fill yes)
		(layer "F.Cu")
		(net "PVCCFA_EHV_FIVRA_CPU1")
	)
	(gr_poly
		(pts
			(xy 108.880656 -237.989618) (xy 108.880656 -237.137702) (xy 108.815632 -237.072678) (xy 106.247946 -237.072678)
			(xy 106.048302 -237.272322) (xy 106.048302 -237.99292) (xy 106.120184 -238.064802) (xy 108.805726 -238.064802)
		)
		(stroke
			(width 0)
			(type solid)
		)
		(fill yes)
		(layer "F.Cu")
		(net "GND")
	)
	(gr_poly
		(pts
			(xy 110.813596 -361.032806) (xy 110.813596 -356.664006) (xy 110.762796 -356.613206) (xy 106.393996 -356.613206)
			(xy 106.343196 -356.664006) (xy 106.343196 -361.032806) (xy 106.393996 -361.083606) (xy 110.762796 -361.083606)
		)
		(stroke
			(width 0)
			(type solid)
		)
		(fill yes)
		(layer "F.Cu")
		(net "GND")
	)
	(gr_poly
		(pts
			(xy 111.369856 -297.27271) (xy 111.369856 -292.82771) (xy 111.188246 -292.6461) (xy 109.105446 -292.6461)
			(xy 108.925106 -292.82644) (xy 108.925106 -297.18254) (xy 109.217206 -297.47464) (xy 111.167926 -297.47464)
		)
		(stroke
			(width 0)
			(type solid)
		)
		(fill yes)
		(layer "F.Cu")
		(net "GND")
	)
	(gr_poly
		(pts
			(xy 117.712236 -297.28033) (xy 117.712236 -292.82009) (xy 117.538246 -292.6461) (xy 115.455446 -292.6461)
			(xy 115.275106 -292.82644) (xy 115.275106 -297.18254) (xy 115.567206 -297.47464) (xy 117.517926 -297.47464)
		)
		(stroke
			(width 0)
			(type solid)
		)
		(fill yes)
		(layer "F.Cu")
		(net "GND")
	)
	(gr_poly
		(pts
			(xy 120.08231 -237.801404) (xy 120.08231 -236.053884) (xy 119.614442 -235.586016) (xy 116.495068 -235.586016)
			(xy 116.190014 -235.89107) (xy 116.190014 -237.814866) (xy 116.41328 -238.037878) (xy 119.845836 -238.037878)
		)
		(stroke
			(width 0)
			(type solid)
		)
		(fill yes)
		(layer "F.Cu")
		(net "PVCCINFAON_CPU1")
	)
	(gr_poly
		(pts
			(xy 121.247662 -262.412988) (xy 121.247662 -260.539992) (xy 121.175272 -260.467602) (xy 119.153178 -260.467602)
			(xy 118.963694 -260.657086) (xy 118.963694 -262.449564) (xy 119.07139 -262.55726) (xy 121.10339 -262.55726)
		)
		(stroke
			(width 0)
			(type solid)
		)
		(fill yes)
		(layer "F.Cu")
		(net "PVCCINFAON_CPU1")
	)
	(gr_poly
		(pts
			(xy 131.840478 -334.535526) (xy 131.840478 -331.075284) (xy 131.627626 -330.862432) (xy 127.614426 -330.862432)
			(xy 127.434086 -331.042772) (xy 127.434086 -334.522318) (xy 127.484886 -334.573118) (xy 131.802886 -334.573118)
		)
		(stroke
			(width 0)
			(type solid)
		)
		(fill yes)
		(layer "F.Cu")
		(net "SW_PVCCIN_CPU1_SW5")
	)
	(gr_poly
		(pts
			(xy 170.37812 -39.098728) (xy 170.37812 -37.015928) (xy 169.92346 -36.561268) (xy 168.18356 -36.561268)
			(xy 167.77208 -36.972748) (xy 167.77208 -39.023798) (xy 167.94861 -39.200328) (xy 170.27652 -39.200328)
		)
		(stroke
			(width 0)
			(type solid)
		)
		(fill yes)
		(layer "F.Cu")
		(net "P3V3_M2_0")
	)
	(gr_poly
		(pts
			(xy 174.22495 -350.963484) (xy 174.22495 -346.311728) (xy 174.085504 -346.172282) (xy 169.930318 -346.172282)
			(xy 169.818558 -346.284042) (xy 169.818558 -350.950276) (xy 169.869358 -351.001076) (xy 174.187358 -351.001076)
		)
		(stroke
			(width 0)
			(type solid)
		)
		(fill yes)
		(layer "F.Cu")
		(net "SW_PVCCFA_EHV_FIVRA_CPU1_SW1")
	)
	(gr_poly
		(pts
			(xy 178.55946 -38.567868) (xy 178.55946 -36.606988) (xy 178.054 -36.101528) (xy 174.01286 -36.101528)
			(xy 173.48962 -36.624768) (xy 173.48962 -38.730428) (xy 173.73854 -38.979348) (xy 178.14798 -38.979348)
		)
		(stroke
			(width 0)
			(type solid)
		)
		(fill yes)
		(layer "F.Cu")
		(net "GND")
	)
	(gr_poly
		(pts
			(xy 183.913272 -350.963484) (xy 183.913272 -346.311728) (xy 183.773826 -346.172282) (xy 179.61864 -346.172282)
			(xy 179.50688 -346.284042) (xy 179.50688 -350.950276) (xy 179.55768 -351.001076) (xy 183.87568 -351.001076)
		)
		(stroke
			(width 0)
			(type solid)
		)
		(fill yes)
		(layer "F.Cu")
		(net "SW_PVCCFA_EHV_FIVRA_CPU1_SW3")
	)
	(gr_poly
		(pts
			(xy 184.81802 -402.11756) (xy 184.81802 -401.09648) (xy 184.74436 -401.02282) (xy 183.26862 -401.02282)
			(xy 183.20766 -401.08378) (xy 183.20766 -402.08962) (xy 183.30418 -402.18614) (xy 184.74944 -402.18614)
		)
		(stroke
			(width 0)
			(type solid)
		)
		(fill yes)
		(layer "F.Cu")
		(net "HSC_VDD_R")
	)
	(gr_poly
		(pts
			(xy 202.97648 -33.746948) (xy 202.97648 -30.876748) (xy 202.13828 -30.038548) (xy 198.22668 -30.038548)
			(xy 197.69328 -30.571948) (xy 197.69328 -34.254948) (xy 197.84568 -34.407348) (xy 202.31608 -34.407348)
		)
		(stroke
			(width 0)
			(type solid)
		)
		(fill yes)
		(layer "F.Cu")
		(net "P12V_SCM")
	)
	(gr_poly
		(pts
			(xy 203.05268 -38.674548) (xy 203.05268 -36.109148) (xy 202.74788 -35.804348) (xy 197.69328 -35.804348)
			(xy 197.46468 -36.032948) (xy 197.46468 -38.014148) (xy 198.48068 -39.030148) (xy 202.69708 -39.030148)
		)
		(stroke
			(width 0)
			(type solid)
		)
		(fill yes)
		(layer "F.Cu")
		(net "P12V_SCM_R")
	)
	(gr_poly
		(pts
			(xy 233.41076 -45.651166) (xy 233.41076 -42.125646) (xy 233.26852 -41.983406) (xy 231.20096 -41.983406)
			(xy 231.04348 -42.140886) (xy 231.04348 -45.734986) (xy 231.10444 -45.795946) (xy 233.26598 -45.795946)
		)
		(stroke
			(width 0)
			(type solid)
		)
		(fill yes)
		(layer "F.Cu")
		(net "GND")
	)
	(gr_poly
		(pts
			(xy 238.88954 -389.47598) (xy 238.88954 -386.72516) (xy 238.74222 -386.57784) (xy 234.30484 -386.57784)
			(xy 233.82732 -387.05536) (xy 233.82732 -389.56996) (xy 233.95178 -389.69442) (xy 238.6711 -389.69442)
		)
		(stroke
			(width 0)
			(type solid)
		)
		(fill yes)
		(layer "F.Cu")
		(net "GND")
	)
	(gr_poly
		(pts
			(xy 252.80493 -54.438042) (xy 252.80493 -53.803042) (xy 252.65253 -53.650642) (xy 250.44273 -53.650642)
			(xy 250.31573 -53.777642) (xy 250.31573 -54.514242) (xy 250.39193 -54.590442) (xy 252.65253 -54.590442)
		)
		(stroke
			(width 0)
			(type solid)
		)
		(fill yes)
		(layer "F.Cu")
		(net "GND")
	)
	(gr_poly
		(pts
			(xy 255.72593 -56.038242) (xy 255.72593 -55.098442) (xy 255.62433 -54.996842) (xy 254.02413 -54.996842)
			(xy 253.99873 -55.022242) (xy 253.99873 -56.038242) (xy 254.17653 -56.216042) (xy 255.54813 -56.216042)
		)
		(stroke
			(width 0)
			(type solid)
		)
		(fill yes)
		(layer "F.Cu")
		(net "P3V3_AUX")
	)
	(gr_poly
		(pts
			(xy 257.381502 -79.621126) (xy 257.381502 -76.942442) (xy 257.25247 -76.81341) (xy 253.986538 -76.81341)
			(xy 253.69139 -77.108558) (xy 253.69139 -79.676498) (xy 254.060452 -80.04556) (xy 256.957068 -80.04556)
		)
		(stroke
			(width 0)
			(type solid)
		)
		(fill yes)
		(layer "F.Cu")
		(net "GND")
	)
	(gr_poly
		(pts
			(xy 257.83159 -96.213168) (xy 257.734562 -96.11614) (xy 257.734562 -95.485712) (xy 257.645662 -95.485712)
			(xy 257.645662 -96.09582) (xy 257.52679 -96.214692) (xy 257.52679 -96.676718) (xy 257.83159 -96.676718)
		)
		(stroke
			(width 0)
			(type solid)
		)
		(fill yes)
		(layer "F.Cu")
		(net "P3V3_AUX_CLK_GEN_VDD_CK440")
	)
	(gr_poly
		(pts
			(xy 259.146548 -97.096326) (xy 259.890768 -97.096326) (xy 259.890768 -97.007426) (xy 259.126482 -97.007426)
			(xy 259.035042 -96.915986) (xy 258.549648 -96.915986) (xy 258.549648 -97.220786) (xy 259.022596 -97.220786)
		)
		(stroke
			(width 0)
			(type solid)
		)
		(fill yes)
		(layer "F.Cu")
		(net "P3V3_AUX_CLK_GEN_VDD_CK440")
	)
	(gr_poly
		(pts
			(xy 259.150612 -101.61016) (xy 259.890768 -101.61016) (xy 259.890768 -101.52126) (xy 259.142484 -101.52126)
			(xy 259.037328 -101.416104) (xy 258.549648 -101.416104) (xy 258.549648 -101.720904) (xy 259.039868 -101.720904)
		)
		(stroke
			(width 0)
			(type solid)
		)
		(fill yes)
		(layer "F.Cu")
		(net "P3V3_AUX_CLK_GEN_VDDMXCK_CK440")
	)
	(gr_poly
		(pts
			(xy 260.07822 -38.120066) (xy 260.07822 -36.608766) (xy 260.0198 -36.550346) (xy 256.90068 -36.550346)
			(xy 256.67208 -36.778946) (xy 256.67208 -38.125146) (xy 256.90068 -38.353746) (xy 259.84454 -38.353746)
		)
		(stroke
			(width 0)
			(type solid)
		)
		(fill yes)
		(layer "F.Cu")
		(net "GND")
	)
	(gr_poly
		(pts
			(xy 266.45108 -93.843348) (xy 266.45108 -92.141548) (xy 265.93038 -91.620848) (xy 263.97458 -91.620848)
			(xy 263.832086 -91.763342) (xy 263.832086 -94.020132) (xy 263.918446 -94.106492) (xy 266.187936 -94.106492)
		)
		(stroke
			(width 0)
			(type solid)
		)
		(fill yes)
		(layer "F.Cu")
		(net "P3V3_AUX_CLK_GEN_VDDA100M_CK440")
	)
	(gr_poly
		(pts
			(xy 290.986718 -360.1847) (xy 290.986718 -355.532944) (xy 290.847272 -355.393498) (xy 286.692086 -355.393498)
			(xy 286.580326 -355.505258) (xy 286.580326 -360.171492) (xy 286.631126 -360.222292) (xy 290.949126 -360.222292)
		)
		(stroke
			(width 0)
			(type solid)
		)
		(fill yes)
		(layer "F.Cu")
		(net "SW_PVCCFA_EHV_FIVRA_CPU0_SW4")
	)
	(gr_poly
		(pts
			(xy 300.67504 -360.1847) (xy 300.67504 -355.532944) (xy 300.535594 -355.393498) (xy 296.380408 -355.393498)
			(xy 296.268648 -355.505258) (xy 296.268648 -360.171492) (xy 296.319448 -360.222292) (xy 300.637448 -360.222292)
		)
		(stroke
			(width 0)
			(type solid)
		)
		(fill yes)
		(layer "F.Cu")
		(net "SW_PVCCFA_EHV_FIVRA_CPU0_SW2")
	)
	(gr_poly
		(pts
			(xy 304.292 -52.288948) (xy 304.292 -45.684948) (xy 304.165 -45.557948) (xy 302.9204 -45.557948)
			(xy 302.768 -45.710348) (xy 302.768 -52.288948) (xy 302.895 -52.415948) (xy 304.165 -52.415948)
		)
		(stroke
			(width 0)
			(type solid)
		)
		(fill yes)
		(layer "F.Cu")
		(net "GND")
	)
	(gr_poly
		(pts
			(xy 352.706432 -239.976406) (xy 352.706432 -238.468662) (xy 352.564192 -238.326422) (xy 351.308924 -238.326422)
			(xy 350.647508 -238.987838) (xy 350.647508 -239.587786) (xy 351.213928 -240.154206) (xy 352.528632 -240.154206)
		)
		(stroke
			(width 0)
			(type solid)
		)
		(fill yes)
		(layer "F.Cu")
		(net "PVCCFA_EHV_FIVRA_CPU0")
	)
	(gr_poly
		(pts
			(xy 353.048316 -297.333416) (xy 353.048316 -292.837616) (xy 352.946716 -292.736016) (xy 351.473516 -292.736016)
			(xy 351.346516 -292.863016) (xy 351.346516 -297.231816) (xy 351.524316 -297.409616) (xy 352.972116 -297.409616)
		)
		(stroke
			(width 0)
			(type solid)
		)
		(fill yes)
		(layer "F.Cu")
		(net "GND")
	)
	(gr_poly
		(pts
			(xy 355.56317 -261.3279) (xy 355.56317 -260.528308) (xy 355.548184 -260.513322) (xy 352.01225 -260.513322)
			(xy 351.925382 -260.60019) (xy 351.925382 -261.661148) (xy 352.129344 -261.86511) (xy 355.02596 -261.86511)
		)
		(stroke
			(width 0)
			(type solid)
		)
		(fill yes)
		(layer "F.Cu")
		(net "PVCCFA_EHV_FIVRA_CPU0")
	)
	(gr_poly
		(pts
			(xy 356.82047 -237.989364) (xy 356.82047 -237.137448) (xy 356.755446 -237.072424) (xy 354.18776 -237.072424)
			(xy 353.988116 -237.272068) (xy 353.988116 -237.992666) (xy 354.059998 -238.064548) (xy 356.74554 -238.064548)
		)
		(stroke
			(width 0)
			(type solid)
		)
		(fill yes)
		(layer "F.Cu")
		(net "GND")
	)
	(gr_poly
		(pts
			(xy 368.022124 -237.80115) (xy 368.022124 -236.05363) (xy 367.554256 -235.585762) (xy 364.434882 -235.585762)
			(xy 364.129828 -235.890816) (xy 364.129828 -237.814612) (xy 364.353094 -238.037624) (xy 367.78565 -238.037624)
		)
		(stroke
			(width 0)
			(type solid)
		)
		(fill yes)
		(layer "F.Cu")
		(net "PVCCINFAON_CPU0")
	)
	(gr_poly
		(pts
			(xy 369.187476 -262.412734) (xy 369.187476 -260.539738) (xy 369.115086 -260.467348) (xy 367.092992 -260.467348)
			(xy 366.903508 -260.656832) (xy 366.903508 -262.44931) (xy 367.011204 -262.557006) (xy 369.043204 -262.557006)
		)
		(stroke
			(width 0)
			(type solid)
		)
		(fill yes)
		(layer "F.Cu")
		(net "PVCCINFAON_CPU0")
	)
	(gr_poly
		(pts
			(xy 393.598146 -79.612998) (xy 393.598146 -76.818744) (xy 393.427966 -76.648564) (xy 391.426446 -76.648564)
			(xy 391.149332 -76.925678) (xy 391.149332 -79.821532) (xy 391.411714 -80.083914) (xy 393.12723 -80.083914)
		)
		(stroke
			(width 0)
			(type solid)
		)
		(fill yes)
		(layer "F.Cu")
		(net "P12V_AUX")
	)
	(gr_poly
		(pts
			(xy 406.43556 -189.090808) (xy 406.43556 -186.517788) (xy 405.64816 -185.730388) (xy 402.73986 -185.730388)
			(xy 402.52396 -185.946288) (xy 402.52396 -189.695328) (xy 402.717 -189.888368) (xy 405.638 -189.888368)
		)
		(stroke
			(width 0)
			(type solid)
		)
		(fill yes)
		(layer "F.Cu")
		(net "PVNN_TERM_CPU0")
	)
	(gr_poly
		(pts
			(xy 413.439864 -181.591458) (xy 413.439864 -177.324258) (xy 413.389064 -177.273458) (xy 409.876752 -177.273458)
			(xy 409.825952 -177.324258) (xy 409.825952 -181.591458) (xy 409.876752 -181.642258) (xy 413.389064 -181.642258)
		)
		(stroke
			(width 0)
			(type solid)
		)
		(fill yes)
		(layer "F.Cu")
		(net "SW_PVCCINFAON_CPU0_SW2")
	)
	(gr_poly
		(pts
			(xy 413.439864 -172.955458) (xy 413.439864 -168.688258) (xy 413.389064 -168.637458) (xy 409.876752 -168.637458)
			(xy 409.825952 -168.688258) (xy 409.825952 -172.955458) (xy 409.876752 -173.006258) (xy 413.389064 -173.006258)
		)
		(stroke
			(width 0)
			(type solid)
		)
		(fill yes)
		(layer "F.Cu")
		(net "SW_PVCCINFAON_CPU0_SW1")
	)
	(gr_poly
		(pts
			(xy 413.439864 -164.319458) (xy 413.439864 -160.052258) (xy 413.389064 -160.001458) (xy 409.876752 -160.001458)
			(xy 409.825952 -160.052258) (xy 409.825952 -164.319458) (xy 409.876752 -164.370258) (xy 413.389064 -164.370258)
		)
		(stroke
			(width 0)
			(type solid)
		)
		(fill yes)
		(layer "F.Cu")
		(net "SW_PVCCD_HV_CPU0_SW1")
	)
	(gr_poly
		(pts
			(xy 416.390328 -155.11272) (xy 416.390328 -151.298402) (xy 416.277552 -151.185626) (xy 411.992318 -151.185626)
			(xy 411.824678 -151.353266) (xy 411.824678 -155.04668) (xy 412.114238 -155.33624) (xy 416.166808 -155.33624)
		)
		(stroke
			(width 0)
			(type solid)
		)
		(fill yes)
		(layer "F.Cu")
		(net "SW_PVCCFA_EHV_CPU0_SW1")
	)
	(gr_poly
		(pts
			(xy 418.361114 -359.496868) (xy 418.361114 -354.845112) (xy 418.221668 -354.705666) (xy 414.066482 -354.705666)
			(xy 413.954722 -354.817426) (xy 413.954722 -359.48366) (xy 414.005522 -359.53446) (xy 418.323522 -359.53446)
		)
		(stroke
			(width 0)
			(type solid)
		)
		(fill yes)
		(layer "F.Cu")
		(net "SW_PVCCFA_EHV_FIVRA_CPU0_SW1")
	)
	(gr_poly
		(pts
			(xy 427.559216 -138.21791) (xy 427.559216 -134.61111) (xy 427.508416 -134.56031) (xy 423.901616 -134.56031)
			(xy 423.871136 -134.591044) (xy 423.871136 -138.23823) (xy 423.901616 -138.26871) (xy 427.508416 -138.26871)
		)
		(stroke
			(width 0)
			(type solid)
		)
		(fill yes)
		(layer "F.Cu")
		(net "GND")
	)
	(gr_poly
		(pts
			(xy 428.049436 -359.496868) (xy 428.049436 -354.845112) (xy 427.90999 -354.705666) (xy 423.754804 -354.705666)
			(xy 423.643044 -354.817426) (xy 423.643044 -359.48366) (xy 423.693844 -359.53446) (xy 428.011844 -359.53446)
		)
		(stroke
			(width 0)
			(type solid)
		)
		(fill yes)
		(layer "F.Cu")
		(net "SW_PVCCFA_EHV_FIVRA_CPU0_SW3")
	)
	(gr_poly
		(pts
			(xy 433.3748 -59.553348) (xy 433.3748 -58.232548) (xy 433.2478 -58.105548) (xy 430.0474 -58.105548)
			(xy 429.8188 -58.334148) (xy 429.8188 -59.553348) (xy 430.022 -59.756548) (xy 433.1716 -59.756548)
		)
		(stroke
			(width 0)
			(type solid)
		)
		(fill yes)
		(layer "F.Cu")
		(net "GND")
	)
	(gr_poly
		(pts
			(xy 439.068972 -26.966418) (xy 439.068972 -24.756618) (xy 438.941972 -24.629618) (xy 438.205372 -24.629618)
			(xy 438.129172 -24.705818) (xy 438.129172 -26.966418) (xy 438.281572 -27.118818) (xy 438.916572 -27.118818)
		)
		(stroke
			(width 0)
			(type solid)
		)
		(fill yes)
		(layer "F.Cu")
		(net "GND")
	)
	(gr_poly
		(pts
			(xy 440.46648 -29.936948) (xy 440.46648 -29.225748) (xy 440.41568 -29.174948) (xy 438.10428 -29.174948)
			(xy 438.00268 -29.276548) (xy 438.00268 -30.038548) (xy 438.35574 -30.391608) (xy 440.01182 -30.391608)
		)
		(stroke
			(width 0)
			(type solid)
		)
		(fill yes)
		(layer "F.Cu")
		(net "P12V_OCP_FLTB_1")
	)
	(gr_poly
		(pts
			(xy 442.52388 -373.090948) (xy 442.52388 -368.264948) (xy 442.26988 -368.010948) (xy 439.09488 -368.010948)
			(xy 438.84088 -368.264948) (xy 438.84088 -373.090948) (xy 438.99328 -373.243348) (xy 442.37148 -373.243348)
		)
		(stroke
			(width 0)
			(type solid)
		)
		(fill yes)
		(layer "F.Cu")
		(net "P5V")
	)
	(gr_poly
		(pts
			(xy 449.354448 -184.568592) (xy 449.354448 -175.78324) (xy 449.165726 -175.594518) (xy 447.066162 -175.594518)
			(xy 446.867788 -175.792892) (xy 446.867788 -184.850024) (xy 447.094102 -185.076592) (xy 448.846448 -185.076592)
		)
		(stroke
			(width 0)
			(type solid)
		)
		(fill yes)
		(layer "F.Cu")
		(net "GND")
	)
	(gr_poly
		(pts
			(xy 455.605642 -384.11023) (xy 455.605642 -383.67843) (xy 455.529442 -383.60223) (xy 454.411842 -383.60223)
			(xy 454.361042 -383.65303) (xy 454.361042 -384.13563) (xy 454.411842 -384.18643) (xy 455.529442 -384.18643)
		)
		(stroke
			(width 0)
			(type solid)
		)
		(fill yes)
		(layer "F.Cu")
		(net "GND")
	)
	(gr_poly
		(pts
			(xy 465.86902 -382.054608) (xy 465.86902 -379.860048) (xy 465.606892 -379.59792) (xy 463.40776 -379.59792)
			(xy 463.22488 -379.7808) (xy 463.22488 -382.090422) (xy 463.554826 -382.420368) (xy 465.50326 -382.420368)
		)
		(stroke
			(width 0)
			(type solid)
		)
		(fill yes)
		(layer "F.Cu")
		(net "P12V_AUX")
	)
	(gr_poly
		(pts
			(xy 33.94075 -131.462272) (xy 33.94075 -127.804672) (xy 33.88995 -127.753872) (xy 30.27426 -127.753872)
			(xy 30.23235 -127.795782) (xy 30.224222 -127.80391) (xy 30.224222 -131.504944) (xy 30.23235 -131.513072)
			(xy 33.88995 -131.513072)
		)
		(stroke
			(width 0)
			(type solid)
		)
		(fill yes)
		(layer "F.Cu")
		(net "GND")
	)
	(gr_poly
		(pts
			(xy 65.787524 -21.956268) (xy 65.775078 -21.943822) (xy 65.063878 -21.943822) (xy 64.911478 -22.096222)
			(xy 64.911478 -25.28824) (xy 65.368678 -25.74544) (xy 65.368678 -26.820622) (xy 65.444878 -26.896822)
			(xy 65.787524 -26.896822)
		)
		(stroke
			(width 0)
			(type solid)
		)
		(fill yes)
		(layer "F.Cu")
		(net "P12V_OCP_AVIN_PD_2")
	)
	(gr_poly
		(pts
			(xy 91.037918 -334.535526) (xy 91.037918 -331.664056) (xy 91.037918 -330.925424) (xy 90.913966 -330.801472)
			(xy 86.786466 -330.801472) (xy 86.631526 -330.956412) (xy 86.631526 -334.467454) (xy 86.73719 -334.573118)
			(xy 91.000326 -334.573118)
		)
		(stroke
			(width 0)
			(type solid)
		)
		(fill yes)
		(layer "F.Cu")
		(net "SW_PVCCIN_CPU1_SW6")
	)
	(gr_poly
		(pts
			(xy 136.4615 -76.790042) (xy 136.4615 -75.435206) (xy 136.286748 -74.556366) (xy 136.191498 -74.461116)
			(xy 133.422136 -74.461116) (xy 133.251702 -74.63155) (xy 133.251702 -76.87564) (xy 133.308344 -76.932282)
			(xy 136.31926 -76.932282)
		)
		(stroke
			(width 0)
			(type solid)
		)
		(fill yes)
		(layer "F.Cu")
		(net "GND")
	)
	(gr_poly
		(pts
			(xy 290.288218 -394.625322) (xy 290.288218 -393.989052) (xy 290.288218 -391.752074) (xy 290.280598 -391.744454)
			(xy 289.684714 -391.744454) (xy 289.675316 -391.753852) (xy 289.675316 -394.485876) (xy 289.91306 -394.72362)
			(xy 290.18992 -394.72362)
		)
		(stroke
			(width 0)
			(type solid)
		)
		(fill yes)
		(layer "F.Cu")
		(net "P12V_HSC_GATE2")
	)
	(gr_poly
		(pts
			(xy 359.347516 -297.272456) (xy 359.347516 -292.805612) (xy 359.245916 -292.704012) (xy 357.166672 -292.704012)
			(xy 356.909116 -292.961568) (xy 356.909116 -297.235626) (xy 357.112316 -297.438826) (xy 357.257858 -297.438826)
			(xy 359.181146 -297.438826)
		)
		(stroke
			(width 0)
			(type solid)
		)
		(fill yes)
		(layer "F.Cu")
		(net "GND")
	)
	(gr_poly
		(pts
			(xy 365.689896 -297.272456) (xy 365.689896 -292.814756) (xy 365.588296 -292.713156) (xy 363.365796 -292.713156)
			(xy 363.251496 -292.827456) (xy 363.251496 -297.261026) (xy 363.429296 -297.438826) (xy 365.454438 -297.438826)
			(xy 365.523526 -297.438826)
		)
		(stroke
			(width 0)
			(type solid)
		)
		(fill yes)
		(layer "F.Cu")
		(net "GND")
	)
	(gr_poly
		(pts
			(xy 107.358942 -331.125322) (xy 107.358942 -328.405998) (xy 107.358942 -327.647808) (xy 107.205526 -327.494392)
			(xy 103.105966 -327.494392) (xy 102.95255 -327.647808) (xy 102.95255 -328.34072) (xy 102.95255 -331.112114)
			(xy 103.00335 -331.162914) (xy 107.32135 -331.162914)
		)
		(stroke
			(width 0)
			(type solid)
		)
		(fill yes)
		(layer "F.Cu")
		(net "SW_PVCCIN_CPU1_SW2")
	)
	(gr_poly
		(pts
			(xy 118.81485 -261.78764) (xy 118.81485 -260.54558) (xy 118.76405 -260.49478) (xy 116.17325 -260.49478)
			(xy 115.97005 -260.69798) (xy 115.97005 -261.43458) (xy 116.12245 -261.58698) (xy 116.54155 -261.58698)
			(xy 116.80063 -261.84606) (xy 118.75643 -261.84606)
		)
		(stroke
			(width 0)
			(type solid)
		)
		(fill yes)
		(layer "F.Cu")
		(net "PVCCFA_EHV_FIVRA_CPU1")
	)
	(gr_poly
		(pts
			(xy 123.679966 -331.125322) (xy 123.679966 -328.452734) (xy 123.679966 -327.809352) (xy 123.387866 -327.517252)
			(xy 119.511826 -327.517252) (xy 119.273574 -327.755504) (xy 119.273574 -328.36231) (xy 119.273574 -331.112114)
			(xy 119.324374 -331.162914) (xy 123.642374 -331.162914)
		)
		(stroke
			(width 0)
			(type solid)
		)
		(fill yes)
		(layer "F.Cu")
		(net "SW_PVCCIN_CPU1_SW4")
	)
	(gr_poly
		(pts
			(xy 124.31903 -362.006642) (xy 124.756926 -362.006642) (xy 124.815854 -361.947714) (xy 124.815854 -360.88701)
			(xy 124.706126 -360.777282) (xy 124.432568 -360.777282) (xy 124.197364 -361.012486) (xy 124.197364 -361.83189)
			(xy 124.197364 -361.887008) (xy 124.318014 -362.007658)
		)
		(stroke
			(width 0)
			(type solid)
		)
		(fill yes)
		(layer "F.Cu")
		(net "GND")
	)
	(gr_poly
		(pts
			(xy 140.00099 -340.326218) (xy 140.00099 -337.480656) (xy 140.00099 -336.787236) (xy 139.814046 -336.600292)
			(xy 135.793226 -336.600292) (xy 135.594598 -336.79892) (xy 135.594598 -337.469734) (xy 135.594598 -340.31301)
			(xy 135.645398 -340.36381) (xy 139.963398 -340.36381)
		)
		(stroke
			(width 0)
			(type solid)
		)
		(fill yes)
		(layer "F.Cu")
		(net "SW_PVCCIN_CPU1_SW8")
	)
	(gr_poly
		(pts
			(xy 164.58946 -56.896508) (xy 164.58946 -54.308248) (xy 163.8427 -53.561488) (xy 159.47136 -53.561488)
			(xy 159.3723 -53.660548) (xy 159.3723 -54.818788) (xy 159.02686 -55.164228) (xy 159.02686 -57.170828)
			(xy 159.13608 -57.280048) (xy 164.20592 -57.280048)
		)
		(stroke
			(width 0)
			(type solid)
		)
		(fill yes)
		(layer "F.Cu")
		(net "P3V3")
	)
	(gr_poly
		(pts
			(xy 175.792384 -26.567892) (xy 175.707548 -26.482548) (xy 175.707548 -22.991572) (xy 175.085502 -22.991572)
			(xy 174.933102 -23.143972) (xy 174.933102 -26.33599) (xy 175.390302 -26.79319) (xy 175.390302 -27.868372)
			(xy 175.466502 -27.944572) (xy 175.792384 -27.944572)
		)
		(stroke
			(width 0)
			(type solid)
		)
		(fill yes)
		(layer "F.Cu")
		(net "P12V_SCM_AVIN_PD")
	)
	(gr_poly
		(pts
			(xy 179.5145 -35.138868) (xy 179.5145 -33.167828) (xy 179.333144 -32.986472) (xy 178.804062 -32.986472)
			(xy 178.702462 -33.088072) (xy 173.337982 -33.088072) (xy 173.251622 -33.174432) (xy 173.251622 -35.257232)
			(xy 173.393862 -35.399472) (xy 179.253896 -35.399472)
		)
		(stroke
			(width 0)
			(type solid)
		)
		(fill yes)
		(layer "F.Cu")
		(net "GND")
	)
	(gr_poly
		(pts
			(xy 218.119452 -61.428884) (xy 218.119452 -59.129422) (xy 218.187524 -59.06135) (xy 218.187524 -58.516012)
			(xy 217.857324 -58.185812) (xy 216.282524 -58.185812) (xy 216.079324 -58.389012) (xy 216.079324 -61.386212)
			(xy 216.282524 -61.589412) (xy 217.958924 -61.589412)
		)
		(stroke
			(width 0)
			(type solid)
		)
		(fill yes)
		(layer "F.Cu")
		(net "GND")
	)
	(gr_poly
		(pts
			(xy 225.805492 -57.0865) (xy 227.843588 -57.0865) (xy 228.46284 -56.467248) (xy 228.46284 -52.687728)
			(xy 228.024944 -52.249832) (xy 220.685106 -52.249832) (xy 220.354906 -52.580032) (xy 220.354906 -57.050432)
			(xy 220.405706 -57.101232) (xy 225.790506 -57.101232)
		)
		(stroke
			(width 0)
			(type solid)
		)
		(fill yes)
		(layer "F.Cu")
		(net "P3V3_E1S_0")
	)
	(gr_poly
		(pts
			(xy 238.71682 -48.988726) (xy 238.71682 -48.468026) (xy 238.62284 -48.374046) (xy 235.97108 -48.374046)
			(xy 235.92536 -48.419766) (xy 235.92536 -48.701706) (xy 235.98378 -48.760126) (xy 237.49508 -48.760126)
			(xy 237.871 -49.136046) (xy 238.5695 -49.136046)
		)
		(stroke
			(width 0)
			(type solid)
		)
		(fill yes)
		(layer "F.Cu")
		(net "P3V3_E1S_0")
	)
	(gr_poly
		(pts
			(xy 244.551708 -396.36446) (xy 244.551708 -394.59154) (xy 244.470428 -394.51026) (xy 244.470428 -393.94384)
			(xy 244.439948 -393.91336) (xy 243.977668 -393.91336) (xy 243.815108 -394.07592) (xy 243.815108 -396.3416)
			(xy 243.845588 -396.37208) (xy 244.544088 -396.37208)
		)
		(stroke
			(width 0)
			(type solid)
		)
		(fill yes)
		(layer "F.Cu")
		(net "P12V_HSC_GATE_G5")
	)
	(gr_poly
		(pts
			(xy 250.486672 -396.36446) (xy 250.486672 -394.59154) (xy 250.405392 -394.51026) (xy 250.405392 -393.94384)
			(xy 250.374912 -393.91336) (xy 249.912632 -393.91336) (xy 249.750072 -394.07592) (xy 249.750072 -396.3416)
			(xy 249.780552 -396.37208) (xy 250.479052 -396.37208)
		)
		(stroke
			(width 0)
			(type solid)
		)
		(fill yes)
		(layer "F.Cu")
		(net "P12V_HSC_GATE_G6")
	)
	(gr_poly
		(pts
			(xy 255.75768 -54.558946) (xy 255.75768 -52.448206) (xy 255.55956 -52.250086) (xy 254.86614 -52.250086)
			(xy 254.84328 -52.272946) (xy 254.84328 -52.933346) (xy 255.07188 -53.161946) (xy 255.07188 -54.584346)
			(xy 255.17348 -54.685946) (xy 255.63068 -54.685946)
		)
		(stroke
			(width 0)
			(type solid)
		)
		(fill yes)
		(layer "F.Cu")
		(net "P12V_E1S_FLTB_0")
	)
	(gr_poly
		(pts
			(xy 256.421636 -396.36446) (xy 256.421636 -394.59154) (xy 256.340356 -394.51026) (xy 256.340356 -393.94384)
			(xy 256.309876 -393.91336) (xy 255.847596 -393.91336) (xy 255.685036 -394.07592) (xy 255.685036 -396.3416)
			(xy 255.715516 -396.37208) (xy 256.414016 -396.37208)
		)
		(stroke
			(width 0)
			(type solid)
		)
		(fill yes)
		(layer "F.Cu")
		(net "P12V_HSC_GATE_G1")
	)
	(gr_poly
		(pts
			(xy 262.3566 -396.36446) (xy 262.3566 -394.59154) (xy 262.27532 -394.51026) (xy 262.27532 -393.94384)
			(xy 262.24484 -393.91336) (xy 261.78256 -393.91336) (xy 261.62 -394.07592) (xy 261.62 -396.3416)
			(xy 261.65048 -396.37208) (xy 262.34898 -396.37208)
		)
		(stroke
			(width 0)
			(type solid)
		)
		(fill yes)
		(layer "F.Cu")
		(net "P12V_HSC_GATE_G2")
	)
	(gr_poly
		(pts
			(xy 268.291564 -396.36446) (xy 268.291564 -394.59154) (xy 268.210284 -394.51026) (xy 268.210284 -393.94384)
			(xy 268.179804 -393.91336) (xy 267.717524 -393.91336) (xy 267.554964 -394.07592) (xy 267.554964 -396.3416)
			(xy 267.585444 -396.37208) (xy 268.283944 -396.37208)
		)
		(stroke
			(width 0)
			(type solid)
		)
		(fill yes)
		(layer "F.Cu")
		(net "P12V_HSC_GATE_G3")
	)
	(gr_poly
		(pts
			(xy 274.226528 -396.36446) (xy 274.226528 -394.59154) (xy 274.145248 -394.51026) (xy 274.145248 -393.94384)
			(xy 274.114768 -393.91336) (xy 273.652488 -393.91336) (xy 273.489928 -394.07592) (xy 273.489928 -396.3416)
			(xy 273.520408 -396.37208) (xy 274.218908 -396.37208)
		)
		(stroke
			(width 0)
			(type solid)
		)
		(fill yes)
		(layer "F.Cu")
		(net "P12V_HSC_GATE_G4")
	)
	(gr_poly
		(pts
			(xy 280.161492 -396.36446) (xy 280.161492 -394.59154) (xy 280.080212 -394.51026) (xy 280.080212 -393.94384)
			(xy 280.049732 -393.91336) (xy 279.587452 -393.91336) (xy 279.424892 -394.07592) (xy 279.424892 -396.3416)
			(xy 279.455372 -396.37208) (xy 280.153872 -396.37208)
		)
		(stroke
			(width 0)
			(type solid)
		)
		(fill yes)
		(layer "F.Cu")
		(net "MB0_CM_GATE_G0")
	)
	(gr_poly
		(pts
			(xy 321.985894 -14.351254) (xy 321.985894 -13.092684) (xy 321.882008 -12.988798) (xy 320.23558 -12.988798)
			(xy 319.70345 -12.988798) (xy 319.55994 -13.132308) (xy 319.55994 -14.351508) (xy 319.641474 -14.433042)
			(xy 320.18224 -14.433042) (xy 321.904106 -14.433042)
		)
		(stroke
			(width 0)
			(type solid)
		)
		(fill yes)
		(layer "F.Cu")
		(net "P3V3_AUX")
	)
	(gr_poly
		(pts
			(xy 330.843636 -340.326218) (xy 330.843636 -337.523836) (xy 330.843636 -336.847688) (xy 330.65974 -336.663792)
			(xy 326.57288 -336.663792) (xy 326.437244 -336.799428) (xy 326.437244 -337.614514) (xy 326.437244 -340.31301)
			(xy 326.488044 -340.36381) (xy 330.806044 -340.36381)
		)
		(stroke
			(width 0)
			(type solid)
		)
		(fill yes)
		(layer "F.Cu")
		(net "SW_PVCCIN_CPU0_SW7")
	)
	(gr_poly
		(pts
			(xy 338.977732 -334.535526) (xy 338.977732 -331.810868) (xy 338.977732 -331.04582) (xy 338.751164 -330.819252)
			(xy 334.664304 -330.819252) (xy 334.57134 -330.912216) (xy 334.57134 -331.713078) (xy 334.57134 -334.522318)
			(xy 334.62214 -334.573118) (xy 338.94014 -334.573118)
		)
		(stroke
			(width 0)
			(type solid)
		)
		(fill yes)
		(layer "F.Cu")
		(net "SW_PVCCIN_CPU0_SW6")
	)
	(gr_poly
		(pts
			(xy 347.138244 -331.125322) (xy 347.138244 -328.33691) (xy 347.138244 -327.583292) (xy 347.051884 -327.496932)
			(xy 342.817704 -327.496932) (xy 342.731852 -327.582784) (xy 342.731852 -328.289412) (xy 342.731852 -331.112114)
			(xy 342.782652 -331.162914) (xy 347.100652 -331.162914)
		)
		(stroke
			(width 0)
			(type solid)
		)
		(fill yes)
		(layer "F.Cu")
		(net "SW_PVCCIN_CPU0_SW1")
	)
	(gr_poly
		(pts
			(xy 355.298756 -331.125322) (xy 355.298756 -328.161396) (xy 355.298756 -327.704704) (xy 355.083364 -327.489312)
			(xy 351.014284 -327.489312) (xy 350.892364 -327.611232) (xy 350.892364 -328.170032) (xy 350.892364 -331.112114)
			(xy 350.943164 -331.162914) (xy 355.261164 -331.162914)
		)
		(stroke
			(width 0)
			(type solid)
		)
		(fill yes)
		(layer "F.Cu")
		(net "SW_PVCCIN_CPU0_SW2")
	)
	(gr_poly
		(pts
			(xy 366.754664 -261.787386) (xy 366.754664 -260.545326) (xy 366.703864 -260.494526) (xy 364.113064 -260.494526)
			(xy 363.909864 -260.697726) (xy 363.909864 -261.434326) (xy 364.062264 -261.586726) (xy 364.481364 -261.586726)
			(xy 364.740444 -261.845806) (xy 366.696244 -261.845806)
		)
		(stroke
			(width 0)
			(type solid)
		)
		(fill yes)
		(layer "F.Cu")
		(net "PVCCFA_EHV_FIVRA_CPU0")
	)
	(gr_poly
		(pts
			(xy 371.682264 -331.062838) (xy 371.682264 -327.618852) (xy 371.570504 -327.507092) (xy 367.310924 -327.507092)
			(xy 367.213388 -327.604628) (xy 367.213388 -328.316336) (xy 367.213388 -328.31659) (xy 367.213388 -331.112114)
			(xy 367.264188 -331.162914) (xy 371.582188 -331.162914)
		)
		(stroke
			(width 0)
			(type solid)
		)
		(fill yes)
		(layer "F.Cu")
		(net "SW_PVCCIN_CPU0_SW4")
	)
	(gr_poly
		(pts
			(xy 372.258844 -362.006642) (xy 372.69674 -362.006642) (xy 372.755668 -361.947714) (xy 372.755668 -360.88701)
			(xy 372.64594 -360.777282) (xy 372.372382 -360.777282) (xy 372.137178 -361.012486) (xy 372.137178 -361.83189)
			(xy 372.137178 -361.887008) (xy 372.257828 -362.007658)
		)
		(stroke
			(width 0)
			(type solid)
		)
		(fill yes)
		(layer "F.Cu")
		(net "GND")
	)
	(gr_poly
		(pts
			(xy 376.504962 -81.054194) (xy 376.504962 -71.40448) (xy 376.290586 -71.190104) (xy 373.587772 -71.190104)
			(xy 373.290592 -71.487284) (xy 373.290592 -79.948024) (xy 373.290592 -81.00314) (xy 373.556276 -81.268824)
			(xy 374.611392 -81.268824) (xy 376.290332 -81.268824)
		)
		(stroke
			(width 0)
			(type solid)
		)
		(fill yes)
		(layer "F.Cu")
		(net "P1V8_PCH_AUX")
	)
	(gr_poly
		(pts
			(xy 378.703332 -81.091024) (xy 378.703332 -80.760824) (xy 378.703332 -71.359776) (xy 378.579126 -71.23557)
			(xy 376.858022 -71.23557) (xy 376.798332 -71.29526) (xy 376.798332 -80.760824) (xy 376.798332 -81.167224)
			(xy 376.899932 -81.268824) (xy 378.525532 -81.268824)
		)
		(stroke
			(width 0)
			(type solid)
		)
		(fill yes)
		(layer "F.Cu")
		(net "GND")
	)
	(gr_poly
		(pts
			(xy 379.780292 -334.535526) (xy 379.780292 -331.672692) (xy 379.780292 -331.04582) (xy 379.576584 -330.842112)
			(xy 375.504964 -330.842112) (xy 375.3739 -330.973176) (xy 375.3739 -331.658722) (xy 375.3739 -334.522318)
			(xy 375.4247 -334.573118) (xy 379.7427 -334.573118)
		)
		(stroke
			(width 0)
			(type solid)
		)
		(fill yes)
		(layer "F.Cu")
		(net "SW_PVCCIN_CPU0_SW5")
	)
	(gr_poly
		(pts
			(xy 383.41554 -370.763292) (xy 383.41554 -367.21161) (xy 383.083054 -366.879124) (xy 369.266724 -366.879124)
			(xy 369.141756 -367.004092) (xy 369.141756 -369.879372) (xy 369.14455 -369.882166) (xy 369.14455 -370.262658)
			(xy 370.253514 -371.371622) (xy 382.80721 -371.371622)
		)
		(stroke
			(width 0)
			(type solid)
		)
		(fill yes)
		(layer "F.Cu")
		(net "PVPP_HBM_CPU0")
	)
	(gr_poly
		(pts
			(xy 387.940804 -340.326218) (xy 387.940804 -337.40979) (xy 387.940804 -336.790792) (xy 387.760464 -336.610452)
			(xy 383.681224 -336.610452) (xy 383.534412 -336.757264) (xy 383.534412 -337.39709) (xy 383.534412 -340.31301)
			(xy 383.585212 -340.36381) (xy 387.903212 -340.36381)
		)
		(stroke
			(width 0)
			(type solid)
		)
		(fill yes)
		(layer "F.Cu")
		(net "SW_PVCCIN_CPU0_SW8")
	)
	(gr_poly
		(pts
			(xy 422.83888 -100.825808) (xy 422.83888 -100.165408) (xy 421.84828 -99.174808) (xy 421.84828 -96.888808)
			(xy 421.56888 -96.609408) (xy 418.67328 -96.609408) (xy 417.91128 -97.371408) (xy 417.91128 -100.851208)
			(xy 418.19068 -101.130608) (xy 422.53408 -101.130608)
		)
		(stroke
			(width 0)
			(type solid)
		)
		(fill yes)
		(layer "F.Cu")
		(net "GND")
	)
	(gr_poly
		(pts
			(xy 434.24856 -180.07584) (xy 434.24856 -179.42306) (xy 434.22824 -179.40274) (xy 433.6161 -179.40274)
			(xy 433.561236 -179.457604) (xy 433.561236 -179.937918) (xy 433.51704 -179.98186) (xy 433.51704 -180.07584)
			(xy 433.54244 -180.10124) (xy 434.22316 -180.10124)
		)
		(stroke
			(width 0)
			(type solid)
		)
		(fill yes)
		(layer "F.Cu")
		(net "PVNN_MAIN_CPU0_REF")
	)
	(gr_poly
		(pts
			(xy 99.19843 -331.125322) (xy 99.19843 -328.405744) (xy 99.197922 -328.405236) (xy 99.197922 -327.779888)
			(xy 98.935286 -327.517252) (xy 95.003366 -327.517252) (xy 94.792038 -327.72858) (xy 94.792038 -328.318876)
			(xy 94.792038 -331.112114) (xy 94.842838 -331.162914) (xy 99.160838 -331.162914)
		)
		(stroke
			(width 0)
			(type solid)
		)
		(fill yes)
		(layer "F.Cu")
		(net "SW_PVCCIN_CPU1_SW1")
	)
	(gr_poly
		(pts
			(xy 115.519454 -331.125322) (xy 115.519454 -328.345546) (xy 115.508786 -328.335132) (xy 115.508786 -327.720452)
			(xy 115.325906 -327.537572) (xy 111.305086 -327.537572) (xy 111.113062 -327.729596) (xy 111.113062 -328.329798)
			(xy 111.113062 -331.112114) (xy 111.163862 -331.162914) (xy 115.481862 -331.162914)
		)
		(stroke
			(width 0)
			(type solid)
		)
		(fill yes)
		(layer "F.Cu")
		(net "SW_PVCCIN_CPU1_SW3")
	)
	(gr_poly
		(pts
			(xy 280.927048 -394.37818) (xy 280.927048 -393.9032) (xy 280.927048 -393.29614) (xy 280.861008 -393.2301)
			(xy 280.421588 -393.2301) (xy 280.334212 -393.317476) (xy 280.334212 -393.96416) (xy 280.334212 -394.3858)
			(xy 280.385012 -394.4366) (xy 280.575512 -394.4366) (xy 280.868628 -394.4366)
		)
		(stroke
			(width 0)
			(type solid)
		)
		(fill yes)
		(layer "F.Cu")
		(net "P12V_HSC_GATE1")
	)
	(gr_poly
		(pts
			(xy 291.276278 -393.371832) (xy 291.276278 -391.145014) (xy 291.276278 -390.590278) (xy 291.06368 -390.37768)
			(xy 290.19246 -390.37768) (xy 290.06038 -390.50976) (xy 290.06038 -390.994646) (xy 290.665154 -391.59942)
			(xy 290.665154 -393.389612) (xy 290.726114 -393.450572) (xy 291.197538 -393.450572)
		)
		(stroke
			(width 0)
			(type solid)
		)
		(fill yes)
		(layer "F.Cu")
		(net "P12V_HSC_GATE1")
	)
	(gr_poly
		(pts
			(xy 363.459268 -331.125322) (xy 363.459268 -328.328274) (xy 363.453172 -328.321924) (xy 363.453172 -327.64476)
			(xy 363.315504 -327.507092) (xy 359.165144 -327.507092) (xy 359.052876 -327.61936) (xy 359.052876 -328.295)
			(xy 359.052876 -331.112114) (xy 359.103676 -331.162914) (xy 363.421676 -331.162914)
		)
		(stroke
			(width 0)
			(type solid)
		)
		(fill yes)
		(layer "F.Cu")
		(net "SW_PVCCIN_CPU0_SW3")
	)
	(gr_poly
		(pts
			(xy 432.947318 -167.028622) (xy 432.947318 -166.746174) (xy 432.947318 -162.103054) (xy 432.800252 -161.955734)
			(xy 431.3682 -161.955734) (xy 430.67986 -161.955734) (xy 430.554892 -162.080702) (xy 430.554892 -166.899082)
			(xy 430.65954 -167.00373) (xy 430.96053 -167.30472) (xy 432.67122 -167.30472)
		)
		(stroke
			(width 0)
			(type solid)
		)
		(fill yes)
		(layer "F.Cu")
		(net "P12V_AUX")
	)
	(gr_poly
		(pts
			(xy 30.36824 -168.666668) (xy 30.36824 -166.547038) (xy 30.322012 -166.50081) (xy 29.80055 -166.50081)
			(xy 29.75102 -166.55034) (xy 29.75102 -167.741854) (xy 29.651706 -167.841168) (xy 28.774644 -167.841168)
			(xy 28.600908 -168.014904) (xy 28.600908 -168.809416) (xy 28.683712 -168.89222) (xy 30.142688 -168.89222)
		)
		(stroke
			(width 0)
			(type solid)
		)
		(fill yes)
		(layer "F.Cu")
		(net "PVCCD_HV_CPU1_VREF")
	)
	(gr_poly
		(pts
			(xy 48.67021 -147.395692) (xy 48.67021 -147.138136) (xy 48.671226 -147.13712) (xy 48.671226 -145.297906)
			(xy 48.523906 -145.15084) (xy 43.086782 -145.15084) (xy 42.939462 -145.297906) (xy 42.939462 -147.13712)
			(xy 42.940478 -147.138136) (xy 42.940478 -147.395692) (xy 43.095926 -147.55114) (xy 48.514762 -147.55114)
		)
		(stroke
			(width 0)
			(type solid)
		)
		(fill yes)
		(layer "F.Cu")
		(net "P12V_AUX")
	)
	(gr_poly
		(pts
			(xy 63.219838 -26.807922) (xy 63.219838 -24.115522) (xy 63.423038 -23.912322) (xy 64.286638 -23.912322)
			(xy 64.362838 -23.836122) (xy 64.362838 -23.074122) (xy 64.235838 -22.947122) (xy 62.991238 -22.947122)
			(xy 62.508638 -23.429722) (xy 62.508638 -26.782522) (xy 62.559438 -26.833322) (xy 63.194438 -26.833322)
		)
		(stroke
			(width 0)
			(type solid)
		)
		(fill yes)
		(layer "F.Cu")
		(net "P12V_AUX")
	)
	(gr_poly
		(pts
			(xy 131.991862 -327.44791) (xy 131.991862 -326.146668) (xy 131.754626 -325.909432) (xy 127.169672 -325.909432)
			(xy 125.848872 -324.588632) (xy 119.308626 -324.588632) (xy 119.054626 -324.842632) (xy 119.054626 -326.112632)
			(xy 119.232426 -326.290432) (xy 123.573794 -326.290432) (xy 124.919994 -327.636632) (xy 131.802886 -327.636632)
		)
		(stroke
			(width 0)
			(type solid)
		)
		(fill yes)
		(layer "F.Cu")
		(net "IND_P1_CPL4")
	)
	(gr_poly
		(pts
			(xy 191.930782 -28.521152) (xy 191.930782 -27.444192) (xy 191.930782 -26.390092) (xy 191.305942 -25.765252)
			(xy 191.178942 -25.765252) (xy 191.120522 -25.823672) (xy 191.120522 -26.633932) (xy 191.120522 -27.583892)
			(xy 191.36614 -27.82951) (xy 191.36614 -28.545028) (xy 191.469264 -28.648152) (xy 191.803782 -28.648152)
		)
		(stroke
			(width 0)
			(type solid)
		)
		(fill yes)
		(layer "F.Cu")
		(net "GND")
	)
	(gr_poly
		(pts
			(xy 224.013522 -73.748138) (xy 224.013522 -72.671178) (xy 224.013522 -71.617078) (xy 223.388682 -70.992238)
			(xy 223.261682 -70.992238) (xy 223.203262 -71.050658) (xy 223.203262 -71.860918) (xy 223.203262 -72.810878)
			(xy 223.378522 -72.986138) (xy 223.378522 -73.748138) (xy 223.505522 -73.875138) (xy 223.886522 -73.875138)
		)
		(stroke
			(width 0)
			(type solid)
		)
		(fill yes)
		(layer "F.Cu")
		(net "GND")
	)
	(gr_poly
		(pts
			(xy 249.522234 -75.755754) (xy 249.522234 -71.463662) (xy 249.522234 -70.156324) (xy 249.522234 -69.655944)
			(xy 249.486166 -69.619876) (xy 245.945406 -69.619876) (xy 245.813326 -69.751956) (xy 245.813326 -70.122796)
			(xy 245.813326 -71.1454) (xy 245.813326 -75.442572) (xy 246.245126 -75.874372) (xy 249.403616 -75.874372)
		)
		(stroke
			(width 0)
			(type solid)
		)
		(fill yes)
		(layer "F.Cu")
		(net "P12V_AUX")
	)
	(gr_poly
		(pts
			(xy 251.717048 -52.670202) (xy 252.79223 -52.670202) (xy 252.86843 -52.594002) (xy 252.86843 -52.24526)
			(xy 252.08357 -52.24526) (xy 251.97689 -52.35194) (xy 248.07418 -52.35194) (xy 248.07418 -52.709826)
			(xy 247.91543 -52.868322) (xy 247.91543 -52.975002) (xy 248.06783 -53.127402) (xy 251.259848 -53.127402)
		)
		(stroke
			(width 0)
			(type solid)
		)
		(fill yes)
		(layer "F.Cu")
		(net "P12V_E1S_AVIN_PD_0")
	)
	(gr_poly
		(pts
			(xy 255.015746 -39.415466) (xy 255.777746 -39.415466) (xy 255.83769 -39.355522) (xy 255.83769 -38.974522)
			(xy 255.71069 -38.847522) (xy 254.63373 -38.847522) (xy 253.57963 -38.847522) (xy 252.95479 -39.472362)
			(xy 252.95479 -39.599362) (xy 253.01321 -39.657782) (xy 253.82347 -39.657782) (xy 254.77343 -39.657782)
		)
		(stroke
			(width 0)
			(type solid)
		)
		(fill yes)
		(layer "F.Cu")
		(net "GND")
	)
	(gr_poly
		(pts
			(xy 321.985894 -21.554186) (xy 321.985894 -16.230854) (xy 321.985894 -14.972284) (xy 321.882008 -14.868398)
			(xy 321.801998 -14.788388) (xy 320.175636 -14.788388) (xy 319.43294 -14.788388) (xy 318.924686 -14.788388)
			(xy 318.81953 -14.893544) (xy 318.81953 -21.465286) (xy 319.14211 -21.787866) (xy 321.752214 -21.787866)
		)
		(stroke
			(width 0)
			(type solid)
		)
		(fill yes)
		(layer "F.Cu")
		(net "P1V8_PCH_AUX")
	)
	(gr_poly
		(pts
			(xy 342.150954 -326.357742) (xy 347.228414 -326.357742) (xy 347.298264 -326.287892) (xy 347.298264 -324.976744)
			(xy 346.909136 -324.588632) (xy 340.45652 -324.588632) (xy 339.21192 -325.833232) (xy 334.496664 -325.833232)
			(xy 334.245712 -326.084184) (xy 334.245712 -327.33488) (xy 334.471264 -327.560432) (xy 340.948264 -327.560432)
		)
		(stroke
			(width 0)
			(type solid)
		)
		(fill yes)
		(layer "F.Cu")
		(net "IND_P0_CPL1")
	)
	(gr_poly
		(pts
			(xy 420.55288 -105.575608) (xy 420.55288 -104.864408) (xy 420.47668 -104.788208) (xy 419.81628 -104.788208)
			(xy 419.46576 -104.437688) (xy 419.46576 -103.782368) (xy 419.2651 -103.581708) (xy 418.29736 -103.581708)
			(xy 418.13226 -103.746808) (xy 418.13226 -105.390188) (xy 418.44468 -105.702608) (xy 420.42588 -105.702608)
		)
		(stroke
			(width 0)
			(type solid)
		)
		(fill yes)
		(layer "F.Cu")
		(net "P3V3_AUX")
	)
	(gr_poly
		(pts
			(xy 430.412906 -121.265442) (xy 430.412906 -120.073928) (xy 430.51222 -119.974614) (xy 431.389282 -119.974614)
			(xy 431.563018 -119.800878) (xy 431.563018 -119.006366) (xy 431.480214 -118.923562) (xy 429.975264 -118.923562)
			(xy 429.767492 -119.131334) (xy 429.767492 -121.210324) (xy 429.850296 -121.293128) (xy 430.38522 -121.293128)
		)
		(stroke
			(width 0)
			(type solid)
		)
		(fill yes)
		(layer "F.Cu")
		(net "PVCCD_HV_CPU0_VREF")
	)
	(gr_poly
		(pts
			(xy 433.944776 -103.77043) (xy 434.706776 -103.77043) (xy 434.833776 -103.64343) (xy 434.833776 -103.26243)
			(xy 434.706776 -103.13543) (xy 433.629816 -103.13543) (xy 432.575716 -103.13543) (xy 431.950876 -103.76027)
			(xy 431.950876 -103.88727) (xy 432.009296 -103.94569) (xy 432.819556 -103.94569) (xy 433.769516 -103.94569)
		)
		(stroke
			(width 0)
			(type solid)
		)
		(fill yes)
		(layer "F.Cu")
		(net "GND")
	)
	(gr_poly
		(pts
			(xy 456.316842 -384.13563) (xy 456.316842 -383.09423) (xy 455.554842 -382.33223) (xy 454.970642 -382.33223)
			(xy 454.88606 -382.416812) (xy 454.88606 -383.062988) (xy 454.942702 -383.11963) (xy 455.681842 -383.11963)
			(xy 455.935842 -383.37363) (xy 455.935842 -384.08483) (xy 456.037442 -384.18643) (xy 456.266042 -384.18643)
		)
		(stroke
			(width 0)
			(type solid)
		)
		(fill yes)
		(layer "F.Cu")
		(net "SW_P5V_AUX_BST")
	)
	(gr_poly
		(pts
			(xy 469.6968 -60.696348) (xy 469.6968 -60.569348) (xy 469.6968 -55.971948) (xy 469.5698 -55.844948)
			(xy 462.9404 -55.844948) (xy 462.4324 -55.844948) (xy 462.28 -55.997348) (xy 462.28 -60.120276) (xy 462.28 -60.736988)
			(xy 462.4324 -60.889388) (xy 467.545166 -60.889388) (xy 469.50376 -60.889388)
		)
		(stroke
			(width 0)
			(type solid)
		)
		(fill yes)
		(layer "F.Cu")
		(net "P12V_AUX")
	)
	(gr_poly
		(pts
			(xy 67.73164 -58.171588) (xy 67.72783 -58.167778) (xy 67.72783 -57.692798) (xy 67.95262 -57.468008)
			(xy 68.64604 -57.468008) (xy 68.79844 -57.315608) (xy 68.79844 -56.794908) (xy 68.7578 -56.754268)
			(xy 66.14668 -56.754268) (xy 65.913 -56.987948) (xy 65.913 -58.003948) (xy 66.14414 -58.235088) (xy 67.66814 -58.235088)
		)
		(stroke
			(width 0)
			(type solid)
		)
		(fill yes)
		(layer "F.Cu")
		(net "P3V3_AUX")
	)
	(gr_poly
		(pts
			(xy 81.548478 -23.571962) (xy 81.548478 -22.495002) (xy 81.548478 -21.440902) (xy 80.923638 -20.816062)
			(xy 80.796638 -20.816062) (xy 80.738218 -20.874482) (xy 80.738218 -21.684742) (xy 80.738218 -22.634702)
			(xy 80.913478 -22.809962) (xy 81.026 -22.922484) (xy 81.026 -23.617682) (xy 81.10728 -23.698962)
			(xy 81.421478 -23.698962)
		)
		(stroke
			(width 0)
			(type solid)
		)
		(fill yes)
		(layer "F.Cu")
		(net "GND")
	)
	(gr_poly
		(pts
			(xy 175.535336 -30.755844) (xy 175.749204 -30.755844) (xy 175.754284 -30.750764) (xy 175.81626 -30.688788)
			(xy 175.81626 -29.997908) (xy 175.75276 -29.934408) (xy 173.47946 -29.934408) (xy 173.355 -30.058868)
			(xy 173.355 -30.742128) (xy 173.355 -31.75254) (xy 173.44136 -31.8389) (xy 173.97222 -31.8389) (xy 174.45228 -31.8389)
		)
		(stroke
			(width 0)
			(type solid)
		)
		(fill yes)
		(layer "F.Cu")
		(net "P12V_SCM_FLTB_N")
	)
	(gr_poly
		(pts
			(xy 194.72148 -69.154548) (xy 194.72148 -68.417948) (xy 195.43268 -67.706748) (xy 195.43268 -66.817748)
			(xy 195.43268 -65.733168) (xy 195.18376 -65.484248) (xy 193.59626 -65.484248) (xy 193.37528 -65.705228)
			(xy 193.37528 -66.589148) (xy 193.37528 -67.579748) (xy 193.98488 -68.189348) (xy 193.98488 -69.230748)
			(xy 194.64528 -69.230748)
		)
		(stroke
			(width 0)
			(type solid)
		)
		(fill yes)
		(layer "F.Cu")
		(net "P3V3_E1S_0_R")
	)
	(gr_poly
		(pts
			(xy 245.628668 -395.01318) (xy 245.628668 -394.17498) (xy 245.356888 -393.9032) (xy 244.785388 -393.9032)
			(xy 244.724428 -393.96416) (xy 244.724428 -394.3858) (xy 244.775228 -394.4366) (xy 244.965728 -394.4366)
			(xy 245.047008 -394.51788) (xy 245.047008 -394.63726) (xy 245.047008 -394.98778) (xy 245.140988 -395.08176)
			(xy 245.560088 -395.08176)
		)
		(stroke
			(width 0)
			(type solid)
		)
		(fill yes)
		(layer "F.Cu")
		(net "P12V_HSC_GATE2")
	)
	(gr_poly
		(pts
			(xy 251.563632 -395.01318) (xy 251.563632 -394.17498) (xy 251.291852 -393.9032) (xy 250.720352 -393.9032)
			(xy 250.659392 -393.96416) (xy 250.659392 -394.3858) (xy 250.710192 -394.4366) (xy 250.900692 -394.4366)
			(xy 250.981972 -394.51788) (xy 250.981972 -394.63726) (xy 250.981972 -394.98778) (xy 251.075952 -395.08176)
			(xy 251.495052 -395.08176)
		)
		(stroke
			(width 0)
			(type solid)
		)
		(fill yes)
		(layer "F.Cu")
		(net "P12V_HSC_GATE2")
	)
	(gr_poly
		(pts
			(xy 252.80493 -55.479442) (xy 252.80493 -54.844696) (xy 250.28652 -54.844696) (xy 250.260866 -54.819042)
			(xy 250.08713 -54.819042) (xy 249.88393 -54.615842) (xy 249.88393 -53.752242) (xy 249.80773 -53.676042)
			(xy 249.04573 -53.676042) (xy 248.91873 -53.803042) (xy 248.91873 -55.047642) (xy 249.40133 -55.530242)
			(xy 252.75413 -55.530242)
		)
		(stroke
			(width 0)
			(type solid)
		)
		(fill yes)
		(layer "F.Cu")
		(net "P12V_AUX")
	)
	(gr_poly
		(pts
			(xy 257.498596 -395.01318) (xy 257.498596 -394.17498) (xy 257.226816 -393.9032) (xy 256.655316 -393.9032)
			(xy 256.594356 -393.96416) (xy 256.594356 -394.3858) (xy 256.645156 -394.4366) (xy 256.835656 -394.4366)
			(xy 256.916936 -394.51788) (xy 256.916936 -394.63726) (xy 256.916936 -394.98778) (xy 257.010916 -395.08176)
			(xy 257.430016 -395.08176)
		)
		(stroke
			(width 0)
			(type solid)
		)
		(fill yes)
		(layer "F.Cu")
		(net "P12V_HSC_GATE2")
	)
	(gr_poly
		(pts
			(xy 263.43356 -395.01318) (xy 263.43356 -394.17498) (xy 263.16178 -393.9032) (xy 262.59028 -393.9032)
			(xy 262.52932 -393.96416) (xy 262.52932 -394.3858) (xy 262.58012 -394.4366) (xy 262.77062 -394.4366)
			(xy 262.8519 -394.51788) (xy 262.8519 -394.63726) (xy 262.8519 -394.98778) (xy 262.94588 -395.08176)
			(xy 263.36498 -395.08176)
		)
		(stroke
			(width 0)
			(type solid)
		)
		(fill yes)
		(layer "F.Cu")
		(net "P12V_HSC_GATE2")
	)
	(gr_poly
		(pts
			(xy 269.368524 -395.01318) (xy 269.368524 -394.17498) (xy 269.096744 -393.9032) (xy 268.525244 -393.9032)
			(xy 268.464284 -393.96416) (xy 268.464284 -394.3858) (xy 268.515084 -394.4366) (xy 268.705584 -394.4366)
			(xy 268.786864 -394.51788) (xy 268.786864 -394.63726) (xy 268.786864 -394.98778) (xy 268.880844 -395.08176)
			(xy 269.299944 -395.08176)
		)
		(stroke
			(width 0)
			(type solid)
		)
		(fill yes)
		(layer "F.Cu")
		(net "P12V_HSC_GATE2")
	)
	(gr_poly
		(pts
			(xy 275.303488 -395.01318) (xy 275.303488 -394.17498) (xy 275.031708 -393.9032) (xy 274.460208 -393.9032)
			(xy 274.399248 -393.96416) (xy 274.399248 -394.3858) (xy 274.450048 -394.4366) (xy 274.640548 -394.4366)
			(xy 274.721828 -394.51788) (xy 274.721828 -394.63726) (xy 274.721828 -394.98778) (xy 274.815808 -395.08176)
			(xy 275.234908 -395.08176)
		)
		(stroke
			(width 0)
			(type solid)
		)
		(fill yes)
		(layer "F.Cu")
		(net "P12V_HSC_GATE2")
	)
	(gr_poly
		(pts
			(xy 302.387 -52.415948) (xy 302.387 -49.748948) (xy 302.387 -45.684948) (xy 302.26 -45.557948) (xy 301.371 -45.557948)
			(xy 301.117 -45.811948) (xy 301.117 -47.437548) (xy 301.4218 -47.742348) (xy 301.4218 -48.326548)
			(xy 301.117 -48.631348) (xy 301.117 -52.034948) (xy 301.625 -52.542948) (xy 302.26 -52.542948)
		)
		(stroke
			(width 0)
			(type solid)
		)
		(fill yes)
		(layer "F.Cu")
		(net "P1V05_PCH_AUX")
	)
	(gr_poly
		(pts
			(xy 351.25787 -238.0488) (xy 352.42119 -238.0488) (xy 352.52152 -237.94847) (xy 352.52152 -237.235492)
			(xy 352.067876 -236.781594) (xy 352.048064 -236.761782) (xy 352.048064 -236.262926) (xy 351.974404 -236.189266)
			(xy 350.633792 -236.189266) (xy 350.571054 -236.252004) (xy 350.571054 -238.306356) (xy 350.668844 -238.404146)
			(xy 350.902524 -238.404146)
		)
		(stroke
			(width 0)
			(type solid)
		)
		(fill yes)
		(layer "F.Cu")
		(net "GND")
	)
	(gr_poly
		(pts
			(xy 437.874664 -24.600408) (xy 437.900572 -24.574754) (xy 437.900572 -24.401018) (xy 438.103772 -24.197818)
			(xy 438.967372 -24.197818) (xy 439.043572 -24.121618) (xy 439.043572 -23.359618) (xy 438.916572 -23.232618)
			(xy 437.671972 -23.232618) (xy 437.189372 -23.715218) (xy 437.189372 -27.068018) (xy 437.240172 -27.118818)
			(xy 437.874664 -27.118818)
		)
		(stroke
			(width 0)
			(type solid)
		)
		(fill yes)
		(layer "F.Cu")
		(net "P12V_AUX")
	)
	(gr_poly
		(pts
			(xy 23.53691 -183.698896) (xy 23.53691 -182.790846) (xy 23.53691 -181.903878) (xy 23.47722 -181.844188)
			(xy 23.47722 -181.125876) (xy 23.38324 -181.031896) (xy 23.269448 -181.031896) (xy 23.24481 -181.056534)
			(xy 23.24481 -181.851046) (xy 23.02256 -182.073296) (xy 23.00351 -182.092346) (xy 23.00351 -183.703976)
			(xy 23.06955 -183.770016) (xy 23.46579 -183.770016)
		)
		(stroke
			(width 0)
			(type solid)
		)
		(fill yes)
		(layer "F.Cu")
		(net "PVNN_MAIN_CPU1_VCC")
	)
	(gr_poly
		(pts
			(xy 29.9593 -127.908304) (xy 29.9593 -126.006098) (xy 30.166564 -125.798834) (xy 30.166564 -125.37313)
			(xy 30.096714 -125.30328) (xy 28.626308 -125.30328) (xy 28.565856 -125.363732) (xy 28.565856 -125.797564)
			(xy 28.634182 -125.86589) (xy 28.634182 -126.30785) (xy 29.139642 -126.81331) (xy 29.139642 -127.697992)
			(xy 29.365956 -127.924306) (xy 29.943298 -127.924306)
		)
		(stroke
			(width 0)
			(type solid)
		)
		(fill yes)
		(layer "F.Cu")
		(net "PVCCINFAON_CPU1_VREF")
	)
	(gr_poly
		(pts
			(xy 46.648624 -106.12374) (xy 46.648624 -103.679498) (xy 46.204124 -103.234998) (xy 46.204124 -102.640384)
			(xy 46.079918 -102.516178) (xy 41.49852 -102.516178) (xy 41.465754 -102.548944) (xy 41.465754 -102.888542)
			(xy 41.485312 -102.9081) (xy 43.276012 -102.9081) (xy 45.328332 -104.96042) (xy 45.328332 -106.058462)
			(xy 45.576744 -106.306874) (xy 46.46549 -106.306874)
		)
		(stroke
			(width 0)
			(type solid)
		)
		(fill yes)
		(layer "F.Cu")
		(net "P3V3_MAX11617_VDD")
	)
	(gr_poly
		(pts
			(xy 59.846464 -175.879506) (xy 59.846464 -172.57141) (xy 59.615324 -172.34027) (xy 55.970424 -172.34027)
			(xy 55.416958 -172.34027) (xy 55.252112 -172.505116) (xy 55.252112 -173.11878) (xy 55.252112 -173.550072)
			(xy 55.252112 -175.339756) (xy 55.252112 -175.93818) (xy 55.429658 -176.115726) (xy 56.074056 -176.115726)
			(xy 56.466994 -176.115726) (xy 59.610244 -176.115726)
		)
		(stroke
			(width 0)
			(type solid)
		)
		(fill yes)
		(layer "F.Cu")
		(net "SW_PVCCFA_EHV_CPU1_SW1")
	)
	(gr_poly
		(pts
			(xy 85.01126 -54.012084) (xy 85.279992 -54.012084) (xy 85.41639 -53.875686) (xy 86.17839 -53.875686)
			(xy 86.30539 -53.748686) (xy 86.30539 -53.367686) (xy 86.17839 -53.240686) (xy 85.10143 -53.240686)
			(xy 84.04733 -53.240686) (xy 83.42249 -53.865526) (xy 83.42249 -53.992526) (xy 83.48091 -54.050946)
			(xy 84.29117 -54.050946) (xy 84.972398 -54.050946)
		)
		(stroke
			(width 0)
			(type solid)
		)
		(fill yes)
		(layer "F.Cu")
		(net "GND")
	)
	(gr_poly
		(pts
			(xy 120.64873 -239.61598) (xy 120.64873 -239.0902) (xy 120.59031 -239.03178) (xy 119.02186 -239.03178)
			(xy 118.96725 -239.08639) (xy 118.96725 -239.38738) (xy 118.916704 -239.43818) (xy 118.916704 -239.46358)
			(xy 118.72087 -239.65916) (xy 118.245636 -239.65916) (xy 118.24335 -239.6617) (xy 118.24335 -240.2332)
			(xy 118.27383 -240.26368) (xy 120.00103 -240.26368)
		)
		(stroke
			(width 0)
			(type solid)
		)
		(fill yes)
		(layer "F.Cu")
		(net "PVCCFA_EHV_FIVRA_CPU1")
	)
	(gr_poly
		(pts
			(arc
				(start 174.21098 -27.675078)
				(mid 174.28408 -27.620259)
				(end 174.36973 -27.588464)
			)
			(xy 174.409862 -27.579828) (xy 174.409862 -25.518872) (xy 174.282862 -25.391872) (xy 173.546262 -25.391872)
			(xy 173.495716 -25.442164) (xy 173.495716 -27.75458) (xy 173.622462 -27.881072) (xy 174.004732 -27.881072)
		)
		(stroke
			(width 0)
			(type solid)
		)
		(fill yes)
		(layer "F.Cu")
		(net "GND")
	)
	(gr_poly
		(pts
			(xy 250.995942 -99.607878) (xy 252.214126 -99.607878) (xy 252.327156 -99.720908) (xy 252.809248 -99.720908)
			(xy 252.809248 -99.416108) (xy 252.32106 -99.416108) (xy 252.21819 -99.518978) (xy 250.998482 -99.518978)
			(xy 250.839224 -99.35972) (xy 250.588272 -99.35972) (xy 250.519692 -99.428046) (xy 250.519692 -99.67849)
			(xy 250.580398 -99.739196) (xy 250.864624 -99.739196)
		)
		(stroke
			(width 0)
			(type solid)
		)
		(fill yes)
		(layer "F.Cu")
		(net "P3V3_AUX_CLK_GEN_VDDPT_CK440")
	)
	(gr_poly
		(pts
			(xy 261.088124 -100.289614) (xy 261.088124 -99.94773) (xy 261.016496 -99.876356) (xy 260.49732 -99.876356)
			(xy 260.362446 -100.01123) (xy 259.151374 -100.01123) (xy 259.04571 -99.905566) (xy 258.554728 -99.905566)
			(xy 258.554728 -100.210366) (xy 259.051044 -100.210366) (xy 259.16128 -100.10013) (xy 260.3246 -100.10013)
			(xy 260.650482 -100.426012) (xy 260.95198 -100.426012)
		)
		(stroke
			(width 0)
			(type solid)
		)
		(fill yes)
		(layer "F.Cu")
		(net "P3V3_AUX_CLK_GEN_VDDMXCK_CK440")
	)
	(gr_poly
		(pts
			(xy 326.968104 -16.684244) (xy 326.968104 -13.066014) (xy 326.869298 -12.967208) (xy 326.869044 -12.966954)
			(xy 326.86498 -12.96289) (xy 326.839072 -12.937236) (xy 322.831206 -12.937236) (xy 322.805298 -12.96289)
			(xy 322.801234 -12.966954) (xy 322.80098 -12.967208) (xy 322.62064 -13.147548) (xy 322.62064 -16.642588)
			(xy 322.961 -16.982948) (xy 326.6694 -16.982948)
		)
		(stroke
			(width 0)
			(type solid)
		)
		(fill yes)
		(layer "F.Cu")
		(net "PGPPA_AUX")
	)
	(gr_poly
		(pts
			(xy 368.588544 -239.615726) (xy 368.588544 -239.089946) (xy 368.530124 -239.031526) (xy 366.961674 -239.031526)
			(xy 366.907064 -239.086136) (xy 366.907064 -239.387126) (xy 366.856264 -239.437672) (xy 366.856264 -239.463326)
			(xy 366.660684 -239.65916) (xy 366.185704 -239.65916) (xy 366.183164 -239.661446) (xy 366.183164 -240.232946)
			(xy 366.213644 -240.263426) (xy 367.940844 -240.263426)
		)
		(stroke
			(width 0)
			(type solid)
		)
		(fill yes)
		(layer "F.Cu")
		(net "PVCCFA_EHV_FIVRA_CPU0")
	)
	(gr_poly
		(pts
			(xy 376.771916 -362.265722) (xy 376.771916 -361.65917) (xy 376.771916 -360.04246) (xy 376.704606 -359.97515)
			(xy 374.695212 -359.97515) (xy 374.64492 -360.025442) (xy 374.64492 -360.429556) (xy 374.701308 -360.485944)
			(xy 375.91873 -360.485944) (xy 376.06478 -360.631994) (xy 376.06478 -361.60329) (xy 376.06478 -362.32719)
			(xy 376.143266 -362.405676) (xy 376.631962 -362.405676)
		)
		(stroke
			(width 0)
			(type solid)
		)
		(fill yes)
		(layer "F.Cu")
		(net "PVPP_HBM_CPU0_VCC")
	)
	(gr_poly
		(pts
			(xy 383.75336 -75.722988) (xy 383.75336 -75.560428) (xy 383.72796 -75.535028) (xy 383.29362 -75.535028)
			(xy 383.158746 -75.535028) (xy 382.33604 -74.712322) (xy 381.945388 -74.712322) (xy 381.894588 -74.763122)
			(xy 381.894588 -75.148948) (xy 381.919988 -75.174348) (xy 382.427226 -75.174348) (xy 382.9812 -75.728322)
			(xy 383.011426 -75.758548) (xy 383.7178 -75.758548)
		)
		(stroke
			(width 0)
			(type solid)
		)
		(fill yes)
		(layer "F.Cu")
		(net "SW_P1V8_PCH_AUX_BST")
	)
	(gr_poly
		(pts
			(xy 445.029844 -77.286104) (xy 445.029844 -76.476352) (xy 444.95212 -76.398628) (xy 444.22822 -76.398628)
			(xy 443.97803 -76.148438) (xy 443.97803 -74.980546) (xy 443.912498 -74.915014) (xy 442.714634 -74.915014)
			(xy 442.537596 -75.092052) (xy 442.537596 -75.969114) (xy 442.537596 -76.205842) (xy 442.537596 -77.123544)
			(xy 442.849 -77.434948) (xy 444.881 -77.434948)
		)
		(stroke
			(width 0)
			(type solid)
		)
		(fill yes)
		(layer "F.Cu")
		(net "GND")
	)
	(gr_poly
		(pts
			(xy 450.18579 -70.436232) (xy 450.57949 -70.436232) (xy 450.93255 -70.436232) (xy 451.19163 -70.436232)
			(xy 451.303136 -70.324726) (xy 451.303136 -65.925446) (xy 451.234556 -65.856866) (xy 450.909436 -65.856866)
			(xy 446.433956 -65.856866) (xy 446.235836 -66.054986) (xy 446.235836 -70.398386) (xy 446.289176 -70.451726)
			(xy 446.472056 -70.451726) (xy 450.170296 -70.451726)
		)
		(stroke
			(width 0)
			(type solid)
		)
		(fill yes)
		(layer "F.Cu")
		(net "SW_P3V3_AUX_SW")
	)
	(gr_poly
		(pts
			(xy 453.689212 -23.857458) (xy 453.689212 -22.780498) (xy 453.689212 -21.726398) (xy 453.064372 -21.101558)
			(xy 452.937372 -21.101558) (xy 452.878952 -21.159978) (xy 452.878952 -21.970238) (xy 452.878952 -22.920198)
			(xy 453.054212 -23.095458) (xy 453.054212 -23.096728) (xy 453.17918 -23.221696) (xy 453.17918 -23.859998)
			(xy 453.30364 -23.984458) (xy 453.562212 -23.984458)
		)
		(stroke
			(width 0)
			(type solid)
		)
		(fill yes)
		(layer "F.Cu")
		(net "GND")
	)
	(gr_poly
		(pts
			(xy 24.420576 -178.982624) (xy 24.420576 -178.486816) (xy 24.105616 -178.171856) (xy 23.908004 -178.171856)
			(xy 23.749508 -178.330352) (xy 23.749508 -178.940206)
			(arc
				(start 23.724108 -178.965606)
				(mid 23.713129 -179.020802)
				(end 23.759922 -179.05222)
			)
			(xy 24.35098 -179.05222)
		)
		(stroke
			(width 0)
			(type solid)
		)
		(fill yes)
		(layer "F.Cu")
		(net "PVNN_MAIN_CPU1_REF")
	)
	(gr_poly
		(pts
			(xy 104.785922 -247.414796) (xy 104.785922 -245.907052) (xy 104.643682 -245.764812) (xy 103.566976 -245.764812)
			(xy 103.565452 -245.766336) (xy 103.171752 -245.766336) (xy 102.52202 -246.416068)
			(arc
				(start 102.52202 -247.0023)
				(mid 102.551052 -247.060224)
				(end 102.568248 -247.122696)
			)
			(xy 102.570788 -247.138698) (xy 103.024686 -247.592596) (xy 104.608122 -247.592596)
		)
		(stroke
			(width 0)
			(type solid)
		)
		(fill yes)
		(layer "F.Cu")
		(net "PVCCD_HV_CPU1")
	)
	(gr_poly
		(pts
			(xy 174.81042 -21.816568) (xy 174.81042 -20.579588) (xy 175.64608 -19.743928) (xy 175.64608 -19.141948)
			(xy 175.52416 -19.020028) (xy 174.96028 -19.020028) (xy 174.78502 -19.195288) (xy 173.99508 -19.195288)
			(xy 172.95876 -20.231608) (xy 172.64888 -20.231608) (xy 172.1993 -20.681188) (xy 172.1993 -22.001988)
			(xy 172.27042 -22.001988) (xy 172.339 -22.070568) (xy 174.55642 -22.070568)
		)
		(stroke
			(width 0)
			(type solid)
		)
		(fill yes)
		(layer "F.Cu")
		(net "GND")
	)
	(gr_poly
		(pts
			(xy 258.19608 -104.472994) (xy 258.19608 -104.258364) (xy 258.03098 -104.093264) (xy 258.030726 -104.093772)
			(xy 257.748532 -104.093772) (xy 257.716782 -104.062022) (xy 257.716782 -103.027988) (xy 257.831844 -102.912926)
			(xy 257.831844 -102.438708) (xy 257.527044 -102.438708) (xy 257.527044 -102.925372) (xy 257.627882 -103.02621)
			(xy 257.627882 -104.464612) (xy 257.808222 -104.644952) (xy 258.024122 -104.644952)
		)
		(stroke
			(width 0)
			(type solid)
		)
		(fill yes)
		(layer "F.Cu")
		(net "P3V3_AUX_CLK_GEN_VDDMXCK_CK440")
	)
	(gr_poly
		(pts
			(xy 323.795644 -336.663284) (xy 324.973696 -335.485232) (xy 330.864464 -335.485232) (xy 331.169264 -335.180432)
			(xy 331.169264 -333.986632) (xy 330.915264 -333.732632) (xy 325.84644 -333.732632) (xy 324.936358 -332.82255)
			(xy 317.686944 -332.82255) (xy 317.453264 -333.05623) (xy 317.453264 -334.240632) (xy 317.453264 -336.39887)
			(xy 317.453264 -337.226656) (xy 317.552578 -337.32597) (xy 323.132958 -337.32597)
		)
		(stroke
			(width 0)
			(type solid)
		)
		(fill yes)
		(layer "F.Cu")
		(net "IND_P0_CPL7")
	)
	(gr_poly
		(pts
			(xy 352.725736 -247.414542) (xy 352.725736 -245.906798) (xy 352.583496 -245.764558) (xy 351.50679 -245.764558)
			(xy 351.505266 -245.766082) (xy 351.111566 -245.766082) (xy 350.461834 -246.415814)
			(arc
				(start 350.461834 -247.001792)
				(mid 350.49105 -247.059946)
				(end 350.508316 -247.122696)
			)
			(xy 350.510856 -247.138698) (xy 350.9645 -247.592342) (xy 352.547936 -247.592342)
		)
		(stroke
			(width 0)
			(type solid)
		)
		(fill yes)
		(layer "F.Cu")
		(net "PVCCD_HV_CPU0")
	)
	(gr_poly
		(pts
			(xy 363.681264 -325.022464) (xy 363.247432 -324.588632) (xy 358.601264 -324.588632) (xy 358.347264 -324.334632)
			(xy 358.347264 -322.810632) (xy 358.118664 -322.582032) (xy 350.701864 -322.582032) (xy 350.473264 -322.810632)
			(xy 350.473264 -323.953632) (xy 350.854264 -324.334632) (xy 355.172264 -324.334632) (xy 355.680264 -324.842632)
			(xy 355.680264 -326.112632) (xy 355.858064 -326.290432) (xy 363.681264 -326.290432)
		)
		(stroke
			(width 0)
			(type solid)
		)
		(fill yes)
		(layer "F.Cu")
		(net "IND_P0_CPL3")
	)
	(gr_poly
		(pts
			(xy 423.598848 -134.648956) (xy 423.598848 -132.878068) (xy 423.7863 -132.690616) (xy 423.7863 -132.146548)
			(xy 423.72407 -132.084318) (xy 423.598848 -132.084318) (xy 422.270174 -132.084318) (xy 422.209722 -132.14477)
			(xy 422.209722 -132.578602) (xy 422.278048 -132.646928) (xy 422.278048 -133.088888) (xy 422.783508 -133.594348)
			(xy 422.783508 -134.47903) (xy 423.009822 -134.705344) (xy 423.54246 -134.705344)
		)
		(stroke
			(width 0)
			(type solid)
		)
		(fill yes)
		(layer "F.Cu")
		(net "PVCCINFAON_CPU0_VREF")
	)
	(gr_poly
		(pts
			(xy 433.315618 -184.826148) (xy 433.315618 -183.94807) (xy 433.348638 -183.91505) (xy 433.348638 -182.80507)
			(xy 433.348638 -182.185818) (xy 433.31892 -182.1561) (xy 433.081176 -182.1561) (xy 433.056538 -182.180738)
			(xy 433.056538 -182.97525) (xy 432.834288 -183.1975) (xy 432.834288 -183.8833) (xy 432.841908 -183.89092)
			(xy 432.841908 -184.755028) (xy 432.948588 -184.861708) (xy 433.280058 -184.861708)
		)
		(stroke
			(width 0)
			(type solid)
		)
		(fill yes)
		(layer "F.Cu")
		(net "PVNN_MAIN_CPU0_VCC")
	)
	(gr_poly
		(pts
			(xy 440.4614 -22.289008) (xy 440.40171 -22.229318) (xy 439.28411 -22.229318) (xy 439.14822 -22.093428)
			(xy 438.79516 -22.093428) (xy 438.658 -22.230588) (xy 438.658 -22.713188) (xy 438.79516 -22.850348)
			(xy 439.1914 -22.850348) (xy 439.592212 -23.25116) (xy 439.592212 -25.573736) (xy 440.049412 -26.030936)
			(xy 440.049412 -27.106118) (xy 440.125612 -27.182318) (xy 440.4614 -27.182318)
		)
		(stroke
			(width 0)
			(type solid)
		)
		(fill yes)
		(layer "F.Cu")
		(net "P12V_OCP_AVIN_PD_1")
	)
	(gr_poly
		(pts
			(xy 449.33108 -378.729748) (xy 449.33108 -369.179348) (xy 448.16268 -368.010948) (xy 443.10808 -368.010948)
			(xy 442.85408 -368.264948) (xy 442.85408 -370.500148) (xy 443.28588 -370.931948) (xy 443.31128 -370.906548)
			(xy 443.94628 -370.906548) (xy 446.22466 -373.184928) (xy 446.22466 -378.973588) (xy 446.3796 -379.128528)
			(xy 446.70726 -379.128528) (xy 446.71488 -379.136148) (xy 448.92468 -379.136148)
		)
		(stroke
			(width 0)
			(type solid)
		)
		(fill yes)
		(layer "F.Cu")
		(net "GND")
	)
	(gr_poly
		(pts
			(xy 41.237916 -393.632182) (xy 41.237916 -391.275824) (xy 41.101264 -391.139172) (xy 38.802564 -391.139172)
			(xy 38.684454 -391.257282) (xy 38.684454 -391.951972) (xy 38.574472 -392.061954) (xy 37.827712 -392.061954)
			(xy 37.777674 -392.111992) (xy 37.777674 -392.24585) (xy 37.824664 -392.29284) (xy 38.616636 -392.29284)
			(xy 38.668706 -392.34491) (xy 38.668706 -393.666218) (xy 38.71341 -393.710922) (xy 41.159176 -393.710922)
		)
		(stroke
			(width 0)
			(type solid)
		)
		(fill yes)
		(layer "F.Cu")
		(net "GND")
	)
	(gr_poly
		(pts
			(xy 74.37628 -63.045848) (xy 74.37628 -60.157868) (xy 73.14692 -58.928508) (xy 72.43572 -58.928508)
			(xy 72.352154 -58.845196) (xy 72.32015 -58.845196) (xy 72.041512 -58.566558) (xy 72.041512 -58.5343)
			(xy 71.91502 -58.407808) (xy 71.91502 -58.214768) (xy 71.74738 -58.047128) (xy 71.5899 -58.047128)
			(xy 71.24192 -58.395108) (xy 71.24192 -63.165228) (xy 71.47306 -63.396368) (xy 74.02576 -63.396368)
		)
		(stroke
			(width 0)
			(type solid)
		)
		(fill yes)
		(layer "F.Cu")
		(net "GND")
	)
	(gr_poly
		(pts
			(xy 85.442298 -334.479392) (xy 85.442298 -328.35596) (xy 86.161626 -327.636632) (xy 91.495626 -327.636632)
			(xy 91.749626 -327.382632) (xy 91.749626 -326.112632) (xy 91.564968 -325.927974) (xy 85.617812 -325.927974)
			(xy 83.875626 -327.67016) (xy 83.875626 -333.191612) (xy 82.96021 -334.107028) (xy 78.43266 -334.107028)
			(xy 78.41996 -334.119728) (xy 78.41996 -335.453228) (xy 78.44536 -335.478628) (xy 84.443062 -335.478628)
		)
		(stroke
			(width 0)
			(type solid)
		)
		(fill yes)
		(layer "F.Cu")
		(net "IND_P1_CPL7")
	)
	(gr_poly
		(pts
			(xy 93.908626 -329.093322) (xy 93.908626 -324.969632) (xy 94.543626 -324.334632) (xy 99.242626 -324.334632)
			(xy 99.750626 -323.826632) (xy 99.750626 -322.810632) (xy 99.522026 -322.582032) (xy 94.54007 -322.582032)
			(xy 92.003626 -325.118476) (xy 92.003626 -327.636632) (xy 91.749626 -327.890632) (xy 86.288626 -327.890632)
			(xy 85.780626 -328.398632) (xy 85.780626 -329.414632) (xy 86.01075 -329.644756) (xy 93.357192 -329.644756)
		)
		(stroke
			(width 0)
			(type solid)
		)
		(fill yes)
		(layer "F.Cu")
		(net "IND_P1_CPL6")
	)
	(gr_poly
		(pts
			(xy 103.931466 -263.133078) (xy 103.931466 -261.999476) (xy 103.778304 -261.846314) (xy 103.772716 -261.846314)
			(xy 103.694484 -261.768082) (xy 103.694484 -260.448552) (xy 103.923084 -260.219952) (xy 108.477558 -260.219952)
			(xy 108.62437 -260.07314) (xy 108.62437 -258.85648) (xy 108.551218 -258.783328) (xy 102.863142 -258.783328)
			(xy 102.731316 -258.915154) (xy 102.731316 -263.115044) (xy 102.8573 -263.241028) (xy 103.823516 -263.241028)
		)
		(stroke
			(width 0)
			(type solid)
		)
		(fill yes)
		(layer "F.Cu")
		(net "GND")
	)
	(gr_poly
		(pts
			(xy 118.800626 -325.985632) (xy 118.800626 -324.715632) (xy 119.181626 -324.334632) (xy 123.400058 -324.334632)
			(xy 123.781058 -323.953632) (xy 123.781058 -322.736464) (xy 123.626626 -322.582032) (xy 116.489226 -322.582032)
			(xy 116.261134 -322.810124) (xy 116.261134 -324.080124) (xy 115.752626 -324.588632) (xy 111.180626 -324.588632)
			(xy 110.799626 -324.969632) (xy 110.799626 -326.112632) (xy 110.962694 -326.2757) (xy 118.510558 -326.2757)
		)
		(stroke
			(width 0)
			(type solid)
		)
		(fill yes)
		(layer "F.Cu")
		(net "IND_P1_CPL3")
	)
	(gr_poly
		(pts
			(xy 128.832102 -362.265722) (xy 128.832102 -361.65917) (xy 128.832102 -361.112054) (xy 128.795018 -361.07497)
			(xy 128.795018 -360.06659) (xy 128.703578 -359.97515) (xy 126.755398 -359.97515) (xy 126.705106 -360.025442)
			(xy 126.705106 -360.429556) (xy 126.761494 -360.485944) (xy 127.978916 -360.485944) (xy 128.124966 -360.631994)
			(xy 128.219962 -360.72699) (xy 128.219962 -362.272326) (xy 128.353058 -362.405676) (xy 128.692148 -362.405676)
		)
		(stroke
			(width 0)
			(type solid)
		)
		(fill yes)
		(layer "F.Cu")
		(net "PVPP_HBM_CPU1_VCC")
	)
	(gr_poly
		(pts
			(xy 216.0651 -55.072788) (xy 216.0651 -54.437788) (xy 216.1921 -54.310788) (xy 216.90076 -54.310788)
			(xy 216.9541 -54.257448) (xy 216.9541 -54.158388) (xy 216.86266 -54.066948) (xy 216.23782 -54.066948)
			(xy 216.08288 -53.912008) (xy 216.08288 -53.721508) (xy 215.95588 -53.594508) (xy 214.61476 -53.594508)
			(xy 214.43188 -53.777388) (xy 214.43188 -55.192168) (xy 214.49538 -55.255668) (xy 215.88222 -55.255668)
		)
		(stroke
			(width 0)
			(type solid)
		)
		(fill yes)
		(layer "F.Cu")
		(net "GND")
	)
	(gr_poly
		(pts
			(xy 245.19128 -39.750746) (xy 247.20042 -39.750746) (xy 247.824752 -39.126414) (xy 247.83669 -39.126414)
			(xy 247.894602 -39.068248) (xy 249.525536 -39.068248) (xy 249.546872 -39.047166) (xy 249.546872 -37.320982)
			(xy 249.191526 -36.965636) (xy 247.79859 -36.965636) (xy 247.78208 -36.982146) (xy 242.90528 -36.982146)
			(xy 242.62588 -37.261546) (xy 242.62588 -40.436546) (xy 242.77828 -40.588946) (xy 244.35308 -40.588946)
		)
		(stroke
			(width 0)
			(type solid)
		)
		(fill yes)
		(layer "F.Cu")
		(net "GND")
	)
	(gr_poly
		(pts
			(xy 255.559306 -105.528872) (xy 255.559306 -105.213912) (xy 255.404366 -105.058972) (xy 255.233932 -105.058972)
			(xy 255.226058 -105.051098) (xy 255.226058 -103.016812) (xy 255.344676 -102.898194) (xy 255.344676 -102.438708)
			(xy 255.026922 -102.438708) (xy 255.026922 -102.91191) (xy 255.137158 -103.022146) (xy 255.137158 -105.088182)
			(xy 255.037082 -105.188258) (xy 255.037082 -105.507028) (xy 255.119886 -105.589832) (xy 255.498346 -105.589832)
		)
		(stroke
			(width 0)
			(type solid)
		)
		(fill yes)
		(layer "F.Cu")
		(net "P3V3_AUX_CLK_GEN_VDDMXCK_CK440")
	)
	(gr_poly
		(pts
			(xy 263.736582 -70.359778) (xy 263.878314 -70.218046) (xy 263.878314 -69.521324) (xy 263.873742 -69.516752)
			(xy 263.873742 -67.914012) (xy 263.873742 -66.809366) (xy 263.873742 -66.20637) (xy 263.732772 -66.0654)
			(xy 263.377172 -66.0654) (xy 263.235186 -66.207386) (xy 263.235186 -66.815462) (xy 263.235186 -67.884294)
			(xy 263.241282 -67.89039) (xy 263.241282 -70.400418) (xy 263.29386 -70.452996) (xy 263.643364 -70.452996)
		)
		(stroke
			(width 0)
			(type solid)
		)
		(fill yes)
		(layer "F.Cu")
		(net "P1V05_PCH_AUX_VCC")
	)
	(gr_poly
		(pts
			(xy 277.36038 -405.8285) (xy 277.36038 -403.99462) (xy 277.5204 -403.8346) (xy 278.31034 -403.8346)
			(xy 278.37384 -403.8981) (xy 278.37384 -405.7777) (xy 278.51862 -405.92248) (xy 280.90622 -405.92248)
			(xy 281.051508 -405.777192) (xy 281.051508 -397.72844) (xy 280.706068 -397.383) (xy 275.6408 -397.383)
			(xy 275.3868 -397.637) (xy 275.3868 -405.8285) (xy 275.48332 -405.92502) (xy 277.26386 -405.92502)
		)
		(stroke
			(width 0)
			(type solid)
		)
		(fill yes)
		(layer "F.Cu")
		(net "P12V_MAIN_R_0")
	)
	(gr_poly
		(pts
			(xy 299.20184 -413.53994) (xy 299.20184 -412.75508) (xy 299.29328 -412.66364) (xy 300.0502 -412.66364)
			(xy 300.06544 -412.6484) (xy 300.06544 -412.48838) (xy 300.02988 -412.45282) (xy 299.27042 -412.45282)
			(xy 299.16628 -412.34868) (xy 299.16628 -412.0515) (xy 299.10532 -411.99054) (xy 297.66768 -411.99054)
			(xy 297.5102 -412.14802) (xy 297.5102 -413.56534) (xy 297.58132 -413.63646) (xy 299.10532 -413.63646)
		)
		(stroke
			(width 0)
			(type solid)
		)
		(fill yes)
		(layer "F.Cu")
		(net "GND")
	)
	(gr_poly
		(pts
			(xy 333.328264 -332.38948) (xy 333.328264 -330.811632) (xy 334.547464 -329.592432) (xy 338.992464 -329.592432)
			(xy 339.170264 -329.414632) (xy 339.170264 -328.144632) (xy 338.916264 -327.890632) (xy 333.902304 -327.890632)
			(xy 331.677264 -330.115672) (xy 331.677264 -330.938632) (xy 330.864464 -331.751432) (xy 326.292464 -331.751432)
			(xy 326.089264 -331.954632) (xy 326.089264 -333.224632) (xy 326.343264 -333.478632) (xy 332.239112 -333.478632)
		)
		(stroke
			(width 0)
			(type solid)
		)
		(fill yes)
		(layer "F.Cu")
		(net "IND_P0_CPL6")
	)
	(gr_poly
		(pts
			(xy 351.87128 -263.132824) (xy 351.87128 -261.999222) (xy 351.718118 -261.84606) (xy 351.71253 -261.84606)
			(xy 351.634298 -261.767828) (xy 351.634298 -260.448298) (xy 351.862898 -260.219698) (xy 356.417372 -260.219698)
			(xy 356.564184 -260.072886) (xy 356.564184 -258.856226) (xy 356.491032 -258.783074) (xy 350.802956 -258.783074)
			(xy 350.67113 -258.9149) (xy 350.67113 -263.11479) (xy 350.797114 -263.240774) (xy 351.76333 -263.240774)
		)
		(stroke
			(width 0)
			(type solid)
		)
		(fill yes)
		(layer "F.Cu")
		(net "GND")
	)
	(gr_poly
		(pts
			(xy 355.426264 -326.112632) (xy 355.426264 -324.969632) (xy 355.045264 -324.588632) (xy 350.727264 -324.588632)
			(xy 350.219264 -324.080632) (xy 350.219264 -322.810632) (xy 349.990664 -322.582032) (xy 342.573102 -322.582032)
			(xy 342.218264 -322.935854) (xy 342.218264 -324.207632) (xy 342.345264 -324.334632) (xy 347.044264 -324.334632)
			(xy 347.552264 -324.842632) (xy 347.552264 -326.112632) (xy 347.730064 -326.290432) (xy 355.248464 -326.290432)
		)
		(stroke
			(width 0)
			(type solid)
		)
		(fill yes)
		(layer "F.Cu")
		(net "IND_P0_CPL2")
	)
	(gr_poly
		(pts
			(xy 371.707664 -326.214232) (xy 371.707664 -324.868032) (xy 371.428264 -324.588632) (xy 366.729264 -324.588632)
			(xy 366.475264 -324.334632) (xy 366.475264 -322.810632) (xy 366.246664 -322.582032) (xy 358.830372 -322.582032)
			(xy 358.601264 -322.810632) (xy 358.601264 -324.080632) (xy 358.855264 -324.334632) (xy 363.427264 -324.334632)
			(xy 363.935264 -324.842632) (xy 363.935264 -326.112632) (xy 364.113064 -326.290432) (xy 371.631464 -326.290432)
		)
		(stroke
			(width 0)
			(type solid)
		)
		(fill yes)
		(layer "F.Cu")
		(net "IND_P0_CPL4")
	)
	(gr_poly
		(pts
			(xy 431.18532 -185.05805) (xy 431.18532 -184.516268) (xy 431.5714 -184.130188) (xy 432.424078 -184.130188)
			(xy 432.571398 -183.982868) (xy 432.571398 -183.04129) (xy 432.777138 -182.83555) (xy 432.777138 -182.08117)
			(xy 432.556158 -181.86019) (xy 431.334418 -181.86019) (xy 431.173128 -181.6989) (xy 426.584618 -181.6989)
			(xy 426.452792 -181.830726) (xy 426.452792 -185.258964) (xy 426.576998 -185.38317) (xy 430.8602 -185.38317)
		)
		(stroke
			(width 0)
			(type solid)
		)
		(fill yes)
		(layer "F.Cu")
		(net "GND")
	)
	(gr_poly
		(pts
			(xy 140.517626 -333.097632) (xy 140.517626 -331.827632) (xy 140.390626 -331.700632) (xy 135.927592 -331.700632)
			(xy 134.167626 -329.940666) (xy 134.167626 -329.005184) (xy 133.053074 -327.890632) (xy 127.64389 -327.890632)
			(xy 127.437896 -328.096626) (xy 127.437896 -328.362564) (xy 127.437896 -329.557888) (xy 127.524764 -329.644756)
			(xy 131.98475 -329.644756) (xy 133.024626 -330.684632) (xy 133.024626 -332.970632) (xy 133.532626 -333.478632)
			(xy 140.136626 -333.478632)
		)
		(stroke
			(width 0)
			(type solid)
		)
		(fill yes)
		(layer "F.Cu")
		(net "IND_P1_CPL5")
	)
	(gr_poly
		(pts
			(xy 247.003316 -55.058564) (xy 247.003316 -53.260752) (xy 246.843296 -53.100732) (xy 245.104666 -53.100732)
			(xy 244.51056 -52.506626) (xy 244.51056 -50.497486) (xy 244.2464 -50.233326) (xy 241.09426 -50.233326)
			(xy 241.0714 -50.210466) (xy 240.8682 -50.413666) (xy 240.8682 -50.954686) (xy 240.99012 -51.076606)
			(xy 242.65128 -51.076606) (xy 243.23548 -51.660806) (xy 243.23548 -53.923946) (xy 244.50548 -55.193946)
			(xy 246.86768 -55.193946)
		)
		(stroke
			(width 0)
			(type solid)
		)
		(fill yes)
		(layer "F.Cu")
		(net "GND")
	)
	(gr_poly
		(pts
			(xy 265.6205 -96.096328) (xy 266.59332 -96.096328) (xy 266.87018 -95.819468) (xy 266.87018 -94.534228)
			(xy 266.68984 -94.353888) (xy 266.300204 -94.353888) (xy 266.293346 -94.361) (xy 263.952228 -94.361)
			(xy 263.772396 -94.540832) (xy 263.772396 -95.374714) (xy 263.73328 -95.41383) (xy 263.73328 -96.027748)
			(arc
				(start 263.750044 -96.044512)
				(mid 263.797938 -96.070336)
				(end 263.840722 -96.103948)
			)
			(xy 265.61288 -96.103948)
		)
		(stroke
			(width 0)
			(type solid)
		)
		(fill yes)
		(layer "F.Cu")
		(net "GND")
	)
	(gr_poly
		(pts
			(xy 383.726182 -75.036172) (xy 383.726182 -74.353928) (xy 383.662428 -74.290174) (xy 383.487168 -74.11466)
			(xy 383.487168 -73.66635) (xy 383.487168 -72.964548) (xy 383.386076 -72.863456) (xy 381.823214 -72.863456)
			(xy 381.762254 -72.924416) (xy 381.762254 -73.321672) (xy 382.405636 -73.965054) (xy 382.878584 -74.438002)
			(xy 383.092198 -74.651616) (xy 383.280666 -74.840084) (xy 383.37236 -74.931778) (xy 383.489454 -75.048872)
			(xy 383.713736 -75.048872)
		)
		(stroke
			(width 0)
			(type solid)
		)
		(fill yes)
		(layer "F.Cu")
		(net "P1V8_PCH_AUX_VCC")
	)
	(gr_poly
		(pts
			(arc
				(start 397.709136 -51.935634)
				(mid 397.736969 -51.931983)
				(end 397.765016 -51.930808)
			)
			(xy 398.804384 -51.930808) (xy 398.881092 -51.8541) (xy 398.881092 -51.703224) (xy 398.791938 -51.61407)
			(xy 397.091408 -51.61407) (xy 397.077692 -51.627786) (xy 396.659354 -51.627786) (xy 396.39875 -51.367182)
			(xy 395.473174 -51.367182) (xy 395.274292 -51.566064) (xy 395.274292 -51.812952) (xy 395.397736 -51.936396)
			(xy 397.704818 -51.936396)
		)
		(stroke
			(width 0)
			(type solid)
		)
		(fill yes)
		(layer "F.Cu")
		(net "P3V3_AUX")
	)
	(gr_poly
		(pts
			(xy 435.205886 -124.862844) (xy 435.205886 -124.712476) (xy 435.193186 -124.699776) (xy 434.371242 -124.699776)
			(xy 434.32984 -124.658374) (xy 434.32984 -121.171716) (xy 434.317902 -121.159778) (xy 430.705514 -121.159778)
			(xy 430.67224 -121.193052) (xy 430.67224 -124.242322) (xy 430.619662 -124.2949) (xy 430.614836 -124.299726)
			(xy 429.82261 -124.299726) (xy 429.796194 -124.326142) (xy 429.796194 -124.854208) (xy 429.819562 -124.877576)
			(xy 435.191154 -124.877576)
		)
		(stroke
			(width 0)
			(type solid)
		)
		(fill yes)
		(layer "F.Cu")
		(net "GND")
	)
	(gr_poly
		(pts
			(xy 446.461642 -390.946894) (xy 446.461642 -379.96749) (xy 446.163446 -379.669294) (xy 446.163446 -379.651514)
			(xy 445.82588 -379.313948) (xy 445.82588 -375.630948) (xy 445.82588 -374.482868) (xy 445.62776 -374.284748)
			(xy 445.11468 -374.284748) (xy 444.75908 -374.284748) (xy 438.58688 -374.284748) (xy 437.618124 -375.253504)
			(xy 437.618124 -379.669294) (xy 437.552846 -379.734572) (xy 437.552846 -390.946894) (xy 438.082182 -391.476484)
			(xy 445.932306 -391.476484)
		)
		(stroke
			(width 0)
			(type solid)
		)
		(fill yes)
		(layer "F.Cu")
		(net "P5V_AUX")
	)
	(gr_poly
		(pts
			(xy 101.309424 -326.2757) (xy 102.121462 -326.2757) (xy 102.290626 -326.106536) (xy 102.290626 -324.836536)
			(xy 102.79253 -324.334632) (xy 107.409488 -324.334632) (xy 107.790488 -323.953632) (xy 107.790488 -322.821554)
			(xy 107.550204 -322.582032) (xy 100.233226 -322.582032) (xy 100.004626 -322.810632) (xy 100.004626 -323.947536)
			(xy 99.36353 -324.588632) (xy 94.797626 -324.588632) (xy 94.162626 -325.223632) (xy 94.162626 -326.112632)
			(xy 94.340426 -326.290432) (xy 101.294692 -326.290432)
		)
		(stroke
			(width 0)
			(type solid)
		)
		(fill yes)
		(layer "F.Cu")
		(net "IND_P1_CPL1")
	)
	(gr_poly
		(pts
			(xy 109.525562 -326.2757) (xy 110.3376 -326.2757) (xy 110.545626 -326.067674) (xy 110.545626 -324.797674)
			(xy 111.008668 -324.334632) (xy 115.625626 -324.334632) (xy 116.006626 -323.953632) (xy 116.006626 -322.821554)
			(xy 115.766342 -322.582032) (xy 108.316268 -322.582032) (xy 108.088176 -322.810124) (xy 108.088176 -324.080124)
			(xy 107.579668 -324.588632) (xy 102.925626 -324.588632) (xy 102.544626 -324.969632) (xy 102.544626 -326.112632)
			(xy 102.722426 -326.290432) (xy 109.51083 -326.290432)
		)
		(stroke
			(width 0)
			(type solid)
		)
		(fill yes)
		(layer "F.Cu")
		(net "IND_P1_CPL2")
	)
	(gr_poly
		(pts
			(xy 133.025642 -74.162666) (xy 133.827774 -74.162666) (xy 133.84784 -74.1426) (xy 135.303006 -74.1426)
			(xy 135.57123 -73.874376) (xy 135.57123 -72.88657) (xy 135.330692 -72.646032) (xy 134.51713 -72.646032)
			(xy 134.28218 -72.411082) (xy 134.28218 -70.328028) (xy 133.72846 -69.774308) (xy 131.555236 -69.774308)
			(xy 131.285488 -70.044056) (xy 131.285488 -72.076818) (xy 130.749548 -72.612758) (xy 130.749548 -74.662792)
			(xy 130.857498 -74.770742) (xy 132.417566 -74.770742)
		)
		(stroke
			(width 0)
			(type solid)
		)
		(fill yes)
		(layer "F.Cu")
		(net "P3V3_AUX_BMC_D")
	)
	(gr_poly
		(pts
			(xy 147.994878 -337.21421) (xy 147.994878 -333.21117) (xy 147.641818 -332.85811) (xy 146.886422 -332.85811)
			(xy 141.392148 -332.85811) (xy 140.771626 -333.478632) (xy 140.517626 -333.732632) (xy 135.818626 -333.732632)
			(xy 135.564626 -333.986632) (xy 135.564626 -335.185258) (xy 135.805926 -335.426558) (xy 142.100808 -335.426558)
			(xy 142.847568 -336.173318) (xy 143.339058 -336.664808) (xy 143.339058 -337.32343) (xy 143.460978 -337.44535)
			(xy 144.1196 -337.44535) (xy 147.763738 -337.44535)
		)
		(stroke
			(width 0)
			(type solid)
		)
		(fill yes)
		(layer "F.Cu")
		(net "IND_P1_CPL8")
	)
	(gr_poly
		(pts
			(xy 192.99428 -72.380348) (xy 192.99428 -71.694548) (xy 193.14668 -71.542148) (xy 193.83248 -71.542148)
			(xy 194.01028 -71.719948) (xy 194.59448 -71.719948) (xy 194.74688 -71.567548) (xy 194.74688 -69.784468)
			(xy 194.57416 -69.611748) (xy 193.97472 -69.611748) (xy 193.90868 -69.677788) (xy 193.90868 -70.195948)
			(xy 193.42608 -70.678548) (xy 192.13068 -70.678548) (xy 191.92748 -70.881748) (xy 191.92748 -72.405748)
			(xy 192.05448 -72.532748) (xy 192.84188 -72.532748)
		)
		(stroke
			(width 0)
			(type solid)
		)
		(fill yes)
		(layer "F.Cu")
		(net "P3V3_AUX")
	)
	(gr_poly
		(pts
			(xy 379.899164 -329.630532) (xy 379.899164 -328.242676) (xy 379.54712 -327.890632) (xy 375.568464 -327.890632)
			(xy 375.111264 -327.433432) (xy 375.111264 -325.604632) (xy 372.088664 -322.582032) (xy 366.957864 -322.582032)
			(xy 366.729264 -322.810632) (xy 366.729264 -324.080632) (xy 366.983264 -324.334632) (xy 371.555264 -324.334632)
			(xy 372.063264 -324.842632) (xy 372.063264 -326.493632) (xy 372.698264 -327.128632) (xy 372.698264 -329.094338)
			(xy 373.247158 -329.643232) (xy 379.886464 -329.643232)
		)
		(stroke
			(width 0)
			(type solid)
		)
		(fill yes)
		(layer "F.Cu")
		(net "IND_P0_CPL5")
	)
	(gr_poly
		(pts
			(xy 123.310904 -360.377232) (xy 123.676664 -360.011472) (xy 123.676664 -359.936034) (xy 123.861322 -359.751376)
			(xy 123.982734 -359.751376) (xy 124.720604 -359.751376) (xy 124.753878 -359.718102) (xy 124.753878 -359.615232)
			(xy 124.752354 -359.613708) (xy 124.752354 -359.581958) (xy 124.722128 -359.551732) (xy 124.690378 -359.551732)
			(xy 123.674378 -359.551732) (xy 123.483878 -359.742232) (xy 123.356878 -359.742232) (xy 122.940064 -360.158792)
			(xy 122.940064 -360.277664) (xy 123.112784 -360.450384) (xy 123.237752 -360.450384)
		)
		(stroke
			(width 0)
			(type solid)
		)
		(fill yes)
		(layer "F.Cu")
		(net "GND")
	)
	(gr_poly
		(pts
			(xy 123.779534 -361.40263) (xy 123.779534 -361.36834) (xy 123.779534 -361.001818) (xy 123.780042 -361.00131)
			(xy 124.3457 -360.435652) (xy 124.667264 -360.435652) (xy 124.733812 -360.435652) (xy 124.794772 -360.374692)
			(xy 124.794772 -360.034078) (xy 124.767086 -360.006392) (xy 124.685552 -360.006392) (xy 124.049282 -360.006392)
			(xy 123.828302 -360.227372) (xy 123.608846 -360.446828) (xy 123.256294 -360.79938) (xy 123.118118 -360.937556)
			(xy 123.118118 -361.38739) (xy 123.161806 -361.431078) (xy 123.751086 -361.431078)
		)
		(stroke
			(width 0)
			(type solid)
		)
		(fill yes)
		(layer "F.Cu")
		(net "SW_PVPP_HBM_CPU1_BST")
	)
	(gr_poly
		(pts
			(xy 255.83007 -96.217994) (xy 255.719834 -96.107758) (xy 255.719834 -95.0214) (xy 255.95453 -94.78645)
			(xy 255.95453 -94.327472) (xy 255.828546 -94.201488) (xy 255.828546 -93.710252) (xy 255.737106 -93.618812)
			(xy 255.411986 -93.618812) (xy 255.297686 -93.733112) (xy 255.297686 -94.175326) (xy 255.465834 -94.343474)
			(xy 255.465834 -94.439232) (xy 255.465834 -94.837758) (xy 255.630934 -95.002858) (xy 255.630934 -96.105218)
			(xy 255.52527 -96.210882) (xy 255.52527 -96.691196) (xy 255.83007 -96.691196)
		)
		(stroke
			(width 0)
			(type solid)
		)
		(fill yes)
		(layer "F.Cu")
		(net "P3V3_AUX_CLK_GEN_VDDA100M_CK440")
	)
	(gr_poly
		(pts
			(xy 269.498572 -74.0664) (xy 269.498572 -69.9516) (xy 269.498572 -69.6976) (xy 269.396972 -69.596)
			(xy 265.06932 -69.596) (xy 264.800334 -69.864986) (xy 263.738614 -70.926452) (xy 261.997952 -70.926452)
			(xy 261.939278 -70.985126) (xy 261.939278 -71.24192) (xy 261.997952 -71.300594) (xy 265.330178 -71.300594)
			(xy 265.55192 -71.522336) (xy 265.55192 -72.954134) (xy 265.2903 -73.215754) (xy 264.942066 -73.563988)
			(xy 264.942066 -74.183494) (xy 265.028172 -74.2696) (xy 269.295372 -74.2696)
		)
		(stroke
			(width 0)
			(type solid)
		)
		(fill yes)
		(layer "F.Cu")
		(net "SW_P1V05_PCH_AUX_SW")
	)
	(gr_poly
		(pts
			(xy 371.616478 -360.011472) (xy 371.616478 -359.936034) (xy 371.801136 -359.751376) (xy 371.922548 -359.751376)
			(xy 372.660418 -359.751376) (xy 372.693692 -359.718102) (xy 372.693692 -359.615232) (xy 372.692168 -359.613708)
			(xy 372.692168 -359.581958) (xy 372.661942 -359.551732) (xy 372.630192 -359.551732) (xy 371.614192 -359.551732)
			(xy 371.423692 -359.742232) (xy 371.296692 -359.742232) (xy 371.234716 -359.742232) (xy 370.930678 -360.04627)
			(xy 370.930678 -360.10977) (xy 371.168422 -360.347514) (xy 371.280182 -360.347514)
		)
		(stroke
			(width 0)
			(type solid)
		)
		(fill yes)
		(layer "F.Cu")
		(net "GND")
	)
	(gr_poly
		(pts
			(xy 371.719348 -361.424982) (xy 371.719348 -361.36834) (xy 371.719348 -361.001818) (xy 371.719856 -361.00131)
			(xy 372.285514 -360.435652) (xy 372.607078 -360.435652) (xy 372.673626 -360.435652) (xy 372.744492 -360.364786)
			(xy 372.744492 -360.043984) (xy 372.7069 -360.006392) (xy 372.625366 -360.006392) (xy 371.989096 -360.006392)
			(xy 371.768116 -360.227372) (xy 371.54866 -360.446828) (xy 371.196108 -360.79938) (xy 371.039644 -360.955844)
			(xy 371.039644 -361.377992) (xy 371.1067 -361.445048) (xy 371.699282 -361.445048)
		)
		(stroke
			(width 0)
			(type solid)
		)
		(fill yes)
		(layer "F.Cu")
		(net "SW_PVPP_HBM_CPU0_BST")
	)
	(gr_poly
		(pts
			(xy 29.542486 -166.656004) (xy 29.542486 -163.52266) (xy 29.54909 -163.516056) (xy 30.341316 -163.516056)
			(xy 30.367732 -163.48964) (xy 30.367732 -162.961574) (xy 30.344364 -162.938206) (xy 29.527246 -162.938206)
			(xy 29.517086 -162.948366) (xy 25.826974 -162.948366) (xy 25.82672 -162.948112) (xy 25.82672 -162.938206)
			(xy 24.972772 -162.938206) (xy 24.95804 -162.952938) (xy 24.95804 -163.103306) (xy 24.97074 -163.116006)
			(xy 25.783286 -163.116006) (xy 25.783286 -166.656004) (xy 25.834086 -166.706804) (xy 29.491686 -166.706804)
		)
		(stroke
			(width 0)
			(type solid)
		)
		(fill yes)
		(layer "F.Cu")
		(net "GND")
	)
	(gr_poly
		(pts
			(xy 63.042038 -29.652722) (xy 63.042038 -28.052522) (xy 63.016638 -28.027122) (xy 62.000638 -28.027122)
			(xy 61.822838 -28.204922)
			(arc
				(start 61.822838 -29.466794)
				(mid 61.984303 -29.544752)
				(end 62.126876 -29.653484)
			)
			(xy 62.141608 -29.6672)
			(arc
				(start 62.21476 -29.6672)
				(mid 62.380969 -29.689389)
				(end 62.535562 -29.754322)
			)
			(xy 62.940438 -29.754322)
		)
		(stroke
			(width 0)
			(type solid)
		)
		(fill yes)
		(layer "F.Cu")
		(net "P3V3_AUX")
	)
	(gr_poly
		(pts
			(xy 386.94233 -67.4624) (xy 386.94233 -67.032378) (xy 387.67639 -66.298318) (xy 392.34491 -66.298318)
			(xy 393.1793 -65.463928) (xy 393.1793 -64.262508) (xy 393.07262 -64.155828) (xy 390.93648 -64.155828)
			(xy 389.95731 -65.134998)
			(arc
				(start 387.532118 -65.134998)
				(mid 387.483082 -65.156677)
				(end 387.432042 -65.173098)
			)
			(xy 387.418834 -65.176654) (xy 386.35686 -66.238628) (xy 385.96824 -66.238628) (xy 385.7879 -66.418968)
			(xy 385.7879 -67.496436) (xy 385.919726 -67.628262) (xy 386.776468 -67.628262)
		)
		(stroke
			(width 0)
			(type solid)
		)
		(fill yes)
		(layer "F.Cu")
		(net "P1V05_PCH_AUX")
	)
	(gr_poly
		(pts
			(xy 3.018028 -192.216532) (xy 3.018028 -176.353724)
			(arc
				(start 3.018028 -163.735512)
				(mid 3.016904 -163.725134)
				(end 3.01371 -163.715192)
			)
			(arc
				(start 3.01371 -163.715192)
				(mid 2.850331 -163.313936)
				(end 2.70891 -162.904424)
			)
			(xy 2.703322 -162.88639) (xy 2.671572 -162.866578)
			(arc
				(start 2.553716 -162.884612)
				(mid 2.522768 -162.90174)
				(end 2.510536 -162.934904)
			)
			(xy 2.510536 -192.17894) (xy 2.607056 -192.27546) (xy 2.9591 -192.27546)
		)
		(stroke
			(width 0)
			(type solid)
		)
		(fill yes)
		(layer "F.Cu")
		(net "GND")
	)
	(gr_poly
		(pts
			(xy 173.063662 -30.700472) (xy 173.063662 -29.100272) (xy 173.038262 -29.074872) (xy 172.022262 -29.074872)
			(xy 171.844462 -29.252672)
			(arc
				(start 171.844462 -29.462222)
				(mid 171.939938 -29.591427)
				(end 171.973748 -29.74848)
			)
			(arc
				(start 171.973748 -29.74848)
				(mid 171.957748 -29.857554)
				(end 171.911264 -29.957522)
			)
			(xy 171.911264 -30.691328) (xy 172.022262 -30.802072) (xy 172.962062 -30.802072)
		)
		(stroke
			(width 0)
			(type solid)
		)
		(fill yes)
		(layer "F.Cu")
		(net "P3V3_AUX")
	)
	(gr_poly
		(pts
			(xy 173.241462 -27.855672) (xy 173.241462 -25.163272) (xy 173.444662 -24.960072) (xy 174.308262 -24.960072)
			(xy 174.384462 -24.883872) (xy 174.384462 -24.121872) (xy 174.257462 -23.994872) (xy 173.012862 -23.994872)
			(xy 172.530262 -24.477472) (xy 172.530262 -26.552906)
			(arc
				(start 172.531532 -26.55824)
				(mid 172.538039 -26.598648)
				(end 172.540168 -26.63952)
			)
			(arc
				(start 172.540168 -26.63952)
				(mid 172.538027 -26.680391)
				(end 172.531532 -26.7208)
			)
			(xy 172.530262 -26.726134) (xy 172.530262 -27.830272) (xy 172.581062 -27.881072) (xy 173.216062 -27.881072)
		)
		(stroke
			(width 0)
			(type solid)
		)
		(fill yes)
		(layer "F.Cu")
		(net "P12V_AUX")
	)
	(gr_poly
		(pts
			(xy 390.839452 -79.800704) (xy 390.839452 -78.657704) (xy 390.839452 -78.170024) (xy 390.839452 -76.719684)
			(xy 390.644126 -76.524358) (xy 385.68122 -76.524358) (xy 385.6736 -76.516738) (xy 385.654042 -76.516738)
			(xy 384.161538 -76.516738) (xy 384.151378 -76.526898) (xy 384.151378 -76.738734) (xy 384.151378 -76.761086)
			(xy 384.181096 -76.790804) (xy 385.247388 -76.790804) (xy 385.662932 -77.206348) (xy 385.662932 -77.280262)
			(xy 385.662932 -78.195424) (xy 385.662932 -78.855824) (xy 385.662932 -79.871824) (xy 385.815332 -80.024224)
			(xy 390.615932 -80.024224)
		)
		(stroke
			(width 0)
			(type solid)
		)
		(fill yes)
		(layer "F.Cu")
		(net "GND")
	)
	(gr_poly
		(pts
			(xy 455.40549 -385.59232) (xy 457.541122 -385.59232) (xy 457.582524 -385.550918) (xy 457.582524 -385.244848)
			(xy 457.548996 -385.21132) (xy 456.5777 -385.21132) (xy 454.141332 -385.21132) (xy 453.878442 -384.94843)
			(xy 453.878442 -383.88163) (xy 453.878442 -383.24663) (xy 454.030842 -383.09423) (xy 454.538842 -383.09423)
			(xy 454.63206 -383.001012) (xy 454.63206 -382.445768) (xy 454.38822 -382.201928) (xy 450.782944 -382.201928)
			(xy 450.373242 -382.61163) (xy 450.373242 -387.10743) (xy 450.471032 -387.20522) (xy 450.703442 -387.43763)
			(xy 453.56018 -387.43763)
		)
		(stroke
			(width 0)
			(type solid)
		)
		(fill yes)
		(layer "F.Cu")
		(net "SW_P5V_AUX_SW")
	)
	(gr_poly
		(pts
			(xy 467.119716 -394.880084) (xy 467.119716 -393.474702) (xy 467.119716 -386.113274) (xy 467.064852 -386.05841)
			(xy 456.57643 -386.05841) (xy 456.5523 -386.082286) (xy 456.5523 -389.384794) (xy 454.02754 -391.909554)
			(xy 437.760872 -391.909554) (xy 437.298846 -391.447528) (xy 437.298846 -379.288294) (xy 437.167782 -379.15723)
			(xy 436.76951 -378.758704) (xy 434.463444 -378.758704) (xy 434.082444 -378.758704) (xy 433.6542 -379.186948)
			(xy 433.6542 -393.962128) (xy 433.90312 -394.211048) (xy 435.195472 -395.503146) (xy 465.091272 -395.503146)
			(xy 466.496654 -395.503146)
		)
		(stroke
			(width 0)
			(type solid)
		)
		(fill yes)
		(layer "F.Cu")
		(net "GND")
	)
	(gr_poly
		(pts
			(xy 2.703322 -345.313508)
			(arc
				(start 2.70891 -345.295474)
				(mid 2.85033 -344.885962)
				(end 3.01371 -344.484706)
			)
			(arc
				(start 3.01371 -344.484706)
				(mid 3.016934 -344.474771)
				(end 3.018028 -344.464386)
			)
			(xy 3.018028 -200.565512) (xy 3.018028 -196.365876) (xy 2.93116 -196.279008) (xy 2.59842 -196.279008)
			(xy 2.510536 -196.366892) (xy 2.510536 -198.902574)
			(arc
				(start 2.510536 -345.264994)
				(mid 2.522818 -345.298115)
				(end 2.553716 -345.315286)
			)
			(xy 2.671572 -345.33332)
		)
		(stroke
			(width 0)
			(type solid)
		)
		(fill yes)
		(layer "F.Cu")
		(net "GND")
	)
	(gr_poly
		(pts
			(xy 29.22524 -181.778148) (xy 29.22524 -178.031648) (xy 29.111448 -177.917856) (xy 28.45689 -177.917856)
			(xy 26.228802 -177.917856) (xy 26.160222 -177.986436) (xy 26.160222 -179.328064) (xy 26.160222 -180.362606)
			(xy 25.96388 -180.558948) (xy 25.22728 -180.558948) (xy 24.973534 -180.305202) (xy 21.892006 -180.305202)
			(xy 21.802344 -180.394864) (xy 21.802344 -180.510942) (xy 21.845524 -180.554122) (xy 24.38908 -180.554122)
			(xy 24.38908 -180.558948) (xy 24.89708 -181.066948) (xy 24.89708 -181.778148) (xy 25.04948 -181.930548)
			(xy 28.010612 -181.930548) (xy 29.07284 -181.930548)
		)
		(stroke
			(width 0)
			(type solid)
		)
		(fill yes)
		(layer "F.Cu")
		(net "SW_PVNN_MAIN_CPU1_SW")
	)
	(gr_poly
		(pts
			(xy 264.666222 -74.21499) (xy 264.666222 -74.10196) (xy 264.666222 -73.721468) (xy 264.597134 -73.65238)
			(xy 264.463276 -73.65238) (xy 264.278364 -73.467468) (xy 264.244582 -73.433686) (xy 264.082022 -73.271126)
			(xy 264.023856 -73.21296) (xy 263.972802 -73.161906) (xy 263.925812 -73.114916) (xy 263.906 -73.095104)
			(xy 263.906 -72.512936) (xy 263.735566 -72.342756) (xy 263.291066 -72.342756) (xy 263.253982 -72.37984)
			(xy 263.253982 -73.223628) (xy 263.39292 -73.223628) (xy 264.107168 -73.937876) (xy 264.107168 -74.087736)
			(xy 264.268966 -74.249534) (xy 264.631678 -74.249534)
		)
		(stroke
			(width 0)
			(type solid)
		)
		(fill yes)
		(layer "F.Cu")
		(net "SW_P1V05_PCH_AUX_BST")
	)
	(gr_poly
		(pts
			(xy 437.722772 -29.938218) (xy 437.722772 -28.338018) (xy 437.697372 -28.312618) (xy 436.681372 -28.312618)
			(xy 436.503572 -28.490418) (xy 436.503572 -28.713938)
			(arc
				(start 436.505604 -28.720796)
				(mid 436.520074 -28.789723)
				(end 436.524908 -28.859988)
			)
			(arc
				(start 436.524908 -28.859988)
				(mid 436.5201 -28.930257)
				(end 436.505604 -28.99918)
			)
			(xy 436.503572 -29.006038)
			(arc
				(start 436.503572 -29.799534)
				(mid 436.661874 -29.904078)
				(end 436.794402 -30.039818)
			)
			(xy 437.621172 -30.039818)
		)
		(stroke
			(width 0)
			(type solid)
		)
		(fill yes)
		(layer "F.Cu")
		(net "P3V3_AUX")
	)
	(gr_poly
		(pts
			(xy 438.8739 -183.002428) (xy 438.8739 -178.283108) (xy 438.80278 -178.211988) (xy 438.34812 -178.211988)
			(xy 436.36057 -178.211988) (xy 435.97195 -178.600608) (xy 435.97195 -180.452268) (xy 435.97195 -180.989478)
			(xy 435.66588 -181.295548) (xy 434.587904 -181.295548) (xy 434.555392 -181.32806) (xy 434.519832 -181.36362)
			(xy 431.663348 -181.36362) (xy 431.614072 -181.412896) (xy 431.614072 -181.467506) (xy 431.614072 -181.55412)
			(xy 431.65268 -181.592728) (xy 434.259482 -181.592728) (xy 434.34508 -181.678326) (xy 435.721252 -183.054498)
			(xy 438.14873 -183.054498) (xy 438.82183 -183.054498)
		)
		(stroke
			(width 0)
			(type solid)
		)
		(fill yes)
		(layer "F.Cu")
		(net "SW_PVNN_MAIN_CPU0_SW")
	)
	(gr_poly
		(pts
			(xy 467.14664 -385.519168) (xy 467.14664 -383.670048) (xy 466.55736 -383.080768) (xy 464.6803 -383.080768)
			(xy 464.31962 -383.441448) (xy 462.26984 -383.441448) (xy 461.503776 -384.207512) (xy 460.706724 -384.207512)
			(xy 460.380842 -384.533648) (xy 460.15148 -384.533648) (xy 455.130408 -384.533648) (xy 455.01179 -384.41503)
			(xy 454.437242 -384.41503) (xy 454.361042 -384.49123) (xy 454.361042 -384.89763) (xy 454.420732 -384.95732)
			(xy 456.8317 -384.95732) (xy 457.868782 -384.95732) (xy 458.412596 -385.501134) (xy 458.414882 -385.501134)
			(xy 458.596746 -385.682998) (xy 466.98281 -385.682998)
		)
		(stroke
			(width 0)
			(type solid)
		)
		(fill yes)
		(layer "F.Cu")
		(net "SW_P5V_AUX_FLT")
	)
	(gr_poly
		(pts
			(xy 43.546268 -185.030872) (xy 43.546268 -179.989226) (xy 43.273726 -179.716684) (xy 42.81043 -179.253388)
			(xy 40.7924 -179.253388) (xy 40.57396 -179.471828) (xy 40.57396 -179.850288) (xy 40.57396 -183.637428)
			(xy 40.21963 -183.991758) (xy 39.866316 -183.991758) (xy 36.96208 -183.991758) (xy 36.709858 -183.739536)
			(xy 36.709858 -174.527718) (xy 36.615624 -174.433484) (xy 36.360862 -174.433484) (xy 36.12388 -174.433484)
			(xy 33.236154 -174.433484) (xy 32.089344 -174.433484) (xy 31.717996 -174.804832) (xy 31.717996 -175.951642)
			(xy 31.717996 -184.782714) (xy 32.61868 -185.683398) (xy 42.893996 -185.683398)
		)
		(stroke
			(width 0)
			(type solid)
		)
		(fill yes)
		(layer "F.Cu")
		(net "PVNN_MAIN_CPU1")
	)
	(gr_poly
		(pts
			(xy 135.269478 -370.758466) (xy 135.689086 -370.338858) (xy 135.704072 -370.323872) (xy 135.704072 -367.81105)
			(xy 135.702548 -367.809526) (xy 135.702548 -367.35004) (xy 135.687562 -367.335054) (xy 135.546084 -367.193576)
			(xy 135.531098 -367.17859)
			(arc
				(start 131.03352 -367.17859)
				(mid 131.013997 -367.174689)
				(end 130.997452 -367.163604)
			)
			(xy 130.835146 -367.001298) (xy 130.82016 -366.986312) (xy 121.241312 -366.986312) (xy 121.226326 -367.001298)
			(xy 121.13133 -367.096294) (xy 121.116344 -367.11128) (xy 121.116344 -370.240052) (xy 121.13133 -370.255038)
			(xy 121.649744 -370.773452) (xy 135.254492 -370.773452)
		)
		(stroke
			(width 0)
			(type solid)
		)
		(fill yes)
		(layer "F.Cu")
		(net "PVPP_HBM_CPU1")
	)
	(gr_poly
		(pts
			(arc
				(start 230.02621 -65.998598)
				(mid 230.089395 -65.982029)
				(end 230.15448 -65.9765)
			)
			(arc
				(start 230.15448 -65.9765)
				(mid 230.219562 -65.982048)
				(end 230.28275 -65.998598)
			)
			(xy 230.290878 -66.001646) (xy 233.75874 -66.001646) (xy 233.93273 -65.827656) (xy 233.93273 -63.525146)
			(xy 233.782108 -63.374524) (xy 232.984802 -63.374524) (xy 232.446322 -62.836044) (xy 232.446322 -61.39307)
			(xy 232.823258 -61.016134) (xy 232.823258 -59.626754) (xy 232.586276 -59.389772) (xy 229.463092 -59.389772)
			(xy 228.698552 -60.154312) (xy 228.698552 -65.836038) (xy 228.86416 -66.001646) (xy 230.018082 -66.001646)
		)
		(stroke
			(width 0)
			(type solid)
		)
		(fill yes)
		(layer "F.Cu")
		(net "GND")
	)
	(gr_poly
		(pts
			(xy 382.477772 -76.313538) (xy 382.51638 -76.27493) (xy 382.526794 -76.264516) (xy 382.543304 -76.248006)
			(xy 384.545078 -76.248006) (xy 384.564636 -76.228448) (xy 384.564636 -76.036424) (xy 384.556 -76.027788)
			(xy 382.89103 -76.027788) (xy 382.874266 -76.011024) (xy 382.365504 -75.502262) (xy 381.617728 -75.502262)
			(xy 381.589788 -75.474322) (xy 381.411988 -75.296522) (xy 381.411988 -74.50328) (xy 381.411988 -74.285602)
			(xy 381.145288 -74.018902) (xy 379.25248 -74.018902) (xy 379.157484 -74.113898) (xy 379.157484 -74.271378)
			(xy 379.157484 -77.284326) (xy 379.30328 -77.430122) (xy 381.361188 -77.430122)
		)
		(stroke
			(width 0)
			(type solid)
		)
		(fill yes)
		(layer "F.Cu")
		(net "SW_P1V8_PCH_AUX_SW")
	)
	(gr_poly
		(pts
			(xy 388.258304 -335.344516) (xy 388.258304 -334.133952) (xy 388.08152 -333.957168) (xy 383.486406 -333.957168)
			(xy 383.298446 -333.769208) (xy 383.023618 -333.49438) (xy 383.023618 -331.980032) (xy 383.023618 -331.149706)
			(xy 383.023618 -330.631546) (xy 382.200404 -329.808332) (xy 382.200404 -327.024492) (xy 381.110998 -325.934832)
			(xy 375.390664 -325.934832) (xy 375.365264 -325.960232) (xy 375.365264 -327.306432) (xy 375.695464 -327.636632)
			(xy 379.656594 -327.636632) (xy 380.191264 -328.171302) (xy 380.191264 -329.795632) (xy 380.699264 -330.303632)
			(xy 380.699264 -334.555084) (xy 381.647954 -335.503774) (xy 388.099046 -335.503774)
		)
		(stroke
			(width 0)
			(type solid)
		)
		(fill yes)
		(layer "F.Cu")
		(net "IND_P0_CPL8")
	)
	(gr_poly
		(pts
			(xy 437.12384 -99.731068) (xy 437.12384 -95.938848) (xy 436.70474 -95.519748)
			(arc
				(start 434.468524 -95.519748)
				(mid 434.23586 -95.576129)
				(end 434.003196 -95.519748)
			)
			(xy 432.8414 -95.519748) (xy 432.50104 -95.179388) (xy 432.50104 -94.666308) (xy 431.9397 -94.666308)
			(xy 431.7111 -94.894908) (xy 431.7111 -95.829628) (xy 430.9237 -96.617028) (xy 430.9237 -99.751388)
			(xy 431.26914 -100.096828) (xy 436.75808 -100.096828)
		)
		(stroke
			(width 0)
			(type solid)
		)
		(fill yes)
		(layer "F.Cu")
		(net "P3V3_OCP_SFF")
	)
	(gr_poly
		(pts
			(arc
				(start 21.317204 -183.190134)
				(mid 21.61413 -183.048164)
				(end 21.911056 -183.190134)
			)
			(xy 22.53107 -183.190134) (xy 22.75967 -182.961534) (xy 22.75967 -181.917086) (xy 22.96541 -181.711346)
			(xy 22.96541 -180.956966) (xy 22.81809 -180.809646) (xy 15.971012 -180.809646) (xy 15.7861 -180.994558)
			(xy 15.7861 -182.973218) (xy 16.003016 -183.190134)
		)
		(stroke
			(width 0)
			(type solid)
		)
		(fill yes)
		(layer "F.Cu")
		(net "GND")
	)
	(gr_poly
		(pts
			(xy 258.232402 -102.075488) (xy 258.232402 -97.081848) (xy 258.166362 -97.015808) (xy 253.490222 -97.015808)
			(xy 253.332742 -96.858328) (xy 253.332742 -96.236028) (xy 253.297182 -96.200468) (xy 253.060962 -96.200468)
			(xy 253.040642 -96.220788) (xy 253.040642 -96.741488) (xy 253.129542 -96.830388) (xy 253.129542 -97.368868)
			(xy 253.073662 -97.424748) (xy 252.949202 -97.424748) (xy 252.326902 -97.424748) (xy 252.309122 -97.442528)
			(xy 252.309122 -97.688908) (xy 252.324362 -97.704148) (xy 252.977142 -97.704148) (xy 253.058422 -97.704148)
			(xy 253.124462 -97.770188) (xy 253.124462 -101.884988) (xy 253.355602 -102.116128) (xy 258.191762 -102.116128)
		)
		(stroke
			(width 0)
			(type solid)
		)
		(fill yes)
		(layer "F.Cu")
		(net "GND")
	)
	(gr_poly
		(pts
			(xy 433.306728 -179.832508) (xy 433.306728 -179.19827) (xy 433.362608 -179.14239) (xy 433.737258 -179.14239)
			(xy 433.783232 -179.096416)
			(arc
				(start 433.783232 -178.959764)
				(mid 433.807522 -178.838121)
				(end 433.87645 -178.734974)
			)
			(xy 433.91328 -178.698144) (xy 433.91328 -177.917348) (xy 433.81168 -177.815748) (xy 433.439062 -177.815748)
			(xy 433.22748 -178.02733) (xy 432.609498 -178.02733) (xy 432.516788 -178.12004) (xy 432.516788 -178.629056)
			(xy 433.027328 -179.139596) (xy 433.027328 -179.819808) (xy 433.075588 -179.868068) (xy 433.271168 -179.868068)
		)
		(stroke
			(width 0)
			(type solid)
		)
		(fill yes)
		(layer "F.Cu")
		(net "GND")
	)
	(gr_poly
		(pts
			(arc
				(start 176.084992 -329.90663)
				(mid 175.84928 -329.90663)
				(end 176.084992 -329.90663)
			)
		)
		(stroke
			(width 0)
			(type solid)
		)
		(fill yes)
		(layer "F.Cu")
		(net "GND")
	)
	(gr_poly
		(pts
			(arc
				(start 178.871626 -327.79843)
				(mid 178.635914 -327.79843)
				(end 178.871626 -327.79843)
			)
		)
		(stroke
			(width 0)
			(type solid)
		)
		(fill yes)
		(layer "F.Cu")
		(net "GND")
	)
	(gr_poly
		(pts
			(arc
				(start 180.151786 -331.140054)
				(mid 179.916074 -331.140054)
				(end 180.151786 -331.140054)
			)
		)
		(stroke
			(width 0)
			(type solid)
		)
		(fill yes)
		(layer "F.Cu")
		(net "GND")
	)
	(gr_poly
		(pts
			(arc
				(start 181.4322 -326.057006)
				(mid 181.196488 -326.057006)
				(end 181.4322 -326.057006)
			)
		)
		(stroke
			(width 0)
			(type solid)
		)
		(fill yes)
		(layer "F.Cu")
		(net "GND")
	)
	(gr_poly
		(pts
			(arc
				(start 192.533524 -360.853736)
				(mid 192.297812 -360.853736)
				(end 192.533524 -360.853736)
			)
		)
		(stroke
			(width 0)
			(type solid)
		)
		(fill yes)
		(layer "F.Cu")
		(net "GND")
	)
	(gr_poly
		(pts
			(arc
				(start 192.593722 -353.22383)
				(mid 192.35801 -353.22383)
				(end 192.593722 -353.22383)
			)
		)
		(stroke
			(width 0)
			(type solid)
		)
		(fill yes)
		(layer "F.Cu")
		(net "GND")
	)
	(gr_poly
		(pts
			(arc
				(start 200.327006 -352.725482)
				(mid 200.091294 -352.725482)
				(end 200.327006 -352.725482)
			)
		)
		(stroke
			(width 0)
			(type solid)
		)
		(fill yes)
		(layer "F.Cu")
		(net "GND")
	)
	(gr_poly
		(pts
			(arc
				(start 203.18349 -109.529118)
				(mid 202.941174 -109.529118)
				(end 203.18349 -109.529118)
			)
		)
		(stroke
			(width 0)
			(type solid)
		)
		(fill yes)
		(layer "F.Cu")
		(net "GND")
	)
	(gr_poly
		(pts
			(arc
				(start 206.933292 -340.47811)
				(mid 206.69758 -340.47811)
				(end 206.933292 -340.47811)
			)
		)
		(stroke
			(width 0)
			(type solid)
		)
		(fill yes)
		(layer "F.Cu")
		(net "GND")
	)
	(gr_poly
		(pts
			(arc
				(start 210.632802 -339.56498)
				(mid 210.39709 -339.56498)
				(end 210.632802 -339.56498)
			)
		)
		(stroke
			(width 0)
			(type solid)
		)
		(fill yes)
		(layer "F.Cu")
		(net "GND")
	)
	(gr_poly
		(pts
			(arc
				(start 210.660996 -340.79815)
				(mid 210.425284 -340.79815)
				(end 210.660996 -340.79815)
			)
		)
		(stroke
			(width 0)
			(type solid)
		)
		(fill yes)
		(layer "F.Cu")
		(net "GND")
	)
	(gr_poly
		(pts
			(arc
				(start 210.660996 -338.266024)
				(mid 210.425284 -338.266024)
				(end 210.660996 -338.266024)
			)
		)
		(stroke
			(width 0)
			(type solid)
		)
		(fill yes)
		(layer "F.Cu")
		(net "GND")
	)
	(gr_poly
		(pts
			(arc
				(start 226.035362 -365.236252)
				(mid 225.79965 -365.236252)
				(end 226.035362 -365.236252)
			)
		)
		(stroke
			(width 0)
			(type solid)
		)
		(fill yes)
		(layer "F.Cu")
		(net "GND")
	)
	(gr_poly
		(pts
			(arc
				(start 253.273306 -326.89419)
				(mid 253.037594 -326.89419)
				(end 253.273306 -326.89419)
			)
		)
		(stroke
			(width 0)
			(type solid)
		)
		(fill yes)
		(layer "F.Cu")
		(net "GND")
	)
	(gr_poly
		(pts
			(arc
				(start 12.06119 -422.44391)
				(mid 11.811762 -422.44391)
				(end 12.06119 -422.44391)
			)
		)
		(stroke
			(width 0)
			(type solid)
		)
		(fill yes)
		(layer "F.Cu")
		(net "GND")
	)
	(gr_poly
		(pts
			(arc
				(start 29.907484 -439.527188)
				(mid 29.658056 -439.527188)
				(end 29.907484 -439.527188)
			)
		)
		(stroke
			(width 0)
			(type solid)
		)
		(fill yes)
		(layer "F.Cu")
		(net "GND")
	)
	(gr_poly
		(pts
			(arc
				(start 35.451034 -439.775092)
				(mid 35.201606 -439.775092)
				(end 35.451034 -439.775092)
			)
		)
		(stroke
			(width 0)
			(type solid)
		)
		(fill yes)
		(layer "F.Cu")
		(net "GND")
	)
	(gr_poly
		(pts
			(arc
				(start 36.91763 -432.406806)
				(mid 36.668202 -432.406806)
				(end 36.91763 -432.406806)
			)
		)
		(stroke
			(width 0)
			(type solid)
		)
		(fill yes)
		(layer "F.Cu")
		(net "GND")
	)
	(gr_poly
		(pts
			(arc
				(start 39.444676 -433.967128)
				(mid 39.195248 -433.967128)
				(end 39.444676 -433.967128)
			)
		)
		(stroke
			(width 0)
			(type solid)
		)
		(fill yes)
		(layer "F.Cu")
		(net "GND")
	)
	(gr_poly
		(pts
			(arc
				(start 42.456608 -437.187594)
				(mid 42.20718 -437.187594)
				(end 42.456608 -437.187594)
			)
		)
		(stroke
			(width 0)
			(type solid)
		)
		(fill yes)
		(layer "F.Cu")
		(net "GND")
	)
	(gr_poly
		(pts
			(arc
				(start 46.815502 -437.011318)
				(mid 46.566074 -437.011318)
				(end 46.815502 -437.011318)
			)
		)
		(stroke
			(width 0)
			(type solid)
		)
		(fill yes)
		(layer "F.Cu")
		(net "GND")
	)
	(gr_poly
		(pts
			(arc
				(start 49.02708 -439.152538)
				(mid 48.777652 -439.152538)
				(end 49.02708 -439.152538)
			)
		)
		(stroke
			(width 0)
			(type solid)
		)
		(fill yes)
		(layer "F.Cu")
		(net "GND")
	)
	(gr_poly
		(pts
			(arc
				(start 49.250854 -434.747924)
				(mid 49.001426 -434.747924)
				(end 49.250854 -434.747924)
			)
		)
		(stroke
			(width 0)
			(type solid)
		)
		(fill yes)
		(layer "F.Cu")
		(net "GND")
	)
	(gr_poly
		(pts
			(arc
				(start 52.342542 -432.020218)
				(mid 52.093114 -432.020218)
				(end 52.342542 -432.020218)
			)
		)
		(stroke
			(width 0)
			(type solid)
		)
		(fill yes)
		(layer "F.Cu")
		(net "GND")
	)
	(gr_poly
		(pts
			(arc
				(start 52.76088 -414.319974)
				(mid 52.511452 -414.319974)
				(end 52.76088 -414.319974)
			)
		)
		(stroke
			(width 0)
			(type solid)
		)
		(fill yes)
		(layer "F.Cu")
		(net "GND")
	)
	(gr_poly
		(pts
			(arc
				(start 54.14645 -436.957978)
				(mid 53.897022 -436.957978)
				(end 54.14645 -436.957978)
			)
		)
		(stroke
			(width 0)
			(type solid)
		)
		(fill yes)
		(layer "F.Cu")
		(net "GND")
	)
	(gr_poly
		(pts
			(arc
				(start 102.295198 -424.62323)
				(mid 102.04577 -424.62323)
				(end 102.295198 -424.62323)
			)
		)
		(stroke
			(width 0)
			(type solid)
		)
		(fill yes)
		(layer "F.Cu")
		(net "GND")
	)
	(gr_poly
		(pts
			(arc
				(start 104.323642 -424.241976)
				(mid 104.074214 -424.241976)
				(end 104.323642 -424.241976)
			)
		)
		(stroke
			(width 0)
			(type solid)
		)
		(fill yes)
		(layer "F.Cu")
		(net "GND")
	)
	(gr_poly
		(pts
			(arc
				(start 162.953192 -418.759386)
				(mid 162.703764 -418.759386)
				(end 162.953192 -418.759386)
			)
		)
		(stroke
			(width 0)
			(type solid)
		)
		(fill yes)
		(layer "F.Cu")
		(net "GND")
	)
	(gr_poly
		(pts
			(arc
				(start 164.058092 -421.74795)
				(mid 163.808664 -421.74795)
				(end 164.058092 -421.74795)
			)
		)
		(stroke
			(width 0)
			(type solid)
		)
		(fill yes)
		(layer "F.Cu")
		(net "GND")
	)
	(gr_poly
		(pts
			(arc
				(start 165.913562 -428.31385)
				(mid 165.664134 -428.31385)
				(end 165.913562 -428.31385)
			)
		)
		(stroke
			(width 0)
			(type solid)
		)
		(fill yes)
		(layer "F.Cu")
		(net "GND")
	)
	(gr_poly
		(pts
			(arc
				(start 166.572692 -418.448744)
				(mid 166.323264 -418.448744)
				(end 166.572692 -418.448744)
			)
		)
		(stroke
			(width 0)
			(type solid)
		)
		(fill yes)
		(layer "F.Cu")
		(net "GND")
	)
	(gr_poly
		(pts
			(arc
				(start 166.995856 -431.476658)
				(mid 166.746428 -431.476658)
				(end 166.995856 -431.476658)
			)
		)
		(stroke
			(width 0)
			(type solid)
		)
		(fill yes)
		(layer "F.Cu")
		(net "GND")
	)
	(gr_poly
		(pts
			(arc
				(start 169.777918 -392.942572)
				(mid 169.52849 -392.942572)
				(end 169.777918 -392.942572)
			)
		)
		(stroke
			(width 0)
			(type solid)
		)
		(fill yes)
		(layer "F.Cu")
		(net "GND")
	)
	(gr_poly
		(pts
			(arc
				(start 172.467524 -399.77314)
				(mid 172.218096 -399.77314)
				(end 172.467524 -399.77314)
			)
		)
		(stroke
			(width 0)
			(type solid)
		)
		(fill yes)
		(layer "F.Cu")
		(net "GND")
	)
	(gr_poly
		(pts
			(arc
				(start 172.639482 -397.320008)
				(mid 172.390054 -397.320008)
				(end 172.639482 -397.320008)
			)
		)
		(stroke
			(width 0)
			(type solid)
		)
		(fill yes)
		(layer "F.Cu")
		(net "GND")
	)
	(gr_poly
		(pts
			(arc
				(start 175.352964 -400.789902)
				(mid 175.103536 -400.789902)
				(end 175.352964 -400.789902)
			)
		)
		(stroke
			(width 0)
			(type solid)
		)
		(fill yes)
		(layer "F.Cu")
		(net "GND")
	)
	(gr_poly
		(pts
			(arc
				(start 178.113436 -21.0947)
				(mid 177.862992 -21.0947)
				(end 178.113436 -21.0947)
			)
		)
		(stroke
			(width 0)
			(type solid)
		)
		(fill yes)
		(layer "F.Cu")
		(net "GND")
	)
	(gr_poly
		(pts
			(arc
				(start 179.050696 -421.122856)
				(mid 178.801268 -421.122856)
				(end 179.050696 -421.122856)
			)
		)
		(stroke
			(width 0)
			(type solid)
		)
		(fill yes)
		(layer "F.Cu")
		(net "GND")
	)
	(gr_poly
		(pts
			(arc
				(start 180.238908 -411.185868)
				(mid 179.98948 -411.185868)
				(end 180.238908 -411.185868)
			)
		)
		(stroke
			(width 0)
			(type solid)
		)
		(fill yes)
		(layer "F.Cu")
		(net "GND")
	)
	(gr_poly
		(pts
			(arc
				(start 181.427628 -413.973264)
				(mid 181.1782 -413.973264)
				(end 181.427628 -413.973264)
			)
		)
		(stroke
			(width 0)
			(type solid)
		)
		(fill yes)
		(layer "F.Cu")
		(net "GND")
	)
	(gr_poly
		(pts
			(arc
				(start 182.555134 -406.494488)
				(mid 182.305706 -406.494488)
				(end 182.555134 -406.494488)
			)
		)
		(stroke
			(width 0)
			(type solid)
		)
		(fill yes)
		(layer "F.Cu")
		(net "GND")
	)
	(gr_poly
		(pts
			(arc
				(start 194.65798 -22.18436)
				(mid 194.397884 -22.18436)
				(end 194.65798 -22.18436)
			)
		)
		(stroke
			(width 0)
			(type solid)
		)
		(fill yes)
		(layer "F.Cu")
		(net "GND")
	)
	(gr_poly
		(pts
			(arc
				(start 223.377252 -129.298954)
				(mid 223.119696 -129.298954)
				(end 223.377252 -129.298954)
			)
		)
		(stroke
			(width 0)
			(type solid)
		)
		(fill yes)
		(layer "F.Cu")
		(net "GND")
	)
	(gr_poly
		(pts
			(arc
				(start 223.377252 -127.973582)
				(mid 223.119696 -127.973582)
				(end 223.377252 -127.973582)
			)
		)
		(stroke
			(width 0)
			(type solid)
		)
		(fill yes)
		(layer "F.Cu")
		(net "GND")
	)
	(gr_poly
		(pts
			(arc
				(start 227.029772 -123.324874)
				(mid 226.772216 -123.324874)
				(end 227.029772 -123.324874)
			)
		)
		(stroke
			(width 0)
			(type solid)
		)
		(fill yes)
		(layer "F.Cu")
		(net "GND")
	)
	(gr_poly
		(pts
			(arc
				(start 227.029772 -121.999502)
				(mid 226.772216 -121.999502)
				(end 227.029772 -121.999502)
			)
		)
		(stroke
			(width 0)
			(type solid)
		)
		(fill yes)
		(layer "F.Cu")
		(net "GND")
	)
	(gr_poly
		(pts
			(arc
				(start 230.932228 -115.668044)
				(mid 230.674672 -115.668044)
				(end 230.932228 -115.668044)
			)
		)
		(stroke
			(width 0)
			(type solid)
		)
		(fill yes)
		(layer "F.Cu")
		(net "GND")
	)
	(gr_poly
		(pts
			(arc
				(start 232.2576 -115.668044)
				(mid 232.000044 -115.668044)
				(end 232.2576 -115.668044)
			)
		)
		(stroke
			(width 0)
			(type solid)
		)
		(fill yes)
		(layer "F.Cu")
		(net "GND")
	)
	(gr_poly
		(pts
			(arc
				(start 281.840686 -387.615684)
				(mid 281.591258 -387.615684)
				(end 281.840686 -387.615684)
			)
		)
		(stroke
			(width 0)
			(type solid)
		)
		(fill yes)
		(layer "F.Cu")
		(net "GND")
	)
	(gr_poly
		(pts
			(arc
				(start 282.840684 -436.457852)
				(mid 282.591256 -436.457852)
				(end 282.840684 -436.457852)
			)
		)
		(stroke
			(width 0)
			(type solid)
		)
		(fill yes)
		(layer "F.Cu")
		(net "GND")
	)
	(gr_poly
		(pts
			(arc
				(start 283.674566 -434.69052)
				(mid 283.425138 -434.69052)
				(end 283.674566 -434.69052)
			)
		)
		(stroke
			(width 0)
			(type solid)
		)
		(fill yes)
		(layer "F.Cu")
		(net "GND")
	)
	(gr_poly
		(pts
			(arc
				(start 296.276014 -410.903166)
				(mid 296.026586 -410.903166)
				(end 296.276014 -410.903166)
			)
		)
		(stroke
			(width 0)
			(type solid)
		)
		(fill yes)
		(layer "F.Cu")
		(net "GND")
	)
	(gr_poly
		(pts
			(arc
				(start 300.987968 -408.056334)
				(mid 300.73854 -408.056334)
				(end 300.987968 -408.056334)
			)
		)
		(stroke
			(width 0)
			(type solid)
		)
		(fill yes)
		(layer "F.Cu")
		(net "GND")
	)
	(gr_poly
		(pts
			(arc
				(start 304.207164 -397.151098)
				(mid 303.960784 -397.151098)
				(end 304.207164 -397.151098)
			)
		)
		(stroke
			(width 0)
			(type solid)
		)
		(fill yes)
		(layer "F.Cu")
		(net "GND")
	)
	(gr_poly
		(pts
			(arc
				(start 361.349544 -400.141948)
				(mid 361.100116 -400.141948)
				(end 361.349544 -400.141948)
			)
		)
		(stroke
			(width 0)
			(type solid)
		)
		(fill yes)
		(layer "F.Cu")
		(net "GND")
	)
	(gr_poly
		(pts
			(arc
				(start 365.446056 -424.460162)
				(mid 365.196628 -424.460162)
				(end 365.446056 -424.460162)
			)
		)
		(stroke
			(width 0)
			(type solid)
		)
		(fill yes)
		(layer "F.Cu")
		(net "GND")
	)
	(gr_poly
		(pts
			(arc
				(start 367.505234 -425.777914)
				(mid 367.255806 -425.777914)
				(end 367.505234 -425.777914)
			)
		)
		(stroke
			(width 0)
			(type solid)
		)
		(fill yes)
		(layer "F.Cu")
		(net "GND")
	)
	(gr_poly
		(pts
			(arc
				(start 17.135856 -407.23312)
				(mid 16.852392 -407.23312)
				(end 17.135856 -407.23312)
			)
		)
		(stroke
			(width 0)
			(type solid)
		)
		(fill yes)
		(layer "F.Cu")
		(net "GND")
	)
	(gr_poly
		(pts
			(arc
				(start 17.135856 -405.974296)
				(mid 16.852392 -405.974296)
				(end 17.135856 -405.974296)
			)
		)
		(stroke
			(width 0)
			(type solid)
		)
		(fill yes)
		(layer "F.Cu")
		(net "GND")
	)
	(gr_poly
		(pts
			(arc
				(start 156.144214 -115.026948)
				(mid 155.879546 -115.026948)
				(end 156.144214 -115.026948)
			)
		)
		(stroke
			(width 0)
			(type solid)
		)
		(fill yes)
		(layer "F.Cu")
		(net "GND")
	)
	(gr_poly
		(pts
			(arc
				(start 163.641278 -116.132356)
				(mid 163.37661 -116.132356)
				(end 163.641278 -116.132356)
			)
		)
		(stroke
			(width 0)
			(type solid)
		)
		(fill yes)
		(layer "F.Cu")
		(net "GND")
	)
	(gr_poly
		(pts
			(arc
				(start 184.427876 2.291588)
				(mid 184.14492 2.291588)
				(end 184.427876 2.291588)
			)
		)
		(stroke
			(width 0)
			(type solid)
		)
		(fill yes)
		(layer "F.Cu")
		(net "DELTA_L_GND_1")
	)
	(gr_poly
		(pts
			(arc
				(start 184.427876 3.550412)
				(mid 184.14492 3.550412)
				(end 184.427876 3.550412)
			)
		)
		(stroke
			(width 0)
			(type solid)
		)
		(fill yes)
		(layer "F.Cu")
		(net "DELTA_L_GND_1")
	)
	(gr_poly
		(pts
			(arc
				(start 184.427876 4.831588)
				(mid 184.14492 4.831588)
				(end 184.427876 4.831588)
			)
		)
		(stroke
			(width 0)
			(type solid)
		)
		(fill yes)
		(layer "F.Cu")
		(net "DELTA_L_GND_1")
	)
	(gr_poly
		(pts
			(arc
				(start 184.427876 6.090412)
				(mid 184.14492 6.090412)
				(end 184.427876 6.090412)
			)
		)
		(stroke
			(width 0)
			(type solid)
		)
		(fill yes)
		(layer "F.Cu")
		(net "DELTA_L_GND_1")
	)
	(gr_poly
		(pts
			(arc
				(start 212.60689 -41.034462)
				(mid 212.336126 -41.034462)
				(end 212.60689 -41.034462)
			)
		)
		(stroke
			(width 0)
			(type solid)
		)
		(fill yes)
		(layer "F.Cu")
		(net "GND")
	)
	(gr_poly
		(pts
			(arc
				(start 212.981032 -53.356256)
				(mid 212.710268 -53.356256)
				(end 212.981032 -53.356256)
			)
		)
		(stroke
			(width 0)
			(type solid)
		)
		(fill yes)
		(layer "F.Cu")
		(net "GND")
	)
	(gr_poly
		(pts
			(arc
				(start 214.135716 -5.328412)
				(mid 213.85276 -5.328412)
				(end 214.135716 -5.328412)
			)
		)
		(stroke
			(width 0)
			(type solid)
		)
		(fill yes)
		(layer "F.Cu")
		(net "DELTA_L_GND_1")
	)
	(gr_poly
		(pts
			(arc
				(start 214.135716 -4.069588)
				(mid 213.85276 -4.069588)
				(end 214.135716 -4.069588)
			)
		)
		(stroke
			(width 0)
			(type solid)
		)
		(fill yes)
		(layer "F.Cu")
		(net "DELTA_L_GND_1")
	)
	(gr_poly
		(pts
			(arc
				(start 214.135716 -2.788412)
				(mid 213.85276 -2.788412)
				(end 214.135716 -2.788412)
			)
		)
		(stroke
			(width 0)
			(type solid)
		)
		(fill yes)
		(layer "F.Cu")
		(net "DELTA_L_GND_1")
	)
	(gr_poly
		(pts
			(arc
				(start 214.135716 -1.529588)
				(mid 213.85276 -1.529588)
				(end 214.135716 -1.529588)
			)
		)
		(stroke
			(width 0)
			(type solid)
		)
		(fill yes)
		(layer "F.Cu")
		(net "DELTA_L_GND_1")
	)
	(gr_poly
		(pts
			(arc
				(start 215.234266 -32.274256)
				(mid 214.963502 -32.274256)
				(end 215.234266 -32.274256)
			)
		)
		(stroke
			(width 0)
			(type solid)
		)
		(fill yes)
		(layer "F.Cu")
		(net "GND")
	)
	(gr_poly
		(pts
			(arc
				(start 217.756486 -32.834072)
				(mid 217.485722 -32.834072)
				(end 217.756486 -32.834072)
			)
		)
		(stroke
			(width 0)
			(type solid)
		)
		(fill yes)
		(layer "F.Cu")
		(net "GND")
	)
	(gr_poly
		(pts
			(arc
				(start 225.250502 -44.21759)
				(mid 224.979738 -44.21759)
				(end 225.250502 -44.21759)
			)
		)
		(stroke
			(width 0)
			(type solid)
		)
		(fill yes)
		(layer "F.Cu")
		(net "GND")
	)
	(gr_poly
		(pts
			(arc
				(start 233.877866 -46.771052)
				(mid 233.607102 -46.771052)
				(end 233.877866 -46.771052)
			)
		)
		(stroke
			(width 0)
			(type solid)
		)
		(fill yes)
		(layer "F.Cu")
		(net "GND")
	)
	(gr_poly
		(pts
			(arc
				(start 248.65584 -5.328412)
				(mid 248.372884 -5.328412)
				(end 248.65584 -5.328412)
			)
		)
		(stroke
			(width 0)
			(type solid)
		)
		(fill yes)
		(layer "F.Cu")
		(net "DELTA_L_GND_1")
	)
	(gr_poly
		(pts
			(arc
				(start 248.65584 -4.069588)
				(mid 248.372884 -4.069588)
				(end 248.65584 -4.069588)
			)
		)
		(stroke
			(width 0)
			(type solid)
		)
		(fill yes)
		(layer "F.Cu")
		(net "DELTA_L_GND_1")
	)
	(gr_poly
		(pts
			(arc
				(start 248.65584 -2.788412)
				(mid 248.372884 -2.788412)
				(end 248.65584 -2.788412)
			)
		)
		(stroke
			(width 0)
			(type solid)
		)
		(fill yes)
		(layer "F.Cu")
		(net "DELTA_L_GND_1")
	)
	(gr_poly
		(pts
			(arc
				(start 248.65584 -1.529588)
				(mid 248.372884 -1.529588)
				(end 248.65584 -1.529588)
			)
		)
		(stroke
			(width 0)
			(type solid)
		)
		(fill yes)
		(layer "F.Cu")
		(net "DELTA_L_GND_1")
	)
	(gr_poly
		(pts
			(arc
				(start 248.65584 2.291588)
				(mid 248.372884 2.291588)
				(end 248.65584 2.291588)
			)
		)
		(stroke
			(width 0)
			(type solid)
		)
		(fill yes)
		(layer "F.Cu")
		(net "DELTA_L_GND_1")
	)
	(gr_poly
		(pts
			(arc
				(start 248.65584 3.550412)
				(mid 248.372884 3.550412)
				(end 248.65584 3.550412)
			)
		)
		(stroke
			(width 0)
			(type solid)
		)
		(fill yes)
		(layer "F.Cu")
		(net "DELTA_L_GND_1")
	)
	(gr_poly
		(pts
			(arc
				(start 248.65584 4.831588)
				(mid 248.372884 4.831588)
				(end 248.65584 4.831588)
			)
		)
		(stroke
			(width 0)
			(type solid)
		)
		(fill yes)
		(layer "F.Cu")
		(net "DELTA_L_GND_1")
	)
	(gr_poly
		(pts
			(arc
				(start 248.65584 6.090412)
				(mid 248.372884 6.090412)
				(end 248.65584 6.090412)
			)
		)
		(stroke
			(width 0)
			(type solid)
		)
		(fill yes)
		(layer "F.Cu")
		(net "DELTA_L_GND_1")
	)
	(gr_poly
		(pts
			(xy 256.764282 -75.419966) (xy 256.764282 -74.77125) (xy 256.764282 -74.147426) (xy 256.999232 -73.912476)
			(xy 257.833876 -73.077832) (xy 258.06654 -72.845168) (xy 258.665472 -72.24649) (xy 258.881626 -72.030336)
			(xy 258.934966 -71.976996) (xy 264.201656 -71.976996) (xy 264.249916 -72.025256) (xy 264.359898 -72.135238)
			(xy 265.203178 -72.135238) (xy 265.241786 -72.09663) (xy 265.241786 -71.58863) (xy 265.221212 -71.568056)
			(xy 263.976612 -71.568056) (xy 262.695182 -71.568056) (xy 261.84987 -71.568056) (xy 261.037578 -70.755764)
			(xy 251.311664 -70.755764) (xy 251.068586 -70.998842) (xy 251.068586 -71.942452) (xy 251.068586 -75.219814)
			(xy 251.674122 -75.82535) (xy 255.710182 -75.82535) (xy 256.358898 -75.82535)
		)
		(stroke
			(width 0)
			(type solid)
		)
		(fill yes)
		(layer "F.Cu")
		(net "SW_P12V_AUX_P1V05_PCH_AUX_FLT")
	)
	(gr_poly
		(pts
			(arc
				(start 263.013444 -0.245618)
				(mid 262.730488 -0.245618)
				(end 263.013444 -0.245618)
			)
		)
		(stroke
			(width 0)
			(type solid)
		)
		(fill yes)
		(layer "F.Cu")
		(net "DELTA_L_GND_1")
	)
	(gr_poly
		(pts
			(arc
				(start 263.013444 1.013206)
				(mid 262.730488 1.013206)
				(end 263.013444 1.013206)
			)
		)
		(stroke
			(width 0)
			(type solid)
		)
		(fill yes)
		(layer "F.Cu")
		(net "DELTA_L_GND_1")
	)
	(gr_poly
		(pts
			(arc
				(start 263.013444 2.294382)
				(mid 262.730488 2.294382)
				(end 263.013444 2.294382)
			)
		)
		(stroke
			(width 0)
			(type solid)
		)
		(fill yes)
		(layer "F.Cu")
		(net "DELTA_L_GND_1")
	)
	(gr_poly
		(pts
			(arc
				(start 263.013444 3.553206)
				(mid 262.730488 3.553206)
				(end 263.013444 3.553206)
			)
		)
		(stroke
			(width 0)
			(type solid)
		)
		(fill yes)
		(layer "F.Cu")
		(net "DELTA_L_GND_1")
	)
	(gr_poly
		(pts
			(arc
				(start 263.013444 4.834382)
				(mid 262.730488 4.834382)
				(end 263.013444 4.834382)
			)
		)
		(stroke
			(width 0)
			(type solid)
		)
		(fill yes)
		(layer "F.Cu")
		(net "DELTA_L_GND_1")
	)
	(gr_poly
		(pts
			(arc
				(start 263.013444 6.093206)
				(mid 262.730488 6.093206)
				(end 263.013444 6.093206)
			)
		)
		(stroke
			(width 0)
			(type solid)
		)
		(fill yes)
		(layer "F.Cu")
		(net "DELTA_L_GND_1")
	)
	(gr_poly
		(pts
			(arc
				(start 263.013444 7.374382)
				(mid 262.730488 7.374382)
				(end 263.013444 7.374382)
			)
		)
		(stroke
			(width 0)
			(type solid)
		)
		(fill yes)
		(layer "F.Cu")
		(net "DELTA_L_GND_1")
	)
	(gr_poly
		(pts
			(arc
				(start 263.013444 8.633206)
				(mid 262.730488 8.633206)
				(end 263.013444 8.633206)
			)
		)
		(stroke
			(width 0)
			(type solid)
		)
		(fill yes)
		(layer "F.Cu")
		(net "DELTA_L_GND_1")
	)
	(gr_poly
		(pts
			(arc
				(start 327.241408 -0.245618)
				(mid 326.958452 -0.245618)
				(end 327.241408 -0.245618)
			)
		)
		(stroke
			(width 0)
			(type solid)
		)
		(fill yes)
		(layer "F.Cu")
		(net "DELTA_L_GND_1")
	)
	(gr_poly
		(pts
			(arc
				(start 327.241408 1.013206)
				(mid 326.958452 1.013206)
				(end 327.241408 1.013206)
			)
		)
		(stroke
			(width 0)
			(type solid)
		)
		(fill yes)
		(layer "F.Cu")
		(net "DELTA_L_GND_1")
	)
	(gr_poly
		(pts
			(arc
				(start 327.241408 2.294382)
				(mid 326.958452 2.294382)
				(end 327.241408 2.294382)
			)
		)
		(stroke
			(width 0)
			(type solid)
		)
		(fill yes)
		(layer "F.Cu")
		(net "DELTA_L_GND_1")
	)
	(gr_poly
		(pts
			(arc
				(start 327.241408 3.553206)
				(mid 326.958452 3.553206)
				(end 327.241408 3.553206)
			)
		)
		(stroke
			(width 0)
			(type solid)
		)
		(fill yes)
		(layer "F.Cu")
		(net "DELTA_L_GND_1")
	)
	(gr_poly
		(pts
			(arc
				(start 327.241408 4.834382)
				(mid 326.958452 4.834382)
				(end 327.241408 4.834382)
			)
		)
		(stroke
			(width 0)
			(type solid)
		)
		(fill yes)
		(layer "F.Cu")
		(net "DELTA_L_GND_1")
	)
	(gr_poly
		(pts
			(arc
				(start 327.241408 6.093206)
				(mid 326.958452 6.093206)
				(end 327.241408 6.093206)
			)
		)
		(stroke
			(width 0)
			(type solid)
		)
		(fill yes)
		(layer "F.Cu")
		(net "DELTA_L_GND_1")
	)
	(gr_poly
		(pts
			(arc
				(start 327.241408 7.374382)
				(mid 326.958452 7.374382)
				(end 327.241408 7.374382)
			)
		)
		(stroke
			(width 0)
			(type solid)
		)
		(fill yes)
		(layer "F.Cu")
		(net "DELTA_L_GND_1")
	)
	(gr_poly
		(pts
			(arc
				(start 327.241408 8.633206)
				(mid 326.958452 8.633206)
				(end 327.241408 8.633206)
			)
		)
		(stroke
			(width 0)
			(type solid)
		)
		(fill yes)
		(layer "F.Cu")
		(net "DELTA_L_GND_1")
	)
	(gr_poly
		(pts
			(arc
				(start 341.58047 -0.245618)
				(mid 341.297514 -0.245618)
				(end 341.58047 -0.245618)
			)
		)
		(stroke
			(width 0)
			(type solid)
		)
		(fill yes)
		(layer "F.Cu")
		(net "DELTA_L_GND_1")
	)
	(gr_poly
		(pts
			(arc
				(start 341.58047 1.013206)
				(mid 341.297514 1.013206)
				(end 341.58047 1.013206)
			)
		)
		(stroke
			(width 0)
			(type solid)
		)
		(fill yes)
		(layer "F.Cu")
		(net "DELTA_L_GND_1")
	)
	(gr_poly
		(pts
			(arc
				(start 341.58047 2.294382)
				(mid 341.297514 2.294382)
				(end 341.58047 2.294382)
			)
		)
		(stroke
			(width 0)
			(type solid)
		)
		(fill yes)
		(layer "F.Cu")
		(net "DELTA_L_GND_1")
	)
	(gr_poly
		(pts
			(arc
				(start 341.58047 3.553206)
				(mid 341.297514 3.553206)
				(end 341.58047 3.553206)
			)
		)
		(stroke
			(width 0)
			(type solid)
		)
		(fill yes)
		(layer "F.Cu")
		(net "DELTA_L_GND_1")
	)
	(gr_poly
		(pts
			(arc
				(start 341.58047 4.834382)
				(mid 341.297514 4.834382)
				(end 341.58047 4.834382)
			)
		)
		(stroke
			(width 0)
			(type solid)
		)
		(fill yes)
		(layer "F.Cu")
		(net "DELTA_L_GND_1")
	)
	(gr_poly
		(pts
			(arc
				(start 341.58047 6.093206)
				(mid 341.297514 6.093206)
				(end 341.58047 6.093206)
			)
		)
		(stroke
			(width 0)
			(type solid)
		)
		(fill yes)
		(layer "F.Cu")
		(net "DELTA_L_GND_1")
	)
	(gr_poly
		(pts
			(arc
				(start 341.58047 7.374382)
				(mid 341.297514 7.374382)
				(end 341.58047 7.374382)
			)
		)
		(stroke
			(width 0)
			(type solid)
		)
		(fill yes)
		(layer "F.Cu")
		(net "DELTA_L_GND_1")
	)
	(gr_poly
		(pts
			(arc
				(start 341.58047 8.633206)
				(mid 341.297514 8.633206)
				(end 341.58047 8.633206)
			)
		)
		(stroke
			(width 0)
			(type solid)
		)
		(fill yes)
		(layer "F.Cu")
		(net "DELTA_L_GND_1")
	)
	(gr_poly
		(pts
			(arc
				(start 376.100594 -0.245618)
				(mid 375.817638 -0.245618)
				(end 376.100594 -0.245618)
			)
		)
		(stroke
			(width 0)
			(type solid)
		)
		(fill yes)
		(layer "F.Cu")
		(net "DELTA_L_GND_1")
	)
	(gr_poly
		(pts
			(arc
				(start 376.100594 1.013206)
				(mid 375.817638 1.013206)
				(end 376.100594 1.013206)
			)
		)
		(stroke
			(width 0)
			(type solid)
		)
		(fill yes)
		(layer "F.Cu")
		(net "DELTA_L_GND_1")
	)
	(gr_poly
		(pts
			(arc
				(start 376.100594 2.294382)
				(mid 375.817638 2.294382)
				(end 376.100594 2.294382)
			)
		)
		(stroke
			(width 0)
			(type solid)
		)
		(fill yes)
		(layer "F.Cu")
		(net "DELTA_L_GND_1")
	)
	(gr_poly
		(pts
			(arc
				(start 376.100594 3.553206)
				(mid 375.817638 3.553206)
				(end 376.100594 3.553206)
			)
		)
		(stroke
			(width 0)
			(type solid)
		)
		(fill yes)
		(layer "F.Cu")
		(net "DELTA_L_GND_1")
	)
	(gr_poly
		(pts
			(arc
				(start 376.100594 4.834382)
				(mid 375.817638 4.834382)
				(end 376.100594 4.834382)
			)
		)
		(stroke
			(width 0)
			(type solid)
		)
		(fill yes)
		(layer "F.Cu")
		(net "DELTA_L_GND_1")
	)
	(gr_poly
		(pts
			(arc
				(start 376.100594 6.093206)
				(mid 375.817638 6.093206)
				(end 376.100594 6.093206)
			)
		)
		(stroke
			(width 0)
			(type solid)
		)
		(fill yes)
		(layer "F.Cu")
		(net "DELTA_L_GND_1")
	)
	(gr_poly
		(pts
			(arc
				(start 376.100594 7.374382)
				(mid 375.817638 7.374382)
				(end 376.100594 7.374382)
			)
		)
		(stroke
			(width 0)
			(type solid)
		)
		(fill yes)
		(layer "F.Cu")
		(net "DELTA_L_GND_1")
	)
	(gr_poly
		(pts
			(arc
				(start 376.100594 8.633206)
				(mid 375.817638 8.633206)
				(end 376.100594 8.633206)
			)
		)
		(stroke
			(width 0)
			(type solid)
		)
		(fill yes)
		(layer "F.Cu")
		(net "DELTA_L_GND_1")
	)
	(gr_poly
		(pts
			(xy 391.110216 -76.170028) (xy 391.244836 -76.170028) (xy 391.246868 -76.167996) (xy 392.0363 -76.167996)
			(xy 392.284712 -75.919584) (xy 392.284712 -74.481944) (xy 392.284712 -74.168) (xy 392.10488 -73.988168)
			(xy 390.4107 -73.988168) (xy 390.05637 -74.342498) (xy 387.182106 -74.342498) (xy 386.745226 -74.779378)
			(xy 386.173726 -74.779378) (xy 385.482592 -75.470512) (xy 384.175 -75.470512) (xy 384.129534 -75.515978)
			(xy 384.129534 -75.5396) (xy 384.129534 -75.731878) (xy 384.170682 -75.773026) (xy 384.579876 -75.773026)
			(xy 384.634486 -75.773026) (xy 384.779774 -75.773026) (xy 385.174744 -76.167996) (xy 385.260596 -76.253848)
			(xy 385.76123 -76.253848) (xy 385.77774 -76.270358) (xy 391.009886 -76.270358)
		)
		(stroke
			(width 0)
			(type solid)
		)
		(fill yes)
		(layer "F.Cu")
		(net "SW_P1V8_PCH_AUX_FLT")
	)
	(gr_poly
		(pts
			(arc
				(start 290.416488 -155.224988)
				(mid 290.120832 -155.224988)
				(end 290.416488 -155.224988)
			)
		)
		(stroke
			(width 0)
			(type solid)
		)
		(fill yes)
		(layer "F.Cu")
		(net "GND")
	)
	(gr_poly
		(pts
			(arc
				(start 293.134288 -155.021788)
				(mid 292.838632 -155.021788)
				(end 293.134288 -155.021788)
			)
		)
		(stroke
			(width 0)
			(type solid)
		)
		(fill yes)
		(layer "F.Cu")
		(net "GND")
	)
	(gr_poly
		(pts
			(arc
				(start 298.341288 -152.956768)
				(mid 298.045632 -152.956768)
				(end 298.341288 -152.956768)
			)
		)
		(stroke
			(width 0)
			(type solid)
		)
		(fill yes)
		(layer "F.Cu")
		(net "GND")
	)
	(gr_poly
		(pts
			(arc
				(start 298.567348 -150.533608)
				(mid 298.271692 -150.533608)
				(end 298.567348 -150.533608)
			)
		)
		(stroke
			(width 0)
			(type solid)
		)
		(fill yes)
		(layer "F.Cu")
		(net "GND")
	)
	(gr_poly
		(pts
			(arc
				(start 298.592748 -148.750528)
				(mid 298.297092 -148.750528)
				(end 298.592748 -148.750528)
			)
		)
		(stroke
			(width 0)
			(type solid)
		)
		(fill yes)
		(layer "F.Cu")
		(net "GND")
	)
	(gr_poly
		(pts
			(xy 328.712576 -16.387572)
			(arc
				(start 328.712576 -15.597632)
				(mid 328.736875 -15.475561)
				(end 328.806048 -15.37208)
			)
			(xy 329.012296 -15.165578)
			(arc
				(start 329.012296 -14.211554)
				(mid 329.036698 -14.08944)
				(end 329.106022 -13.986002)
			)
			(xy 329.133708 -13.958062) (xy 329.133708 -13.78966) (xy 329.37958 -13.543788) (xy 330.29144 -13.543788)
			(xy 330.49718 -13.338048) (xy 330.49718 -12.88034) (xy 330.32192 -12.70508) (xy 327.60539 -12.70508)
			(xy 327.50379 -12.80668) (xy 327.50379 -16.151606) (xy 327.750932 -16.398748) (xy 328.7014 -16.398748)
		)
		(stroke
			(width 0)
			(type solid)
		)
		(fill yes)
		(layer "F.Cu")
		(net "GND")
	)
	(gr_poly
		(pts
			(arc
				(start 467.755986 -342.565228)
				(mid 467.780281 -342.546644)
				(end 467.789514 -342.517476)
			)
			(arc
				(start 467.789514 -165.682422)
				(mid 467.780298 -165.653243)
				(end 467.755986 -165.63467)
			)
			(xy 467.651084 -165.59657) (xy 467.620096 -165.604952)
			(arc
				(start 467.609936 -165.617398)
				(mid 467.455595 -165.797395)
				(end 467.295992 -165.972744)
			)
			(arc
				(start 467.295992 -165.972744)
				(mid 467.28579 -165.98883)
				(end 467.282276 -166.007542)
			)
			(arc
				(start 467.282276 -342.192356)
				(mid 467.28584 -342.211048)
				(end 467.295992 -342.227154)
			)
			(arc
				(start 467.295992 -342.227154)
				(mid 467.4556 -342.402499)
				(end 467.609936 -342.5825)
			)
			(xy 467.620096 -342.594946) (xy 467.651084 -342.603328)
		)
		(stroke
			(width 0)
			(type solid)
		)
		(fill yes)
		(layer "F.Cu")
		(net "GND")
	)
	(gr_poly
		(pts
			(xy 73.23836 -55.550308) (xy 73.23836 -52.233068) (xy 72.5932 -51.587908) (xy 68.0212 -51.587908)
			(xy 68.01358 -51.580288) (xy 67.81292 -51.780948) (xy 67.81292 -52.873148) (xy 68.04152 -53.101748)
			(xy 71.56704 -53.101748) (xy 71.66102 -53.195728) (xy 71.66102 -53.275738)
			(arc
				(start 71.666862 -53.28666)
				(mid 71.686772 -53.338737)
				(end 71.693278 -53.394102)
			)
			(xy 71.693024 -53.394102) (xy 71.693024 -53.693314)
			(arc
				(start 71.693278 -53.693314)
				(mid 71.686717 -53.748666)
				(end 71.666862 -53.800756)
			)
			(xy 71.66102 -53.811678) (xy 71.66102 -54.252368) (xy 71.14032 -54.773068) (xy 71.14032 -55.771288)
			(xy 71.17842 -55.809388) (xy 72.97928 -55.809388)
		)
		(stroke
			(width 0)
			(type solid)
		)
		(fill yes)
		(layer "F.Cu")
		(net "GND")
	)
	(gr_poly
		(pts
			(xy 129.04216 -27.201368) (xy 129.961386 -27.201368) (xy 130.149854 -27.0129) (xy 130.149854 -26.629614)
			(xy 130.025902 -26.505662) (xy 129.616962 -26.505662) (xy 129.369058 -26.257758) (xy 129.369058 -24.891746)
			(xy 129.16408 -24.686768) (xy 129.16408 -24.049228) (xy 128.88722 -23.772368) (xy 128.17348 -23.772368)
			(xy 127.934212 -23.5331) (xy 127.54356 -23.5331) (xy 127.489712 -23.586948) (xy 127.489712 -23.926292)
			(xy 127.73406 -24.17064) (xy 127.73406 -26.612342)
			(arc
				(start 127.735584 -26.618692)
				(mid 127.744293 -26.663277)
				(end 127.747268 -26.708608)
			)
			(arc
				(start 127.747268 -26.708608)
				(mid 127.744306 -26.753941)
				(end 127.735584 -26.798524)
			)
			(xy 127.73406 -26.804874) (xy 127.73406 -27.455368) (xy 127.97028 -27.691588) (xy 128.55194 -27.691588)
		)
		(stroke
			(width 0)
			(type solid)
		)
		(fill yes)
		(layer "F.Cu")
		(net "GND")
	)
	(gr_poly
		(pts
			(arc
				(start 153.071068 -193.40703)
				(mid 152.758648 -193.40703)
				(end 153.071068 -193.40703)
			)
		)
		(stroke
			(width 0)
			(type solid)
		)
		(fill yes)
		(layer "F.Cu")
		(net "GND")
	)
	(gr_poly
		(pts
			(arc
				(start 153.398728 -187.55741)
				(mid 153.086308 -187.55741)
				(end 153.398728 -187.55741)
			)
		)
		(stroke
			(width 0)
			(type solid)
		)
		(fill yes)
		(layer "F.Cu")
		(net "GND")
	)
	(gr_poly
		(pts
			(arc
				(start 156.27985 -187.846462)
				(mid 155.96743 -187.846462)
				(end 156.27985 -187.846462)
			)
		)
		(stroke
			(width 0)
			(type solid)
		)
		(fill yes)
		(layer "F.Cu")
		(net "GND")
	)
	(gr_poly
		(pts
			(arc
				(start 173.982888 -188.55563)
				(mid 173.670468 -188.55563)
				(end 173.982888 -188.55563)
			)
		)
		(stroke
			(width 0)
			(type solid)
		)
		(fill yes)
		(layer "F.Cu")
		(net "GND")
	)
	(gr_poly
		(pts
			(arc
				(start 178.443128 -188.68771)
				(mid 178.130708 -188.68771)
				(end 178.443128 -188.68771)
			)
		)
		(stroke
			(width 0)
			(type solid)
		)
		(fill yes)
		(layer "F.Cu")
		(net "GND")
	)
	(gr_poly
		(pts
			(arc
				(start 216.86901 -190.769748)
				(mid 216.55659 -190.769748)
				(end 216.86901 -190.769748)
			)
		)
		(stroke
			(width 0)
			(type solid)
		)
		(fill yes)
		(layer "F.Cu")
		(net "GND")
	)
	(gr_poly
		(pts
			(arc
				(start 225.32721 -187.747148)
				(mid 225.01479 -187.747148)
				(end 225.32721 -187.747148)
			)
		)
		(stroke
			(width 0)
			(type solid)
		)
		(fill yes)
		(layer "F.Cu")
		(net "GND")
	)
	(gr_poly
		(pts
			(arc
				(start 235.00461 -209.362548)
				(mid 234.69219 -209.362548)
				(end 235.00461 -209.362548)
			)
		)
		(stroke
			(width 0)
			(type solid)
		)
		(fill yes)
		(layer "F.Cu")
		(net "GND")
	)
	(gr_poly
		(pts
			(arc
				(start 235.66501 -206.111348)
				(mid 235.35259 -206.111348)
				(end 235.66501 -206.111348)
			)
		)
		(stroke
			(width 0)
			(type solid)
		)
		(fill yes)
		(layer "F.Cu")
		(net "GND")
	)
	(gr_poly
		(pts
			(arc
				(start 236.178344 -257.724656)
				(mid 235.865924 -257.724656)
				(end 236.178344 -257.724656)
			)
		)
		(stroke
			(width 0)
			(type solid)
		)
		(fill yes)
		(layer "F.Cu")
		(net "GND")
	)
	(gr_poly
		(pts
			(arc
				(start 239.27181 -205.755748)
				(mid 238.95939 -205.755748)
				(end 239.27181 -205.755748)
			)
		)
		(stroke
			(width 0)
			(type solid)
		)
		(fill yes)
		(layer "F.Cu")
		(net "GND")
	)
	(gr_poly
		(pts
			(arc
				(start 243.15801 -199.862948)
				(mid 242.84559 -199.862948)
				(end 243.15801 -199.862948)
			)
		)
		(stroke
			(width 0)
			(type solid)
		)
		(fill yes)
		(layer "F.Cu")
		(net "GND")
	)
	(gr_poly
		(pts
			(arc
				(start 243.76761 -200.624948)
				(mid 243.45519 -200.624948)
				(end 243.76761 -200.624948)
			)
		)
		(stroke
			(width 0)
			(type solid)
		)
		(fill yes)
		(layer "F.Cu")
		(net "GND")
	)
	(gr_poly
		(pts
			(arc
				(start 229.764844 -55.132986)
				(mid 229.431596 -55.132986)
				(end 229.764844 -55.132986)
			)
		)
		(stroke
			(width 0)
			(type solid)
		)
		(fill yes)
		(layer "F.Cu")
		(net "GND")
	)
	(gr_poly
		(pts
			(arc
				(start 229.764844 -51.53279)
				(mid 229.431596 -51.53279)
				(end 229.764844 -51.53279)
			)
		)
		(stroke
			(width 0)
			(type solid)
		)
		(fill yes)
		(layer "F.Cu")
		(net "GND")
	)
	(gr_poly
		(pts
			(arc
				(start 229.777544 -57.030366)
				(mid 229.444296 -57.030366)
				(end 229.777544 -57.030366)
			)
		)
		(stroke
			(width 0)
			(type solid)
		)
		(fill yes)
		(layer "F.Cu")
		(net "GND")
	)
	(gr_poly
		(pts
			(arc
				(start 229.777544 -53.43017)
				(mid 229.444296 -53.43017)
				(end 229.777544 -53.43017)
			)
		)
		(stroke
			(width 0)
			(type solid)
		)
		(fill yes)
		(layer "F.Cu")
		(net "GND")
	)
	(gr_poly
		(pts
			(arc
				(start 239.34166 -50.558954)
				(mid 239.008412 -50.558954)
				(end 239.34166 -50.558954)
			)
		)
		(stroke
			(width 0)
			(type solid)
		)
		(fill yes)
		(layer "F.Cu")
		(net "GND")
	)
	(gr_poly
		(pts
			(arc
				(start 239.34166 -49.136554)
				(mid 239.008412 -49.136554)
				(end 239.34166 -49.136554)
			)
		)
		(stroke
			(width 0)
			(type solid)
		)
		(fill yes)
		(layer "F.Cu")
		(net "GND")
	)
	(gr_poly
		(pts
			(arc
				(start 240.166144 -58.597038)
				(mid 239.832896 -58.597038)
				(end 240.166144 -58.597038)
			)
		)
		(stroke
			(width 0)
			(type solid)
		)
		(fill yes)
		(layer "F.Cu")
		(net "GND")
	)
	(gr_poly
		(pts
			(arc
				(start 240.166144 -57.174638)
				(mid 239.832896 -57.174638)
				(end 240.166144 -57.174638)
			)
		)
		(stroke
			(width 0)
			(type solid)
		)
		(fill yes)
		(layer "F.Cu")
		(net "GND")
	)
	(gr_poly
		(pts
			(arc
				(start 240.166144 -55.005986)
				(mid 239.832896 -55.005986)
				(end 240.166144 -55.005986)
			)
		)
		(stroke
			(width 0)
			(type solid)
		)
		(fill yes)
		(layer "F.Cu")
		(net "GND")
	)
	(gr_poly
		(pts
			(arc
				(start 240.166144 -53.583586)
				(mid 239.832896 -53.583586)
				(end 240.166144 -53.583586)
			)
		)
		(stroke
			(width 0)
			(type solid)
		)
		(fill yes)
		(layer "F.Cu")
		(net "GND")
	)
	(gr_poly
		(pts
			(arc
				(start 241.81054 -53.196998)
				(mid 241.477292 -53.196998)
				(end 241.81054 -53.196998)
			)
		)
		(stroke
			(width 0)
			(type solid)
		)
		(fill yes)
		(layer "F.Cu")
		(net "GND")
	)
	(gr_poly
		(pts
			(arc
				(start 241.81054 -51.774598)
				(mid 241.477292 -51.774598)
				(end 241.81054 -51.774598)
			)
		)
		(stroke
			(width 0)
			(type solid)
		)
		(fill yes)
		(layer "F.Cu")
		(net "GND")
	)
	(gr_poly
		(pts
			(arc
				(start 242.70462 -58.946034)
				(mid 242.371372 -58.946034)
				(end 242.70462 -58.946034)
			)
		)
		(stroke
			(width 0)
			(type solid)
		)
		(fill yes)
		(layer "F.Cu")
		(net "GND")
	)
	(gr_poly
		(pts
			(arc
				(start 242.71224 -57.338214)
				(mid 242.378992 -57.338214)
				(end 242.71224 -57.338214)
			)
		)
		(stroke
			(width 0)
			(type solid)
		)
		(fill yes)
		(layer "F.Cu")
		(net "GND")
	)
	(gr_poly
		(pts
			(arc
				(start 246.920258 -61.558932)
				(mid 246.58701 -61.558932)
				(end 246.920258 -61.558932)
			)
		)
		(stroke
			(width 0)
			(type solid)
		)
		(fill yes)
		(layer "F.Cu")
		(net "GND")
	)
	(gr_poly
		(pts
			(arc
				(start 261.156704 -31.173928)
				(mid 260.823456 -31.173928)
				(end 261.156704 -31.173928)
			)
		)
		(stroke
			(width 0)
			(type solid)
		)
		(fill yes)
		(layer "F.Cu")
		(net "GND")
	)
	(gr_poly
		(pts
			(arc
				(start 263.729724 -32.725868)
				(mid 263.396476 -32.725868)
				(end 263.729724 -32.725868)
			)
		)
		(stroke
			(width 0)
			(type solid)
		)
		(fill yes)
		(layer "F.Cu")
		(net "GND")
	)
	(gr_poly
		(pts
			(arc
				(start 271.138904 -38.514528)
				(mid 270.805656 -38.514528)
				(end 271.138904 -38.514528)
			)
		)
		(stroke
			(width 0)
			(type solid)
		)
		(fill yes)
		(layer "F.Cu")
		(net "GND")
	)
	(gr_poly
		(pts
			(arc
				(start 274.047204 -23.739348)
				(mid 273.713956 -23.739348)
				(end 274.047204 -23.739348)
			)
		)
		(stroke
			(width 0)
			(type solid)
		)
		(fill yes)
		(layer "F.Cu")
		(net "GND")
	)
	(gr_poly
		(pts
			(arc
				(start 280.196544 -33.965388)
				(mid 279.863296 -33.965388)
				(end 280.196544 -33.965388)
			)
		)
		(stroke
			(width 0)
			(type solid)
		)
		(fill yes)
		(layer "F.Cu")
		(net "GND")
	)
	(gr_poly
		(pts
			(arc
				(start 287.173416 -16.963644)
				(mid 286.840168 -16.963644)
				(end 287.173416 -16.963644)
			)
		)
		(stroke
			(width 0)
			(type solid)
		)
		(fill yes)
		(layer "F.Cu")
		(net "GND")
	)
	(gr_poly
		(pts
			(arc
				(start 302.858424 -14.432788)
				(mid 302.525176 -14.432788)
				(end 302.858424 -14.432788)
			)
		)
		(stroke
			(width 0)
			(type solid)
		)
		(fill yes)
		(layer "F.Cu")
		(net "GND")
	)
	(gr_poly
		(pts
			(arc
				(start 316.093856 -29.675328)
				(mid 315.760608 -29.675328)
				(end 316.093856 -29.675328)
			)
		)
		(stroke
			(width 0)
			(type solid)
		)
		(fill yes)
		(layer "F.Cu")
		(net "GND")
	)
	(gr_poly
		(pts
			(arc
				(start 318.418718 -28.423362)
				(mid 318.08547 -28.423362)
				(end 318.418718 -28.423362)
			)
		)
		(stroke
			(width 0)
			(type solid)
		)
		(fill yes)
		(layer "F.Cu")
		(net "GND")
	)
	(gr_poly
		(pts
			(arc
				(start 365.591344 -16.360648)
				(mid 365.258096 -16.360648)
				(end 365.591344 -16.360648)
			)
		)
		(stroke
			(width 0)
			(type solid)
		)
		(fill yes)
		(layer "F.Cu")
		(net "GND")
	)
	(gr_poly
		(pts
			(arc
				(start 6.470396 -55.93588)
				(mid 6.104636 -55.93588)
				(end 6.470396 -55.93588)
			)
		)
		(stroke
			(width 0)
			(type solid)
		)
		(fill yes)
		(layer "F.Cu")
		(net "GND")
	)
	(gr_poly
		(pts
			(arc
				(start 6.485636 -60.063888)
				(mid 6.119876 -60.063888)
				(end 6.485636 -60.063888)
			)
		)
		(stroke
			(width 0)
			(type solid)
		)
		(fill yes)
		(layer "F.Cu")
		(net "GND")
	)
	(gr_poly
		(pts
			(arc
				(start 6.723888 -51.631596)
				(mid 6.358128 -51.631596)
				(end 6.723888 -51.631596)
			)
		)
		(stroke
			(width 0)
			(type solid)
		)
		(fill yes)
		(layer "F.Cu")
		(net "GND")
	)
	(gr_poly
		(pts
			(arc
				(start 6.800596 -49.567592)
				(mid 6.434836 -49.567592)
				(end 6.800596 -49.567592)
			)
		)
		(stroke
			(width 0)
			(type solid)
		)
		(fill yes)
		(layer "F.Cu")
		(net "GND")
	)
	(gr_poly
		(pts
			(arc
				(start 9.22528 -57.75452)
				(mid 8.85952 -57.75452)
				(end 9.22528 -57.75452)
			)
		)
		(stroke
			(width 0)
			(type solid)
		)
		(fill yes)
		(layer "F.Cu")
		(net "GND")
	)
	(gr_poly
		(pts
			(arc
				(start 11.621516 -114.072924)
				(mid 11.255756 -114.072924)
				(end 11.621516 -114.072924)
			)
		)
		(stroke
			(width 0)
			(type solid)
		)
		(fill yes)
		(layer "F.Cu")
		(net "GND")
	)
	(gr_poly
		(pts
			(arc
				(start 11.659108 -108.28274)
				(mid 11.293348 -108.28274)
				(end 11.659108 -108.28274)
			)
		)
		(stroke
			(width 0)
			(type solid)
		)
		(fill yes)
		(layer "F.Cu")
		(net "GND")
	)
	(gr_poly
		(pts
			(arc
				(start 12.277852 -104.930702)
				(mid 11.912092 -104.930702)
				(end 12.277852 -104.930702)
			)
		)
		(stroke
			(width 0)
			(type solid)
		)
		(fill yes)
		(layer "F.Cu")
		(net "GND")
	)
	(gr_poly
		(pts
			(arc
				(start 12.278106 -106.97337)
				(mid 11.912346 -106.97337)
				(end 12.278106 -106.97337)
			)
		)
		(stroke
			(width 0)
			(type solid)
		)
		(fill yes)
		(layer "F.Cu")
		(net "GND")
	)
	(gr_poly
		(pts
			(arc
				(start 12.88034 -114.072924)
				(mid 12.51458 -114.072924)
				(end 12.88034 -114.072924)
			)
		)
		(stroke
			(width 0)
			(type solid)
		)
		(fill yes)
		(layer "F.Cu")
		(net "GND")
	)
	(gr_poly
		(pts
			(arc
				(start 12.917932 -108.28274)
				(mid 12.552172 -108.28274)
				(end 12.917932 -108.28274)
			)
		)
		(stroke
			(width 0)
			(type solid)
		)
		(fill yes)
		(layer "F.Cu")
		(net "GND")
	)
	(gr_poly
		(pts
			(arc
				(start 15.011146 -17.61236)
				(mid 14.645386 -17.61236)
				(end 15.011146 -17.61236)
			)
		)
		(stroke
			(width 0)
			(type solid)
		)
		(fill yes)
		(layer "F.Cu")
		(net "GND")
	)
	(gr_poly
		(pts
			(arc
				(start 15.519146 -18.246344)
				(mid 15.153386 -18.246344)
				(end 15.519146 -18.246344)
			)
		)
		(stroke
			(width 0)
			(type solid)
		)
		(fill yes)
		(layer "F.Cu")
		(net "GND")
	)
	(gr_poly
		(pts
			(arc
				(start 15.519146 -16.978376)
				(mid 15.153386 -16.978376)
				(end 15.519146 -16.978376)
			)
		)
		(stroke
			(width 0)
			(type solid)
		)
		(fill yes)
		(layer "F.Cu")
		(net "GND")
	)
	(gr_poly
		(pts
			(arc
				(start 15.522702 -108.28274)
				(mid 15.156942 -108.28274)
				(end 15.522702 -108.28274)
			)
		)
		(stroke
			(width 0)
			(type solid)
		)
		(fill yes)
		(layer "F.Cu")
		(net "GND")
	)
	(gr_poly
		(pts
			(arc
				(start 15.598648 -22.127972)
				(mid 15.232888 -22.127972)
				(end 15.598648 -22.127972)
			)
		)
		(stroke
			(width 0)
			(type solid)
		)
		(fill yes)
		(layer "F.Cu")
		(net "GND")
	)
	(gr_poly
		(pts
			(arc
				(start 16.136112 -106.27995)
				(mid 15.770352 -106.27995)
				(end 16.136112 -106.27995)
			)
		)
		(stroke
			(width 0)
			(type solid)
		)
		(fill yes)
		(layer "F.Cu")
		(net "GND")
	)
	(gr_poly
		(pts
			(arc
				(start 16.142462 -104.151938)
				(mid 15.776702 -104.151938)
				(end 16.142462 -104.151938)
			)
		)
		(stroke
			(width 0)
			(type solid)
		)
		(fill yes)
		(layer "F.Cu")
		(net "GND")
	)
	(gr_poly
		(pts
			(arc
				(start 16.77797 -18.246344)
				(mid 16.41221 -18.246344)
				(end 16.77797 -18.246344)
			)
		)
		(stroke
			(width 0)
			(type solid)
		)
		(fill yes)
		(layer "F.Cu")
		(net "GND")
	)
	(gr_poly
		(pts
			(arc
				(start 16.77797 -16.978376)
				(mid 16.41221 -16.978376)
				(end 16.77797 -16.978376)
			)
		)
		(stroke
			(width 0)
			(type solid)
		)
		(fill yes)
		(layer "F.Cu")
		(net "GND")
	)
	(gr_poly
		(pts
			(arc
				(start 16.781526 -108.28274)
				(mid 16.415766 -108.28274)
				(end 16.781526 -108.28274)
			)
		)
		(stroke
			(width 0)
			(type solid)
		)
		(fill yes)
		(layer "F.Cu")
		(net "GND")
	)
	(gr_poly
		(pts
			(arc
				(start 16.857472 -22.127972)
				(mid 16.491712 -22.127972)
				(end 16.857472 -22.127972)
			)
		)
		(stroke
			(width 0)
			(type solid)
		)
		(fill yes)
		(layer "F.Cu")
		(net "GND")
	)
	(gr_poly
		(pts
			(arc
				(start 17.28597 -17.61236)
				(mid 16.92021 -17.61236)
				(end 17.28597 -17.61236)
			)
		)
		(stroke
			(width 0)
			(type solid)
		)
		(fill yes)
		(layer "F.Cu")
		(net "GND")
	)
	(gr_poly
		(pts
			(arc
				(start 17.805146 -19.13636)
				(mid 17.439386 -19.13636)
				(end 17.805146 -19.13636)
			)
		)
		(stroke
			(width 0)
			(type solid)
		)
		(fill yes)
		(layer "F.Cu")
		(net "GND")
	)
	(gr_poly
		(pts
			(arc
				(start 18.313146 -19.770344)
				(mid 17.947386 -19.770344)
				(end 18.313146 -19.770344)
			)
		)
		(stroke
			(width 0)
			(type solid)
		)
		(fill yes)
		(layer "F.Cu")
		(net "GND")
	)
	(gr_poly
		(pts
			(arc
				(start 18.313146 -18.502376)
				(mid 17.947386 -18.502376)
				(end 18.313146 -18.502376)
			)
		)
		(stroke
			(width 0)
			(type solid)
		)
		(fill yes)
		(layer "F.Cu")
		(net "GND")
	)
	(gr_poly
		(pts
			(arc
				(start 18.493994 -6.597396)
				(mid 18.128234 -6.597396)
				(end 18.493994 -6.597396)
			)
		)
		(stroke
			(width 0)
			(type solid)
		)
		(fill yes)
		(layer "F.Cu")
		(net "GND")
	)
	(gr_poly
		(pts
			(arc
				(start 19.001994 -6.090412)
				(mid 18.636234 -6.090412)
				(end 19.001994 -6.090412)
			)
		)
		(stroke
			(width 0)
			(type solid)
		)
		(fill yes)
		(layer "F.Cu")
		(net "GND")
	)
	(gr_poly
		(pts
			(arc
				(start 19.57197 -19.770344)
				(mid 19.20621 -19.770344)
				(end 19.57197 -19.770344)
			)
		)
		(stroke
			(width 0)
			(type solid)
		)
		(fill yes)
		(layer "F.Cu")
		(net "GND")
	)
	(gr_poly
		(pts
			(arc
				(start 19.57197 -18.502376)
				(mid 19.20621 -18.502376)
				(end 19.57197 -18.502376)
			)
		)
		(stroke
			(width 0)
			(type solid)
		)
		(fill yes)
		(layer "F.Cu")
		(net "GND")
	)
	(gr_poly
		(pts
			(arc
				(start 20.07997 -19.13636)
				(mid 19.71421 -19.13636)
				(end 20.07997 -19.13636)
			)
		)
		(stroke
			(width 0)
			(type solid)
		)
		(fill yes)
		(layer "F.Cu")
		(net "GND")
	)
	(gr_poly
		(pts
			(arc
				(start 20.260818 -6.090412)
				(mid 19.895058 -6.090412)
				(end 20.260818 -6.090412)
			)
		)
		(stroke
			(width 0)
			(type solid)
		)
		(fill yes)
		(layer "F.Cu")
		(net "GND")
	)
	(gr_poly
		(pts
			(arc
				(start 20.298664 -4.962652)
				(mid 19.932904 -4.962652)
				(end 20.298664 -4.962652)
			)
		)
		(stroke
			(width 0)
			(type solid)
		)
		(fill yes)
		(layer "F.Cu")
		(net "GND")
	)
	(gr_poly
		(pts
			(arc
				(start 20.599146 -17.61236)
				(mid 20.233386 -17.61236)
				(end 20.599146 -17.61236)
			)
		)
		(stroke
			(width 0)
			(type solid)
		)
		(fill yes)
		(layer "F.Cu")
		(net "GND")
	)
	(gr_poly
		(pts
			(arc
				(start 20.61972 -166.540688)
				(mid 20.25396 -166.540688)
				(end 20.61972 -166.540688)
			)
		)
		(stroke
			(width 0)
			(type solid)
		)
		(fill yes)
		(layer "F.Cu")
		(net "GND")
	)
	(gr_poly
		(pts
			(arc
				(start 20.768818 -6.597396)
				(mid 20.403058 -6.597396)
				(end 20.768818 -6.597396)
			)
		)
		(stroke
			(width 0)
			(type solid)
		)
		(fill yes)
		(layer "F.Cu")
		(net "GND")
	)
	(gr_poly
		(pts
			(arc
				(start 20.806664 -5.596636)
				(mid 20.440904 -5.596636)
				(end 20.806664 -5.596636)
			)
		)
		(stroke
			(width 0)
			(type solid)
		)
		(fill yes)
		(layer "F.Cu")
		(net "GND")
	)
	(gr_poly
		(pts
			(arc
				(start 20.806664 -4.328668)
				(mid 20.440904 -4.328668)
				(end 20.806664 -4.328668)
			)
		)
		(stroke
			(width 0)
			(type solid)
		)
		(fill yes)
		(layer "F.Cu")
		(net "GND")
	)
	(gr_poly
		(pts
			(arc
				(start 21.107146 -18.246344)
				(mid 20.741386 -18.246344)
				(end 21.107146 -18.246344)
			)
		)
		(stroke
			(width 0)
			(type solid)
		)
		(fill yes)
		(layer "F.Cu")
		(net "GND")
	)
	(gr_poly
		(pts
			(arc
				(start 21.107146 -16.978376)
				(mid 20.741386 -16.978376)
				(end 21.107146 -16.978376)
			)
		)
		(stroke
			(width 0)
			(type solid)
		)
		(fill yes)
		(layer "F.Cu")
		(net "GND")
	)
	(gr_poly
		(pts
			(arc
				(start 22.065488 -5.596636)
				(mid 21.699728 -5.596636)
				(end 22.065488 -5.596636)
			)
		)
		(stroke
			(width 0)
			(type solid)
		)
		(fill yes)
		(layer "F.Cu")
		(net "GND")
	)
	(gr_poly
		(pts
			(arc
				(start 22.065488 -4.328668)
				(mid 21.699728 -4.328668)
				(end 22.065488 -4.328668)
			)
		)
		(stroke
			(width 0)
			(type solid)
		)
		(fill yes)
		(layer "F.Cu")
		(net "GND")
	)
	(gr_poly
		(pts
			(arc
				(start 22.093936 -6.597396)
				(mid 21.728176 -6.597396)
				(end 22.093936 -6.597396)
			)
		)
		(stroke
			(width 0)
			(type solid)
		)
		(fill yes)
		(layer "F.Cu")
		(net "GND")
	)
	(gr_poly
		(pts
			(arc
				(start 22.36597 -18.246344)
				(mid 22.00021 -18.246344)
				(end 22.36597 -18.246344)
			)
		)
		(stroke
			(width 0)
			(type solid)
		)
		(fill yes)
		(layer "F.Cu")
		(net "GND")
	)
	(gr_poly
		(pts
			(arc
				(start 22.36597 -16.978376)
				(mid 22.00021 -16.978376)
				(end 22.36597 -16.978376)
			)
		)
		(stroke
			(width 0)
			(type solid)
		)
		(fill yes)
		(layer "F.Cu")
		(net "GND")
	)
	(gr_poly
		(pts
			(arc
				(start 22.573488 -4.962652)
				(mid 22.207728 -4.962652)
				(end 22.573488 -4.962652)
			)
		)
		(stroke
			(width 0)
			(type solid)
		)
		(fill yes)
		(layer "F.Cu")
		(net "GND")
	)
	(gr_poly
		(pts
			(arc
				(start 22.601936 -6.090412)
				(mid 22.236176 -6.090412)
				(end 22.601936 -6.090412)
			)
		)
		(stroke
			(width 0)
			(type solid)
		)
		(fill yes)
		(layer "F.Cu")
		(net "GND")
	)
	(gr_poly
		(pts
			(arc
				(start 22.87397 -17.61236)
				(mid 22.50821 -17.61236)
				(end 22.87397 -17.61236)
			)
		)
		(stroke
			(width 0)
			(type solid)
		)
		(fill yes)
		(layer "F.Cu")
		(net "GND")
	)
	(gr_poly
		(pts
			(arc
				(start 23.393146 -19.13636)
				(mid 23.027386 -19.13636)
				(end 23.393146 -19.13636)
			)
		)
		(stroke
			(width 0)
			(type solid)
		)
		(fill yes)
		(layer "F.Cu")
		(net "GND")
	)
	(gr_poly
		(pts
			(arc
				(start 23.86076 -6.090412)
				(mid 23.495 -6.090412)
				(end 23.86076 -6.090412)
			)
		)
		(stroke
			(width 0)
			(type solid)
		)
		(fill yes)
		(layer "F.Cu")
		(net "GND")
	)
	(gr_poly
		(pts
			(arc
				(start 23.898606 -4.962652)
				(mid 23.532846 -4.962652)
				(end 23.898606 -4.962652)
			)
		)
		(stroke
			(width 0)
			(type solid)
		)
		(fill yes)
		(layer "F.Cu")
		(net "GND")
	)
	(gr_poly
		(pts
			(arc
				(start 23.901146 -19.770344)
				(mid 23.535386 -19.770344)
				(end 23.901146 -19.770344)
			)
		)
		(stroke
			(width 0)
			(type solid)
		)
		(fill yes)
		(layer "F.Cu")
		(net "GND")
	)
	(gr_poly
		(pts
			(arc
				(start 23.901146 -18.502376)
				(mid 23.535386 -18.502376)
				(end 23.901146 -18.502376)
			)
		)
		(stroke
			(width 0)
			(type solid)
		)
		(fill yes)
		(layer "F.Cu")
		(net "GND")
	)
	(gr_poly
		(pts
			(arc
				(start 24.36876 -6.597396)
				(mid 24.003 -6.597396)
				(end 24.36876 -6.597396)
			)
		)
		(stroke
			(width 0)
			(type solid)
		)
		(fill yes)
		(layer "F.Cu")
		(net "GND")
	)
	(gr_poly
		(pts
			(arc
				(start 24.406606 -5.596636)
				(mid 24.040846 -5.596636)
				(end 24.406606 -5.596636)
			)
		)
		(stroke
			(width 0)
			(type solid)
		)
		(fill yes)
		(layer "F.Cu")
		(net "GND")
	)
	(gr_poly
		(pts
			(arc
				(start 24.406606 -4.328668)
				(mid 24.040846 -4.328668)
				(end 24.406606 -4.328668)
			)
		)
		(stroke
			(width 0)
			(type solid)
		)
		(fill yes)
		(layer "F.Cu")
		(net "GND")
	)
	(gr_poly
		(pts
			(arc
				(start 25.15997 -19.770344)
				(mid 24.79421 -19.770344)
				(end 25.15997 -19.770344)
			)
		)
		(stroke
			(width 0)
			(type solid)
		)
		(fill yes)
		(layer "F.Cu")
		(net "GND")
	)
	(gr_poly
		(pts
			(arc
				(start 25.15997 -18.502376)
				(mid 24.79421 -18.502376)
				(end 25.15997 -18.502376)
			)
		)
		(stroke
			(width 0)
			(type solid)
		)
		(fill yes)
		(layer "F.Cu")
		(net "GND")
	)
	(gr_poly
		(pts
			(arc
				(start 25.66543 -5.596636)
				(mid 25.29967 -5.596636)
				(end 25.66543 -5.596636)
			)
		)
		(stroke
			(width 0)
			(type solid)
		)
		(fill yes)
		(layer "F.Cu")
		(net "GND")
	)
	(gr_poly
		(pts
			(arc
				(start 25.66543 -4.328668)
				(mid 25.29967 -4.328668)
				(end 25.66543 -4.328668)
			)
		)
		(stroke
			(width 0)
			(type solid)
		)
		(fill yes)
		(layer "F.Cu")
		(net "GND")
	)
	(gr_poly
		(pts
			(arc
				(start 25.66797 -19.13636)
				(mid 25.30221 -19.13636)
				(end 25.66797 -19.13636)
			)
		)
		(stroke
			(width 0)
			(type solid)
		)
		(fill yes)
		(layer "F.Cu")
		(net "GND")
	)
	(gr_poly
		(pts
			(arc
				(start 25.693878 -6.597396)
				(mid 25.328118 -6.597396)
				(end 25.693878 -6.597396)
			)
		)
		(stroke
			(width 0)
			(type solid)
		)
		(fill yes)
		(layer "F.Cu")
		(net "GND")
	)
	(gr_poly
		(pts
			(arc
				(start 26.17343 -4.962652)
				(mid 25.80767 -4.962652)
				(end 26.17343 -4.962652)
			)
		)
		(stroke
			(width 0)
			(type solid)
		)
		(fill yes)
		(layer "F.Cu")
		(net "GND")
	)
	(gr_poly
		(pts
			(arc
				(start 26.187146 -17.61236)
				(mid 25.821386 -17.61236)
				(end 26.187146 -17.61236)
			)
		)
		(stroke
			(width 0)
			(type solid)
		)
		(fill yes)
		(layer "F.Cu")
		(net "GND")
	)
	(gr_poly
		(pts
			(arc
				(start 26.201878 -6.090412)
				(mid 25.836118 -6.090412)
				(end 26.201878 -6.090412)
			)
		)
		(stroke
			(width 0)
			(type solid)
		)
		(fill yes)
		(layer "F.Cu")
		(net "GND")
	)
	(gr_poly
		(pts
			(arc
				(start 26.695146 -18.246344)
				(mid 26.329386 -18.246344)
				(end 26.695146 -18.246344)
			)
		)
		(stroke
			(width 0)
			(type solid)
		)
		(fill yes)
		(layer "F.Cu")
		(net "GND")
	)
	(gr_poly
		(pts
			(arc
				(start 26.695146 -16.978376)
				(mid 26.329386 -16.978376)
				(end 26.695146 -16.978376)
			)
		)
		(stroke
			(width 0)
			(type solid)
		)
		(fill yes)
		(layer "F.Cu")
		(net "GND")
	)
	(gr_poly
		(pts
			(arc
				(start 27.460702 -6.090412)
				(mid 27.094942 -6.090412)
				(end 27.460702 -6.090412)
			)
		)
		(stroke
			(width 0)
			(type solid)
		)
		(fill yes)
		(layer "F.Cu")
		(net "GND")
	)
	(gr_poly
		(pts
			(arc
				(start 27.498548 -4.962652)
				(mid 27.132788 -4.962652)
				(end 27.498548 -4.962652)
			)
		)
		(stroke
			(width 0)
			(type solid)
		)
		(fill yes)
		(layer "F.Cu")
		(net "GND")
	)
	(gr_poly
		(pts
			(arc
				(start 27.95397 -18.246344)
				(mid 27.58821 -18.246344)
				(end 27.95397 -18.246344)
			)
		)
		(stroke
			(width 0)
			(type solid)
		)
		(fill yes)
		(layer "F.Cu")
		(net "GND")
	)
	(gr_poly
		(pts
			(arc
				(start 27.95397 -16.978376)
				(mid 27.58821 -16.978376)
				(end 27.95397 -16.978376)
			)
		)
		(stroke
			(width 0)
			(type solid)
		)
		(fill yes)
		(layer "F.Cu")
		(net "GND")
	)
	(gr_poly
		(pts
			(arc
				(start 27.968702 -6.597396)
				(mid 27.602942 -6.597396)
				(end 27.968702 -6.597396)
			)
		)
		(stroke
			(width 0)
			(type solid)
		)
		(fill yes)
		(layer "F.Cu")
		(net "GND")
	)
	(gr_poly
		(pts
			(arc
				(start 28.006548 -5.596636)
				(mid 27.640788 -5.596636)
				(end 28.006548 -5.596636)
			)
		)
		(stroke
			(width 0)
			(type solid)
		)
		(fill yes)
		(layer "F.Cu")
		(net "GND")
	)
	(gr_poly
		(pts
			(arc
				(start 28.006548 -4.328668)
				(mid 27.640788 -4.328668)
				(end 28.006548 -4.328668)
			)
		)
		(stroke
			(width 0)
			(type solid)
		)
		(fill yes)
		(layer "F.Cu")
		(net "GND")
	)
	(gr_poly
		(pts
			(arc
				(start 28.46197 -17.61236)
				(mid 28.09621 -17.61236)
				(end 28.46197 -17.61236)
			)
		)
		(stroke
			(width 0)
			(type solid)
		)
		(fill yes)
		(layer "F.Cu")
		(net "GND")
	)
	(gr_poly
		(pts
			(arc
				(start 28.981146 -19.13636)
				(mid 28.615386 -19.13636)
				(end 28.981146 -19.13636)
			)
		)
		(stroke
			(width 0)
			(type solid)
		)
		(fill yes)
		(layer "F.Cu")
		(net "GND")
	)
	(gr_poly
		(pts
			(arc
				(start 29.265372 -5.596636)
				(mid 28.899612 -5.596636)
				(end 29.265372 -5.596636)
			)
		)
		(stroke
			(width 0)
			(type solid)
		)
		(fill yes)
		(layer "F.Cu")
		(net "GND")
	)
	(gr_poly
		(pts
			(arc
				(start 29.265372 -4.328668)
				(mid 28.899612 -4.328668)
				(end 29.265372 -4.328668)
			)
		)
		(stroke
			(width 0)
			(type solid)
		)
		(fill yes)
		(layer "F.Cu")
		(net "GND")
	)
	(gr_poly
		(pts
			(arc
				(start 29.294074 -6.597396)
				(mid 28.928314 -6.597396)
				(end 29.294074 -6.597396)
			)
		)
		(stroke
			(width 0)
			(type solid)
		)
		(fill yes)
		(layer "F.Cu")
		(net "GND")
	)
	(gr_poly
		(pts
			(arc
				(start 29.489146 -19.770344)
				(mid 29.123386 -19.770344)
				(end 29.489146 -19.770344)
			)
		)
		(stroke
			(width 0)
			(type solid)
		)
		(fill yes)
		(layer "F.Cu")
		(net "GND")
	)
	(gr_poly
		(pts
			(arc
				(start 29.489146 -18.502376)
				(mid 29.123386 -18.502376)
				(end 29.489146 -18.502376)
			)
		)
		(stroke
			(width 0)
			(type solid)
		)
		(fill yes)
		(layer "F.Cu")
		(net "GND")
	)
	(gr_poly
		(pts
			(arc
				(start 29.773372 -4.962652)
				(mid 29.407612 -4.962652)
				(end 29.773372 -4.962652)
			)
		)
		(stroke
			(width 0)
			(type solid)
		)
		(fill yes)
		(layer "F.Cu")
		(net "GND")
	)
	(gr_poly
		(pts
			(arc
				(start 29.802074 -6.090412)
				(mid 29.436314 -6.090412)
				(end 29.802074 -6.090412)
			)
		)
		(stroke
			(width 0)
			(type solid)
		)
		(fill yes)
		(layer "F.Cu")
		(net "GND")
	)
	(gr_poly
		(pts
			(arc
				(start 30.74797 -19.770344)
				(mid 30.38221 -19.770344)
				(end 30.74797 -19.770344)
			)
		)
		(stroke
			(width 0)
			(type solid)
		)
		(fill yes)
		(layer "F.Cu")
		(net "GND")
	)
	(gr_poly
		(pts
			(arc
				(start 30.74797 -18.502376)
				(mid 30.38221 -18.502376)
				(end 30.74797 -18.502376)
			)
		)
		(stroke
			(width 0)
			(type solid)
		)
		(fill yes)
		(layer "F.Cu")
		(net "GND")
	)
	(gr_poly
		(pts
			(arc
				(start 31.060898 -6.090412)
				(mid 30.695138 -6.090412)
				(end 31.060898 -6.090412)
			)
		)
		(stroke
			(width 0)
			(type solid)
		)
		(fill yes)
		(layer "F.Cu")
		(net "GND")
	)
	(gr_poly
		(pts
			(arc
				(start 31.098744 -4.962652)
				(mid 30.732984 -4.962652)
				(end 31.098744 -4.962652)
			)
		)
		(stroke
			(width 0)
			(type solid)
		)
		(fill yes)
		(layer "F.Cu")
		(net "GND")
	)
	(gr_poly
		(pts
			(arc
				(start 31.25597 -19.13636)
				(mid 30.89021 -19.13636)
				(end 31.25597 -19.13636)
			)
		)
		(stroke
			(width 0)
			(type solid)
		)
		(fill yes)
		(layer "F.Cu")
		(net "GND")
	)
	(gr_poly
		(pts
			(arc
				(start 31.568898 -6.597396)
				(mid 31.203138 -6.597396)
				(end 31.568898 -6.597396)
			)
		)
		(stroke
			(width 0)
			(type solid)
		)
		(fill yes)
		(layer "F.Cu")
		(net "GND")
	)
	(gr_poly
		(pts
			(arc
				(start 31.606744 -5.596636)
				(mid 31.240984 -5.596636)
				(end 31.606744 -5.596636)
			)
		)
		(stroke
			(width 0)
			(type solid)
		)
		(fill yes)
		(layer "F.Cu")
		(net "GND")
	)
	(gr_poly
		(pts
			(arc
				(start 31.606744 -4.328668)
				(mid 31.240984 -4.328668)
				(end 31.606744 -4.328668)
			)
		)
		(stroke
			(width 0)
			(type solid)
		)
		(fill yes)
		(layer "F.Cu")
		(net "GND")
	)
	(gr_poly
		(pts
			(arc
				(start 31.775146 -17.61236)
				(mid 31.409386 -17.61236)
				(end 31.775146 -17.61236)
			)
		)
		(stroke
			(width 0)
			(type solid)
		)
		(fill yes)
		(layer "F.Cu")
		(net "GND")
	)
	(gr_poly
		(pts
			(arc
				(start 32.283146 -18.246344)
				(mid 31.917386 -18.246344)
				(end 32.283146 -18.246344)
			)
		)
		(stroke
			(width 0)
			(type solid)
		)
		(fill yes)
		(layer "F.Cu")
		(net "GND")
	)
	(gr_poly
		(pts
			(arc
				(start 32.283146 -16.978376)
				(mid 31.917386 -16.978376)
				(end 32.283146 -16.978376)
			)
		)
		(stroke
			(width 0)
			(type solid)
		)
		(fill yes)
		(layer "F.Cu")
		(net "GND")
	)
	(gr_poly
		(pts
			(arc
				(start 32.493204 -121.974864)
				(mid 32.127444 -121.974864)
				(end 32.493204 -121.974864)
			)
		)
		(stroke
			(width 0)
			(type solid)
		)
		(fill yes)
		(layer "F.Cu")
		(net "GND")
	)
	(gr_poly
		(pts
			(arc
				(start 32.865568 -5.596636)
				(mid 32.499808 -5.596636)
				(end 32.865568 -5.596636)
			)
		)
		(stroke
			(width 0)
			(type solid)
		)
		(fill yes)
		(layer "F.Cu")
		(net "GND")
	)
	(gr_poly
		(pts
			(arc
				(start 32.865568 -4.328668)
				(mid 32.499808 -4.328668)
				(end 32.865568 -4.328668)
			)
		)
		(stroke
			(width 0)
			(type solid)
		)
		(fill yes)
		(layer "F.Cu")
		(net "GND")
	)
	(gr_poly
		(pts
			(arc
				(start 33.373568 -4.962652)
				(mid 33.007808 -4.962652)
				(end 33.373568 -4.962652)
			)
		)
		(stroke
			(width 0)
			(type solid)
		)
		(fill yes)
		(layer "F.Cu")
		(net "GND")
	)
	(gr_poly
		(pts
			(arc
				(start 33.54197 -18.246344)
				(mid 33.17621 -18.246344)
				(end 33.54197 -18.246344)
			)
		)
		(stroke
			(width 0)
			(type solid)
		)
		(fill yes)
		(layer "F.Cu")
		(net "GND")
	)
	(gr_poly
		(pts
			(arc
				(start 33.54197 -16.978376)
				(mid 33.17621 -16.978376)
				(end 33.54197 -16.978376)
			)
		)
		(stroke
			(width 0)
			(type solid)
		)
		(fill yes)
		(layer "F.Cu")
		(net "GND")
	)
	(gr_poly
		(pts
			(arc
				(start 34.04997 -17.61236)
				(mid 33.68421 -17.61236)
				(end 34.04997 -17.61236)
			)
		)
		(stroke
			(width 0)
			(type solid)
		)
		(fill yes)
		(layer "F.Cu")
		(net "GND")
	)
	(gr_poly
		(pts
			(arc
				(start 34.569146 -19.13636)
				(mid 34.203386 -19.13636)
				(end 34.569146 -19.13636)
			)
		)
		(stroke
			(width 0)
			(type solid)
		)
		(fill yes)
		(layer "F.Cu")
		(net "GND")
	)
	(gr_poly
		(pts
			(arc
				(start 34.803334 -45.49013)
				(mid 34.437574 -45.49013)
				(end 34.803334 -45.49013)
			)
		)
		(stroke
			(width 0)
			(type solid)
		)
		(fill yes)
		(layer "F.Cu")
		(net "GND")
	)
	(gr_poly
		(pts
			(arc
				(start 35.077146 -19.770344)
				(mid 34.711386 -19.770344)
				(end 35.077146 -19.770344)
			)
		)
		(stroke
			(width 0)
			(type solid)
		)
		(fill yes)
		(layer "F.Cu")
		(net "GND")
	)
	(gr_poly
		(pts
			(arc
				(start 35.077146 -18.502376)
				(mid 34.711386 -18.502376)
				(end 35.077146 -18.502376)
			)
		)
		(stroke
			(width 0)
			(type solid)
		)
		(fill yes)
		(layer "F.Cu")
		(net "GND")
	)
	(gr_poly
		(pts
			(arc
				(start 36.33597 -19.770344)
				(mid 35.97021 -19.770344)
				(end 36.33597 -19.770344)
			)
		)
		(stroke
			(width 0)
			(type solid)
		)
		(fill yes)
		(layer "F.Cu")
		(net "GND")
	)
	(gr_poly
		(pts
			(arc
				(start 36.33597 -18.502376)
				(mid 35.97021 -18.502376)
				(end 36.33597 -18.502376)
			)
		)
		(stroke
			(width 0)
			(type solid)
		)
		(fill yes)
		(layer "F.Cu")
		(net "GND")
	)
	(gr_poly
		(pts
			(arc
				(start 36.59124 -51.973988)
				(mid 36.22548 -51.973988)
				(end 36.59124 -51.973988)
			)
		)
		(stroke
			(width 0)
			(type solid)
		)
		(fill yes)
		(layer "F.Cu")
		(net "GND")
	)
	(gr_poly
		(pts
			(arc
				(start 36.84397 -19.13636)
				(mid 36.47821 -19.13636)
				(end 36.84397 -19.13636)
			)
		)
		(stroke
			(width 0)
			(type solid)
		)
		(fill yes)
		(layer "F.Cu")
		(net "GND")
	)
	(gr_poly
		(pts
			(arc
				(start 37.363146 -17.61236)
				(mid 36.997386 -17.61236)
				(end 37.363146 -17.61236)
			)
		)
		(stroke
			(width 0)
			(type solid)
		)
		(fill yes)
		(layer "F.Cu")
		(net "GND")
	)
	(gr_poly
		(pts
			(arc
				(start 37.749734 -47.968408)
				(mid 37.383974 -47.968408)
				(end 37.749734 -47.968408)
			)
		)
		(stroke
			(width 0)
			(type solid)
		)
		(fill yes)
		(layer "F.Cu")
		(net "GND")
	)
	(gr_poly
		(pts
			(arc
				(start 37.871146 -18.246344)
				(mid 37.505386 -18.246344)
				(end 37.871146 -18.246344)
			)
		)
		(stroke
			(width 0)
			(type solid)
		)
		(fill yes)
		(layer "F.Cu")
		(net "GND")
	)
	(gr_poly
		(pts
			(arc
				(start 37.871146 -16.978376)
				(mid 37.505386 -16.978376)
				(end 37.871146 -16.978376)
			)
		)
		(stroke
			(width 0)
			(type solid)
		)
		(fill yes)
		(layer "F.Cu")
		(net "GND")
	)
	(gr_poly
		(pts
			(arc
				(start 38.404038 -6.597396)
				(mid 38.038278 -6.597396)
				(end 38.404038 -6.597396)
			)
		)
		(stroke
			(width 0)
			(type solid)
		)
		(fill yes)
		(layer "F.Cu")
		(net "GND")
	)
	(gr_poly
		(pts
			(arc
				(start 38.912038 -6.090412)
				(mid 38.546278 -6.090412)
				(end 38.912038 -6.090412)
			)
		)
		(stroke
			(width 0)
			(type solid)
		)
		(fill yes)
		(layer "F.Cu")
		(net "GND")
	)
	(gr_poly
		(pts
			(arc
				(start 39.12997 -18.246344)
				(mid 38.76421 -18.246344)
				(end 39.12997 -18.246344)
			)
		)
		(stroke
			(width 0)
			(type solid)
		)
		(fill yes)
		(layer "F.Cu")
		(net "GND")
	)
	(gr_poly
		(pts
			(arc
				(start 39.12997 -16.978376)
				(mid 38.76421 -16.978376)
				(end 39.12997 -16.978376)
			)
		)
		(stroke
			(width 0)
			(type solid)
		)
		(fill yes)
		(layer "F.Cu")
		(net "GND")
	)
	(gr_poly
		(pts
			(arc
				(start 39.63797 -17.61236)
				(mid 39.27221 -17.61236)
				(end 39.63797 -17.61236)
			)
		)
		(stroke
			(width 0)
			(type solid)
		)
		(fill yes)
		(layer "F.Cu")
		(net "GND")
	)
	(gr_poly
		(pts
			(arc
				(start 40.170862 -6.090412)
				(mid 39.805102 -6.090412)
				(end 40.170862 -6.090412)
			)
		)
		(stroke
			(width 0)
			(type solid)
		)
		(fill yes)
		(layer "F.Cu")
		(net "GND")
	)
	(gr_poly
		(pts
			(arc
				(start 40.208708 -4.962652)
				(mid 39.842948 -4.962652)
				(end 40.208708 -4.962652)
			)
		)
		(stroke
			(width 0)
			(type solid)
		)
		(fill yes)
		(layer "F.Cu")
		(net "GND")
	)
	(gr_poly
		(pts
			(arc
				(start 40.462962 -19.13636)
				(mid 40.097202 -19.13636)
				(end 40.462962 -19.13636)
			)
		)
		(stroke
			(width 0)
			(type solid)
		)
		(fill yes)
		(layer "F.Cu")
		(net "GND")
	)
	(gr_poly
		(pts
			(arc
				(start 40.60063 -113.960656)
				(mid 40.23487 -113.960656)
				(end 40.60063 -113.960656)
			)
		)
		(stroke
			(width 0)
			(type solid)
		)
		(fill yes)
		(layer "F.Cu")
		(net "GND")
	)
	(gr_poly
		(pts
			(arc
				(start 40.678862 -6.597396)
				(mid 40.313102 -6.597396)
				(end 40.678862 -6.597396)
			)
		)
		(stroke
			(width 0)
			(type solid)
		)
		(fill yes)
		(layer "F.Cu")
		(net "GND")
	)
	(gr_poly
		(pts
			(arc
				(start 40.716708 -5.596636)
				(mid 40.350948 -5.596636)
				(end 40.716708 -5.596636)
			)
		)
		(stroke
			(width 0)
			(type solid)
		)
		(fill yes)
		(layer "F.Cu")
		(net "GND")
	)
	(gr_poly
		(pts
			(arc
				(start 40.716708 -4.328668)
				(mid 40.350948 -4.328668)
				(end 40.716708 -4.328668)
			)
		)
		(stroke
			(width 0)
			(type solid)
		)
		(fill yes)
		(layer "F.Cu")
		(net "GND")
	)
	(gr_poly
		(pts
			(arc
				(start 40.970962 -19.770344)
				(mid 40.605202 -19.770344)
				(end 40.970962 -19.770344)
			)
		)
		(stroke
			(width 0)
			(type solid)
		)
		(fill yes)
		(layer "F.Cu")
		(net "GND")
	)
	(gr_poly
		(pts
			(arc
				(start 40.970962 -18.502376)
				(mid 40.605202 -18.502376)
				(end 40.970962 -18.502376)
			)
		)
		(stroke
			(width 0)
			(type solid)
		)
		(fill yes)
		(layer "F.Cu")
		(net "GND")
	)
	(gr_poly
		(pts
			(arc
				(start 41.52138 -130.175508)
				(mid 41.15562 -130.175508)
				(end 41.52138 -130.175508)
			)
		)
		(stroke
			(width 0)
			(type solid)
		)
		(fill yes)
		(layer "F.Cu")
		(net "GND")
	)
	(gr_poly
		(pts
			(arc
				(start 41.975532 -5.596636)
				(mid 41.609772 -5.596636)
				(end 41.975532 -5.596636)
			)
		)
		(stroke
			(width 0)
			(type solid)
		)
		(fill yes)
		(layer "F.Cu")
		(net "GND")
	)
	(gr_poly
		(pts
			(arc
				(start 41.975532 -4.328668)
				(mid 41.609772 -4.328668)
				(end 41.975532 -4.328668)
			)
		)
		(stroke
			(width 0)
			(type solid)
		)
		(fill yes)
		(layer "F.Cu")
		(net "GND")
	)
	(gr_poly
		(pts
			(arc
				(start 42.00398 -6.597396)
				(mid 41.63822 -6.597396)
				(end 42.00398 -6.597396)
			)
		)
		(stroke
			(width 0)
			(type solid)
		)
		(fill yes)
		(layer "F.Cu")
		(net "GND")
	)
	(gr_poly
		(pts
			(arc
				(start 42.229786 -19.770344)
				(mid 41.864026 -19.770344)
				(end 42.229786 -19.770344)
			)
		)
		(stroke
			(width 0)
			(type solid)
		)
		(fill yes)
		(layer "F.Cu")
		(net "GND")
	)
	(gr_poly
		(pts
			(arc
				(start 42.229786 -18.502376)
				(mid 41.864026 -18.502376)
				(end 42.229786 -18.502376)
			)
		)
		(stroke
			(width 0)
			(type solid)
		)
		(fill yes)
		(layer "F.Cu")
		(net "GND")
	)
	(gr_poly
		(pts
			(arc
				(start 42.483532 -4.962652)
				(mid 42.117772 -4.962652)
				(end 42.483532 -4.962652)
			)
		)
		(stroke
			(width 0)
			(type solid)
		)
		(fill yes)
		(layer "F.Cu")
		(net "GND")
	)
	(gr_poly
		(pts
			(arc
				(start 42.51198 -6.090412)
				(mid 42.14622 -6.090412)
				(end 42.51198 -6.090412)
			)
		)
		(stroke
			(width 0)
			(type solid)
		)
		(fill yes)
		(layer "F.Cu")
		(net "GND")
	)
	(gr_poly
		(pts
			(arc
				(start 42.737786 -19.13636)
				(mid 42.372026 -19.13636)
				(end 42.737786 -19.13636)
			)
		)
		(stroke
			(width 0)
			(type solid)
		)
		(fill yes)
		(layer "F.Cu")
		(net "GND")
	)
	(gr_poly
		(pts
			(arc
				(start 43.256962 -17.61236)
				(mid 42.891202 -17.61236)
				(end 43.256962 -17.61236)
			)
		)
		(stroke
			(width 0)
			(type solid)
		)
		(fill yes)
		(layer "F.Cu")
		(net "GND")
	)
	(gr_poly
		(pts
			(arc
				(start 43.764962 -18.246344)
				(mid 43.399202 -18.246344)
				(end 43.764962 -18.246344)
			)
		)
		(stroke
			(width 0)
			(type solid)
		)
		(fill yes)
		(layer "F.Cu")
		(net "GND")
	)
	(gr_poly
		(pts
			(arc
				(start 43.764962 -16.978376)
				(mid 43.399202 -16.978376)
				(end 43.764962 -16.978376)
			)
		)
		(stroke
			(width 0)
			(type solid)
		)
		(fill yes)
		(layer "F.Cu")
		(net "GND")
	)
	(gr_poly
		(pts
			(arc
				(start 43.770804 -6.090412)
				(mid 43.405044 -6.090412)
				(end 43.770804 -6.090412)
			)
		)
		(stroke
			(width 0)
			(type solid)
		)
		(fill yes)
		(layer "F.Cu")
		(net "GND")
	)
	(gr_poly
		(pts
			(arc
				(start 43.80865 -4.962652)
				(mid 43.44289 -4.962652)
				(end 43.80865 -4.962652)
			)
		)
		(stroke
			(width 0)
			(type solid)
		)
		(fill yes)
		(layer "F.Cu")
		(net "GND")
	)
	(gr_poly
		(pts
			(arc
				(start 44.278804 -6.597396)
				(mid 43.913044 -6.597396)
				(end 44.278804 -6.597396)
			)
		)
		(stroke
			(width 0)
			(type solid)
		)
		(fill yes)
		(layer "F.Cu")
		(net "GND")
	)
	(gr_poly
		(pts
			(arc
				(start 44.31665 -5.596636)
				(mid 43.95089 -5.596636)
				(end 44.31665 -5.596636)
			)
		)
		(stroke
			(width 0)
			(type solid)
		)
		(fill yes)
		(layer "F.Cu")
		(net "GND")
	)
	(gr_poly
		(pts
			(arc
				(start 44.31665 -4.328668)
				(mid 43.95089 -4.328668)
				(end 44.31665 -4.328668)
			)
		)
		(stroke
			(width 0)
			(type solid)
		)
		(fill yes)
		(layer "F.Cu")
		(net "GND")
	)
	(gr_poly
		(pts
			(arc
				(start 44.79544 -115.259866)
				(mid 44.42968 -115.259866)
				(end 44.79544 -115.259866)
			)
		)
		(stroke
			(width 0)
			(type solid)
		)
		(fill yes)
		(layer "F.Cu")
		(net "GND")
	)
	(gr_poly
		(pts
			(arc
				(start 45.023786 -18.246344)
				(mid 44.658026 -18.246344)
				(end 45.023786 -18.246344)
			)
		)
		(stroke
			(width 0)
			(type solid)
		)
		(fill yes)
		(layer "F.Cu")
		(net "GND")
	)
	(gr_poly
		(pts
			(arc
				(start 45.023786 -16.978376)
				(mid 44.658026 -16.978376)
				(end 45.023786 -16.978376)
			)
		)
		(stroke
			(width 0)
			(type solid)
		)
		(fill yes)
		(layer "F.Cu")
		(net "GND")
	)
	(gr_poly
		(pts
			(arc
				(start 45.531786 -17.61236)
				(mid 45.166026 -17.61236)
				(end 45.531786 -17.61236)
			)
		)
		(stroke
			(width 0)
			(type solid)
		)
		(fill yes)
		(layer "F.Cu")
		(net "GND")
	)
	(gr_poly
		(pts
			(arc
				(start 45.575474 -5.596636)
				(mid 45.209714 -5.596636)
				(end 45.575474 -5.596636)
			)
		)
		(stroke
			(width 0)
			(type solid)
		)
		(fill yes)
		(layer "F.Cu")
		(net "GND")
	)
	(gr_poly
		(pts
			(arc
				(start 45.575474 -4.328668)
				(mid 45.209714 -4.328668)
				(end 45.575474 -4.328668)
			)
		)
		(stroke
			(width 0)
			(type solid)
		)
		(fill yes)
		(layer "F.Cu")
		(net "GND")
	)
	(gr_poly
		(pts
			(arc
				(start 46.050962 -19.13636)
				(mid 45.685202 -19.13636)
				(end 46.050962 -19.13636)
			)
		)
		(stroke
			(width 0)
			(type solid)
		)
		(fill yes)
		(layer "F.Cu")
		(net "GND")
	)
	(gr_poly
		(pts
			(arc
				(start 46.083474 -4.962652)
				(mid 45.717714 -4.962652)
				(end 46.083474 -4.962652)
			)
		)
		(stroke
			(width 0)
			(type solid)
		)
		(fill yes)
		(layer "F.Cu")
		(net "GND")
	)
	(gr_poly
		(pts
			(arc
				(start 46.558962 -19.770344)
				(mid 46.193202 -19.770344)
				(end 46.558962 -19.770344)
			)
		)
		(stroke
			(width 0)
			(type solid)
		)
		(fill yes)
		(layer "F.Cu")
		(net "GND")
	)
	(gr_poly
		(pts
			(arc
				(start 46.558962 -18.502376)
				(mid 46.193202 -18.502376)
				(end 46.558962 -18.502376)
			)
		)
		(stroke
			(width 0)
			(type solid)
		)
		(fill yes)
		(layer "F.Cu")
		(net "GND")
	)
	(gr_poly
		(pts
			(arc
				(start 46.956218 -113.557812)
				(mid 46.590458 -113.557812)
				(end 46.956218 -113.557812)
			)
		)
		(stroke
			(width 0)
			(type solid)
		)
		(fill yes)
		(layer "F.Cu")
		(net "GND")
	)
	(gr_poly
		(pts
			(arc
				(start 47.04334 -102.159562)
				(mid 46.67758 -102.159562)
				(end 47.04334 -102.159562)
			)
		)
		(stroke
			(width 0)
			(type solid)
		)
		(fill yes)
		(layer "F.Cu")
		(net "GND")
	)
	(gr_poly
		(pts
			(arc
				(start 47.817786 -19.770344)
				(mid 47.452026 -19.770344)
				(end 47.817786 -19.770344)
			)
		)
		(stroke
			(width 0)
			(type solid)
		)
		(fill yes)
		(layer "F.Cu")
		(net "GND")
	)
	(gr_poly
		(pts
			(arc
				(start 47.817786 -18.502376)
				(mid 47.452026 -18.502376)
				(end 47.817786 -18.502376)
			)
		)
		(stroke
			(width 0)
			(type solid)
		)
		(fill yes)
		(layer "F.Cu")
		(net "GND")
	)
	(gr_poly
		(pts
			(arc
				(start 47.965106 -404.51786)
				(mid 47.599346 -404.51786)
				(end 47.965106 -404.51786)
			)
		)
		(stroke
			(width 0)
			(type solid)
		)
		(fill yes)
		(layer "F.Cu")
		(net "GND")
	)
	(gr_poly
		(pts
			(arc
				(start 47.965106 -403.249892)
				(mid 47.599346 -403.249892)
				(end 47.965106 -403.249892)
			)
		)
		(stroke
			(width 0)
			(type solid)
		)
		(fill yes)
		(layer "F.Cu")
		(net "GND")
	)
	(gr_poly
		(pts
			(arc
				(start 47.965106 -401.492212)
				(mid 47.599346 -401.492212)
				(end 47.965106 -401.492212)
			)
		)
		(stroke
			(width 0)
			(type solid)
		)
		(fill yes)
		(layer "F.Cu")
		(net "GND")
	)
	(gr_poly
		(pts
			(arc
				(start 47.965106 -400.224244)
				(mid 47.599346 -400.224244)
				(end 47.965106 -400.224244)
			)
		)
		(stroke
			(width 0)
			(type solid)
		)
		(fill yes)
		(layer "F.Cu")
		(net "GND")
	)
	(gr_poly
		(pts
			(arc
				(start 47.991014 -115.328192)
				(mid 47.625254 -115.328192)
				(end 47.991014 -115.328192)
			)
		)
		(stroke
			(width 0)
			(type solid)
		)
		(fill yes)
		(layer "F.Cu")
		(net "GND")
	)
	(gr_poly
		(pts
			(arc
				(start 48.325786 -19.13636)
				(mid 47.960026 -19.13636)
				(end 48.325786 -19.13636)
			)
		)
		(stroke
			(width 0)
			(type solid)
		)
		(fill yes)
		(layer "F.Cu")
		(net "GND")
	)
	(gr_poly
		(pts
			(arc
				(start 48.77435 -109.274864)
				(mid 48.40859 -109.274864)
				(end 48.77435 -109.274864)
			)
		)
		(stroke
			(width 0)
			(type solid)
		)
		(fill yes)
		(layer "F.Cu")
		(net "GND")
	)
	(gr_poly
		(pts
			(arc
				(start 48.844962 -17.61236)
				(mid 48.479202 -17.61236)
				(end 48.844962 -17.61236)
			)
		)
		(stroke
			(width 0)
			(type solid)
		)
		(fill yes)
		(layer "F.Cu")
		(net "GND")
	)
	(gr_poly
		(pts
			(arc
				(start 49.22393 -404.51786)
				(mid 48.85817 -404.51786)
				(end 49.22393 -404.51786)
			)
		)
		(stroke
			(width 0)
			(type solid)
		)
		(fill yes)
		(layer "F.Cu")
		(net "GND")
	)
	(gr_poly
		(pts
			(arc
				(start 49.22393 -403.249892)
				(mid 48.85817 -403.249892)
				(end 49.22393 -403.249892)
			)
		)
		(stroke
			(width 0)
			(type solid)
		)
		(fill yes)
		(layer "F.Cu")
		(net "GND")
	)
	(gr_poly
		(pts
			(arc
				(start 49.22393 -401.492212)
				(mid 48.85817 -401.492212)
				(end 49.22393 -401.492212)
			)
		)
		(stroke
			(width 0)
			(type solid)
		)
		(fill yes)
		(layer "F.Cu")
		(net "GND")
	)
	(gr_poly
		(pts
			(arc
				(start 49.22393 -400.224244)
				(mid 48.85817 -400.224244)
				(end 49.22393 -400.224244)
			)
		)
		(stroke
			(width 0)
			(type solid)
		)
		(fill yes)
		(layer "F.Cu")
		(net "GND")
	)
	(gr_poly
		(pts
			(arc
				(start 49.311306 -410.664152)
				(mid 48.945546 -410.664152)
				(end 49.311306 -410.664152)
			)
		)
		(stroke
			(width 0)
			(type solid)
		)
		(fill yes)
		(layer "F.Cu")
		(net "GND")
	)
	(gr_poly
		(pts
			(arc
				(start 49.311306 -409.396184)
				(mid 48.945546 -409.396184)
				(end 49.311306 -409.396184)
			)
		)
		(stroke
			(width 0)
			(type solid)
		)
		(fill yes)
		(layer "F.Cu")
		(net "GND")
	)
	(gr_poly
		(pts
			(arc
				(start 49.311306 -407.638504)
				(mid 48.945546 -407.638504)
				(end 49.311306 -407.638504)
			)
		)
		(stroke
			(width 0)
			(type solid)
		)
		(fill yes)
		(layer "F.Cu")
		(net "GND")
	)
	(gr_poly
		(pts
			(arc
				(start 49.311306 -406.370536)
				(mid 48.945546 -406.370536)
				(end 49.311306 -406.370536)
			)
		)
		(stroke
			(width 0)
			(type solid)
		)
		(fill yes)
		(layer "F.Cu")
		(net "GND")
	)
	(gr_poly
		(pts
			(arc
				(start 49.352962 -18.246344)
				(mid 48.987202 -18.246344)
				(end 49.352962 -18.246344)
			)
		)
		(stroke
			(width 0)
			(type solid)
		)
		(fill yes)
		(layer "F.Cu")
		(net "GND")
	)
	(gr_poly
		(pts
			(arc
				(start 49.352962 -16.978376)
				(mid 48.987202 -16.978376)
				(end 49.352962 -16.978376)
			)
		)
		(stroke
			(width 0)
			(type solid)
		)
		(fill yes)
		(layer "F.Cu")
		(net "GND")
	)
	(gr_poly
		(pts
			(arc
				(start 49.614074 -6.597396)
				(mid 49.248314 -6.597396)
				(end 49.614074 -6.597396)
			)
		)
		(stroke
			(width 0)
			(type solid)
		)
		(fill yes)
		(layer "F.Cu")
		(net "GND")
	)
	(gr_poly
		(pts
			(arc
				(start 50.02149 -113.68151)
				(mid 49.65573 -113.68151)
				(end 50.02149 -113.68151)
			)
		)
		(stroke
			(width 0)
			(type solid)
		)
		(fill yes)
		(layer "F.Cu")
		(net "GND")
	)
	(gr_poly
		(pts
			(arc
				(start 50.122074 -6.090412)
				(mid 49.756314 -6.090412)
				(end 50.122074 -6.090412)
			)
		)
		(stroke
			(width 0)
			(type solid)
		)
		(fill yes)
		(layer "F.Cu")
		(net "GND")
	)
	(gr_poly
		(pts
			(arc
				(start 50.57013 -410.664152)
				(mid 50.20437 -410.664152)
				(end 50.57013 -410.664152)
			)
		)
		(stroke
			(width 0)
			(type solid)
		)
		(fill yes)
		(layer "F.Cu")
		(net "GND")
	)
	(gr_poly
		(pts
			(arc
				(start 50.57013 -409.396184)
				(mid 50.20437 -409.396184)
				(end 50.57013 -409.396184)
			)
		)
		(stroke
			(width 0)
			(type solid)
		)
		(fill yes)
		(layer "F.Cu")
		(net "GND")
	)
	(gr_poly
		(pts
			(arc
				(start 50.57013 -407.638504)
				(mid 50.20437 -407.638504)
				(end 50.57013 -407.638504)
			)
		)
		(stroke
			(width 0)
			(type solid)
		)
		(fill yes)
		(layer "F.Cu")
		(net "GND")
	)
	(gr_poly
		(pts
			(arc
				(start 50.57013 -406.370536)
				(mid 50.20437 -406.370536)
				(end 50.57013 -406.370536)
			)
		)
		(stroke
			(width 0)
			(type solid)
		)
		(fill yes)
		(layer "F.Cu")
		(net "GND")
	)
	(gr_poly
		(pts
			(arc
				(start 50.611786 -18.246344)
				(mid 50.246026 -18.246344)
				(end 50.611786 -18.246344)
			)
		)
		(stroke
			(width 0)
			(type solid)
		)
		(fill yes)
		(layer "F.Cu")
		(net "GND")
	)
	(gr_poly
		(pts
			(arc
				(start 50.611786 -16.978376)
				(mid 50.246026 -16.978376)
				(end 50.611786 -16.978376)
			)
		)
		(stroke
			(width 0)
			(type solid)
		)
		(fill yes)
		(layer "F.Cu")
		(net "GND")
	)
	(gr_poly
		(pts
			(arc
				(start 50.740818 -108.871004)
				(mid 50.375058 -108.871004)
				(end 50.740818 -108.871004)
			)
		)
		(stroke
			(width 0)
			(type solid)
		)
		(fill yes)
		(layer "F.Cu")
		(net "GND")
	)
	(gr_poly
		(pts
			(arc
				(start 50.764186 -107.412028)
				(mid 50.398426 -107.412028)
				(end 50.764186 -107.412028)
			)
		)
		(stroke
			(width 0)
			(type solid)
		)
		(fill yes)
		(layer "F.Cu")
		(net "GND")
	)
	(gr_poly
		(pts
			(arc
				(start 51.028346 -404.51786)
				(mid 50.662586 -404.51786)
				(end 51.028346 -404.51786)
			)
		)
		(stroke
			(width 0)
			(type solid)
		)
		(fill yes)
		(layer "F.Cu")
		(net "GND")
	)
	(gr_poly
		(pts
			(arc
				(start 51.028346 -403.249892)
				(mid 50.662586 -403.249892)
				(end 51.028346 -403.249892)
			)
		)
		(stroke
			(width 0)
			(type solid)
		)
		(fill yes)
		(layer "F.Cu")
		(net "GND")
	)
	(gr_poly
		(pts
			(arc
				(start 51.028346 -401.492212)
				(mid 50.662586 -401.492212)
				(end 51.028346 -401.492212)
			)
		)
		(stroke
			(width 0)
			(type solid)
		)
		(fill yes)
		(layer "F.Cu")
		(net "GND")
	)
	(gr_poly
		(pts
			(arc
				(start 51.028346 -400.224244)
				(mid 50.662586 -400.224244)
				(end 51.028346 -400.224244)
			)
		)
		(stroke
			(width 0)
			(type solid)
		)
		(fill yes)
		(layer "F.Cu")
		(net "GND")
	)
	(gr_poly
		(pts
			(arc
				(start 51.119786 -17.61236)
				(mid 50.754026 -17.61236)
				(end 51.119786 -17.61236)
			)
		)
		(stroke
			(width 0)
			(type solid)
		)
		(fill yes)
		(layer "F.Cu")
		(net "GND")
	)
	(gr_poly
		(pts
			(arc
				(start 51.380898 -6.090412)
				(mid 51.015138 -6.090412)
				(end 51.380898 -6.090412)
			)
		)
		(stroke
			(width 0)
			(type solid)
		)
		(fill yes)
		(layer "F.Cu")
		(net "GND")
	)
	(gr_poly
		(pts
			(arc
				(start 51.418744 -4.962652)
				(mid 51.052984 -4.962652)
				(end 51.418744 -4.962652)
			)
		)
		(stroke
			(width 0)
			(type solid)
		)
		(fill yes)
		(layer "F.Cu")
		(net "GND")
	)
	(gr_poly
		(pts
			(arc
				(start 51.672998 -19.13636)
				(mid 51.307238 -19.13636)
				(end 51.672998 -19.13636)
			)
		)
		(stroke
			(width 0)
			(type solid)
		)
		(fill yes)
		(layer "F.Cu")
		(net "GND")
	)
	(gr_poly
		(pts
			(arc
				(start 51.888898 -6.597396)
				(mid 51.523138 -6.597396)
				(end 51.888898 -6.597396)
			)
		)
		(stroke
			(width 0)
			(type solid)
		)
		(fill yes)
		(layer "F.Cu")
		(net "GND")
	)
	(gr_poly
		(pts
			(arc
				(start 51.926744 -5.596636)
				(mid 51.560984 -5.596636)
				(end 51.926744 -5.596636)
			)
		)
		(stroke
			(width 0)
			(type solid)
		)
		(fill yes)
		(layer "F.Cu")
		(net "GND")
	)
	(gr_poly
		(pts
			(arc
				(start 51.926744 -4.328668)
				(mid 51.560984 -4.328668)
				(end 51.926744 -4.328668)
			)
		)
		(stroke
			(width 0)
			(type solid)
		)
		(fill yes)
		(layer "F.Cu")
		(net "GND")
	)
	(gr_poly
		(pts
			(arc
				(start 52.180998 -19.770344)
				(mid 51.815238 -19.770344)
				(end 52.180998 -19.770344)
			)
		)
		(stroke
			(width 0)
			(type solid)
		)
		(fill yes)
		(layer "F.Cu")
		(net "GND")
	)
	(gr_poly
		(pts
			(arc
				(start 52.180998 -18.502376)
				(mid 51.815238 -18.502376)
				(end 52.180998 -18.502376)
			)
		)
		(stroke
			(width 0)
			(type solid)
		)
		(fill yes)
		(layer "F.Cu")
		(net "GND")
	)
	(gr_poly
		(pts
			(arc
				(start 52.28717 -404.51786)
				(mid 51.92141 -404.51786)
				(end 52.28717 -404.51786)
			)
		)
		(stroke
			(width 0)
			(type solid)
		)
		(fill yes)
		(layer "F.Cu")
		(net "GND")
	)
	(gr_poly
		(pts
			(arc
				(start 52.28717 -403.249892)
				(mid 51.92141 -403.249892)
				(end 52.28717 -403.249892)
			)
		)
		(stroke
			(width 0)
			(type solid)
		)
		(fill yes)
		(layer "F.Cu")
		(net "GND")
	)
	(gr_poly
		(pts
			(arc
				(start 52.28717 -401.492212)
				(mid 51.92141 -401.492212)
				(end 52.28717 -401.492212)
			)
		)
		(stroke
			(width 0)
			(type solid)
		)
		(fill yes)
		(layer "F.Cu")
		(net "GND")
	)
	(gr_poly
		(pts
			(arc
				(start 52.28717 -400.224244)
				(mid 51.92141 -400.224244)
				(end 52.28717 -400.224244)
			)
		)
		(stroke
			(width 0)
			(type solid)
		)
		(fill yes)
		(layer "F.Cu")
		(net "GND")
	)
	(gr_poly
		(pts
			(arc
				(start 52.374546 -410.664152)
				(mid 52.008786 -410.664152)
				(end 52.374546 -410.664152)
			)
		)
		(stroke
			(width 0)
			(type solid)
		)
		(fill yes)
		(layer "F.Cu")
		(net "GND")
	)
	(gr_poly
		(pts
			(arc
				(start 52.374546 -409.396184)
				(mid 52.008786 -409.396184)
				(end 52.374546 -409.396184)
			)
		)
		(stroke
			(width 0)
			(type solid)
		)
		(fill yes)
		(layer "F.Cu")
		(net "GND")
	)
	(gr_poly
		(pts
			(arc
				(start 52.374546 -407.638504)
				(mid 52.008786 -407.638504)
				(end 52.374546 -407.638504)
			)
		)
		(stroke
			(width 0)
			(type solid)
		)
		(fill yes)
		(layer "F.Cu")
		(net "GND")
	)
	(gr_poly
		(pts
			(arc
				(start 52.374546 -406.370536)
				(mid 52.008786 -406.370536)
				(end 52.374546 -406.370536)
			)
		)
		(stroke
			(width 0)
			(type solid)
		)
		(fill yes)
		(layer "F.Cu")
		(net "GND")
	)
	(gr_poly
		(pts
			(arc
				(start 53.185568 -5.596636)
				(mid 52.819808 -5.596636)
				(end 53.185568 -5.596636)
			)
		)
		(stroke
			(width 0)
			(type solid)
		)
		(fill yes)
		(layer "F.Cu")
		(net "GND")
	)
	(gr_poly
		(pts
			(arc
				(start 53.185568 -4.328668)
				(mid 52.819808 -4.328668)
				(end 53.185568 -4.328668)
			)
		)
		(stroke
			(width 0)
			(type solid)
		)
		(fill yes)
		(layer "F.Cu")
		(net "GND")
	)
	(gr_poly
		(pts
			(arc
				(start 53.214016 -6.597396)
				(mid 52.848256 -6.597396)
				(end 53.214016 -6.597396)
			)
		)
		(stroke
			(width 0)
			(type solid)
		)
		(fill yes)
		(layer "F.Cu")
		(net "GND")
	)
	(gr_poly
		(pts
			(arc
				(start 53.439822 -19.770344)
				(mid 53.074062 -19.770344)
				(end 53.439822 -19.770344)
			)
		)
		(stroke
			(width 0)
			(type solid)
		)
		(fill yes)
		(layer "F.Cu")
		(net "GND")
	)
	(gr_poly
		(pts
			(arc
				(start 53.439822 -18.502376)
				(mid 53.074062 -18.502376)
				(end 53.439822 -18.502376)
			)
		)
		(stroke
			(width 0)
			(type solid)
		)
		(fill yes)
		(layer "F.Cu")
		(net "GND")
	)
	(gr_poly
		(pts
			(arc
				(start 53.63337 -410.664152)
				(mid 53.26761 -410.664152)
				(end 53.63337 -410.664152)
			)
		)
		(stroke
			(width 0)
			(type solid)
		)
		(fill yes)
		(layer "F.Cu")
		(net "GND")
	)
	(gr_poly
		(pts
			(arc
				(start 53.63337 -409.396184)
				(mid 53.26761 -409.396184)
				(end 53.63337 -409.396184)
			)
		)
		(stroke
			(width 0)
			(type solid)
		)
		(fill yes)
		(layer "F.Cu")
		(net "GND")
	)
	(gr_poly
		(pts
			(arc
				(start 53.63337 -407.638504)
				(mid 53.26761 -407.638504)
				(end 53.63337 -407.638504)
			)
		)
		(stroke
			(width 0)
			(type solid)
		)
		(fill yes)
		(layer "F.Cu")
		(net "GND")
	)
	(gr_poly
		(pts
			(arc
				(start 53.63337 -406.370536)
				(mid 53.26761 -406.370536)
				(end 53.63337 -406.370536)
			)
		)
		(stroke
			(width 0)
			(type solid)
		)
		(fill yes)
		(layer "F.Cu")
		(net "GND")
	)
	(gr_poly
		(pts
			(arc
				(start 53.693568 -4.962652)
				(mid 53.327808 -4.962652)
				(end 53.693568 -4.962652)
			)
		)
		(stroke
			(width 0)
			(type solid)
		)
		(fill yes)
		(layer "F.Cu")
		(net "GND")
	)
	(gr_poly
		(pts
			(arc
				(start 53.722016 -6.090412)
				(mid 53.356256 -6.090412)
				(end 53.722016 -6.090412)
			)
		)
		(stroke
			(width 0)
			(type solid)
		)
		(fill yes)
		(layer "F.Cu")
		(net "GND")
	)
	(gr_poly
		(pts
			(arc
				(start 53.947822 -19.13636)
				(mid 53.582062 -19.13636)
				(end 53.947822 -19.13636)
			)
		)
		(stroke
			(width 0)
			(type solid)
		)
		(fill yes)
		(layer "F.Cu")
		(net "GND")
	)
	(gr_poly
		(pts
			(arc
				(start 54.091586 -404.51786)
				(mid 53.725826 -404.51786)
				(end 54.091586 -404.51786)
			)
		)
		(stroke
			(width 0)
			(type solid)
		)
		(fill yes)
		(layer "F.Cu")
		(net "GND")
	)
	(gr_poly
		(pts
			(arc
				(start 54.091586 -403.249892)
				(mid 53.725826 -403.249892)
				(end 54.091586 -403.249892)
			)
		)
		(stroke
			(width 0)
			(type solid)
		)
		(fill yes)
		(layer "F.Cu")
		(net "GND")
	)
	(gr_poly
		(pts
			(arc
				(start 54.091586 -401.492212)
				(mid 53.725826 -401.492212)
				(end 54.091586 -401.492212)
			)
		)
		(stroke
			(width 0)
			(type solid)
		)
		(fill yes)
		(layer "F.Cu")
		(net "GND")
	)
	(gr_poly
		(pts
			(arc
				(start 54.091586 -400.224244)
				(mid 53.725826 -400.224244)
				(end 54.091586 -400.224244)
			)
		)
		(stroke
			(width 0)
			(type solid)
		)
		(fill yes)
		(layer "F.Cu")
		(net "GND")
	)
	(gr_poly
		(pts
			(arc
				(start 54.466998 -17.61236)
				(mid 54.101238 -17.61236)
				(end 54.466998 -17.61236)
			)
		)
		(stroke
			(width 0)
			(type solid)
		)
		(fill yes)
		(layer "F.Cu")
		(net "GND")
	)
	(gr_poly
		(pts
			(arc
				(start 54.974998 -18.246344)
				(mid 54.609238 -18.246344)
				(end 54.974998 -18.246344)
			)
		)
		(stroke
			(width 0)
			(type solid)
		)
		(fill yes)
		(layer "F.Cu")
		(net "GND")
	)
	(gr_poly
		(pts
			(arc
				(start 54.974998 -16.978376)
				(mid 54.609238 -16.978376)
				(end 54.974998 -16.978376)
			)
		)
		(stroke
			(width 0)
			(type solid)
		)
		(fill yes)
		(layer "F.Cu")
		(net "GND")
	)
	(gr_poly
		(pts
			(arc
				(start 54.98084 -6.090412)
				(mid 54.61508 -6.090412)
				(end 54.98084 -6.090412)
			)
		)
		(stroke
			(width 0)
			(type solid)
		)
		(fill yes)
		(layer "F.Cu")
		(net "GND")
	)
	(gr_poly
		(pts
			(arc
				(start 55.018686 -4.962652)
				(mid 54.652926 -4.962652)
				(end 55.018686 -4.962652)
			)
		)
		(stroke
			(width 0)
			(type solid)
		)
		(fill yes)
		(layer "F.Cu")
		(net "GND")
	)
	(gr_poly
		(pts
			(arc
				(start 55.35041 -404.51786)
				(mid 54.98465 -404.51786)
				(end 55.35041 -404.51786)
			)
		)
		(stroke
			(width 0)
			(type solid)
		)
		(fill yes)
		(layer "F.Cu")
		(net "GND")
	)
	(gr_poly
		(pts
			(arc
				(start 55.35041 -403.249892)
				(mid 54.98465 -403.249892)
				(end 55.35041 -403.249892)
			)
		)
		(stroke
			(width 0)
			(type solid)
		)
		(fill yes)
		(layer "F.Cu")
		(net "GND")
	)
	(gr_poly
		(pts
			(arc
				(start 55.35041 -401.492212)
				(mid 54.98465 -401.492212)
				(end 55.35041 -401.492212)
			)
		)
		(stroke
			(width 0)
			(type solid)
		)
		(fill yes)
		(layer "F.Cu")
		(net "GND")
	)
	(gr_poly
		(pts
			(arc
				(start 55.35041 -400.224244)
				(mid 54.98465 -400.224244)
				(end 55.35041 -400.224244)
			)
		)
		(stroke
			(width 0)
			(type solid)
		)
		(fill yes)
		(layer "F.Cu")
		(net "GND")
	)
	(gr_poly
		(pts
			(arc
				(start 55.437786 -410.664152)
				(mid 55.072026 -410.664152)
				(end 55.437786 -410.664152)
			)
		)
		(stroke
			(width 0)
			(type solid)
		)
		(fill yes)
		(layer "F.Cu")
		(net "GND")
	)
	(gr_poly
		(pts
			(arc
				(start 55.437786 -409.396184)
				(mid 55.072026 -409.396184)
				(end 55.437786 -409.396184)
			)
		)
		(stroke
			(width 0)
			(type solid)
		)
		(fill yes)
		(layer "F.Cu")
		(net "GND")
	)
	(gr_poly
		(pts
			(arc
				(start 55.437786 -407.638504)
				(mid 55.072026 -407.638504)
				(end 55.437786 -407.638504)
			)
		)
		(stroke
			(width 0)
			(type solid)
		)
		(fill yes)
		(layer "F.Cu")
		(net "GND")
	)
	(gr_poly
		(pts
			(arc
				(start 55.437786 -406.370536)
				(mid 55.072026 -406.370536)
				(end 55.437786 -406.370536)
			)
		)
		(stroke
			(width 0)
			(type solid)
		)
		(fill yes)
		(layer "F.Cu")
		(net "GND")
	)
	(gr_poly
		(pts
			(arc
				(start 55.48884 -6.597396)
				(mid 55.12308 -6.597396)
				(end 55.48884 -6.597396)
			)
		)
		(stroke
			(width 0)
			(type solid)
		)
		(fill yes)
		(layer "F.Cu")
		(net "GND")
	)
	(gr_poly
		(pts
			(arc
				(start 55.526686 -5.596636)
				(mid 55.160926 -5.596636)
				(end 55.526686 -5.596636)
			)
		)
		(stroke
			(width 0)
			(type solid)
		)
		(fill yes)
		(layer "F.Cu")
		(net "GND")
	)
	(gr_poly
		(pts
			(arc
				(start 55.526686 -4.328668)
				(mid 55.160926 -4.328668)
				(end 55.526686 -4.328668)
			)
		)
		(stroke
			(width 0)
			(type solid)
		)
		(fill yes)
		(layer "F.Cu")
		(net "GND")
	)
	(gr_poly
		(pts
			(arc
				(start 56.233822 -18.246344)
				(mid 55.868062 -18.246344)
				(end 56.233822 -18.246344)
			)
		)
		(stroke
			(width 0)
			(type solid)
		)
		(fill yes)
		(layer "F.Cu")
		(net "GND")
	)
	(gr_poly
		(pts
			(arc
				(start 56.233822 -16.978376)
				(mid 55.868062 -16.978376)
				(end 56.233822 -16.978376)
			)
		)
		(stroke
			(width 0)
			(type solid)
		)
		(fill yes)
		(layer "F.Cu")
		(net "GND")
	)
	(gr_poly
		(pts
			(arc
				(start 56.277002 -109.221016)
				(mid 55.911242 -109.221016)
				(end 56.277002 -109.221016)
			)
		)
		(stroke
			(width 0)
			(type solid)
		)
		(fill yes)
		(layer "F.Cu")
		(net "GND")
	)
	(gr_poly
		(pts
			(arc
				(start 56.284876 -112.288066)
				(mid 55.919116 -112.288066)
				(end 56.284876 -112.288066)
			)
		)
		(stroke
			(width 0)
			(type solid)
		)
		(fill yes)
		(layer "F.Cu")
		(net "GND")
	)
	(gr_poly
		(pts
			(arc
				(start 56.69661 -410.664152)
				(mid 56.33085 -410.664152)
				(end 56.69661 -410.664152)
			)
		)
		(stroke
			(width 0)
			(type solid)
		)
		(fill yes)
		(layer "F.Cu")
		(net "GND")
	)
	(gr_poly
		(pts
			(arc
				(start 56.69661 -409.396184)
				(mid 56.33085 -409.396184)
				(end 56.69661 -409.396184)
			)
		)
		(stroke
			(width 0)
			(type solid)
		)
		(fill yes)
		(layer "F.Cu")
		(net "GND")
	)
	(gr_poly
		(pts
			(arc
				(start 56.69661 -407.638504)
				(mid 56.33085 -407.638504)
				(end 56.69661 -407.638504)
			)
		)
		(stroke
			(width 0)
			(type solid)
		)
		(fill yes)
		(layer "F.Cu")
		(net "GND")
	)
	(gr_poly
		(pts
			(arc
				(start 56.69661 -406.370536)
				(mid 56.33085 -406.370536)
				(end 56.69661 -406.370536)
			)
		)
		(stroke
			(width 0)
			(type solid)
		)
		(fill yes)
		(layer "F.Cu")
		(net "GND")
	)
	(gr_poly
		(pts
			(arc
				(start 56.741822 -17.61236)
				(mid 56.376062 -17.61236)
				(end 56.741822 -17.61236)
			)
		)
		(stroke
			(width 0)
			(type solid)
		)
		(fill yes)
		(layer "F.Cu")
		(net "GND")
	)
	(gr_poly
		(pts
			(arc
				(start 56.78551 -5.596636)
				(mid 56.41975 -5.596636)
				(end 56.78551 -5.596636)
			)
		)
		(stroke
			(width 0)
			(type solid)
		)
		(fill yes)
		(layer "F.Cu")
		(net "GND")
	)
	(gr_poly
		(pts
			(arc
				(start 56.78551 -4.328668)
				(mid 56.41975 -4.328668)
				(end 56.78551 -4.328668)
			)
		)
		(stroke
			(width 0)
			(type solid)
		)
		(fill yes)
		(layer "F.Cu")
		(net "GND")
	)
	(gr_poly
		(pts
			(arc
				(start 56.9087 -108.322618)
				(mid 56.54294 -108.322618)
				(end 56.9087 -108.322618)
			)
		)
		(stroke
			(width 0)
			(type solid)
		)
		(fill yes)
		(layer "F.Cu")
		(net "GND")
	)
	(gr_poly
		(pts
			(arc
				(start 57.154826 -404.51786)
				(mid 56.789066 -404.51786)
				(end 57.154826 -404.51786)
			)
		)
		(stroke
			(width 0)
			(type solid)
		)
		(fill yes)
		(layer "F.Cu")
		(net "GND")
	)
	(gr_poly
		(pts
			(arc
				(start 57.154826 -403.249892)
				(mid 56.789066 -403.249892)
				(end 57.154826 -403.249892)
			)
		)
		(stroke
			(width 0)
			(type solid)
		)
		(fill yes)
		(layer "F.Cu")
		(net "GND")
	)
	(gr_poly
		(pts
			(arc
				(start 57.154826 -401.492212)
				(mid 56.789066 -401.492212)
				(end 57.154826 -401.492212)
			)
		)
		(stroke
			(width 0)
			(type solid)
		)
		(fill yes)
		(layer "F.Cu")
		(net "GND")
	)
	(gr_poly
		(pts
			(arc
				(start 57.154826 -400.224244)
				(mid 56.789066 -400.224244)
				(end 57.154826 -400.224244)
			)
		)
		(stroke
			(width 0)
			(type solid)
		)
		(fill yes)
		(layer "F.Cu")
		(net "GND")
	)
	(gr_poly
		(pts
			(arc
				(start 57.260998 -19.13636)
				(mid 56.895238 -19.13636)
				(end 57.260998 -19.13636)
			)
		)
		(stroke
			(width 0)
			(type solid)
		)
		(fill yes)
		(layer "F.Cu")
		(net "GND")
	)
	(gr_poly
		(pts
			(arc
				(start 57.29351 -4.962652)
				(mid 56.92775 -4.962652)
				(end 57.29351 -4.962652)
			)
		)
		(stroke
			(width 0)
			(type solid)
		)
		(fill yes)
		(layer "F.Cu")
		(net "GND")
	)
	(gr_poly
		(pts
			(arc
				(start 57.768998 -19.770344)
				(mid 57.403238 -19.770344)
				(end 57.768998 -19.770344)
			)
		)
		(stroke
			(width 0)
			(type solid)
		)
		(fill yes)
		(layer "F.Cu")
		(net "GND")
	)
	(gr_poly
		(pts
			(arc
				(start 57.768998 -18.502376)
				(mid 57.403238 -18.502376)
				(end 57.768998 -18.502376)
			)
		)
		(stroke
			(width 0)
			(type solid)
		)
		(fill yes)
		(layer "F.Cu")
		(net "GND")
	)
	(gr_poly
		(pts
			(arc
				(start 58.41365 -404.51786)
				(mid 58.04789 -404.51786)
				(end 58.41365 -404.51786)
			)
		)
		(stroke
			(width 0)
			(type solid)
		)
		(fill yes)
		(layer "F.Cu")
		(net "GND")
	)
	(gr_poly
		(pts
			(arc
				(start 58.41365 -403.249892)
				(mid 58.04789 -403.249892)
				(end 58.41365 -403.249892)
			)
		)
		(stroke
			(width 0)
			(type solid)
		)
		(fill yes)
		(layer "F.Cu")
		(net "GND")
	)
	(gr_poly
		(pts
			(arc
				(start 58.41365 -401.492212)
				(mid 58.04789 -401.492212)
				(end 58.41365 -401.492212)
			)
		)
		(stroke
			(width 0)
			(type solid)
		)
		(fill yes)
		(layer "F.Cu")
		(net "GND")
	)
	(gr_poly
		(pts
			(arc
				(start 58.41365 -400.224244)
				(mid 58.04789 -400.224244)
				(end 58.41365 -400.224244)
			)
		)
		(stroke
			(width 0)
			(type solid)
		)
		(fill yes)
		(layer "F.Cu")
		(net "GND")
	)
	(gr_poly
		(pts
			(arc
				(start 58.501026 -410.664152)
				(mid 58.135266 -410.664152)
				(end 58.501026 -410.664152)
			)
		)
		(stroke
			(width 0)
			(type solid)
		)
		(fill yes)
		(layer "F.Cu")
		(net "GND")
	)
	(gr_poly
		(pts
			(arc
				(start 58.501026 -409.396184)
				(mid 58.135266 -409.396184)
				(end 58.501026 -409.396184)
			)
		)
		(stroke
			(width 0)
			(type solid)
		)
		(fill yes)
		(layer "F.Cu")
		(net "GND")
	)
	(gr_poly
		(pts
			(arc
				(start 58.501026 -407.638504)
				(mid 58.135266 -407.638504)
				(end 58.501026 -407.638504)
			)
		)
		(stroke
			(width 0)
			(type solid)
		)
		(fill yes)
		(layer "F.Cu")
		(net "GND")
	)
	(gr_poly
		(pts
			(arc
				(start 58.501026 -406.370536)
				(mid 58.135266 -406.370536)
				(end 58.501026 -406.370536)
			)
		)
		(stroke
			(width 0)
			(type solid)
		)
		(fill yes)
		(layer "F.Cu")
		(net "GND")
	)
	(gr_poly
		(pts
			(arc
				(start 59.027822 -19.770344)
				(mid 58.662062 -19.770344)
				(end 59.027822 -19.770344)
			)
		)
		(stroke
			(width 0)
			(type solid)
		)
		(fill yes)
		(layer "F.Cu")
		(net "GND")
	)
	(gr_poly
		(pts
			(arc
				(start 59.027822 -18.502376)
				(mid 58.662062 -18.502376)
				(end 59.027822 -18.502376)
			)
		)
		(stroke
			(width 0)
			(type solid)
		)
		(fill yes)
		(layer "F.Cu")
		(net "GND")
	)
	(gr_poly
		(pts
			(arc
				(start 59.535822 -19.13636)
				(mid 59.170062 -19.13636)
				(end 59.535822 -19.13636)
			)
		)
		(stroke
			(width 0)
			(type solid)
		)
		(fill yes)
		(layer "F.Cu")
		(net "GND")
	)
	(gr_poly
		(pts
			(arc
				(start 59.75985 -410.664152)
				(mid 59.39409 -410.664152)
				(end 59.75985 -410.664152)
			)
		)
		(stroke
			(width 0)
			(type solid)
		)
		(fill yes)
		(layer "F.Cu")
		(net "GND")
	)
	(gr_poly
		(pts
			(arc
				(start 59.75985 -409.396184)
				(mid 59.39409 -409.396184)
				(end 59.75985 -409.396184)
			)
		)
		(stroke
			(width 0)
			(type solid)
		)
		(fill yes)
		(layer "F.Cu")
		(net "GND")
	)
	(gr_poly
		(pts
			(arc
				(start 59.75985 -407.638504)
				(mid 59.39409 -407.638504)
				(end 59.75985 -407.638504)
			)
		)
		(stroke
			(width 0)
			(type solid)
		)
		(fill yes)
		(layer "F.Cu")
		(net "GND")
	)
	(gr_poly
		(pts
			(arc
				(start 59.75985 -406.370536)
				(mid 59.39409 -406.370536)
				(end 59.75985 -406.370536)
			)
		)
		(stroke
			(width 0)
			(type solid)
		)
		(fill yes)
		(layer "F.Cu")
		(net "GND")
	)
	(gr_poly
		(pts
			(arc
				(start 60.218066 -404.51786)
				(mid 59.852306 -404.51786)
				(end 60.218066 -404.51786)
			)
		)
		(stroke
			(width 0)
			(type solid)
		)
		(fill yes)
		(layer "F.Cu")
		(net "GND")
	)
	(gr_poly
		(pts
			(arc
				(start 60.218066 -403.249892)
				(mid 59.852306 -403.249892)
				(end 60.218066 -403.249892)
			)
		)
		(stroke
			(width 0)
			(type solid)
		)
		(fill yes)
		(layer "F.Cu")
		(net "GND")
	)
	(gr_poly
		(pts
			(arc
				(start 60.218066 -401.492212)
				(mid 59.852306 -401.492212)
				(end 60.218066 -401.492212)
			)
		)
		(stroke
			(width 0)
			(type solid)
		)
		(fill yes)
		(layer "F.Cu")
		(net "GND")
	)
	(gr_poly
		(pts
			(arc
				(start 60.218066 -400.224244)
				(mid 59.852306 -400.224244)
				(end 60.218066 -400.224244)
			)
		)
		(stroke
			(width 0)
			(type solid)
		)
		(fill yes)
		(layer "F.Cu")
		(net "GND")
	)
	(gr_poly
		(pts
			(arc
				(start 60.517786 -44.263564)
				(mid 60.152026 -44.263564)
				(end 60.517786 -44.263564)
			)
		)
		(stroke
			(width 0)
			(type solid)
		)
		(fill yes)
		(layer "F.Cu")
		(net "GND")
	)
	(gr_poly
		(pts
			(arc
				(start 61.47689 -404.51786)
				(mid 61.11113 -404.51786)
				(end 61.47689 -404.51786)
			)
		)
		(stroke
			(width 0)
			(type solid)
		)
		(fill yes)
		(layer "F.Cu")
		(net "GND")
	)
	(gr_poly
		(pts
			(arc
				(start 61.47689 -403.249892)
				(mid 61.11113 -403.249892)
				(end 61.47689 -403.249892)
			)
		)
		(stroke
			(width 0)
			(type solid)
		)
		(fill yes)
		(layer "F.Cu")
		(net "GND")
	)
	(gr_poly
		(pts
			(arc
				(start 61.47689 -401.492212)
				(mid 61.11113 -401.492212)
				(end 61.47689 -401.492212)
			)
		)
		(stroke
			(width 0)
			(type solid)
		)
		(fill yes)
		(layer "F.Cu")
		(net "GND")
	)
	(gr_poly
		(pts
			(arc
				(start 61.47689 -400.224244)
				(mid 61.11113 -400.224244)
				(end 61.47689 -400.224244)
			)
		)
		(stroke
			(width 0)
			(type solid)
		)
		(fill yes)
		(layer "F.Cu")
		(net "GND")
	)
	(gr_poly
		(pts
			(arc
				(start 61.564266 -410.664152)
				(mid 61.198506 -410.664152)
				(end 61.564266 -410.664152)
			)
		)
		(stroke
			(width 0)
			(type solid)
		)
		(fill yes)
		(layer "F.Cu")
		(net "GND")
	)
	(gr_poly
		(pts
			(arc
				(start 61.564266 -409.396184)
				(mid 61.198506 -409.396184)
				(end 61.564266 -409.396184)
			)
		)
		(stroke
			(width 0)
			(type solid)
		)
		(fill yes)
		(layer "F.Cu")
		(net "GND")
	)
	(gr_poly
		(pts
			(arc
				(start 61.564266 -407.638504)
				(mid 61.198506 -407.638504)
				(end 61.564266 -407.638504)
			)
		)
		(stroke
			(width 0)
			(type solid)
		)
		(fill yes)
		(layer "F.Cu")
		(net "GND")
	)
	(gr_poly
		(pts
			(arc
				(start 61.564266 -406.370536)
				(mid 61.198506 -406.370536)
				(end 61.564266 -406.370536)
			)
		)
		(stroke
			(width 0)
			(type solid)
		)
		(fill yes)
		(layer "F.Cu")
		(net "GND")
	)
	(gr_poly
		(pts
			(arc
				(start 62.02934 -5.842508)
				(mid 61.66358 -5.842508)
				(end 62.02934 -5.842508)
			)
		)
		(stroke
			(width 0)
			(type solid)
		)
		(fill yes)
		(layer "F.Cu")
		(net "GND")
	)
	(gr_poly
		(pts
			(arc
				(start 62.82309 -410.664152)
				(mid 62.45733 -410.664152)
				(end 62.82309 -410.664152)
			)
		)
		(stroke
			(width 0)
			(type solid)
		)
		(fill yes)
		(layer "F.Cu")
		(net "GND")
	)
	(gr_poly
		(pts
			(arc
				(start 62.82309 -409.396184)
				(mid 62.45733 -409.396184)
				(end 62.82309 -409.396184)
			)
		)
		(stroke
			(width 0)
			(type solid)
		)
		(fill yes)
		(layer "F.Cu")
		(net "GND")
	)
	(gr_poly
		(pts
			(arc
				(start 62.82309 -407.638504)
				(mid 62.45733 -407.638504)
				(end 62.82309 -407.638504)
			)
		)
		(stroke
			(width 0)
			(type solid)
		)
		(fill yes)
		(layer "F.Cu")
		(net "GND")
	)
	(gr_poly
		(pts
			(arc
				(start 62.82309 -406.370536)
				(mid 62.45733 -406.370536)
				(end 62.82309 -406.370536)
			)
		)
		(stroke
			(width 0)
			(type solid)
		)
		(fill yes)
		(layer "F.Cu")
		(net "GND")
	)
	(gr_poly
		(pts
			(arc
				(start 63.281306 -404.51786)
				(mid 62.915546 -404.51786)
				(end 63.281306 -404.51786)
			)
		)
		(stroke
			(width 0)
			(type solid)
		)
		(fill yes)
		(layer "F.Cu")
		(net "GND")
	)
	(gr_poly
		(pts
			(arc
				(start 63.281306 -403.249892)
				(mid 62.915546 -403.249892)
				(end 63.281306 -403.249892)
			)
		)
		(stroke
			(width 0)
			(type solid)
		)
		(fill yes)
		(layer "F.Cu")
		(net "GND")
	)
	(gr_poly
		(pts
			(arc
				(start 63.281306 -401.492212)
				(mid 62.915546 -401.492212)
				(end 63.281306 -401.492212)
			)
		)
		(stroke
			(width 0)
			(type solid)
		)
		(fill yes)
		(layer "F.Cu")
		(net "GND")
	)
	(gr_poly
		(pts
			(arc
				(start 63.281306 -400.224244)
				(mid 62.915546 -400.224244)
				(end 63.281306 -400.224244)
			)
		)
		(stroke
			(width 0)
			(type solid)
		)
		(fill yes)
		(layer "F.Cu")
		(net "GND")
	)
	(gr_poly
		(pts
			(arc
				(start 63.50508 -129.631948)
				(mid 63.13932 -129.631948)
				(end 63.50508 -129.631948)
			)
		)
		(stroke
			(width 0)
			(type solid)
		)
		(fill yes)
		(layer "F.Cu")
		(net "GND")
	)
	(gr_poly
		(pts
			(arc
				(start 63.64732 -131.628388)
				(mid 63.28156 -131.628388)
				(end 63.64732 -131.628388)
			)
		)
		(stroke
			(width 0)
			(type solid)
		)
		(fill yes)
		(layer "F.Cu")
		(net "GND")
	)
	(gr_poly
		(pts
			(arc
				(start 64.54013 -404.51786)
				(mid 64.17437 -404.51786)
				(end 64.54013 -404.51786)
			)
		)
		(stroke
			(width 0)
			(type solid)
		)
		(fill yes)
		(layer "F.Cu")
		(net "GND")
	)
	(gr_poly
		(pts
			(arc
				(start 64.54013 -403.249892)
				(mid 64.17437 -403.249892)
				(end 64.54013 -403.249892)
			)
		)
		(stroke
			(width 0)
			(type solid)
		)
		(fill yes)
		(layer "F.Cu")
		(net "GND")
	)
	(gr_poly
		(pts
			(arc
				(start 64.54013 -401.492212)
				(mid 64.17437 -401.492212)
				(end 64.54013 -401.492212)
			)
		)
		(stroke
			(width 0)
			(type solid)
		)
		(fill yes)
		(layer "F.Cu")
		(net "GND")
	)
	(gr_poly
		(pts
			(arc
				(start 64.54013 -400.224244)
				(mid 64.17437 -400.224244)
				(end 64.54013 -400.224244)
			)
		)
		(stroke
			(width 0)
			(type solid)
		)
		(fill yes)
		(layer "F.Cu")
		(net "GND")
	)
	(gr_poly
		(pts
			(arc
				(start 64.627506 -410.664152)
				(mid 64.261746 -410.664152)
				(end 64.627506 -410.664152)
			)
		)
		(stroke
			(width 0)
			(type solid)
		)
		(fill yes)
		(layer "F.Cu")
		(net "GND")
	)
	(gr_poly
		(pts
			(arc
				(start 64.627506 -409.396184)
				(mid 64.261746 -409.396184)
				(end 64.627506 -409.396184)
			)
		)
		(stroke
			(width 0)
			(type solid)
		)
		(fill yes)
		(layer "F.Cu")
		(net "GND")
	)
	(gr_poly
		(pts
			(arc
				(start 64.627506 -407.638504)
				(mid 64.261746 -407.638504)
				(end 64.627506 -407.638504)
			)
		)
		(stroke
			(width 0)
			(type solid)
		)
		(fill yes)
		(layer "F.Cu")
		(net "GND")
	)
	(gr_poly
		(pts
			(arc
				(start 64.627506 -406.370536)
				(mid 64.261746 -406.370536)
				(end 64.627506 -406.370536)
			)
		)
		(stroke
			(width 0)
			(type solid)
		)
		(fill yes)
		(layer "F.Cu")
		(net "GND")
	)
	(gr_poly
		(pts
			(arc
				(start 64.64808 -130.901948)
				(mid 64.28232 -130.901948)
				(end 64.64808 -130.901948)
			)
		)
		(stroke
			(width 0)
			(type solid)
		)
		(fill yes)
		(layer "F.Cu")
		(net "GND")
	)
	(gr_poly
		(pts
			(arc
				(start 65.571116 -105.637584)
				(mid 65.205356 -105.637584)
				(end 65.571116 -105.637584)
			)
		)
		(stroke
			(width 0)
			(type solid)
		)
		(fill yes)
		(layer "F.Cu")
		(net "GND")
	)
	(gr_poly
		(pts
			(arc
				(start 65.88633 -410.664152)
				(mid 65.52057 -410.664152)
				(end 65.88633 -410.664152)
			)
		)
		(stroke
			(width 0)
			(type solid)
		)
		(fill yes)
		(layer "F.Cu")
		(net "GND")
	)
	(gr_poly
		(pts
			(arc
				(start 65.88633 -409.396184)
				(mid 65.52057 -409.396184)
				(end 65.88633 -409.396184)
			)
		)
		(stroke
			(width 0)
			(type solid)
		)
		(fill yes)
		(layer "F.Cu")
		(net "GND")
	)
	(gr_poly
		(pts
			(arc
				(start 65.88633 -407.638504)
				(mid 65.52057 -407.638504)
				(end 65.88633 -407.638504)
			)
		)
		(stroke
			(width 0)
			(type solid)
		)
		(fill yes)
		(layer "F.Cu")
		(net "GND")
	)
	(gr_poly
		(pts
			(arc
				(start 65.88633 -406.370536)
				(mid 65.52057 -406.370536)
				(end 65.88633 -406.370536)
			)
		)
		(stroke
			(width 0)
			(type solid)
		)
		(fill yes)
		(layer "F.Cu")
		(net "GND")
	)
	(gr_poly
		(pts
			(arc
				(start 65.904364 -103.591868)
				(mid 65.538604 -103.591868)
				(end 65.904364 -103.591868)
			)
		)
		(stroke
			(width 0)
			(type solid)
		)
		(fill yes)
		(layer "F.Cu")
		(net "GND")
	)
	(gr_poly
		(pts
			(arc
				(start 66.344546 -404.51786)
				(mid 65.978786 -404.51786)
				(end 66.344546 -404.51786)
			)
		)
		(stroke
			(width 0)
			(type solid)
		)
		(fill yes)
		(layer "F.Cu")
		(net "GND")
	)
	(gr_poly
		(pts
			(arc
				(start 66.344546 -403.249892)
				(mid 65.978786 -403.249892)
				(end 66.344546 -403.249892)
			)
		)
		(stroke
			(width 0)
			(type solid)
		)
		(fill yes)
		(layer "F.Cu")
		(net "GND")
	)
	(gr_poly
		(pts
			(arc
				(start 66.344546 -401.492212)
				(mid 65.978786 -401.492212)
				(end 66.344546 -401.492212)
			)
		)
		(stroke
			(width 0)
			(type solid)
		)
		(fill yes)
		(layer "F.Cu")
		(net "GND")
	)
	(gr_poly
		(pts
			(arc
				(start 66.344546 -400.200368)
				(mid 65.978786 -400.200368)
				(end 66.344546 -400.200368)
			)
		)
		(stroke
			(width 0)
			(type solid)
		)
		(fill yes)
		(layer "F.Cu")
		(net "GND")
	)
	(gr_poly
		(pts
			(arc
				(start 66.427858 -107.798362)
				(mid 66.062098 -107.798362)
				(end 66.427858 -107.798362)
			)
		)
		(stroke
			(width 0)
			(type solid)
		)
		(fill yes)
		(layer "F.Cu")
		(net "GND")
	)
	(gr_poly
		(pts
			(arc
				(start 67.056 -8.969248)
				(mid 66.69024 -8.969248)
				(end 67.056 -8.969248)
			)
		)
		(stroke
			(width 0)
			(type solid)
		)
		(fill yes)
		(layer "F.Cu")
		(net "GND")
	)
	(gr_poly
		(pts
			(arc
				(start 67.60337 -404.51786)
				(mid 67.23761 -404.51786)
				(end 67.60337 -404.51786)
			)
		)
		(stroke
			(width 0)
			(type solid)
		)
		(fill yes)
		(layer "F.Cu")
		(net "GND")
	)
	(gr_poly
		(pts
			(arc
				(start 67.60337 -403.249892)
				(mid 67.23761 -403.249892)
				(end 67.60337 -403.249892)
			)
		)
		(stroke
			(width 0)
			(type solid)
		)
		(fill yes)
		(layer "F.Cu")
		(net "GND")
	)
	(gr_poly
		(pts
			(arc
				(start 67.60337 -401.492212)
				(mid 67.23761 -401.492212)
				(end 67.60337 -401.492212)
			)
		)
		(stroke
			(width 0)
			(type solid)
		)
		(fill yes)
		(layer "F.Cu")
		(net "GND")
	)
	(gr_poly
		(pts
			(arc
				(start 67.60337 -400.200368)
				(mid 67.23761 -400.200368)
				(end 67.60337 -400.200368)
			)
		)
		(stroke
			(width 0)
			(type solid)
		)
		(fill yes)
		(layer "F.Cu")
		(net "GND")
	)
	(gr_poly
		(pts
			(arc
				(start 67.690746 -410.664152)
				(mid 67.324986 -410.664152)
				(end 67.690746 -410.664152)
			)
		)
		(stroke
			(width 0)
			(type solid)
		)
		(fill yes)
		(layer "F.Cu")
		(net "GND")
	)
	(gr_poly
		(pts
			(arc
				(start 67.690746 -409.396184)
				(mid 67.324986 -409.396184)
				(end 67.690746 -409.396184)
			)
		)
		(stroke
			(width 0)
			(type solid)
		)
		(fill yes)
		(layer "F.Cu")
		(net "GND")
	)
	(gr_poly
		(pts
			(arc
				(start 67.690746 -407.638504)
				(mid 67.324986 -407.638504)
				(end 67.690746 -407.638504)
			)
		)
		(stroke
			(width 0)
			(type solid)
		)
		(fill yes)
		(layer "F.Cu")
		(net "GND")
	)
	(gr_poly
		(pts
			(arc
				(start 67.690746 -406.34666)
				(mid 67.324986 -406.34666)
				(end 67.690746 -406.34666)
			)
		)
		(stroke
			(width 0)
			(type solid)
		)
		(fill yes)
		(layer "F.Cu")
		(net "GND")
	)
	(gr_poly
		(pts
			(arc
				(start 68.94957 -410.664152)
				(mid 68.58381 -410.664152)
				(end 68.94957 -410.664152)
			)
		)
		(stroke
			(width 0)
			(type solid)
		)
		(fill yes)
		(layer "F.Cu")
		(net "GND")
	)
	(gr_poly
		(pts
			(arc
				(start 68.94957 -409.396184)
				(mid 68.58381 -409.396184)
				(end 68.94957 -409.396184)
			)
		)
		(stroke
			(width 0)
			(type solid)
		)
		(fill yes)
		(layer "F.Cu")
		(net "GND")
	)
	(gr_poly
		(pts
			(arc
				(start 68.94957 -407.638504)
				(mid 68.58381 -407.638504)
				(end 68.94957 -407.638504)
			)
		)
		(stroke
			(width 0)
			(type solid)
		)
		(fill yes)
		(layer "F.Cu")
		(net "GND")
	)
	(gr_poly
		(pts
			(arc
				(start 68.94957 -406.34666)
				(mid 68.58381 -406.34666)
				(end 68.94957 -406.34666)
			)
		)
		(stroke
			(width 0)
			(type solid)
		)
		(fill yes)
		(layer "F.Cu")
		(net "GND")
	)
	(gr_poly
		(pts
			(arc
				(start 69.16928 -10.201148)
				(mid 68.80352 -10.201148)
				(end 69.16928 -10.201148)
			)
		)
		(stroke
			(width 0)
			(type solid)
		)
		(fill yes)
		(layer "F.Cu")
		(net "GND")
	)
	(gr_poly
		(pts
			(arc
				(start 69.407786 -404.51786)
				(mid 69.042026 -404.51786)
				(end 69.407786 -404.51786)
			)
		)
		(stroke
			(width 0)
			(type solid)
		)
		(fill yes)
		(layer "F.Cu")
		(net "GND")
	)
	(gr_poly
		(pts
			(arc
				(start 69.407786 -403.249892)
				(mid 69.042026 -403.249892)
				(end 69.407786 -403.249892)
			)
		)
		(stroke
			(width 0)
			(type solid)
		)
		(fill yes)
		(layer "F.Cu")
		(net "GND")
	)
	(gr_poly
		(pts
			(arc
				(start 69.407786 -401.492212)
				(mid 69.042026 -401.492212)
				(end 69.407786 -401.492212)
			)
		)
		(stroke
			(width 0)
			(type solid)
		)
		(fill yes)
		(layer "F.Cu")
		(net "GND")
	)
	(gr_poly
		(pts
			(arc
				(start 69.407786 -400.224244)
				(mid 69.042026 -400.224244)
				(end 69.407786 -400.224244)
			)
		)
		(stroke
			(width 0)
			(type solid)
		)
		(fill yes)
		(layer "F.Cu")
		(net "GND")
	)
	(gr_poly
		(pts
			(arc
				(start 69.42328 -6.904228)
				(mid 69.05752 -6.904228)
				(end 69.42328 -6.904228)
			)
		)
		(stroke
			(width 0)
			(type solid)
		)
		(fill yes)
		(layer "F.Cu")
		(net "GND")
	)
	(gr_poly
		(pts
			(arc
				(start 70.66661 -404.51786)
				(mid 70.30085 -404.51786)
				(end 70.66661 -404.51786)
			)
		)
		(stroke
			(width 0)
			(type solid)
		)
		(fill yes)
		(layer "F.Cu")
		(net "GND")
	)
	(gr_poly
		(pts
			(arc
				(start 70.66661 -403.249892)
				(mid 70.30085 -403.249892)
				(end 70.66661 -403.249892)
			)
		)
		(stroke
			(width 0)
			(type solid)
		)
		(fill yes)
		(layer "F.Cu")
		(net "GND")
	)
	(gr_poly
		(pts
			(arc
				(start 70.66661 -401.492212)
				(mid 70.30085 -401.492212)
				(end 70.66661 -401.492212)
			)
		)
		(stroke
			(width 0)
			(type solid)
		)
		(fill yes)
		(layer "F.Cu")
		(net "GND")
	)
	(gr_poly
		(pts
			(arc
				(start 70.66661 -400.224244)
				(mid 70.30085 -400.224244)
				(end 70.66661 -400.224244)
			)
		)
		(stroke
			(width 0)
			(type solid)
		)
		(fill yes)
		(layer "F.Cu")
		(net "GND")
	)
	(gr_poly
		(pts
			(arc
				(start 70.753986 -410.664152)
				(mid 70.388226 -410.664152)
				(end 70.753986 -410.664152)
			)
		)
		(stroke
			(width 0)
			(type solid)
		)
		(fill yes)
		(layer "F.Cu")
		(net "GND")
	)
	(gr_poly
		(pts
			(arc
				(start 70.753986 -409.396184)
				(mid 70.388226 -409.396184)
				(end 70.753986 -409.396184)
			)
		)
		(stroke
			(width 0)
			(type solid)
		)
		(fill yes)
		(layer "F.Cu")
		(net "GND")
	)
	(gr_poly
		(pts
			(arc
				(start 70.753986 -407.638504)
				(mid 70.388226 -407.638504)
				(end 70.753986 -407.638504)
			)
		)
		(stroke
			(width 0)
			(type solid)
		)
		(fill yes)
		(layer "F.Cu")
		(net "GND")
	)
	(gr_poly
		(pts
			(arc
				(start 70.753986 -406.370536)
				(mid 70.388226 -406.370536)
				(end 70.753986 -406.370536)
			)
		)
		(stroke
			(width 0)
			(type solid)
		)
		(fill yes)
		(layer "F.Cu")
		(net "GND")
	)
	(gr_poly
		(pts
			(arc
				(start 72.01281 -410.664152)
				(mid 71.64705 -410.664152)
				(end 72.01281 -410.664152)
			)
		)
		(stroke
			(width 0)
			(type solid)
		)
		(fill yes)
		(layer "F.Cu")
		(net "GND")
	)
	(gr_poly
		(pts
			(arc
				(start 72.01281 -409.396184)
				(mid 71.64705 -409.396184)
				(end 72.01281 -409.396184)
			)
		)
		(stroke
			(width 0)
			(type solid)
		)
		(fill yes)
		(layer "F.Cu")
		(net "GND")
	)
	(gr_poly
		(pts
			(arc
				(start 72.01281 -407.638504)
				(mid 71.64705 -407.638504)
				(end 72.01281 -407.638504)
			)
		)
		(stroke
			(width 0)
			(type solid)
		)
		(fill yes)
		(layer "F.Cu")
		(net "GND")
	)
	(gr_poly
		(pts
			(arc
				(start 72.01281 -406.370536)
				(mid 71.64705 -406.370536)
				(end 72.01281 -406.370536)
			)
		)
		(stroke
			(width 0)
			(type solid)
		)
		(fill yes)
		(layer "F.Cu")
		(net "GND")
	)
	(gr_poly
		(pts
			(arc
				(start 72.471026 -404.51786)
				(mid 72.105266 -404.51786)
				(end 72.471026 -404.51786)
			)
		)
		(stroke
			(width 0)
			(type solid)
		)
		(fill yes)
		(layer "F.Cu")
		(net "GND")
	)
	(gr_poly
		(pts
			(arc
				(start 72.471026 -403.249892)
				(mid 72.105266 -403.249892)
				(end 72.471026 -403.249892)
			)
		)
		(stroke
			(width 0)
			(type solid)
		)
		(fill yes)
		(layer "F.Cu")
		(net "GND")
	)
	(gr_poly
		(pts
			(arc
				(start 72.471026 -401.492212)
				(mid 72.105266 -401.492212)
				(end 72.471026 -401.492212)
			)
		)
		(stroke
			(width 0)
			(type solid)
		)
		(fill yes)
		(layer "F.Cu")
		(net "GND")
	)
	(gr_poly
		(pts
			(arc
				(start 72.471026 -400.224244)
				(mid 72.105266 -400.224244)
				(end 72.471026 -400.224244)
			)
		)
		(stroke
			(width 0)
			(type solid)
		)
		(fill yes)
		(layer "F.Cu")
		(net "GND")
	)
	(gr_poly
		(pts
			(arc
				(start 72.80148 -6.086348)
				(mid 72.43572 -6.086348)
				(end 72.80148 -6.086348)
			)
		)
		(stroke
			(width 0)
			(type solid)
		)
		(fill yes)
		(layer "F.Cu")
		(net "GND")
	)
	(gr_poly
		(pts
			(arc
				(start 72.95388 -13.325348)
				(mid 72.58812 -13.325348)
				(end 72.95388 -13.325348)
			)
		)
		(stroke
			(width 0)
			(type solid)
		)
		(fill yes)
		(layer "F.Cu")
		(net "GND")
	)
	(gr_poly
		(pts
			(arc
				(start 73.28408 -15.255748)
				(mid 72.91832 -15.255748)
				(end 73.28408 -15.255748)
			)
		)
		(stroke
			(width 0)
			(type solid)
		)
		(fill yes)
		(layer "F.Cu")
		(net "GND")
	)
	(gr_poly
		(pts
			(arc
				(start 73.72985 -404.51786)
				(mid 73.36409 -404.51786)
				(end 73.72985 -404.51786)
			)
		)
		(stroke
			(width 0)
			(type solid)
		)
		(fill yes)
		(layer "F.Cu")
		(net "GND")
	)
	(gr_poly
		(pts
			(arc
				(start 73.72985 -403.249892)
				(mid 73.36409 -403.249892)
				(end 73.72985 -403.249892)
			)
		)
		(stroke
			(width 0)
			(type solid)
		)
		(fill yes)
		(layer "F.Cu")
		(net "GND")
	)
	(gr_poly
		(pts
			(arc
				(start 73.72985 -401.492212)
				(mid 73.36409 -401.492212)
				(end 73.72985 -401.492212)
			)
		)
		(stroke
			(width 0)
			(type solid)
		)
		(fill yes)
		(layer "F.Cu")
		(net "GND")
	)
	(gr_poly
		(pts
			(arc
				(start 73.72985 -400.224244)
				(mid 73.36409 -400.224244)
				(end 73.72985 -400.224244)
			)
		)
		(stroke
			(width 0)
			(type solid)
		)
		(fill yes)
		(layer "F.Cu")
		(net "GND")
	)
	(gr_poly
		(pts
			(arc
				(start 73.817226 -410.664152)
				(mid 73.451466 -410.664152)
				(end 73.817226 -410.664152)
			)
		)
		(stroke
			(width 0)
			(type solid)
		)
		(fill yes)
		(layer "F.Cu")
		(net "GND")
	)
	(gr_poly
		(pts
			(arc
				(start 73.817226 -409.396184)
				(mid 73.451466 -409.396184)
				(end 73.817226 -409.396184)
			)
		)
		(stroke
			(width 0)
			(type solid)
		)
		(fill yes)
		(layer "F.Cu")
		(net "GND")
	)
	(gr_poly
		(pts
			(arc
				(start 73.817226 -407.638504)
				(mid 73.451466 -407.638504)
				(end 73.817226 -407.638504)
			)
		)
		(stroke
			(width 0)
			(type solid)
		)
		(fill yes)
		(layer "F.Cu")
		(net "GND")
	)
	(gr_poly
		(pts
			(arc
				(start 73.817226 -406.370536)
				(mid 73.451466 -406.370536)
				(end 73.817226 -406.370536)
			)
		)
		(stroke
			(width 0)
			(type solid)
		)
		(fill yes)
		(layer "F.Cu")
		(net "GND")
	)
	(gr_poly
		(pts
			(arc
				(start 74.26452 -5.497068)
				(mid 73.89876 -5.497068)
				(end 74.26452 -5.497068)
			)
		)
		(stroke
			(width 0)
			(type solid)
		)
		(fill yes)
		(layer "F.Cu")
		(net "GND")
	)
	(gr_poly
		(pts
			(arc
				(start 75.07605 -410.664152)
				(mid 74.71029 -410.664152)
				(end 75.07605 -410.664152)
			)
		)
		(stroke
			(width 0)
			(type solid)
		)
		(fill yes)
		(layer "F.Cu")
		(net "GND")
	)
	(gr_poly
		(pts
			(arc
				(start 75.07605 -409.396184)
				(mid 74.71029 -409.396184)
				(end 75.07605 -409.396184)
			)
		)
		(stroke
			(width 0)
			(type solid)
		)
		(fill yes)
		(layer "F.Cu")
		(net "GND")
	)
	(gr_poly
		(pts
			(arc
				(start 75.07605 -407.638504)
				(mid 74.71029 -407.638504)
				(end 75.07605 -407.638504)
			)
		)
		(stroke
			(width 0)
			(type solid)
		)
		(fill yes)
		(layer "F.Cu")
		(net "GND")
	)
	(gr_poly
		(pts
			(arc
				(start 75.07605 -406.370536)
				(mid 74.71029 -406.370536)
				(end 75.07605 -406.370536)
			)
		)
		(stroke
			(width 0)
			(type solid)
		)
		(fill yes)
		(layer "F.Cu")
		(net "GND")
	)
	(gr_poly
		(pts
			(arc
				(start 75.534266 -404.51786)
				(mid 75.168506 -404.51786)
				(end 75.534266 -404.51786)
			)
		)
		(stroke
			(width 0)
			(type solid)
		)
		(fill yes)
		(layer "F.Cu")
		(net "GND")
	)
	(gr_poly
		(pts
			(arc
				(start 75.534266 -403.249892)
				(mid 75.168506 -403.249892)
				(end 75.534266 -403.249892)
			)
		)
		(stroke
			(width 0)
			(type solid)
		)
		(fill yes)
		(layer "F.Cu")
		(net "GND")
	)
	(gr_poly
		(pts
			(arc
				(start 75.534266 -401.492212)
				(mid 75.168506 -401.492212)
				(end 75.534266 -401.492212)
			)
		)
		(stroke
			(width 0)
			(type solid)
		)
		(fill yes)
		(layer "F.Cu")
		(net "GND")
	)
	(gr_poly
		(pts
			(arc
				(start 75.534266 -400.224244)
				(mid 75.168506 -400.224244)
				(end 75.534266 -400.224244)
			)
		)
		(stroke
			(width 0)
			(type solid)
		)
		(fill yes)
		(layer "F.Cu")
		(net "GND")
	)
	(gr_poly
		(pts
			(arc
				(start 76.79309 -404.51786)
				(mid 76.42733 -404.51786)
				(end 76.79309 -404.51786)
			)
		)
		(stroke
			(width 0)
			(type solid)
		)
		(fill yes)
		(layer "F.Cu")
		(net "GND")
	)
	(gr_poly
		(pts
			(arc
				(start 76.79309 -403.249892)
				(mid 76.42733 -403.249892)
				(end 76.79309 -403.249892)
			)
		)
		(stroke
			(width 0)
			(type solid)
		)
		(fill yes)
		(layer "F.Cu")
		(net "GND")
	)
	(gr_poly
		(pts
			(arc
				(start 76.79309 -401.492212)
				(mid 76.42733 -401.492212)
				(end 76.79309 -401.492212)
			)
		)
		(stroke
			(width 0)
			(type solid)
		)
		(fill yes)
		(layer "F.Cu")
		(net "GND")
	)
	(gr_poly
		(pts
			(arc
				(start 76.79309 -400.224244)
				(mid 76.42733 -400.224244)
				(end 76.79309 -400.224244)
			)
		)
		(stroke
			(width 0)
			(type solid)
		)
		(fill yes)
		(layer "F.Cu")
		(net "GND")
	)
	(gr_poly
		(pts
			(arc
				(start 76.880466 -410.664152)
				(mid 76.514706 -410.664152)
				(end 76.880466 -410.664152)
			)
		)
		(stroke
			(width 0)
			(type solid)
		)
		(fill yes)
		(layer "F.Cu")
		(net "GND")
	)
	(gr_poly
		(pts
			(arc
				(start 76.880466 -409.396184)
				(mid 76.514706 -409.396184)
				(end 76.880466 -409.396184)
			)
		)
		(stroke
			(width 0)
			(type solid)
		)
		(fill yes)
		(layer "F.Cu")
		(net "GND")
	)
	(gr_poly
		(pts
			(arc
				(start 76.880466 -407.638504)
				(mid 76.514706 -407.638504)
				(end 76.880466 -407.638504)
			)
		)
		(stroke
			(width 0)
			(type solid)
		)
		(fill yes)
		(layer "F.Cu")
		(net "GND")
	)
	(gr_poly
		(pts
			(arc
				(start 76.880466 -406.370536)
				(mid 76.514706 -406.370536)
				(end 76.880466 -406.370536)
			)
		)
		(stroke
			(width 0)
			(type solid)
		)
		(fill yes)
		(layer "F.Cu")
		(net "GND")
	)
	(gr_poly
		(pts
			(arc
				(start 78.13929 -410.664152)
				(mid 77.77353 -410.664152)
				(end 78.13929 -410.664152)
			)
		)
		(stroke
			(width 0)
			(type solid)
		)
		(fill yes)
		(layer "F.Cu")
		(net "GND")
	)
	(gr_poly
		(pts
			(arc
				(start 78.13929 -409.396184)
				(mid 77.77353 -409.396184)
				(end 78.13929 -409.396184)
			)
		)
		(stroke
			(width 0)
			(type solid)
		)
		(fill yes)
		(layer "F.Cu")
		(net "GND")
	)
	(gr_poly
		(pts
			(arc
				(start 78.13929 -407.638504)
				(mid 77.77353 -407.638504)
				(end 78.13929 -407.638504)
			)
		)
		(stroke
			(width 0)
			(type solid)
		)
		(fill yes)
		(layer "F.Cu")
		(net "GND")
	)
	(gr_poly
		(pts
			(arc
				(start 78.13929 -406.370536)
				(mid 77.77353 -406.370536)
				(end 78.13929 -406.370536)
			)
		)
		(stroke
			(width 0)
			(type solid)
		)
		(fill yes)
		(layer "F.Cu")
		(net "GND")
	)
	(gr_poly
		(pts
			(arc
				(start 78.597506 -404.51786)
				(mid 78.231746 -404.51786)
				(end 78.597506 -404.51786)
			)
		)
		(stroke
			(width 0)
			(type solid)
		)
		(fill yes)
		(layer "F.Cu")
		(net "GND")
	)
	(gr_poly
		(pts
			(arc
				(start 78.597506 -403.249892)
				(mid 78.231746 -403.249892)
				(end 78.597506 -403.249892)
			)
		)
		(stroke
			(width 0)
			(type solid)
		)
		(fill yes)
		(layer "F.Cu")
		(net "GND")
	)
	(gr_poly
		(pts
			(arc
				(start 78.597506 -401.492212)
				(mid 78.231746 -401.492212)
				(end 78.597506 -401.492212)
			)
		)
		(stroke
			(width 0)
			(type solid)
		)
		(fill yes)
		(layer "F.Cu")
		(net "GND")
	)
	(gr_poly
		(pts
			(arc
				(start 78.597506 -400.224244)
				(mid 78.231746 -400.224244)
				(end 78.597506 -400.224244)
			)
		)
		(stroke
			(width 0)
			(type solid)
		)
		(fill yes)
		(layer "F.Cu")
		(net "GND")
	)
	(gr_poly
		(pts
			(arc
				(start 79.85633 -404.51786)
				(mid 79.49057 -404.51786)
				(end 79.85633 -404.51786)
			)
		)
		(stroke
			(width 0)
			(type solid)
		)
		(fill yes)
		(layer "F.Cu")
		(net "GND")
	)
	(gr_poly
		(pts
			(arc
				(start 79.85633 -403.249892)
				(mid 79.49057 -403.249892)
				(end 79.85633 -403.249892)
			)
		)
		(stroke
			(width 0)
			(type solid)
		)
		(fill yes)
		(layer "F.Cu")
		(net "GND")
	)
	(gr_poly
		(pts
			(arc
				(start 79.85633 -401.492212)
				(mid 79.49057 -401.492212)
				(end 79.85633 -401.492212)
			)
		)
		(stroke
			(width 0)
			(type solid)
		)
		(fill yes)
		(layer "F.Cu")
		(net "GND")
	)
	(gr_poly
		(pts
			(arc
				(start 79.85633 -400.224244)
				(mid 79.49057 -400.224244)
				(end 79.85633 -400.224244)
			)
		)
		(stroke
			(width 0)
			(type solid)
		)
		(fill yes)
		(layer "F.Cu")
		(net "GND")
	)
	(gr_poly
		(pts
			(arc
				(start 79.943706 -410.664152)
				(mid 79.577946 -410.664152)
				(end 79.943706 -410.664152)
			)
		)
		(stroke
			(width 0)
			(type solid)
		)
		(fill yes)
		(layer "F.Cu")
		(net "GND")
	)
	(gr_poly
		(pts
			(arc
				(start 79.943706 -409.396184)
				(mid 79.577946 -409.396184)
				(end 79.943706 -409.396184)
			)
		)
		(stroke
			(width 0)
			(type solid)
		)
		(fill yes)
		(layer "F.Cu")
		(net "GND")
	)
	(gr_poly
		(pts
			(arc
				(start 79.943706 -407.638504)
				(mid 79.577946 -407.638504)
				(end 79.943706 -407.638504)
			)
		)
		(stroke
			(width 0)
			(type solid)
		)
		(fill yes)
		(layer "F.Cu")
		(net "GND")
	)
	(gr_poly
		(pts
			(arc
				(start 79.943706 -406.370536)
				(mid 79.577946 -406.370536)
				(end 79.943706 -406.370536)
			)
		)
		(stroke
			(width 0)
			(type solid)
		)
		(fill yes)
		(layer "F.Cu")
		(net "GND")
	)
	(gr_poly
		(pts
			(arc
				(start 81.20253 -410.664152)
				(mid 80.83677 -410.664152)
				(end 81.20253 -410.664152)
			)
		)
		(stroke
			(width 0)
			(type solid)
		)
		(fill yes)
		(layer "F.Cu")
		(net "GND")
	)
	(gr_poly
		(pts
			(arc
				(start 81.20253 -409.396184)
				(mid 80.83677 -409.396184)
				(end 81.20253 -409.396184)
			)
		)
		(stroke
			(width 0)
			(type solid)
		)
		(fill yes)
		(layer "F.Cu")
		(net "GND")
	)
	(gr_poly
		(pts
			(arc
				(start 81.20253 -407.638504)
				(mid 80.83677 -407.638504)
				(end 81.20253 -407.638504)
			)
		)
		(stroke
			(width 0)
			(type solid)
		)
		(fill yes)
		(layer "F.Cu")
		(net "GND")
	)
	(gr_poly
		(pts
			(arc
				(start 81.20253 -406.370536)
				(mid 80.83677 -406.370536)
				(end 81.20253 -406.370536)
			)
		)
		(stroke
			(width 0)
			(type solid)
		)
		(fill yes)
		(layer "F.Cu")
		(net "GND")
	)
	(gr_poly
		(pts
			(arc
				(start 81.660746 -404.51786)
				(mid 81.294986 -404.51786)
				(end 81.660746 -404.51786)
			)
		)
		(stroke
			(width 0)
			(type solid)
		)
		(fill yes)
		(layer "F.Cu")
		(net "GND")
	)
	(gr_poly
		(pts
			(arc
				(start 81.660746 -403.249892)
				(mid 81.294986 -403.249892)
				(end 81.660746 -403.249892)
			)
		)
		(stroke
			(width 0)
			(type solid)
		)
		(fill yes)
		(layer "F.Cu")
		(net "GND")
	)
	(gr_poly
		(pts
			(arc
				(start 81.660746 -401.492212)
				(mid 81.294986 -401.492212)
				(end 81.660746 -401.492212)
			)
		)
		(stroke
			(width 0)
			(type solid)
		)
		(fill yes)
		(layer "F.Cu")
		(net "GND")
	)
	(gr_poly
		(pts
			(arc
				(start 81.660746 -400.224244)
				(mid 81.294986 -400.224244)
				(end 81.660746 -400.224244)
			)
		)
		(stroke
			(width 0)
			(type solid)
		)
		(fill yes)
		(layer "F.Cu")
		(net "GND")
	)
	(gr_poly
		(pts
			(arc
				(start 82.91957 -404.51786)
				(mid 82.55381 -404.51786)
				(end 82.91957 -404.51786)
			)
		)
		(stroke
			(width 0)
			(type solid)
		)
		(fill yes)
		(layer "F.Cu")
		(net "GND")
	)
	(gr_poly
		(pts
			(arc
				(start 82.91957 -403.249892)
				(mid 82.55381 -403.249892)
				(end 82.91957 -403.249892)
			)
		)
		(stroke
			(width 0)
			(type solid)
		)
		(fill yes)
		(layer "F.Cu")
		(net "GND")
	)
	(gr_poly
		(pts
			(arc
				(start 82.91957 -401.492212)
				(mid 82.55381 -401.492212)
				(end 82.91957 -401.492212)
			)
		)
		(stroke
			(width 0)
			(type solid)
		)
		(fill yes)
		(layer "F.Cu")
		(net "GND")
	)
	(gr_poly
		(pts
			(arc
				(start 82.91957 -400.224244)
				(mid 82.55381 -400.224244)
				(end 82.91957 -400.224244)
			)
		)
		(stroke
			(width 0)
			(type solid)
		)
		(fill yes)
		(layer "F.Cu")
		(net "GND")
	)
	(gr_poly
		(pts
			(arc
				(start 83.006946 -410.664152)
				(mid 82.641186 -410.664152)
				(end 83.006946 -410.664152)
			)
		)
		(stroke
			(width 0)
			(type solid)
		)
		(fill yes)
		(layer "F.Cu")
		(net "GND")
	)
	(gr_poly
		(pts
			(arc
				(start 83.006946 -409.396184)
				(mid 82.641186 -409.396184)
				(end 83.006946 -409.396184)
			)
		)
		(stroke
			(width 0)
			(type solid)
		)
		(fill yes)
		(layer "F.Cu")
		(net "GND")
	)
	(gr_poly
		(pts
			(arc
				(start 83.006946 -407.638504)
				(mid 82.641186 -407.638504)
				(end 83.006946 -407.638504)
			)
		)
		(stroke
			(width 0)
			(type solid)
		)
		(fill yes)
		(layer "F.Cu")
		(net "GND")
	)
	(gr_poly
		(pts
			(arc
				(start 83.006946 -406.370536)
				(mid 82.641186 -406.370536)
				(end 83.006946 -406.370536)
			)
		)
		(stroke
			(width 0)
			(type solid)
		)
		(fill yes)
		(layer "F.Cu")
		(net "GND")
	)
	(gr_poly
		(pts
			(arc
				(start 84.26577 -410.664152)
				(mid 83.90001 -410.664152)
				(end 84.26577 -410.664152)
			)
		)
		(stroke
			(width 0)
			(type solid)
		)
		(fill yes)
		(layer "F.Cu")
		(net "GND")
	)
	(gr_poly
		(pts
			(arc
				(start 84.26577 -409.396184)
				(mid 83.90001 -409.396184)
				(end 84.26577 -409.396184)
			)
		)
		(stroke
			(width 0)
			(type solid)
		)
		(fill yes)
		(layer "F.Cu")
		(net "GND")
	)
	(gr_poly
		(pts
			(arc
				(start 84.26577 -407.638504)
				(mid 83.90001 -407.638504)
				(end 84.26577 -407.638504)
			)
		)
		(stroke
			(width 0)
			(type solid)
		)
		(fill yes)
		(layer "F.Cu")
		(net "GND")
	)
	(gr_poly
		(pts
			(arc
				(start 84.26577 -406.370536)
				(mid 83.90001 -406.370536)
				(end 84.26577 -406.370536)
			)
		)
		(stroke
			(width 0)
			(type solid)
		)
		(fill yes)
		(layer "F.Cu")
		(net "GND")
	)
	(gr_poly
		(pts
			(arc
				(start 84.44992 -179.294028)
				(mid 84.08416 -179.294028)
				(end 84.44992 -179.294028)
			)
		)
		(stroke
			(width 0)
			(type solid)
		)
		(fill yes)
		(layer "F.Cu")
		(net "GND")
	)
	(gr_poly
		(pts
			(arc
				(start 84.723986 -404.51786)
				(mid 84.358226 -404.51786)
				(end 84.723986 -404.51786)
			)
		)
		(stroke
			(width 0)
			(type solid)
		)
		(fill yes)
		(layer "F.Cu")
		(net "GND")
	)
	(gr_poly
		(pts
			(arc
				(start 84.723986 -403.249892)
				(mid 84.358226 -403.249892)
				(end 84.723986 -403.249892)
			)
		)
		(stroke
			(width 0)
			(type solid)
		)
		(fill yes)
		(layer "F.Cu")
		(net "GND")
	)
	(gr_poly
		(pts
			(arc
				(start 84.723986 -401.492212)
				(mid 84.358226 -401.492212)
				(end 84.723986 -401.492212)
			)
		)
		(stroke
			(width 0)
			(type solid)
		)
		(fill yes)
		(layer "F.Cu")
		(net "GND")
	)
	(gr_poly
		(pts
			(arc
				(start 84.723986 -400.224244)
				(mid 84.358226 -400.224244)
				(end 84.723986 -400.224244)
			)
		)
		(stroke
			(width 0)
			(type solid)
		)
		(fill yes)
		(layer "F.Cu")
		(net "GND")
	)
	(gr_poly
		(pts
			(arc
				(start 85.98281 -404.51786)
				(mid 85.61705 -404.51786)
				(end 85.98281 -404.51786)
			)
		)
		(stroke
			(width 0)
			(type solid)
		)
		(fill yes)
		(layer "F.Cu")
		(net "GND")
	)
	(gr_poly
		(pts
			(arc
				(start 85.98281 -403.249892)
				(mid 85.61705 -403.249892)
				(end 85.98281 -403.249892)
			)
		)
		(stroke
			(width 0)
			(type solid)
		)
		(fill yes)
		(layer "F.Cu")
		(net "GND")
	)
	(gr_poly
		(pts
			(arc
				(start 85.98281 -401.492212)
				(mid 85.61705 -401.492212)
				(end 85.98281 -401.492212)
			)
		)
		(stroke
			(width 0)
			(type solid)
		)
		(fill yes)
		(layer "F.Cu")
		(net "GND")
	)
	(gr_poly
		(pts
			(arc
				(start 85.98281 -400.224244)
				(mid 85.61705 -400.224244)
				(end 85.98281 -400.224244)
			)
		)
		(stroke
			(width 0)
			(type solid)
		)
		(fill yes)
		(layer "F.Cu")
		(net "GND")
	)
	(gr_poly
		(pts
			(arc
				(start 86.070186 -410.664152)
				(mid 85.704426 -410.664152)
				(end 86.070186 -410.664152)
			)
		)
		(stroke
			(width 0)
			(type solid)
		)
		(fill yes)
		(layer "F.Cu")
		(net "GND")
	)
	(gr_poly
		(pts
			(arc
				(start 86.070186 -409.396184)
				(mid 85.704426 -409.396184)
				(end 86.070186 -409.396184)
			)
		)
		(stroke
			(width 0)
			(type solid)
		)
		(fill yes)
		(layer "F.Cu")
		(net "GND")
	)
	(gr_poly
		(pts
			(arc
				(start 86.070186 -407.638504)
				(mid 85.704426 -407.638504)
				(end 86.070186 -407.638504)
			)
		)
		(stroke
			(width 0)
			(type solid)
		)
		(fill yes)
		(layer "F.Cu")
		(net "GND")
	)
	(gr_poly
		(pts
			(arc
				(start 86.070186 -406.370536)
				(mid 85.704426 -406.370536)
				(end 86.070186 -406.370536)
			)
		)
		(stroke
			(width 0)
			(type solid)
		)
		(fill yes)
		(layer "F.Cu")
		(net "GND")
	)
	(gr_poly
		(pts
			(arc
				(start 87.32901 -410.664152)
				(mid 86.96325 -410.664152)
				(end 87.32901 -410.664152)
			)
		)
		(stroke
			(width 0)
			(type solid)
		)
		(fill yes)
		(layer "F.Cu")
		(net "GND")
	)
	(gr_poly
		(pts
			(arc
				(start 87.32901 -409.396184)
				(mid 86.96325 -409.396184)
				(end 87.32901 -409.396184)
			)
		)
		(stroke
			(width 0)
			(type solid)
		)
		(fill yes)
		(layer "F.Cu")
		(net "GND")
	)
	(gr_poly
		(pts
			(arc
				(start 87.32901 -407.638504)
				(mid 86.96325 -407.638504)
				(end 87.32901 -407.638504)
			)
		)
		(stroke
			(width 0)
			(type solid)
		)
		(fill yes)
		(layer "F.Cu")
		(net "GND")
	)
	(gr_poly
		(pts
			(arc
				(start 87.32901 -406.370536)
				(mid 86.96325 -406.370536)
				(end 87.32901 -406.370536)
			)
		)
		(stroke
			(width 0)
			(type solid)
		)
		(fill yes)
		(layer "F.Cu")
		(net "GND")
	)
	(gr_poly
		(pts
			(arc
				(start 87.787226 -404.51786)
				(mid 87.421466 -404.51786)
				(end 87.787226 -404.51786)
			)
		)
		(stroke
			(width 0)
			(type solid)
		)
		(fill yes)
		(layer "F.Cu")
		(net "GND")
	)
	(gr_poly
		(pts
			(arc
				(start 87.787226 -403.249892)
				(mid 87.421466 -403.249892)
				(end 87.787226 -403.249892)
			)
		)
		(stroke
			(width 0)
			(type solid)
		)
		(fill yes)
		(layer "F.Cu")
		(net "GND")
	)
	(gr_poly
		(pts
			(arc
				(start 87.787226 -401.492212)
				(mid 87.421466 -401.492212)
				(end 87.787226 -401.492212)
			)
		)
		(stroke
			(width 0)
			(type solid)
		)
		(fill yes)
		(layer "F.Cu")
		(net "GND")
	)
	(gr_poly
		(pts
			(arc
				(start 87.787226 -400.224244)
				(mid 87.421466 -400.224244)
				(end 87.787226 -400.224244)
			)
		)
		(stroke
			(width 0)
			(type solid)
		)
		(fill yes)
		(layer "F.Cu")
		(net "GND")
	)
	(gr_poly
		(pts
			(arc
				(start 88.033606 -48.949864)
				(mid 87.667846 -48.949864)
				(end 88.033606 -48.949864)
			)
		)
		(stroke
			(width 0)
			(type solid)
		)
		(fill yes)
		(layer "F.Cu")
		(net "GND")
	)
	(gr_poly
		(pts
			(arc
				(start 88.571578 -191.861948)
				(mid 88.212422 -191.861948)
				(end 88.571578 -191.861948)
			)
		)
		(stroke
			(width 0)
			(type solid)
		)
		(fill yes)
		(layer "F.Cu")
		(net "GND")
	)
	(gr_poly
		(pts
			(arc
				(start 89.04605 -404.51786)
				(mid 88.68029 -404.51786)
				(end 89.04605 -404.51786)
			)
		)
		(stroke
			(width 0)
			(type solid)
		)
		(fill yes)
		(layer "F.Cu")
		(net "GND")
	)
	(gr_poly
		(pts
			(arc
				(start 89.04605 -403.249892)
				(mid 88.68029 -403.249892)
				(end 89.04605 -403.249892)
			)
		)
		(stroke
			(width 0)
			(type solid)
		)
		(fill yes)
		(layer "F.Cu")
		(net "GND")
	)
	(gr_poly
		(pts
			(arc
				(start 89.04605 -401.492212)
				(mid 88.68029 -401.492212)
				(end 89.04605 -401.492212)
			)
		)
		(stroke
			(width 0)
			(type solid)
		)
		(fill yes)
		(layer "F.Cu")
		(net "GND")
	)
	(gr_poly
		(pts
			(arc
				(start 89.04605 -400.224244)
				(mid 88.68029 -400.224244)
				(end 89.04605 -400.224244)
			)
		)
		(stroke
			(width 0)
			(type solid)
		)
		(fill yes)
		(layer "F.Cu")
		(net "GND")
	)
	(gr_poly
		(pts
			(arc
				(start 89.133426 -410.664152)
				(mid 88.767666 -410.664152)
				(end 89.133426 -410.664152)
			)
		)
		(stroke
			(width 0)
			(type solid)
		)
		(fill yes)
		(layer "F.Cu")
		(net "GND")
	)
	(gr_poly
		(pts
			(arc
				(start 89.133426 -409.396184)
				(mid 88.767666 -409.396184)
				(end 89.133426 -409.396184)
			)
		)
		(stroke
			(width 0)
			(type solid)
		)
		(fill yes)
		(layer "F.Cu")
		(net "GND")
	)
	(gr_poly
		(pts
			(arc
				(start 89.133426 -407.638504)
				(mid 88.767666 -407.638504)
				(end 89.133426 -407.638504)
			)
		)
		(stroke
			(width 0)
			(type solid)
		)
		(fill yes)
		(layer "F.Cu")
		(net "GND")
	)
	(gr_poly
		(pts
			(arc
				(start 89.133426 -406.370536)
				(mid 88.767666 -406.370536)
				(end 89.133426 -406.370536)
			)
		)
		(stroke
			(width 0)
			(type solid)
		)
		(fill yes)
		(layer "F.Cu")
		(net "GND")
	)
	(gr_poly
		(pts
			(arc
				(start 90.39225 -410.664152)
				(mid 90.02649 -410.664152)
				(end 90.39225 -410.664152)
			)
		)
		(stroke
			(width 0)
			(type solid)
		)
		(fill yes)
		(layer "F.Cu")
		(net "GND")
	)
	(gr_poly
		(pts
			(arc
				(start 90.39225 -409.396184)
				(mid 90.02649 -409.396184)
				(end 90.39225 -409.396184)
			)
		)
		(stroke
			(width 0)
			(type solid)
		)
		(fill yes)
		(layer "F.Cu")
		(net "GND")
	)
	(gr_poly
		(pts
			(arc
				(start 90.39225 -407.638504)
				(mid 90.02649 -407.638504)
				(end 90.39225 -407.638504)
			)
		)
		(stroke
			(width 0)
			(type solid)
		)
		(fill yes)
		(layer "F.Cu")
		(net "GND")
	)
	(gr_poly
		(pts
			(arc
				(start 90.39225 -406.370536)
				(mid 90.02649 -406.370536)
				(end 90.39225 -406.370536)
			)
		)
		(stroke
			(width 0)
			(type solid)
		)
		(fill yes)
		(layer "F.Cu")
		(net "GND")
	)
	(gr_poly
		(pts
			(arc
				(start 90.67038 -54.950868)
				(mid 90.30462 -54.950868)
				(end 90.67038 -54.950868)
			)
		)
		(stroke
			(width 0)
			(type solid)
		)
		(fill yes)
		(layer "F.Cu")
		(net "GND")
	)
	(gr_poly
		(pts
			(arc
				(start 90.850466 -404.51786)
				(mid 90.484706 -404.51786)
				(end 90.850466 -404.51786)
			)
		)
		(stroke
			(width 0)
			(type solid)
		)
		(fill yes)
		(layer "F.Cu")
		(net "GND")
	)
	(gr_poly
		(pts
			(arc
				(start 90.850466 -403.249892)
				(mid 90.484706 -403.249892)
				(end 90.850466 -403.249892)
			)
		)
		(stroke
			(width 0)
			(type solid)
		)
		(fill yes)
		(layer "F.Cu")
		(net "GND")
	)
	(gr_poly
		(pts
			(arc
				(start 90.850466 -401.492212)
				(mid 90.484706 -401.492212)
				(end 90.850466 -401.492212)
			)
		)
		(stroke
			(width 0)
			(type solid)
		)
		(fill yes)
		(layer "F.Cu")
		(net "GND")
	)
	(gr_poly
		(pts
			(arc
				(start 90.850466 -400.200368)
				(mid 90.484706 -400.200368)
				(end 90.850466 -400.200368)
			)
		)
		(stroke
			(width 0)
			(type solid)
		)
		(fill yes)
		(layer "F.Cu")
		(net "GND")
	)
	(gr_poly
		(pts
			(arc
				(start 91.167966 -52.874926)
				(mid 90.802206 -52.874926)
				(end 91.167966 -52.874926)
			)
		)
		(stroke
			(width 0)
			(type solid)
		)
		(fill yes)
		(layer "F.Cu")
		(net "GND")
	)
	(gr_poly
		(pts
			(arc
				(start 92.10929 -404.51786)
				(mid 91.74353 -404.51786)
				(end 92.10929 -404.51786)
			)
		)
		(stroke
			(width 0)
			(type solid)
		)
		(fill yes)
		(layer "F.Cu")
		(net "GND")
	)
	(gr_poly
		(pts
			(arc
				(start 92.10929 -403.249892)
				(mid 91.74353 -403.249892)
				(end 92.10929 -403.249892)
			)
		)
		(stroke
			(width 0)
			(type solid)
		)
		(fill yes)
		(layer "F.Cu")
		(net "GND")
	)
	(gr_poly
		(pts
			(arc
				(start 92.10929 -401.492212)
				(mid 91.74353 -401.492212)
				(end 92.10929 -401.492212)
			)
		)
		(stroke
			(width 0)
			(type solid)
		)
		(fill yes)
		(layer "F.Cu")
		(net "GND")
	)
	(gr_poly
		(pts
			(arc
				(start 92.10929 -400.200368)
				(mid 91.74353 -400.200368)
				(end 92.10929 -400.200368)
			)
		)
		(stroke
			(width 0)
			(type solid)
		)
		(fill yes)
		(layer "F.Cu")
		(net "GND")
	)
	(gr_poly
		(pts
			(arc
				(start 92.196666 -410.664152)
				(mid 91.830906 -410.664152)
				(end 92.196666 -410.664152)
			)
		)
		(stroke
			(width 0)
			(type solid)
		)
		(fill yes)
		(layer "F.Cu")
		(net "GND")
	)
	(gr_poly
		(pts
			(arc
				(start 92.196666 -409.396184)
				(mid 91.830906 -409.396184)
				(end 92.196666 -409.396184)
			)
		)
		(stroke
			(width 0)
			(type solid)
		)
		(fill yes)
		(layer "F.Cu")
		(net "GND")
	)
	(gr_poly
		(pts
			(arc
				(start 92.196666 -407.638504)
				(mid 91.830906 -407.638504)
				(end 92.196666 -407.638504)
			)
		)
		(stroke
			(width 0)
			(type solid)
		)
		(fill yes)
		(layer "F.Cu")
		(net "GND")
	)
	(gr_poly
		(pts
			(arc
				(start 92.196666 -406.34666)
				(mid 91.830906 -406.34666)
				(end 92.196666 -406.34666)
			)
		)
		(stroke
			(width 0)
			(type solid)
		)
		(fill yes)
		(layer "F.Cu")
		(net "GND")
	)
	(gr_poly
		(pts
			(arc
				(start 93.13926 -112.944148)
				(mid 92.7735 -112.944148)
				(end 93.13926 -112.944148)
			)
		)
		(stroke
			(width 0)
			(type solid)
		)
		(fill yes)
		(layer "F.Cu")
		(net "GND")
	)
	(gr_poly
		(pts
			(arc
				(start 93.45549 -410.664152)
				(mid 93.08973 -410.664152)
				(end 93.45549 -410.664152)
			)
		)
		(stroke
			(width 0)
			(type solid)
		)
		(fill yes)
		(layer "F.Cu")
		(net "GND")
	)
	(gr_poly
		(pts
			(arc
				(start 93.45549 -409.396184)
				(mid 93.08973 -409.396184)
				(end 93.45549 -409.396184)
			)
		)
		(stroke
			(width 0)
			(type solid)
		)
		(fill yes)
		(layer "F.Cu")
		(net "GND")
	)
	(gr_poly
		(pts
			(arc
				(start 93.45549 -407.638504)
				(mid 93.08973 -407.638504)
				(end 93.45549 -407.638504)
			)
		)
		(stroke
			(width 0)
			(type solid)
		)
		(fill yes)
		(layer "F.Cu")
		(net "GND")
	)
	(gr_poly
		(pts
			(arc
				(start 93.45549 -406.34666)
				(mid 93.08973 -406.34666)
				(end 93.45549 -406.34666)
			)
		)
		(stroke
			(width 0)
			(type solid)
		)
		(fill yes)
		(layer "F.Cu")
		(net "GND")
	)
	(gr_poly
		(pts
			(arc
				(start 93.913706 -404.51786)
				(mid 93.547946 -404.51786)
				(end 93.913706 -404.51786)
			)
		)
		(stroke
			(width 0)
			(type solid)
		)
		(fill yes)
		(layer "F.Cu")
		(net "GND")
	)
	(gr_poly
		(pts
			(arc
				(start 93.913706 -403.249892)
				(mid 93.547946 -403.249892)
				(end 93.913706 -403.249892)
			)
		)
		(stroke
			(width 0)
			(type solid)
		)
		(fill yes)
		(layer "F.Cu")
		(net "GND")
	)
	(gr_poly
		(pts
			(arc
				(start 93.913706 -401.492212)
				(mid 93.547946 -401.492212)
				(end 93.913706 -401.492212)
			)
		)
		(stroke
			(width 0)
			(type solid)
		)
		(fill yes)
		(layer "F.Cu")
		(net "GND")
	)
	(gr_poly
		(pts
			(arc
				(start 93.913706 -400.224244)
				(mid 93.547946 -400.224244)
				(end 93.913706 -400.224244)
			)
		)
		(stroke
			(width 0)
			(type solid)
		)
		(fill yes)
		(layer "F.Cu")
		(net "GND")
	)
	(gr_poly
		(pts
			(arc
				(start 94.08414 -109.680248)
				(mid 93.71838 -109.680248)
				(end 94.08414 -109.680248)
			)
		)
		(stroke
			(width 0)
			(type solid)
		)
		(fill yes)
		(layer "F.Cu")
		(net "GND")
	)
	(gr_poly
		(pts
			(arc
				(start 94.97314 -111.338868)
				(mid 94.60738 -111.338868)
				(end 94.97314 -111.338868)
			)
		)
		(stroke
			(width 0)
			(type solid)
		)
		(fill yes)
		(layer "F.Cu")
		(net "GND")
	)
	(gr_poly
		(pts
			(arc
				(start 95.17253 -404.51786)
				(mid 94.80677 -404.51786)
				(end 95.17253 -404.51786)
			)
		)
		(stroke
			(width 0)
			(type solid)
		)
		(fill yes)
		(layer "F.Cu")
		(net "GND")
	)
	(gr_poly
		(pts
			(arc
				(start 95.17253 -403.249892)
				(mid 94.80677 -403.249892)
				(end 95.17253 -403.249892)
			)
		)
		(stroke
			(width 0)
			(type solid)
		)
		(fill yes)
		(layer "F.Cu")
		(net "GND")
	)
	(gr_poly
		(pts
			(arc
				(start 95.17253 -401.492212)
				(mid 94.80677 -401.492212)
				(end 95.17253 -401.492212)
			)
		)
		(stroke
			(width 0)
			(type solid)
		)
		(fill yes)
		(layer "F.Cu")
		(net "GND")
	)
	(gr_poly
		(pts
			(arc
				(start 95.17253 -400.224244)
				(mid 94.80677 -400.224244)
				(end 95.17253 -400.224244)
			)
		)
		(stroke
			(width 0)
			(type solid)
		)
		(fill yes)
		(layer "F.Cu")
		(net "GND")
	)
	(gr_poly
		(pts
			(arc
				(start 95.259906 -410.664152)
				(mid 94.894146 -410.664152)
				(end 95.259906 -410.664152)
			)
		)
		(stroke
			(width 0)
			(type solid)
		)
		(fill yes)
		(layer "F.Cu")
		(net "GND")
	)
	(gr_poly
		(pts
			(arc
				(start 95.259906 -409.396184)
				(mid 94.894146 -409.396184)
				(end 95.259906 -409.396184)
			)
		)
		(stroke
			(width 0)
			(type solid)
		)
		(fill yes)
		(layer "F.Cu")
		(net "GND")
	)
	(gr_poly
		(pts
			(arc
				(start 95.259906 -407.638504)
				(mid 94.894146 -407.638504)
				(end 95.259906 -407.638504)
			)
		)
		(stroke
			(width 0)
			(type solid)
		)
		(fill yes)
		(layer "F.Cu")
		(net "GND")
	)
	(gr_poly
		(pts
			(arc
				(start 95.259906 -406.370536)
				(mid 94.894146 -406.370536)
				(end 95.259906 -406.370536)
			)
		)
		(stroke
			(width 0)
			(type solid)
		)
		(fill yes)
		(layer "F.Cu")
		(net "GND")
	)
	(gr_poly
		(pts
			(arc
				(start 95.428054 -33.383982)
				(mid 95.062294 -33.383982)
				(end 95.428054 -33.383982)
			)
		)
		(stroke
			(width 0)
			(type solid)
		)
		(fill yes)
		(layer "F.Cu")
		(net "GND")
	)
	(gr_poly
		(pts
			(arc
				(start 95.5167 -30.780228)
				(mid 95.15094 -30.780228)
				(end 95.5167 -30.780228)
			)
		)
		(stroke
			(width 0)
			(type solid)
		)
		(fill yes)
		(layer "F.Cu")
		(net "GND")
	)
	(gr_poly
		(pts
			(arc
				(start 96.51873 -410.664152)
				(mid 96.15297 -410.664152)
				(end 96.51873 -410.664152)
			)
		)
		(stroke
			(width 0)
			(type solid)
		)
		(fill yes)
		(layer "F.Cu")
		(net "GND")
	)
	(gr_poly
		(pts
			(arc
				(start 96.51873 -409.396184)
				(mid 96.15297 -409.396184)
				(end 96.51873 -409.396184)
			)
		)
		(stroke
			(width 0)
			(type solid)
		)
		(fill yes)
		(layer "F.Cu")
		(net "GND")
	)
	(gr_poly
		(pts
			(arc
				(start 96.51873 -407.638504)
				(mid 96.15297 -407.638504)
				(end 96.51873 -407.638504)
			)
		)
		(stroke
			(width 0)
			(type solid)
		)
		(fill yes)
		(layer "F.Cu")
		(net "GND")
	)
	(gr_poly
		(pts
			(arc
				(start 96.51873 -406.370536)
				(mid 96.15297 -406.370536)
				(end 96.51873 -406.370536)
			)
		)
		(stroke
			(width 0)
			(type solid)
		)
		(fill yes)
		(layer "F.Cu")
		(net "GND")
	)
	(gr_poly
		(pts
			(arc
				(start 96.9391 -388.976108)
				(mid 96.57334 -388.976108)
				(end 96.9391 -388.976108)
			)
		)
		(stroke
			(width 0)
			(type solid)
		)
		(fill yes)
		(layer "F.Cu")
		(net "GND")
	)
	(gr_poly
		(pts
			(arc
				(start 97.42932 -119.664988)
				(mid 97.06356 -119.664988)
				(end 97.42932 -119.664988)
			)
		)
		(stroke
			(width 0)
			(type solid)
		)
		(fill yes)
		(layer "F.Cu")
		(net "GND")
	)
	(gr_poly
		(pts
			(arc
				(start 97.77222 -389.674608)
				(mid 97.40646 -389.674608)
				(end 97.77222 -389.674608)
			)
		)
		(stroke
			(width 0)
			(type solid)
		)
		(fill yes)
		(layer "F.Cu")
		(net "GND")
	)
	(gr_poly
		(pts
			(arc
				(start 97.84842 -111.420148)
				(mid 97.48266 -111.420148)
				(end 97.84842 -111.420148)
			)
		)
		(stroke
			(width 0)
			(type solid)
		)
		(fill yes)
		(layer "F.Cu")
		(net "GND")
	)
	(gr_poly
		(pts
			(arc
				(start 98.10496 -109.032548)
				(mid 97.7392 -109.032548)
				(end 98.10496 -109.032548)
			)
		)
		(stroke
			(width 0)
			(type solid)
		)
		(fill yes)
		(layer "F.Cu")
		(net "GND")
	)
	(gr_poly
		(pts
			(arc
				(start 98.1583 -117.074188)
				(mid 97.79254 -117.074188)
				(end 98.1583 -117.074188)
			)
		)
		(stroke
			(width 0)
			(type solid)
		)
		(fill yes)
		(layer "F.Cu")
		(net "GND")
	)
	(gr_poly
		(pts
			(arc
				(start 99.53498 -113.106708)
				(mid 99.16922 -113.106708)
				(end 99.53498 -113.106708)
			)
		)
		(stroke
			(width 0)
			(type solid)
		)
		(fill yes)
		(layer "F.Cu")
		(net "GND")
	)
	(gr_poly
		(pts
			(arc
				(start 99.58832 -125.910848)
				(mid 99.22256 -125.910848)
				(end 99.58832 -125.910848)
			)
		)
		(stroke
			(width 0)
			(type solid)
		)
		(fill yes)
		(layer "F.Cu")
		(net "GND")
	)
	(gr_poly
		(pts
			(arc
				(start 99.59086 -361.894628)
				(mid 99.2251 -361.894628)
				(end 99.59086 -361.894628)
			)
		)
		(stroke
			(width 0)
			(type solid)
		)
		(fill yes)
		(layer "F.Cu")
		(net "GND")
	)
	(gr_poly
		(pts
			(arc
				(start 100.2157 -15.763748)
				(mid 99.84994 -15.763748)
				(end 100.2157 -15.763748)
			)
		)
		(stroke
			(width 0)
			(type solid)
		)
		(fill yes)
		(layer "F.Cu")
		(net "GND")
	)
	(gr_poly
		(pts
			(arc
				(start 100.47732 -131.778248)
				(mid 100.11156 -131.778248)
				(end 100.47732 -131.778248)
			)
		)
		(stroke
			(width 0)
			(type solid)
		)
		(fill yes)
		(layer "F.Cu")
		(net "GND")
	)
	(gr_poly
		(pts
			(arc
				(start 100.49002 -415.87928)
				(mid 100.12426 -415.87928)
				(end 100.49002 -415.87928)
			)
		)
		(stroke
			(width 0)
			(type solid)
		)
		(fill yes)
		(layer "F.Cu")
		(net "GND")
	)
	(gr_poly
		(pts
			(arc
				(start 100.49002 -414.620456)
				(mid 100.12426 -414.620456)
				(end 100.49002 -414.620456)
			)
		)
		(stroke
			(width 0)
			(type solid)
		)
		(fill yes)
		(layer "F.Cu")
		(net "GND")
	)
	(gr_poly
		(pts
			(arc
				(start 100.91166 -120.040908)
				(mid 100.5459 -120.040908)
				(end 100.91166 -120.040908)
			)
		)
		(stroke
			(width 0)
			(type solid)
		)
		(fill yes)
		(layer "F.Cu")
		(net "GND")
	)
	(gr_poly
		(pts
			(arc
				(start 101.73208 -15.154148)
				(mid 101.36632 -15.154148)
				(end 101.73208 -15.154148)
			)
		)
		(stroke
			(width 0)
			(type solid)
		)
		(fill yes)
		(layer "F.Cu")
		(net "GND")
	)
	(gr_poly
		(pts
			(arc
				(start 102.489 -126.840488)
				(mid 102.12324 -126.840488)
				(end 102.489 -126.840488)
			)
		)
		(stroke
			(width 0)
			(type solid)
		)
		(fill yes)
		(layer "F.Cu")
		(net "GND")
	)
	(gr_poly
		(pts
			(arc
				(start 102.59568 -145.445988)
				(mid 102.22992 -145.445988)
				(end 102.59568 -145.445988)
			)
		)
		(stroke
			(width 0)
			(type solid)
		)
		(fill yes)
		(layer "F.Cu")
		(net "GND")
	)
	(gr_poly
		(pts
			(arc
				(start 102.61092 -111.595408)
				(mid 102.24516 -111.595408)
				(end 102.61092 -111.595408)
			)
		)
		(stroke
			(width 0)
			(type solid)
		)
		(fill yes)
		(layer "F.Cu")
		(net "GND")
	)
	(gr_poly
		(pts
			(arc
				(start 102.74808 -15.154148)
				(mid 102.38232 -15.154148)
				(end 102.74808 -15.154148)
			)
		)
		(stroke
			(width 0)
			(type solid)
		)
		(fill yes)
		(layer "F.Cu")
		(net "GND")
	)
	(gr_poly
		(pts
			(arc
				(start 103.68534 -55.095648)
				(mid 103.31958 -55.095648)
				(end 103.68534 -55.095648)
			)
		)
		(stroke
			(width 0)
			(type solid)
		)
		(fill yes)
		(layer "F.Cu")
		(net "GND")
	)
	(gr_poly
		(pts
			(arc
				(start 104.34574 -61.450728)
				(mid 103.97998 -61.450728)
				(end 104.34574 -61.450728)
			)
		)
		(stroke
			(width 0)
			(type solid)
		)
		(fill yes)
		(layer "F.Cu")
		(net "GND")
	)
	(gr_poly
		(pts
			(arc
				(start 105.03916 -58.908188)
				(mid 104.6734 -58.908188)
				(end 105.03916 -58.908188)
			)
		)
		(stroke
			(width 0)
			(type solid)
		)
		(fill yes)
		(layer "F.Cu")
		(net "GND")
	)
	(gr_poly
		(pts
			(arc
				(start 105.0671 -15.893288)
				(mid 104.70134 -15.893288)
				(end 105.0671 -15.893288)
			)
		)
		(stroke
			(width 0)
			(type solid)
		)
		(fill yes)
		(layer "F.Cu")
		(net "GND")
	)
	(gr_poly
		(pts
			(arc
				(start 105.6259 -121.971308)
				(mid 105.26014 -121.971308)
				(end 105.6259 -121.971308)
			)
		)
		(stroke
			(width 0)
			(type solid)
		)
		(fill yes)
		(layer "F.Cu")
		(net "GND")
	)
	(gr_poly
		(pts
			(arc
				(start 106.10342 -111.595408)
				(mid 105.73766 -111.595408)
				(end 106.10342 -111.595408)
			)
		)
		(stroke
			(width 0)
			(type solid)
		)
		(fill yes)
		(layer "F.Cu")
		(net "GND")
	)
	(gr_poly
		(pts
			(arc
				(start 107.04322 -61.590428)
				(mid 106.67746 -61.590428)
				(end 107.04322 -61.590428)
			)
		)
		(stroke
			(width 0)
			(type solid)
		)
		(fill yes)
		(layer "F.Cu")
		(net "GND")
	)
	(gr_poly
		(pts
			(arc
				(start 107.42422 -56.248808)
				(mid 107.05846 -56.248808)
				(end 107.42422 -56.248808)
			)
		)
		(stroke
			(width 0)
			(type solid)
		)
		(fill yes)
		(layer "F.Cu")
		(net "GND")
	)
	(gr_poly
		(pts
			(arc
				(start 108.1278 -111.623348)
				(mid 107.76204 -111.623348)
				(end 108.1278 -111.623348)
			)
		)
		(stroke
			(width 0)
			(type solid)
		)
		(fill yes)
		(layer "F.Cu")
		(net "GND")
	)
	(gr_poly
		(pts
			(arc
				(start 108.196126 -85.867494)
				(mid 107.830366 -85.867494)
				(end 108.196126 -85.867494)
			)
		)
		(stroke
			(width 0)
			(type solid)
		)
		(fill yes)
		(layer "F.Cu")
		(net "GND")
	)
	(gr_poly
		(pts
			(arc
				(start 108.84154 -127.218948)
				(mid 108.47578 -127.218948)
				(end 108.84154 -127.218948)
			)
		)
		(stroke
			(width 0)
			(type solid)
		)
		(fill yes)
		(layer "F.Cu")
		(net "GND")
	)
	(gr_poly
		(pts
			(arc
				(start 108.8644 -128.636268)
				(mid 108.49864 -128.636268)
				(end 108.8644 -128.636268)
			)
		)
		(stroke
			(width 0)
			(type solid)
		)
		(fill yes)
		(layer "F.Cu")
		(net "GND")
	)
	(gr_poly
		(pts
			(arc
				(start 109.02442 -131.023868)
				(mid 108.65866 -131.023868)
				(end 109.02442 -131.023868)
			)
		)
		(stroke
			(width 0)
			(type solid)
		)
		(fill yes)
		(layer "F.Cu")
		(net "GND")
	)
	(gr_poly
		(pts
			(arc
				(start 109.6518 -33.698688)
				(mid 109.28604 -33.698688)
				(end 109.6518 -33.698688)
			)
		)
		(stroke
			(width 0)
			(type solid)
		)
		(fill yes)
		(layer "F.Cu")
		(net "GND")
	)
	(gr_poly
		(pts
			(arc
				(start 114.58448 -86.058248)
				(mid 114.21872 -86.058248)
				(end 114.58448 -86.058248)
			)
		)
		(stroke
			(width 0)
			(type solid)
		)
		(fill yes)
		(layer "F.Cu")
		(net "GND")
	)
	(gr_poly
		(pts
			(arc
				(start 115.835684 -132.178806)
				(mid 115.469924 -132.178806)
				(end 115.835684 -132.178806)
			)
		)
		(stroke
			(width 0)
			(type solid)
		)
		(fill yes)
		(layer "F.Cu")
		(net "GND")
	)
	(gr_poly
		(pts
			(arc
				(start 117.09908 -77.130148)
				(mid 116.73332 -77.130148)
				(end 117.09908 -77.130148)
			)
		)
		(stroke
			(width 0)
			(type solid)
		)
		(fill yes)
		(layer "F.Cu")
		(net "GND")
	)
	(gr_poly
		(pts
			(arc
				(start 119.17934 -86.505288)
				(mid 118.81358 -86.505288)
				(end 119.17934 -86.505288)
			)
		)
		(stroke
			(width 0)
			(type solid)
		)
		(fill yes)
		(layer "F.Cu")
		(net "GND")
	)
	(gr_poly
		(pts
			(arc
				(start 120.05564 -151.773128)
				(mid 119.68988 -151.773128)
				(end 120.05564 -151.773128)
			)
		)
		(stroke
			(width 0)
			(type solid)
		)
		(fill yes)
		(layer "F.Cu")
		(net "GND")
	)
	(gr_poly
		(pts
			(arc
				(start 120.140222 -404.51786)
				(mid 119.774462 -404.51786)
				(end 120.140222 -404.51786)
			)
		)
		(stroke
			(width 0)
			(type solid)
		)
		(fill yes)
		(layer "F.Cu")
		(net "GND")
	)
	(gr_poly
		(pts
			(arc
				(start 120.140222 -403.249892)
				(mid 119.774462 -403.249892)
				(end 120.140222 -403.249892)
			)
		)
		(stroke
			(width 0)
			(type solid)
		)
		(fill yes)
		(layer "F.Cu")
		(net "GND")
	)
	(gr_poly
		(pts
			(arc
				(start 120.140222 -401.492212)
				(mid 119.774462 -401.492212)
				(end 120.140222 -401.492212)
			)
		)
		(stroke
			(width 0)
			(type solid)
		)
		(fill yes)
		(layer "F.Cu")
		(net "GND")
	)
	(gr_poly
		(pts
			(arc
				(start 120.140222 -400.224244)
				(mid 119.774462 -400.224244)
				(end 120.140222 -400.224244)
			)
		)
		(stroke
			(width 0)
			(type solid)
		)
		(fill yes)
		(layer "F.Cu")
		(net "GND")
	)
	(gr_poly
		(pts
			(arc
				(start 120.27408 -76.063348)
				(mid 119.90832 -76.063348)
				(end 120.27408 -76.063348)
			)
		)
		(stroke
			(width 0)
			(type solid)
		)
		(fill yes)
		(layer "F.Cu")
		(net "GND")
	)
	(gr_poly
		(pts
			(arc
				(start 120.54586 -128.681988)
				(mid 120.1801 -128.681988)
				(end 120.54586 -128.681988)
			)
		)
		(stroke
			(width 0)
			(type solid)
		)
		(fill yes)
		(layer "F.Cu")
		(net "GND")
	)
	(gr_poly
		(pts
			(arc
				(start 120.63476 -145.486628)
				(mid 120.269 -145.486628)
				(end 120.63476 -145.486628)
			)
		)
		(stroke
			(width 0)
			(type solid)
		)
		(fill yes)
		(layer "F.Cu")
		(net "GND")
	)
	(gr_poly
		(pts
			(arc
				(start 121.27484 -78.555088)
				(mid 120.90908 -78.555088)
				(end 121.27484 -78.555088)
			)
		)
		(stroke
			(width 0)
			(type solid)
		)
		(fill yes)
		(layer "F.Cu")
		(net "GND")
	)
	(gr_poly
		(pts
			(arc
				(start 121.399046 -404.51786)
				(mid 121.033286 -404.51786)
				(end 121.399046 -404.51786)
			)
		)
		(stroke
			(width 0)
			(type solid)
		)
		(fill yes)
		(layer "F.Cu")
		(net "GND")
	)
	(gr_poly
		(pts
			(arc
				(start 121.399046 -403.249892)
				(mid 121.033286 -403.249892)
				(end 121.399046 -403.249892)
			)
		)
		(stroke
			(width 0)
			(type solid)
		)
		(fill yes)
		(layer "F.Cu")
		(net "GND")
	)
	(gr_poly
		(pts
			(arc
				(start 121.399046 -401.492212)
				(mid 121.033286 -401.492212)
				(end 121.399046 -401.492212)
			)
		)
		(stroke
			(width 0)
			(type solid)
		)
		(fill yes)
		(layer "F.Cu")
		(net "GND")
	)
	(gr_poly
		(pts
			(arc
				(start 121.399046 -400.224244)
				(mid 121.033286 -400.224244)
				(end 121.399046 -400.224244)
			)
		)
		(stroke
			(width 0)
			(type solid)
		)
		(fill yes)
		(layer "F.Cu")
		(net "GND")
	)
	(gr_poly
		(pts
			(arc
				(start 121.486422 -410.664152)
				(mid 121.120662 -410.664152)
				(end 121.486422 -410.664152)
			)
		)
		(stroke
			(width 0)
			(type solid)
		)
		(fill yes)
		(layer "F.Cu")
		(net "GND")
	)
	(gr_poly
		(pts
			(arc
				(start 121.486422 -409.396184)
				(mid 121.120662 -409.396184)
				(end 121.486422 -409.396184)
			)
		)
		(stroke
			(width 0)
			(type solid)
		)
		(fill yes)
		(layer "F.Cu")
		(net "GND")
	)
	(gr_poly
		(pts
			(arc
				(start 121.486422 -407.638504)
				(mid 121.120662 -407.638504)
				(end 121.486422 -407.638504)
			)
		)
		(stroke
			(width 0)
			(type solid)
		)
		(fill yes)
		(layer "F.Cu")
		(net "GND")
	)
	(gr_poly
		(pts
			(arc
				(start 121.486422 -406.370536)
				(mid 121.120662 -406.370536)
				(end 121.486422 -406.370536)
			)
		)
		(stroke
			(width 0)
			(type solid)
		)
		(fill yes)
		(layer "F.Cu")
		(net "GND")
	)
	(gr_poly
		(pts
			(arc
				(start 122.03684 -76.251308)
				(mid 121.67108 -76.251308)
				(end 122.03684 -76.251308)
			)
		)
		(stroke
			(width 0)
			(type solid)
		)
		(fill yes)
		(layer "F.Cu")
		(net "GND")
	)
	(gr_poly
		(pts
			(arc
				(start 122.745246 -410.664152)
				(mid 122.379486 -410.664152)
				(end 122.745246 -410.664152)
			)
		)
		(stroke
			(width 0)
			(type solid)
		)
		(fill yes)
		(layer "F.Cu")
		(net "GND")
	)
	(gr_poly
		(pts
			(arc
				(start 122.745246 -409.396184)
				(mid 122.379486 -409.396184)
				(end 122.745246 -409.396184)
			)
		)
		(stroke
			(width 0)
			(type solid)
		)
		(fill yes)
		(layer "F.Cu")
		(net "GND")
	)
	(gr_poly
		(pts
			(arc
				(start 122.745246 -407.638504)
				(mid 122.379486 -407.638504)
				(end 122.745246 -407.638504)
			)
		)
		(stroke
			(width 0)
			(type solid)
		)
		(fill yes)
		(layer "F.Cu")
		(net "GND")
	)
	(gr_poly
		(pts
			(arc
				(start 122.745246 -406.370536)
				(mid 122.379486 -406.370536)
				(end 122.745246 -406.370536)
			)
		)
		(stroke
			(width 0)
			(type solid)
		)
		(fill yes)
		(layer "F.Cu")
		(net "GND")
	)
	(gr_poly
		(pts
			(arc
				(start 123.203462 -404.51786)
				(mid 122.837702 -404.51786)
				(end 123.203462 -404.51786)
			)
		)
		(stroke
			(width 0)
			(type solid)
		)
		(fill yes)
		(layer "F.Cu")
		(net "GND")
	)
	(gr_poly
		(pts
			(arc
				(start 123.203462 -403.249892)
				(mid 122.837702 -403.249892)
				(end 123.203462 -403.249892)
			)
		)
		(stroke
			(width 0)
			(type solid)
		)
		(fill yes)
		(layer "F.Cu")
		(net "GND")
	)
	(gr_poly
		(pts
			(arc
				(start 123.203462 -401.492212)
				(mid 122.837702 -401.492212)
				(end 123.203462 -401.492212)
			)
		)
		(stroke
			(width 0)
			(type solid)
		)
		(fill yes)
		(layer "F.Cu")
		(net "GND")
	)
	(gr_poly
		(pts
			(arc
				(start 123.203462 -400.224244)
				(mid 122.837702 -400.224244)
				(end 123.203462 -400.224244)
			)
		)
		(stroke
			(width 0)
			(type solid)
		)
		(fill yes)
		(layer "F.Cu")
		(net "GND")
	)
	(gr_poly
		(pts
			(arc
				(start 123.32208 -78.069948)
				(mid 122.95632 -78.069948)
				(end 123.32208 -78.069948)
			)
		)
		(stroke
			(width 0)
			(type solid)
		)
		(fill yes)
		(layer "F.Cu")
		(net "GND")
	)
	(gr_poly
		(pts
			(arc
				(start 124.462286 -404.51786)
				(mid 124.096526 -404.51786)
				(end 124.462286 -404.51786)
			)
		)
		(stroke
			(width 0)
			(type solid)
		)
		(fill yes)
		(layer "F.Cu")
		(net "GND")
	)
	(gr_poly
		(pts
			(arc
				(start 124.462286 -403.249892)
				(mid 124.096526 -403.249892)
				(end 124.462286 -403.249892)
			)
		)
		(stroke
			(width 0)
			(type solid)
		)
		(fill yes)
		(layer "F.Cu")
		(net "GND")
	)
	(gr_poly
		(pts
			(arc
				(start 124.462286 -401.492212)
				(mid 124.096526 -401.492212)
				(end 124.462286 -401.492212)
			)
		)
		(stroke
			(width 0)
			(type solid)
		)
		(fill yes)
		(layer "F.Cu")
		(net "GND")
	)
	(gr_poly
		(pts
			(arc
				(start 124.462286 -400.224244)
				(mid 124.096526 -400.224244)
				(end 124.462286 -400.224244)
			)
		)
		(stroke
			(width 0)
			(type solid)
		)
		(fill yes)
		(layer "F.Cu")
		(net "GND")
	)
	(gr_poly
		(pts
			(arc
				(start 124.549662 -410.664152)
				(mid 124.183902 -410.664152)
				(end 124.549662 -410.664152)
			)
		)
		(stroke
			(width 0)
			(type solid)
		)
		(fill yes)
		(layer "F.Cu")
		(net "GND")
	)
	(gr_poly
		(pts
			(arc
				(start 124.549662 -409.396184)
				(mid 124.183902 -409.396184)
				(end 124.549662 -409.396184)
			)
		)
		(stroke
			(width 0)
			(type solid)
		)
		(fill yes)
		(layer "F.Cu")
		(net "GND")
	)
	(gr_poly
		(pts
			(arc
				(start 124.549662 -407.638504)
				(mid 124.183902 -407.638504)
				(end 124.549662 -407.638504)
			)
		)
		(stroke
			(width 0)
			(type solid)
		)
		(fill yes)
		(layer "F.Cu")
		(net "GND")
	)
	(gr_poly
		(pts
			(arc
				(start 124.549662 -406.370536)
				(mid 124.183902 -406.370536)
				(end 124.549662 -406.370536)
			)
		)
		(stroke
			(width 0)
			(type solid)
		)
		(fill yes)
		(layer "F.Cu")
		(net "GND")
	)
	(gr_poly
		(pts
			(arc
				(start 124.6378 -63.630048)
				(mid 124.27204 -63.630048)
				(end 124.6378 -63.630048)
			)
		)
		(stroke
			(width 0)
			(type solid)
		)
		(fill yes)
		(layer "F.Cu")
		(net "GND")
	)
	(gr_poly
		(pts
			(arc
				(start 125.169676 -76.277724)
				(mid 124.803916 -76.277724)
				(end 125.169676 -76.277724)
			)
		)
		(stroke
			(width 0)
			(type solid)
		)
		(fill yes)
		(layer "F.Cu")
		(net "GND")
	)
	(gr_poly
		(pts
			(arc
				(start 125.808486 -410.664152)
				(mid 125.442726 -410.664152)
				(end 125.808486 -410.664152)
			)
		)
		(stroke
			(width 0)
			(type solid)
		)
		(fill yes)
		(layer "F.Cu")
		(net "GND")
	)
	(gr_poly
		(pts
			(arc
				(start 125.808486 -409.396184)
				(mid 125.442726 -409.396184)
				(end 125.808486 -409.396184)
			)
		)
		(stroke
			(width 0)
			(type solid)
		)
		(fill yes)
		(layer "F.Cu")
		(net "GND")
	)
	(gr_poly
		(pts
			(arc
				(start 125.808486 -407.638504)
				(mid 125.442726 -407.638504)
				(end 125.808486 -407.638504)
			)
		)
		(stroke
			(width 0)
			(type solid)
		)
		(fill yes)
		(layer "F.Cu")
		(net "GND")
	)
	(gr_poly
		(pts
			(arc
				(start 125.808486 -406.370536)
				(mid 125.442726 -406.370536)
				(end 125.808486 -406.370536)
			)
		)
		(stroke
			(width 0)
			(type solid)
		)
		(fill yes)
		(layer "F.Cu")
		(net "GND")
	)
	(gr_poly
		(pts
			(arc
				(start 126.266702 -404.51786)
				(mid 125.900942 -404.51786)
				(end 126.266702 -404.51786)
			)
		)
		(stroke
			(width 0)
			(type solid)
		)
		(fill yes)
		(layer "F.Cu")
		(net "GND")
	)
	(gr_poly
		(pts
			(arc
				(start 126.266702 -403.249892)
				(mid 125.900942 -403.249892)
				(end 126.266702 -403.249892)
			)
		)
		(stroke
			(width 0)
			(type solid)
		)
		(fill yes)
		(layer "F.Cu")
		(net "GND")
	)
	(gr_poly
		(pts
			(arc
				(start 126.266702 -401.492212)
				(mid 125.900942 -401.492212)
				(end 126.266702 -401.492212)
			)
		)
		(stroke
			(width 0)
			(type solid)
		)
		(fill yes)
		(layer "F.Cu")
		(net "GND")
	)
	(gr_poly
		(pts
			(arc
				(start 126.266702 -400.224244)
				(mid 125.900942 -400.224244)
				(end 126.266702 -400.224244)
			)
		)
		(stroke
			(width 0)
			(type solid)
		)
		(fill yes)
		(layer "F.Cu")
		(net "GND")
	)
	(gr_poly
		(pts
			(arc
				(start 127.525526 -404.51786)
				(mid 127.159766 -404.51786)
				(end 127.525526 -404.51786)
			)
		)
		(stroke
			(width 0)
			(type solid)
		)
		(fill yes)
		(layer "F.Cu")
		(net "GND")
	)
	(gr_poly
		(pts
			(arc
				(start 127.525526 -403.249892)
				(mid 127.159766 -403.249892)
				(end 127.525526 -403.249892)
			)
		)
		(stroke
			(width 0)
			(type solid)
		)
		(fill yes)
		(layer "F.Cu")
		(net "GND")
	)
	(gr_poly
		(pts
			(arc
				(start 127.525526 -401.492212)
				(mid 127.159766 -401.492212)
				(end 127.525526 -401.492212)
			)
		)
		(stroke
			(width 0)
			(type solid)
		)
		(fill yes)
		(layer "F.Cu")
		(net "GND")
	)
	(gr_poly
		(pts
			(arc
				(start 127.525526 -400.224244)
				(mid 127.159766 -400.224244)
				(end 127.525526 -400.224244)
			)
		)
		(stroke
			(width 0)
			(type solid)
		)
		(fill yes)
		(layer "F.Cu")
		(net "GND")
	)
	(gr_poly
		(pts
			(arc
				(start 127.612902 -410.664152)
				(mid 127.247142 -410.664152)
				(end 127.612902 -410.664152)
			)
		)
		(stroke
			(width 0)
			(type solid)
		)
		(fill yes)
		(layer "F.Cu")
		(net "GND")
	)
	(gr_poly
		(pts
			(arc
				(start 127.612902 -409.396184)
				(mid 127.247142 -409.396184)
				(end 127.612902 -409.396184)
			)
		)
		(stroke
			(width 0)
			(type solid)
		)
		(fill yes)
		(layer "F.Cu")
		(net "GND")
	)
	(gr_poly
		(pts
			(arc
				(start 127.612902 -407.638504)
				(mid 127.247142 -407.638504)
				(end 127.612902 -407.638504)
			)
		)
		(stroke
			(width 0)
			(type solid)
		)
		(fill yes)
		(layer "F.Cu")
		(net "GND")
	)
	(gr_poly
		(pts
			(arc
				(start 127.612902 -406.370536)
				(mid 127.247142 -406.370536)
				(end 127.612902 -406.370536)
			)
		)
		(stroke
			(width 0)
			(type solid)
		)
		(fill yes)
		(layer "F.Cu")
		(net "GND")
	)
	(gr_poly
		(pts
			(arc
				(start 128.68148 -79.136748)
				(mid 128.31572 -79.136748)
				(end 128.68148 -79.136748)
			)
		)
		(stroke
			(width 0)
			(type solid)
		)
		(fill yes)
		(layer "F.Cu")
		(net "GND")
	)
	(gr_poly
		(pts
			(arc
				(start 128.871726 -410.664152)
				(mid 128.505966 -410.664152)
				(end 128.871726 -410.664152)
			)
		)
		(stroke
			(width 0)
			(type solid)
		)
		(fill yes)
		(layer "F.Cu")
		(net "GND")
	)
	(gr_poly
		(pts
			(arc
				(start 128.871726 -409.396184)
				(mid 128.505966 -409.396184)
				(end 128.871726 -409.396184)
			)
		)
		(stroke
			(width 0)
			(type solid)
		)
		(fill yes)
		(layer "F.Cu")
		(net "GND")
	)
	(gr_poly
		(pts
			(arc
				(start 128.871726 -407.638504)
				(mid 128.505966 -407.638504)
				(end 128.871726 -407.638504)
			)
		)
		(stroke
			(width 0)
			(type solid)
		)
		(fill yes)
		(layer "F.Cu")
		(net "GND")
	)
	(gr_poly
		(pts
			(arc
				(start 128.871726 -406.370536)
				(mid 128.505966 -406.370536)
				(end 128.871726 -406.370536)
			)
		)
		(stroke
			(width 0)
			(type solid)
		)
		(fill yes)
		(layer "F.Cu")
		(net "GND")
	)
	(gr_poly
		(pts
			(arc
				(start 129.329942 -404.51786)
				(mid 128.964182 -404.51786)
				(end 129.329942 -404.51786)
			)
		)
		(stroke
			(width 0)
			(type solid)
		)
		(fill yes)
		(layer "F.Cu")
		(net "GND")
	)
	(gr_poly
		(pts
			(arc
				(start 129.329942 -403.249892)
				(mid 128.964182 -403.249892)
				(end 129.329942 -403.249892)
			)
		)
		(stroke
			(width 0)
			(type solid)
		)
		(fill yes)
		(layer "F.Cu")
		(net "GND")
	)
	(gr_poly
		(pts
			(arc
				(start 129.329942 -401.492212)
				(mid 128.964182 -401.492212)
				(end 129.329942 -401.492212)
			)
		)
		(stroke
			(width 0)
			(type solid)
		)
		(fill yes)
		(layer "F.Cu")
		(net "GND")
	)
	(gr_poly
		(pts
			(arc
				(start 129.329942 -400.224244)
				(mid 128.964182 -400.224244)
				(end 129.329942 -400.224244)
			)
		)
		(stroke
			(width 0)
			(type solid)
		)
		(fill yes)
		(layer "F.Cu")
		(net "GND")
	)
	(gr_poly
		(pts
			(arc
				(start 129.91084 -84.478368)
				(mid 129.54508 -84.478368)
				(end 129.91084 -84.478368)
			)
		)
		(stroke
			(width 0)
			(type solid)
		)
		(fill yes)
		(layer "F.Cu")
		(net "GND")
	)
	(gr_poly
		(pts
			(arc
				(start 130.588766 -404.51786)
				(mid 130.223006 -404.51786)
				(end 130.588766 -404.51786)
			)
		)
		(stroke
			(width 0)
			(type solid)
		)
		(fill yes)
		(layer "F.Cu")
		(net "GND")
	)
	(gr_poly
		(pts
			(arc
				(start 130.588766 -403.249892)
				(mid 130.223006 -403.249892)
				(end 130.588766 -403.249892)
			)
		)
		(stroke
			(width 0)
			(type solid)
		)
		(fill yes)
		(layer "F.Cu")
		(net "GND")
	)
	(gr_poly
		(pts
			(arc
				(start 130.588766 -401.492212)
				(mid 130.223006 -401.492212)
				(end 130.588766 -401.492212)
			)
		)
		(stroke
			(width 0)
			(type solid)
		)
		(fill yes)
		(layer "F.Cu")
		(net "GND")
	)
	(gr_poly
		(pts
			(arc
				(start 130.588766 -400.224244)
				(mid 130.223006 -400.224244)
				(end 130.588766 -400.224244)
			)
		)
		(stroke
			(width 0)
			(type solid)
		)
		(fill yes)
		(layer "F.Cu")
		(net "GND")
	)
	(gr_poly
		(pts
			(arc
				(start 130.676142 -410.664152)
				(mid 130.310382 -410.664152)
				(end 130.676142 -410.664152)
			)
		)
		(stroke
			(width 0)
			(type solid)
		)
		(fill yes)
		(layer "F.Cu")
		(net "GND")
	)
	(gr_poly
		(pts
			(arc
				(start 130.676142 -409.396184)
				(mid 130.310382 -409.396184)
				(end 130.676142 -409.396184)
			)
		)
		(stroke
			(width 0)
			(type solid)
		)
		(fill yes)
		(layer "F.Cu")
		(net "GND")
	)
	(gr_poly
		(pts
			(arc
				(start 130.676142 -407.638504)
				(mid 130.310382 -407.638504)
				(end 130.676142 -407.638504)
			)
		)
		(stroke
			(width 0)
			(type solid)
		)
		(fill yes)
		(layer "F.Cu")
		(net "GND")
	)
	(gr_poly
		(pts
			(arc
				(start 130.676142 -406.370536)
				(mid 130.310382 -406.370536)
				(end 130.676142 -406.370536)
			)
		)
		(stroke
			(width 0)
			(type solid)
		)
		(fill yes)
		(layer "F.Cu")
		(net "GND")
	)
	(gr_poly
		(pts
			(arc
				(start 131.934966 -410.664152)
				(mid 131.569206 -410.664152)
				(end 131.934966 -410.664152)
			)
		)
		(stroke
			(width 0)
			(type solid)
		)
		(fill yes)
		(layer "F.Cu")
		(net "GND")
	)
	(gr_poly
		(pts
			(arc
				(start 131.934966 -409.396184)
				(mid 131.569206 -409.396184)
				(end 131.934966 -409.396184)
			)
		)
		(stroke
			(width 0)
			(type solid)
		)
		(fill yes)
		(layer "F.Cu")
		(net "GND")
	)
	(gr_poly
		(pts
			(arc
				(start 131.934966 -407.638504)
				(mid 131.569206 -407.638504)
				(end 131.934966 -407.638504)
			)
		)
		(stroke
			(width 0)
			(type solid)
		)
		(fill yes)
		(layer "F.Cu")
		(net "GND")
	)
	(gr_poly
		(pts
			(arc
				(start 131.934966 -406.370536)
				(mid 131.569206 -406.370536)
				(end 131.934966 -406.370536)
			)
		)
		(stroke
			(width 0)
			(type solid)
		)
		(fill yes)
		(layer "F.Cu")
		(net "GND")
	)
	(gr_poly
		(pts
			(arc
				(start 132.393182 -404.51786)
				(mid 132.027422 -404.51786)
				(end 132.393182 -404.51786)
			)
		)
		(stroke
			(width 0)
			(type solid)
		)
		(fill yes)
		(layer "F.Cu")
		(net "GND")
	)
	(gr_poly
		(pts
			(arc
				(start 132.393182 -403.249892)
				(mid 132.027422 -403.249892)
				(end 132.393182 -403.249892)
			)
		)
		(stroke
			(width 0)
			(type solid)
		)
		(fill yes)
		(layer "F.Cu")
		(net "GND")
	)
	(gr_poly
		(pts
			(arc
				(start 132.393182 -401.492212)
				(mid 132.027422 -401.492212)
				(end 132.393182 -401.492212)
			)
		)
		(stroke
			(width 0)
			(type solid)
		)
		(fill yes)
		(layer "F.Cu")
		(net "GND")
	)
	(gr_poly
		(pts
			(arc
				(start 132.393182 -400.224244)
				(mid 132.027422 -400.224244)
				(end 132.393182 -400.224244)
			)
		)
		(stroke
			(width 0)
			(type solid)
		)
		(fill yes)
		(layer "F.Cu")
		(net "GND")
	)
	(gr_poly
		(pts
			(arc
				(start 132.44322 -150.508208)
				(mid 132.07746 -150.508208)
				(end 132.44322 -150.508208)
			)
		)
		(stroke
			(width 0)
			(type solid)
		)
		(fill yes)
		(layer "F.Cu")
		(net "GND")
	)
	(gr_poly
		(pts
			(arc
				(start 132.659374 -139.908026)
				(mid 132.293614 -139.908026)
				(end 132.659374 -139.908026)
			)
		)
		(stroke
			(width 0)
			(type solid)
		)
		(fill yes)
		(layer "F.Cu")
		(net "GND")
	)
	(gr_poly
		(pts
			(arc
				(start 133.19252 -82.098388)
				(mid 132.82676 -82.098388)
				(end 133.19252 -82.098388)
			)
		)
		(stroke
			(width 0)
			(type solid)
		)
		(fill yes)
		(layer "F.Cu")
		(net "GND")
	)
	(gr_poly
		(pts
			(arc
				(start 133.652006 -404.51786)
				(mid 133.286246 -404.51786)
				(end 133.652006 -404.51786)
			)
		)
		(stroke
			(width 0)
			(type solid)
		)
		(fill yes)
		(layer "F.Cu")
		(net "GND")
	)
	(gr_poly
		(pts
			(arc
				(start 133.652006 -403.249892)
				(mid 133.286246 -403.249892)
				(end 133.652006 -403.249892)
			)
		)
		(stroke
			(width 0)
			(type solid)
		)
		(fill yes)
		(layer "F.Cu")
		(net "GND")
	)
	(gr_poly
		(pts
			(arc
				(start 133.652006 -401.492212)
				(mid 133.286246 -401.492212)
				(end 133.652006 -401.492212)
			)
		)
		(stroke
			(width 0)
			(type solid)
		)
		(fill yes)
		(layer "F.Cu")
		(net "GND")
	)
	(gr_poly
		(pts
			(arc
				(start 133.652006 -400.224244)
				(mid 133.286246 -400.224244)
				(end 133.652006 -400.224244)
			)
		)
		(stroke
			(width 0)
			(type solid)
		)
		(fill yes)
		(layer "F.Cu")
		(net "GND")
	)
	(gr_poly
		(pts
			(arc
				(start 133.739382 -410.664152)
				(mid 133.373622 -410.664152)
				(end 133.739382 -410.664152)
			)
		)
		(stroke
			(width 0)
			(type solid)
		)
		(fill yes)
		(layer "F.Cu")
		(net "GND")
	)
	(gr_poly
		(pts
			(arc
				(start 133.739382 -409.396184)
				(mid 133.373622 -409.396184)
				(end 133.739382 -409.396184)
			)
		)
		(stroke
			(width 0)
			(type solid)
		)
		(fill yes)
		(layer "F.Cu")
		(net "GND")
	)
	(gr_poly
		(pts
			(arc
				(start 133.739382 -407.638504)
				(mid 133.373622 -407.638504)
				(end 133.739382 -407.638504)
			)
		)
		(stroke
			(width 0)
			(type solid)
		)
		(fill yes)
		(layer "F.Cu")
		(net "GND")
	)
	(gr_poly
		(pts
			(arc
				(start 133.739382 -406.370536)
				(mid 133.373622 -406.370536)
				(end 133.739382 -406.370536)
			)
		)
		(stroke
			(width 0)
			(type solid)
		)
		(fill yes)
		(layer "F.Cu")
		(net "GND")
	)
	(gr_poly
		(pts
			(arc
				(start 133.858 -144.556988)
				(mid 133.49224 -144.556988)
				(end 133.858 -144.556988)
			)
		)
		(stroke
			(width 0)
			(type solid)
		)
		(fill yes)
		(layer "F.Cu")
		(net "GND")
	)
	(gr_poly
		(pts
			(arc
				(start 134.609586 -25.399238)
				(mid 134.243826 -25.399238)
				(end 134.609586 -25.399238)
			)
		)
		(stroke
			(width 0)
			(type solid)
		)
		(fill yes)
		(layer "F.Cu")
		(net "GND")
	)
	(gr_poly
		(pts
			(arc
				(start 134.609586 -23.599394)
				(mid 134.243826 -23.599394)
				(end 134.609586 -23.599394)
			)
		)
		(stroke
			(width 0)
			(type solid)
		)
		(fill yes)
		(layer "F.Cu")
		(net "GND")
	)
	(gr_poly
		(pts
			(arc
				(start 134.998206 -410.664152)
				(mid 134.632446 -410.664152)
				(end 134.998206 -410.664152)
			)
		)
		(stroke
			(width 0)
			(type solid)
		)
		(fill yes)
		(layer "F.Cu")
		(net "GND")
	)
	(gr_poly
		(pts
			(arc
				(start 134.998206 -409.396184)
				(mid 134.632446 -409.396184)
				(end 134.998206 -409.396184)
			)
		)
		(stroke
			(width 0)
			(type solid)
		)
		(fill yes)
		(layer "F.Cu")
		(net "GND")
	)
	(gr_poly
		(pts
			(arc
				(start 134.998206 -407.638504)
				(mid 134.632446 -407.638504)
				(end 134.998206 -407.638504)
			)
		)
		(stroke
			(width 0)
			(type solid)
		)
		(fill yes)
		(layer "F.Cu")
		(net "GND")
	)
	(gr_poly
		(pts
			(arc
				(start 134.998206 -406.370536)
				(mid 134.632446 -406.370536)
				(end 134.998206 -406.370536)
			)
		)
		(stroke
			(width 0)
			(type solid)
		)
		(fill yes)
		(layer "F.Cu")
		(net "GND")
	)
	(gr_poly
		(pts
			(arc
				(start 135.456422 -404.51786)
				(mid 135.090662 -404.51786)
				(end 135.456422 -404.51786)
			)
		)
		(stroke
			(width 0)
			(type solid)
		)
		(fill yes)
		(layer "F.Cu")
		(net "GND")
	)
	(gr_poly
		(pts
			(arc
				(start 135.456422 -403.249892)
				(mid 135.090662 -403.249892)
				(end 135.456422 -403.249892)
			)
		)
		(stroke
			(width 0)
			(type solid)
		)
		(fill yes)
		(layer "F.Cu")
		(net "GND")
	)
	(gr_poly
		(pts
			(arc
				(start 135.456422 -401.492212)
				(mid 135.090662 -401.492212)
				(end 135.456422 -401.492212)
			)
		)
		(stroke
			(width 0)
			(type solid)
		)
		(fill yes)
		(layer "F.Cu")
		(net "GND")
	)
	(gr_poly
		(pts
			(arc
				(start 135.456422 -400.224244)
				(mid 135.090662 -400.224244)
				(end 135.456422 -400.224244)
			)
		)
		(stroke
			(width 0)
			(type solid)
		)
		(fill yes)
		(layer "F.Cu")
		(net "GND")
	)
	(gr_poly
		(pts
			(arc
				(start 136.14654 -145.524728)
				(mid 135.78078 -145.524728)
				(end 136.14654 -145.524728)
			)
		)
		(stroke
			(width 0)
			(type solid)
		)
		(fill yes)
		(layer "F.Cu")
		(net "GND")
	)
	(gr_poly
		(pts
			(arc
				(start 136.2329 -77.876908)
				(mid 135.86714 -77.876908)
				(end 136.2329 -77.876908)
			)
		)
		(stroke
			(width 0)
			(type solid)
		)
		(fill yes)
		(layer "F.Cu")
		(net "GND")
	)
	(gr_poly
		(pts
			(arc
				(start 136.715246 -404.51786)
				(mid 136.349486 -404.51786)
				(end 136.715246 -404.51786)
			)
		)
		(stroke
			(width 0)
			(type solid)
		)
		(fill yes)
		(layer "F.Cu")
		(net "GND")
	)
	(gr_poly
		(pts
			(arc
				(start 136.715246 -403.249892)
				(mid 136.349486 -403.249892)
				(end 136.715246 -403.249892)
			)
		)
		(stroke
			(width 0)
			(type solid)
		)
		(fill yes)
		(layer "F.Cu")
		(net "GND")
	)
	(gr_poly
		(pts
			(arc
				(start 136.715246 -401.492212)
				(mid 136.349486 -401.492212)
				(end 136.715246 -401.492212)
			)
		)
		(stroke
			(width 0)
			(type solid)
		)
		(fill yes)
		(layer "F.Cu")
		(net "GND")
	)
	(gr_poly
		(pts
			(arc
				(start 136.715246 -400.224244)
				(mid 136.349486 -400.224244)
				(end 136.715246 -400.224244)
			)
		)
		(stroke
			(width 0)
			(type solid)
		)
		(fill yes)
		(layer "F.Cu")
		(net "GND")
	)
	(gr_poly
		(pts
			(arc
				(start 136.802622 -410.664152)
				(mid 136.436862 -410.664152)
				(end 136.802622 -410.664152)
			)
		)
		(stroke
			(width 0)
			(type solid)
		)
		(fill yes)
		(layer "F.Cu")
		(net "GND")
	)
	(gr_poly
		(pts
			(arc
				(start 136.802622 -409.396184)
				(mid 136.436862 -409.396184)
				(end 136.802622 -409.396184)
			)
		)
		(stroke
			(width 0)
			(type solid)
		)
		(fill yes)
		(layer "F.Cu")
		(net "GND")
	)
	(gr_poly
		(pts
			(arc
				(start 136.802622 -407.638504)
				(mid 136.436862 -407.638504)
				(end 136.802622 -407.638504)
			)
		)
		(stroke
			(width 0)
			(type solid)
		)
		(fill yes)
		(layer "F.Cu")
		(net "GND")
	)
	(gr_poly
		(pts
			(arc
				(start 136.802622 -406.370536)
				(mid 136.436862 -406.370536)
				(end 136.802622 -406.370536)
			)
		)
		(stroke
			(width 0)
			(type solid)
		)
		(fill yes)
		(layer "F.Cu")
		(net "GND")
	)
	(gr_poly
		(pts
			(arc
				(start 138.053572 -51.472084)
				(mid 137.687812 -51.472084)
				(end 138.053572 -51.472084)
			)
		)
		(stroke
			(width 0)
			(type solid)
		)
		(fill yes)
		(layer "F.Cu")
		(net "GND")
	)
	(gr_poly
		(pts
			(arc
				(start 138.061446 -410.664152)
				(mid 137.695686 -410.664152)
				(end 138.061446 -410.664152)
			)
		)
		(stroke
			(width 0)
			(type solid)
		)
		(fill yes)
		(layer "F.Cu")
		(net "GND")
	)
	(gr_poly
		(pts
			(arc
				(start 138.061446 -409.396184)
				(mid 137.695686 -409.396184)
				(end 138.061446 -409.396184)
			)
		)
		(stroke
			(width 0)
			(type solid)
		)
		(fill yes)
		(layer "F.Cu")
		(net "GND")
	)
	(gr_poly
		(pts
			(arc
				(start 138.061446 -407.638504)
				(mid 137.695686 -407.638504)
				(end 138.061446 -407.638504)
			)
		)
		(stroke
			(width 0)
			(type solid)
		)
		(fill yes)
		(layer "F.Cu")
		(net "GND")
	)
	(gr_poly
		(pts
			(arc
				(start 138.061446 -406.370536)
				(mid 137.695686 -406.370536)
				(end 138.061446 -406.370536)
			)
		)
		(stroke
			(width 0)
			(type solid)
		)
		(fill yes)
		(layer "F.Cu")
		(net "GND")
	)
	(gr_poly
		(pts
			(arc
				(start 138.21918 -149.926548)
				(mid 137.85342 -149.926548)
				(end 138.21918 -149.926548)
			)
		)
		(stroke
			(width 0)
			(type solid)
		)
		(fill yes)
		(layer "F.Cu")
		(net "GND")
	)
	(gr_poly
		(pts
			(arc
				(start 138.519662 -404.51786)
				(mid 138.153902 -404.51786)
				(end 138.519662 -404.51786)
			)
		)
		(stroke
			(width 0)
			(type solid)
		)
		(fill yes)
		(layer "F.Cu")
		(net "GND")
	)
	(gr_poly
		(pts
			(arc
				(start 138.519662 -403.249892)
				(mid 138.153902 -403.249892)
				(end 138.519662 -403.249892)
			)
		)
		(stroke
			(width 0)
			(type solid)
		)
		(fill yes)
		(layer "F.Cu")
		(net "GND")
	)
	(gr_poly
		(pts
			(arc
				(start 138.519662 -401.492212)
				(mid 138.153902 -401.492212)
				(end 138.519662 -401.492212)
			)
		)
		(stroke
			(width 0)
			(type solid)
		)
		(fill yes)
		(layer "F.Cu")
		(net "GND")
	)
	(gr_poly
		(pts
			(arc
				(start 138.519662 -400.200368)
				(mid 138.153902 -400.200368)
				(end 138.519662 -400.200368)
			)
		)
		(stroke
			(width 0)
			(type solid)
		)
		(fill yes)
		(layer "F.Cu")
		(net "GND")
	)
	(gr_poly
		(pts
			(arc
				(start 138.926316 -19.670522)
				(mid 138.560556 -19.670522)
				(end 138.926316 -19.670522)
			)
		)
		(stroke
			(width 0)
			(type solid)
		)
		(fill yes)
		(layer "F.Cu")
		(net "GND")
	)
	(gr_poly
		(pts
			(arc
				(start 139.778486 -404.51786)
				(mid 139.412726 -404.51786)
				(end 139.778486 -404.51786)
			)
		)
		(stroke
			(width 0)
			(type solid)
		)
		(fill yes)
		(layer "F.Cu")
		(net "GND")
	)
	(gr_poly
		(pts
			(arc
				(start 139.778486 -403.249892)
				(mid 139.412726 -403.249892)
				(end 139.778486 -403.249892)
			)
		)
		(stroke
			(width 0)
			(type solid)
		)
		(fill yes)
		(layer "F.Cu")
		(net "GND")
	)
	(gr_poly
		(pts
			(arc
				(start 139.778486 -401.492212)
				(mid 139.412726 -401.492212)
				(end 139.778486 -401.492212)
			)
		)
		(stroke
			(width 0)
			(type solid)
		)
		(fill yes)
		(layer "F.Cu")
		(net "GND")
	)
	(gr_poly
		(pts
			(arc
				(start 139.778486 -400.200368)
				(mid 139.412726 -400.200368)
				(end 139.778486 -400.200368)
			)
		)
		(stroke
			(width 0)
			(type solid)
		)
		(fill yes)
		(layer "F.Cu")
		(net "GND")
	)
	(gr_poly
		(pts
			(arc
				(start 139.865862 -410.664152)
				(mid 139.500102 -410.664152)
				(end 139.865862 -410.664152)
			)
		)
		(stroke
			(width 0)
			(type solid)
		)
		(fill yes)
		(layer "F.Cu")
		(net "GND")
	)
	(gr_poly
		(pts
			(arc
				(start 139.865862 -409.396184)
				(mid 139.500102 -409.396184)
				(end 139.865862 -409.396184)
			)
		)
		(stroke
			(width 0)
			(type solid)
		)
		(fill yes)
		(layer "F.Cu")
		(net "GND")
	)
	(gr_poly
		(pts
			(arc
				(start 139.865862 -407.638504)
				(mid 139.500102 -407.638504)
				(end 139.865862 -407.638504)
			)
		)
		(stroke
			(width 0)
			(type solid)
		)
		(fill yes)
		(layer "F.Cu")
		(net "GND")
	)
	(gr_poly
		(pts
			(arc
				(start 139.865862 -406.34666)
				(mid 139.500102 -406.34666)
				(end 139.865862 -406.34666)
			)
		)
		(stroke
			(width 0)
			(type solid)
		)
		(fill yes)
		(layer "F.Cu")
		(net "GND")
	)
	(gr_poly
		(pts
			(arc
				(start 140.72616 -19.670522)
				(mid 140.3604 -19.670522)
				(end 140.72616 -19.670522)
			)
		)
		(stroke
			(width 0)
			(type solid)
		)
		(fill yes)
		(layer "F.Cu")
		(net "GND")
	)
	(gr_poly
		(pts
			(arc
				(start 140.811758 -49.240948)
				(mid 140.445998 -49.240948)
				(end 140.811758 -49.240948)
			)
		)
		(stroke
			(width 0)
			(type solid)
		)
		(fill yes)
		(layer "F.Cu")
		(net "GND")
	)
	(gr_poly
		(pts
			(arc
				(start 141.124686 -410.664152)
				(mid 140.758926 -410.664152)
				(end 141.124686 -410.664152)
			)
		)
		(stroke
			(width 0)
			(type solid)
		)
		(fill yes)
		(layer "F.Cu")
		(net "GND")
	)
	(gr_poly
		(pts
			(arc
				(start 141.124686 -409.396184)
				(mid 140.758926 -409.396184)
				(end 141.124686 -409.396184)
			)
		)
		(stroke
			(width 0)
			(type solid)
		)
		(fill yes)
		(layer "F.Cu")
		(net "GND")
	)
	(gr_poly
		(pts
			(arc
				(start 141.124686 -407.638504)
				(mid 140.758926 -407.638504)
				(end 141.124686 -407.638504)
			)
		)
		(stroke
			(width 0)
			(type solid)
		)
		(fill yes)
		(layer "F.Cu")
		(net "GND")
	)
	(gr_poly
		(pts
			(arc
				(start 141.124686 -406.34666)
				(mid 140.758926 -406.34666)
				(end 141.124686 -406.34666)
			)
		)
		(stroke
			(width 0)
			(type solid)
		)
		(fill yes)
		(layer "F.Cu")
		(net "GND")
	)
	(gr_poly
		(pts
			(arc
				(start 141.582902 -404.51786)
				(mid 141.217142 -404.51786)
				(end 141.582902 -404.51786)
			)
		)
		(stroke
			(width 0)
			(type solid)
		)
		(fill yes)
		(layer "F.Cu")
		(net "GND")
	)
	(gr_poly
		(pts
			(arc
				(start 141.582902 -403.249892)
				(mid 141.217142 -403.249892)
				(end 141.582902 -403.249892)
			)
		)
		(stroke
			(width 0)
			(type solid)
		)
		(fill yes)
		(layer "F.Cu")
		(net "GND")
	)
	(gr_poly
		(pts
			(arc
				(start 141.582902 -401.492212)
				(mid 141.217142 -401.492212)
				(end 141.582902 -401.492212)
			)
		)
		(stroke
			(width 0)
			(type solid)
		)
		(fill yes)
		(layer "F.Cu")
		(net "GND")
	)
	(gr_poly
		(pts
			(arc
				(start 141.582902 -400.224244)
				(mid 141.217142 -400.224244)
				(end 141.582902 -400.224244)
			)
		)
		(stroke
			(width 0)
			(type solid)
		)
		(fill yes)
		(layer "F.Cu")
		(net "GND")
	)
	(gr_poly
		(pts
			(arc
				(start 142.841726 -404.51786)
				(mid 142.475966 -404.51786)
				(end 142.841726 -404.51786)
			)
		)
		(stroke
			(width 0)
			(type solid)
		)
		(fill yes)
		(layer "F.Cu")
		(net "GND")
	)
	(gr_poly
		(pts
			(arc
				(start 142.841726 -403.249892)
				(mid 142.475966 -403.249892)
				(end 142.841726 -403.249892)
			)
		)
		(stroke
			(width 0)
			(type solid)
		)
		(fill yes)
		(layer "F.Cu")
		(net "GND")
	)
	(gr_poly
		(pts
			(arc
				(start 142.841726 -401.492212)
				(mid 142.475966 -401.492212)
				(end 142.841726 -401.492212)
			)
		)
		(stroke
			(width 0)
			(type solid)
		)
		(fill yes)
		(layer "F.Cu")
		(net "GND")
	)
	(gr_poly
		(pts
			(arc
				(start 142.841726 -400.224244)
				(mid 142.475966 -400.224244)
				(end 142.841726 -400.224244)
			)
		)
		(stroke
			(width 0)
			(type solid)
		)
		(fill yes)
		(layer "F.Cu")
		(net "GND")
	)
	(gr_poly
		(pts
			(arc
				(start 142.929102 -410.664152)
				(mid 142.563342 -410.664152)
				(end 142.929102 -410.664152)
			)
		)
		(stroke
			(width 0)
			(type solid)
		)
		(fill yes)
		(layer "F.Cu")
		(net "GND")
	)
	(gr_poly
		(pts
			(arc
				(start 142.929102 -409.396184)
				(mid 142.563342 -409.396184)
				(end 142.929102 -409.396184)
			)
		)
		(stroke
			(width 0)
			(type solid)
		)
		(fill yes)
		(layer "F.Cu")
		(net "GND")
	)
	(gr_poly
		(pts
			(arc
				(start 142.929102 -407.638504)
				(mid 142.563342 -407.638504)
				(end 142.929102 -407.638504)
			)
		)
		(stroke
			(width 0)
			(type solid)
		)
		(fill yes)
		(layer "F.Cu")
		(net "GND")
	)
	(gr_poly
		(pts
			(arc
				(start 142.929102 -406.370536)
				(mid 142.563342 -406.370536)
				(end 142.929102 -406.370536)
			)
		)
		(stroke
			(width 0)
			(type solid)
		)
		(fill yes)
		(layer "F.Cu")
		(net "GND")
	)
	(gr_poly
		(pts
			(arc
				(start 143.129 -8.341868)
				(mid 142.76324 -8.341868)
				(end 143.129 -8.341868)
			)
		)
		(stroke
			(width 0)
			(type solid)
		)
		(fill yes)
		(layer "F.Cu")
		(net "GND")
	)
	(gr_poly
		(pts
			(arc
				(start 143.5481 -11.463528)
				(mid 143.18234 -11.463528)
				(end 143.5481 -11.463528)
			)
		)
		(stroke
			(width 0)
			(type solid)
		)
		(fill yes)
		(layer "F.Cu")
		(net "GND")
	)
	(gr_poly
		(pts
			(arc
				(start 144.187926 -410.664152)
				(mid 143.822166 -410.664152)
				(end 144.187926 -410.664152)
			)
		)
		(stroke
			(width 0)
			(type solid)
		)
		(fill yes)
		(layer "F.Cu")
		(net "GND")
	)
	(gr_poly
		(pts
			(arc
				(start 144.187926 -409.396184)
				(mid 143.822166 -409.396184)
				(end 144.187926 -409.396184)
			)
		)
		(stroke
			(width 0)
			(type solid)
		)
		(fill yes)
		(layer "F.Cu")
		(net "GND")
	)
	(gr_poly
		(pts
			(arc
				(start 144.187926 -407.638504)
				(mid 143.822166 -407.638504)
				(end 144.187926 -407.638504)
			)
		)
		(stroke
			(width 0)
			(type solid)
		)
		(fill yes)
		(layer "F.Cu")
		(net "GND")
	)
	(gr_poly
		(pts
			(arc
				(start 144.187926 -406.370536)
				(mid 143.822166 -406.370536)
				(end 144.187926 -406.370536)
			)
		)
		(stroke
			(width 0)
			(type solid)
		)
		(fill yes)
		(layer "F.Cu")
		(net "GND")
	)
	(gr_poly
		(pts
			(arc
				(start 144.492726 -55.350664)
				(mid 144.126966 -55.350664)
				(end 144.492726 -55.350664)
			)
		)
		(stroke
			(width 0)
			(type solid)
		)
		(fill yes)
		(layer "F.Cu")
		(net "GND")
	)
	(gr_poly
		(pts
			(arc
				(start 144.646142 -404.51786)
				(mid 144.280382 -404.51786)
				(end 144.646142 -404.51786)
			)
		)
		(stroke
			(width 0)
			(type solid)
		)
		(fill yes)
		(layer "F.Cu")
		(net "GND")
	)
	(gr_poly
		(pts
			(arc
				(start 144.646142 -403.249892)
				(mid 144.280382 -403.249892)
				(end 144.646142 -403.249892)
			)
		)
		(stroke
			(width 0)
			(type solid)
		)
		(fill yes)
		(layer "F.Cu")
		(net "GND")
	)
	(gr_poly
		(pts
			(arc
				(start 144.646142 -401.492212)
				(mid 144.280382 -401.492212)
				(end 144.646142 -401.492212)
			)
		)
		(stroke
			(width 0)
			(type solid)
		)
		(fill yes)
		(layer "F.Cu")
		(net "GND")
	)
	(gr_poly
		(pts
			(arc
				(start 144.646142 -400.224244)
				(mid 144.280382 -400.224244)
				(end 144.646142 -400.224244)
			)
		)
		(stroke
			(width 0)
			(type solid)
		)
		(fill yes)
		(layer "F.Cu")
		(net "GND")
	)
	(gr_poly
		(pts
			(arc
				(start 144.878552 -58.372248)
				(mid 144.512792 -58.372248)
				(end 144.878552 -58.372248)
			)
		)
		(stroke
			(width 0)
			(type solid)
		)
		(fill yes)
		(layer "F.Cu")
		(net "GND")
	)
	(gr_poly
		(pts
			(arc
				(start 145.904966 -404.51786)
				(mid 145.539206 -404.51786)
				(end 145.904966 -404.51786)
			)
		)
		(stroke
			(width 0)
			(type solid)
		)
		(fill yes)
		(layer "F.Cu")
		(net "GND")
	)
	(gr_poly
		(pts
			(arc
				(start 145.904966 -403.249892)
				(mid 145.539206 -403.249892)
				(end 145.904966 -403.249892)
			)
		)
		(stroke
			(width 0)
			(type solid)
		)
		(fill yes)
		(layer "F.Cu")
		(net "GND")
	)
	(gr_poly
		(pts
			(arc
				(start 145.904966 -401.492212)
				(mid 145.539206 -401.492212)
				(end 145.904966 -401.492212)
			)
		)
		(stroke
			(width 0)
			(type solid)
		)
		(fill yes)
		(layer "F.Cu")
		(net "GND")
	)
	(gr_poly
		(pts
			(arc
				(start 145.904966 -400.224244)
				(mid 145.539206 -400.224244)
				(end 145.904966 -400.224244)
			)
		)
		(stroke
			(width 0)
			(type solid)
		)
		(fill yes)
		(layer "F.Cu")
		(net "GND")
	)
	(gr_poly
		(pts
			(arc
				(start 145.992342 -410.664152)
				(mid 145.626582 -410.664152)
				(end 145.992342 -410.664152)
			)
		)
		(stroke
			(width 0)
			(type solid)
		)
		(fill yes)
		(layer "F.Cu")
		(net "GND")
	)
	(gr_poly
		(pts
			(arc
				(start 145.992342 -409.396184)
				(mid 145.626582 -409.396184)
				(end 145.992342 -409.396184)
			)
		)
		(stroke
			(width 0)
			(type solid)
		)
		(fill yes)
		(layer "F.Cu")
		(net "GND")
	)
	(gr_poly
		(pts
			(arc
				(start 145.992342 -407.638504)
				(mid 145.626582 -407.638504)
				(end 145.992342 -407.638504)
			)
		)
		(stroke
			(width 0)
			(type solid)
		)
		(fill yes)
		(layer "F.Cu")
		(net "GND")
	)
	(gr_poly
		(pts
			(arc
				(start 145.992342 -406.370536)
				(mid 145.626582 -406.370536)
				(end 145.992342 -406.370536)
			)
		)
		(stroke
			(width 0)
			(type solid)
		)
		(fill yes)
		(layer "F.Cu")
		(net "GND")
	)
	(gr_poly
		(pts
			(arc
				(start 147.15236 -11.458448)
				(mid 146.7866 -11.458448)
				(end 147.15236 -11.458448)
			)
		)
		(stroke
			(width 0)
			(type solid)
		)
		(fill yes)
		(layer "F.Cu")
		(net "GND")
	)
	(gr_poly
		(pts
			(arc
				(start 147.175474 -58.447686)
				(mid 146.809714 -58.447686)
				(end 147.175474 -58.447686)
			)
		)
		(stroke
			(width 0)
			(type solid)
		)
		(fill yes)
		(layer "F.Cu")
		(net "GND")
	)
	(gr_poly
		(pts
			(arc
				(start 147.251166 -410.664152)
				(mid 146.885406 -410.664152)
				(end 147.251166 -410.664152)
			)
		)
		(stroke
			(width 0)
			(type solid)
		)
		(fill yes)
		(layer "F.Cu")
		(net "GND")
	)
	(gr_poly
		(pts
			(arc
				(start 147.251166 -409.396184)
				(mid 146.885406 -409.396184)
				(end 147.251166 -409.396184)
			)
		)
		(stroke
			(width 0)
			(type solid)
		)
		(fill yes)
		(layer "F.Cu")
		(net "GND")
	)
	(gr_poly
		(pts
			(arc
				(start 147.251166 -407.638504)
				(mid 146.885406 -407.638504)
				(end 147.251166 -407.638504)
			)
		)
		(stroke
			(width 0)
			(type solid)
		)
		(fill yes)
		(layer "F.Cu")
		(net "GND")
	)
	(gr_poly
		(pts
			(arc
				(start 147.251166 -406.370536)
				(mid 146.885406 -406.370536)
				(end 147.251166 -406.370536)
			)
		)
		(stroke
			(width 0)
			(type solid)
		)
		(fill yes)
		(layer "F.Cu")
		(net "GND")
	)
	(gr_poly
		(pts
			(arc
				(start 147.60448 -76.810108)
				(mid 147.23872 -76.810108)
				(end 147.60448 -76.810108)
			)
		)
		(stroke
			(width 0)
			(type solid)
		)
		(fill yes)
		(layer "F.Cu")
		(net "GND")
	)
	(gr_poly
		(pts
			(arc
				(start 147.683728 -54.832758)
				(mid 147.317968 -54.832758)
				(end 147.683728 -54.832758)
			)
		)
		(stroke
			(width 0)
			(type solid)
		)
		(fill yes)
		(layer "F.Cu")
		(net "GND")
	)
	(gr_poly
		(pts
			(arc
				(start 147.709382 -404.51786)
				(mid 147.343622 -404.51786)
				(end 147.709382 -404.51786)
			)
		)
		(stroke
			(width 0)
			(type solid)
		)
		(fill yes)
		(layer "F.Cu")
		(net "GND")
	)
	(gr_poly
		(pts
			(arc
				(start 147.709382 -403.249892)
				(mid 147.343622 -403.249892)
				(end 147.709382 -403.249892)
			)
		)
		(stroke
			(width 0)
			(type solid)
		)
		(fill yes)
		(layer "F.Cu")
		(net "GND")
	)
	(gr_poly
		(pts
			(arc
				(start 147.709382 -401.492212)
				(mid 147.343622 -401.492212)
				(end 147.709382 -401.492212)
			)
		)
		(stroke
			(width 0)
			(type solid)
		)
		(fill yes)
		(layer "F.Cu")
		(net "GND")
	)
	(gr_poly
		(pts
			(arc
				(start 147.709382 -400.224244)
				(mid 147.343622 -400.224244)
				(end 147.709382 -400.224244)
			)
		)
		(stroke
			(width 0)
			(type solid)
		)
		(fill yes)
		(layer "F.Cu")
		(net "GND")
	)
	(gr_poly
		(pts
			(arc
				(start 148.121624 -91.702128)
				(mid 147.755864 -91.702128)
				(end 148.121624 -91.702128)
			)
		)
		(stroke
			(width 0)
			(type solid)
		)
		(fill yes)
		(layer "F.Cu")
		(net "GND")
	)
	(gr_poly
		(pts
			(arc
				(start 148.968206 -404.51786)
				(mid 148.602446 -404.51786)
				(end 148.968206 -404.51786)
			)
		)
		(stroke
			(width 0)
			(type solid)
		)
		(fill yes)
		(layer "F.Cu")
		(net "GND")
	)
	(gr_poly
		(pts
			(arc
				(start 148.968206 -403.249892)
				(mid 148.602446 -403.249892)
				(end 148.968206 -403.249892)
			)
		)
		(stroke
			(width 0)
			(type solid)
		)
		(fill yes)
		(layer "F.Cu")
		(net "GND")
	)
	(gr_poly
		(pts
			(arc
				(start 148.968206 -401.492212)
				(mid 148.602446 -401.492212)
				(end 148.968206 -401.492212)
			)
		)
		(stroke
			(width 0)
			(type solid)
		)
		(fill yes)
		(layer "F.Cu")
		(net "GND")
	)
	(gr_poly
		(pts
			(arc
				(start 148.968206 -400.224244)
				(mid 148.602446 -400.224244)
				(end 148.968206 -400.224244)
			)
		)
		(stroke
			(width 0)
			(type solid)
		)
		(fill yes)
		(layer "F.Cu")
		(net "GND")
	)
	(gr_poly
		(pts
			(arc
				(start 149.055582 -410.664152)
				(mid 148.689822 -410.664152)
				(end 149.055582 -410.664152)
			)
		)
		(stroke
			(width 0)
			(type solid)
		)
		(fill yes)
		(layer "F.Cu")
		(net "GND")
	)
	(gr_poly
		(pts
			(arc
				(start 149.055582 -409.396184)
				(mid 148.689822 -409.396184)
				(end 149.055582 -409.396184)
			)
		)
		(stroke
			(width 0)
			(type solid)
		)
		(fill yes)
		(layer "F.Cu")
		(net "GND")
	)
	(gr_poly
		(pts
			(arc
				(start 149.055582 -407.638504)
				(mid 148.689822 -407.638504)
				(end 149.055582 -407.638504)
			)
		)
		(stroke
			(width 0)
			(type solid)
		)
		(fill yes)
		(layer "F.Cu")
		(net "GND")
	)
	(gr_poly
		(pts
			(arc
				(start 149.055582 -406.370536)
				(mid 148.689822 -406.370536)
				(end 149.055582 -406.370536)
			)
		)
		(stroke
			(width 0)
			(type solid)
		)
		(fill yes)
		(layer "F.Cu")
		(net "GND")
	)
	(gr_poly
		(pts
			(arc
				(start 149.23516 -79.924148)
				(mid 148.8694 -79.924148)
				(end 149.23516 -79.924148)
			)
		)
		(stroke
			(width 0)
			(type solid)
		)
		(fill yes)
		(layer "F.Cu")
		(net "GND")
	)
	(gr_poly
		(pts
			(arc
				(start 150.128478 -45.111416)
				(mid 149.762718 -45.111416)
				(end 150.128478 -45.111416)
			)
		)
		(stroke
			(width 0)
			(type solid)
		)
		(fill yes)
		(layer "F.Cu")
		(net "GND")
	)
	(gr_poly
		(pts
			(arc
				(start 150.13178 -74.778108)
				(mid 149.76602 -74.778108)
				(end 150.13178 -74.778108)
			)
		)
		(stroke
			(width 0)
			(type solid)
		)
		(fill yes)
		(layer "F.Cu")
		(net "GND")
	)
	(gr_poly
		(pts
			(arc
				(start 150.314406 -410.664152)
				(mid 149.948646 -410.664152)
				(end 150.314406 -410.664152)
			)
		)
		(stroke
			(width 0)
			(type solid)
		)
		(fill yes)
		(layer "F.Cu")
		(net "GND")
	)
	(gr_poly
		(pts
			(arc
				(start 150.314406 -409.396184)
				(mid 149.948646 -409.396184)
				(end 150.314406 -409.396184)
			)
		)
		(stroke
			(width 0)
			(type solid)
		)
		(fill yes)
		(layer "F.Cu")
		(net "GND")
	)
	(gr_poly
		(pts
			(arc
				(start 150.314406 -407.638504)
				(mid 149.948646 -407.638504)
				(end 150.314406 -407.638504)
			)
		)
		(stroke
			(width 0)
			(type solid)
		)
		(fill yes)
		(layer "F.Cu")
		(net "GND")
	)
	(gr_poly
		(pts
			(arc
				(start 150.314406 -406.370536)
				(mid 149.948646 -406.370536)
				(end 150.314406 -406.370536)
			)
		)
		(stroke
			(width 0)
			(type solid)
		)
		(fill yes)
		(layer "F.Cu")
		(net "GND")
	)
	(gr_poly
		(pts
			(arc
				(start 150.772622 -404.51786)
				(mid 150.406862 -404.51786)
				(end 150.772622 -404.51786)
			)
		)
		(stroke
			(width 0)
			(type solid)
		)
		(fill yes)
		(layer "F.Cu")
		(net "GND")
	)
	(gr_poly
		(pts
			(arc
				(start 150.772622 -403.249892)
				(mid 150.406862 -403.249892)
				(end 150.772622 -403.249892)
			)
		)
		(stroke
			(width 0)
			(type solid)
		)
		(fill yes)
		(layer "F.Cu")
		(net "GND")
	)
	(gr_poly
		(pts
			(arc
				(start 150.772622 -401.492212)
				(mid 150.406862 -401.492212)
				(end 150.772622 -401.492212)
			)
		)
		(stroke
			(width 0)
			(type solid)
		)
		(fill yes)
		(layer "F.Cu")
		(net "GND")
	)
	(gr_poly
		(pts
			(arc
				(start 150.772622 -400.224244)
				(mid 150.406862 -400.224244)
				(end 150.772622 -400.224244)
			)
		)
		(stroke
			(width 0)
			(type solid)
		)
		(fill yes)
		(layer "F.Cu")
		(net "GND")
	)
	(gr_poly
		(pts
			(arc
				(start 150.78456 -82.895948)
				(mid 150.4188 -82.895948)
				(end 150.78456 -82.895948)
			)
		)
		(stroke
			(width 0)
			(type solid)
		)
		(fill yes)
		(layer "F.Cu")
		(net "GND")
	)
	(gr_poly
		(pts
			(arc
				(start 151.714454 -46.951646)
				(mid 151.348694 -46.951646)
				(end 151.714454 -46.951646)
			)
		)
		(stroke
			(width 0)
			(type solid)
		)
		(fill yes)
		(layer "F.Cu")
		(net "GND")
	)
	(gr_poly
		(pts
			(arc
				(start 151.78024 -11.468608)
				(mid 151.41448 -11.468608)
				(end 151.78024 -11.468608)
			)
		)
		(stroke
			(width 0)
			(type solid)
		)
		(fill yes)
		(layer "F.Cu")
		(net "GND")
	)
	(gr_poly
		(pts
			(arc
				(start 152.02916 -80.533748)
				(mid 151.6634 -80.533748)
				(end 152.02916 -80.533748)
			)
		)
		(stroke
			(width 0)
			(type solid)
		)
		(fill yes)
		(layer "F.Cu")
		(net "GND")
	)
	(gr_poly
		(pts
			(arc
				(start 152.031446 -404.51786)
				(mid 151.665686 -404.51786)
				(end 152.031446 -404.51786)
			)
		)
		(stroke
			(width 0)
			(type solid)
		)
		(fill yes)
		(layer "F.Cu")
		(net "GND")
	)
	(gr_poly
		(pts
			(arc
				(start 152.031446 -403.249892)
				(mid 151.665686 -403.249892)
				(end 152.031446 -403.249892)
			)
		)
		(stroke
			(width 0)
			(type solid)
		)
		(fill yes)
		(layer "F.Cu")
		(net "GND")
	)
	(gr_poly
		(pts
			(arc
				(start 152.031446 -401.492212)
				(mid 151.665686 -401.492212)
				(end 152.031446 -401.492212)
			)
		)
		(stroke
			(width 0)
			(type solid)
		)
		(fill yes)
		(layer "F.Cu")
		(net "GND")
	)
	(gr_poly
		(pts
			(arc
				(start 152.031446 -400.224244)
				(mid 151.665686 -400.224244)
				(end 152.031446 -400.224244)
			)
		)
		(stroke
			(width 0)
			(type solid)
		)
		(fill yes)
		(layer "F.Cu")
		(net "GND")
	)
	(gr_poly
		(pts
			(arc
				(start 152.118822 -410.664152)
				(mid 151.753062 -410.664152)
				(end 152.118822 -410.664152)
			)
		)
		(stroke
			(width 0)
			(type solid)
		)
		(fill yes)
		(layer "F.Cu")
		(net "GND")
	)
	(gr_poly
		(pts
			(arc
				(start 152.118822 -409.396184)
				(mid 151.753062 -409.396184)
				(end 152.118822 -409.396184)
			)
		)
		(stroke
			(width 0)
			(type solid)
		)
		(fill yes)
		(layer "F.Cu")
		(net "GND")
	)
	(gr_poly
		(pts
			(arc
				(start 152.118822 -407.638504)
				(mid 151.753062 -407.638504)
				(end 152.118822 -407.638504)
			)
		)
		(stroke
			(width 0)
			(type solid)
		)
		(fill yes)
		(layer "F.Cu")
		(net "GND")
	)
	(gr_poly
		(pts
			(arc
				(start 152.118822 -406.370536)
				(mid 151.753062 -406.370536)
				(end 152.118822 -406.370536)
			)
		)
		(stroke
			(width 0)
			(type solid)
		)
		(fill yes)
		(layer "F.Cu")
		(net "GND")
	)
	(gr_poly
		(pts
			(arc
				(start 152.84958 -25.402032)
				(mid 152.48382 -25.402032)
				(end 152.84958 -25.402032)
			)
		)
		(stroke
			(width 0)
			(type solid)
		)
		(fill yes)
		(layer "F.Cu")
		(net "GND")
	)
	(gr_poly
		(pts
			(arc
				(start 153.377646 -410.664152)
				(mid 153.011886 -410.664152)
				(end 153.377646 -410.664152)
			)
		)
		(stroke
			(width 0)
			(type solid)
		)
		(fill yes)
		(layer "F.Cu")
		(net "GND")
	)
	(gr_poly
		(pts
			(arc
				(start 153.377646 -409.396184)
				(mid 153.011886 -409.396184)
				(end 153.377646 -409.396184)
			)
		)
		(stroke
			(width 0)
			(type solid)
		)
		(fill yes)
		(layer "F.Cu")
		(net "GND")
	)
	(gr_poly
		(pts
			(arc
				(start 153.377646 -407.638504)
				(mid 153.011886 -407.638504)
				(end 153.377646 -407.638504)
			)
		)
		(stroke
			(width 0)
			(type solid)
		)
		(fill yes)
		(layer "F.Cu")
		(net "GND")
	)
	(gr_poly
		(pts
			(arc
				(start 153.377646 -406.370536)
				(mid 153.011886 -406.370536)
				(end 153.377646 -406.370536)
			)
		)
		(stroke
			(width 0)
			(type solid)
		)
		(fill yes)
		(layer "F.Cu")
		(net "GND")
	)
	(gr_poly
		(pts
			(arc
				(start 153.835862 -404.51786)
				(mid 153.470102 -404.51786)
				(end 153.835862 -404.51786)
			)
		)
		(stroke
			(width 0)
			(type solid)
		)
		(fill yes)
		(layer "F.Cu")
		(net "GND")
	)
	(gr_poly
		(pts
			(arc
				(start 153.835862 -403.249892)
				(mid 153.470102 -403.249892)
				(end 153.835862 -403.249892)
			)
		)
		(stroke
			(width 0)
			(type solid)
		)
		(fill yes)
		(layer "F.Cu")
		(net "GND")
	)
	(gr_poly
		(pts
			(arc
				(start 153.835862 -401.492212)
				(mid 153.470102 -401.492212)
				(end 153.835862 -401.492212)
			)
		)
		(stroke
			(width 0)
			(type solid)
		)
		(fill yes)
		(layer "F.Cu")
		(net "GND")
	)
	(gr_poly
		(pts
			(arc
				(start 153.835862 -400.224244)
				(mid 153.470102 -400.224244)
				(end 153.835862 -400.224244)
			)
		)
		(stroke
			(width 0)
			(type solid)
		)
		(fill yes)
		(layer "F.Cu")
		(net "GND")
	)
	(gr_poly
		(pts
			(arc
				(start 153.86812 -10.770108)
				(mid 153.50236 -10.770108)
				(end 153.86812 -10.770108)
			)
		)
		(stroke
			(width 0)
			(type solid)
		)
		(fill yes)
		(layer "F.Cu")
		(net "GND")
	)
	(gr_poly
		(pts
			(arc
				(start 154.58694 -8.734806)
				(mid 154.22118 -8.734806)
				(end 154.58694 -8.734806)
			)
		)
		(stroke
			(width 0)
			(type solid)
		)
		(fill yes)
		(layer "F.Cu")
		(net "GND")
	)
	(gr_poly
		(pts
			(arc
				(start 154.8257 -95.072708)
				(mid 154.45994 -95.072708)
				(end 154.8257 -95.072708)
			)
		)
		(stroke
			(width 0)
			(type solid)
		)
		(fill yes)
		(layer "F.Cu")
		(net "GND")
	)
	(gr_poly
		(pts
			(arc
				(start 155.083256 -83.923378)
				(mid 154.717496 -83.923378)
				(end 155.083256 -83.923378)
			)
		)
		(stroke
			(width 0)
			(type solid)
		)
		(fill yes)
		(layer "F.Cu")
		(net "GND")
	)
	(gr_poly
		(pts
			(arc
				(start 155.094686 -404.51786)
				(mid 154.728926 -404.51786)
				(end 155.094686 -404.51786)
			)
		)
		(stroke
			(width 0)
			(type solid)
		)
		(fill yes)
		(layer "F.Cu")
		(net "GND")
	)
	(gr_poly
		(pts
			(arc
				(start 155.094686 -403.249892)
				(mid 154.728926 -403.249892)
				(end 155.094686 -403.249892)
			)
		)
		(stroke
			(width 0)
			(type solid)
		)
		(fill yes)
		(layer "F.Cu")
		(net "GND")
	)
	(gr_poly
		(pts
			(arc
				(start 155.094686 -401.492212)
				(mid 154.728926 -401.492212)
				(end 155.094686 -401.492212)
			)
		)
		(stroke
			(width 0)
			(type solid)
		)
		(fill yes)
		(layer "F.Cu")
		(net "GND")
	)
	(gr_poly
		(pts
			(arc
				(start 155.094686 -400.224244)
				(mid 154.728926 -400.224244)
				(end 155.094686 -400.224244)
			)
		)
		(stroke
			(width 0)
			(type solid)
		)
		(fill yes)
		(layer "F.Cu")
		(net "GND")
	)
	(gr_poly
		(pts
			(arc
				(start 155.182062 -410.664152)
				(mid 154.816302 -410.664152)
				(end 155.182062 -410.664152)
			)
		)
		(stroke
			(width 0)
			(type solid)
		)
		(fill yes)
		(layer "F.Cu")
		(net "GND")
	)
	(gr_poly
		(pts
			(arc
				(start 155.182062 -409.396184)
				(mid 154.816302 -409.396184)
				(end 155.182062 -409.396184)
			)
		)
		(stroke
			(width 0)
			(type solid)
		)
		(fill yes)
		(layer "F.Cu")
		(net "GND")
	)
	(gr_poly
		(pts
			(arc
				(start 155.182062 -407.638504)
				(mid 154.816302 -407.638504)
				(end 155.182062 -407.638504)
			)
		)
		(stroke
			(width 0)
			(type solid)
		)
		(fill yes)
		(layer "F.Cu")
		(net "GND")
	)
	(gr_poly
		(pts
			(arc
				(start 155.182062 -406.370536)
				(mid 154.816302 -406.370536)
				(end 155.182062 -406.370536)
			)
		)
		(stroke
			(width 0)
			(type solid)
		)
		(fill yes)
		(layer "F.Cu")
		(net "GND")
	)
	(gr_poly
		(pts
			(arc
				(start 155.3845 -47.846488)
				(mid 155.01874 -47.846488)
				(end 155.3845 -47.846488)
			)
		)
		(stroke
			(width 0)
			(type solid)
		)
		(fill yes)
		(layer "F.Cu")
		(net "GND")
	)
	(gr_poly
		(pts
			(arc
				(start 155.45562 -67.633088)
				(mid 155.08986 -67.633088)
				(end 155.45562 -67.633088)
			)
		)
		(stroke
			(width 0)
			(type solid)
		)
		(fill yes)
		(layer "F.Cu")
		(net "GND")
	)
	(gr_poly
		(pts
			(arc
				(start 156.440886 -410.664152)
				(mid 156.075126 -410.664152)
				(end 156.440886 -410.664152)
			)
		)
		(stroke
			(width 0)
			(type solid)
		)
		(fill yes)
		(layer "F.Cu")
		(net "GND")
	)
	(gr_poly
		(pts
			(arc
				(start 156.440886 -409.396184)
				(mid 156.075126 -409.396184)
				(end 156.440886 -409.396184)
			)
		)
		(stroke
			(width 0)
			(type solid)
		)
		(fill yes)
		(layer "F.Cu")
		(net "GND")
	)
	(gr_poly
		(pts
			(arc
				(start 156.440886 -407.638504)
				(mid 156.075126 -407.638504)
				(end 156.440886 -407.638504)
			)
		)
		(stroke
			(width 0)
			(type solid)
		)
		(fill yes)
		(layer "F.Cu")
		(net "GND")
	)
	(gr_poly
		(pts
			(arc
				(start 156.440886 -406.370536)
				(mid 156.075126 -406.370536)
				(end 156.440886 -406.370536)
			)
		)
		(stroke
			(width 0)
			(type solid)
		)
		(fill yes)
		(layer "F.Cu")
		(net "GND")
	)
	(gr_poly
		(pts
			(arc
				(start 156.49956 -10.754868)
				(mid 156.1338 -10.754868)
				(end 156.49956 -10.754868)
			)
		)
		(stroke
			(width 0)
			(type solid)
		)
		(fill yes)
		(layer "F.Cu")
		(net "GND")
	)
	(gr_poly
		(pts
			(arc
				(start 156.538168 -44.181268)
				(mid 156.172408 -44.181268)
				(end 156.538168 -44.181268)
			)
		)
		(stroke
			(width 0)
			(type solid)
		)
		(fill yes)
		(layer "F.Cu")
		(net "GND")
	)
	(gr_poly
		(pts
			(arc
				(start 156.538422 -46.223936)
				(mid 156.172662 -46.223936)
				(end 156.538422 -46.223936)
			)
		)
		(stroke
			(width 0)
			(type solid)
		)
		(fill yes)
		(layer "F.Cu")
		(net "GND")
	)
	(gr_poly
		(pts
			(arc
				(start 156.899102 -404.51786)
				(mid 156.533342 -404.51786)
				(end 156.899102 -404.51786)
			)
		)
		(stroke
			(width 0)
			(type solid)
		)
		(fill yes)
		(layer "F.Cu")
		(net "GND")
	)
	(gr_poly
		(pts
			(arc
				(start 156.899102 -403.249892)
				(mid 156.533342 -403.249892)
				(end 156.899102 -403.249892)
			)
		)
		(stroke
			(width 0)
			(type solid)
		)
		(fill yes)
		(layer "F.Cu")
		(net "GND")
	)
	(gr_poly
		(pts
			(arc
				(start 156.899102 -401.492212)
				(mid 156.533342 -401.492212)
				(end 156.899102 -401.492212)
			)
		)
		(stroke
			(width 0)
			(type solid)
		)
		(fill yes)
		(layer "F.Cu")
		(net "GND")
	)
	(gr_poly
		(pts
			(arc
				(start 156.899102 -400.224244)
				(mid 156.533342 -400.224244)
				(end 156.899102 -400.224244)
			)
		)
		(stroke
			(width 0)
			(type solid)
		)
		(fill yes)
		(layer "F.Cu")
		(net "GND")
	)
	(gr_poly
		(pts
			(arc
				(start 157.6705 -47.950628)
				(mid 157.30474 -47.950628)
				(end 157.6705 -47.950628)
			)
		)
		(stroke
			(width 0)
			(type solid)
		)
		(fill yes)
		(layer "F.Cu")
		(net "GND")
	)
	(gr_poly
		(pts
			(arc
				(start 158.10484 -67.551808)
				(mid 157.73908 -67.551808)
				(end 158.10484 -67.551808)
			)
		)
		(stroke
			(width 0)
			(type solid)
		)
		(fill yes)
		(layer "F.Cu")
		(net "GND")
	)
	(gr_poly
		(pts
			(arc
				(start 158.157926 -404.51786)
				(mid 157.792166 -404.51786)
				(end 158.157926 -404.51786)
			)
		)
		(stroke
			(width 0)
			(type solid)
		)
		(fill yes)
		(layer "F.Cu")
		(net "GND")
	)
	(gr_poly
		(pts
			(arc
				(start 158.157926 -403.249892)
				(mid 157.792166 -403.249892)
				(end 158.157926 -403.249892)
			)
		)
		(stroke
			(width 0)
			(type solid)
		)
		(fill yes)
		(layer "F.Cu")
		(net "GND")
	)
	(gr_poly
		(pts
			(arc
				(start 158.157926 -401.492212)
				(mid 157.792166 -401.492212)
				(end 158.157926 -401.492212)
			)
		)
		(stroke
			(width 0)
			(type solid)
		)
		(fill yes)
		(layer "F.Cu")
		(net "GND")
	)
	(gr_poly
		(pts
			(arc
				(start 158.157926 -400.224244)
				(mid 157.792166 -400.224244)
				(end 158.157926 -400.224244)
			)
		)
		(stroke
			(width 0)
			(type solid)
		)
		(fill yes)
		(layer "F.Cu")
		(net "GND")
	)
	(gr_poly
		(pts
			(arc
				(start 158.245302 -410.664152)
				(mid 157.879542 -410.664152)
				(end 158.245302 -410.664152)
			)
		)
		(stroke
			(width 0)
			(type solid)
		)
		(fill yes)
		(layer "F.Cu")
		(net "GND")
	)
	(gr_poly
		(pts
			(arc
				(start 158.245302 -409.396184)
				(mid 157.879542 -409.396184)
				(end 158.245302 -409.396184)
			)
		)
		(stroke
			(width 0)
			(type solid)
		)
		(fill yes)
		(layer "F.Cu")
		(net "GND")
	)
	(gr_poly
		(pts
			(arc
				(start 158.245302 -407.638504)
				(mid 157.879542 -407.638504)
				(end 158.245302 -407.638504)
			)
		)
		(stroke
			(width 0)
			(type solid)
		)
		(fill yes)
		(layer "F.Cu")
		(net "GND")
	)
	(gr_poly
		(pts
			(arc
				(start 158.245302 -406.370536)
				(mid 157.879542 -406.370536)
				(end 158.245302 -406.370536)
			)
		)
		(stroke
			(width 0)
			(type solid)
		)
		(fill yes)
		(layer "F.Cu")
		(net "GND")
	)
	(gr_poly
		(pts
			(arc
				(start 158.5722 -85.452966)
				(mid 158.20644 -85.452966)
				(end 158.5722 -85.452966)
			)
		)
		(stroke
			(width 0)
			(type solid)
		)
		(fill yes)
		(layer "F.Cu")
		(net "GND")
	)
	(gr_poly
		(pts
			(arc
				(start 159.151828 -48.576992)
				(mid 158.786068 -48.576992)
				(end 159.151828 -48.576992)
			)
		)
		(stroke
			(width 0)
			(type solid)
		)
		(fill yes)
		(layer "F.Cu")
		(net "GND")
	)
	(gr_poly
		(pts
			(arc
				(start 159.504126 -410.664152)
				(mid 159.138366 -410.664152)
				(end 159.504126 -410.664152)
			)
		)
		(stroke
			(width 0)
			(type solid)
		)
		(fill yes)
		(layer "F.Cu")
		(net "GND")
	)
	(gr_poly
		(pts
			(arc
				(start 159.504126 -409.396184)
				(mid 159.138366 -409.396184)
				(end 159.504126 -409.396184)
			)
		)
		(stroke
			(width 0)
			(type solid)
		)
		(fill yes)
		(layer "F.Cu")
		(net "GND")
	)
	(gr_poly
		(pts
			(arc
				(start 159.504126 -407.638504)
				(mid 159.138366 -407.638504)
				(end 159.504126 -407.638504)
			)
		)
		(stroke
			(width 0)
			(type solid)
		)
		(fill yes)
		(layer "F.Cu")
		(net "GND")
	)
	(gr_poly
		(pts
			(arc
				(start 159.504126 -406.370536)
				(mid 159.138366 -406.370536)
				(end 159.504126 -406.370536)
			)
		)
		(stroke
			(width 0)
			(type solid)
		)
		(fill yes)
		(layer "F.Cu")
		(net "GND")
	)
	(gr_poly
		(pts
			(arc
				(start 159.744156 -43.274488)
				(mid 159.378396 -43.274488)
				(end 159.744156 -43.274488)
			)
		)
		(stroke
			(width 0)
			(type solid)
		)
		(fill yes)
		(layer "F.Cu")
		(net "GND")
	)
	(gr_poly
		(pts
			(arc
				(start 159.74441 -45.317156)
				(mid 159.37865 -45.317156)
				(end 159.74441 -45.317156)
			)
		)
		(stroke
			(width 0)
			(type solid)
		)
		(fill yes)
		(layer "F.Cu")
		(net "GND")
	)
	(gr_poly
		(pts
			(arc
				(start 159.769556 -80.519778)
				(mid 159.403796 -80.519778)
				(end 159.769556 -80.519778)
			)
		)
		(stroke
			(width 0)
			(type solid)
		)
		(fill yes)
		(layer "F.Cu")
		(net "GND")
	)
	(gr_poly
		(pts
			(arc
				(start 159.962342 -404.51786)
				(mid 159.596582 -404.51786)
				(end 159.962342 -404.51786)
			)
		)
		(stroke
			(width 0)
			(type solid)
		)
		(fill yes)
		(layer "F.Cu")
		(net "GND")
	)
	(gr_poly
		(pts
			(arc
				(start 159.962342 -403.249892)
				(mid 159.596582 -403.249892)
				(end 159.962342 -403.249892)
			)
		)
		(stroke
			(width 0)
			(type solid)
		)
		(fill yes)
		(layer "F.Cu")
		(net "GND")
	)
	(gr_poly
		(pts
			(arc
				(start 159.962342 -401.492212)
				(mid 159.596582 -401.492212)
				(end 159.962342 -401.492212)
			)
		)
		(stroke
			(width 0)
			(type solid)
		)
		(fill yes)
		(layer "F.Cu")
		(net "GND")
	)
	(gr_poly
		(pts
			(arc
				(start 159.962342 -400.224244)
				(mid 159.596582 -400.224244)
				(end 159.962342 -400.224244)
			)
		)
		(stroke
			(width 0)
			(type solid)
		)
		(fill yes)
		(layer "F.Cu")
		(net "GND")
	)
	(gr_poly
		(pts
			(arc
				(start 160.410652 -48.576992)
				(mid 160.044892 -48.576992)
				(end 160.410652 -48.576992)
			)
		)
		(stroke
			(width 0)
			(type solid)
		)
		(fill yes)
		(layer "F.Cu")
		(net "GND")
	)
	(gr_poly
		(pts
			(arc
				(start 160.595564 -21.596096)
				(mid 160.229804 -21.596096)
				(end 160.595564 -21.596096)
			)
		)
		(stroke
			(width 0)
			(type solid)
		)
		(fill yes)
		(layer "F.Cu")
		(net "GND")
	)
	(gr_poly
		(pts
			(arc
				(start 160.828482 -10.998708)
				(mid 160.462722 -10.998708)
				(end 160.828482 -10.998708)
			)
		)
		(stroke
			(width 0)
			(type solid)
		)
		(fill yes)
		(layer "F.Cu")
		(net "GND")
	)
	(gr_poly
		(pts
			(arc
				(start 160.87344 -27.313128)
				(mid 160.50768 -27.313128)
				(end 160.87344 -27.313128)
			)
		)
		(stroke
			(width 0)
			(type solid)
		)
		(fill yes)
		(layer "F.Cu")
		(net "GND")
	)
	(gr_poly
		(pts
			(arc
				(start 160.999932 -75.378564)
				(mid 160.634172 -75.378564)
				(end 160.999932 -75.378564)
			)
		)
		(stroke
			(width 0)
			(type solid)
		)
		(fill yes)
		(layer "F.Cu")
		(net "GND")
	)
	(gr_poly
		(pts
			(arc
				(start 161.221166 -404.51786)
				(mid 160.855406 -404.51786)
				(end 161.221166 -404.51786)
			)
		)
		(stroke
			(width 0)
			(type solid)
		)
		(fill yes)
		(layer "F.Cu")
		(net "GND")
	)
	(gr_poly
		(pts
			(arc
				(start 161.221166 -403.249892)
				(mid 160.855406 -403.249892)
				(end 161.221166 -403.249892)
			)
		)
		(stroke
			(width 0)
			(type solid)
		)
		(fill yes)
		(layer "F.Cu")
		(net "GND")
	)
	(gr_poly
		(pts
			(arc
				(start 161.221166 -401.492212)
				(mid 160.855406 -401.492212)
				(end 161.221166 -401.492212)
			)
		)
		(stroke
			(width 0)
			(type solid)
		)
		(fill yes)
		(layer "F.Cu")
		(net "GND")
	)
	(gr_poly
		(pts
			(arc
				(start 161.221166 -400.224244)
				(mid 160.855406 -400.224244)
				(end 161.221166 -400.224244)
			)
		)
		(stroke
			(width 0)
			(type solid)
		)
		(fill yes)
		(layer "F.Cu")
		(net "GND")
	)
	(gr_poly
		(pts
			(arc
				(start 161.308542 -410.664152)
				(mid 160.942782 -410.664152)
				(end 161.308542 -410.664152)
			)
		)
		(stroke
			(width 0)
			(type solid)
		)
		(fill yes)
		(layer "F.Cu")
		(net "GND")
	)
	(gr_poly
		(pts
			(arc
				(start 161.308542 -409.396184)
				(mid 160.942782 -409.396184)
				(end 161.308542 -409.396184)
			)
		)
		(stroke
			(width 0)
			(type solid)
		)
		(fill yes)
		(layer "F.Cu")
		(net "GND")
	)
	(gr_poly
		(pts
			(arc
				(start 161.308542 -407.638504)
				(mid 160.942782 -407.638504)
				(end 161.308542 -407.638504)
			)
		)
		(stroke
			(width 0)
			(type solid)
		)
		(fill yes)
		(layer "F.Cu")
		(net "GND")
	)
	(gr_poly
		(pts
			(arc
				(start 161.308542 -406.370536)
				(mid 160.942782 -406.370536)
				(end 161.308542 -406.370536)
			)
		)
		(stroke
			(width 0)
			(type solid)
		)
		(fill yes)
		(layer "F.Cu")
		(net "GND")
	)
	(gr_poly
		(pts
			(arc
				(start 162.10788 -28.031948)
				(mid 161.74212 -28.031948)
				(end 162.10788 -28.031948)
			)
		)
		(stroke
			(width 0)
			(type solid)
		)
		(fill yes)
		(layer "F.Cu")
		(net "GND")
	)
	(gr_poly
		(pts
			(arc
				(start 162.567366 -410.664152)
				(mid 162.201606 -410.664152)
				(end 162.567366 -410.664152)
			)
		)
		(stroke
			(width 0)
			(type solid)
		)
		(fill yes)
		(layer "F.Cu")
		(net "GND")
	)
	(gr_poly
		(pts
			(arc
				(start 162.567366 -409.396184)
				(mid 162.201606 -409.396184)
				(end 162.567366 -409.396184)
			)
		)
		(stroke
			(width 0)
			(type solid)
		)
		(fill yes)
		(layer "F.Cu")
		(net "GND")
	)
	(gr_poly
		(pts
			(arc
				(start 162.567366 -407.638504)
				(mid 162.201606 -407.638504)
				(end 162.567366 -407.638504)
			)
		)
		(stroke
			(width 0)
			(type solid)
		)
		(fill yes)
		(layer "F.Cu")
		(net "GND")
	)
	(gr_poly
		(pts
			(arc
				(start 162.567366 -406.370536)
				(mid 162.201606 -406.370536)
				(end 162.567366 -406.370536)
			)
		)
		(stroke
			(width 0)
			(type solid)
		)
		(fill yes)
		(layer "F.Cu")
		(net "GND")
	)
	(gr_poly
		(pts
			(arc
				(start 163.025582 -404.51786)
				(mid 162.659822 -404.51786)
				(end 163.025582 -404.51786)
			)
		)
		(stroke
			(width 0)
			(type solid)
		)
		(fill yes)
		(layer "F.Cu")
		(net "GND")
	)
	(gr_poly
		(pts
			(arc
				(start 163.025582 -403.249892)
				(mid 162.659822 -403.249892)
				(end 163.025582 -403.249892)
			)
		)
		(stroke
			(width 0)
			(type solid)
		)
		(fill yes)
		(layer "F.Cu")
		(net "GND")
	)
	(gr_poly
		(pts
			(arc
				(start 163.025582 -401.492212)
				(mid 162.659822 -401.492212)
				(end 163.025582 -401.492212)
			)
		)
		(stroke
			(width 0)
			(type solid)
		)
		(fill yes)
		(layer "F.Cu")
		(net "GND")
	)
	(gr_poly
		(pts
			(arc
				(start 163.025582 -400.200368)
				(mid 162.659822 -400.200368)
				(end 163.025582 -400.200368)
			)
		)
		(stroke
			(width 0)
			(type solid)
		)
		(fill yes)
		(layer "F.Cu")
		(net "GND")
	)
	(gr_poly
		(pts
			(arc
				(start 164.10178 -15.395448)
				(mid 163.73602 -15.395448)
				(end 164.10178 -15.395448)
			)
		)
		(stroke
			(width 0)
			(type solid)
		)
		(fill yes)
		(layer "F.Cu")
		(net "GND")
	)
	(gr_poly
		(pts
			(arc
				(start 164.146992 -78.390242)
				(mid 163.781232 -78.390242)
				(end 164.146992 -78.390242)
			)
		)
		(stroke
			(width 0)
			(type solid)
		)
		(fill yes)
		(layer "F.Cu")
		(net "GND")
	)
	(gr_poly
		(pts
			(arc
				(start 164.217858 -77.289914)
				(mid 163.852098 -77.289914)
				(end 164.217858 -77.289914)
			)
		)
		(stroke
			(width 0)
			(type solid)
		)
		(fill yes)
		(layer "F.Cu")
		(net "GND")
	)
	(gr_poly
		(pts
			(arc
				(start 164.235384 -75.242674)
				(mid 163.869624 -75.242674)
				(end 164.235384 -75.242674)
			)
		)
		(stroke
			(width 0)
			(type solid)
		)
		(fill yes)
		(layer "F.Cu")
		(net "GND")
	)
	(gr_poly
		(pts
			(arc
				(start 164.284406 -404.51786)
				(mid 163.918646 -404.51786)
				(end 164.284406 -404.51786)
			)
		)
		(stroke
			(width 0)
			(type solid)
		)
		(fill yes)
		(layer "F.Cu")
		(net "GND")
	)
	(gr_poly
		(pts
			(arc
				(start 164.284406 -403.249892)
				(mid 163.918646 -403.249892)
				(end 164.284406 -403.249892)
			)
		)
		(stroke
			(width 0)
			(type solid)
		)
		(fill yes)
		(layer "F.Cu")
		(net "GND")
	)
	(gr_poly
		(pts
			(arc
				(start 164.284406 -401.492212)
				(mid 163.918646 -401.492212)
				(end 164.284406 -401.492212)
			)
		)
		(stroke
			(width 0)
			(type solid)
		)
		(fill yes)
		(layer "F.Cu")
		(net "GND")
	)
	(gr_poly
		(pts
			(arc
				(start 164.284406 -400.200368)
				(mid 163.918646 -400.200368)
				(end 164.284406 -400.200368)
			)
		)
		(stroke
			(width 0)
			(type solid)
		)
		(fill yes)
		(layer "F.Cu")
		(net "GND")
	)
	(gr_poly
		(pts
			(arc
				(start 164.371782 -410.664152)
				(mid 164.006022 -410.664152)
				(end 164.371782 -410.664152)
			)
		)
		(stroke
			(width 0)
			(type solid)
		)
		(fill yes)
		(layer "F.Cu")
		(net "GND")
	)
	(gr_poly
		(pts
			(arc
				(start 164.371782 -409.396184)
				(mid 164.006022 -409.396184)
				(end 164.371782 -409.396184)
			)
		)
		(stroke
			(width 0)
			(type solid)
		)
		(fill yes)
		(layer "F.Cu")
		(net "GND")
	)
	(gr_poly
		(pts
			(arc
				(start 164.371782 -407.638504)
				(mid 164.006022 -407.638504)
				(end 164.371782 -407.638504)
			)
		)
		(stroke
			(width 0)
			(type solid)
		)
		(fill yes)
		(layer "F.Cu")
		(net "GND")
	)
	(gr_poly
		(pts
			(arc
				(start 164.371782 -406.34666)
				(mid 164.006022 -406.34666)
				(end 164.371782 -406.34666)
			)
		)
		(stroke
			(width 0)
			(type solid)
		)
		(fill yes)
		(layer "F.Cu")
		(net "GND")
	)
	(gr_poly
		(pts
			(arc
				(start 164.37864 -11.082528)
				(mid 164.01288 -11.082528)
				(end 164.37864 -11.082528)
			)
		)
		(stroke
			(width 0)
			(type solid)
		)
		(fill yes)
		(layer "F.Cu")
		(net "GND")
	)
	(gr_poly
		(pts
			(arc
				(start 164.57168 -89.9922)
				(mid 164.20592 -89.9922)
				(end 164.57168 -89.9922)
			)
		)
		(stroke
			(width 0)
			(type solid)
		)
		(fill yes)
		(layer "F.Cu")
		(net "GND")
	)
	(gr_poly
		(pts
			(arc
				(start 165.630606 -410.664152)
				(mid 165.264846 -410.664152)
				(end 165.630606 -410.664152)
			)
		)
		(stroke
			(width 0)
			(type solid)
		)
		(fill yes)
		(layer "F.Cu")
		(net "GND")
	)
	(gr_poly
		(pts
			(arc
				(start 165.630606 -409.396184)
				(mid 165.264846 -409.396184)
				(end 165.630606 -409.396184)
			)
		)
		(stroke
			(width 0)
			(type solid)
		)
		(fill yes)
		(layer "F.Cu")
		(net "GND")
	)
	(gr_poly
		(pts
			(arc
				(start 165.630606 -407.638504)
				(mid 165.264846 -407.638504)
				(end 165.630606 -407.638504)
			)
		)
		(stroke
			(width 0)
			(type solid)
		)
		(fill yes)
		(layer "F.Cu")
		(net "GND")
	)
	(gr_poly
		(pts
			(arc
				(start 165.630606 -406.34666)
				(mid 165.264846 -406.34666)
				(end 165.630606 -406.34666)
			)
		)
		(stroke
			(width 0)
			(type solid)
		)
		(fill yes)
		(layer "F.Cu")
		(net "GND")
	)
	(gr_poly
		(pts
			(arc
				(start 166.088822 -404.51786)
				(mid 165.723062 -404.51786)
				(end 166.088822 -404.51786)
			)
		)
		(stroke
			(width 0)
			(type solid)
		)
		(fill yes)
		(layer "F.Cu")
		(net "GND")
	)
	(gr_poly
		(pts
			(arc
				(start 166.088822 -403.249892)
				(mid 165.723062 -403.249892)
				(end 166.088822 -403.249892)
			)
		)
		(stroke
			(width 0)
			(type solid)
		)
		(fill yes)
		(layer "F.Cu")
		(net "GND")
	)
	(gr_poly
		(pts
			(arc
				(start 166.088822 -401.492212)
				(mid 165.723062 -401.492212)
				(end 166.088822 -401.492212)
			)
		)
		(stroke
			(width 0)
			(type solid)
		)
		(fill yes)
		(layer "F.Cu")
		(net "GND")
	)
	(gr_poly
		(pts
			(arc
				(start 166.088822 -400.224244)
				(mid 165.723062 -400.224244)
				(end 166.088822 -400.224244)
			)
		)
		(stroke
			(width 0)
			(type solid)
		)
		(fill yes)
		(layer "F.Cu")
		(net "GND")
	)
	(gr_poly
		(pts
			(arc
				(start 166.416736 -11.463782)
				(mid 166.050976 -11.463782)
				(end 166.416736 -11.463782)
			)
		)
		(stroke
			(width 0)
			(type solid)
		)
		(fill yes)
		(layer "F.Cu")
		(net "GND")
	)
	(gr_poly
		(pts
			(arc
				(start 166.452804 -363.525562)
				(mid 166.087044 -363.525562)
				(end 166.452804 -363.525562)
			)
		)
		(stroke
			(width 0)
			(type solid)
		)
		(fill yes)
		(layer "F.Cu")
		(net "GND")
	)
	(gr_poly
		(pts
			(arc
				(start 167.347646 -404.51786)
				(mid 166.981886 -404.51786)
				(end 167.347646 -404.51786)
			)
		)
		(stroke
			(width 0)
			(type solid)
		)
		(fill yes)
		(layer "F.Cu")
		(net "GND")
	)
	(gr_poly
		(pts
			(arc
				(start 167.347646 -403.249892)
				(mid 166.981886 -403.249892)
				(end 167.347646 -403.249892)
			)
		)
		(stroke
			(width 0)
			(type solid)
		)
		(fill yes)
		(layer "F.Cu")
		(net "GND")
	)
	(gr_poly
		(pts
			(arc
				(start 167.347646 -401.492212)
				(mid 166.981886 -401.492212)
				(end 167.347646 -401.492212)
			)
		)
		(stroke
			(width 0)
			(type solid)
		)
		(fill yes)
		(layer "F.Cu")
		(net "GND")
	)
	(gr_poly
		(pts
			(arc
				(start 167.347646 -400.224244)
				(mid 166.981886 -400.224244)
				(end 167.347646 -400.224244)
			)
		)
		(stroke
			(width 0)
			(type solid)
		)
		(fill yes)
		(layer "F.Cu")
		(net "GND")
	)
	(gr_poly
		(pts
			(arc
				(start 167.435022 -410.664152)
				(mid 167.069262 -410.664152)
				(end 167.435022 -410.664152)
			)
		)
		(stroke
			(width 0)
			(type solid)
		)
		(fill yes)
		(layer "F.Cu")
		(net "GND")
	)
	(gr_poly
		(pts
			(arc
				(start 167.435022 -409.396184)
				(mid 167.069262 -409.396184)
				(end 167.435022 -409.396184)
			)
		)
		(stroke
			(width 0)
			(type solid)
		)
		(fill yes)
		(layer "F.Cu")
		(net "GND")
	)
	(gr_poly
		(pts
			(arc
				(start 167.435022 -407.638504)
				(mid 167.069262 -407.638504)
				(end 167.435022 -407.638504)
			)
		)
		(stroke
			(width 0)
			(type solid)
		)
		(fill yes)
		(layer "F.Cu")
		(net "GND")
	)
	(gr_poly
		(pts
			(arc
				(start 167.435022 -406.370536)
				(mid 167.069262 -406.370536)
				(end 167.435022 -406.370536)
			)
		)
		(stroke
			(width 0)
			(type solid)
		)
		(fill yes)
		(layer "F.Cu")
		(net "GND")
	)
	(gr_poly
		(pts
			(arc
				(start 168.693846 -410.664152)
				(mid 168.328086 -410.664152)
				(end 168.693846 -410.664152)
			)
		)
		(stroke
			(width 0)
			(type solid)
		)
		(fill yes)
		(layer "F.Cu")
		(net "GND")
	)
	(gr_poly
		(pts
			(arc
				(start 168.693846 -409.396184)
				(mid 168.328086 -409.396184)
				(end 168.693846 -409.396184)
			)
		)
		(stroke
			(width 0)
			(type solid)
		)
		(fill yes)
		(layer "F.Cu")
		(net "GND")
	)
	(gr_poly
		(pts
			(arc
				(start 168.693846 -407.638504)
				(mid 168.328086 -407.638504)
				(end 168.693846 -407.638504)
			)
		)
		(stroke
			(width 0)
			(type solid)
		)
		(fill yes)
		(layer "F.Cu")
		(net "GND")
	)
	(gr_poly
		(pts
			(arc
				(start 168.693846 -406.370536)
				(mid 168.328086 -406.370536)
				(end 168.693846 -406.370536)
			)
		)
		(stroke
			(width 0)
			(type solid)
		)
		(fill yes)
		(layer "F.Cu")
		(net "GND")
	)
	(gr_poly
		(pts
			(arc
				(start 170.87215 -11.206226)
				(mid 170.50639 -11.206226)
				(end 170.87215 -11.206226)
			)
		)
		(stroke
			(width 0)
			(type solid)
		)
		(fill yes)
		(layer "F.Cu")
		(net "GND")
	)
	(gr_poly
		(pts
			(arc
				(start 171.31538 -19.733768)
				(mid 170.94962 -19.733768)
				(end 171.31538 -19.733768)
			)
		)
		(stroke
			(width 0)
			(type solid)
		)
		(fill yes)
		(layer "F.Cu")
		(net "GND")
	)
	(gr_poly
		(pts
			(arc
				(start 171.69003 -14.759432)
				(mid 171.32427 -14.759432)
				(end 171.69003 -14.759432)
			)
		)
		(stroke
			(width 0)
			(type solid)
		)
		(fill yes)
		(layer "F.Cu")
		(net "GND")
	)
	(gr_poly
		(pts
			(arc
				(start 173.63694 -18.451068)
				(mid 173.27118 -18.451068)
				(end 173.63694 -18.451068)
			)
		)
		(stroke
			(width 0)
			(type solid)
		)
		(fill yes)
		(layer "F.Cu")
		(net "GND")
	)
	(gr_poly
		(pts
			(arc
				(start 176.0474 -11.057128)
				(mid 175.68164 -11.057128)
				(end 176.0474 -11.057128)
			)
		)
		(stroke
			(width 0)
			(type solid)
		)
		(fill yes)
		(layer "F.Cu")
		(net "GND")
	)
	(gr_poly
		(pts
			(arc
				(start 177.179732 -11.458448)
				(mid 176.813972 -11.458448)
				(end 177.179732 -11.458448)
			)
		)
		(stroke
			(width 0)
			(type solid)
		)
		(fill yes)
		(layer "F.Cu")
		(net "GND")
	)
	(gr_poly
		(pts
			(arc
				(start 178.13782 -14.676628)
				(mid 177.77206 -14.676628)
				(end 178.13782 -14.676628)
			)
		)
		(stroke
			(width 0)
			(type solid)
		)
		(fill yes)
		(layer "F.Cu")
		(net "GND")
	)
	(gr_poly
		(pts
			(arc
				(start 178.449732 -11.458448)
				(mid 178.083972 -11.458448)
				(end 178.449732 -11.458448)
			)
		)
		(stroke
			(width 0)
			(type solid)
		)
		(fill yes)
		(layer "F.Cu")
		(net "GND")
	)
	(gr_poly
		(pts
			(arc
				(start 181.590188 -54.152546)
				(mid 181.224428 -54.152546)
				(end 181.590188 -54.152546)
			)
		)
		(stroke
			(width 0)
			(type solid)
		)
		(fill yes)
		(layer "F.Cu")
		(net "GND")
	)
	(gr_poly
		(pts
			(arc
				(start 181.590188 -52.893722)
				(mid 181.224428 -52.893722)
				(end 181.590188 -52.893722)
			)
		)
		(stroke
			(width 0)
			(type solid)
		)
		(fill yes)
		(layer "F.Cu")
		(net "GND")
	)
	(gr_poly
		(pts
			(arc
				(start 181.590188 -51.14671)
				(mid 181.224428 -51.14671)
				(end 181.590188 -51.14671)
			)
		)
		(stroke
			(width 0)
			(type solid)
		)
		(fill yes)
		(layer "F.Cu")
		(net "GND")
	)
	(gr_poly
		(pts
			(arc
				(start 181.590188 -49.887886)
				(mid 181.224428 -49.887886)
				(end 181.590188 -49.887886)
			)
		)
		(stroke
			(width 0)
			(type solid)
		)
		(fill yes)
		(layer "F.Cu")
		(net "GND")
	)
	(gr_poly
		(pts
			(arc
				(start 181.590188 -48.22571)
				(mid 181.224428 -48.22571)
				(end 181.590188 -48.22571)
			)
		)
		(stroke
			(width 0)
			(type solid)
		)
		(fill yes)
		(layer "F.Cu")
		(net "GND")
	)
	(gr_poly
		(pts
			(arc
				(start 181.590188 -46.966886)
				(mid 181.224428 -46.966886)
				(end 181.590188 -46.966886)
			)
		)
		(stroke
			(width 0)
			(type solid)
		)
		(fill yes)
		(layer "F.Cu")
		(net "GND")
	)
	(gr_poly
		(pts
			(arc
				(start 181.590188 -45.17771)
				(mid 181.224428 -45.17771)
				(end 181.590188 -45.17771)
			)
		)
		(stroke
			(width 0)
			(type solid)
		)
		(fill yes)
		(layer "F.Cu")
		(net "GND")
	)
	(gr_poly
		(pts
			(arc
				(start 181.590188 -43.918886)
				(mid 181.224428 -43.918886)
				(end 181.590188 -43.918886)
			)
		)
		(stroke
			(width 0)
			(type solid)
		)
		(fill yes)
		(layer "F.Cu")
		(net "GND")
	)
	(gr_poly
		(pts
			(arc
				(start 182.858156 -54.152546)
				(mid 182.492396 -54.152546)
				(end 182.858156 -54.152546)
			)
		)
		(stroke
			(width 0)
			(type solid)
		)
		(fill yes)
		(layer "F.Cu")
		(net "GND")
	)
	(gr_poly
		(pts
			(arc
				(start 182.858156 -52.893722)
				(mid 182.492396 -52.893722)
				(end 182.858156 -52.893722)
			)
		)
		(stroke
			(width 0)
			(type solid)
		)
		(fill yes)
		(layer "F.Cu")
		(net "GND")
	)
	(gr_poly
		(pts
			(arc
				(start 182.858156 -51.14671)
				(mid 182.492396 -51.14671)
				(end 182.858156 -51.14671)
			)
		)
		(stroke
			(width 0)
			(type solid)
		)
		(fill yes)
		(layer "F.Cu")
		(net "GND")
	)
	(gr_poly
		(pts
			(arc
				(start 182.858156 -49.887886)
				(mid 182.492396 -49.887886)
				(end 182.858156 -49.887886)
			)
		)
		(stroke
			(width 0)
			(type solid)
		)
		(fill yes)
		(layer "F.Cu")
		(net "GND")
	)
	(gr_poly
		(pts
			(arc
				(start 182.858156 -48.22571)
				(mid 182.492396 -48.22571)
				(end 182.858156 -48.22571)
			)
		)
		(stroke
			(width 0)
			(type solid)
		)
		(fill yes)
		(layer "F.Cu")
		(net "GND")
	)
	(gr_poly
		(pts
			(arc
				(start 182.858156 -46.966886)
				(mid 182.492396 -46.966886)
				(end 182.858156 -46.966886)
			)
		)
		(stroke
			(width 0)
			(type solid)
		)
		(fill yes)
		(layer "F.Cu")
		(net "GND")
	)
	(gr_poly
		(pts
			(arc
				(start 182.858156 -45.17771)
				(mid 182.492396 -45.17771)
				(end 182.858156 -45.17771)
			)
		)
		(stroke
			(width 0)
			(type solid)
		)
		(fill yes)
		(layer "F.Cu")
		(net "GND")
	)
	(gr_poly
		(pts
			(arc
				(start 182.858156 -43.918886)
				(mid 182.492396 -43.918886)
				(end 182.858156 -43.918886)
			)
		)
		(stroke
			(width 0)
			(type solid)
		)
		(fill yes)
		(layer "F.Cu")
		(net "GND")
	)
	(gr_poly
		(pts
			(arc
				(start 185.3438 -10.127488)
				(mid 184.97804 -10.127488)
				(end 185.3438 -10.127488)
			)
		)
		(stroke
			(width 0)
			(type solid)
		)
		(fill yes)
		(layer "F.Cu")
		(net "GND")
	)
	(gr_poly
		(pts
			(arc
				(start 185.39968 -149.593808)
				(mid 185.03392 -149.593808)
				(end 185.39968 -149.593808)
			)
		)
		(stroke
			(width 0)
			(type solid)
		)
		(fill yes)
		(layer "F.Cu")
		(net "GND")
	)
	(gr_poly
		(pts
			(arc
				(start 185.9407 -15.420848)
				(mid 185.57494 -15.420848)
				(end 185.9407 -15.420848)
			)
		)
		(stroke
			(width 0)
			(type solid)
		)
		(fill yes)
		(layer "F.Cu")
		(net "GND")
	)
	(gr_poly
		(pts
			(arc
				(start 187.32754 -10.117328)
				(mid 186.96178 -10.117328)
				(end 187.32754 -10.117328)
			)
		)
		(stroke
			(width 0)
			(type solid)
		)
		(fill yes)
		(layer "F.Cu")
		(net "GND")
	)
	(gr_poly
		(pts
			(arc
				(start 187.941204 -154.43708)
				(mid 187.575444 -154.43708)
				(end 187.941204 -154.43708)
			)
		)
		(stroke
			(width 0)
			(type solid)
		)
		(fill yes)
		(layer "F.Cu")
		(net "GND")
	)
	(gr_poly
		(pts
			(arc
				(start 187.941204 -153.178256)
				(mid 187.575444 -153.178256)
				(end 187.941204 -153.178256)
			)
		)
		(stroke
			(width 0)
			(type solid)
		)
		(fill yes)
		(layer "F.Cu")
		(net "GND")
	)
	(gr_poly
		(pts
			(arc
				(start 188.86424 -10.117328)
				(mid 188.49848 -10.117328)
				(end 188.86424 -10.117328)
			)
		)
		(stroke
			(width 0)
			(type solid)
		)
		(fill yes)
		(layer "F.Cu")
		(net "GND")
	)
	(gr_poly
		(pts
			(arc
				(start 191.37376 -14.986508)
				(mid 191.008 -14.986508)
				(end 191.37376 -14.986508)
			)
		)
		(stroke
			(width 0)
			(type solid)
		)
		(fill yes)
		(layer "F.Cu")
		(net "GND")
	)
	(gr_poly
		(pts
			(arc
				(start 192.00368 -75.199748)
				(mid 191.63792 -75.199748)
				(end 192.00368 -75.199748)
			)
		)
		(stroke
			(width 0)
			(type solid)
		)
		(fill yes)
		(layer "F.Cu")
		(net "GND")
	)
	(gr_poly
		(pts
			(arc
				(start 193.824352 -21.358352)
				(mid 193.458592 -21.358352)
				(end 193.824352 -21.358352)
			)
		)
		(stroke
			(width 0)
			(type solid)
		)
		(fill yes)
		(layer "F.Cu")
		(net "GND")
	)
	(gr_poly
		(pts
			(arc
				(start 195.007992 -23.23846)
				(mid 194.642232 -23.23846)
				(end 195.007992 -23.23846)
			)
		)
		(stroke
			(width 0)
			(type solid)
		)
		(fill yes)
		(layer "F.Cu")
		(net "GND")
	)
	(gr_poly
		(pts
			(arc
				(start 195.01231 -24.37384)
				(mid 194.64655 -24.37384)
				(end 195.01231 -24.37384)
			)
		)
		(stroke
			(width 0)
			(type solid)
		)
		(fill yes)
		(layer "F.Cu")
		(net "GND")
	)
	(gr_poly
		(pts
			(arc
				(start 195.016374 -25.389586)
				(mid 194.650614 -25.389586)
				(end 195.016374 -25.389586)
			)
		)
		(stroke
			(width 0)
			(type solid)
		)
		(fill yes)
		(layer "F.Cu")
		(net "GND")
	)
	(gr_poly
		(pts
			(arc
				(start 195.581016 -26.38933)
				(mid 195.215256 -26.38933)
				(end 195.581016 -26.38933)
			)
		)
		(stroke
			(width 0)
			(type solid)
		)
		(fill yes)
		(layer "F.Cu")
		(net "GND")
	)
	(gr_poly
		(pts
			(arc
				(start 195.70573 -27.426158)
				(mid 195.33997 -27.426158)
				(end 195.70573 -27.426158)
			)
		)
		(stroke
			(width 0)
			(type solid)
		)
		(fill yes)
		(layer "F.Cu")
		(net "GND")
	)
	(gr_poly
		(pts
			(arc
				(start 196.050154 -28.394152)
				(mid 195.684394 -28.394152)
				(end 196.050154 -28.394152)
			)
		)
		(stroke
			(width 0)
			(type solid)
		)
		(fill yes)
		(layer "F.Cu")
		(net "GND")
	)
	(gr_poly
		(pts
			(arc
				(start 196.58076 -75.250548)
				(mid 196.215 -75.250548)
				(end 196.58076 -75.250548)
			)
		)
		(stroke
			(width 0)
			(type solid)
		)
		(fill yes)
		(layer "F.Cu")
		(net "GND")
	)
	(gr_poly
		(pts
			(arc
				(start 196.764402 -29.116782)
				(mid 196.398642 -29.116782)
				(end 196.764402 -29.116782)
			)
		)
		(stroke
			(width 0)
			(type solid)
		)
		(fill yes)
		(layer "F.Cu")
		(net "GND")
	)
	(gr_poly
		(pts
			(arc
				(start 197.4723 -29.839666)
				(mid 197.10654 -29.839666)
				(end 197.4723 -29.839666)
			)
		)
		(stroke
			(width 0)
			(type solid)
		)
		(fill yes)
		(layer "F.Cu")
		(net "GND")
	)
	(gr_poly
		(pts
			(arc
				(start 198.07936 -77.765148)
				(mid 197.7136 -77.765148)
				(end 198.07936 -77.765148)
			)
		)
		(stroke
			(width 0)
			(type solid)
		)
		(fill yes)
		(layer "F.Cu")
		(net "GND")
	)
	(gr_poly
		(pts
			(arc
				(start 202.16114 -75.837288)
				(mid 201.79538 -75.837288)
				(end 202.16114 -75.837288)
			)
		)
		(stroke
			(width 0)
			(type solid)
		)
		(fill yes)
		(layer "F.Cu")
		(net "GND")
	)
	(gr_poly
		(pts
			(arc
				(start 204.98308 -71.034148)
				(mid 204.61732 -71.034148)
				(end 204.98308 -71.034148)
			)
		)
		(stroke
			(width 0)
			(type solid)
		)
		(fill yes)
		(layer "F.Cu")
		(net "GND")
	)
	(gr_poly
		(pts
			(arc
				(start 205.056232 -89.178638)
				(mid 204.690472 -89.178638)
				(end 205.056232 -89.178638)
			)
		)
		(stroke
			(width 0)
			(type solid)
		)
		(fill yes)
		(layer "F.Cu")
		(net "GND")
	)
	(gr_poly
		(pts
			(arc
				(start 205.84668 -69.484748)
				(mid 205.48092 -69.484748)
				(end 205.84668 -69.484748)
			)
		)
		(stroke
			(width 0)
			(type solid)
		)
		(fill yes)
		(layer "F.Cu")
		(net "GND")
	)
	(gr_poly
		(pts
			(arc
				(start 206.121254 -94.64421)
				(mid 205.755494 -94.64421)
				(end 206.121254 -94.64421)
			)
		)
		(stroke
			(width 0)
			(type solid)
		)
		(fill yes)
		(layer "F.Cu")
		(net "GND")
	)
	(gr_poly
		(pts
			(arc
				(start 206.90205 -89.918032)
				(mid 206.53629 -89.918032)
				(end 206.90205 -89.918032)
			)
		)
		(stroke
			(width 0)
			(type solid)
		)
		(fill yes)
		(layer "F.Cu")
		(net "GND")
	)
	(gr_poly
		(pts
			(arc
				(start 207.55356 -72.913748)
				(mid 207.1878 -72.913748)
				(end 207.55356 -72.913748)
			)
		)
		(stroke
			(width 0)
			(type solid)
		)
		(fill yes)
		(layer "F.Cu")
		(net "GND")
	)
	(gr_poly
		(pts
			(arc
				(start 208.700624 -90.666824)
				(mid 208.334864 -90.666824)
				(end 208.700624 -90.666824)
			)
		)
		(stroke
			(width 0)
			(type solid)
		)
		(fill yes)
		(layer "F.Cu")
		(net "GND")
	)
	(gr_poly
		(pts
			(arc
				(start 208.758536 -94.567248)
				(mid 208.392776 -94.567248)
				(end 208.758536 -94.567248)
			)
		)
		(stroke
			(width 0)
			(type solid)
		)
		(fill yes)
		(layer "F.Cu")
		(net "GND")
	)
	(gr_poly
		(pts
			(arc
				(start 210.551268 -91.42984)
				(mid 210.185508 -91.42984)
				(end 210.551268 -91.42984)
			)
		)
		(stroke
			(width 0)
			(type solid)
		)
		(fill yes)
		(layer "F.Cu")
		(net "GND")
	)
	(gr_poly
		(pts
			(arc
				(start 210.93176 -70.500748)
				(mid 210.566 -70.500748)
				(end 210.93176 -70.500748)
			)
		)
		(stroke
			(width 0)
			(type solid)
		)
		(fill yes)
		(layer "F.Cu")
		(net "GND")
	)
	(gr_poly
		(pts
			(arc
				(start 210.95208 -68.976748)
				(mid 210.58632 -68.976748)
				(end 210.95208 -68.976748)
			)
		)
		(stroke
			(width 0)
			(type solid)
		)
		(fill yes)
		(layer "F.Cu")
		(net "GND")
	)
	(gr_poly
		(pts
			(arc
				(start 212.12048 -72.100948)
				(mid 211.75472 -72.100948)
				(end 212.12048 -72.100948)
			)
		)
		(stroke
			(width 0)
			(type solid)
		)
		(fill yes)
		(layer "F.Cu")
		(net "GND")
	)
	(gr_poly
		(pts
			(arc
				(start 212.24748 -74.539348)
				(mid 211.88172 -74.539348)
				(end 212.24748 -74.539348)
			)
		)
		(stroke
			(width 0)
			(type solid)
		)
		(fill yes)
		(layer "F.Cu")
		(net "GND")
	)
	(gr_poly
		(pts
			(arc
				(start 212.392514 -92.202762)
				(mid 212.026754 -92.202762)
				(end 212.392514 -92.202762)
			)
		)
		(stroke
			(width 0)
			(type solid)
		)
		(fill yes)
		(layer "F.Cu")
		(net "GND")
	)
	(gr_poly
		(pts
			(arc
				(start 214.338662 -93.004132)
				(mid 213.972902 -93.004132)
				(end 214.338662 -93.004132)
			)
		)
		(stroke
			(width 0)
			(type solid)
		)
		(fill yes)
		(layer "F.Cu")
		(net "GND")
	)
	(gr_poly
		(pts
			(arc
				(start 216.154 -28.918408)
				(mid 215.78824 -28.918408)
				(end 216.154 -28.918408)
			)
		)
		(stroke
			(width 0)
			(type solid)
		)
		(fill yes)
		(layer "F.Cu")
		(net "GND")
	)
	(gr_poly
		(pts
			(arc
				(start 216.437464 -93.881956)
				(mid 216.071704 -93.881956)
				(end 216.437464 -93.881956)
			)
		)
		(stroke
			(width 0)
			(type solid)
		)
		(fill yes)
		(layer "F.Cu")
		(net "GND")
	)
	(gr_poly
		(pts
			(arc
				(start 216.79408 -73.294748)
				(mid 216.42832 -73.294748)
				(end 216.79408 -73.294748)
			)
		)
		(stroke
			(width 0)
			(type solid)
		)
		(fill yes)
		(layer "F.Cu")
		(net "GND")
	)
	(gr_poly
		(pts
			(arc
				(start 216.89568 -75.555348)
				(mid 216.52992 -75.555348)
				(end 216.89568 -75.555348)
			)
		)
		(stroke
			(width 0)
			(type solid)
		)
		(fill yes)
		(layer "F.Cu")
		(net "GND")
	)
	(gr_poly
		(pts
			(arc
				(start 217.78468 -77.434948)
				(mid 217.41892 -77.434948)
				(end 217.78468 -77.434948)
			)
		)
		(stroke
			(width 0)
			(type solid)
		)
		(fill yes)
		(layer "F.Cu")
		(net "GND")
	)
	(gr_poly
		(pts
			(arc
				(start 218.555316 -94.750128)
				(mid 218.189556 -94.750128)
				(end 218.555316 -94.750128)
			)
		)
		(stroke
			(width 0)
			(type solid)
		)
		(fill yes)
		(layer "F.Cu")
		(net "GND")
	)
	(gr_poly
		(pts
			(arc
				(start 218.860878 -18.256758)
				(mid 218.495118 -18.256758)
				(end 218.860878 -18.256758)
			)
		)
		(stroke
			(width 0)
			(type solid)
		)
		(fill yes)
		(layer "F.Cu")
		(net "GND")
	)
	(gr_poly
		(pts
			(arc
				(start 218.96578 -15.664688)
				(mid 218.60002 -15.664688)
				(end 218.96578 -15.664688)
			)
		)
		(stroke
			(width 0)
			(type solid)
		)
		(fill yes)
		(layer "F.Cu")
		(net "GND")
	)
	(gr_poly
		(pts
			(arc
				(start 220.635068 -95.6183)
				(mid 220.269308 -95.6183)
				(end 220.635068 -95.6183)
			)
		)
		(stroke
			(width 0)
			(type solid)
		)
		(fill yes)
		(layer "F.Cu")
		(net "GND")
	)
	(gr_poly
		(pts
			(arc
				(start 220.702378 -18.289524)
				(mid 220.336618 -18.289524)
				(end 220.702378 -18.289524)
			)
		)
		(stroke
			(width 0)
			(type solid)
		)
		(fill yes)
		(layer "F.Cu")
		(net "GND")
	)
	(gr_poly
		(pts
			(arc
				(start 222.667068 -96.467422)
				(mid 222.301308 -96.467422)
				(end 222.667068 -96.467422)
			)
		)
		(stroke
			(width 0)
			(type solid)
		)
		(fill yes)
		(layer "F.Cu")
		(net "GND")
	)
	(gr_poly
		(pts
			(arc
				(start 223.823022 -83.65998)
				(mid 223.457262 -83.65998)
				(end 223.823022 -83.65998)
			)
		)
		(stroke
			(width 0)
			(type solid)
		)
		(fill yes)
		(layer "F.Cu")
		(net "GND")
	)
	(gr_poly
		(pts
			(arc
				(start 224.584768 -97.25914)
				(mid 224.219008 -97.25914)
				(end 224.584768 -97.25914)
			)
		)
		(stroke
			(width 0)
			(type solid)
		)
		(fill yes)
		(layer "F.Cu")
		(net "GND")
	)
	(gr_poly
		(pts
			(arc
				(start 225.318828 -135.73252)
				(mid 224.953068 -135.73252)
				(end 225.318828 -135.73252)
			)
		)
		(stroke
			(width 0)
			(type solid)
		)
		(fill yes)
		(layer "F.Cu")
		(net "GND")
	)
	(gr_poly
		(pts
			(arc
				(start 225.651314 -125.670818)
				(mid 225.285554 -125.670818)
				(end 225.651314 -125.670818)
			)
		)
		(stroke
			(width 0)
			(type solid)
		)
		(fill yes)
		(layer "F.Cu")
		(net "GND")
	)
	(gr_poly
		(pts
			(arc
				(start 225.651314 -123.909074)
				(mid 225.285554 -123.909074)
				(end 225.651314 -123.909074)
			)
		)
		(stroke
			(width 0)
			(type solid)
		)
		(fill yes)
		(layer "F.Cu")
		(net "GND")
	)
	(gr_poly
		(pts
			(arc
				(start 225.701606 -98.200972)
				(mid 225.335846 -98.200972)
				(end 225.701606 -98.200972)
			)
		)
		(stroke
			(width 0)
			(type solid)
		)
		(fill yes)
		(layer "F.Cu")
		(net "GND")
	)
	(gr_poly
		(pts
			(arc
				(start 227.080572 -135.73252)
				(mid 226.714812 -135.73252)
				(end 227.080572 -135.73252)
			)
		)
		(stroke
			(width 0)
			(type solid)
		)
		(fill yes)
		(layer "F.Cu")
		(net "GND")
	)
	(gr_poly
		(pts
			(arc
				(start 227.13188 -86.121748)
				(mid 226.76612 -86.121748)
				(end 227.13188 -86.121748)
			)
		)
		(stroke
			(width 0)
			(type solid)
		)
		(fill yes)
		(layer "F.Cu")
		(net "GND")
	)
	(gr_poly
		(pts
			(arc
				(start 227.150168 -127.7747)
				(mid 226.784408 -127.7747)
				(end 227.150168 -127.7747)
			)
		)
		(stroke
			(width 0)
			(type solid)
		)
		(fill yes)
		(layer "F.Cu")
		(net "GND")
	)
	(gr_poly
		(pts
			(arc
				(start 227.150168 -126.012956)
				(mid 226.784408 -126.012956)
				(end 227.150168 -126.012956)
			)
		)
		(stroke
			(width 0)
			(type solid)
		)
		(fill yes)
		(layer "F.Cu")
		(net "GND")
	)
	(gr_poly
		(pts
			(arc
				(start 227.350828 -232.077768)
				(mid 226.991672 -232.077768)
				(end 227.350828 -232.077768)
			)
		)
		(stroke
			(width 0)
			(type solid)
		)
		(fill yes)
		(layer "F.Cu")
		(net "GND")
	)
	(gr_poly
		(pts
			(arc
				(start 228.290628 -248.069608)
				(mid 227.924868 -248.069608)
				(end 228.290628 -248.069608)
			)
		)
		(stroke
			(width 0)
			(type solid)
		)
		(fill yes)
		(layer "F.Cu")
		(net "GND")
	)
	(gr_poly
		(pts
			(arc
				(start 228.290628 -246.307864)
				(mid 227.924868 -246.307864)
				(end 228.290628 -246.307864)
			)
		)
		(stroke
			(width 0)
			(type solid)
		)
		(fill yes)
		(layer "F.Cu")
		(net "GND")
	)
	(gr_poly
		(pts
			(arc
				(start 228.646228 -135.47852)
				(mid 228.280468 -135.47852)
				(end 228.646228 -135.47852)
			)
		)
		(stroke
			(width 0)
			(type solid)
		)
		(fill yes)
		(layer "F.Cu")
		(net "GND")
	)
	(gr_poly
		(pts
			(arc
				(start 228.68763 -120.359424)
				(mid 228.32187 -120.359424)
				(end 228.68763 -120.359424)
			)
		)
		(stroke
			(width 0)
			(type solid)
		)
		(fill yes)
		(layer "F.Cu")
		(net "GND")
	)
	(gr_poly
		(pts
			(arc
				(start 228.798374 -131.546092)
				(mid 228.432614 -131.546092)
				(end 228.798374 -131.546092)
			)
		)
		(stroke
			(width 0)
			(type solid)
		)
		(fill yes)
		(layer "F.Cu")
		(net "GND")
	)
	(gr_poly
		(pts
			(arc
				(start 228.798374 -129.784348)
				(mid 228.432614 -129.784348)
				(end 228.798374 -129.784348)
			)
		)
		(stroke
			(width 0)
			(type solid)
		)
		(fill yes)
		(layer "F.Cu")
		(net "GND")
	)
	(gr_poly
		(pts
			(arc
				(start 230.407972 -135.47852)
				(mid 230.042212 -135.47852)
				(end 230.407972 -135.47852)
			)
		)
		(stroke
			(width 0)
			(type solid)
		)
		(fill yes)
		(layer "F.Cu")
		(net "GND")
	)
	(gr_poly
		(pts
			(arc
				(start 231.735884 -132.95122)
				(mid 231.370124 -132.95122)
				(end 231.735884 -132.95122)
			)
		)
		(stroke
			(width 0)
			(type solid)
		)
		(fill yes)
		(layer "F.Cu")
		(net "GND")
	)
	(gr_poly
		(pts
			(arc
				(start 233.497628 -132.95122)
				(mid 233.131868 -132.95122)
				(end 233.497628 -132.95122)
			)
		)
		(stroke
			(width 0)
			(type solid)
		)
		(fill yes)
		(layer "F.Cu")
		(net "GND")
	)
	(gr_poly
		(pts
			(arc
				(start 233.679746 -117.155976)
				(mid 233.313986 -117.155976)
				(end 233.679746 -117.155976)
			)
		)
		(stroke
			(width 0)
			(type solid)
		)
		(fill yes)
		(layer "F.Cu")
		(net "GND")
	)
	(gr_poly
		(pts
			(arc
				(start 235.043218 -135.570976)
				(mid 234.677458 -135.570976)
				(end 235.043218 -135.570976)
			)
		)
		(stroke
			(width 0)
			(type solid)
		)
		(fill yes)
		(layer "F.Cu")
		(net "GND")
	)
	(gr_poly
		(pts
			(arc
				(start 235.043218 -133.809232)
				(mid 234.677458 -133.809232)
				(end 235.043218 -133.809232)
			)
		)
		(stroke
			(width 0)
			(type solid)
		)
		(fill yes)
		(layer "F.Cu")
		(net "GND")
	)
	(gr_poly
		(pts
			(arc
				(start 235.44149 -117.155976)
				(mid 235.07573 -117.155976)
				(end 235.44149 -117.155976)
			)
		)
		(stroke
			(width 0)
			(type solid)
		)
		(fill yes)
		(layer "F.Cu")
		(net "GND")
	)
	(gr_poly
		(pts
			(arc
				(start 237.094776 -115.706652)
				(mid 236.729016 -115.706652)
				(end 237.094776 -115.706652)
			)
		)
		(stroke
			(width 0)
			(type solid)
		)
		(fill yes)
		(layer "F.Cu")
		(net "GND")
	)
	(gr_poly
		(pts
			(arc
				(start 238.545878 -115.685316)
				(mid 238.180118 -115.685316)
				(end 238.545878 -115.685316)
			)
		)
		(stroke
			(width 0)
			(type solid)
		)
		(fill yes)
		(layer "F.Cu")
		(net "GND")
	)
	(gr_poly
		(pts
			(arc
				(start 238.713518 -133.923278)
				(mid 238.347758 -133.923278)
				(end 238.713518 -133.923278)
			)
		)
		(stroke
			(width 0)
			(type solid)
		)
		(fill yes)
		(layer "F.Cu")
		(net "GND")
	)
	(gr_poly
		(pts
			(arc
				(start 238.760508 -135.64108)
				(mid 238.394748 -135.64108)
				(end 238.760508 -135.64108)
			)
		)
		(stroke
			(width 0)
			(type solid)
		)
		(fill yes)
		(layer "F.Cu")
		(net "GND")
	)
	(gr_poly
		(pts
			(arc
				(start 239.122966 -116.951252)
				(mid 238.757206 -116.951252)
				(end 239.122966 -116.951252)
			)
		)
		(stroke
			(width 0)
			(type solid)
		)
		(fill yes)
		(layer "F.Cu")
		(net "GND")
	)
	(gr_poly
		(pts
			(arc
				(start 239.614964 -101.801422)
				(mid 239.249204 -101.801422)
				(end 239.614964 -101.801422)
			)
		)
		(stroke
			(width 0)
			(type solid)
		)
		(fill yes)
		(layer "F.Cu")
		(net "GND")
	)
	(gr_poly
		(pts
			(arc
				(start 239.660938 -109.138466)
				(mid 239.295178 -109.138466)
				(end 239.660938 -109.138466)
			)
		)
		(stroke
			(width 0)
			(type solid)
		)
		(fill yes)
		(layer "F.Cu")
		(net "GND")
	)
	(gr_poly
		(pts
			(arc
				(start 239.660938 -107.376722)
				(mid 239.295178 -107.376722)
				(end 239.660938 -107.376722)
			)
		)
		(stroke
			(width 0)
			(type solid)
		)
		(fill yes)
		(layer "F.Cu")
		(net "GND")
	)
	(gr_poly
		(pts
			(arc
				(start 240.41608 -111.607346)
				(mid 240.05032 -111.607346)
				(end 240.41608 -111.607346)
			)
		)
		(stroke
			(width 0)
			(type solid)
		)
		(fill yes)
		(layer "F.Cu")
		(net "GND")
	)
	(gr_poly
		(pts
			(arc
				(start 240.41608 -109.845602)
				(mid 240.05032 -109.845602)
				(end 240.41608 -109.845602)
			)
		)
		(stroke
			(width 0)
			(type solid)
		)
		(fill yes)
		(layer "F.Cu")
		(net "GND")
	)
	(gr_poly
		(pts
			(arc
				(start 240.591848 -116.94414)
				(mid 240.226088 -116.94414)
				(end 240.591848 -116.94414)
			)
		)
		(stroke
			(width 0)
			(type solid)
		)
		(fill yes)
		(layer "F.Cu")
		(net "GND")
	)
	(gr_poly
		(pts
			(arc
				(start 240.76914 -133.94182)
				(mid 240.40338 -133.94182)
				(end 240.76914 -133.94182)
			)
		)
		(stroke
			(width 0)
			(type solid)
		)
		(fill yes)
		(layer "F.Cu")
		(net "GND")
	)
	(gr_poly
		(pts
			(arc
				(start 241.10061 -127.707136)
				(mid 240.73485 -127.707136)
				(end 241.10061 -127.707136)
			)
		)
		(stroke
			(width 0)
			(type solid)
		)
		(fill yes)
		(layer "F.Cu")
		(net "GND")
	)
	(gr_poly
		(pts
			(arc
				(start 241.150902 -129.412238)
				(mid 240.785142 -129.412238)
				(end 241.150902 -129.412238)
			)
		)
		(stroke
			(width 0)
			(type solid)
		)
		(fill yes)
		(layer "F.Cu")
		(net "GND")
	)
	(gr_poly
		(pts
			(arc
				(start 242.148868 -134.458456)
				(mid 241.783108 -134.458456)
				(end 242.148868 -134.458456)
			)
		)
		(stroke
			(width 0)
			(type solid)
		)
		(fill yes)
		(layer "F.Cu")
		(net "GND")
	)
	(gr_poly
		(pts
			(arc
				(start 243.054632 -131.17068)
				(mid 242.688872 -131.17068)
				(end 243.054632 -131.17068)
			)
		)
		(stroke
			(width 0)
			(type solid)
		)
		(fill yes)
		(layer "F.Cu")
		(net "GND")
	)
	(gr_poly
		(pts
			(arc
				(start 243.054632 -129.408936)
				(mid 242.688872 -129.408936)
				(end 243.054632 -129.408936)
			)
		)
		(stroke
			(width 0)
			(type solid)
		)
		(fill yes)
		(layer "F.Cu")
		(net "GND")
	)
	(gr_poly
		(pts
			(arc
				(start 243.054632 -127.58928)
				(mid 242.688872 -127.58928)
				(end 243.054632 -127.58928)
			)
		)
		(stroke
			(width 0)
			(type solid)
		)
		(fill yes)
		(layer "F.Cu")
		(net "GND")
	)
	(gr_poly
		(pts
			(arc
				(start 243.054632 -125.827536)
				(mid 242.688872 -125.827536)
				(end 243.054632 -125.827536)
			)
		)
		(stroke
			(width 0)
			(type solid)
		)
		(fill yes)
		(layer "F.Cu")
		(net "GND")
	)
	(gr_poly
		(pts
			(arc
				(start 243.703856 -166.897812)
				(mid 243.343684 -166.897812)
				(end 243.703856 -166.897812)
			)
		)
		(stroke
			(width 0)
			(type solid)
		)
		(fill yes)
		(layer "F.Cu")
		(net "GND")
	)
	(gr_poly
		(pts
			(arc
				(start 243.73205 -168.244012)
				(mid 243.371878 -168.244012)
				(end 243.73205 -168.244012)
			)
		)
		(stroke
			(width 0)
			(type solid)
		)
		(fill yes)
		(layer "F.Cu")
		(net "GND")
	)
	(gr_poly
		(pts
			(arc
				(start 243.910612 -134.458456)
				(mid 243.544852 -134.458456)
				(end 243.910612 -134.458456)
			)
		)
		(stroke
			(width 0)
			(type solid)
		)
		(fill yes)
		(layer "F.Cu")
		(net "GND")
	)
	(gr_poly
		(pts
			(arc
				(start 244.572028 -135.92302)
				(mid 244.206268 -135.92302)
				(end 244.572028 -135.92302)
			)
		)
		(stroke
			(width 0)
			(type solid)
		)
		(fill yes)
		(layer "F.Cu")
		(net "GND")
	)
	(gr_poly
		(pts
			(arc
				(start 244.914166 -168.925748)
				(mid 244.553994 -168.925748)
				(end 244.914166 -168.925748)
			)
		)
		(stroke
			(width 0)
			(type solid)
		)
		(fill yes)
		(layer "F.Cu")
		(net "GND")
	)
	(gr_poly
		(pts
			(arc
				(start 246.333772 -135.92302)
				(mid 245.968012 -135.92302)
				(end 246.333772 -135.92302)
			)
		)
		(stroke
			(width 0)
			(type solid)
		)
		(fill yes)
		(layer "F.Cu")
		(net "GND")
	)
	(gr_poly
		(pts
			(arc
				(start 246.576596 -123.370086)
				(mid 246.210836 -123.370086)
				(end 246.576596 -123.370086)
			)
		)
		(stroke
			(width 0)
			(type solid)
		)
		(fill yes)
		(layer "F.Cu")
		(net "GND")
	)
	(gr_poly
		(pts
			(arc
				(start 246.576596 -121.608342)
				(mid 246.210836 -121.608342)
				(end 246.576596 -121.608342)
			)
		)
		(stroke
			(width 0)
			(type solid)
		)
		(fill yes)
		(layer "F.Cu")
		(net "GND")
	)
	(gr_poly
		(pts
			(arc
				(start 247.321324 -99.865434)
				(mid 246.955564 -99.865434)
				(end 247.321324 -99.865434)
			)
		)
		(stroke
			(width 0)
			(type solid)
		)
		(fill yes)
		(layer "F.Cu")
		(net "GND")
	)
	(gr_poly
		(pts
			(arc
				(start 248.158762 -135.693404)
				(mid 247.793002 -135.693404)
				(end 248.158762 -135.693404)
			)
		)
		(stroke
			(width 0)
			(type solid)
		)
		(fill yes)
		(layer "F.Cu")
		(net "GND")
	)
	(gr_poly
		(pts
			(arc
				(start 250.543568 -109.972094)
				(mid 250.177808 -109.972094)
				(end 250.543568 -109.972094)
			)
		)
		(stroke
			(width 0)
			(type solid)
		)
		(fill yes)
		(layer "F.Cu")
		(net "GND")
	)
	(gr_poly
		(pts
			(arc
				(start 251.175266 -103.903272)
				(mid 250.809506 -103.903272)
				(end 251.175266 -103.903272)
			)
		)
		(stroke
			(width 0)
			(type solid)
		)
		(fill yes)
		(layer "F.Cu")
		(net "GND")
	)
	(gr_poly
		(pts
			(arc
				(start 251.921518 -134.595108)
				(mid 251.555758 -134.595108)
				(end 251.921518 -134.595108)
			)
		)
		(stroke
			(width 0)
			(type solid)
		)
		(fill yes)
		(layer "F.Cu")
		(net "GND")
	)
	(gr_poly
		(pts
			(arc
				(start 252.305312 -109.972094)
				(mid 251.939552 -109.972094)
				(end 252.305312 -109.972094)
			)
		)
		(stroke
			(width 0)
			(type solid)
		)
		(fill yes)
		(layer "F.Cu")
		(net "GND")
	)
	(gr_poly
		(pts
			(arc
				(start 254.85344 -151.051768)
				(mid 254.48768 -151.051768)
				(end 254.85344 -151.051768)
			)
		)
		(stroke
			(width 0)
			(type solid)
		)
		(fill yes)
		(layer "F.Cu")
		(net "GND")
	)
	(gr_poly
		(pts
			(arc
				(start 257.132074 -109.229652)
				(mid 256.766314 -109.229652)
				(end 257.132074 -109.229652)
			)
		)
		(stroke
			(width 0)
			(type solid)
		)
		(fill yes)
		(layer "F.Cu")
		(net "GND")
	)
	(gr_poly
		(pts
			(arc
				(start 257.61188 -87.6046)
				(mid 257.24612 -87.6046)
				(end 257.61188 -87.6046)
			)
		)
		(stroke
			(width 0)
			(type solid)
		)
		(fill yes)
		(layer "F.Cu")
		(net "GND")
	)
	(gr_poly
		(pts
			(arc
				(start 258.630674 -109.229652)
				(mid 258.264914 -109.229652)
				(end 258.630674 -109.229652)
			)
		)
		(stroke
			(width 0)
			(type solid)
		)
		(fill yes)
		(layer "F.Cu")
		(net "GND")
	)
	(gr_poly
		(pts
			(arc
				(start 259.042916 -127.971042)
				(mid 258.682744 -127.971042)
				(end 259.042916 -127.971042)
			)
		)
		(stroke
			(width 0)
			(type solid)
		)
		(fill yes)
		(layer "F.Cu")
		(net "GND")
	)
	(gr_poly
		(pts
			(arc
				(start 260.21284 -151.422608)
				(mid 259.84708 -151.422608)
				(end 260.21284 -151.422608)
			)
		)
		(stroke
			(width 0)
			(type solid)
		)
		(fill yes)
		(layer "F.Cu")
		(net "GND")
	)
	(gr_poly
		(pts
			(arc
				(start 261.08914 -129.710688)
				(mid 260.72338 -129.710688)
				(end 261.08914 -129.710688)
			)
		)
		(stroke
			(width 0)
			(type solid)
		)
		(fill yes)
		(layer "F.Cu")
		(net "GND")
	)
	(gr_poly
		(pts
			(arc
				(start 261.572756 -98.519488)
				(mid 261.206996 -98.519488)
				(end 261.572756 -98.519488)
			)
		)
		(stroke
			(width 0)
			(type solid)
		)
		(fill yes)
		(layer "F.Cu")
		(net "GND")
	)
	(gr_poly
		(pts
			(arc
				(start 261.572756 -97.29978)
				(mid 261.206996 -97.29978)
				(end 261.572756 -97.29978)
			)
		)
		(stroke
			(width 0)
			(type solid)
		)
		(fill yes)
		(layer "F.Cu")
		(net "GND")
	)
	(gr_poly
		(pts
			(arc
				(start 261.60476 -132.088128)
				(mid 261.239 -132.088128)
				(end 261.60476 -132.088128)
			)
		)
		(stroke
			(width 0)
			(type solid)
		)
		(fill yes)
		(layer "F.Cu")
		(net "GND")
	)
	(gr_poly
		(pts
			(arc
				(start 262.0518 -152.075388)
				(mid 261.68604 -152.075388)
				(end 262.0518 -152.075388)
			)
		)
		(stroke
			(width 0)
			(type solid)
		)
		(fill yes)
		(layer "F.Cu")
		(net "GND")
	)
	(gr_poly
		(pts
			(arc
				(start 263.4488 -151.453088)
				(mid 263.08304 -151.453088)
				(end 263.4488 -151.453088)
			)
		)
		(stroke
			(width 0)
			(type solid)
		)
		(fill yes)
		(layer "F.Cu")
		(net "GND")
	)
	(gr_poly
		(pts
			(arc
				(start 263.89076 -149.824948)
				(mid 263.525 -149.824948)
				(end 263.89076 -149.824948)
			)
		)
		(stroke
			(width 0)
			(type solid)
		)
		(fill yes)
		(layer "F.Cu")
		(net "GND")
	)
	(gr_poly
		(pts
			(arc
				(start 265.28776 -149.697948)
				(mid 264.922 -149.697948)
				(end 265.28776 -149.697948)
			)
		)
		(stroke
			(width 0)
			(type solid)
		)
		(fill yes)
		(layer "F.Cu")
		(net "GND")
	)
	(gr_poly
		(pts
			(arc
				(start 265.90371 -112.445546)
				(mid 265.543538 -112.445546)
				(end 265.90371 -112.445546)
			)
		)
		(stroke
			(width 0)
			(type solid)
		)
		(fill yes)
		(layer "F.Cu")
		(net "GND")
	)
	(gr_poly
		(pts
			(arc
				(start 266.93368 -151.907748)
				(mid 266.56792 -151.907748)
				(end 266.93368 -151.907748)
			)
		)
		(stroke
			(width 0)
			(type solid)
		)
		(fill yes)
		(layer "F.Cu")
		(net "GND")
	)
	(gr_poly
		(pts
			(arc
				(start 266.98194 -153.459688)
				(mid 266.61618 -153.459688)
				(end 266.98194 -153.459688)
			)
		)
		(stroke
			(width 0)
			(type solid)
		)
		(fill yes)
		(layer "F.Cu")
		(net "GND")
	)
	(gr_poly
		(pts
			(arc
				(start 267.69568 -155.489148)
				(mid 267.32992 -155.489148)
				(end 267.69568 -155.489148)
			)
		)
		(stroke
			(width 0)
			(type solid)
		)
		(fill yes)
		(layer "F.Cu")
		(net "GND")
	)
	(gr_poly
		(pts
			(arc
				(start 268.478 -152.712928)
				(mid 268.11224 -152.712928)
				(end 268.478 -152.712928)
			)
		)
		(stroke
			(width 0)
			(type solid)
		)
		(fill yes)
		(layer "F.Cu")
		(net "GND")
	)
	(gr_poly
		(pts
			(arc
				(start 272.908776 -121.124218)
				(mid 272.543016 -121.124218)
				(end 272.908776 -121.124218)
			)
		)
		(stroke
			(width 0)
			(type solid)
		)
		(fill yes)
		(layer "F.Cu")
		(net "GND")
	)
	(gr_poly
		(pts
			(arc
				(start 274.98421 -120.034558)
				(mid 274.624038 -120.034558)
				(end 274.98421 -120.034558)
			)
		)
		(stroke
			(width 0)
			(type solid)
		)
		(fill yes)
		(layer "F.Cu")
		(net "GND")
	)
	(gr_poly
		(pts
			(arc
				(start 284.801056 -79.2988)
				(mid 284.435296 -79.2988)
				(end 284.801056 -79.2988)
			)
		)
		(stroke
			(width 0)
			(type solid)
		)
		(fill yes)
		(layer "F.Cu")
		(net "GND")
	)
	(gr_poly
		(pts
			(arc
				(start 287.20161 -76.615798)
				(mid 286.83585 -76.615798)
				(end 287.20161 -76.615798)
			)
		)
		(stroke
			(width 0)
			(type solid)
		)
		(fill yes)
		(layer "F.Cu")
		(net "GND")
	)
	(gr_poly
		(pts
			(arc
				(start 290.327588 -93.099128)
				(mid 289.961828 -93.099128)
				(end 290.327588 -93.099128)
			)
		)
		(stroke
			(width 0)
			(type solid)
		)
		(fill yes)
		(layer "F.Cu")
		(net "GND")
	)
	(gr_poly
		(pts
			(arc
				(start 297.75404 -78.969108)
				(mid 297.38828 -78.969108)
				(end 297.75404 -78.969108)
			)
		)
		(stroke
			(width 0)
			(type solid)
		)
		(fill yes)
		(layer "F.Cu")
		(net "GND")
	)
	(gr_poly
		(pts
			(arc
				(start 300.003972 -73.612756)
				(mid 299.638212 -73.612756)
				(end 300.003972 -73.612756)
			)
		)
		(stroke
			(width 0)
			(type solid)
		)
		(fill yes)
		(layer "F.Cu")
		(net "GND")
	)
	(gr_poly
		(pts
			(arc
				(start 303.965356 -404.51786)
				(mid 303.599596 -404.51786)
				(end 303.965356 -404.51786)
			)
		)
		(stroke
			(width 0)
			(type solid)
		)
		(fill yes)
		(layer "F.Cu")
		(net "GND")
	)
	(gr_poly
		(pts
			(arc
				(start 303.965356 -403.249892)
				(mid 303.599596 -403.249892)
				(end 303.965356 -403.249892)
			)
		)
		(stroke
			(width 0)
			(type solid)
		)
		(fill yes)
		(layer "F.Cu")
		(net "GND")
	)
	(gr_poly
		(pts
			(arc
				(start 303.965356 -401.492212)
				(mid 303.599596 -401.492212)
				(end 303.965356 -401.492212)
			)
		)
		(stroke
			(width 0)
			(type solid)
		)
		(fill yes)
		(layer "F.Cu")
		(net "GND")
	)
	(gr_poly
		(pts
			(arc
				(start 303.965356 -400.224244)
				(mid 303.599596 -400.224244)
				(end 303.965356 -400.224244)
			)
		)
		(stroke
			(width 0)
			(type solid)
		)
		(fill yes)
		(layer "F.Cu")
		(net "GND")
	)
	(gr_poly
		(pts
			(arc
				(start 305.22418 -404.51786)
				(mid 304.85842 -404.51786)
				(end 305.22418 -404.51786)
			)
		)
		(stroke
			(width 0)
			(type solid)
		)
		(fill yes)
		(layer "F.Cu")
		(net "GND")
	)
	(gr_poly
		(pts
			(arc
				(start 305.22418 -403.249892)
				(mid 304.85842 -403.249892)
				(end 305.22418 -403.249892)
			)
		)
		(stroke
			(width 0)
			(type solid)
		)
		(fill yes)
		(layer "F.Cu")
		(net "GND")
	)
	(gr_poly
		(pts
			(arc
				(start 305.22418 -401.492212)
				(mid 304.85842 -401.492212)
				(end 305.22418 -401.492212)
			)
		)
		(stroke
			(width 0)
			(type solid)
		)
		(fill yes)
		(layer "F.Cu")
		(net "GND")
	)
	(gr_poly
		(pts
			(arc
				(start 305.22418 -400.224244)
				(mid 304.85842 -400.224244)
				(end 305.22418 -400.224244)
			)
		)
		(stroke
			(width 0)
			(type solid)
		)
		(fill yes)
		(layer "F.Cu")
		(net "GND")
	)
	(gr_poly
		(pts
			(arc
				(start 305.311556 -410.664152)
				(mid 304.945796 -410.664152)
				(end 305.311556 -410.664152)
			)
		)
		(stroke
			(width 0)
			(type solid)
		)
		(fill yes)
		(layer "F.Cu")
		(net "GND")
	)
	(gr_poly
		(pts
			(arc
				(start 305.311556 -409.396184)
				(mid 304.945796 -409.396184)
				(end 305.311556 -409.396184)
			)
		)
		(stroke
			(width 0)
			(type solid)
		)
		(fill yes)
		(layer "F.Cu")
		(net "GND")
	)
	(gr_poly
		(pts
			(arc
				(start 305.311556 -407.638504)
				(mid 304.945796 -407.638504)
				(end 305.311556 -407.638504)
			)
		)
		(stroke
			(width 0)
			(type solid)
		)
		(fill yes)
		(layer "F.Cu")
		(net "GND")
	)
	(gr_poly
		(pts
			(arc
				(start 305.311556 -406.370536)
				(mid 304.945796 -406.370536)
				(end 305.311556 -406.370536)
			)
		)
		(stroke
			(width 0)
			(type solid)
		)
		(fill yes)
		(layer "F.Cu")
		(net "GND")
	)
	(gr_poly
		(pts
			(arc
				(start 305.64328 -192.954148)
				(mid 305.27752 -192.954148)
				(end 305.64328 -192.954148)
			)
		)
		(stroke
			(width 0)
			(type solid)
		)
		(fill yes)
		(layer "F.Cu")
		(net "GND")
	)
	(gr_poly
		(pts
			(arc
				(start 305.962812 -47.104554)
				(mid 305.597052 -47.104554)
				(end 305.962812 -47.104554)
			)
		)
		(stroke
			(width 0)
			(type solid)
		)
		(fill yes)
		(layer "F.Cu")
		(net "GND")
	)
	(gr_poly
		(pts
			(arc
				(start 306.57038 -410.664152)
				(mid 306.20462 -410.664152)
				(end 306.57038 -410.664152)
			)
		)
		(stroke
			(width 0)
			(type solid)
		)
		(fill yes)
		(layer "F.Cu")
		(net "GND")
	)
	(gr_poly
		(pts
			(arc
				(start 306.57038 -409.396184)
				(mid 306.20462 -409.396184)
				(end 306.57038 -409.396184)
			)
		)
		(stroke
			(width 0)
			(type solid)
		)
		(fill yes)
		(layer "F.Cu")
		(net "GND")
	)
	(gr_poly
		(pts
			(arc
				(start 306.57038 -407.638504)
				(mid 306.20462 -407.638504)
				(end 306.57038 -407.638504)
			)
		)
		(stroke
			(width 0)
			(type solid)
		)
		(fill yes)
		(layer "F.Cu")
		(net "GND")
	)
	(gr_poly
		(pts
			(arc
				(start 306.57038 -406.370536)
				(mid 306.20462 -406.370536)
				(end 306.57038 -406.370536)
			)
		)
		(stroke
			(width 0)
			(type solid)
		)
		(fill yes)
		(layer "F.Cu")
		(net "GND")
	)
	(gr_poly
		(pts
			(arc
				(start 307.028596 -404.51786)
				(mid 306.662836 -404.51786)
				(end 307.028596 -404.51786)
			)
		)
		(stroke
			(width 0)
			(type solid)
		)
		(fill yes)
		(layer "F.Cu")
		(net "GND")
	)
	(gr_poly
		(pts
			(arc
				(start 307.028596 -403.249892)
				(mid 306.662836 -403.249892)
				(end 307.028596 -403.249892)
			)
		)
		(stroke
			(width 0)
			(type solid)
		)
		(fill yes)
		(layer "F.Cu")
		(net "GND")
	)
	(gr_poly
		(pts
			(arc
				(start 307.028596 -401.492212)
				(mid 306.662836 -401.492212)
				(end 307.028596 -401.492212)
			)
		)
		(stroke
			(width 0)
			(type solid)
		)
		(fill yes)
		(layer "F.Cu")
		(net "GND")
	)
	(gr_poly
		(pts
			(arc
				(start 307.028596 -400.224244)
				(mid 306.662836 -400.224244)
				(end 307.028596 -400.224244)
			)
		)
		(stroke
			(width 0)
			(type solid)
		)
		(fill yes)
		(layer "F.Cu")
		(net "GND")
	)
	(gr_poly
		(pts
			(arc
				(start 307.10759 -68.872354)
				(mid 306.74183 -68.872354)
				(end 307.10759 -68.872354)
			)
		)
		(stroke
			(width 0)
			(type solid)
		)
		(fill yes)
		(layer "F.Cu")
		(net "GND")
	)
	(gr_poly
		(pts
			(arc
				(start 308.28742 -404.51786)
				(mid 307.92166 -404.51786)
				(end 308.28742 -404.51786)
			)
		)
		(stroke
			(width 0)
			(type solid)
		)
		(fill yes)
		(layer "F.Cu")
		(net "GND")
	)
	(gr_poly
		(pts
			(arc
				(start 308.28742 -403.249892)
				(mid 307.92166 -403.249892)
				(end 308.28742 -403.249892)
			)
		)
		(stroke
			(width 0)
			(type solid)
		)
		(fill yes)
		(layer "F.Cu")
		(net "GND")
	)
	(gr_poly
		(pts
			(arc
				(start 308.28742 -401.492212)
				(mid 307.92166 -401.492212)
				(end 308.28742 -401.492212)
			)
		)
		(stroke
			(width 0)
			(type solid)
		)
		(fill yes)
		(layer "F.Cu")
		(net "GND")
	)
	(gr_poly
		(pts
			(arc
				(start 308.28742 -400.224244)
				(mid 307.92166 -400.224244)
				(end 308.28742 -400.224244)
			)
		)
		(stroke
			(width 0)
			(type solid)
		)
		(fill yes)
		(layer "F.Cu")
		(net "GND")
	)
	(gr_poly
		(pts
			(arc
				(start 308.374796 -410.664152)
				(mid 308.009036 -410.664152)
				(end 308.374796 -410.664152)
			)
		)
		(stroke
			(width 0)
			(type solid)
		)
		(fill yes)
		(layer "F.Cu")
		(net "GND")
	)
	(gr_poly
		(pts
			(arc
				(start 308.374796 -409.396184)
				(mid 308.009036 -409.396184)
				(end 308.374796 -409.396184)
			)
		)
		(stroke
			(width 0)
			(type solid)
		)
		(fill yes)
		(layer "F.Cu")
		(net "GND")
	)
	(gr_poly
		(pts
			(arc
				(start 308.374796 -407.638504)
				(mid 308.009036 -407.638504)
				(end 308.374796 -407.638504)
			)
		)
		(stroke
			(width 0)
			(type solid)
		)
		(fill yes)
		(layer "F.Cu")
		(net "GND")
	)
	(gr_poly
		(pts
			(arc
				(start 308.374796 -406.370536)
				(mid 308.009036 -406.370536)
				(end 308.374796 -406.370536)
			)
		)
		(stroke
			(width 0)
			(type solid)
		)
		(fill yes)
		(layer "F.Cu")
		(net "GND")
	)
	(gr_poly
		(pts
			(arc
				(start 309.63362 -410.664152)
				(mid 309.26786 -410.664152)
				(end 309.63362 -410.664152)
			)
		)
		(stroke
			(width 0)
			(type solid)
		)
		(fill yes)
		(layer "F.Cu")
		(net "GND")
	)
	(gr_poly
		(pts
			(arc
				(start 309.63362 -409.396184)
				(mid 309.26786 -409.396184)
				(end 309.63362 -409.396184)
			)
		)
		(stroke
			(width 0)
			(type solid)
		)
		(fill yes)
		(layer "F.Cu")
		(net "GND")
	)
	(gr_poly
		(pts
			(arc
				(start 309.63362 -407.638504)
				(mid 309.26786 -407.638504)
				(end 309.63362 -407.638504)
			)
		)
		(stroke
			(width 0)
			(type solid)
		)
		(fill yes)
		(layer "F.Cu")
		(net "GND")
	)
	(gr_poly
		(pts
			(arc
				(start 309.63362 -406.370536)
				(mid 309.26786 -406.370536)
				(end 309.63362 -406.370536)
			)
		)
		(stroke
			(width 0)
			(type solid)
		)
		(fill yes)
		(layer "F.Cu")
		(net "GND")
	)
	(gr_poly
		(pts
			(arc
				(start 310.091836 -404.51786)
				(mid 309.726076 -404.51786)
				(end 310.091836 -404.51786)
			)
		)
		(stroke
			(width 0)
			(type solid)
		)
		(fill yes)
		(layer "F.Cu")
		(net "GND")
	)
	(gr_poly
		(pts
			(arc
				(start 310.091836 -403.249892)
				(mid 309.726076 -403.249892)
				(end 310.091836 -403.249892)
			)
		)
		(stroke
			(width 0)
			(type solid)
		)
		(fill yes)
		(layer "F.Cu")
		(net "GND")
	)
	(gr_poly
		(pts
			(arc
				(start 310.091836 -401.492212)
				(mid 309.726076 -401.492212)
				(end 310.091836 -401.492212)
			)
		)
		(stroke
			(width 0)
			(type solid)
		)
		(fill yes)
		(layer "F.Cu")
		(net "GND")
	)
	(gr_poly
		(pts
			(arc
				(start 310.091836 -400.224244)
				(mid 309.726076 -400.224244)
				(end 310.091836 -400.224244)
			)
		)
		(stroke
			(width 0)
			(type solid)
		)
		(fill yes)
		(layer "F.Cu")
		(net "GND")
	)
	(gr_poly
		(pts
			(arc
				(start 311.35066 -404.51786)
				(mid 310.9849 -404.51786)
				(end 311.35066 -404.51786)
			)
		)
		(stroke
			(width 0)
			(type solid)
		)
		(fill yes)
		(layer "F.Cu")
		(net "GND")
	)
	(gr_poly
		(pts
			(arc
				(start 311.35066 -403.249892)
				(mid 310.9849 -403.249892)
				(end 311.35066 -403.249892)
			)
		)
		(stroke
			(width 0)
			(type solid)
		)
		(fill yes)
		(layer "F.Cu")
		(net "GND")
	)
	(gr_poly
		(pts
			(arc
				(start 311.35066 -401.492212)
				(mid 310.9849 -401.492212)
				(end 311.35066 -401.492212)
			)
		)
		(stroke
			(width 0)
			(type solid)
		)
		(fill yes)
		(layer "F.Cu")
		(net "GND")
	)
	(gr_poly
		(pts
			(arc
				(start 311.35066 -400.224244)
				(mid 310.9849 -400.224244)
				(end 311.35066 -400.224244)
			)
		)
		(stroke
			(width 0)
			(type solid)
		)
		(fill yes)
		(layer "F.Cu")
		(net "GND")
	)
	(gr_poly
		(pts
			(arc
				(start 311.438036 -410.664152)
				(mid 311.072276 -410.664152)
				(end 311.438036 -410.664152)
			)
		)
		(stroke
			(width 0)
			(type solid)
		)
		(fill yes)
		(layer "F.Cu")
		(net "GND")
	)
	(gr_poly
		(pts
			(arc
				(start 311.438036 -409.396184)
				(mid 311.072276 -409.396184)
				(end 311.438036 -409.396184)
			)
		)
		(stroke
			(width 0)
			(type solid)
		)
		(fill yes)
		(layer "F.Cu")
		(net "GND")
	)
	(gr_poly
		(pts
			(arc
				(start 311.438036 -407.638504)
				(mid 311.072276 -407.638504)
				(end 311.438036 -407.638504)
			)
		)
		(stroke
			(width 0)
			(type solid)
		)
		(fill yes)
		(layer "F.Cu")
		(net "GND")
	)
	(gr_poly
		(pts
			(arc
				(start 311.438036 -406.370536)
				(mid 311.072276 -406.370536)
				(end 311.438036 -406.370536)
			)
		)
		(stroke
			(width 0)
			(type solid)
		)
		(fill yes)
		(layer "F.Cu")
		(net "GND")
	)
	(gr_poly
		(pts
			(arc
				(start 311.96788 -96.6216)
				(mid 311.60212 -96.6216)
				(end 311.96788 -96.6216)
			)
		)
		(stroke
			(width 0)
			(type solid)
		)
		(fill yes)
		(layer "F.Cu")
		(net "GND")
	)
	(gr_poly
		(pts
			(arc
				(start 312.69686 -410.664152)
				(mid 312.3311 -410.664152)
				(end 312.69686 -410.664152)
			)
		)
		(stroke
			(width 0)
			(type solid)
		)
		(fill yes)
		(layer "F.Cu")
		(net "GND")
	)
	(gr_poly
		(pts
			(arc
				(start 312.69686 -409.396184)
				(mid 312.3311 -409.396184)
				(end 312.69686 -409.396184)
			)
		)
		(stroke
			(width 0)
			(type solid)
		)
		(fill yes)
		(layer "F.Cu")
		(net "GND")
	)
	(gr_poly
		(pts
			(arc
				(start 312.69686 -407.638504)
				(mid 312.3311 -407.638504)
				(end 312.69686 -407.638504)
			)
		)
		(stroke
			(width 0)
			(type solid)
		)
		(fill yes)
		(layer "F.Cu")
		(net "GND")
	)
	(gr_poly
		(pts
			(arc
				(start 312.69686 -406.370536)
				(mid 312.3311 -406.370536)
				(end 312.69686 -406.370536)
			)
		)
		(stroke
			(width 0)
			(type solid)
		)
		(fill yes)
		(layer "F.Cu")
		(net "GND")
	)
	(gr_poly
		(pts
			(arc
				(start 313.155076 -404.51786)
				(mid 312.789316 -404.51786)
				(end 313.155076 -404.51786)
			)
		)
		(stroke
			(width 0)
			(type solid)
		)
		(fill yes)
		(layer "F.Cu")
		(net "GND")
	)
	(gr_poly
		(pts
			(arc
				(start 313.155076 -403.249892)
				(mid 312.789316 -403.249892)
				(end 313.155076 -403.249892)
			)
		)
		(stroke
			(width 0)
			(type solid)
		)
		(fill yes)
		(layer "F.Cu")
		(net "GND")
	)
	(gr_poly
		(pts
			(arc
				(start 313.155076 -401.492212)
				(mid 312.789316 -401.492212)
				(end 313.155076 -401.492212)
			)
		)
		(stroke
			(width 0)
			(type solid)
		)
		(fill yes)
		(layer "F.Cu")
		(net "GND")
	)
	(gr_poly
		(pts
			(arc
				(start 313.155076 -400.224244)
				(mid 312.789316 -400.224244)
				(end 313.155076 -400.224244)
			)
		)
		(stroke
			(width 0)
			(type solid)
		)
		(fill yes)
		(layer "F.Cu")
		(net "GND")
	)
	(gr_poly
		(pts
			(arc
				(start 314.4139 -404.51786)
				(mid 314.04814 -404.51786)
				(end 314.4139 -404.51786)
			)
		)
		(stroke
			(width 0)
			(type solid)
		)
		(fill yes)
		(layer "F.Cu")
		(net "GND")
	)
	(gr_poly
		(pts
			(arc
				(start 314.4139 -403.249892)
				(mid 314.04814 -403.249892)
				(end 314.4139 -403.249892)
			)
		)
		(stroke
			(width 0)
			(type solid)
		)
		(fill yes)
		(layer "F.Cu")
		(net "GND")
	)
	(gr_poly
		(pts
			(arc
				(start 314.4139 -401.492212)
				(mid 314.04814 -401.492212)
				(end 314.4139 -401.492212)
			)
		)
		(stroke
			(width 0)
			(type solid)
		)
		(fill yes)
		(layer "F.Cu")
		(net "GND")
	)
	(gr_poly
		(pts
			(arc
				(start 314.4139 -400.224244)
				(mid 314.04814 -400.224244)
				(end 314.4139 -400.224244)
			)
		)
		(stroke
			(width 0)
			(type solid)
		)
		(fill yes)
		(layer "F.Cu")
		(net "GND")
	)
	(gr_poly
		(pts
			(arc
				(start 314.501276 -410.664152)
				(mid 314.135516 -410.664152)
				(end 314.501276 -410.664152)
			)
		)
		(stroke
			(width 0)
			(type solid)
		)
		(fill yes)
		(layer "F.Cu")
		(net "GND")
	)
	(gr_poly
		(pts
			(arc
				(start 314.501276 -409.396184)
				(mid 314.135516 -409.396184)
				(end 314.501276 -409.396184)
			)
		)
		(stroke
			(width 0)
			(type solid)
		)
		(fill yes)
		(layer "F.Cu")
		(net "GND")
	)
	(gr_poly
		(pts
			(arc
				(start 314.501276 -407.638504)
				(mid 314.135516 -407.638504)
				(end 314.501276 -407.638504)
			)
		)
		(stroke
			(width 0)
			(type solid)
		)
		(fill yes)
		(layer "F.Cu")
		(net "GND")
	)
	(gr_poly
		(pts
			(arc
				(start 314.501276 -406.370536)
				(mid 314.135516 -406.370536)
				(end 314.501276 -406.370536)
			)
		)
		(stroke
			(width 0)
			(type solid)
		)
		(fill yes)
		(layer "F.Cu")
		(net "GND")
	)
	(gr_poly
		(pts
			(arc
				(start 315.7601 -410.664152)
				(mid 315.39434 -410.664152)
				(end 315.7601 -410.664152)
			)
		)
		(stroke
			(width 0)
			(type solid)
		)
		(fill yes)
		(layer "F.Cu")
		(net "GND")
	)
	(gr_poly
		(pts
			(arc
				(start 315.7601 -409.396184)
				(mid 315.39434 -409.396184)
				(end 315.7601 -409.396184)
			)
		)
		(stroke
			(width 0)
			(type solid)
		)
		(fill yes)
		(layer "F.Cu")
		(net "GND")
	)
	(gr_poly
		(pts
			(arc
				(start 315.7601 -407.638504)
				(mid 315.39434 -407.638504)
				(end 315.7601 -407.638504)
			)
		)
		(stroke
			(width 0)
			(type solid)
		)
		(fill yes)
		(layer "F.Cu")
		(net "GND")
	)
	(gr_poly
		(pts
			(arc
				(start 315.7601 -406.370536)
				(mid 315.39434 -406.370536)
				(end 315.7601 -406.370536)
			)
		)
		(stroke
			(width 0)
			(type solid)
		)
		(fill yes)
		(layer "F.Cu")
		(net "GND")
	)
	(gr_poly
		(pts
			(arc
				(start 316.218316 -404.51786)
				(mid 315.852556 -404.51786)
				(end 316.218316 -404.51786)
			)
		)
		(stroke
			(width 0)
			(type solid)
		)
		(fill yes)
		(layer "F.Cu")
		(net "GND")
	)
	(gr_poly
		(pts
			(arc
				(start 316.218316 -403.249892)
				(mid 315.852556 -403.249892)
				(end 316.218316 -403.249892)
			)
		)
		(stroke
			(width 0)
			(type solid)
		)
		(fill yes)
		(layer "F.Cu")
		(net "GND")
	)
	(gr_poly
		(pts
			(arc
				(start 316.218316 -401.492212)
				(mid 315.852556 -401.492212)
				(end 316.218316 -401.492212)
			)
		)
		(stroke
			(width 0)
			(type solid)
		)
		(fill yes)
		(layer "F.Cu")
		(net "GND")
	)
	(gr_poly
		(pts
			(arc
				(start 316.218316 -400.224244)
				(mid 315.852556 -400.224244)
				(end 316.218316 -400.224244)
			)
		)
		(stroke
			(width 0)
			(type solid)
		)
		(fill yes)
		(layer "F.Cu")
		(net "GND")
	)
	(gr_poly
		(pts
			(arc
				(start 317.47714 -404.51786)
				(mid 317.11138 -404.51786)
				(end 317.47714 -404.51786)
			)
		)
		(stroke
			(width 0)
			(type solid)
		)
		(fill yes)
		(layer "F.Cu")
		(net "GND")
	)
	(gr_poly
		(pts
			(arc
				(start 317.47714 -403.249892)
				(mid 317.11138 -403.249892)
				(end 317.47714 -403.249892)
			)
		)
		(stroke
			(width 0)
			(type solid)
		)
		(fill yes)
		(layer "F.Cu")
		(net "GND")
	)
	(gr_poly
		(pts
			(arc
				(start 317.47714 -401.492212)
				(mid 317.11138 -401.492212)
				(end 317.47714 -401.492212)
			)
		)
		(stroke
			(width 0)
			(type solid)
		)
		(fill yes)
		(layer "F.Cu")
		(net "GND")
	)
	(gr_poly
		(pts
			(arc
				(start 317.47714 -400.224244)
				(mid 317.11138 -400.224244)
				(end 317.47714 -400.224244)
			)
		)
		(stroke
			(width 0)
			(type solid)
		)
		(fill yes)
		(layer "F.Cu")
		(net "GND")
	)
	(gr_poly
		(pts
			(arc
				(start 317.564516 -410.664152)
				(mid 317.198756 -410.664152)
				(end 317.564516 -410.664152)
			)
		)
		(stroke
			(width 0)
			(type solid)
		)
		(fill yes)
		(layer "F.Cu")
		(net "GND")
	)
	(gr_poly
		(pts
			(arc
				(start 317.564516 -409.396184)
				(mid 317.198756 -409.396184)
				(end 317.564516 -409.396184)
			)
		)
		(stroke
			(width 0)
			(type solid)
		)
		(fill yes)
		(layer "F.Cu")
		(net "GND")
	)
	(gr_poly
		(pts
			(arc
				(start 317.564516 -407.638504)
				(mid 317.198756 -407.638504)
				(end 317.564516 -407.638504)
			)
		)
		(stroke
			(width 0)
			(type solid)
		)
		(fill yes)
		(layer "F.Cu")
		(net "GND")
	)
	(gr_poly
		(pts
			(arc
				(start 317.564516 -406.370536)
				(mid 317.198756 -406.370536)
				(end 317.564516 -406.370536)
			)
		)
		(stroke
			(width 0)
			(type solid)
		)
		(fill yes)
		(layer "F.Cu")
		(net "GND")
	)
	(gr_poly
		(pts
			(arc
				(start 318.82334 -410.664152)
				(mid 318.45758 -410.664152)
				(end 318.82334 -410.664152)
			)
		)
		(stroke
			(width 0)
			(type solid)
		)
		(fill yes)
		(layer "F.Cu")
		(net "GND")
	)
	(gr_poly
		(pts
			(arc
				(start 318.82334 -409.396184)
				(mid 318.45758 -409.396184)
				(end 318.82334 -409.396184)
			)
		)
		(stroke
			(width 0)
			(type solid)
		)
		(fill yes)
		(layer "F.Cu")
		(net "GND")
	)
	(gr_poly
		(pts
			(arc
				(start 318.82334 -407.638504)
				(mid 318.45758 -407.638504)
				(end 318.82334 -407.638504)
			)
		)
		(stroke
			(width 0)
			(type solid)
		)
		(fill yes)
		(layer "F.Cu")
		(net "GND")
	)
	(gr_poly
		(pts
			(arc
				(start 318.82334 -406.370536)
				(mid 318.45758 -406.370536)
				(end 318.82334 -406.370536)
			)
		)
		(stroke
			(width 0)
			(type solid)
		)
		(fill yes)
		(layer "F.Cu")
		(net "GND")
	)
	(gr_poly
		(pts
			(arc
				(start 319.281556 -404.51786)
				(mid 318.915796 -404.51786)
				(end 319.281556 -404.51786)
			)
		)
		(stroke
			(width 0)
			(type solid)
		)
		(fill yes)
		(layer "F.Cu")
		(net "GND")
	)
	(gr_poly
		(pts
			(arc
				(start 319.281556 -403.249892)
				(mid 318.915796 -403.249892)
				(end 319.281556 -403.249892)
			)
		)
		(stroke
			(width 0)
			(type solid)
		)
		(fill yes)
		(layer "F.Cu")
		(net "GND")
	)
	(gr_poly
		(pts
			(arc
				(start 319.281556 -401.492212)
				(mid 318.915796 -401.492212)
				(end 319.281556 -401.492212)
			)
		)
		(stroke
			(width 0)
			(type solid)
		)
		(fill yes)
		(layer "F.Cu")
		(net "GND")
	)
	(gr_poly
		(pts
			(arc
				(start 319.281556 -400.224244)
				(mid 318.915796 -400.224244)
				(end 319.281556 -400.224244)
			)
		)
		(stroke
			(width 0)
			(type solid)
		)
		(fill yes)
		(layer "F.Cu")
		(net "GND")
	)
	(gr_poly
		(pts
			(arc
				(start 320.54038 -404.51786)
				(mid 320.17462 -404.51786)
				(end 320.54038 -404.51786)
			)
		)
		(stroke
			(width 0)
			(type solid)
		)
		(fill yes)
		(layer "F.Cu")
		(net "GND")
	)
	(gr_poly
		(pts
			(arc
				(start 320.54038 -403.249892)
				(mid 320.17462 -403.249892)
				(end 320.54038 -403.249892)
			)
		)
		(stroke
			(width 0)
			(type solid)
		)
		(fill yes)
		(layer "F.Cu")
		(net "GND")
	)
	(gr_poly
		(pts
			(arc
				(start 320.54038 -401.492212)
				(mid 320.17462 -401.492212)
				(end 320.54038 -401.492212)
			)
		)
		(stroke
			(width 0)
			(type solid)
		)
		(fill yes)
		(layer "F.Cu")
		(net "GND")
	)
	(gr_poly
		(pts
			(arc
				(start 320.54038 -400.224244)
				(mid 320.17462 -400.224244)
				(end 320.54038 -400.224244)
			)
		)
		(stroke
			(width 0)
			(type solid)
		)
		(fill yes)
		(layer "F.Cu")
		(net "GND")
	)
	(gr_poly
		(pts
			(arc
				(start 320.627756 -410.664152)
				(mid 320.261996 -410.664152)
				(end 320.627756 -410.664152)
			)
		)
		(stroke
			(width 0)
			(type solid)
		)
		(fill yes)
		(layer "F.Cu")
		(net "GND")
	)
	(gr_poly
		(pts
			(arc
				(start 320.627756 -409.396184)
				(mid 320.261996 -409.396184)
				(end 320.627756 -409.396184)
			)
		)
		(stroke
			(width 0)
			(type solid)
		)
		(fill yes)
		(layer "F.Cu")
		(net "GND")
	)
	(gr_poly
		(pts
			(arc
				(start 320.627756 -407.638504)
				(mid 320.261996 -407.638504)
				(end 320.627756 -407.638504)
			)
		)
		(stroke
			(width 0)
			(type solid)
		)
		(fill yes)
		(layer "F.Cu")
		(net "GND")
	)
	(gr_poly
		(pts
			(arc
				(start 320.627756 -406.370536)
				(mid 320.261996 -406.370536)
				(end 320.627756 -406.370536)
			)
		)
		(stroke
			(width 0)
			(type solid)
		)
		(fill yes)
		(layer "F.Cu")
		(net "GND")
	)
	(gr_poly
		(pts
			(arc
				(start 321.88658 -410.664152)
				(mid 321.52082 -410.664152)
				(end 321.88658 -410.664152)
			)
		)
		(stroke
			(width 0)
			(type solid)
		)
		(fill yes)
		(layer "F.Cu")
		(net "GND")
	)
	(gr_poly
		(pts
			(arc
				(start 321.88658 -409.396184)
				(mid 321.52082 -409.396184)
				(end 321.88658 -409.396184)
			)
		)
		(stroke
			(width 0)
			(type solid)
		)
		(fill yes)
		(layer "F.Cu")
		(net "GND")
	)
	(gr_poly
		(pts
			(arc
				(start 321.88658 -407.638504)
				(mid 321.52082 -407.638504)
				(end 321.88658 -407.638504)
			)
		)
		(stroke
			(width 0)
			(type solid)
		)
		(fill yes)
		(layer "F.Cu")
		(net "GND")
	)
	(gr_poly
		(pts
			(arc
				(start 321.88658 -406.370536)
				(mid 321.52082 -406.370536)
				(end 321.88658 -406.370536)
			)
		)
		(stroke
			(width 0)
			(type solid)
		)
		(fill yes)
		(layer "F.Cu")
		(net "GND")
	)
	(gr_poly
		(pts
			(arc
				(start 322.344796 -404.51786)
				(mid 321.979036 -404.51786)
				(end 322.344796 -404.51786)
			)
		)
		(stroke
			(width 0)
			(type solid)
		)
		(fill yes)
		(layer "F.Cu")
		(net "GND")
	)
	(gr_poly
		(pts
			(arc
				(start 322.344796 -403.249892)
				(mid 321.979036 -403.249892)
				(end 322.344796 -403.249892)
			)
		)
		(stroke
			(width 0)
			(type solid)
		)
		(fill yes)
		(layer "F.Cu")
		(net "GND")
	)
	(gr_poly
		(pts
			(arc
				(start 322.344796 -401.492212)
				(mid 321.979036 -401.492212)
				(end 322.344796 -401.492212)
			)
		)
		(stroke
			(width 0)
			(type solid)
		)
		(fill yes)
		(layer "F.Cu")
		(net "GND")
	)
	(gr_poly
		(pts
			(arc
				(start 322.344796 -400.200368)
				(mid 321.979036 -400.200368)
				(end 322.344796 -400.200368)
			)
		)
		(stroke
			(width 0)
			(type solid)
		)
		(fill yes)
		(layer "F.Cu")
		(net "GND")
	)
	(gr_poly
		(pts
			(arc
				(start 323.60362 -404.51786)
				(mid 323.23786 -404.51786)
				(end 323.60362 -404.51786)
			)
		)
		(stroke
			(width 0)
			(type solid)
		)
		(fill yes)
		(layer "F.Cu")
		(net "GND")
	)
	(gr_poly
		(pts
			(arc
				(start 323.60362 -403.249892)
				(mid 323.23786 -403.249892)
				(end 323.60362 -403.249892)
			)
		)
		(stroke
			(width 0)
			(type solid)
		)
		(fill yes)
		(layer "F.Cu")
		(net "GND")
	)
	(gr_poly
		(pts
			(arc
				(start 323.60362 -401.492212)
				(mid 323.23786 -401.492212)
				(end 323.60362 -401.492212)
			)
		)
		(stroke
			(width 0)
			(type solid)
		)
		(fill yes)
		(layer "F.Cu")
		(net "GND")
	)
	(gr_poly
		(pts
			(arc
				(start 323.60362 -400.200368)
				(mid 323.23786 -400.200368)
				(end 323.60362 -400.200368)
			)
		)
		(stroke
			(width 0)
			(type solid)
		)
		(fill yes)
		(layer "F.Cu")
		(net "GND")
	)
	(gr_poly
		(pts
			(arc
				(start 323.690996 -410.664152)
				(mid 323.325236 -410.664152)
				(end 323.690996 -410.664152)
			)
		)
		(stroke
			(width 0)
			(type solid)
		)
		(fill yes)
		(layer "F.Cu")
		(net "GND")
	)
	(gr_poly
		(pts
			(arc
				(start 323.690996 -409.396184)
				(mid 323.325236 -409.396184)
				(end 323.690996 -409.396184)
			)
		)
		(stroke
			(width 0)
			(type solid)
		)
		(fill yes)
		(layer "F.Cu")
		(net "GND")
	)
	(gr_poly
		(pts
			(arc
				(start 323.690996 -407.638504)
				(mid 323.325236 -407.638504)
				(end 323.690996 -407.638504)
			)
		)
		(stroke
			(width 0)
			(type solid)
		)
		(fill yes)
		(layer "F.Cu")
		(net "GND")
	)
	(gr_poly
		(pts
			(arc
				(start 323.690996 -406.34666)
				(mid 323.325236 -406.34666)
				(end 323.690996 -406.34666)
			)
		)
		(stroke
			(width 0)
			(type solid)
		)
		(fill yes)
		(layer "F.Cu")
		(net "GND")
	)
	(gr_poly
		(pts
			(arc
				(start 324.94982 -410.664152)
				(mid 324.58406 -410.664152)
				(end 324.94982 -410.664152)
			)
		)
		(stroke
			(width 0)
			(type solid)
		)
		(fill yes)
		(layer "F.Cu")
		(net "GND")
	)
	(gr_poly
		(pts
			(arc
				(start 324.94982 -409.396184)
				(mid 324.58406 -409.396184)
				(end 324.94982 -409.396184)
			)
		)
		(stroke
			(width 0)
			(type solid)
		)
		(fill yes)
		(layer "F.Cu")
		(net "GND")
	)
	(gr_poly
		(pts
			(arc
				(start 324.94982 -407.638504)
				(mid 324.58406 -407.638504)
				(end 324.94982 -407.638504)
			)
		)
		(stroke
			(width 0)
			(type solid)
		)
		(fill yes)
		(layer "F.Cu")
		(net "GND")
	)
	(gr_poly
		(pts
			(arc
				(start 324.94982 -406.34666)
				(mid 324.58406 -406.34666)
				(end 324.94982 -406.34666)
			)
		)
		(stroke
			(width 0)
			(type solid)
		)
		(fill yes)
		(layer "F.Cu")
		(net "GND")
	)
	(gr_poly
		(pts
			(arc
				(start 325.408036 -404.51786)
				(mid 325.042276 -404.51786)
				(end 325.408036 -404.51786)
			)
		)
		(stroke
			(width 0)
			(type solid)
		)
		(fill yes)
		(layer "F.Cu")
		(net "GND")
	)
	(gr_poly
		(pts
			(arc
				(start 325.408036 -403.249892)
				(mid 325.042276 -403.249892)
				(end 325.408036 -403.249892)
			)
		)
		(stroke
			(width 0)
			(type solid)
		)
		(fill yes)
		(layer "F.Cu")
		(net "GND")
	)
	(gr_poly
		(pts
			(arc
				(start 325.408036 -401.492212)
				(mid 325.042276 -401.492212)
				(end 325.408036 -401.492212)
			)
		)
		(stroke
			(width 0)
			(type solid)
		)
		(fill yes)
		(layer "F.Cu")
		(net "GND")
	)
	(gr_poly
		(pts
			(arc
				(start 325.408036 -400.224244)
				(mid 325.042276 -400.224244)
				(end 325.408036 -400.224244)
			)
		)
		(stroke
			(width 0)
			(type solid)
		)
		(fill yes)
		(layer "F.Cu")
		(net "GND")
	)
	(gr_poly
		(pts
			(arc
				(start 326.66686 -404.51786)
				(mid 326.3011 -404.51786)
				(end 326.66686 -404.51786)
			)
		)
		(stroke
			(width 0)
			(type solid)
		)
		(fill yes)
		(layer "F.Cu")
		(net "GND")
	)
	(gr_poly
		(pts
			(arc
				(start 326.66686 -403.249892)
				(mid 326.3011 -403.249892)
				(end 326.66686 -403.249892)
			)
		)
		(stroke
			(width 0)
			(type solid)
		)
		(fill yes)
		(layer "F.Cu")
		(net "GND")
	)
	(gr_poly
		(pts
			(arc
				(start 326.66686 -401.492212)
				(mid 326.3011 -401.492212)
				(end 326.66686 -401.492212)
			)
		)
		(stroke
			(width 0)
			(type solid)
		)
		(fill yes)
		(layer "F.Cu")
		(net "GND")
	)
	(gr_poly
		(pts
			(arc
				(start 326.66686 -400.224244)
				(mid 326.3011 -400.224244)
				(end 326.66686 -400.224244)
			)
		)
		(stroke
			(width 0)
			(type solid)
		)
		(fill yes)
		(layer "F.Cu")
		(net "GND")
	)
	(gr_poly
		(pts
			(arc
				(start 326.754236 -410.664152)
				(mid 326.388476 -410.664152)
				(end 326.754236 -410.664152)
			)
		)
		(stroke
			(width 0)
			(type solid)
		)
		(fill yes)
		(layer "F.Cu")
		(net "GND")
	)
	(gr_poly
		(pts
			(arc
				(start 326.754236 -409.396184)
				(mid 326.388476 -409.396184)
				(end 326.754236 -409.396184)
			)
		)
		(stroke
			(width 0)
			(type solid)
		)
		(fill yes)
		(layer "F.Cu")
		(net "GND")
	)
	(gr_poly
		(pts
			(arc
				(start 326.754236 -407.638504)
				(mid 326.388476 -407.638504)
				(end 326.754236 -407.638504)
			)
		)
		(stroke
			(width 0)
			(type solid)
		)
		(fill yes)
		(layer "F.Cu")
		(net "GND")
	)
	(gr_poly
		(pts
			(arc
				(start 326.754236 -406.370536)
				(mid 326.388476 -406.370536)
				(end 326.754236 -406.370536)
			)
		)
		(stroke
			(width 0)
			(type solid)
		)
		(fill yes)
		(layer "F.Cu")
		(net "GND")
	)
	(gr_poly
		(pts
			(arc
				(start 328.01306 -410.664152)
				(mid 327.6473 -410.664152)
				(end 328.01306 -410.664152)
			)
		)
		(stroke
			(width 0)
			(type solid)
		)
		(fill yes)
		(layer "F.Cu")
		(net "GND")
	)
	(gr_poly
		(pts
			(arc
				(start 328.01306 -409.396184)
				(mid 327.6473 -409.396184)
				(end 328.01306 -409.396184)
			)
		)
		(stroke
			(width 0)
			(type solid)
		)
		(fill yes)
		(layer "F.Cu")
		(net "GND")
	)
	(gr_poly
		(pts
			(arc
				(start 328.01306 -407.638504)
				(mid 327.6473 -407.638504)
				(end 328.01306 -407.638504)
			)
		)
		(stroke
			(width 0)
			(type solid)
		)
		(fill yes)
		(layer "F.Cu")
		(net "GND")
	)
	(gr_poly
		(pts
			(arc
				(start 328.01306 -406.370536)
				(mid 327.6473 -406.370536)
				(end 328.01306 -406.370536)
			)
		)
		(stroke
			(width 0)
			(type solid)
		)
		(fill yes)
		(layer "F.Cu")
		(net "GND")
	)
	(gr_poly
		(pts
			(arc
				(start 328.471276 -404.51786)
				(mid 328.105516 -404.51786)
				(end 328.471276 -404.51786)
			)
		)
		(stroke
			(width 0)
			(type solid)
		)
		(fill yes)
		(layer "F.Cu")
		(net "GND")
	)
	(gr_poly
		(pts
			(arc
				(start 328.471276 -403.249892)
				(mid 328.105516 -403.249892)
				(end 328.471276 -403.249892)
			)
		)
		(stroke
			(width 0)
			(type solid)
		)
		(fill yes)
		(layer "F.Cu")
		(net "GND")
	)
	(gr_poly
		(pts
			(arc
				(start 328.471276 -401.492212)
				(mid 328.105516 -401.492212)
				(end 328.471276 -401.492212)
			)
		)
		(stroke
			(width 0)
			(type solid)
		)
		(fill yes)
		(layer "F.Cu")
		(net "GND")
	)
	(gr_poly
		(pts
			(arc
				(start 328.471276 -400.224244)
				(mid 328.105516 -400.224244)
				(end 328.471276 -400.224244)
			)
		)
		(stroke
			(width 0)
			(type solid)
		)
		(fill yes)
		(layer "F.Cu")
		(net "GND")
	)
	(gr_poly
		(pts
			(arc
				(start 329.338178 -80.155034)
				(mid 328.972418 -80.155034)
				(end 329.338178 -80.155034)
			)
		)
		(stroke
			(width 0)
			(type solid)
		)
		(fill yes)
		(layer "F.Cu")
		(net "GND")
	)
	(gr_poly
		(pts
			(arc
				(start 329.7301 -404.51786)
				(mid 329.36434 -404.51786)
				(end 329.7301 -404.51786)
			)
		)
		(stroke
			(width 0)
			(type solid)
		)
		(fill yes)
		(layer "F.Cu")
		(net "GND")
	)
	(gr_poly
		(pts
			(arc
				(start 329.7301 -403.249892)
				(mid 329.36434 -403.249892)
				(end 329.7301 -403.249892)
			)
		)
		(stroke
			(width 0)
			(type solid)
		)
		(fill yes)
		(layer "F.Cu")
		(net "GND")
	)
	(gr_poly
		(pts
			(arc
				(start 329.7301 -401.492212)
				(mid 329.36434 -401.492212)
				(end 329.7301 -401.492212)
			)
		)
		(stroke
			(width 0)
			(type solid)
		)
		(fill yes)
		(layer "F.Cu")
		(net "GND")
	)
	(gr_poly
		(pts
			(arc
				(start 329.7301 -400.224244)
				(mid 329.36434 -400.224244)
				(end 329.7301 -400.224244)
			)
		)
		(stroke
			(width 0)
			(type solid)
		)
		(fill yes)
		(layer "F.Cu")
		(net "GND")
	)
	(gr_poly
		(pts
			(arc
				(start 329.817476 -410.664152)
				(mid 329.451716 -410.664152)
				(end 329.817476 -410.664152)
			)
		)
		(stroke
			(width 0)
			(type solid)
		)
		(fill yes)
		(layer "F.Cu")
		(net "GND")
	)
	(gr_poly
		(pts
			(arc
				(start 329.817476 -409.396184)
				(mid 329.451716 -409.396184)
				(end 329.817476 -409.396184)
			)
		)
		(stroke
			(width 0)
			(type solid)
		)
		(fill yes)
		(layer "F.Cu")
		(net "GND")
	)
	(gr_poly
		(pts
			(arc
				(start 329.817476 -407.638504)
				(mid 329.451716 -407.638504)
				(end 329.817476 -407.638504)
			)
		)
		(stroke
			(width 0)
			(type solid)
		)
		(fill yes)
		(layer "F.Cu")
		(net "GND")
	)
	(gr_poly
		(pts
			(arc
				(start 329.817476 -406.370536)
				(mid 329.451716 -406.370536)
				(end 329.817476 -406.370536)
			)
		)
		(stroke
			(width 0)
			(type solid)
		)
		(fill yes)
		(layer "F.Cu")
		(net "GND")
	)
	(gr_poly
		(pts
			(arc
				(start 331.00518 -73.678288)
				(mid 330.63942 -73.678288)
				(end 331.00518 -73.678288)
			)
		)
		(stroke
			(width 0)
			(type solid)
		)
		(fill yes)
		(layer "F.Cu")
		(net "GND")
	)
	(gr_poly
		(pts
			(arc
				(start 331.0763 -410.664152)
				(mid 330.71054 -410.664152)
				(end 331.0763 -410.664152)
			)
		)
		(stroke
			(width 0)
			(type solid)
		)
		(fill yes)
		(layer "F.Cu")
		(net "GND")
	)
	(gr_poly
		(pts
			(arc
				(start 331.0763 -409.396184)
				(mid 330.71054 -409.396184)
				(end 331.0763 -409.396184)
			)
		)
		(stroke
			(width 0)
			(type solid)
		)
		(fill yes)
		(layer "F.Cu")
		(net "GND")
	)
	(gr_poly
		(pts
			(arc
				(start 331.0763 -407.638504)
				(mid 330.71054 -407.638504)
				(end 331.0763 -407.638504)
			)
		)
		(stroke
			(width 0)
			(type solid)
		)
		(fill yes)
		(layer "F.Cu")
		(net "GND")
	)
	(gr_poly
		(pts
			(arc
				(start 331.0763 -406.370536)
				(mid 330.71054 -406.370536)
				(end 331.0763 -406.370536)
			)
		)
		(stroke
			(width 0)
			(type solid)
		)
		(fill yes)
		(layer "F.Cu")
		(net "GND")
	)
	(gr_poly
		(pts
			(arc
				(start 331.534516 -404.51786)
				(mid 331.168756 -404.51786)
				(end 331.534516 -404.51786)
			)
		)
		(stroke
			(width 0)
			(type solid)
		)
		(fill yes)
		(layer "F.Cu")
		(net "GND")
	)
	(gr_poly
		(pts
			(arc
				(start 331.534516 -403.249892)
				(mid 331.168756 -403.249892)
				(end 331.534516 -403.249892)
			)
		)
		(stroke
			(width 0)
			(type solid)
		)
		(fill yes)
		(layer "F.Cu")
		(net "GND")
	)
	(gr_poly
		(pts
			(arc
				(start 331.534516 -401.492212)
				(mid 331.168756 -401.492212)
				(end 331.534516 -401.492212)
			)
		)
		(stroke
			(width 0)
			(type solid)
		)
		(fill yes)
		(layer "F.Cu")
		(net "GND")
	)
	(gr_poly
		(pts
			(arc
				(start 331.534516 -400.224244)
				(mid 331.168756 -400.224244)
				(end 331.534516 -400.224244)
			)
		)
		(stroke
			(width 0)
			(type solid)
		)
		(fill yes)
		(layer "F.Cu")
		(net "GND")
	)
	(gr_poly
		(pts
			(arc
				(start 332.363572 -73.040494)
				(mid 331.997812 -73.040494)
				(end 332.363572 -73.040494)
			)
		)
		(stroke
			(width 0)
			(type solid)
		)
		(fill yes)
		(layer "F.Cu")
		(net "GND")
	)
	(gr_poly
		(pts
			(arc
				(start 332.61554 -73.703688)
				(mid 332.24978 -73.703688)
				(end 332.61554 -73.703688)
			)
		)
		(stroke
			(width 0)
			(type solid)
		)
		(fill yes)
		(layer "F.Cu")
		(net "GND")
	)
	(gr_poly
		(pts
			(arc
				(start 332.79334 -404.51786)
				(mid 332.42758 -404.51786)
				(end 332.79334 -404.51786)
			)
		)
		(stroke
			(width 0)
			(type solid)
		)
		(fill yes)
		(layer "F.Cu")
		(net "GND")
	)
	(gr_poly
		(pts
			(arc
				(start 332.79334 -403.249892)
				(mid 332.42758 -403.249892)
				(end 332.79334 -403.249892)
			)
		)
		(stroke
			(width 0)
			(type solid)
		)
		(fill yes)
		(layer "F.Cu")
		(net "GND")
	)
	(gr_poly
		(pts
			(arc
				(start 332.79334 -401.492212)
				(mid 332.42758 -401.492212)
				(end 332.79334 -401.492212)
			)
		)
		(stroke
			(width 0)
			(type solid)
		)
		(fill yes)
		(layer "F.Cu")
		(net "GND")
	)
	(gr_poly
		(pts
			(arc
				(start 332.79334 -400.224244)
				(mid 332.42758 -400.224244)
				(end 332.79334 -400.224244)
			)
		)
		(stroke
			(width 0)
			(type solid)
		)
		(fill yes)
		(layer "F.Cu")
		(net "GND")
	)
	(gr_poly
		(pts
			(arc
				(start 332.880716 -410.664152)
				(mid 332.514956 -410.664152)
				(end 332.880716 -410.664152)
			)
		)
		(stroke
			(width 0)
			(type solid)
		)
		(fill yes)
		(layer "F.Cu")
		(net "GND")
	)
	(gr_poly
		(pts
			(arc
				(start 332.880716 -409.396184)
				(mid 332.514956 -409.396184)
				(end 332.880716 -409.396184)
			)
		)
		(stroke
			(width 0)
			(type solid)
		)
		(fill yes)
		(layer "F.Cu")
		(net "GND")
	)
	(gr_poly
		(pts
			(arc
				(start 332.880716 -407.638504)
				(mid 332.514956 -407.638504)
				(end 332.880716 -407.638504)
			)
		)
		(stroke
			(width 0)
			(type solid)
		)
		(fill yes)
		(layer "F.Cu")
		(net "GND")
	)
	(gr_poly
		(pts
			(arc
				(start 332.880716 -406.370536)
				(mid 332.514956 -406.370536)
				(end 332.880716 -406.370536)
			)
		)
		(stroke
			(width 0)
			(type solid)
		)
		(fill yes)
		(layer "F.Cu")
		(net "GND")
	)
	(gr_poly
		(pts
			(arc
				(start 333.747364 -73.058274)
				(mid 333.381604 -73.058274)
				(end 333.747364 -73.058274)
			)
		)
		(stroke
			(width 0)
			(type solid)
		)
		(fill yes)
		(layer "F.Cu")
		(net "GND")
	)
	(gr_poly
		(pts
			(arc
				(start 334.13954 -410.664152)
				(mid 333.77378 -410.664152)
				(end 334.13954 -410.664152)
			)
		)
		(stroke
			(width 0)
			(type solid)
		)
		(fill yes)
		(layer "F.Cu")
		(net "GND")
	)
	(gr_poly
		(pts
			(arc
				(start 334.13954 -409.396184)
				(mid 333.77378 -409.396184)
				(end 334.13954 -409.396184)
			)
		)
		(stroke
			(width 0)
			(type solid)
		)
		(fill yes)
		(layer "F.Cu")
		(net "GND")
	)
	(gr_poly
		(pts
			(arc
				(start 334.13954 -407.638504)
				(mid 333.77378 -407.638504)
				(end 334.13954 -407.638504)
			)
		)
		(stroke
			(width 0)
			(type solid)
		)
		(fill yes)
		(layer "F.Cu")
		(net "GND")
	)
	(gr_poly
		(pts
			(arc
				(start 334.13954 -406.370536)
				(mid 333.77378 -406.370536)
				(end 334.13954 -406.370536)
			)
		)
		(stroke
			(width 0)
			(type solid)
		)
		(fill yes)
		(layer "F.Cu")
		(net "GND")
	)
	(gr_poly
		(pts
			(arc
				(start 334.597756 -404.51786)
				(mid 334.231996 -404.51786)
				(end 334.597756 -404.51786)
			)
		)
		(stroke
			(width 0)
			(type solid)
		)
		(fill yes)
		(layer "F.Cu")
		(net "GND")
	)
	(gr_poly
		(pts
			(arc
				(start 334.597756 -403.249892)
				(mid 334.231996 -403.249892)
				(end 334.597756 -403.249892)
			)
		)
		(stroke
			(width 0)
			(type solid)
		)
		(fill yes)
		(layer "F.Cu")
		(net "GND")
	)
	(gr_poly
		(pts
			(arc
				(start 334.597756 -401.492212)
				(mid 334.231996 -401.492212)
				(end 334.597756 -401.492212)
			)
		)
		(stroke
			(width 0)
			(type solid)
		)
		(fill yes)
		(layer "F.Cu")
		(net "GND")
	)
	(gr_poly
		(pts
			(arc
				(start 334.597756 -400.224244)
				(mid 334.231996 -400.224244)
				(end 334.597756 -400.224244)
			)
		)
		(stroke
			(width 0)
			(type solid)
		)
		(fill yes)
		(layer "F.Cu")
		(net "GND")
	)
	(gr_poly
		(pts
			(arc
				(start 335.85658 -404.51786)
				(mid 335.49082 -404.51786)
				(end 335.85658 -404.51786)
			)
		)
		(stroke
			(width 0)
			(type solid)
		)
		(fill yes)
		(layer "F.Cu")
		(net "GND")
	)
	(gr_poly
		(pts
			(arc
				(start 335.85658 -403.249892)
				(mid 335.49082 -403.249892)
				(end 335.85658 -403.249892)
			)
		)
		(stroke
			(width 0)
			(type solid)
		)
		(fill yes)
		(layer "F.Cu")
		(net "GND")
	)
	(gr_poly
		(pts
			(arc
				(start 335.85658 -401.492212)
				(mid 335.49082 -401.492212)
				(end 335.85658 -401.492212)
			)
		)
		(stroke
			(width 0)
			(type solid)
		)
		(fill yes)
		(layer "F.Cu")
		(net "GND")
	)
	(gr_poly
		(pts
			(arc
				(start 335.85658 -400.224244)
				(mid 335.49082 -400.224244)
				(end 335.85658 -400.224244)
			)
		)
		(stroke
			(width 0)
			(type solid)
		)
		(fill yes)
		(layer "F.Cu")
		(net "GND")
	)
	(gr_poly
		(pts
			(arc
				(start 335.943956 -410.664152)
				(mid 335.578196 -410.664152)
				(end 335.943956 -410.664152)
			)
		)
		(stroke
			(width 0)
			(type solid)
		)
		(fill yes)
		(layer "F.Cu")
		(net "GND")
	)
	(gr_poly
		(pts
			(arc
				(start 335.943956 -409.396184)
				(mid 335.578196 -409.396184)
				(end 335.943956 -409.396184)
			)
		)
		(stroke
			(width 0)
			(type solid)
		)
		(fill yes)
		(layer "F.Cu")
		(net "GND")
	)
	(gr_poly
		(pts
			(arc
				(start 335.943956 -407.638504)
				(mid 335.578196 -407.638504)
				(end 335.943956 -407.638504)
			)
		)
		(stroke
			(width 0)
			(type solid)
		)
		(fill yes)
		(layer "F.Cu")
		(net "GND")
	)
	(gr_poly
		(pts
			(arc
				(start 335.943956 -406.370536)
				(mid 335.578196 -406.370536)
				(end 335.943956 -406.370536)
			)
		)
		(stroke
			(width 0)
			(type solid)
		)
		(fill yes)
		(layer "F.Cu")
		(net "GND")
	)
	(gr_poly
		(pts
			(arc
				(start 337.20278 -410.664152)
				(mid 336.83702 -410.664152)
				(end 337.20278 -410.664152)
			)
		)
		(stroke
			(width 0)
			(type solid)
		)
		(fill yes)
		(layer "F.Cu")
		(net "GND")
	)
	(gr_poly
		(pts
			(arc
				(start 337.20278 -409.396184)
				(mid 336.83702 -409.396184)
				(end 337.20278 -409.396184)
			)
		)
		(stroke
			(width 0)
			(type solid)
		)
		(fill yes)
		(layer "F.Cu")
		(net "GND")
	)
	(gr_poly
		(pts
			(arc
				(start 337.20278 -407.638504)
				(mid 336.83702 -407.638504)
				(end 337.20278 -407.638504)
			)
		)
		(stroke
			(width 0)
			(type solid)
		)
		(fill yes)
		(layer "F.Cu")
		(net "GND")
	)
	(gr_poly
		(pts
			(arc
				(start 337.20278 -406.370536)
				(mid 336.83702 -406.370536)
				(end 337.20278 -406.370536)
			)
		)
		(stroke
			(width 0)
			(type solid)
		)
		(fill yes)
		(layer "F.Cu")
		(net "GND")
	)
	(gr_poly
		(pts
			(arc
				(start 337.660996 -404.51786)
				(mid 337.295236 -404.51786)
				(end 337.660996 -404.51786)
			)
		)
		(stroke
			(width 0)
			(type solid)
		)
		(fill yes)
		(layer "F.Cu")
		(net "GND")
	)
	(gr_poly
		(pts
			(arc
				(start 337.660996 -403.249892)
				(mid 337.295236 -403.249892)
				(end 337.660996 -403.249892)
			)
		)
		(stroke
			(width 0)
			(type solid)
		)
		(fill yes)
		(layer "F.Cu")
		(net "GND")
	)
	(gr_poly
		(pts
			(arc
				(start 337.660996 -401.492212)
				(mid 337.295236 -401.492212)
				(end 337.660996 -401.492212)
			)
		)
		(stroke
			(width 0)
			(type solid)
		)
		(fill yes)
		(layer "F.Cu")
		(net "GND")
	)
	(gr_poly
		(pts
			(arc
				(start 337.660996 -400.224244)
				(mid 337.295236 -400.224244)
				(end 337.660996 -400.224244)
			)
		)
		(stroke
			(width 0)
			(type solid)
		)
		(fill yes)
		(layer "F.Cu")
		(net "GND")
	)
	(gr_poly
		(pts
			(arc
				(start 338.91982 -404.51786)
				(mid 338.55406 -404.51786)
				(end 338.91982 -404.51786)
			)
		)
		(stroke
			(width 0)
			(type solid)
		)
		(fill yes)
		(layer "F.Cu")
		(net "GND")
	)
	(gr_poly
		(pts
			(arc
				(start 338.91982 -403.249892)
				(mid 338.55406 -403.249892)
				(end 338.91982 -403.249892)
			)
		)
		(stroke
			(width 0)
			(type solid)
		)
		(fill yes)
		(layer "F.Cu")
		(net "GND")
	)
	(gr_poly
		(pts
			(arc
				(start 338.91982 -401.492212)
				(mid 338.55406 -401.492212)
				(end 338.91982 -401.492212)
			)
		)
		(stroke
			(width 0)
			(type solid)
		)
		(fill yes)
		(layer "F.Cu")
		(net "GND")
	)
	(gr_poly
		(pts
			(arc
				(start 338.91982 -400.224244)
				(mid 338.55406 -400.224244)
				(end 338.91982 -400.224244)
			)
		)
		(stroke
			(width 0)
			(type solid)
		)
		(fill yes)
		(layer "F.Cu")
		(net "GND")
	)
	(gr_poly
		(pts
			(arc
				(start 339.007196 -410.664152)
				(mid 338.641436 -410.664152)
				(end 339.007196 -410.664152)
			)
		)
		(stroke
			(width 0)
			(type solid)
		)
		(fill yes)
		(layer "F.Cu")
		(net "GND")
	)
	(gr_poly
		(pts
			(arc
				(start 339.007196 -409.396184)
				(mid 338.641436 -409.396184)
				(end 339.007196 -409.396184)
			)
		)
		(stroke
			(width 0)
			(type solid)
		)
		(fill yes)
		(layer "F.Cu")
		(net "GND")
	)
	(gr_poly
		(pts
			(arc
				(start 339.007196 -407.638504)
				(mid 338.641436 -407.638504)
				(end 339.007196 -407.638504)
			)
		)
		(stroke
			(width 0)
			(type solid)
		)
		(fill yes)
		(layer "F.Cu")
		(net "GND")
	)
	(gr_poly
		(pts
			(arc
				(start 339.007196 -406.370536)
				(mid 338.641436 -406.370536)
				(end 339.007196 -406.370536)
			)
		)
		(stroke
			(width 0)
			(type solid)
		)
		(fill yes)
		(layer "F.Cu")
		(net "GND")
	)
	(gr_poly
		(pts
			(arc
				(start 340.26602 -410.664152)
				(mid 339.90026 -410.664152)
				(end 340.26602 -410.664152)
			)
		)
		(stroke
			(width 0)
			(type solid)
		)
		(fill yes)
		(layer "F.Cu")
		(net "GND")
	)
	(gr_poly
		(pts
			(arc
				(start 340.26602 -409.396184)
				(mid 339.90026 -409.396184)
				(end 340.26602 -409.396184)
			)
		)
		(stroke
			(width 0)
			(type solid)
		)
		(fill yes)
		(layer "F.Cu")
		(net "GND")
	)
	(gr_poly
		(pts
			(arc
				(start 340.26602 -407.638504)
				(mid 339.90026 -407.638504)
				(end 340.26602 -407.638504)
			)
		)
		(stroke
			(width 0)
			(type solid)
		)
		(fill yes)
		(layer "F.Cu")
		(net "GND")
	)
	(gr_poly
		(pts
			(arc
				(start 340.26602 -406.370536)
				(mid 339.90026 -406.370536)
				(end 340.26602 -406.370536)
			)
		)
		(stroke
			(width 0)
			(type solid)
		)
		(fill yes)
		(layer "F.Cu")
		(net "GND")
	)
	(gr_poly
		(pts
			(arc
				(start 340.724236 -404.51786)
				(mid 340.358476 -404.51786)
				(end 340.724236 -404.51786)
			)
		)
		(stroke
			(width 0)
			(type solid)
		)
		(fill yes)
		(layer "F.Cu")
		(net "GND")
	)
	(gr_poly
		(pts
			(arc
				(start 340.724236 -403.249892)
				(mid 340.358476 -403.249892)
				(end 340.724236 -403.249892)
			)
		)
		(stroke
			(width 0)
			(type solid)
		)
		(fill yes)
		(layer "F.Cu")
		(net "GND")
	)
	(gr_poly
		(pts
			(arc
				(start 340.724236 -401.492212)
				(mid 340.358476 -401.492212)
				(end 340.724236 -401.492212)
			)
		)
		(stroke
			(width 0)
			(type solid)
		)
		(fill yes)
		(layer "F.Cu")
		(net "GND")
	)
	(gr_poly
		(pts
			(arc
				(start 340.724236 -400.224244)
				(mid 340.358476 -400.224244)
				(end 340.724236 -400.224244)
			)
		)
		(stroke
			(width 0)
			(type solid)
		)
		(fill yes)
		(layer "F.Cu")
		(net "GND")
	)
	(gr_poly
		(pts
			(arc
				(start 341.98306 -404.51786)
				(mid 341.6173 -404.51786)
				(end 341.98306 -404.51786)
			)
		)
		(stroke
			(width 0)
			(type solid)
		)
		(fill yes)
		(layer "F.Cu")
		(net "GND")
	)
	(gr_poly
		(pts
			(arc
				(start 341.98306 -403.249892)
				(mid 341.6173 -403.249892)
				(end 341.98306 -403.249892)
			)
		)
		(stroke
			(width 0)
			(type solid)
		)
		(fill yes)
		(layer "F.Cu")
		(net "GND")
	)
	(gr_poly
		(pts
			(arc
				(start 341.98306 -401.492212)
				(mid 341.6173 -401.492212)
				(end 341.98306 -401.492212)
			)
		)
		(stroke
			(width 0)
			(type solid)
		)
		(fill yes)
		(layer "F.Cu")
		(net "GND")
	)
	(gr_poly
		(pts
			(arc
				(start 341.98306 -400.224244)
				(mid 341.6173 -400.224244)
				(end 341.98306 -400.224244)
			)
		)
		(stroke
			(width 0)
			(type solid)
		)
		(fill yes)
		(layer "F.Cu")
		(net "GND")
	)
	(gr_poly
		(pts
			(arc
				(start 342.070436 -410.664152)
				(mid 341.704676 -410.664152)
				(end 342.070436 -410.664152)
			)
		)
		(stroke
			(width 0)
			(type solid)
		)
		(fill yes)
		(layer "F.Cu")
		(net "GND")
	)
	(gr_poly
		(pts
			(arc
				(start 342.070436 -409.396184)
				(mid 341.704676 -409.396184)
				(end 342.070436 -409.396184)
			)
		)
		(stroke
			(width 0)
			(type solid)
		)
		(fill yes)
		(layer "F.Cu")
		(net "GND")
	)
	(gr_poly
		(pts
			(arc
				(start 342.070436 -407.638504)
				(mid 341.704676 -407.638504)
				(end 342.070436 -407.638504)
			)
		)
		(stroke
			(width 0)
			(type solid)
		)
		(fill yes)
		(layer "F.Cu")
		(net "GND")
	)
	(gr_poly
		(pts
			(arc
				(start 342.070436 -406.370536)
				(mid 341.704676 -406.370536)
				(end 342.070436 -406.370536)
			)
		)
		(stroke
			(width 0)
			(type solid)
		)
		(fill yes)
		(layer "F.Cu")
		(net "GND")
	)
	(gr_poly
		(pts
			(arc
				(start 343.32926 -410.664152)
				(mid 342.9635 -410.664152)
				(end 343.32926 -410.664152)
			)
		)
		(stroke
			(width 0)
			(type solid)
		)
		(fill yes)
		(layer "F.Cu")
		(net "GND")
	)
	(gr_poly
		(pts
			(arc
				(start 343.32926 -409.396184)
				(mid 342.9635 -409.396184)
				(end 343.32926 -409.396184)
			)
		)
		(stroke
			(width 0)
			(type solid)
		)
		(fill yes)
		(layer "F.Cu")
		(net "GND")
	)
	(gr_poly
		(pts
			(arc
				(start 343.32926 -407.638504)
				(mid 342.9635 -407.638504)
				(end 343.32926 -407.638504)
			)
		)
		(stroke
			(width 0)
			(type solid)
		)
		(fill yes)
		(layer "F.Cu")
		(net "GND")
	)
	(gr_poly
		(pts
			(arc
				(start 343.32926 -406.370536)
				(mid 342.9635 -406.370536)
				(end 343.32926 -406.370536)
			)
		)
		(stroke
			(width 0)
			(type solid)
		)
		(fill yes)
		(layer "F.Cu")
		(net "GND")
	)
	(gr_poly
		(pts
			(arc
				(start 343.787476 -404.51786)
				(mid 343.421716 -404.51786)
				(end 343.787476 -404.51786)
			)
		)
		(stroke
			(width 0)
			(type solid)
		)
		(fill yes)
		(layer "F.Cu")
		(net "GND")
	)
	(gr_poly
		(pts
			(arc
				(start 343.787476 -403.249892)
				(mid 343.421716 -403.249892)
				(end 343.787476 -403.249892)
			)
		)
		(stroke
			(width 0)
			(type solid)
		)
		(fill yes)
		(layer "F.Cu")
		(net "GND")
	)
	(gr_poly
		(pts
			(arc
				(start 343.787476 -401.492212)
				(mid 343.421716 -401.492212)
				(end 343.787476 -401.492212)
			)
		)
		(stroke
			(width 0)
			(type solid)
		)
		(fill yes)
		(layer "F.Cu")
		(net "GND")
	)
	(gr_poly
		(pts
			(arc
				(start 343.787476 -400.224244)
				(mid 343.421716 -400.224244)
				(end 343.787476 -400.224244)
			)
		)
		(stroke
			(width 0)
			(type solid)
		)
		(fill yes)
		(layer "F.Cu")
		(net "GND")
	)
	(gr_poly
		(pts
			(arc
				(start 345.0463 -404.51786)
				(mid 344.68054 -404.51786)
				(end 345.0463 -404.51786)
			)
		)
		(stroke
			(width 0)
			(type solid)
		)
		(fill yes)
		(layer "F.Cu")
		(net "GND")
	)
	(gr_poly
		(pts
			(arc
				(start 345.0463 -403.249892)
				(mid 344.68054 -403.249892)
				(end 345.0463 -403.249892)
			)
		)
		(stroke
			(width 0)
			(type solid)
		)
		(fill yes)
		(layer "F.Cu")
		(net "GND")
	)
	(gr_poly
		(pts
			(arc
				(start 345.0463 -401.492212)
				(mid 344.68054 -401.492212)
				(end 345.0463 -401.492212)
			)
		)
		(stroke
			(width 0)
			(type solid)
		)
		(fill yes)
		(layer "F.Cu")
		(net "GND")
	)
	(gr_poly
		(pts
			(arc
				(start 345.0463 -400.224244)
				(mid 344.68054 -400.224244)
				(end 345.0463 -400.224244)
			)
		)
		(stroke
			(width 0)
			(type solid)
		)
		(fill yes)
		(layer "F.Cu")
		(net "GND")
	)
	(gr_poly
		(pts
			(arc
				(start 345.133676 -410.664152)
				(mid 344.767916 -410.664152)
				(end 345.133676 -410.664152)
			)
		)
		(stroke
			(width 0)
			(type solid)
		)
		(fill yes)
		(layer "F.Cu")
		(net "GND")
	)
	(gr_poly
		(pts
			(arc
				(start 345.133676 -409.396184)
				(mid 344.767916 -409.396184)
				(end 345.133676 -409.396184)
			)
		)
		(stroke
			(width 0)
			(type solid)
		)
		(fill yes)
		(layer "F.Cu")
		(net "GND")
	)
	(gr_poly
		(pts
			(arc
				(start 345.133676 -407.638504)
				(mid 344.767916 -407.638504)
				(end 345.133676 -407.638504)
			)
		)
		(stroke
			(width 0)
			(type solid)
		)
		(fill yes)
		(layer "F.Cu")
		(net "GND")
	)
	(gr_poly
		(pts
			(arc
				(start 345.133676 -406.370536)
				(mid 344.767916 -406.370536)
				(end 345.133676 -406.370536)
			)
		)
		(stroke
			(width 0)
			(type solid)
		)
		(fill yes)
		(layer "F.Cu")
		(net "GND")
	)
	(gr_poly
		(pts
			(arc
				(start 346.3925 -410.664152)
				(mid 346.02674 -410.664152)
				(end 346.3925 -410.664152)
			)
		)
		(stroke
			(width 0)
			(type solid)
		)
		(fill yes)
		(layer "F.Cu")
		(net "GND")
	)
	(gr_poly
		(pts
			(arc
				(start 346.3925 -409.396184)
				(mid 346.02674 -409.396184)
				(end 346.3925 -409.396184)
			)
		)
		(stroke
			(width 0)
			(type solid)
		)
		(fill yes)
		(layer "F.Cu")
		(net "GND")
	)
	(gr_poly
		(pts
			(arc
				(start 346.3925 -407.638504)
				(mid 346.02674 -407.638504)
				(end 346.3925 -407.638504)
			)
		)
		(stroke
			(width 0)
			(type solid)
		)
		(fill yes)
		(layer "F.Cu")
		(net "GND")
	)
	(gr_poly
		(pts
			(arc
				(start 346.3925 -406.370536)
				(mid 346.02674 -406.370536)
				(end 346.3925 -406.370536)
			)
		)
		(stroke
			(width 0)
			(type solid)
		)
		(fill yes)
		(layer "F.Cu")
		(net "GND")
	)
	(gr_poly
		(pts
			(arc
				(start 346.850716 -404.51786)
				(mid 346.484956 -404.51786)
				(end 346.850716 -404.51786)
			)
		)
		(stroke
			(width 0)
			(type solid)
		)
		(fill yes)
		(layer "F.Cu")
		(net "GND")
	)
	(gr_poly
		(pts
			(arc
				(start 346.850716 -403.249892)
				(mid 346.484956 -403.249892)
				(end 346.850716 -403.249892)
			)
		)
		(stroke
			(width 0)
			(type solid)
		)
		(fill yes)
		(layer "F.Cu")
		(net "GND")
	)
	(gr_poly
		(pts
			(arc
				(start 346.850716 -401.492212)
				(mid 346.484956 -401.492212)
				(end 346.850716 -401.492212)
			)
		)
		(stroke
			(width 0)
			(type solid)
		)
		(fill yes)
		(layer "F.Cu")
		(net "GND")
	)
	(gr_poly
		(pts
			(arc
				(start 346.850716 -400.200368)
				(mid 346.484956 -400.200368)
				(end 346.850716 -400.200368)
			)
		)
		(stroke
			(width 0)
			(type solid)
		)
		(fill yes)
		(layer "F.Cu")
		(net "GND")
	)
	(gr_poly
		(pts
			(arc
				(start 348.10954 -404.51786)
				(mid 347.74378 -404.51786)
				(end 348.10954 -404.51786)
			)
		)
		(stroke
			(width 0)
			(type solid)
		)
		(fill yes)
		(layer "F.Cu")
		(net "GND")
	)
	(gr_poly
		(pts
			(arc
				(start 348.10954 -403.249892)
				(mid 347.74378 -403.249892)
				(end 348.10954 -403.249892)
			)
		)
		(stroke
			(width 0)
			(type solid)
		)
		(fill yes)
		(layer "F.Cu")
		(net "GND")
	)
	(gr_poly
		(pts
			(arc
				(start 348.10954 -401.492212)
				(mid 347.74378 -401.492212)
				(end 348.10954 -401.492212)
			)
		)
		(stroke
			(width 0)
			(type solid)
		)
		(fill yes)
		(layer "F.Cu")
		(net "GND")
	)
	(gr_poly
		(pts
			(arc
				(start 348.10954 -400.200368)
				(mid 347.74378 -400.200368)
				(end 348.10954 -400.200368)
			)
		)
		(stroke
			(width 0)
			(type solid)
		)
		(fill yes)
		(layer "F.Cu")
		(net "GND")
	)
	(gr_poly
		(pts
			(arc
				(start 348.196916 -410.664152)
				(mid 347.831156 -410.664152)
				(end 348.196916 -410.664152)
			)
		)
		(stroke
			(width 0)
			(type solid)
		)
		(fill yes)
		(layer "F.Cu")
		(net "GND")
	)
	(gr_poly
		(pts
			(arc
				(start 348.196916 -409.396184)
				(mid 347.831156 -409.396184)
				(end 348.196916 -409.396184)
			)
		)
		(stroke
			(width 0)
			(type solid)
		)
		(fill yes)
		(layer "F.Cu")
		(net "GND")
	)
	(gr_poly
		(pts
			(arc
				(start 348.196916 -407.638504)
				(mid 347.831156 -407.638504)
				(end 348.196916 -407.638504)
			)
		)
		(stroke
			(width 0)
			(type solid)
		)
		(fill yes)
		(layer "F.Cu")
		(net "GND")
	)
	(gr_poly
		(pts
			(arc
				(start 348.196916 -406.34666)
				(mid 347.831156 -406.34666)
				(end 348.196916 -406.34666)
			)
		)
		(stroke
			(width 0)
			(type solid)
		)
		(fill yes)
		(layer "F.Cu")
		(net "GND")
	)
	(gr_poly
		(pts
			(arc
				(start 348.311724 -44.796964)
				(mid 347.945964 -44.796964)
				(end 348.311724 -44.796964)
			)
		)
		(stroke
			(width 0)
			(type solid)
		)
		(fill yes)
		(layer "F.Cu")
		(net "GND")
	)
	(gr_poly
		(pts
			(arc
				(start 349.45574 -410.664152)
				(mid 349.08998 -410.664152)
				(end 349.45574 -410.664152)
			)
		)
		(stroke
			(width 0)
			(type solid)
		)
		(fill yes)
		(layer "F.Cu")
		(net "GND")
	)
	(gr_poly
		(pts
			(arc
				(start 349.45574 -409.396184)
				(mid 349.08998 -409.396184)
				(end 349.45574 -409.396184)
			)
		)
		(stroke
			(width 0)
			(type solid)
		)
		(fill yes)
		(layer "F.Cu")
		(net "GND")
	)
	(gr_poly
		(pts
			(arc
				(start 349.45574 -407.638504)
				(mid 349.08998 -407.638504)
				(end 349.45574 -407.638504)
			)
		)
		(stroke
			(width 0)
			(type solid)
		)
		(fill yes)
		(layer "F.Cu")
		(net "GND")
	)
	(gr_poly
		(pts
			(arc
				(start 349.45574 -406.34666)
				(mid 349.08998 -406.34666)
				(end 349.45574 -406.34666)
			)
		)
		(stroke
			(width 0)
			(type solid)
		)
		(fill yes)
		(layer "F.Cu")
		(net "GND")
	)
	(gr_poly
		(pts
			(arc
				(start 349.913956 -404.51786)
				(mid 349.548196 -404.51786)
				(end 349.913956 -404.51786)
			)
		)
		(stroke
			(width 0)
			(type solid)
		)
		(fill yes)
		(layer "F.Cu")
		(net "GND")
	)
	(gr_poly
		(pts
			(arc
				(start 349.913956 -403.249892)
				(mid 349.548196 -403.249892)
				(end 349.913956 -403.249892)
			)
		)
		(stroke
			(width 0)
			(type solid)
		)
		(fill yes)
		(layer "F.Cu")
		(net "GND")
	)
	(gr_poly
		(pts
			(arc
				(start 349.913956 -401.492212)
				(mid 349.548196 -401.492212)
				(end 349.913956 -401.492212)
			)
		)
		(stroke
			(width 0)
			(type solid)
		)
		(fill yes)
		(layer "F.Cu")
		(net "GND")
	)
	(gr_poly
		(pts
			(arc
				(start 349.913956 -400.224244)
				(mid 349.548196 -400.224244)
				(end 349.913956 -400.224244)
			)
		)
		(stroke
			(width 0)
			(type solid)
		)
		(fill yes)
		(layer "F.Cu")
		(net "GND")
	)
	(gr_poly
		(pts
			(arc
				(start 350.08693 -50.191416)
				(mid 349.732346 -50.191416)
				(end 350.08693 -50.191416)
			)
		)
		(stroke
			(width 0)
			(type solid)
		)
		(fill yes)
		(layer "F.Cu")
		(net "GND")
	)
	(gr_poly
		(pts
			(arc
				(start 350.695006 -44.78782)
				(mid 350.329246 -44.78782)
				(end 350.695006 -44.78782)
			)
		)
		(stroke
			(width 0)
			(type solid)
		)
		(fill yes)
		(layer "F.Cu")
		(net "GND")
	)
	(gr_poly
		(pts
			(arc
				(start 351.17278 -404.51786)
				(mid 350.80702 -404.51786)
				(end 351.17278 -404.51786)
			)
		)
		(stroke
			(width 0)
			(type solid)
		)
		(fill yes)
		(layer "F.Cu")
		(net "GND")
	)
	(gr_poly
		(pts
			(arc
				(start 351.17278 -403.249892)
				(mid 350.80702 -403.249892)
				(end 351.17278 -403.249892)
			)
		)
		(stroke
			(width 0)
			(type solid)
		)
		(fill yes)
		(layer "F.Cu")
		(net "GND")
	)
	(gr_poly
		(pts
			(arc
				(start 351.17278 -401.492212)
				(mid 350.80702 -401.492212)
				(end 351.17278 -401.492212)
			)
		)
		(stroke
			(width 0)
			(type solid)
		)
		(fill yes)
		(layer "F.Cu")
		(net "GND")
	)
	(gr_poly
		(pts
			(arc
				(start 351.17278 -400.224244)
				(mid 350.80702 -400.224244)
				(end 351.17278 -400.224244)
			)
		)
		(stroke
			(width 0)
			(type solid)
		)
		(fill yes)
		(layer "F.Cu")
		(net "GND")
	)
	(gr_poly
		(pts
			(arc
				(start 351.260156 -410.664152)
				(mid 350.894396 -410.664152)
				(end 351.260156 -410.664152)
			)
		)
		(stroke
			(width 0)
			(type solid)
		)
		(fill yes)
		(layer "F.Cu")
		(net "GND")
	)
	(gr_poly
		(pts
			(arc
				(start 351.260156 -409.396184)
				(mid 350.894396 -409.396184)
				(end 351.260156 -409.396184)
			)
		)
		(stroke
			(width 0)
			(type solid)
		)
		(fill yes)
		(layer "F.Cu")
		(net "GND")
	)
	(gr_poly
		(pts
			(arc
				(start 351.260156 -407.638504)
				(mid 350.894396 -407.638504)
				(end 351.260156 -407.638504)
			)
		)
		(stroke
			(width 0)
			(type solid)
		)
		(fill yes)
		(layer "F.Cu")
		(net "GND")
	)
	(gr_poly
		(pts
			(arc
				(start 351.260156 -406.370536)
				(mid 350.894396 -406.370536)
				(end 351.260156 -406.370536)
			)
		)
		(stroke
			(width 0)
			(type solid)
		)
		(fill yes)
		(layer "F.Cu")
		(net "GND")
	)
	(gr_poly
		(pts
			(arc
				(start 352.02114 -127.315468)
				(mid 351.65538 -127.315468)
				(end 352.02114 -127.315468)
			)
		)
		(stroke
			(width 0)
			(type solid)
		)
		(fill yes)
		(layer "F.Cu")
		(net "GND")
	)
	(gr_poly
		(pts
			(arc
				(start 352.419412 -50.207672)
				(mid 352.064828 -50.207672)
				(end 352.419412 -50.207672)
			)
		)
		(stroke
			(width 0)
			(type solid)
		)
		(fill yes)
		(layer "F.Cu")
		(net "GND")
	)
	(gr_poly
		(pts
			(arc
				(start 352.51898 -410.664152)
				(mid 352.15322 -410.664152)
				(end 352.51898 -410.664152)
			)
		)
		(stroke
			(width 0)
			(type solid)
		)
		(fill yes)
		(layer "F.Cu")
		(net "GND")
	)
	(gr_poly
		(pts
			(arc
				(start 352.51898 -409.396184)
				(mid 352.15322 -409.396184)
				(end 352.51898 -409.396184)
			)
		)
		(stroke
			(width 0)
			(type solid)
		)
		(fill yes)
		(layer "F.Cu")
		(net "GND")
	)
	(gr_poly
		(pts
			(arc
				(start 352.51898 -407.638504)
				(mid 352.15322 -407.638504)
				(end 352.51898 -407.638504)
			)
		)
		(stroke
			(width 0)
			(type solid)
		)
		(fill yes)
		(layer "F.Cu")
		(net "GND")
	)
	(gr_poly
		(pts
			(arc
				(start 352.51898 -406.370536)
				(mid 352.15322 -406.370536)
				(end 352.51898 -406.370536)
			)
		)
		(stroke
			(width 0)
			(type solid)
		)
		(fill yes)
		(layer "F.Cu")
		(net "GND")
	)
	(gr_poly
		(pts
			(arc
				(start 353.29876 -126.426468)
				(mid 352.933 -126.426468)
				(end 353.29876 -126.426468)
			)
		)
		(stroke
			(width 0)
			(type solid)
		)
		(fill yes)
		(layer "F.Cu")
		(net "GND")
	)
	(gr_poly
		(pts
			(arc
				(start 354.588826 -50.207672)
				(mid 354.234242 -50.207672)
				(end 354.588826 -50.207672)
			)
		)
		(stroke
			(width 0)
			(type solid)
		)
		(fill yes)
		(layer "F.Cu")
		(net "GND")
	)
	(gr_poly
		(pts
			(arc
				(start 356.09784 -43.604688)
				(mid 355.73208 -43.604688)
				(end 356.09784 -43.604688)
			)
		)
		(stroke
			(width 0)
			(type solid)
		)
		(fill yes)
		(layer "F.Cu")
		(net "GND")
	)
	(gr_poly
		(pts
			(arc
				(start 356.811326 -50.207672)
				(mid 356.456742 -50.207672)
				(end 356.811326 -50.207672)
			)
		)
		(stroke
			(width 0)
			(type solid)
		)
		(fill yes)
		(layer "F.Cu")
		(net "GND")
	)
	(gr_poly
		(pts
			(arc
				(start 356.900988 -35.240468)
				(mid 356.535228 -35.240468)
				(end 356.900988 -35.240468)
			)
		)
		(stroke
			(width 0)
			(type solid)
		)
		(fill yes)
		(layer "F.Cu")
		(net "GND")
	)
	(gr_poly
		(pts
			(arc
				(start 358.210612 -39.853616)
				(mid 357.844852 -39.853616)
				(end 358.210612 -39.853616)
			)
		)
		(stroke
			(width 0)
			(type solid)
		)
		(fill yes)
		(layer "F.Cu")
		(net "GND")
	)
	(gr_poly
		(pts
			(arc
				(start 358.210612 -38.594792)
				(mid 357.844852 -38.594792)
				(end 358.210612 -38.594792)
			)
		)
		(stroke
			(width 0)
			(type solid)
		)
		(fill yes)
		(layer "F.Cu")
		(net "GND")
	)
	(gr_poly
		(pts
			(arc
				(start 358.250744 -43.610784)
				(mid 357.884984 -43.610784)
				(end 358.250744 -43.610784)
			)
		)
		(stroke
			(width 0)
			(type solid)
		)
		(fill yes)
		(layer "F.Cu")
		(net "GND")
	)
	(gr_poly
		(pts
			(arc
				(start 359.041446 -50.207672)
				(mid 358.686862 -50.207672)
				(end 359.041446 -50.207672)
			)
		)
		(stroke
			(width 0)
			(type solid)
		)
		(fill yes)
		(layer "F.Cu")
		(net "GND")
	)
	(gr_poly
		(pts
			(arc
				(start 359.073196 -35.240468)
				(mid 358.707436 -35.240468)
				(end 359.073196 -35.240468)
			)
		)
		(stroke
			(width 0)
			(type solid)
		)
		(fill yes)
		(layer "F.Cu")
		(net "GND")
	)
	(gr_poly
		(pts
			(arc
				(start 360.422952 -43.610784)
				(mid 360.057192 -43.610784)
				(end 360.422952 -43.610784)
			)
		)
		(stroke
			(width 0)
			(type solid)
		)
		(fill yes)
		(layer "F.Cu")
		(net "GND")
	)
	(gr_poly
		(pts
			(arc
				(start 365.037624 -76.281026)
				(mid 364.671864 -76.281026)
				(end 365.037624 -76.281026)
			)
		)
		(stroke
			(width 0)
			(type solid)
		)
		(fill yes)
		(layer "F.Cu")
		(net "GND")
	)
	(gr_poly
		(pts
			(arc
				(start 371.408198 -404.51786)
				(mid 371.042438 -404.51786)
				(end 371.408198 -404.51786)
			)
		)
		(stroke
			(width 0)
			(type solid)
		)
		(fill yes)
		(layer "F.Cu")
		(net "GND")
	)
	(gr_poly
		(pts
			(arc
				(start 371.408198 -403.249892)
				(mid 371.042438 -403.249892)
				(end 371.408198 -403.249892)
			)
		)
		(stroke
			(width 0)
			(type solid)
		)
		(fill yes)
		(layer "F.Cu")
		(net "GND")
	)
	(gr_poly
		(pts
			(arc
				(start 371.408198 -401.492212)
				(mid 371.042438 -401.492212)
				(end 371.408198 -401.492212)
			)
		)
		(stroke
			(width 0)
			(type solid)
		)
		(fill yes)
		(layer "F.Cu")
		(net "GND")
	)
	(gr_poly
		(pts
			(arc
				(start 371.408198 -400.224244)
				(mid 371.042438 -400.224244)
				(end 371.408198 -400.224244)
			)
		)
		(stroke
			(width 0)
			(type solid)
		)
		(fill yes)
		(layer "F.Cu")
		(net "GND")
	)
	(gr_poly
		(pts
			(arc
				(start 372.667022 -404.51786)
				(mid 372.301262 -404.51786)
				(end 372.667022 -404.51786)
			)
		)
		(stroke
			(width 0)
			(type solid)
		)
		(fill yes)
		(layer "F.Cu")
		(net "GND")
	)
	(gr_poly
		(pts
			(arc
				(start 372.667022 -403.249892)
				(mid 372.301262 -403.249892)
				(end 372.667022 -403.249892)
			)
		)
		(stroke
			(width 0)
			(type solid)
		)
		(fill yes)
		(layer "F.Cu")
		(net "GND")
	)
	(gr_poly
		(pts
			(arc
				(start 372.667022 -401.492212)
				(mid 372.301262 -401.492212)
				(end 372.667022 -401.492212)
			)
		)
		(stroke
			(width 0)
			(type solid)
		)
		(fill yes)
		(layer "F.Cu")
		(net "GND")
	)
	(gr_poly
		(pts
			(arc
				(start 372.667022 -400.224244)
				(mid 372.301262 -400.224244)
				(end 372.667022 -400.224244)
			)
		)
		(stroke
			(width 0)
			(type solid)
		)
		(fill yes)
		(layer "F.Cu")
		(net "GND")
	)
	(gr_poly
		(pts
			(arc
				(start 372.754398 -410.664152)
				(mid 372.388638 -410.664152)
				(end 372.754398 -410.664152)
			)
		)
		(stroke
			(width 0)
			(type solid)
		)
		(fill yes)
		(layer "F.Cu")
		(net "GND")
	)
	(gr_poly
		(pts
			(arc
				(start 372.754398 -409.396184)
				(mid 372.388638 -409.396184)
				(end 372.754398 -409.396184)
			)
		)
		(stroke
			(width 0)
			(type solid)
		)
		(fill yes)
		(layer "F.Cu")
		(net "GND")
	)
	(gr_poly
		(pts
			(arc
				(start 372.754398 -407.638504)
				(mid 372.388638 -407.638504)
				(end 372.754398 -407.638504)
			)
		)
		(stroke
			(width 0)
			(type solid)
		)
		(fill yes)
		(layer "F.Cu")
		(net "GND")
	)
	(gr_poly
		(pts
			(arc
				(start 372.754398 -406.370536)
				(mid 372.388638 -406.370536)
				(end 372.754398 -406.370536)
			)
		)
		(stroke
			(width 0)
			(type solid)
		)
		(fill yes)
		(layer "F.Cu")
		(net "GND")
	)
	(gr_poly
		(pts
			(arc
				(start 374.013222 -410.664152)
				(mid 373.647462 -410.664152)
				(end 374.013222 -410.664152)
			)
		)
		(stroke
			(width 0)
			(type solid)
		)
		(fill yes)
		(layer "F.Cu")
		(net "GND")
	)
	(gr_poly
		(pts
			(arc
				(start 374.013222 -409.396184)
				(mid 373.647462 -409.396184)
				(end 374.013222 -409.396184)
			)
		)
		(stroke
			(width 0)
			(type solid)
		)
		(fill yes)
		(layer "F.Cu")
		(net "GND")
	)
	(gr_poly
		(pts
			(arc
				(start 374.013222 -407.638504)
				(mid 373.647462 -407.638504)
				(end 374.013222 -407.638504)
			)
		)
		(stroke
			(width 0)
			(type solid)
		)
		(fill yes)
		(layer "F.Cu")
		(net "GND")
	)
	(gr_poly
		(pts
			(arc
				(start 374.013222 -406.370536)
				(mid 373.647462 -406.370536)
				(end 374.013222 -406.370536)
			)
		)
		(stroke
			(width 0)
			(type solid)
		)
		(fill yes)
		(layer "F.Cu")
		(net "GND")
	)
	(gr_poly
		(pts
			(arc
				(start 374.471438 -404.51786)
				(mid 374.105678 -404.51786)
				(end 374.471438 -404.51786)
			)
		)
		(stroke
			(width 0)
			(type solid)
		)
		(fill yes)
		(layer "F.Cu")
		(net "GND")
	)
	(gr_poly
		(pts
			(arc
				(start 374.471438 -403.249892)
				(mid 374.105678 -403.249892)
				(end 374.471438 -403.249892)
			)
		)
		(stroke
			(width 0)
			(type solid)
		)
		(fill yes)
		(layer "F.Cu")
		(net "GND")
	)
	(gr_poly
		(pts
			(arc
				(start 374.471438 -401.492212)
				(mid 374.105678 -401.492212)
				(end 374.471438 -401.492212)
			)
		)
		(stroke
			(width 0)
			(type solid)
		)
		(fill yes)
		(layer "F.Cu")
		(net "GND")
	)
	(gr_poly
		(pts
			(arc
				(start 374.471438 -400.224244)
				(mid 374.105678 -400.224244)
				(end 374.471438 -400.224244)
			)
		)
		(stroke
			(width 0)
			(type solid)
		)
		(fill yes)
		(layer "F.Cu")
		(net "GND")
	)
	(gr_poly
		(pts
			(arc
				(start 375.730262 -404.51786)
				(mid 375.364502 -404.51786)
				(end 375.730262 -404.51786)
			)
		)
		(stroke
			(width 0)
			(type solid)
		)
		(fill yes)
		(layer "F.Cu")
		(net "GND")
	)
	(gr_poly
		(pts
			(arc
				(start 375.730262 -403.249892)
				(mid 375.364502 -403.249892)
				(end 375.730262 -403.249892)
			)
		)
		(stroke
			(width 0)
			(type solid)
		)
		(fill yes)
		(layer "F.Cu")
		(net "GND")
	)
	(gr_poly
		(pts
			(arc
				(start 375.730262 -401.492212)
				(mid 375.364502 -401.492212)
				(end 375.730262 -401.492212)
			)
		)
		(stroke
			(width 0)
			(type solid)
		)
		(fill yes)
		(layer "F.Cu")
		(net "GND")
	)
	(gr_poly
		(pts
			(arc
				(start 375.730262 -400.224244)
				(mid 375.364502 -400.224244)
				(end 375.730262 -400.224244)
			)
		)
		(stroke
			(width 0)
			(type solid)
		)
		(fill yes)
		(layer "F.Cu")
		(net "GND")
	)
	(gr_poly
		(pts
			(arc
				(start 375.778776 -415.846006)
				(mid 375.413016 -415.846006)
				(end 375.778776 -415.846006)
			)
		)
		(stroke
			(width 0)
			(type solid)
		)
		(fill yes)
		(layer "F.Cu")
		(net "GND")
	)
	(gr_poly
		(pts
			(arc
				(start 375.817638 -410.664152)
				(mid 375.451878 -410.664152)
				(end 375.817638 -410.664152)
			)
		)
		(stroke
			(width 0)
			(type solid)
		)
		(fill yes)
		(layer "F.Cu")
		(net "GND")
	)
	(gr_poly
		(pts
			(arc
				(start 375.817638 -409.396184)
				(mid 375.451878 -409.396184)
				(end 375.817638 -409.396184)
			)
		)
		(stroke
			(width 0)
			(type solid)
		)
		(fill yes)
		(layer "F.Cu")
		(net "GND")
	)
	(gr_poly
		(pts
			(arc
				(start 375.817638 -407.638504)
				(mid 375.451878 -407.638504)
				(end 375.817638 -407.638504)
			)
		)
		(stroke
			(width 0)
			(type solid)
		)
		(fill yes)
		(layer "F.Cu")
		(net "GND")
	)
	(gr_poly
		(pts
			(arc
				(start 375.817638 -406.370536)
				(mid 375.451878 -406.370536)
				(end 375.817638 -406.370536)
			)
		)
		(stroke
			(width 0)
			(type solid)
		)
		(fill yes)
		(layer "F.Cu")
		(net "GND")
	)
	(gr_poly
		(pts
			(arc
				(start 377.076462 -410.664152)
				(mid 376.710702 -410.664152)
				(end 377.076462 -410.664152)
			)
		)
		(stroke
			(width 0)
			(type solid)
		)
		(fill yes)
		(layer "F.Cu")
		(net "GND")
	)
	(gr_poly
		(pts
			(arc
				(start 377.076462 -409.396184)
				(mid 376.710702 -409.396184)
				(end 377.076462 -409.396184)
			)
		)
		(stroke
			(width 0)
			(type solid)
		)
		(fill yes)
		(layer "F.Cu")
		(net "GND")
	)
	(gr_poly
		(pts
			(arc
				(start 377.076462 -407.638504)
				(mid 376.710702 -407.638504)
				(end 377.076462 -407.638504)
			)
		)
		(stroke
			(width 0)
			(type solid)
		)
		(fill yes)
		(layer "F.Cu")
		(net "GND")
	)
	(gr_poly
		(pts
			(arc
				(start 377.076462 -406.370536)
				(mid 376.710702 -406.370536)
				(end 377.076462 -406.370536)
			)
		)
		(stroke
			(width 0)
			(type solid)
		)
		(fill yes)
		(layer "F.Cu")
		(net "GND")
	)
	(gr_poly
		(pts
			(arc
				(start 377.534678 -404.51786)
				(mid 377.168918 -404.51786)
				(end 377.534678 -404.51786)
			)
		)
		(stroke
			(width 0)
			(type solid)
		)
		(fill yes)
		(layer "F.Cu")
		(net "GND")
	)
	(gr_poly
		(pts
			(arc
				(start 377.534678 -403.249892)
				(mid 377.168918 -403.249892)
				(end 377.534678 -403.249892)
			)
		)
		(stroke
			(width 0)
			(type solid)
		)
		(fill yes)
		(layer "F.Cu")
		(net "GND")
	)
	(gr_poly
		(pts
			(arc
				(start 377.534678 -401.492212)
				(mid 377.168918 -401.492212)
				(end 377.534678 -401.492212)
			)
		)
		(stroke
			(width 0)
			(type solid)
		)
		(fill yes)
		(layer "F.Cu")
		(net "GND")
	)
	(gr_poly
		(pts
			(arc
				(start 377.534678 -400.224244)
				(mid 377.168918 -400.224244)
				(end 377.534678 -400.224244)
			)
		)
		(stroke
			(width 0)
			(type solid)
		)
		(fill yes)
		(layer "F.Cu")
		(net "GND")
	)
	(gr_poly
		(pts
			(arc
				(start 378.793502 -404.51786)
				(mid 378.427742 -404.51786)
				(end 378.793502 -404.51786)
			)
		)
		(stroke
			(width 0)
			(type solid)
		)
		(fill yes)
		(layer "F.Cu")
		(net "GND")
	)
	(gr_poly
		(pts
			(arc
				(start 378.793502 -403.249892)
				(mid 378.427742 -403.249892)
				(end 378.793502 -403.249892)
			)
		)
		(stroke
			(width 0)
			(type solid)
		)
		(fill yes)
		(layer "F.Cu")
		(net "GND")
	)
	(gr_poly
		(pts
			(arc
				(start 378.793502 -401.492212)
				(mid 378.427742 -401.492212)
				(end 378.793502 -401.492212)
			)
		)
		(stroke
			(width 0)
			(type solid)
		)
		(fill yes)
		(layer "F.Cu")
		(net "GND")
	)
	(gr_poly
		(pts
			(arc
				(start 378.793502 -400.224244)
				(mid 378.427742 -400.224244)
				(end 378.793502 -400.224244)
			)
		)
		(stroke
			(width 0)
			(type solid)
		)
		(fill yes)
		(layer "F.Cu")
		(net "GND")
	)
	(gr_poly
		(pts
			(arc
				(start 378.880878 -410.664152)
				(mid 378.515118 -410.664152)
				(end 378.880878 -410.664152)
			)
		)
		(stroke
			(width 0)
			(type solid)
		)
		(fill yes)
		(layer "F.Cu")
		(net "GND")
	)
	(gr_poly
		(pts
			(arc
				(start 378.880878 -409.396184)
				(mid 378.515118 -409.396184)
				(end 378.880878 -409.396184)
			)
		)
		(stroke
			(width 0)
			(type solid)
		)
		(fill yes)
		(layer "F.Cu")
		(net "GND")
	)
	(gr_poly
		(pts
			(arc
				(start 378.880878 -407.638504)
				(mid 378.515118 -407.638504)
				(end 378.880878 -407.638504)
			)
		)
		(stroke
			(width 0)
			(type solid)
		)
		(fill yes)
		(layer "F.Cu")
		(net "GND")
	)
	(gr_poly
		(pts
			(arc
				(start 378.880878 -406.370536)
				(mid 378.515118 -406.370536)
				(end 378.880878 -406.370536)
			)
		)
		(stroke
			(width 0)
			(type solid)
		)
		(fill yes)
		(layer "F.Cu")
		(net "GND")
	)
	(gr_poly
		(pts
			(arc
				(start 380.139702 -410.664152)
				(mid 379.773942 -410.664152)
				(end 380.139702 -410.664152)
			)
		)
		(stroke
			(width 0)
			(type solid)
		)
		(fill yes)
		(layer "F.Cu")
		(net "GND")
	)
	(gr_poly
		(pts
			(arc
				(start 380.139702 -409.396184)
				(mid 379.773942 -409.396184)
				(end 380.139702 -409.396184)
			)
		)
		(stroke
			(width 0)
			(type solid)
		)
		(fill yes)
		(layer "F.Cu")
		(net "GND")
	)
	(gr_poly
		(pts
			(arc
				(start 380.139702 -407.638504)
				(mid 379.773942 -407.638504)
				(end 380.139702 -407.638504)
			)
		)
		(stroke
			(width 0)
			(type solid)
		)
		(fill yes)
		(layer "F.Cu")
		(net "GND")
	)
	(gr_poly
		(pts
			(arc
				(start 380.139702 -406.370536)
				(mid 379.773942 -406.370536)
				(end 380.139702 -406.370536)
			)
		)
		(stroke
			(width 0)
			(type solid)
		)
		(fill yes)
		(layer "F.Cu")
		(net "GND")
	)
	(gr_poly
		(pts
			(arc
				(start 380.597918 -404.51786)
				(mid 380.232158 -404.51786)
				(end 380.597918 -404.51786)
			)
		)
		(stroke
			(width 0)
			(type solid)
		)
		(fill yes)
		(layer "F.Cu")
		(net "GND")
	)
	(gr_poly
		(pts
			(arc
				(start 380.597918 -403.249892)
				(mid 380.232158 -403.249892)
				(end 380.597918 -403.249892)
			)
		)
		(stroke
			(width 0)
			(type solid)
		)
		(fill yes)
		(layer "F.Cu")
		(net "GND")
	)
	(gr_poly
		(pts
			(arc
				(start 380.597918 -401.492212)
				(mid 380.232158 -401.492212)
				(end 380.597918 -401.492212)
			)
		)
		(stroke
			(width 0)
			(type solid)
		)
		(fill yes)
		(layer "F.Cu")
		(net "GND")
	)
	(gr_poly
		(pts
			(arc
				(start 380.597918 -400.224244)
				(mid 380.232158 -400.224244)
				(end 380.597918 -400.224244)
			)
		)
		(stroke
			(width 0)
			(type solid)
		)
		(fill yes)
		(layer "F.Cu")
		(net "GND")
	)
	(gr_poly
		(pts
			(arc
				(start 381.856742 -404.51786)
				(mid 381.490982 -404.51786)
				(end 381.856742 -404.51786)
			)
		)
		(stroke
			(width 0)
			(type solid)
		)
		(fill yes)
		(layer "F.Cu")
		(net "GND")
	)
	(gr_poly
		(pts
			(arc
				(start 381.856742 -403.249892)
				(mid 381.490982 -403.249892)
				(end 381.856742 -403.249892)
			)
		)
		(stroke
			(width 0)
			(type solid)
		)
		(fill yes)
		(layer "F.Cu")
		(net "GND")
	)
	(gr_poly
		(pts
			(arc
				(start 381.856742 -401.492212)
				(mid 381.490982 -401.492212)
				(end 381.856742 -401.492212)
			)
		)
		(stroke
			(width 0)
			(type solid)
		)
		(fill yes)
		(layer "F.Cu")
		(net "GND")
	)
	(gr_poly
		(pts
			(arc
				(start 381.856742 -400.224244)
				(mid 381.490982 -400.224244)
				(end 381.856742 -400.224244)
			)
		)
		(stroke
			(width 0)
			(type solid)
		)
		(fill yes)
		(layer "F.Cu")
		(net "GND")
	)
	(gr_poly
		(pts
			(arc
				(start 381.944118 -410.664152)
				(mid 381.578358 -410.664152)
				(end 381.944118 -410.664152)
			)
		)
		(stroke
			(width 0)
			(type solid)
		)
		(fill yes)
		(layer "F.Cu")
		(net "GND")
	)
	(gr_poly
		(pts
			(arc
				(start 381.944118 -409.396184)
				(mid 381.578358 -409.396184)
				(end 381.944118 -409.396184)
			)
		)
		(stroke
			(width 0)
			(type solid)
		)
		(fill yes)
		(layer "F.Cu")
		(net "GND")
	)
	(gr_poly
		(pts
			(arc
				(start 381.944118 -407.638504)
				(mid 381.578358 -407.638504)
				(end 381.944118 -407.638504)
			)
		)
		(stroke
			(width 0)
			(type solid)
		)
		(fill yes)
		(layer "F.Cu")
		(net "GND")
	)
	(gr_poly
		(pts
			(arc
				(start 381.944118 -406.370536)
				(mid 381.578358 -406.370536)
				(end 381.944118 -406.370536)
			)
		)
		(stroke
			(width 0)
			(type solid)
		)
		(fill yes)
		(layer "F.Cu")
		(net "GND")
	)
	(gr_poly
		(pts
			(arc
				(start 383.202942 -410.664152)
				(mid 382.837182 -410.664152)
				(end 383.202942 -410.664152)
			)
		)
		(stroke
			(width 0)
			(type solid)
		)
		(fill yes)
		(layer "F.Cu")
		(net "GND")
	)
	(gr_poly
		(pts
			(arc
				(start 383.202942 -409.396184)
				(mid 382.837182 -409.396184)
				(end 383.202942 -409.396184)
			)
		)
		(stroke
			(width 0)
			(type solid)
		)
		(fill yes)
		(layer "F.Cu")
		(net "GND")
	)
	(gr_poly
		(pts
			(arc
				(start 383.202942 -407.638504)
				(mid 382.837182 -407.638504)
				(end 383.202942 -407.638504)
			)
		)
		(stroke
			(width 0)
			(type solid)
		)
		(fill yes)
		(layer "F.Cu")
		(net "GND")
	)
	(gr_poly
		(pts
			(arc
				(start 383.202942 -406.370536)
				(mid 382.837182 -406.370536)
				(end 383.202942 -406.370536)
			)
		)
		(stroke
			(width 0)
			(type solid)
		)
		(fill yes)
		(layer "F.Cu")
		(net "GND")
	)
	(gr_poly
		(pts
			(arc
				(start 383.661158 -404.51786)
				(mid 383.295398 -404.51786)
				(end 383.661158 -404.51786)
			)
		)
		(stroke
			(width 0)
			(type solid)
		)
		(fill yes)
		(layer "F.Cu")
		(net "GND")
	)
	(gr_poly
		(pts
			(arc
				(start 383.661158 -403.249892)
				(mid 383.295398 -403.249892)
				(end 383.661158 -403.249892)
			)
		)
		(stroke
			(width 0)
			(type solid)
		)
		(fill yes)
		(layer "F.Cu")
		(net "GND")
	)
	(gr_poly
		(pts
			(arc
				(start 383.661158 -401.492212)
				(mid 383.295398 -401.492212)
				(end 383.661158 -401.492212)
			)
		)
		(stroke
			(width 0)
			(type solid)
		)
		(fill yes)
		(layer "F.Cu")
		(net "GND")
	)
	(gr_poly
		(pts
			(arc
				(start 383.661158 -400.224244)
				(mid 383.295398 -400.224244)
				(end 383.661158 -400.224244)
			)
		)
		(stroke
			(width 0)
			(type solid)
		)
		(fill yes)
		(layer "F.Cu")
		(net "GND")
	)
	(gr_poly
		(pts
			(arc
				(start 384.919982 -404.51786)
				(mid 384.554222 -404.51786)
				(end 384.919982 -404.51786)
			)
		)
		(stroke
			(width 0)
			(type solid)
		)
		(fill yes)
		(layer "F.Cu")
		(net "GND")
	)
	(gr_poly
		(pts
			(arc
				(start 384.919982 -403.249892)
				(mid 384.554222 -403.249892)
				(end 384.919982 -403.249892)
			)
		)
		(stroke
			(width 0)
			(type solid)
		)
		(fill yes)
		(layer "F.Cu")
		(net "GND")
	)
	(gr_poly
		(pts
			(arc
				(start 384.919982 -401.492212)
				(mid 384.554222 -401.492212)
				(end 384.919982 -401.492212)
			)
		)
		(stroke
			(width 0)
			(type solid)
		)
		(fill yes)
		(layer "F.Cu")
		(net "GND")
	)
	(gr_poly
		(pts
			(arc
				(start 384.919982 -400.224244)
				(mid 384.554222 -400.224244)
				(end 384.919982 -400.224244)
			)
		)
		(stroke
			(width 0)
			(type solid)
		)
		(fill yes)
		(layer "F.Cu")
		(net "GND")
	)
	(gr_poly
		(pts
			(arc
				(start 385.007358 -410.664152)
				(mid 384.641598 -410.664152)
				(end 385.007358 -410.664152)
			)
		)
		(stroke
			(width 0)
			(type solid)
		)
		(fill yes)
		(layer "F.Cu")
		(net "GND")
	)
	(gr_poly
		(pts
			(arc
				(start 385.007358 -409.396184)
				(mid 384.641598 -409.396184)
				(end 385.007358 -409.396184)
			)
		)
		(stroke
			(width 0)
			(type solid)
		)
		(fill yes)
		(layer "F.Cu")
		(net "GND")
	)
	(gr_poly
		(pts
			(arc
				(start 385.007358 -407.638504)
				(mid 384.641598 -407.638504)
				(end 385.007358 -407.638504)
			)
		)
		(stroke
			(width 0)
			(type solid)
		)
		(fill yes)
		(layer "F.Cu")
		(net "GND")
	)
	(gr_poly
		(pts
			(arc
				(start 385.007358 -406.370536)
				(mid 384.641598 -406.370536)
				(end 385.007358 -406.370536)
			)
		)
		(stroke
			(width 0)
			(type solid)
		)
		(fill yes)
		(layer "F.Cu")
		(net "GND")
	)
	(gr_poly
		(pts
			(arc
				(start 386.266182 -410.664152)
				(mid 385.900422 -410.664152)
				(end 386.266182 -410.664152)
			)
		)
		(stroke
			(width 0)
			(type solid)
		)
		(fill yes)
		(layer "F.Cu")
		(net "GND")
	)
	(gr_poly
		(pts
			(arc
				(start 386.266182 -409.396184)
				(mid 385.900422 -409.396184)
				(end 386.266182 -409.396184)
			)
		)
		(stroke
			(width 0)
			(type solid)
		)
		(fill yes)
		(layer "F.Cu")
		(net "GND")
	)
	(gr_poly
		(pts
			(arc
				(start 386.266182 -407.638504)
				(mid 385.900422 -407.638504)
				(end 386.266182 -407.638504)
			)
		)
		(stroke
			(width 0)
			(type solid)
		)
		(fill yes)
		(layer "F.Cu")
		(net "GND")
	)
	(gr_poly
		(pts
			(arc
				(start 386.266182 -406.370536)
				(mid 385.900422 -406.370536)
				(end 386.266182 -406.370536)
			)
		)
		(stroke
			(width 0)
			(type solid)
		)
		(fill yes)
		(layer "F.Cu")
		(net "GND")
	)
	(gr_poly
		(pts
			(arc
				(start 386.724398 -404.51786)
				(mid 386.358638 -404.51786)
				(end 386.724398 -404.51786)
			)
		)
		(stroke
			(width 0)
			(type solid)
		)
		(fill yes)
		(layer "F.Cu")
		(net "GND")
	)
	(gr_poly
		(pts
			(arc
				(start 386.724398 -403.249892)
				(mid 386.358638 -403.249892)
				(end 386.724398 -403.249892)
			)
		)
		(stroke
			(width 0)
			(type solid)
		)
		(fill yes)
		(layer "F.Cu")
		(net "GND")
	)
	(gr_poly
		(pts
			(arc
				(start 386.724398 -401.492212)
				(mid 386.358638 -401.492212)
				(end 386.724398 -401.492212)
			)
		)
		(stroke
			(width 0)
			(type solid)
		)
		(fill yes)
		(layer "F.Cu")
		(net "GND")
	)
	(gr_poly
		(pts
			(arc
				(start 386.724398 -400.224244)
				(mid 386.358638 -400.224244)
				(end 386.724398 -400.224244)
			)
		)
		(stroke
			(width 0)
			(type solid)
		)
		(fill yes)
		(layer "F.Cu")
		(net "GND")
	)
	(gr_poly
		(pts
			(arc
				(start 387.983222 -404.51786)
				(mid 387.617462 -404.51786)
				(end 387.983222 -404.51786)
			)
		)
		(stroke
			(width 0)
			(type solid)
		)
		(fill yes)
		(layer "F.Cu")
		(net "GND")
	)
	(gr_poly
		(pts
			(arc
				(start 387.983222 -403.249892)
				(mid 387.617462 -403.249892)
				(end 387.983222 -403.249892)
			)
		)
		(stroke
			(width 0)
			(type solid)
		)
		(fill yes)
		(layer "F.Cu")
		(net "GND")
	)
	(gr_poly
		(pts
			(arc
				(start 387.983222 -401.492212)
				(mid 387.617462 -401.492212)
				(end 387.983222 -401.492212)
			)
		)
		(stroke
			(width 0)
			(type solid)
		)
		(fill yes)
		(layer "F.Cu")
		(net "GND")
	)
	(gr_poly
		(pts
			(arc
				(start 387.983222 -400.224244)
				(mid 387.617462 -400.224244)
				(end 387.983222 -400.224244)
			)
		)
		(stroke
			(width 0)
			(type solid)
		)
		(fill yes)
		(layer "F.Cu")
		(net "GND")
	)
	(gr_poly
		(pts
			(arc
				(start 388.070598 -410.664152)
				(mid 387.704838 -410.664152)
				(end 388.070598 -410.664152)
			)
		)
		(stroke
			(width 0)
			(type solid)
		)
		(fill yes)
		(layer "F.Cu")
		(net "GND")
	)
	(gr_poly
		(pts
			(arc
				(start 388.070598 -409.396184)
				(mid 387.704838 -409.396184)
				(end 388.070598 -409.396184)
			)
		)
		(stroke
			(width 0)
			(type solid)
		)
		(fill yes)
		(layer "F.Cu")
		(net "GND")
	)
	(gr_poly
		(pts
			(arc
				(start 388.070598 -407.638504)
				(mid 387.704838 -407.638504)
				(end 388.070598 -407.638504)
			)
		)
		(stroke
			(width 0)
			(type solid)
		)
		(fill yes)
		(layer "F.Cu")
		(net "GND")
	)
	(gr_poly
		(pts
			(arc
				(start 388.070598 -406.370536)
				(mid 387.704838 -406.370536)
				(end 388.070598 -406.370536)
			)
		)
		(stroke
			(width 0)
			(type solid)
		)
		(fill yes)
		(layer "F.Cu")
		(net "GND")
	)
	(gr_poly
		(pts
			(arc
				(start 388.756652 -26.185622)
				(mid 388.390892 -26.185622)
				(end 388.756652 -26.185622)
			)
		)
		(stroke
			(width 0)
			(type solid)
		)
		(fill yes)
		(layer "F.Cu")
		(net "GND")
	)
	(gr_poly
		(pts
			(arc
				(start 389.329422 -410.664152)
				(mid 388.963662 -410.664152)
				(end 389.329422 -410.664152)
			)
		)
		(stroke
			(width 0)
			(type solid)
		)
		(fill yes)
		(layer "F.Cu")
		(net "GND")
	)
	(gr_poly
		(pts
			(arc
				(start 389.329422 -409.396184)
				(mid 388.963662 -409.396184)
				(end 389.329422 -409.396184)
			)
		)
		(stroke
			(width 0)
			(type solid)
		)
		(fill yes)
		(layer "F.Cu")
		(net "GND")
	)
	(gr_poly
		(pts
			(arc
				(start 389.329422 -407.638504)
				(mid 388.963662 -407.638504)
				(end 389.329422 -407.638504)
			)
		)
		(stroke
			(width 0)
			(type solid)
		)
		(fill yes)
		(layer "F.Cu")
		(net "GND")
	)
	(gr_poly
		(pts
			(arc
				(start 389.329422 -406.370536)
				(mid 388.963662 -406.370536)
				(end 389.329422 -406.370536)
			)
		)
		(stroke
			(width 0)
			(type solid)
		)
		(fill yes)
		(layer "F.Cu")
		(net "GND")
	)
	(gr_poly
		(pts
			(arc
				(start 389.518652 -17.601438)
				(mid 389.152892 -17.601438)
				(end 389.518652 -17.601438)
			)
		)
		(stroke
			(width 0)
			(type solid)
		)
		(fill yes)
		(layer "F.Cu")
		(net "GND")
	)
	(gr_poly
		(pts
			(arc
				(start 389.787638 -404.51786)
				(mid 389.421878 -404.51786)
				(end 389.787638 -404.51786)
			)
		)
		(stroke
			(width 0)
			(type solid)
		)
		(fill yes)
		(layer "F.Cu")
		(net "GND")
	)
	(gr_poly
		(pts
			(arc
				(start 389.787638 -403.249892)
				(mid 389.421878 -403.249892)
				(end 389.787638 -403.249892)
			)
		)
		(stroke
			(width 0)
			(type solid)
		)
		(fill yes)
		(layer "F.Cu")
		(net "GND")
	)
	(gr_poly
		(pts
			(arc
				(start 389.787638 -401.492212)
				(mid 389.421878 -401.492212)
				(end 389.787638 -401.492212)
			)
		)
		(stroke
			(width 0)
			(type solid)
		)
		(fill yes)
		(layer "F.Cu")
		(net "GND")
	)
	(gr_poly
		(pts
			(arc
				(start 389.787638 -400.200368)
				(mid 389.421878 -400.200368)
				(end 389.787638 -400.200368)
			)
		)
		(stroke
			(width 0)
			(type solid)
		)
		(fill yes)
		(layer "F.Cu")
		(net "GND")
	)
	(gr_poly
		(pts
			(arc
				(start 390.015476 -26.185622)
				(mid 389.649716 -26.185622)
				(end 390.015476 -26.185622)
			)
		)
		(stroke
			(width 0)
			(type solid)
		)
		(fill yes)
		(layer "F.Cu")
		(net "GND")
	)
	(gr_poly
		(pts
			(arc
				(start 390.026652 -18.235422)
				(mid 389.660892 -18.235422)
				(end 390.026652 -18.235422)
			)
		)
		(stroke
			(width 0)
			(type solid)
		)
		(fill yes)
		(layer "F.Cu")
		(net "GND")
	)
	(gr_poly
		(pts
			(arc
				(start 390.026652 -16.967454)
				(mid 389.660892 -16.967454)
				(end 390.026652 -16.967454)
			)
		)
		(stroke
			(width 0)
			(type solid)
		)
		(fill yes)
		(layer "F.Cu")
		(net "GND")
	)
	(gr_poly
		(pts
			(arc
				(start 391.046462 -404.51786)
				(mid 390.680702 -404.51786)
				(end 391.046462 -404.51786)
			)
		)
		(stroke
			(width 0)
			(type solid)
		)
		(fill yes)
		(layer "F.Cu")
		(net "GND")
	)
	(gr_poly
		(pts
			(arc
				(start 391.046462 -403.249892)
				(mid 390.680702 -403.249892)
				(end 391.046462 -403.249892)
			)
		)
		(stroke
			(width 0)
			(type solid)
		)
		(fill yes)
		(layer "F.Cu")
		(net "GND")
	)
	(gr_poly
		(pts
			(arc
				(start 391.046462 -401.492212)
				(mid 390.680702 -401.492212)
				(end 391.046462 -401.492212)
			)
		)
		(stroke
			(width 0)
			(type solid)
		)
		(fill yes)
		(layer "F.Cu")
		(net "GND")
	)
	(gr_poly
		(pts
			(arc
				(start 391.046462 -400.200368)
				(mid 390.680702 -400.200368)
				(end 391.046462 -400.200368)
			)
		)
		(stroke
			(width 0)
			(type solid)
		)
		(fill yes)
		(layer "F.Cu")
		(net "GND")
	)
	(gr_poly
		(pts
			(arc
				(start 391.133838 -410.664152)
				(mid 390.768078 -410.664152)
				(end 391.133838 -410.664152)
			)
		)
		(stroke
			(width 0)
			(type solid)
		)
		(fill yes)
		(layer "F.Cu")
		(net "GND")
	)
	(gr_poly
		(pts
			(arc
				(start 391.133838 -409.396184)
				(mid 390.768078 -409.396184)
				(end 391.133838 -409.396184)
			)
		)
		(stroke
			(width 0)
			(type solid)
		)
		(fill yes)
		(layer "F.Cu")
		(net "GND")
	)
	(gr_poly
		(pts
			(arc
				(start 391.133838 -407.638504)
				(mid 390.768078 -407.638504)
				(end 391.133838 -407.638504)
			)
		)
		(stroke
			(width 0)
			(type solid)
		)
		(fill yes)
		(layer "F.Cu")
		(net "GND")
	)
	(gr_poly
		(pts
			(arc
				(start 391.133838 -406.34666)
				(mid 390.768078 -406.34666)
				(end 391.133838 -406.34666)
			)
		)
		(stroke
			(width 0)
			(type solid)
		)
		(fill yes)
		(layer "F.Cu")
		(net "GND")
	)
	(gr_poly
		(pts
			(arc
				(start 391.285476 -18.235422)
				(mid 390.919716 -18.235422)
				(end 391.285476 -18.235422)
			)
		)
		(stroke
			(width 0)
			(type solid)
		)
		(fill yes)
		(layer "F.Cu")
		(net "GND")
	)
	(gr_poly
		(pts
			(arc
				(start 391.285476 -16.967454)
				(mid 390.919716 -16.967454)
				(end 391.285476 -16.967454)
			)
		)
		(stroke
			(width 0)
			(type solid)
		)
		(fill yes)
		(layer "F.Cu")
		(net "GND")
	)
	(gr_poly
		(pts
			(arc
				(start 391.793476 -17.601438)
				(mid 391.427716 -17.601438)
				(end 391.793476 -17.601438)
			)
		)
		(stroke
			(width 0)
			(type solid)
		)
		(fill yes)
		(layer "F.Cu")
		(net "GND")
	)
	(gr_poly
		(pts
			(arc
				(start 392.312652 -19.125438)
				(mid 391.946892 -19.125438)
				(end 392.312652 -19.125438)
			)
		)
		(stroke
			(width 0)
			(type solid)
		)
		(fill yes)
		(layer "F.Cu")
		(net "GND")
	)
	(gr_poly
		(pts
			(arc
				(start 392.392662 -410.664152)
				(mid 392.026902 -410.664152)
				(end 392.392662 -410.664152)
			)
		)
		(stroke
			(width 0)
			(type solid)
		)
		(fill yes)
		(layer "F.Cu")
		(net "GND")
	)
	(gr_poly
		(pts
			(arc
				(start 392.392662 -409.396184)
				(mid 392.026902 -409.396184)
				(end 392.392662 -409.396184)
			)
		)
		(stroke
			(width 0)
			(type solid)
		)
		(fill yes)
		(layer "F.Cu")
		(net "GND")
	)
	(gr_poly
		(pts
			(arc
				(start 392.392662 -407.638504)
				(mid 392.026902 -407.638504)
				(end 392.392662 -407.638504)
			)
		)
		(stroke
			(width 0)
			(type solid)
		)
		(fill yes)
		(layer "F.Cu")
		(net "GND")
	)
	(gr_poly
		(pts
			(arc
				(start 392.392662 -406.34666)
				(mid 392.026902 -406.34666)
				(end 392.392662 -406.34666)
			)
		)
		(stroke
			(width 0)
			(type solid)
		)
		(fill yes)
		(layer "F.Cu")
		(net "GND")
	)
	(gr_poly
		(pts
			(arc
				(start 392.820652 -19.759422)
				(mid 392.454892 -19.759422)
				(end 392.820652 -19.759422)
			)
		)
		(stroke
			(width 0)
			(type solid)
		)
		(fill yes)
		(layer "F.Cu")
		(net "GND")
	)
	(gr_poly
		(pts
			(arc
				(start 392.820652 -18.491454)
				(mid 392.454892 -18.491454)
				(end 392.820652 -18.491454)
			)
		)
		(stroke
			(width 0)
			(type solid)
		)
		(fill yes)
		(layer "F.Cu")
		(net "GND")
	)
	(gr_poly
		(pts
			(arc
				(start 392.850878 -404.51786)
				(mid 392.485118 -404.51786)
				(end 392.850878 -404.51786)
			)
		)
		(stroke
			(width 0)
			(type solid)
		)
		(fill yes)
		(layer "F.Cu")
		(net "GND")
	)
	(gr_poly
		(pts
			(arc
				(start 392.850878 -403.249892)
				(mid 392.485118 -403.249892)
				(end 392.850878 -403.249892)
			)
		)
		(stroke
			(width 0)
			(type solid)
		)
		(fill yes)
		(layer "F.Cu")
		(net "GND")
	)
	(gr_poly
		(pts
			(arc
				(start 392.850878 -401.492212)
				(mid 392.485118 -401.492212)
				(end 392.850878 -401.492212)
			)
		)
		(stroke
			(width 0)
			(type solid)
		)
		(fill yes)
		(layer "F.Cu")
		(net "GND")
	)
	(gr_poly
		(pts
			(arc
				(start 392.850878 -400.224244)
				(mid 392.485118 -400.224244)
				(end 392.850878 -400.224244)
			)
		)
		(stroke
			(width 0)
			(type solid)
		)
		(fill yes)
		(layer "F.Cu")
		(net "GND")
	)
	(gr_poly
		(pts
			(arc
				(start 393.0015 -6.586474)
				(mid 392.63574 -6.586474)
				(end 393.0015 -6.586474)
			)
		)
		(stroke
			(width 0)
			(type solid)
		)
		(fill yes)
		(layer "F.Cu")
		(net "GND")
	)
	(gr_poly
		(pts
			(arc
				(start 393.5095 -6.07949)
				(mid 393.14374 -6.07949)
				(end 393.5095 -6.07949)
			)
		)
		(stroke
			(width 0)
			(type solid)
		)
		(fill yes)
		(layer "F.Cu")
		(net "GND")
	)
	(gr_poly
		(pts
			(arc
				(start 394.079476 -19.759422)
				(mid 393.713716 -19.759422)
				(end 394.079476 -19.759422)
			)
		)
		(stroke
			(width 0)
			(type solid)
		)
		(fill yes)
		(layer "F.Cu")
		(net "GND")
	)
	(gr_poly
		(pts
			(arc
				(start 394.079476 -18.491454)
				(mid 393.713716 -18.491454)
				(end 394.079476 -18.491454)
			)
		)
		(stroke
			(width 0)
			(type solid)
		)
		(fill yes)
		(layer "F.Cu")
		(net "GND")
	)
	(gr_poly
		(pts
			(arc
				(start 394.109702 -404.51786)
				(mid 393.743942 -404.51786)
				(end 394.109702 -404.51786)
			)
		)
		(stroke
			(width 0)
			(type solid)
		)
		(fill yes)
		(layer "F.Cu")
		(net "GND")
	)
	(gr_poly
		(pts
			(arc
				(start 394.109702 -403.249892)
				(mid 393.743942 -403.249892)
				(end 394.109702 -403.249892)
			)
		)
		(stroke
			(width 0)
			(type solid)
		)
		(fill yes)
		(layer "F.Cu")
		(net "GND")
	)
	(gr_poly
		(pts
			(arc
				(start 394.109702 -401.492212)
				(mid 393.743942 -401.492212)
				(end 394.109702 -401.492212)
			)
		)
		(stroke
			(width 0)
			(type solid)
		)
		(fill yes)
		(layer "F.Cu")
		(net "GND")
	)
	(gr_poly
		(pts
			(arc
				(start 394.109702 -400.224244)
				(mid 393.743942 -400.224244)
				(end 394.109702 -400.224244)
			)
		)
		(stroke
			(width 0)
			(type solid)
		)
		(fill yes)
		(layer "F.Cu")
		(net "GND")
	)
	(gr_poly
		(pts
			(arc
				(start 394.197078 -410.664152)
				(mid 393.831318 -410.664152)
				(end 394.197078 -410.664152)
			)
		)
		(stroke
			(width 0)
			(type solid)
		)
		(fill yes)
		(layer "F.Cu")
		(net "GND")
	)
	(gr_poly
		(pts
			(arc
				(start 394.197078 -409.396184)
				(mid 393.831318 -409.396184)
				(end 394.197078 -409.396184)
			)
		)
		(stroke
			(width 0)
			(type solid)
		)
		(fill yes)
		(layer "F.Cu")
		(net "GND")
	)
	(gr_poly
		(pts
			(arc
				(start 394.197078 -407.638504)
				(mid 393.831318 -407.638504)
				(end 394.197078 -407.638504)
			)
		)
		(stroke
			(width 0)
			(type solid)
		)
		(fill yes)
		(layer "F.Cu")
		(net "GND")
	)
	(gr_poly
		(pts
			(arc
				(start 394.197078 -406.370536)
				(mid 393.831318 -406.370536)
				(end 394.197078 -406.370536)
			)
		)
		(stroke
			(width 0)
			(type solid)
		)
		(fill yes)
		(layer "F.Cu")
		(net "GND")
	)
	(gr_poly
		(pts
			(arc
				(start 394.587476 -19.125438)
				(mid 394.221716 -19.125438)
				(end 394.587476 -19.125438)
			)
		)
		(stroke
			(width 0)
			(type solid)
		)
		(fill yes)
		(layer "F.Cu")
		(net "GND")
	)
	(gr_poly
		(pts
			(arc
				(start 394.768324 -6.07949)
				(mid 394.402564 -6.07949)
				(end 394.768324 -6.07949)
			)
		)
		(stroke
			(width 0)
			(type solid)
		)
		(fill yes)
		(layer "F.Cu")
		(net "GND")
	)
	(gr_poly
		(pts
			(arc
				(start 394.80617 -4.95173)
				(mid 394.44041 -4.95173)
				(end 394.80617 -4.95173)
			)
		)
		(stroke
			(width 0)
			(type solid)
		)
		(fill yes)
		(layer "F.Cu")
		(net "GND")
	)
	(gr_poly
		(pts
			(arc
				(start 395.106652 -17.601438)
				(mid 394.740892 -17.601438)
				(end 395.106652 -17.601438)
			)
		)
		(stroke
			(width 0)
			(type solid)
		)
		(fill yes)
		(layer "F.Cu")
		(net "GND")
	)
	(gr_poly
		(pts
			(arc
				(start 395.276324 -6.586474)
				(mid 394.910564 -6.586474)
				(end 395.276324 -6.586474)
			)
		)
		(stroke
			(width 0)
			(type solid)
		)
		(fill yes)
		(layer "F.Cu")
		(net "GND")
	)
	(gr_poly
		(pts
			(arc
				(start 395.31417 -5.585714)
				(mid 394.94841 -5.585714)
				(end 395.31417 -5.585714)
			)
		)
		(stroke
			(width 0)
			(type solid)
		)
		(fill yes)
		(layer "F.Cu")
		(net "GND")
	)
	(gr_poly
		(pts
			(arc
				(start 395.31417 -4.317746)
				(mid 394.94841 -4.317746)
				(end 395.31417 -4.317746)
			)
		)
		(stroke
			(width 0)
			(type solid)
		)
		(fill yes)
		(layer "F.Cu")
		(net "GND")
	)
	(gr_poly
		(pts
			(arc
				(start 395.455902 -410.664152)
				(mid 395.090142 -410.664152)
				(end 395.455902 -410.664152)
			)
		)
		(stroke
			(width 0)
			(type solid)
		)
		(fill yes)
		(layer "F.Cu")
		(net "GND")
	)
	(gr_poly
		(pts
			(arc
				(start 395.455902 -409.396184)
				(mid 395.090142 -409.396184)
				(end 395.455902 -409.396184)
			)
		)
		(stroke
			(width 0)
			(type solid)
		)
		(fill yes)
		(layer "F.Cu")
		(net "GND")
	)
	(gr_poly
		(pts
			(arc
				(start 395.455902 -407.638504)
				(mid 395.090142 -407.638504)
				(end 395.455902 -407.638504)
			)
		)
		(stroke
			(width 0)
			(type solid)
		)
		(fill yes)
		(layer "F.Cu")
		(net "GND")
	)
	(gr_poly
		(pts
			(arc
				(start 395.455902 -406.370536)
				(mid 395.090142 -406.370536)
				(end 395.455902 -406.370536)
			)
		)
		(stroke
			(width 0)
			(type solid)
		)
		(fill yes)
		(layer "F.Cu")
		(net "GND")
	)
	(gr_poly
		(pts
			(arc
				(start 395.614652 -18.235422)
				(mid 395.248892 -18.235422)
				(end 395.614652 -18.235422)
			)
		)
		(stroke
			(width 0)
			(type solid)
		)
		(fill yes)
		(layer "F.Cu")
		(net "GND")
	)
	(gr_poly
		(pts
			(arc
				(start 395.614652 -16.967454)
				(mid 395.248892 -16.967454)
				(end 395.614652 -16.967454)
			)
		)
		(stroke
			(width 0)
			(type solid)
		)
		(fill yes)
		(layer "F.Cu")
		(net "GND")
	)
	(gr_poly
		(pts
			(arc
				(start 395.914118 -404.51786)
				(mid 395.548358 -404.51786)
				(end 395.914118 -404.51786)
			)
		)
		(stroke
			(width 0)
			(type solid)
		)
		(fill yes)
		(layer "F.Cu")
		(net "GND")
	)
	(gr_poly
		(pts
			(arc
				(start 395.914118 -403.249892)
				(mid 395.548358 -403.249892)
				(end 395.914118 -403.249892)
			)
		)
		(stroke
			(width 0)
			(type solid)
		)
		(fill yes)
		(layer "F.Cu")
		(net "GND")
	)
	(gr_poly
		(pts
			(arc
				(start 395.914118 -401.492212)
				(mid 395.548358 -401.492212)
				(end 395.914118 -401.492212)
			)
		)
		(stroke
			(width 0)
			(type solid)
		)
		(fill yes)
		(layer "F.Cu")
		(net "GND")
	)
	(gr_poly
		(pts
			(arc
				(start 395.914118 -400.224244)
				(mid 395.548358 -400.224244)
				(end 395.914118 -400.224244)
			)
		)
		(stroke
			(width 0)
			(type solid)
		)
		(fill yes)
		(layer "F.Cu")
		(net "GND")
	)
	(gr_poly
		(pts
			(arc
				(start 396.572994 -5.585714)
				(mid 396.207234 -5.585714)
				(end 396.572994 -5.585714)
			)
		)
		(stroke
			(width 0)
			(type solid)
		)
		(fill yes)
		(layer "F.Cu")
		(net "GND")
	)
	(gr_poly
		(pts
			(arc
				(start 396.572994 -4.317746)
				(mid 396.207234 -4.317746)
				(end 396.572994 -4.317746)
			)
		)
		(stroke
			(width 0)
			(type solid)
		)
		(fill yes)
		(layer "F.Cu")
		(net "GND")
	)
	(gr_poly
		(pts
			(arc
				(start 396.601442 -6.586474)
				(mid 396.235682 -6.586474)
				(end 396.601442 -6.586474)
			)
		)
		(stroke
			(width 0)
			(type solid)
		)
		(fill yes)
		(layer "F.Cu")
		(net "GND")
	)
	(gr_poly
		(pts
			(arc
				(start 396.873476 -18.235422)
				(mid 396.507716 -18.235422)
				(end 396.873476 -18.235422)
			)
		)
		(stroke
			(width 0)
			(type solid)
		)
		(fill yes)
		(layer "F.Cu")
		(net "GND")
	)
	(gr_poly
		(pts
			(arc
				(start 396.873476 -16.967454)
				(mid 396.507716 -16.967454)
				(end 396.873476 -16.967454)
			)
		)
		(stroke
			(width 0)
			(type solid)
		)
		(fill yes)
		(layer "F.Cu")
		(net "GND")
	)
	(gr_poly
		(pts
			(arc
				(start 397.080994 -4.95173)
				(mid 396.715234 -4.95173)
				(end 397.080994 -4.95173)
			)
		)
		(stroke
			(width 0)
			(type solid)
		)
		(fill yes)
		(layer "F.Cu")
		(net "GND")
	)
	(gr_poly
		(pts
			(arc
				(start 397.109442 -6.07949)
				(mid 396.743682 -6.07949)
				(end 397.109442 -6.07949)
			)
		)
		(stroke
			(width 0)
			(type solid)
		)
		(fill yes)
		(layer "F.Cu")
		(net "GND")
	)
	(gr_poly
		(pts
			(arc
				(start 397.172942 -404.51786)
				(mid 396.807182 -404.51786)
				(end 397.172942 -404.51786)
			)
		)
		(stroke
			(width 0)
			(type solid)
		)
		(fill yes)
		(layer "F.Cu")
		(net "GND")
	)
	(gr_poly
		(pts
			(arc
				(start 397.172942 -403.249892)
				(mid 396.807182 -403.249892)
				(end 397.172942 -403.249892)
			)
		)
		(stroke
			(width 0)
			(type solid)
		)
		(fill yes)
		(layer "F.Cu")
		(net "GND")
	)
	(gr_poly
		(pts
			(arc
				(start 397.172942 -401.492212)
				(mid 396.807182 -401.492212)
				(end 397.172942 -401.492212)
			)
		)
		(stroke
			(width 0)
			(type solid)
		)
		(fill yes)
		(layer "F.Cu")
		(net "GND")
	)
	(gr_poly
		(pts
			(arc
				(start 397.172942 -400.224244)
				(mid 396.807182 -400.224244)
				(end 397.172942 -400.224244)
			)
		)
		(stroke
			(width 0)
			(type solid)
		)
		(fill yes)
		(layer "F.Cu")
		(net "GND")
	)
	(gr_poly
		(pts
			(arc
				(start 397.260318 -410.664152)
				(mid 396.894558 -410.664152)
				(end 397.260318 -410.664152)
			)
		)
		(stroke
			(width 0)
			(type solid)
		)
		(fill yes)
		(layer "F.Cu")
		(net "GND")
	)
	(gr_poly
		(pts
			(arc
				(start 397.260318 -409.396184)
				(mid 396.894558 -409.396184)
				(end 397.260318 -409.396184)
			)
		)
		(stroke
			(width 0)
			(type solid)
		)
		(fill yes)
		(layer "F.Cu")
		(net "GND")
	)
	(gr_poly
		(pts
			(arc
				(start 397.260318 -407.638504)
				(mid 396.894558 -407.638504)
				(end 397.260318 -407.638504)
			)
		)
		(stroke
			(width 0)
			(type solid)
		)
		(fill yes)
		(layer "F.Cu")
		(net "GND")
	)
	(gr_poly
		(pts
			(arc
				(start 397.260318 -406.370536)
				(mid 396.894558 -406.370536)
				(end 397.260318 -406.370536)
			)
		)
		(stroke
			(width 0)
			(type solid)
		)
		(fill yes)
		(layer "F.Cu")
		(net "GND")
	)
	(gr_poly
		(pts
			(arc
				(start 397.381476 -17.601438)
				(mid 397.015716 -17.601438)
				(end 397.381476 -17.601438)
			)
		)
		(stroke
			(width 0)
			(type solid)
		)
		(fill yes)
		(layer "F.Cu")
		(net "GND")
	)
	(gr_poly
		(pts
			(arc
				(start 397.900652 -19.125438)
				(mid 397.534892 -19.125438)
				(end 397.900652 -19.125438)
			)
		)
		(stroke
			(width 0)
			(type solid)
		)
		(fill yes)
		(layer "F.Cu")
		(net "GND")
	)
	(gr_poly
		(pts
			(arc
				(start 398.368266 -6.07949)
				(mid 398.002506 -6.07949)
				(end 398.368266 -6.07949)
			)
		)
		(stroke
			(width 0)
			(type solid)
		)
		(fill yes)
		(layer "F.Cu")
		(net "GND")
	)
	(gr_poly
		(pts
			(arc
				(start 398.406112 -4.95173)
				(mid 398.040352 -4.95173)
				(end 398.406112 -4.95173)
			)
		)
		(stroke
			(width 0)
			(type solid)
		)
		(fill yes)
		(layer "F.Cu")
		(net "GND")
	)
	(gr_poly
		(pts
			(arc
				(start 398.408652 -19.759422)
				(mid 398.042892 -19.759422)
				(end 398.408652 -19.759422)
			)
		)
		(stroke
			(width 0)
			(type solid)
		)
		(fill yes)
		(layer "F.Cu")
		(net "GND")
	)
	(gr_poly
		(pts
			(arc
				(start 398.408652 -18.491454)
				(mid 398.042892 -18.491454)
				(end 398.408652 -18.491454)
			)
		)
		(stroke
			(width 0)
			(type solid)
		)
		(fill yes)
		(layer "F.Cu")
		(net "GND")
	)
	(gr_poly
		(pts
			(arc
				(start 398.519142 -410.664152)
				(mid 398.153382 -410.664152)
				(end 398.519142 -410.664152)
			)
		)
		(stroke
			(width 0)
			(type solid)
		)
		(fill yes)
		(layer "F.Cu")
		(net "GND")
	)
	(gr_poly
		(pts
			(arc
				(start 398.519142 -409.396184)
				(mid 398.153382 -409.396184)
				(end 398.519142 -409.396184)
			)
		)
		(stroke
			(width 0)
			(type solid)
		)
		(fill yes)
		(layer "F.Cu")
		(net "GND")
	)
	(gr_poly
		(pts
			(arc
				(start 398.519142 -407.638504)
				(mid 398.153382 -407.638504)
				(end 398.519142 -407.638504)
			)
		)
		(stroke
			(width 0)
			(type solid)
		)
		(fill yes)
		(layer "F.Cu")
		(net "GND")
	)
	(gr_poly
		(pts
			(arc
				(start 398.519142 -406.370536)
				(mid 398.153382 -406.370536)
				(end 398.519142 -406.370536)
			)
		)
		(stroke
			(width 0)
			(type solid)
		)
		(fill yes)
		(layer "F.Cu")
		(net "GND")
	)
	(gr_poly
		(pts
			(arc
				(start 398.876266 -6.586474)
				(mid 398.510506 -6.586474)
				(end 398.876266 -6.586474)
			)
		)
		(stroke
			(width 0)
			(type solid)
		)
		(fill yes)
		(layer "F.Cu")
		(net "GND")
	)
	(gr_poly
		(pts
			(arc
				(start 398.914112 -5.585714)
				(mid 398.548352 -5.585714)
				(end 398.914112 -5.585714)
			)
		)
		(stroke
			(width 0)
			(type solid)
		)
		(fill yes)
		(layer "F.Cu")
		(net "GND")
	)
	(gr_poly
		(pts
			(arc
				(start 398.914112 -4.317746)
				(mid 398.548352 -4.317746)
				(end 398.914112 -4.317746)
			)
		)
		(stroke
			(width 0)
			(type solid)
		)
		(fill yes)
		(layer "F.Cu")
		(net "GND")
	)
	(gr_poly
		(pts
			(arc
				(start 398.977358 -404.51786)
				(mid 398.611598 -404.51786)
				(end 398.977358 -404.51786)
			)
		)
		(stroke
			(width 0)
			(type solid)
		)
		(fill yes)
		(layer "F.Cu")
		(net "GND")
	)
	(gr_poly
		(pts
			(arc
				(start 398.977358 -403.249892)
				(mid 398.611598 -403.249892)
				(end 398.977358 -403.249892)
			)
		)
		(stroke
			(width 0)
			(type solid)
		)
		(fill yes)
		(layer "F.Cu")
		(net "GND")
	)
	(gr_poly
		(pts
			(arc
				(start 398.977358 -401.492212)
				(mid 398.611598 -401.492212)
				(end 398.977358 -401.492212)
			)
		)
		(stroke
			(width 0)
			(type solid)
		)
		(fill yes)
		(layer "F.Cu")
		(net "GND")
	)
	(gr_poly
		(pts
			(arc
				(start 398.977358 -400.224244)
				(mid 398.611598 -400.224244)
				(end 398.977358 -400.224244)
			)
		)
		(stroke
			(width 0)
			(type solid)
		)
		(fill yes)
		(layer "F.Cu")
		(net "GND")
	)
	(gr_poly
		(pts
			(arc
				(start 399.667476 -19.759422)
				(mid 399.301716 -19.759422)
				(end 399.667476 -19.759422)
			)
		)
		(stroke
			(width 0)
			(type solid)
		)
		(fill yes)
		(layer "F.Cu")
		(net "GND")
	)
	(gr_poly
		(pts
			(arc
				(start 399.667476 -18.491454)
				(mid 399.301716 -18.491454)
				(end 399.667476 -18.491454)
			)
		)
		(stroke
			(width 0)
			(type solid)
		)
		(fill yes)
		(layer "F.Cu")
		(net "GND")
	)
	(gr_poly
		(pts
			(arc
				(start 400.172936 -5.585714)
				(mid 399.807176 -5.585714)
				(end 400.172936 -5.585714)
			)
		)
		(stroke
			(width 0)
			(type solid)
		)
		(fill yes)
		(layer "F.Cu")
		(net "GND")
	)
	(gr_poly
		(pts
			(arc
				(start 400.172936 -4.317746)
				(mid 399.807176 -4.317746)
				(end 400.172936 -4.317746)
			)
		)
		(stroke
			(width 0)
			(type solid)
		)
		(fill yes)
		(layer "F.Cu")
		(net "GND")
	)
	(gr_poly
		(pts
			(arc
				(start 400.175476 -19.125438)
				(mid 399.809716 -19.125438)
				(end 400.175476 -19.125438)
			)
		)
		(stroke
			(width 0)
			(type solid)
		)
		(fill yes)
		(layer "F.Cu")
		(net "GND")
	)
	(gr_poly
		(pts
			(arc
				(start 400.201384 -6.586474)
				(mid 399.835624 -6.586474)
				(end 400.201384 -6.586474)
			)
		)
		(stroke
			(width 0)
			(type solid)
		)
		(fill yes)
		(layer "F.Cu")
		(net "GND")
	)
	(gr_poly
		(pts
			(arc
				(start 400.236182 -404.51786)
				(mid 399.870422 -404.51786)
				(end 400.236182 -404.51786)
			)
		)
		(stroke
			(width 0)
			(type solid)
		)
		(fill yes)
		(layer "F.Cu")
		(net "GND")
	)
	(gr_poly
		(pts
			(arc
				(start 400.236182 -403.249892)
				(mid 399.870422 -403.249892)
				(end 400.236182 -403.249892)
			)
		)
		(stroke
			(width 0)
			(type solid)
		)
		(fill yes)
		(layer "F.Cu")
		(net "GND")
	)
	(gr_poly
		(pts
			(arc
				(start 400.236182 -401.492212)
				(mid 399.870422 -401.492212)
				(end 400.236182 -401.492212)
			)
		)
		(stroke
			(width 0)
			(type solid)
		)
		(fill yes)
		(layer "F.Cu")
		(net "GND")
	)
	(gr_poly
		(pts
			(arc
				(start 400.236182 -400.224244)
				(mid 399.870422 -400.224244)
				(end 400.236182 -400.224244)
			)
		)
		(stroke
			(width 0)
			(type solid)
		)
		(fill yes)
		(layer "F.Cu")
		(net "GND")
	)
	(gr_poly
		(pts
			(arc
				(start 400.275806 -77.197966)
				(mid 399.910046 -77.197966)
				(end 400.275806 -77.197966)
			)
		)
		(stroke
			(width 0)
			(type solid)
		)
		(fill yes)
		(layer "F.Cu")
		(net "GND")
	)
	(gr_poly
		(pts
			(arc
				(start 400.323558 -410.664152)
				(mid 399.957798 -410.664152)
				(end 400.323558 -410.664152)
			)
		)
		(stroke
			(width 0)
			(type solid)
		)
		(fill yes)
		(layer "F.Cu")
		(net "GND")
	)
	(gr_poly
		(pts
			(arc
				(start 400.323558 -409.396184)
				(mid 399.957798 -409.396184)
				(end 400.323558 -409.396184)
			)
		)
		(stroke
			(width 0)
			(type solid)
		)
		(fill yes)
		(layer "F.Cu")
		(net "GND")
	)
	(gr_poly
		(pts
			(arc
				(start 400.323558 -407.638504)
				(mid 399.957798 -407.638504)
				(end 400.323558 -407.638504)
			)
		)
		(stroke
			(width 0)
			(type solid)
		)
		(fill yes)
		(layer "F.Cu")
		(net "GND")
	)
	(gr_poly
		(pts
			(arc
				(start 400.323558 -406.370536)
				(mid 399.957798 -406.370536)
				(end 400.323558 -406.370536)
			)
		)
		(stroke
			(width 0)
			(type solid)
		)
		(fill yes)
		(layer "F.Cu")
		(net "GND")
	)
	(gr_poly
		(pts
			(arc
				(start 400.680936 -4.95173)
				(mid 400.315176 -4.95173)
				(end 400.680936 -4.95173)
			)
		)
		(stroke
			(width 0)
			(type solid)
		)
		(fill yes)
		(layer "F.Cu")
		(net "GND")
	)
	(gr_poly
		(pts
			(arc
				(start 400.694652 -17.601438)
				(mid 400.328892 -17.601438)
				(end 400.694652 -17.601438)
			)
		)
		(stroke
			(width 0)
			(type solid)
		)
		(fill yes)
		(layer "F.Cu")
		(net "GND")
	)
	(gr_poly
		(pts
			(arc
				(start 400.709384 -6.07949)
				(mid 400.343624 -6.07949)
				(end 400.709384 -6.07949)
			)
		)
		(stroke
			(width 0)
			(type solid)
		)
		(fill yes)
		(layer "F.Cu")
		(net "GND")
	)
	(gr_poly
		(pts
			(arc
				(start 401.202652 -18.235422)
				(mid 400.836892 -18.235422)
				(end 401.202652 -18.235422)
			)
		)
		(stroke
			(width 0)
			(type solid)
		)
		(fill yes)
		(layer "F.Cu")
		(net "GND")
	)
	(gr_poly
		(pts
			(arc
				(start 401.202652 -16.967454)
				(mid 400.836892 -16.967454)
				(end 401.202652 -16.967454)
			)
		)
		(stroke
			(width 0)
			(type solid)
		)
		(fill yes)
		(layer "F.Cu")
		(net "GND")
	)
	(gr_poly
		(pts
			(arc
				(start 401.582382 -410.664152)
				(mid 401.216622 -410.664152)
				(end 401.582382 -410.664152)
			)
		)
		(stroke
			(width 0)
			(type solid)
		)
		(fill yes)
		(layer "F.Cu")
		(net "GND")
	)
	(gr_poly
		(pts
			(arc
				(start 401.582382 -409.396184)
				(mid 401.216622 -409.396184)
				(end 401.582382 -409.396184)
			)
		)
		(stroke
			(width 0)
			(type solid)
		)
		(fill yes)
		(layer "F.Cu")
		(net "GND")
	)
	(gr_poly
		(pts
			(arc
				(start 401.582382 -407.638504)
				(mid 401.216622 -407.638504)
				(end 401.582382 -407.638504)
			)
		)
		(stroke
			(width 0)
			(type solid)
		)
		(fill yes)
		(layer "F.Cu")
		(net "GND")
	)
	(gr_poly
		(pts
			(arc
				(start 401.582382 -406.370536)
				(mid 401.216622 -406.370536)
				(end 401.582382 -406.370536)
			)
		)
		(stroke
			(width 0)
			(type solid)
		)
		(fill yes)
		(layer "F.Cu")
		(net "GND")
	)
	(gr_poly
		(pts
			(arc
				(start 401.968208 -6.07949)
				(mid 401.602448 -6.07949)
				(end 401.968208 -6.07949)
			)
		)
		(stroke
			(width 0)
			(type solid)
		)
		(fill yes)
		(layer "F.Cu")
		(net "GND")
	)
	(gr_poly
		(pts
			(arc
				(start 402.006054 -4.95173)
				(mid 401.640294 -4.95173)
				(end 402.006054 -4.95173)
			)
		)
		(stroke
			(width 0)
			(type solid)
		)
		(fill yes)
		(layer "F.Cu")
		(net "GND")
	)
	(gr_poly
		(pts
			(arc
				(start 402.040598 -404.51786)
				(mid 401.674838 -404.51786)
				(end 402.040598 -404.51786)
			)
		)
		(stroke
			(width 0)
			(type solid)
		)
		(fill yes)
		(layer "F.Cu")
		(net "GND")
	)
	(gr_poly
		(pts
			(arc
				(start 402.040598 -403.249892)
				(mid 401.674838 -403.249892)
				(end 402.040598 -403.249892)
			)
		)
		(stroke
			(width 0)
			(type solid)
		)
		(fill yes)
		(layer "F.Cu")
		(net "GND")
	)
	(gr_poly
		(pts
			(arc
				(start 402.040598 -401.492212)
				(mid 401.674838 -401.492212)
				(end 402.040598 -401.492212)
			)
		)
		(stroke
			(width 0)
			(type solid)
		)
		(fill yes)
		(layer "F.Cu")
		(net "GND")
	)
	(gr_poly
		(pts
			(arc
				(start 402.040598 -400.224244)
				(mid 401.674838 -400.224244)
				(end 402.040598 -400.224244)
			)
		)
		(stroke
			(width 0)
			(type solid)
		)
		(fill yes)
		(layer "F.Cu")
		(net "GND")
	)
	(gr_poly
		(pts
			(arc
				(start 402.461476 -18.235422)
				(mid 402.095716 -18.235422)
				(end 402.461476 -18.235422)
			)
		)
		(stroke
			(width 0)
			(type solid)
		)
		(fill yes)
		(layer "F.Cu")
		(net "GND")
	)
	(gr_poly
		(pts
			(arc
				(start 402.461476 -16.967454)
				(mid 402.095716 -16.967454)
				(end 402.461476 -16.967454)
			)
		)
		(stroke
			(width 0)
			(type solid)
		)
		(fill yes)
		(layer "F.Cu")
		(net "GND")
	)
	(gr_poly
		(pts
			(arc
				(start 402.476208 -6.586474)
				(mid 402.110448 -6.586474)
				(end 402.476208 -6.586474)
			)
		)
		(stroke
			(width 0)
			(type solid)
		)
		(fill yes)
		(layer "F.Cu")
		(net "GND")
	)
	(gr_poly
		(pts
			(arc
				(start 402.514054 -5.585714)
				(mid 402.148294 -5.585714)
				(end 402.514054 -5.585714)
			)
		)
		(stroke
			(width 0)
			(type solid)
		)
		(fill yes)
		(layer "F.Cu")
		(net "GND")
	)
	(gr_poly
		(pts
			(arc
				(start 402.514054 -4.317746)
				(mid 402.148294 -4.317746)
				(end 402.514054 -4.317746)
			)
		)
		(stroke
			(width 0)
			(type solid)
		)
		(fill yes)
		(layer "F.Cu")
		(net "GND")
	)
	(gr_poly
		(pts
			(arc
				(start 402.969476 -17.601438)
				(mid 402.603716 -17.601438)
				(end 402.969476 -17.601438)
			)
		)
		(stroke
			(width 0)
			(type solid)
		)
		(fill yes)
		(layer "F.Cu")
		(net "GND")
	)
	(gr_poly
		(pts
			(arc
				(start 403.299422 -404.51786)
				(mid 402.933662 -404.51786)
				(end 403.299422 -404.51786)
			)
		)
		(stroke
			(width 0)
			(type solid)
		)
		(fill yes)
		(layer "F.Cu")
		(net "GND")
	)
	(gr_poly
		(pts
			(arc
				(start 403.299422 -403.249892)
				(mid 402.933662 -403.249892)
				(end 403.299422 -403.249892)
			)
		)
		(stroke
			(width 0)
			(type solid)
		)
		(fill yes)
		(layer "F.Cu")
		(net "GND")
	)
	(gr_poly
		(pts
			(arc
				(start 403.299422 -401.492212)
				(mid 402.933662 -401.492212)
				(end 403.299422 -401.492212)
			)
		)
		(stroke
			(width 0)
			(type solid)
		)
		(fill yes)
		(layer "F.Cu")
		(net "GND")
	)
	(gr_poly
		(pts
			(arc
				(start 403.299422 -400.224244)
				(mid 402.933662 -400.224244)
				(end 403.299422 -400.224244)
			)
		)
		(stroke
			(width 0)
			(type solid)
		)
		(fill yes)
		(layer "F.Cu")
		(net "GND")
	)
	(gr_poly
		(pts
			(arc
				(start 403.386798 -410.664152)
				(mid 403.021038 -410.664152)
				(end 403.386798 -410.664152)
			)
		)
		(stroke
			(width 0)
			(type solid)
		)
		(fill yes)
		(layer "F.Cu")
		(net "GND")
	)
	(gr_poly
		(pts
			(arc
				(start 403.386798 -409.396184)
				(mid 403.021038 -409.396184)
				(end 403.386798 -409.396184)
			)
		)
		(stroke
			(width 0)
			(type solid)
		)
		(fill yes)
		(layer "F.Cu")
		(net "GND")
	)
	(gr_poly
		(pts
			(arc
				(start 403.386798 -407.638504)
				(mid 403.021038 -407.638504)
				(end 403.386798 -407.638504)
			)
		)
		(stroke
			(width 0)
			(type solid)
		)
		(fill yes)
		(layer "F.Cu")
		(net "GND")
	)
	(gr_poly
		(pts
			(arc
				(start 403.386798 -406.370536)
				(mid 403.021038 -406.370536)
				(end 403.386798 -406.370536)
			)
		)
		(stroke
			(width 0)
			(type solid)
		)
		(fill yes)
		(layer "F.Cu")
		(net "GND")
	)
	(gr_poly
		(pts
			(arc
				(start 403.488652 -19.125438)
				(mid 403.122892 -19.125438)
				(end 403.488652 -19.125438)
			)
		)
		(stroke
			(width 0)
			(type solid)
		)
		(fill yes)
		(layer "F.Cu")
		(net "GND")
	)
	(gr_poly
		(pts
			(arc
				(start 403.772878 -5.585714)
				(mid 403.407118 -5.585714)
				(end 403.772878 -5.585714)
			)
		)
		(stroke
			(width 0)
			(type solid)
		)
		(fill yes)
		(layer "F.Cu")
		(net "GND")
	)
	(gr_poly
		(pts
			(arc
				(start 403.772878 -4.317746)
				(mid 403.407118 -4.317746)
				(end 403.772878 -4.317746)
			)
		)
		(stroke
			(width 0)
			(type solid)
		)
		(fill yes)
		(layer "F.Cu")
		(net "GND")
	)
	(gr_poly
		(pts
			(arc
				(start 403.80158 -6.586474)
				(mid 403.43582 -6.586474)
				(end 403.80158 -6.586474)
			)
		)
		(stroke
			(width 0)
			(type solid)
		)
		(fill yes)
		(layer "F.Cu")
		(net "GND")
	)
	(gr_poly
		(pts
			(arc
				(start 403.996652 -19.759422)
				(mid 403.630892 -19.759422)
				(end 403.996652 -19.759422)
			)
		)
		(stroke
			(width 0)
			(type solid)
		)
		(fill yes)
		(layer "F.Cu")
		(net "GND")
	)
	(gr_poly
		(pts
			(arc
				(start 403.996652 -18.491454)
				(mid 403.630892 -18.491454)
				(end 403.996652 -18.491454)
			)
		)
		(stroke
			(width 0)
			(type solid)
		)
		(fill yes)
		(layer "F.Cu")
		(net "GND")
	)
	(gr_poly
		(pts
			(arc
				(start 404.280878 -4.95173)
				(mid 403.915118 -4.95173)
				(end 404.280878 -4.95173)
			)
		)
		(stroke
			(width 0)
			(type solid)
		)
		(fill yes)
		(layer "F.Cu")
		(net "GND")
	)
	(gr_poly
		(pts
			(arc
				(start 404.30958 -6.07949)
				(mid 403.94382 -6.07949)
				(end 404.30958 -6.07949)
			)
		)
		(stroke
			(width 0)
			(type solid)
		)
		(fill yes)
		(layer "F.Cu")
		(net "GND")
	)
	(gr_poly
		(pts
			(arc
				(start 404.645622 -410.664152)
				(mid 404.279862 -410.664152)
				(end 404.645622 -410.664152)
			)
		)
		(stroke
			(width 0)
			(type solid)
		)
		(fill yes)
		(layer "F.Cu")
		(net "GND")
	)
	(gr_poly
		(pts
			(arc
				(start 404.645622 -409.396184)
				(mid 404.279862 -409.396184)
				(end 404.645622 -409.396184)
			)
		)
		(stroke
			(width 0)
			(type solid)
		)
		(fill yes)
		(layer "F.Cu")
		(net "GND")
	)
	(gr_poly
		(pts
			(arc
				(start 404.645622 -407.638504)
				(mid 404.279862 -407.638504)
				(end 404.645622 -407.638504)
			)
		)
		(stroke
			(width 0)
			(type solid)
		)
		(fill yes)
		(layer "F.Cu")
		(net "GND")
	)
	(gr_poly
		(pts
			(arc
				(start 404.645622 -406.370536)
				(mid 404.279862 -406.370536)
				(end 404.645622 -406.370536)
			)
		)
		(stroke
			(width 0)
			(type solid)
		)
		(fill yes)
		(layer "F.Cu")
		(net "GND")
	)
	(gr_poly
		(pts
			(arc
				(start 405.103838 -404.51786)
				(mid 404.738078 -404.51786)
				(end 405.103838 -404.51786)
			)
		)
		(stroke
			(width 0)
			(type solid)
		)
		(fill yes)
		(layer "F.Cu")
		(net "GND")
	)
	(gr_poly
		(pts
			(arc
				(start 405.103838 -403.249892)
				(mid 404.738078 -403.249892)
				(end 405.103838 -403.249892)
			)
		)
		(stroke
			(width 0)
			(type solid)
		)
		(fill yes)
		(layer "F.Cu")
		(net "GND")
	)
	(gr_poly
		(pts
			(arc
				(start 405.103838 -401.492212)
				(mid 404.738078 -401.492212)
				(end 405.103838 -401.492212)
			)
		)
		(stroke
			(width 0)
			(type solid)
		)
		(fill yes)
		(layer "F.Cu")
		(net "GND")
	)
	(gr_poly
		(pts
			(arc
				(start 405.103838 -400.224244)
				(mid 404.738078 -400.224244)
				(end 405.103838 -400.224244)
			)
		)
		(stroke
			(width 0)
			(type solid)
		)
		(fill yes)
		(layer "F.Cu")
		(net "GND")
	)
	(gr_poly
		(pts
			(arc
				(start 405.255476 -19.759422)
				(mid 404.889716 -19.759422)
				(end 405.255476 -19.759422)
			)
		)
		(stroke
			(width 0)
			(type solid)
		)
		(fill yes)
		(layer "F.Cu")
		(net "GND")
	)
	(gr_poly
		(pts
			(arc
				(start 405.255476 -18.491454)
				(mid 404.889716 -18.491454)
				(end 405.255476 -18.491454)
			)
		)
		(stroke
			(width 0)
			(type solid)
		)
		(fill yes)
		(layer "F.Cu")
		(net "GND")
	)
	(gr_poly
		(pts
			(arc
				(start 405.568404 -6.07949)
				(mid 405.202644 -6.07949)
				(end 405.568404 -6.07949)
			)
		)
		(stroke
			(width 0)
			(type solid)
		)
		(fill yes)
		(layer "F.Cu")
		(net "GND")
	)
	(gr_poly
		(pts
			(arc
				(start 405.60625 -4.95173)
				(mid 405.24049 -4.95173)
				(end 405.60625 -4.95173)
			)
		)
		(stroke
			(width 0)
			(type solid)
		)
		(fill yes)
		(layer "F.Cu")
		(net "GND")
	)
	(gr_poly
		(pts
			(arc
				(start 405.763476 -19.125438)
				(mid 405.397716 -19.125438)
				(end 405.763476 -19.125438)
			)
		)
		(stroke
			(width 0)
			(type solid)
		)
		(fill yes)
		(layer "F.Cu")
		(net "GND")
	)
	(gr_poly
		(pts
			(arc
				(start 406.076404 -6.586474)
				(mid 405.710644 -6.586474)
				(end 406.076404 -6.586474)
			)
		)
		(stroke
			(width 0)
			(type solid)
		)
		(fill yes)
		(layer "F.Cu")
		(net "GND")
	)
	(gr_poly
		(pts
			(arc
				(start 406.11425 -5.585714)
				(mid 405.74849 -5.585714)
				(end 406.11425 -5.585714)
			)
		)
		(stroke
			(width 0)
			(type solid)
		)
		(fill yes)
		(layer "F.Cu")
		(net "GND")
	)
	(gr_poly
		(pts
			(arc
				(start 406.11425 -4.317746)
				(mid 405.74849 -4.317746)
				(end 406.11425 -4.317746)
			)
		)
		(stroke
			(width 0)
			(type solid)
		)
		(fill yes)
		(layer "F.Cu")
		(net "GND")
	)
	(gr_poly
		(pts
			(arc
				(start 406.282652 -17.601438)
				(mid 405.916892 -17.601438)
				(end 406.282652 -17.601438)
			)
		)
		(stroke
			(width 0)
			(type solid)
		)
		(fill yes)
		(layer "F.Cu")
		(net "GND")
	)
	(gr_poly
		(pts
			(arc
				(start 406.362662 -404.51786)
				(mid 405.996902 -404.51786)
				(end 406.362662 -404.51786)
			)
		)
		(stroke
			(width 0)
			(type solid)
		)
		(fill yes)
		(layer "F.Cu")
		(net "GND")
	)
	(gr_poly
		(pts
			(arc
				(start 406.362662 -403.249892)
				(mid 405.996902 -403.249892)
				(end 406.362662 -403.249892)
			)
		)
		(stroke
			(width 0)
			(type solid)
		)
		(fill yes)
		(layer "F.Cu")
		(net "GND")
	)
	(gr_poly
		(pts
			(arc
				(start 406.362662 -401.492212)
				(mid 405.996902 -401.492212)
				(end 406.362662 -401.492212)
			)
		)
		(stroke
			(width 0)
			(type solid)
		)
		(fill yes)
		(layer "F.Cu")
		(net "GND")
	)
	(gr_poly
		(pts
			(arc
				(start 406.362662 -400.224244)
				(mid 405.996902 -400.224244)
				(end 406.362662 -400.224244)
			)
		)
		(stroke
			(width 0)
			(type solid)
		)
		(fill yes)
		(layer "F.Cu")
		(net "GND")
	)
	(gr_poly
		(pts
			(arc
				(start 406.450038 -410.664152)
				(mid 406.084278 -410.664152)
				(end 406.450038 -410.664152)
			)
		)
		(stroke
			(width 0)
			(type solid)
		)
		(fill yes)
		(layer "F.Cu")
		(net "GND")
	)
	(gr_poly
		(pts
			(arc
				(start 406.450038 -409.396184)
				(mid 406.084278 -409.396184)
				(end 406.450038 -409.396184)
			)
		)
		(stroke
			(width 0)
			(type solid)
		)
		(fill yes)
		(layer "F.Cu")
		(net "GND")
	)
	(gr_poly
		(pts
			(arc
				(start 406.450038 -407.638504)
				(mid 406.084278 -407.638504)
				(end 406.450038 -407.638504)
			)
		)
		(stroke
			(width 0)
			(type solid)
		)
		(fill yes)
		(layer "F.Cu")
		(net "GND")
	)
	(gr_poly
		(pts
			(arc
				(start 406.450038 -406.370536)
				(mid 406.084278 -406.370536)
				(end 406.450038 -406.370536)
			)
		)
		(stroke
			(width 0)
			(type solid)
		)
		(fill yes)
		(layer "F.Cu")
		(net "GND")
	)
	(gr_poly
		(pts
			(arc
				(start 406.790652 -18.235422)
				(mid 406.424892 -18.235422)
				(end 406.790652 -18.235422)
			)
		)
		(stroke
			(width 0)
			(type solid)
		)
		(fill yes)
		(layer "F.Cu")
		(net "GND")
	)
	(gr_poly
		(pts
			(arc
				(start 406.790652 -16.967454)
				(mid 406.424892 -16.967454)
				(end 406.790652 -16.967454)
			)
		)
		(stroke
			(width 0)
			(type solid)
		)
		(fill yes)
		(layer "F.Cu")
		(net "GND")
	)
	(gr_poly
		(pts
			(arc
				(start 407.373074 -5.585714)
				(mid 407.007314 -5.585714)
				(end 407.373074 -5.585714)
			)
		)
		(stroke
			(width 0)
			(type solid)
		)
		(fill yes)
		(layer "F.Cu")
		(net "GND")
	)
	(gr_poly
		(pts
			(arc
				(start 407.373074 -4.317746)
				(mid 407.007314 -4.317746)
				(end 407.373074 -4.317746)
			)
		)
		(stroke
			(width 0)
			(type solid)
		)
		(fill yes)
		(layer "F.Cu")
		(net "GND")
	)
	(gr_poly
		(pts
			(arc
				(start 407.529284 -50.307494)
				(mid 407.163524 -50.307494)
				(end 407.529284 -50.307494)
			)
		)
		(stroke
			(width 0)
			(type solid)
		)
		(fill yes)
		(layer "F.Cu")
		(net "GND")
	)
	(gr_poly
		(pts
			(arc
				(start 407.542492 -48.245522)
				(mid 407.176732 -48.245522)
				(end 407.542492 -48.245522)
			)
		)
		(stroke
			(width 0)
			(type solid)
		)
		(fill yes)
		(layer "F.Cu")
		(net "GND")
	)
	(gr_poly
		(pts
			(arc
				(start 407.708862 -410.664152)
				(mid 407.343102 -410.664152)
				(end 407.708862 -410.664152)
			)
		)
		(stroke
			(width 0)
			(type solid)
		)
		(fill yes)
		(layer "F.Cu")
		(net "GND")
	)
	(gr_poly
		(pts
			(arc
				(start 407.708862 -409.396184)
				(mid 407.343102 -409.396184)
				(end 407.708862 -409.396184)
			)
		)
		(stroke
			(width 0)
			(type solid)
		)
		(fill yes)
		(layer "F.Cu")
		(net "GND")
	)
	(gr_poly
		(pts
			(arc
				(start 407.708862 -407.638504)
				(mid 407.343102 -407.638504)
				(end 407.708862 -407.638504)
			)
		)
		(stroke
			(width 0)
			(type solid)
		)
		(fill yes)
		(layer "F.Cu")
		(net "GND")
	)
	(gr_poly
		(pts
			(arc
				(start 407.708862 -406.370536)
				(mid 407.343102 -406.370536)
				(end 407.708862 -406.370536)
			)
		)
		(stroke
			(width 0)
			(type solid)
		)
		(fill yes)
		(layer "F.Cu")
		(net "GND")
	)
	(gr_poly
		(pts
			(arc
				(start 407.881074 -4.95173)
				(mid 407.515314 -4.95173)
				(end 407.881074 -4.95173)
			)
		)
		(stroke
			(width 0)
			(type solid)
		)
		(fill yes)
		(layer "F.Cu")
		(net "GND")
	)
	(gr_poly
		(pts
			(arc
				(start 408.049476 -18.235422)
				(mid 407.683716 -18.235422)
				(end 408.049476 -18.235422)
			)
		)
		(stroke
			(width 0)
			(type solid)
		)
		(fill yes)
		(layer "F.Cu")
		(net "GND")
	)
	(gr_poly
		(pts
			(arc
				(start 408.049476 -16.967454)
				(mid 407.683716 -16.967454)
				(end 408.049476 -16.967454)
			)
		)
		(stroke
			(width 0)
			(type solid)
		)
		(fill yes)
		(layer "F.Cu")
		(net "GND")
	)
	(gr_poly
		(pts
			(arc
				(start 408.167078 -404.51786)
				(mid 407.801318 -404.51786)
				(end 408.167078 -404.51786)
			)
		)
		(stroke
			(width 0)
			(type solid)
		)
		(fill yes)
		(layer "F.Cu")
		(net "GND")
	)
	(gr_poly
		(pts
			(arc
				(start 408.167078 -403.249892)
				(mid 407.801318 -403.249892)
				(end 408.167078 -403.249892)
			)
		)
		(stroke
			(width 0)
			(type solid)
		)
		(fill yes)
		(layer "F.Cu")
		(net "GND")
	)
	(gr_poly
		(pts
			(arc
				(start 408.167078 -401.492212)
				(mid 407.801318 -401.492212)
				(end 408.167078 -401.492212)
			)
		)
		(stroke
			(width 0)
			(type solid)
		)
		(fill yes)
		(layer "F.Cu")
		(net "GND")
	)
	(gr_poly
		(pts
			(arc
				(start 408.167078 -400.224244)
				(mid 407.801318 -400.224244)
				(end 408.167078 -400.224244)
			)
		)
		(stroke
			(width 0)
			(type solid)
		)
		(fill yes)
		(layer "F.Cu")
		(net "GND")
	)
	(gr_poly
		(pts
			(arc
				(start 408.557476 -17.601438)
				(mid 408.191716 -17.601438)
				(end 408.557476 -17.601438)
			)
		)
		(stroke
			(width 0)
			(type solid)
		)
		(fill yes)
		(layer "F.Cu")
		(net "GND")
	)
	(gr_poly
		(pts
			(arc
				(start 409.076652 -19.125438)
				(mid 408.710892 -19.125438)
				(end 409.076652 -19.125438)
			)
		)
		(stroke
			(width 0)
			(type solid)
		)
		(fill yes)
		(layer "F.Cu")
		(net "GND")
	)
	(gr_poly
		(pts
			(arc
				(start 409.425902 -404.51786)
				(mid 409.060142 -404.51786)
				(end 409.425902 -404.51786)
			)
		)
		(stroke
			(width 0)
			(type solid)
		)
		(fill yes)
		(layer "F.Cu")
		(net "GND")
	)
	(gr_poly
		(pts
			(arc
				(start 409.425902 -403.249892)
				(mid 409.060142 -403.249892)
				(end 409.425902 -403.249892)
			)
		)
		(stroke
			(width 0)
			(type solid)
		)
		(fill yes)
		(layer "F.Cu")
		(net "GND")
	)
	(gr_poly
		(pts
			(arc
				(start 409.425902 -401.492212)
				(mid 409.060142 -401.492212)
				(end 409.425902 -401.492212)
			)
		)
		(stroke
			(width 0)
			(type solid)
		)
		(fill yes)
		(layer "F.Cu")
		(net "GND")
	)
	(gr_poly
		(pts
			(arc
				(start 409.425902 -400.224244)
				(mid 409.060142 -400.224244)
				(end 409.425902 -400.224244)
			)
		)
		(stroke
			(width 0)
			(type solid)
		)
		(fill yes)
		(layer "F.Cu")
		(net "GND")
	)
	(gr_poly
		(pts
			(arc
				(start 409.513278 -410.664152)
				(mid 409.147518 -410.664152)
				(end 409.513278 -410.664152)
			)
		)
		(stroke
			(width 0)
			(type solid)
		)
		(fill yes)
		(layer "F.Cu")
		(net "GND")
	)
	(gr_poly
		(pts
			(arc
				(start 409.513278 -409.396184)
				(mid 409.147518 -409.396184)
				(end 409.513278 -409.396184)
			)
		)
		(stroke
			(width 0)
			(type solid)
		)
		(fill yes)
		(layer "F.Cu")
		(net "GND")
	)
	(gr_poly
		(pts
			(arc
				(start 409.513278 -407.638504)
				(mid 409.147518 -407.638504)
				(end 409.513278 -407.638504)
			)
		)
		(stroke
			(width 0)
			(type solid)
		)
		(fill yes)
		(layer "F.Cu")
		(net "GND")
	)
	(gr_poly
		(pts
			(arc
				(start 409.513278 -406.370536)
				(mid 409.147518 -406.370536)
				(end 409.513278 -406.370536)
			)
		)
		(stroke
			(width 0)
			(type solid)
		)
		(fill yes)
		(layer "F.Cu")
		(net "GND")
	)
	(gr_poly
		(pts
			(arc
				(start 409.584652 -19.759422)
				(mid 409.218892 -19.759422)
				(end 409.584652 -19.759422)
			)
		)
		(stroke
			(width 0)
			(type solid)
		)
		(fill yes)
		(layer "F.Cu")
		(net "GND")
	)
	(gr_poly
		(pts
			(arc
				(start 409.584652 -18.491454)
				(mid 409.218892 -18.491454)
				(end 409.584652 -18.491454)
			)
		)
		(stroke
			(width 0)
			(type solid)
		)
		(fill yes)
		(layer "F.Cu")
		(net "GND")
	)
	(gr_poly
		(pts
			(arc
				(start 410.772102 -410.664152)
				(mid 410.406342 -410.664152)
				(end 410.772102 -410.664152)
			)
		)
		(stroke
			(width 0)
			(type solid)
		)
		(fill yes)
		(layer "F.Cu")
		(net "GND")
	)
	(gr_poly
		(pts
			(arc
				(start 410.772102 -409.396184)
				(mid 410.406342 -409.396184)
				(end 410.772102 -409.396184)
			)
		)
		(stroke
			(width 0)
			(type solid)
		)
		(fill yes)
		(layer "F.Cu")
		(net "GND")
	)
	(gr_poly
		(pts
			(arc
				(start 410.772102 -407.638504)
				(mid 410.406342 -407.638504)
				(end 410.772102 -407.638504)
			)
		)
		(stroke
			(width 0)
			(type solid)
		)
		(fill yes)
		(layer "F.Cu")
		(net "GND")
	)
	(gr_poly
		(pts
			(arc
				(start 410.772102 -406.370536)
				(mid 410.406342 -406.370536)
				(end 410.772102 -406.370536)
			)
		)
		(stroke
			(width 0)
			(type solid)
		)
		(fill yes)
		(layer "F.Cu")
		(net "GND")
	)
	(gr_poly
		(pts
			(arc
				(start 410.843476 -19.759422)
				(mid 410.477716 -19.759422)
				(end 410.843476 -19.759422)
			)
		)
		(stroke
			(width 0)
			(type solid)
		)
		(fill yes)
		(layer "F.Cu")
		(net "GND")
	)
	(gr_poly
		(pts
			(arc
				(start 410.843476 -18.491454)
				(mid 410.477716 -18.491454)
				(end 410.843476 -18.491454)
			)
		)
		(stroke
			(width 0)
			(type solid)
		)
		(fill yes)
		(layer "F.Cu")
		(net "GND")
	)
	(gr_poly
		(pts
			(arc
				(start 411.230318 -404.51786)
				(mid 410.864558 -404.51786)
				(end 411.230318 -404.51786)
			)
		)
		(stroke
			(width 0)
			(type solid)
		)
		(fill yes)
		(layer "F.Cu")
		(net "GND")
	)
	(gr_poly
		(pts
			(arc
				(start 411.230318 -403.249892)
				(mid 410.864558 -403.249892)
				(end 411.230318 -403.249892)
			)
		)
		(stroke
			(width 0)
			(type solid)
		)
		(fill yes)
		(layer "F.Cu")
		(net "GND")
	)
	(gr_poly
		(pts
			(arc
				(start 411.230318 -401.492212)
				(mid 410.864558 -401.492212)
				(end 411.230318 -401.492212)
			)
		)
		(stroke
			(width 0)
			(type solid)
		)
		(fill yes)
		(layer "F.Cu")
		(net "GND")
	)
	(gr_poly
		(pts
			(arc
				(start 411.230318 -400.224244)
				(mid 410.864558 -400.224244)
				(end 411.230318 -400.224244)
			)
		)
		(stroke
			(width 0)
			(type solid)
		)
		(fill yes)
		(layer "F.Cu")
		(net "GND")
	)
	(gr_poly
		(pts
			(arc
				(start 411.351476 -19.125438)
				(mid 410.985716 -19.125438)
				(end 411.351476 -19.125438)
			)
		)
		(stroke
			(width 0)
			(type solid)
		)
		(fill yes)
		(layer "F.Cu")
		(net "GND")
	)
	(gr_poly
		(pts
			(arc
				(start 411.870652 -17.601438)
				(mid 411.504892 -17.601438)
				(end 411.870652 -17.601438)
			)
		)
		(stroke
			(width 0)
			(type solid)
		)
		(fill yes)
		(layer "F.Cu")
		(net "GND")
	)
	(gr_poly
		(pts
			(arc
				(start 412.378652 -18.235422)
				(mid 412.012892 -18.235422)
				(end 412.378652 -18.235422)
			)
		)
		(stroke
			(width 0)
			(type solid)
		)
		(fill yes)
		(layer "F.Cu")
		(net "GND")
	)
	(gr_poly
		(pts
			(arc
				(start 412.378652 -16.967454)
				(mid 412.012892 -16.967454)
				(end 412.378652 -16.967454)
			)
		)
		(stroke
			(width 0)
			(type solid)
		)
		(fill yes)
		(layer "F.Cu")
		(net "GND")
	)
	(gr_poly
		(pts
			(arc
				(start 412.489142 -404.51786)
				(mid 412.123382 -404.51786)
				(end 412.489142 -404.51786)
			)
		)
		(stroke
			(width 0)
			(type solid)
		)
		(fill yes)
		(layer "F.Cu")
		(net "GND")
	)
	(gr_poly
		(pts
			(arc
				(start 412.489142 -403.249892)
				(mid 412.123382 -403.249892)
				(end 412.489142 -403.249892)
			)
		)
		(stroke
			(width 0)
			(type solid)
		)
		(fill yes)
		(layer "F.Cu")
		(net "GND")
	)
	(gr_poly
		(pts
			(arc
				(start 412.489142 -401.492212)
				(mid 412.123382 -401.492212)
				(end 412.489142 -401.492212)
			)
		)
		(stroke
			(width 0)
			(type solid)
		)
		(fill yes)
		(layer "F.Cu")
		(net "GND")
	)
	(gr_poly
		(pts
			(arc
				(start 412.489142 -400.224244)
				(mid 412.123382 -400.224244)
				(end 412.489142 -400.224244)
			)
		)
		(stroke
			(width 0)
			(type solid)
		)
		(fill yes)
		(layer "F.Cu")
		(net "GND")
	)
	(gr_poly
		(pts
			(arc
				(start 412.576518 -410.664152)
				(mid 412.210758 -410.664152)
				(end 412.576518 -410.664152)
			)
		)
		(stroke
			(width 0)
			(type solid)
		)
		(fill yes)
		(layer "F.Cu")
		(net "GND")
	)
	(gr_poly
		(pts
			(arc
				(start 412.576518 -409.396184)
				(mid 412.210758 -409.396184)
				(end 412.576518 -409.396184)
			)
		)
		(stroke
			(width 0)
			(type solid)
		)
		(fill yes)
		(layer "F.Cu")
		(net "GND")
	)
	(gr_poly
		(pts
			(arc
				(start 412.576518 -407.638504)
				(mid 412.210758 -407.638504)
				(end 412.576518 -407.638504)
			)
		)
		(stroke
			(width 0)
			(type solid)
		)
		(fill yes)
		(layer "F.Cu")
		(net "GND")
	)
	(gr_poly
		(pts
			(arc
				(start 412.576518 -406.370536)
				(mid 412.210758 -406.370536)
				(end 412.576518 -406.370536)
			)
		)
		(stroke
			(width 0)
			(type solid)
		)
		(fill yes)
		(layer "F.Cu")
		(net "GND")
	)
	(gr_poly
		(pts
			(arc
				(start 412.911544 -6.586474)
				(mid 412.545784 -6.586474)
				(end 412.911544 -6.586474)
			)
		)
		(stroke
			(width 0)
			(type solid)
		)
		(fill yes)
		(layer "F.Cu")
		(net "GND")
	)
	(gr_poly
		(pts
			(arc
				(start 413.419544 -6.07949)
				(mid 413.053784 -6.07949)
				(end 413.419544 -6.07949)
			)
		)
		(stroke
			(width 0)
			(type solid)
		)
		(fill yes)
		(layer "F.Cu")
		(net "GND")
	)
	(gr_poly
		(pts
			(arc
				(start 413.637476 -18.235422)
				(mid 413.271716 -18.235422)
				(end 413.637476 -18.235422)
			)
		)
		(stroke
			(width 0)
			(type solid)
		)
		(fill yes)
		(layer "F.Cu")
		(net "GND")
	)
	(gr_poly
		(pts
			(arc
				(start 413.637476 -16.967454)
				(mid 413.271716 -16.967454)
				(end 413.637476 -16.967454)
			)
		)
		(stroke
			(width 0)
			(type solid)
		)
		(fill yes)
		(layer "F.Cu")
		(net "GND")
	)
	(gr_poly
		(pts
			(arc
				(start 413.835342 -410.664152)
				(mid 413.469582 -410.664152)
				(end 413.835342 -410.664152)
			)
		)
		(stroke
			(width 0)
			(type solid)
		)
		(fill yes)
		(layer "F.Cu")
		(net "GND")
	)
	(gr_poly
		(pts
			(arc
				(start 413.835342 -409.396184)
				(mid 413.469582 -409.396184)
				(end 413.835342 -409.396184)
			)
		)
		(stroke
			(width 0)
			(type solid)
		)
		(fill yes)
		(layer "F.Cu")
		(net "GND")
	)
	(gr_poly
		(pts
			(arc
				(start 413.835342 -407.638504)
				(mid 413.469582 -407.638504)
				(end 413.835342 -407.638504)
			)
		)
		(stroke
			(width 0)
			(type solid)
		)
		(fill yes)
		(layer "F.Cu")
		(net "GND")
	)
	(gr_poly
		(pts
			(arc
				(start 413.835342 -406.370536)
				(mid 413.469582 -406.370536)
				(end 413.835342 -406.370536)
			)
		)
		(stroke
			(width 0)
			(type solid)
		)
		(fill yes)
		(layer "F.Cu")
		(net "GND")
	)
	(gr_poly
		(pts
			(arc
				(start 414.145476 -17.601438)
				(mid 413.779716 -17.601438)
				(end 414.145476 -17.601438)
			)
		)
		(stroke
			(width 0)
			(type solid)
		)
		(fill yes)
		(layer "F.Cu")
		(net "GND")
	)
	(gr_poly
		(pts
			(arc
				(start 414.293558 -404.51786)
				(mid 413.927798 -404.51786)
				(end 414.293558 -404.51786)
			)
		)
		(stroke
			(width 0)
			(type solid)
		)
		(fill yes)
		(layer "F.Cu")
		(net "GND")
	)
	(gr_poly
		(pts
			(arc
				(start 414.293558 -403.249892)
				(mid 413.927798 -403.249892)
				(end 414.293558 -403.249892)
			)
		)
		(stroke
			(width 0)
			(type solid)
		)
		(fill yes)
		(layer "F.Cu")
		(net "GND")
	)
	(gr_poly
		(pts
			(arc
				(start 414.293558 -401.492212)
				(mid 413.927798 -401.492212)
				(end 414.293558 -401.492212)
			)
		)
		(stroke
			(width 0)
			(type solid)
		)
		(fill yes)
		(layer "F.Cu")
		(net "GND")
	)
	(gr_poly
		(pts
			(arc
				(start 414.293558 -400.200368)
				(mid 413.927798 -400.200368)
				(end 414.293558 -400.200368)
			)
		)
		(stroke
			(width 0)
			(type solid)
		)
		(fill yes)
		(layer "F.Cu")
		(net "GND")
	)
	(gr_poly
		(pts
			(arc
				(start 414.678368 -6.07949)
				(mid 414.312608 -6.07949)
				(end 414.678368 -6.07949)
			)
		)
		(stroke
			(width 0)
			(type solid)
		)
		(fill yes)
		(layer "F.Cu")
		(net "GND")
	)
	(gr_poly
		(pts
			(arc
				(start 414.716214 -4.95173)
				(mid 414.350454 -4.95173)
				(end 414.716214 -4.95173)
			)
		)
		(stroke
			(width 0)
			(type solid)
		)
		(fill yes)
		(layer "F.Cu")
		(net "GND")
	)
	(gr_poly
		(pts
			(arc
				(start 414.970468 -19.125438)
				(mid 414.604708 -19.125438)
				(end 414.970468 -19.125438)
			)
		)
		(stroke
			(width 0)
			(type solid)
		)
		(fill yes)
		(layer "F.Cu")
		(net "GND")
	)
	(gr_poly
		(pts
			(arc
				(start 415.186368 -6.586474)
				(mid 414.820608 -6.586474)
				(end 415.186368 -6.586474)
			)
		)
		(stroke
			(width 0)
			(type solid)
		)
		(fill yes)
		(layer "F.Cu")
		(net "GND")
	)
	(gr_poly
		(pts
			(arc
				(start 415.224214 -5.585714)
				(mid 414.858454 -5.585714)
				(end 415.224214 -5.585714)
			)
		)
		(stroke
			(width 0)
			(type solid)
		)
		(fill yes)
		(layer "F.Cu")
		(net "GND")
	)
	(gr_poly
		(pts
			(arc
				(start 415.224214 -4.317746)
				(mid 414.858454 -4.317746)
				(end 415.224214 -4.317746)
			)
		)
		(stroke
			(width 0)
			(type solid)
		)
		(fill yes)
		(layer "F.Cu")
		(net "GND")
	)
	(gr_poly
		(pts
			(arc
				(start 415.478468 -19.759422)
				(mid 415.112708 -19.759422)
				(end 415.478468 -19.759422)
			)
		)
		(stroke
			(width 0)
			(type solid)
		)
		(fill yes)
		(layer "F.Cu")
		(net "GND")
	)
	(gr_poly
		(pts
			(arc
				(start 415.478468 -18.491454)
				(mid 415.112708 -18.491454)
				(end 415.478468 -18.491454)
			)
		)
		(stroke
			(width 0)
			(type solid)
		)
		(fill yes)
		(layer "F.Cu")
		(net "GND")
	)
	(gr_poly
		(pts
			(arc
				(start 415.552382 -404.51786)
				(mid 415.186622 -404.51786)
				(end 415.552382 -404.51786)
			)
		)
		(stroke
			(width 0)
			(type solid)
		)
		(fill yes)
		(layer "F.Cu")
		(net "GND")
	)
	(gr_poly
		(pts
			(arc
				(start 415.552382 -403.249892)
				(mid 415.186622 -403.249892)
				(end 415.552382 -403.249892)
			)
		)
		(stroke
			(width 0)
			(type solid)
		)
		(fill yes)
		(layer "F.Cu")
		(net "GND")
	)
	(gr_poly
		(pts
			(arc
				(start 415.552382 -401.492212)
				(mid 415.186622 -401.492212)
				(end 415.552382 -401.492212)
			)
		)
		(stroke
			(width 0)
			(type solid)
		)
		(fill yes)
		(layer "F.Cu")
		(net "GND")
	)
	(gr_poly
		(pts
			(arc
				(start 415.552382 -400.200368)
				(mid 415.186622 -400.200368)
				(end 415.552382 -400.200368)
			)
		)
		(stroke
			(width 0)
			(type solid)
		)
		(fill yes)
		(layer "F.Cu")
		(net "GND")
	)
	(gr_poly
		(pts
			(arc
				(start 415.639758 -410.664152)
				(mid 415.273998 -410.664152)
				(end 415.639758 -410.664152)
			)
		)
		(stroke
			(width 0)
			(type solid)
		)
		(fill yes)
		(layer "F.Cu")
		(net "GND")
	)
	(gr_poly
		(pts
			(arc
				(start 415.639758 -409.396184)
				(mid 415.273998 -409.396184)
				(end 415.639758 -409.396184)
			)
		)
		(stroke
			(width 0)
			(type solid)
		)
		(fill yes)
		(layer "F.Cu")
		(net "GND")
	)
	(gr_poly
		(pts
			(arc
				(start 415.639758 -407.638504)
				(mid 415.273998 -407.638504)
				(end 415.639758 -407.638504)
			)
		)
		(stroke
			(width 0)
			(type solid)
		)
		(fill yes)
		(layer "F.Cu")
		(net "GND")
	)
	(gr_poly
		(pts
			(arc
				(start 415.639758 -406.34666)
				(mid 415.273998 -406.34666)
				(end 415.639758 -406.34666)
			)
		)
		(stroke
			(width 0)
			(type solid)
		)
		(fill yes)
		(layer "F.Cu")
		(net "GND")
	)
	(gr_poly
		(pts
			(arc
				(start 416.483038 -5.585714)
				(mid 416.117278 -5.585714)
				(end 416.483038 -5.585714)
			)
		)
		(stroke
			(width 0)
			(type solid)
		)
		(fill yes)
		(layer "F.Cu")
		(net "GND")
	)
	(gr_poly
		(pts
			(arc
				(start 416.483038 -4.317746)
				(mid 416.117278 -4.317746)
				(end 416.483038 -4.317746)
			)
		)
		(stroke
			(width 0)
			(type solid)
		)
		(fill yes)
		(layer "F.Cu")
		(net "GND")
	)
	(gr_poly
		(pts
			(arc
				(start 416.511486 -6.586474)
				(mid 416.145726 -6.586474)
				(end 416.511486 -6.586474)
			)
		)
		(stroke
			(width 0)
			(type solid)
		)
		(fill yes)
		(layer "F.Cu")
		(net "GND")
	)
	(gr_poly
		(pts
			(arc
				(start 416.737292 -19.759422)
				(mid 416.371532 -19.759422)
				(end 416.737292 -19.759422)
			)
		)
		(stroke
			(width 0)
			(type solid)
		)
		(fill yes)
		(layer "F.Cu")
		(net "GND")
	)
	(gr_poly
		(pts
			(arc
				(start 416.737292 -18.491454)
				(mid 416.371532 -18.491454)
				(end 416.737292 -18.491454)
			)
		)
		(stroke
			(width 0)
			(type solid)
		)
		(fill yes)
		(layer "F.Cu")
		(net "GND")
	)
	(gr_poly
		(pts
			(arc
				(start 416.898582 -410.664152)
				(mid 416.532822 -410.664152)
				(end 416.898582 -410.664152)
			)
		)
		(stroke
			(width 0)
			(type solid)
		)
		(fill yes)
		(layer "F.Cu")
		(net "GND")
	)
	(gr_poly
		(pts
			(arc
				(start 416.898582 -409.396184)
				(mid 416.532822 -409.396184)
				(end 416.898582 -409.396184)
			)
		)
		(stroke
			(width 0)
			(type solid)
		)
		(fill yes)
		(layer "F.Cu")
		(net "GND")
	)
	(gr_poly
		(pts
			(arc
				(start 416.898582 -407.638504)
				(mid 416.532822 -407.638504)
				(end 416.898582 -407.638504)
			)
		)
		(stroke
			(width 0)
			(type solid)
		)
		(fill yes)
		(layer "F.Cu")
		(net "GND")
	)
	(gr_poly
		(pts
			(arc
				(start 416.898582 -406.34666)
				(mid 416.532822 -406.34666)
				(end 416.898582 -406.34666)
			)
		)
		(stroke
			(width 0)
			(type solid)
		)
		(fill yes)
		(layer "F.Cu")
		(net "GND")
	)
	(gr_poly
		(pts
			(arc
				(start 416.991038 -4.95173)
				(mid 416.625278 -4.95173)
				(end 416.991038 -4.95173)
			)
		)
		(stroke
			(width 0)
			(type solid)
		)
		(fill yes)
		(layer "F.Cu")
		(net "GND")
	)
	(gr_poly
		(pts
			(arc
				(start 417.019486 -6.07949)
				(mid 416.653726 -6.07949)
				(end 417.019486 -6.07949)
			)
		)
		(stroke
			(width 0)
			(type solid)
		)
		(fill yes)
		(layer "F.Cu")
		(net "GND")
	)
	(gr_poly
		(pts
			(arc
				(start 417.245292 -19.125438)
				(mid 416.879532 -19.125438)
				(end 417.245292 -19.125438)
			)
		)
		(stroke
			(width 0)
			(type solid)
		)
		(fill yes)
		(layer "F.Cu")
		(net "GND")
	)
	(gr_poly
		(pts
			(arc
				(start 417.356798 -404.51786)
				(mid 416.991038 -404.51786)
				(end 417.356798 -404.51786)
			)
		)
		(stroke
			(width 0)
			(type solid)
		)
		(fill yes)
		(layer "F.Cu")
		(net "GND")
	)
	(gr_poly
		(pts
			(arc
				(start 417.356798 -403.249892)
				(mid 416.991038 -403.249892)
				(end 417.356798 -403.249892)
			)
		)
		(stroke
			(width 0)
			(type solid)
		)
		(fill yes)
		(layer "F.Cu")
		(net "GND")
	)
	(gr_poly
		(pts
			(arc
				(start 417.356798 -401.492212)
				(mid 416.991038 -401.492212)
				(end 417.356798 -401.492212)
			)
		)
		(stroke
			(width 0)
			(type solid)
		)
		(fill yes)
		(layer "F.Cu")
		(net "GND")
	)
	(gr_poly
		(pts
			(arc
				(start 417.356798 -400.224244)
				(mid 416.991038 -400.224244)
				(end 417.356798 -400.224244)
			)
		)
		(stroke
			(width 0)
			(type solid)
		)
		(fill yes)
		(layer "F.Cu")
		(net "GND")
	)
	(gr_poly
		(pts
			(arc
				(start 417.764468 -17.601438)
				(mid 417.398708 -17.601438)
				(end 417.764468 -17.601438)
			)
		)
		(stroke
			(width 0)
			(type solid)
		)
		(fill yes)
		(layer "F.Cu")
		(net "GND")
	)
	(gr_poly
		(pts
			(arc
				(start 418.272468 -18.235422)
				(mid 417.906708 -18.235422)
				(end 418.272468 -18.235422)
			)
		)
		(stroke
			(width 0)
			(type solid)
		)
		(fill yes)
		(layer "F.Cu")
		(net "GND")
	)
	(gr_poly
		(pts
			(arc
				(start 418.272468 -16.967454)
				(mid 417.906708 -16.967454)
				(end 418.272468 -16.967454)
			)
		)
		(stroke
			(width 0)
			(type solid)
		)
		(fill yes)
		(layer "F.Cu")
		(net "GND")
	)
	(gr_poly
		(pts
			(arc
				(start 418.27831 -6.07949)
				(mid 417.91255 -6.07949)
				(end 418.27831 -6.07949)
			)
		)
		(stroke
			(width 0)
			(type solid)
		)
		(fill yes)
		(layer "F.Cu")
		(net "GND")
	)
	(gr_poly
		(pts
			(arc
				(start 418.316156 -4.95173)
				(mid 417.950396 -4.95173)
				(end 418.316156 -4.95173)
			)
		)
		(stroke
			(width 0)
			(type solid)
		)
		(fill yes)
		(layer "F.Cu")
		(net "GND")
	)
	(gr_poly
		(pts
			(arc
				(start 418.615622 -404.51786)
				(mid 418.249862 -404.51786)
				(end 418.615622 -404.51786)
			)
		)
		(stroke
			(width 0)
			(type solid)
		)
		(fill yes)
		(layer "F.Cu")
		(net "GND")
	)
	(gr_poly
		(pts
			(arc
				(start 418.615622 -403.249892)
				(mid 418.249862 -403.249892)
				(end 418.615622 -403.249892)
			)
		)
		(stroke
			(width 0)
			(type solid)
		)
		(fill yes)
		(layer "F.Cu")
		(net "GND")
	)
	(gr_poly
		(pts
			(arc
				(start 418.615622 -401.492212)
				(mid 418.249862 -401.492212)
				(end 418.615622 -401.492212)
			)
		)
		(stroke
			(width 0)
			(type solid)
		)
		(fill yes)
		(layer "F.Cu")
		(net "GND")
	)
	(gr_poly
		(pts
			(arc
				(start 418.615622 -400.224244)
				(mid 418.249862 -400.224244)
				(end 418.615622 -400.224244)
			)
		)
		(stroke
			(width 0)
			(type solid)
		)
		(fill yes)
		(layer "F.Cu")
		(net "GND")
	)
	(gr_poly
		(pts
			(arc
				(start 418.702998 -410.664152)
				(mid 418.337238 -410.664152)
				(end 418.702998 -410.664152)
			)
		)
		(stroke
			(width 0)
			(type solid)
		)
		(fill yes)
		(layer "F.Cu")
		(net "GND")
	)
	(gr_poly
		(pts
			(arc
				(start 418.702998 -409.396184)
				(mid 418.337238 -409.396184)
				(end 418.702998 -409.396184)
			)
		)
		(stroke
			(width 0)
			(type solid)
		)
		(fill yes)
		(layer "F.Cu")
		(net "GND")
	)
	(gr_poly
		(pts
			(arc
				(start 418.702998 -407.638504)
				(mid 418.337238 -407.638504)
				(end 418.702998 -407.638504)
			)
		)
		(stroke
			(width 0)
			(type solid)
		)
		(fill yes)
		(layer "F.Cu")
		(net "GND")
	)
	(gr_poly
		(pts
			(arc
				(start 418.702998 -406.370536)
				(mid 418.337238 -406.370536)
				(end 418.702998 -406.370536)
			)
		)
		(stroke
			(width 0)
			(type solid)
		)
		(fill yes)
		(layer "F.Cu")
		(net "GND")
	)
	(gr_poly
		(pts
			(arc
				(start 418.78631 -6.586474)
				(mid 418.42055 -6.586474)
				(end 418.78631 -6.586474)
			)
		)
		(stroke
			(width 0)
			(type solid)
		)
		(fill yes)
		(layer "F.Cu")
		(net "GND")
	)
	(gr_poly
		(pts
			(arc
				(start 418.824156 -5.585714)
				(mid 418.458396 -5.585714)
				(end 418.824156 -5.585714)
			)
		)
		(stroke
			(width 0)
			(type solid)
		)
		(fill yes)
		(layer "F.Cu")
		(net "GND")
	)
	(gr_poly
		(pts
			(arc
				(start 418.824156 -4.317746)
				(mid 418.458396 -4.317746)
				(end 418.824156 -4.317746)
			)
		)
		(stroke
			(width 0)
			(type solid)
		)
		(fill yes)
		(layer "F.Cu")
		(net "GND")
	)
	(gr_poly
		(pts
			(arc
				(start 419.531292 -18.235422)
				(mid 419.165532 -18.235422)
				(end 419.531292 -18.235422)
			)
		)
		(stroke
			(width 0)
			(type solid)
		)
		(fill yes)
		(layer "F.Cu")
		(net "GND")
	)
	(gr_poly
		(pts
			(arc
				(start 419.531292 -16.967454)
				(mid 419.165532 -16.967454)
				(end 419.531292 -16.967454)
			)
		)
		(stroke
			(width 0)
			(type solid)
		)
		(fill yes)
		(layer "F.Cu")
		(net "GND")
	)
	(gr_poly
		(pts
			(arc
				(start 419.961822 -410.664152)
				(mid 419.596062 -410.664152)
				(end 419.961822 -410.664152)
			)
		)
		(stroke
			(width 0)
			(type solid)
		)
		(fill yes)
		(layer "F.Cu")
		(net "GND")
	)
	(gr_poly
		(pts
			(arc
				(start 419.961822 -409.396184)
				(mid 419.596062 -409.396184)
				(end 419.961822 -409.396184)
			)
		)
		(stroke
			(width 0)
			(type solid)
		)
		(fill yes)
		(layer "F.Cu")
		(net "GND")
	)
	(gr_poly
		(pts
			(arc
				(start 419.961822 -407.638504)
				(mid 419.596062 -407.638504)
				(end 419.961822 -407.638504)
			)
		)
		(stroke
			(width 0)
			(type solid)
		)
		(fill yes)
		(layer "F.Cu")
		(net "GND")
	)
	(gr_poly
		(pts
			(arc
				(start 419.961822 -406.370536)
				(mid 419.596062 -406.370536)
				(end 419.961822 -406.370536)
			)
		)
		(stroke
			(width 0)
			(type solid)
		)
		(fill yes)
		(layer "F.Cu")
		(net "GND")
	)
	(gr_poly
		(pts
			(arc
				(start 420.039292 -17.601438)
				(mid 419.673532 -17.601438)
				(end 420.039292 -17.601438)
			)
		)
		(stroke
			(width 0)
			(type solid)
		)
		(fill yes)
		(layer "F.Cu")
		(net "GND")
	)
	(gr_poly
		(pts
			(arc
				(start 420.08298 -5.585714)
				(mid 419.71722 -5.585714)
				(end 420.08298 -5.585714)
			)
		)
		(stroke
			(width 0)
			(type solid)
		)
		(fill yes)
		(layer "F.Cu")
		(net "GND")
	)
	(gr_poly
		(pts
			(arc
				(start 420.08298 -4.317746)
				(mid 419.71722 -4.317746)
				(end 420.08298 -4.317746)
			)
		)
		(stroke
			(width 0)
			(type solid)
		)
		(fill yes)
		(layer "F.Cu")
		(net "GND")
	)
	(gr_poly
		(pts
			(arc
				(start 420.558468 -19.125438)
				(mid 420.192708 -19.125438)
				(end 420.558468 -19.125438)
			)
		)
		(stroke
			(width 0)
			(type solid)
		)
		(fill yes)
		(layer "F.Cu")
		(net "GND")
	)
	(gr_poly
		(pts
			(arc
				(start 420.59098 -4.95173)
				(mid 420.22522 -4.95173)
				(end 420.59098 -4.95173)
			)
		)
		(stroke
			(width 0)
			(type solid)
		)
		(fill yes)
		(layer "F.Cu")
		(net "GND")
	)
	(gr_poly
		(pts
			(arc
				(start 421.066468 -19.759422)
				(mid 420.700708 -19.759422)
				(end 421.066468 -19.759422)
			)
		)
		(stroke
			(width 0)
			(type solid)
		)
		(fill yes)
		(layer "F.Cu")
		(net "GND")
	)
	(gr_poly
		(pts
			(arc
				(start 421.066468 -18.491454)
				(mid 420.700708 -18.491454)
				(end 421.066468 -18.491454)
			)
		)
		(stroke
			(width 0)
			(type solid)
		)
		(fill yes)
		(layer "F.Cu")
		(net "GND")
	)
	(gr_poly
		(pts
			(arc
				(start 421.867584 -58.6994)
				(mid 421.501824 -58.6994)
				(end 421.867584 -58.6994)
			)
		)
		(stroke
			(width 0)
			(type solid)
		)
		(fill yes)
		(layer "F.Cu")
		(net "GND")
	)
	(gr_poly
		(pts
			(arc
				(start 422.325292 -19.759422)
				(mid 421.959532 -19.759422)
				(end 422.325292 -19.759422)
			)
		)
		(stroke
			(width 0)
			(type solid)
		)
		(fill yes)
		(layer "F.Cu")
		(net "GND")
	)
	(gr_poly
		(pts
			(arc
				(start 422.325292 -18.491454)
				(mid 421.959532 -18.491454)
				(end 422.325292 -18.491454)
			)
		)
		(stroke
			(width 0)
			(type solid)
		)
		(fill yes)
		(layer "F.Cu")
		(net "GND")
	)
	(gr_poly
		(pts
			(arc
				(start 422.833292 -19.125438)
				(mid 422.467532 -19.125438)
				(end 422.833292 -19.125438)
			)
		)
		(stroke
			(width 0)
			(type solid)
		)
		(fill yes)
		(layer "F.Cu")
		(net "GND")
	)
	(gr_poly
		(pts
			(arc
				(start 423.352468 -17.601438)
				(mid 422.986708 -17.601438)
				(end 423.352468 -17.601438)
			)
		)
		(stroke
			(width 0)
			(type solid)
		)
		(fill yes)
		(layer "F.Cu")
		(net "GND")
	)
	(gr_poly
		(pts
			(arc
				(start 423.365676 -58.34634)
				(mid 422.999916 -58.34634)
				(end 423.365676 -58.34634)
			)
		)
		(stroke
			(width 0)
			(type solid)
		)
		(fill yes)
		(layer "F.Cu")
		(net "GND")
	)
	(gr_poly
		(pts
			(arc
				(start 423.860468 -18.235422)
				(mid 423.494708 -18.235422)
				(end 423.860468 -18.235422)
			)
		)
		(stroke
			(width 0)
			(type solid)
		)
		(fill yes)
		(layer "F.Cu")
		(net "GND")
	)
	(gr_poly
		(pts
			(arc
				(start 423.860468 -16.967454)
				(mid 423.494708 -16.967454)
				(end 423.860468 -16.967454)
			)
		)
		(stroke
			(width 0)
			(type solid)
		)
		(fill yes)
		(layer "F.Cu")
		(net "GND")
	)
	(gr_poly
		(pts
			(arc
				(start 424.12158 -6.586474)
				(mid 423.75582 -6.586474)
				(end 424.12158 -6.586474)
			)
		)
		(stroke
			(width 0)
			(type solid)
		)
		(fill yes)
		(layer "F.Cu")
		(net "GND")
	)
	(gr_poly
		(pts
			(arc
				(start 424.46448 -58.283348)
				(mid 424.09872 -58.283348)
				(end 424.46448 -58.283348)
			)
		)
		(stroke
			(width 0)
			(type solid)
		)
		(fill yes)
		(layer "F.Cu")
		(net "GND")
	)
	(gr_poly
		(pts
			(arc
				(start 424.62958 -6.07949)
				(mid 424.26382 -6.07949)
				(end 424.62958 -6.07949)
			)
		)
		(stroke
			(width 0)
			(type solid)
		)
		(fill yes)
		(layer "F.Cu")
		(net "GND")
	)
	(gr_poly
		(pts
			(arc
				(start 425.119292 -18.235422)
				(mid 424.753532 -18.235422)
				(end 425.119292 -18.235422)
			)
		)
		(stroke
			(width 0)
			(type solid)
		)
		(fill yes)
		(layer "F.Cu")
		(net "GND")
	)
	(gr_poly
		(pts
			(arc
				(start 425.119292 -16.967454)
				(mid 424.753532 -16.967454)
				(end 425.119292 -16.967454)
			)
		)
		(stroke
			(width 0)
			(type solid)
		)
		(fill yes)
		(layer "F.Cu")
		(net "GND")
	)
	(gr_poly
		(pts
			(arc
				(start 425.627292 -17.601438)
				(mid 425.261532 -17.601438)
				(end 425.627292 -17.601438)
			)
		)
		(stroke
			(width 0)
			(type solid)
		)
		(fill yes)
		(layer "F.Cu")
		(net "GND")
	)
	(gr_poly
		(pts
			(arc
				(start 425.888404 -6.07949)
				(mid 425.522644 -6.07949)
				(end 425.888404 -6.07949)
			)
		)
		(stroke
			(width 0)
			(type solid)
		)
		(fill yes)
		(layer "F.Cu")
		(net "GND")
	)
	(gr_poly
		(pts
			(arc
				(start 425.92625 -4.95173)
				(mid 425.56049 -4.95173)
				(end 425.92625 -4.95173)
			)
		)
		(stroke
			(width 0)
			(type solid)
		)
		(fill yes)
		(layer "F.Cu")
		(net "GND")
	)
	(gr_poly
		(pts
			(arc
				(start 425.96308 -55.819548)
				(mid 425.59732 -55.819548)
				(end 425.96308 -55.819548)
			)
		)
		(stroke
			(width 0)
			(type solid)
		)
		(fill yes)
		(layer "F.Cu")
		(net "GND")
	)
	(gr_poly
		(pts
			(arc
				(start 426.180504 -19.125438)
				(mid 425.814744 -19.125438)
				(end 426.180504 -19.125438)
			)
		)
		(stroke
			(width 0)
			(type solid)
		)
		(fill yes)
		(layer "F.Cu")
		(net "GND")
	)
	(gr_poly
		(pts
			(arc
				(start 426.396404 -6.586474)
				(mid 426.030644 -6.586474)
				(end 426.396404 -6.586474)
			)
		)
		(stroke
			(width 0)
			(type solid)
		)
		(fill yes)
		(layer "F.Cu")
		(net "GND")
	)
	(gr_poly
		(pts
			(arc
				(start 426.43425 -5.585714)
				(mid 426.06849 -5.585714)
				(end 426.43425 -5.585714)
			)
		)
		(stroke
			(width 0)
			(type solid)
		)
		(fill yes)
		(layer "F.Cu")
		(net "GND")
	)
	(gr_poly
		(pts
			(arc
				(start 426.43425 -4.317746)
				(mid 426.06849 -4.317746)
				(end 426.43425 -4.317746)
			)
		)
		(stroke
			(width 0)
			(type solid)
		)
		(fill yes)
		(layer "F.Cu")
		(net "GND")
	)
	(gr_poly
		(pts
			(arc
				(start 426.688504 -19.759422)
				(mid 426.322744 -19.759422)
				(end 426.688504 -19.759422)
			)
		)
		(stroke
			(width 0)
			(type solid)
		)
		(fill yes)
		(layer "F.Cu")
		(net "GND")
	)
	(gr_poly
		(pts
			(arc
				(start 426.688504 -18.491454)
				(mid 426.322744 -18.491454)
				(end 426.688504 -18.491454)
			)
		)
		(stroke
			(width 0)
			(type solid)
		)
		(fill yes)
		(layer "F.Cu")
		(net "GND")
	)
	(gr_poly
		(pts
			(arc
				(start 427.38548 -57.902348)
				(mid 427.01972 -57.902348)
				(end 427.38548 -57.902348)
			)
		)
		(stroke
			(width 0)
			(type solid)
		)
		(fill yes)
		(layer "F.Cu")
		(net "GND")
	)
	(gr_poly
		(pts
			(arc
				(start 427.693074 -5.585714)
				(mid 427.327314 -5.585714)
				(end 427.693074 -5.585714)
			)
		)
		(stroke
			(width 0)
			(type solid)
		)
		(fill yes)
		(layer "F.Cu")
		(net "GND")
	)
	(gr_poly
		(pts
			(arc
				(start 427.693074 -4.317746)
				(mid 427.327314 -4.317746)
				(end 427.693074 -4.317746)
			)
		)
		(stroke
			(width 0)
			(type solid)
		)
		(fill yes)
		(layer "F.Cu")
		(net "GND")
	)
	(gr_poly
		(pts
			(arc
				(start 427.721522 -6.586474)
				(mid 427.355762 -6.586474)
				(end 427.721522 -6.586474)
			)
		)
		(stroke
			(width 0)
			(type solid)
		)
		(fill yes)
		(layer "F.Cu")
		(net "GND")
	)
	(gr_poly
		(pts
			(arc
				(start 427.947328 -19.759422)
				(mid 427.581568 -19.759422)
				(end 427.947328 -19.759422)
			)
		)
		(stroke
			(width 0)
			(type solid)
		)
		(fill yes)
		(layer "F.Cu")
		(net "GND")
	)
	(gr_poly
		(pts
			(arc
				(start 427.947328 -18.491454)
				(mid 427.581568 -18.491454)
				(end 427.947328 -18.491454)
			)
		)
		(stroke
			(width 0)
			(type solid)
		)
		(fill yes)
		(layer "F.Cu")
		(net "GND")
	)
	(gr_poly
		(pts
			(arc
				(start 428.201074 -4.95173)
				(mid 427.835314 -4.95173)
				(end 428.201074 -4.95173)
			)
		)
		(stroke
			(width 0)
			(type solid)
		)
		(fill yes)
		(layer "F.Cu")
		(net "GND")
	)
	(gr_poly
		(pts
			(arc
				(start 428.229522 -6.07949)
				(mid 427.863762 -6.07949)
				(end 428.229522 -6.07949)
			)
		)
		(stroke
			(width 0)
			(type solid)
		)
		(fill yes)
		(layer "F.Cu")
		(net "GND")
	)
	(gr_poly
		(pts
			(arc
				(start 428.455328 -19.125438)
				(mid 428.089568 -19.125438)
				(end 428.455328 -19.125438)
			)
		)
		(stroke
			(width 0)
			(type solid)
		)
		(fill yes)
		(layer "F.Cu")
		(net "GND")
	)
	(gr_poly
		(pts
			(arc
				(start 428.974504 -17.601438)
				(mid 428.608744 -17.601438)
				(end 428.974504 -17.601438)
			)
		)
		(stroke
			(width 0)
			(type solid)
		)
		(fill yes)
		(layer "F.Cu")
		(net "GND")
	)
	(gr_poly
		(pts
			(arc
				(start 429.482504 -18.235422)
				(mid 429.116744 -18.235422)
				(end 429.482504 -18.235422)
			)
		)
		(stroke
			(width 0)
			(type solid)
		)
		(fill yes)
		(layer "F.Cu")
		(net "GND")
	)
	(gr_poly
		(pts
			(arc
				(start 429.482504 -16.967454)
				(mid 429.116744 -16.967454)
				(end 429.482504 -16.967454)
			)
		)
		(stroke
			(width 0)
			(type solid)
		)
		(fill yes)
		(layer "F.Cu")
		(net "GND")
	)
	(gr_poly
		(pts
			(arc
				(start 429.488346 -6.07949)
				(mid 429.122586 -6.07949)
				(end 429.488346 -6.07949)
			)
		)
		(stroke
			(width 0)
			(type solid)
		)
		(fill yes)
		(layer "F.Cu")
		(net "GND")
	)
	(gr_poly
		(pts
			(arc
				(start 429.526192 -4.95173)
				(mid 429.160432 -4.95173)
				(end 429.526192 -4.95173)
			)
		)
		(stroke
			(width 0)
			(type solid)
		)
		(fill yes)
		(layer "F.Cu")
		(net "GND")
	)
	(gr_poly
		(pts
			(arc
				(start 429.996346 -6.586474)
				(mid 429.630586 -6.586474)
				(end 429.996346 -6.586474)
			)
		)
		(stroke
			(width 0)
			(type solid)
		)
		(fill yes)
		(layer "F.Cu")
		(net "GND")
	)
	(gr_poly
		(pts
			(arc
				(start 430.034192 -5.585714)
				(mid 429.668432 -5.585714)
				(end 430.034192 -5.585714)
			)
		)
		(stroke
			(width 0)
			(type solid)
		)
		(fill yes)
		(layer "F.Cu")
		(net "GND")
	)
	(gr_poly
		(pts
			(arc
				(start 430.034192 -4.317746)
				(mid 429.668432 -4.317746)
				(end 430.034192 -4.317746)
			)
		)
		(stroke
			(width 0)
			(type solid)
		)
		(fill yes)
		(layer "F.Cu")
		(net "GND")
	)
	(gr_poly
		(pts
			(arc
				(start 430.741328 -18.235422)
				(mid 430.375568 -18.235422)
				(end 430.741328 -18.235422)
			)
		)
		(stroke
			(width 0)
			(type solid)
		)
		(fill yes)
		(layer "F.Cu")
		(net "GND")
	)
	(gr_poly
		(pts
			(arc
				(start 430.741328 -16.967454)
				(mid 430.375568 -16.967454)
				(end 430.741328 -16.967454)
			)
		)
		(stroke
			(width 0)
			(type solid)
		)
		(fill yes)
		(layer "F.Cu")
		(net "GND")
	)
	(gr_poly
		(pts
			(arc
				(start 431.249328 -17.601438)
				(mid 430.883568 -17.601438)
				(end 431.249328 -17.601438)
			)
		)
		(stroke
			(width 0)
			(type solid)
		)
		(fill yes)
		(layer "F.Cu")
		(net "GND")
	)
	(gr_poly
		(pts
			(arc
				(start 431.293016 -5.585714)
				(mid 430.927256 -5.585714)
				(end 431.293016 -5.585714)
			)
		)
		(stroke
			(width 0)
			(type solid)
		)
		(fill yes)
		(layer "F.Cu")
		(net "GND")
	)
	(gr_poly
		(pts
			(arc
				(start 431.293016 -4.317746)
				(mid 430.927256 -4.317746)
				(end 431.293016 -4.317746)
			)
		)
		(stroke
			(width 0)
			(type solid)
		)
		(fill yes)
		(layer "F.Cu")
		(net "GND")
	)
	(gr_poly
		(pts
			(arc
				(start 431.768504 -19.125438)
				(mid 431.402744 -19.125438)
				(end 431.768504 -19.125438)
			)
		)
		(stroke
			(width 0)
			(type solid)
		)
		(fill yes)
		(layer "F.Cu")
		(net "GND")
	)
	(gr_poly
		(pts
			(arc
				(start 431.801016 -4.95173)
				(mid 431.435256 -4.95173)
				(end 431.801016 -4.95173)
			)
		)
		(stroke
			(width 0)
			(type solid)
		)
		(fill yes)
		(layer "F.Cu")
		(net "GND")
	)
	(gr_poly
		(pts
			(arc
				(start 432.276504 -19.759422)
				(mid 431.910744 -19.759422)
				(end 432.276504 -19.759422)
			)
		)
		(stroke
			(width 0)
			(type solid)
		)
		(fill yes)
		(layer "F.Cu")
		(net "GND")
	)
	(gr_poly
		(pts
			(arc
				(start 432.276504 -18.491454)
				(mid 431.910744 -18.491454)
				(end 432.276504 -18.491454)
			)
		)
		(stroke
			(width 0)
			(type solid)
		)
		(fill yes)
		(layer "F.Cu")
		(net "GND")
	)
	(gr_poly
		(pts
			(arc
				(start 433.535328 -19.759422)
				(mid 433.169568 -19.759422)
				(end 433.535328 -19.759422)
			)
		)
		(stroke
			(width 0)
			(type solid)
		)
		(fill yes)
		(layer "F.Cu")
		(net "GND")
	)
	(gr_poly
		(pts
			(arc
				(start 433.535328 -18.491454)
				(mid 433.169568 -18.491454)
				(end 433.535328 -18.491454)
			)
		)
		(stroke
			(width 0)
			(type solid)
		)
		(fill yes)
		(layer "F.Cu")
		(net "GND")
	)
	(gr_poly
		(pts
			(arc
				(start 434.043328 -19.125438)
				(mid 433.677568 -19.125438)
				(end 434.043328 -19.125438)
			)
		)
		(stroke
			(width 0)
			(type solid)
		)
		(fill yes)
		(layer "F.Cu")
		(net "GND")
	)
	(gr_poly
		(pts
			(arc
				(start 434.901848 -118.968266)
				(mid 434.528468 -118.968266)
				(end 434.901848 -118.968266)
			)
		)
		(stroke
			(width 0)
			(type solid)
		)
		(fill yes)
		(layer "F.Cu")
		(net "GND")
	)
	(gr_poly
		(pts
			(arc
				(start 434.901848 -118.168166)
				(mid 434.528468 -118.168166)
				(end 434.901848 -118.168166)
			)
		)
		(stroke
			(width 0)
			(type solid)
		)
		(fill yes)
		(layer "F.Cu")
		(net "GND")
	)
	(gr_poly
		(pts
			(arc
				(start 441.559696 -46.517306)
				(mid 441.193936 -46.517306)
				(end 441.559696 -46.517306)
			)
		)
		(stroke
			(width 0)
			(type solid)
		)
		(fill yes)
		(layer "F.Cu")
		(net "GND")
	)
	(gr_poly
		(pts
			(arc
				(start 444.27648 -9.464548)
				(mid 443.91072 -9.464548)
				(end 444.27648 -9.464548)
			)
		)
		(stroke
			(width 0)
			(type solid)
		)
		(fill yes)
		(layer "F.Cu")
		(net "GND")
	)
	(gr_poly
		(pts
			(arc
				(start 444.426086 -96.572324)
				(mid 444.060326 -96.572324)
				(end 444.426086 -96.572324)
			)
		)
		(stroke
			(width 0)
			(type solid)
		)
		(fill yes)
		(layer "F.Cu")
		(net "GND")
	)
	(gr_poly
		(pts
			(arc
				(start 445.72174 -4.140708)
				(mid 445.35598 -4.140708)
				(end 445.72174 -4.140708)
			)
		)
		(stroke
			(width 0)
			(type solid)
		)
		(fill yes)
		(layer "F.Cu")
		(net "GND")
	)
	(gr_poly
		(pts
			(arc
				(start 447.14668 -14.646148)
				(mid 446.78092 -14.646148)
				(end 447.14668 -14.646148)
			)
		)
		(stroke
			(width 0)
			(type solid)
		)
		(fill yes)
		(layer "F.Cu")
		(net "GND")
	)
	(gr_poly
		(pts
			(arc
				(start 448.34048 -14.595348)
				(mid 447.97472 -14.595348)
				(end 448.34048 -14.595348)
			)
		)
		(stroke
			(width 0)
			(type solid)
		)
		(fill yes)
		(layer "F.Cu")
		(net "GND")
	)
	(gr_poly
		(pts
			(arc
				(start 448.71386 -45.565568)
				(mid 448.3481 -45.565568)
				(end 448.71386 -45.565568)
			)
		)
		(stroke
			(width 0)
			(type solid)
		)
		(fill yes)
		(layer "F.Cu")
		(net "GND")
	)
	(gr_poly
		(pts
			(arc
				(start 449.447158 -96.646492)
				(mid 449.081398 -96.646492)
				(end 449.447158 -96.646492)
			)
		)
		(stroke
			(width 0)
			(type solid)
		)
		(fill yes)
		(layer "F.Cu")
		(net "GND")
	)
	(gr_poly
		(pts
			(arc
				(start 451.32752 -150.569168)
				(mid 450.96176 -150.569168)
				(end 451.32752 -150.569168)
			)
		)
		(stroke
			(width 0)
			(type solid)
		)
		(fill yes)
		(layer "F.Cu")
		(net "GND")
	)
	(gr_poly
		(pts
			(arc
				(start 452.38416 -45.110908)
				(mid 452.0184 -45.110908)
				(end 452.38416 -45.110908)
			)
		)
		(stroke
			(width 0)
			(type solid)
		)
		(fill yes)
		(layer "F.Cu")
		(net "GND")
	)
	(gr_poly
		(pts
			(xy 300.55058 -394.0175) (xy 300.55058 -386.69468) (xy 300.310804 -386.454904) (xy 299.154596 -386.454904)
			(xy 298.96308 -386.64642)
			(arc
				(start 298.96308 -388.597648)
				(mid 299.394336 -389.360091)
				(end 298.96308 -390.12241)
			)
			(xy 298.96308 -393.97686) (xy 299.23232 -394.2461) (xy 300.32198 -394.2461)
		)
		(stroke
			(width 0)
			(type solid)
		)
		(fill yes)
		(layer "F.Cu")
		(net "GND")
	)
	(gr_poly
		(pts
			(xy 456.78852 -33.861248) (xy 456.78852 -18.611088) (xy 458.73416 -16.665448) (xy 459.62062 -16.665448)
			(xy 460.22006 -16.066008) (xy 460.22006 -14.039088) (xy 460.063342 -13.88237) (xy 456.020932 -13.88237)
			(xy 455.924412 -13.97889) (xy 455.924412 -16.186658) (xy 456.172824 -16.435324) (xy 456.172824 -17.652746)
			(arc
				(start 456.176634 -17.662144)
				(mid 456.205275 -17.756914)
				(end 456.214988 -17.855438)
			)
			(arc
				(start 456.214988 -23.945342)
				(mid 456.205253 -24.043861)
				(end 456.176634 -24.138636)
			)
			(xy 456.172824 -24.148034) (xy 456.172824 -25.449784) (xy 454.984612 -26.637996) (xy 454.984612 -28.810458)
			(xy 453.511412 -30.283658) (xy 447.821812 -30.283658) (xy 447.796412 -30.309058) (xy 447.796412 -33.839658)
			(xy 448.304412 -34.347658) (xy 456.30211 -34.347658)
		)
		(stroke
			(width 0)
			(type solid)
		)
		(fill yes)
		(layer "F.Cu")
		(net "GND")
	)
	(gr_poly
		(pts
			(xy 23.495 -178.834796) (xy 23.495 -178.095148) (xy 23.6728 -177.917348) (xy 24.145494 -177.917348)
			(xy 24.305768 -177.757074)
			(arc
				(start 24.306276 -177.736754)
				(mid 24.338945 -177.585942)
				(end 24.425402 -177.458116)
			)
			(xy 24.59228 -177.290984) (xy 24.59228 -176.672748) (xy 24.51608 -176.596548) (xy 24.041608 -176.596548)
			(xy 23.72868 -176.909476) (xy 23.14575 -176.909476) (xy 23.048722 -177.006504) (xy 23.048722 -177.694844)
			(xy 23.2156 -177.861468) (xy 23.2156 -178.353212)
			(arc
				(start 23.21814 -178.360832)
				(mid 23.231869 -178.41879)
				(end 23.236428 -178.47818)
			)
			(arc
				(start 23.236428 -178.47818)
				(mid 23.231893 -178.537573)
				(end 23.21814 -178.595528)
			)
			(xy 23.2156 -178.603148) (xy 23.2156 -178.834796) (xy 23.241 -178.860196) (xy 23.4696 -178.860196)
		)
		(stroke
			(width 0)
			(type solid)
		)
		(fill yes)
		(layer "F.Cu")
		(net "GND")
	)
	(gr_poly
		(pts
			(xy 127.4191 -364.827312) (xy 127.4191 -361.789472) (xy 127.4191 -361.5563) (xy 127.21336 -361.35056)
			(xy 126.980188 -361.35056) (xy 126.375414 -360.745786) (xy 126.375414 -360.604054) (xy 126.375414 -360.466386)
			(xy 126.375414 -359.803192) (xy 126.18847 -359.616248) (xy 126.18847 -358.785922) (xy 126.161038 -358.75849)
			(xy 125.887734 -358.75849) (xy 125.867414 -358.77881) (xy 125.867414 -360.266742) (xy 125.866398 -360.267758)
			(xy 125.866398 -360.795316) (xy 125.866398 -360.920792) (xy 125.866398 -361.891326) (xy 125.866398 -362.126784)
			(xy 125.656594 -362.336588) (xy 124.296678 -362.336588) (xy 124.2949 -362.33481) (xy 124.171456 -362.33481)
			(xy 123.864878 -362.028232) (xy 123.864878 -361.825032) (xy 123.763278 -361.723432) (xy 123.728226 -361.68838)
			(xy 123.241562 -361.68838) (xy 123.144026 -361.785662) (xy 123.144026 -364.746286) (xy 123.266454 -364.868714)
			(xy 127.377698 -364.868714)
		)
		(stroke
			(width 0)
			(type solid)
		)
		(fill yes)
		(layer "F.Cu")
		(net "SW_PVPP_HBM_CPU1_SW")
	)
	(gr_poly
		(pts
			(xy 264.639806 -76.020676) (xy 264.639806 -74.651616) (xy 264.642346 -74.649076) (xy 264.517378 -74.524108)
			(xy 264.13206 -74.524108) (xy 263.694418 -74.086466) (xy 263.694418 -73.918318) (xy 263.274048 -73.497948)
			(xy 263.07796 -73.497948) (xy 262.98398 -73.403968) (xy 262.98398 -72.424036) (xy 262.962136 -72.402192)
			(xy 262.859266 -72.402192) (xy 262.857742 -72.403716) (xy 262.825992 -72.403716) (xy 262.795766 -72.433942)
			(xy 262.795766 -72.465692) (xy 262.795766 -73.481692) (xy 262.986266 -73.672192) (xy 262.986266 -73.799192)
			(xy 263.402826 -74.216006) (xy 263.402826 -74.351896) (xy 263.857486 -74.806556) (xy 263.993376 -74.806556)
			(xy 264.218166 -74.806556) (xy 264.289286 -74.877676) (xy 264.289286 -75.550776) (xy 264.119106 -75.720956)
			(xy 262.628126 -75.720956) (xy 262.564626 -75.784456) (xy 262.564626 -76.198476) (xy 262.623046 -76.256896)
			(xy 264.403586 -76.256896)
		)
		(stroke
			(width 0)
			(type solid)
		)
		(fill yes)
		(layer "F.Cu")
		(net "GND")
	)
	(gr_poly
		(pts
			(xy 385.406138 -80.46339) (xy 385.406138 -79.902558) (xy 385.406138 -79.722726) (xy 385.406138 -77.439012)
			(xy 385.203954 -77.236828) (xy 384.99669 -77.236828) (xy 384.98399 -77.249528) (xy 384.98399 -78.132178)
			(xy 385.061968 -78.210156) (xy 385.061968 -78.972156) (xy 385.061968 -79.08036) (xy 385.061968 -79.6417)
			(xy 385.061968 -79.76616) (xy 384.93446 -79.893668) (xy 383.78892 -79.893668) (xy 383.667 -79.771748)
			(xy 383.42062 -79.525368) (xy 383.34696 -79.451708) (xy 383.34696 -78.707488) (xy 383.42062 -78.633828)
			(xy 383.67462 -78.379828) (xy 383.67462 -77.968348) (xy 383.7305 -77.912468) (xy 383.7305 -77.301852)
			(xy 383.71272 -77.284072) (xy 383.338324 -77.284072) (xy 383.141982 -77.480668) (xy 383.141982 -78.191106)
			(xy 383.0193 -78.313788) (xy 383.0193 -80.576928) (xy 383.16916 -80.726788) (xy 383.45872 -80.726788)
			(xy 385.14274 -80.726788)
		)
		(stroke
			(width 0)
			(type solid)
		)
		(fill yes)
		(layer "F.Cu")
		(net "P1V8_PCH_AUX_VCC")
	)
	(gr_poly
		(pts
			(xy 65.43548 -20.411948) (xy 65.43548 -17.211548) (xy 65.91808 -16.728948) (xy 65.91808 -14.163548)
			(xy 65.76568 -14.011148) (xy 64.95288 -14.011148) (xy 64.80048 -14.163548) (xy 64.80048 -16.754348)
			(xy 63.852298 -17.70253)
			(arc
				(start 63.85052 -17.720818)
				(mid 63.727285 -17.96663)
				(end 63.47079 -18.06575)
			)
			(arc
				(start 63.47079 -18.06575)
				(mid 63.291549 -18.021022)
				(end 63.154306 -17.897348)
			)
			(xy 62.38748 -17.897348) (xy 62.15888 -18.125948) (xy 62.15888 -20.234148) (xy 62.71768 -20.792948)
			(xy 65.05448 -20.792948)
		)
		(stroke
			(width 0)
			(type solid)
		)
		(fill yes)
		(layer "F.Cu")
		(net "GND")
	)
	(gr_poly
		(pts
			(arc
				(start 235.995972 -134.741666)
				(mid 235.545376 -134.741666)
				(end 235.995972 -134.741666)
			)
		)
		(stroke
			(width 0)
			(type solid)
		)
		(fill yes)
		(layer "F.Cu")
		(net "GND")
	)
	(gr_poly
		(pts
			(arc
				(start 238.03102 -134.741412)
				(mid 237.595664 -134.741412)
				(end 238.03102 -134.741412)
			)
		)
		(stroke
			(width 0)
			(type solid)
		)
		(fill yes)
		(layer "F.Cu")
		(net "GND")
	)
	(gr_poly
		(pts
			(xy 375.6025 -364.617762) (xy 375.6025 -362.033058) (xy 375.601484 -362.032296) (xy 375.601484 -361.750864)
			(xy 375.10212 -361.2515) (xy 374.820942 -361.2515) (xy 374.315228 -360.745786) (xy 374.315228 -360.604054)
			(xy 374.315228 -360.466386) (xy 374.315228 -359.803192) (xy 374.128284 -359.616248) (xy 374.128284 -358.756204)
			(xy 374.083326 -358.711246) (xy 373.83847 -358.711246) (xy 373.807228 -358.742488) (xy 373.807228 -358.773476)
			(xy 373.807228 -360.266742) (xy 373.806212 -360.267758) (xy 373.806212 -360.795316) (xy 373.806212 -360.920792)
			(xy 373.806212 -361.891326) (xy 373.806212 -362.126784) (xy 373.596408 -362.336588) (xy 372.236492 -362.336588)
			(xy 372.234714 -362.33481) (xy 372.11127 -362.33481) (xy 371.804692 -362.028232) (xy 371.804692 -361.825032)
			(xy 371.678708 -361.699048) (xy 371.106954 -361.699048) (xy 370.9416 -361.864402) (xy 370.9416 -364.45063)
			(xy 371.23751 -364.74654) (xy 375.473722 -364.74654)
		)
		(stroke
			(width 0)
			(type solid)
		)
		(fill yes)
		(layer "F.Cu")
		(net "SW_PVPP_HBM_CPU0_SW")
	)
	(gr_poly
		(pts
			(xy 444.562738 -336.26425) (xy 444.562738 -332.59395) (xy 444.349378 -332.38059) (xy 443.493398 -332.38059)
			(xy 443.353698 -332.52029)
			(arc
				(start 443.353698 -333.88554)
				(mid 443.400331 -333.946232)
				(end 443.416944 -334.020922)
			)
			(arc
				(start 443.416944 -334.521302)
				(mid 443.365017 -334.646413)
				(end 443.239906 -334.69834)
			)
			(arc
				(start 442.239146 -334.69834)
				(mid 442.22282 -334.697563)
				(end 442.206634 -334.695292)
			)
			(arc
				(start 442.206634 -334.695292)
				(mid 442.122998 -334.716925)
				(end 442.086238 -334.795114)
			)
			(xy 442.086238 -336.13217) (xy 442.355478 -336.40141) (xy 444.425578 -336.40141)
		)
		(stroke
			(width 0)
			(type solid)
		)
		(fill yes)
		(layer "F.Cu")
		(net "GND")
	)
	(gr_poly
		(pts
			(xy 85.587078 -13.64869) (xy 85.535262 -13.596874) (xy 81.340198 -13.596874) (xy 81.243678 -13.693394)
			(xy 81.243678 -15.901162) (xy 81.804256 -16.46174)
			(arc
				(start 83.31708 -16.46174)
				(mid 83.511624 -16.500531)
				(end 83.67649 -16.610838)
			)
			(arc
				(start 84.168488 -17.102836)
				(mid 84.27867 -17.267735)
				(end 84.317332 -17.462246)
			)
			(xy 84.317332 -23.825962) (xy 84.317078 -23.844758) (xy 84.317078 -24.511762) (xy 82.775552 -26.053288)
			(xy 80.67548 -26.053288) (xy 80.303878 -26.42489) (xy 80.303878 -28.524962) (xy 78.830678 -29.998162)
			(xy 73.141078 -29.998162) (xy 73.115678 -30.023562) (xy 73.115678 -33.554162) (xy 73.623678 -34.062162)
			(xy 85.587078 -34.062162)
		)
		(stroke
			(width 0)
			(type solid)
		)
		(fill yes)
		(layer "F.Cu")
		(net "GND")
	)
	(gr_poly
		(pts
			(arc
				(start 49.105312 -104.968548)
				(mid 49.191075 -104.921421)
				(end 49.19726 -104.823768)
			)
			(arc
				(start 49.19726 -104.823768)
				(mid 49.170358 -104.744849)
				(end 49.161192 -104.66197)
			)
			(arc
				(start 49.161192 -104.66197)
				(mid 49.263834 -104.40162)
				(end 49.516538 -104.281478)
			)
			(arc
				(start 49.516538 -104.281478)
				(mid 49.583978 -104.249398)
				(end 49.61128 -104.179878)
			)
			(xy 49.61128 -103.698548) (xy 49.38268 -103.469948) (xy 47.29988 -103.469948) (xy 47.09668 -103.673148)
			(xy 47.09668 -104.917748) (xy 47.14748 -104.968548)
		)
		(stroke
			(width 0)
			(type solid)
		)
		(fill yes)
		(layer "F.Cu")
		(net "GND")
	)
	(gr_poly
		(pts
			(xy 103.318056 -238.049054) (xy 104.481376 -238.049054) (xy 104.581706 -237.948724) (xy 104.581706 -237.235746)
			(xy 104.128062 -236.781848) (xy 104.10825 -236.762036) (xy 104.10825 -236.26318) (xy 104.041702 -236.196632)
			(arc
				(start 104.005888 -236.23143)
				(mid 103.900175 -236.299906)
				(end 103.776526 -236.323886)
			)
			(arc
				(start 103.776526 -236.323886)
				(mid 103.627539 -236.288394)
				(end 103.510588 -236.18952)
			)
			(xy 103.29037 -236.18952)
			(arc
				(start 103.284274 -236.191044)
				(mid 103.24358 -236.198826)
				(end 103.202232 -236.201458)
			)
			(arc
				(start 103.202232 -236.201458)
				(mid 103.160884 -236.198829)
				(end 103.12019 -236.191044)
			)
			(xy 103.114094 -236.18952) (xy 102.693978 -236.18952) (xy 102.63124 -236.252258) (xy 102.63124 -238.30661)
			(xy 102.72903 -238.4044) (xy 102.96271 -238.4044)
		)
		(stroke
			(width 0)
			(type solid)
		)
		(fill yes)
		(layer "F.Cu")
		(net "GND")
	)
	(gr_poly
		(pts
			(xy 121.203974 -247.51411) (xy 121.203974 -247.059958)
			(arc
				(start 121.198894 -247.049544)
				(mid 121.173481 -246.976912)
				(end 121.164858 -246.900446)
			)
			(arc
				(start 121.164858 -246.900446)
				(mid 121.173085 -246.825758)
				(end 121.19737 -246.75465)
			)
			(xy 121.202196 -246.744236) (xy 121.202196 -246.489474)
			(arc
				(start 121.198894 -246.480838)
				(mid 121.183119 -246.423622)
				(end 121.177812 -246.364506)
			)
			(arc
				(start 121.177812 -246.364506)
				(mid 121.183097 -246.305387)
				(end 121.198894 -246.248174)
			)
			(xy 121.202196 -246.239538) (xy 121.202196 -246.059706) (xy 121.15673 -246.01424) (xy 120.072912 -246.01424)
			(xy 119.820182 -245.76151) (xy 119.32539 -245.76151) (xy 119.324882 -245.762272) (xy 119.120158 -245.762272)
			(xy 119.028718 -245.853712) (xy 119.028718 -246.410988) (xy 118.88343 -246.556276) (xy 118.88343 -246.808752)
			(xy 119.149114 -247.074436) (xy 119.149114 -247.537224) (xy 119.19966 -247.58777) (xy 121.130314 -247.58777)
		)
		(stroke
			(width 0)
			(type solid)
		)
		(fill yes)
		(layer "F.Cu")
		(net "PVCCD_HV_CPU1")
	)
	(gr_poly
		(pts
			(xy 369.143788 -247.513856) (xy 369.143788 -247.05945)
			(arc
				(start 369.138708 -247.049036)
				(mid 369.113477 -246.976637)
				(end 369.104926 -246.900446)
			)
			(arc
				(start 369.104926 -246.900446)
				(mid 369.113085 -246.826032)
				(end 369.137184 -246.755158)
			)
			(xy 369.14201 -246.744744) (xy 369.14201 -246.488712)
			(arc
				(start 369.138708 -246.480076)
				(mid 369.123101 -246.423225)
				(end 369.11788 -246.364506)
			)
			(arc
				(start 369.11788 -246.364506)
				(mid 369.123138 -246.305793)
				(end 369.138708 -246.248936)
			)
			(xy 369.14201 -246.2403) (xy 369.14201 -246.059452) (xy 369.096544 -246.013986) (xy 368.012726 -246.013986)
			(xy 367.759996 -245.761256) (xy 367.265204 -245.761256) (xy 367.264696 -245.762018) (xy 367.059972 -245.762018)
			(xy 366.968532 -245.853458) (xy 366.968532 -246.410734) (xy 366.823244 -246.556022) (xy 366.823244 -246.808498)
			(xy 367.088928 -247.074182) (xy 367.088928 -247.53697) (xy 367.139474 -247.587516) (xy 369.070128 -247.587516)
		)
		(stroke
			(width 0)
			(type solid)
		)
		(fill yes)
		(layer "F.Cu")
		(net "PVCCD_HV_CPU0")
	)
	(gr_poly
		(pts
			(xy 446.104772 -34.383218) (xy 446.104772 -32.943292)
			(arc
				(start 444.733172 -32.943292)
				(mid 444.685537 -32.94023)
				(end 444.638684 -32.9311)
			)
			(xy 444.632334 -32.929576)
			(arc
				(start 444.583566 -32.929576)
				(mid 444.422564 -32.863997)
				(end 444.355728 -32.703516)
			)
			(xy 444.355728 -32.4358) (xy 444.38824 -32.4358) (xy 444.402464 -32.40786) (xy 444.409576 -32.394398)
			(xy 444.415672 -32.382968) (xy 444.415672 -32.224218) (xy 443.463172 -32.224218) (xy 443.336172 -32.351218)
			(xy 443.336172 -32.910018) (xy 443.056772 -33.189418) (xy 441.558172 -33.189418) (xy 441.405772 -33.037018)
			(xy 441.405772 -32.402018) (xy 441.329572 -32.325818) (xy 437.997092 -32.325818) (xy 437.910732 -32.412178)
			(xy 437.910732 -34.494978) (xy 438.052972 -34.637218) (xy 445.850772 -34.637218)
		)
		(stroke
			(width 0)
			(type solid)
		)
		(fill yes)
		(layer "F.Cu")
		(net "GND")
	)
	(gr_poly
		(pts
			(xy 437.55818 -7.617206) (xy 437.578754 -7.596632) (xy 437.749442 -7.596632) (xy 437.772556 -7.619746)
			(xy 437.772556 -9.032748) (xy 438.158128 -9.032748) (xy 438.158128 -7.617206) (xy 438.178702 -7.596632)
			(xy 438.34939 -7.596632) (xy 438.372504 -7.619746) (xy 438.372504 -9.032748) (xy 438.758076 -9.032748)
			(xy 438.758076 -7.617206) (xy 438.77865 -7.596632) (xy 438.949338 -7.596632) (xy 438.972452 -7.619746)
			(xy 438.972452 -9.032748) (xy 439.358024 -9.032748) (xy 439.358024 -7.617206) (xy 439.378852 -7.596632)
			(xy 439.54954 -7.596632) (xy 439.572908 -7.619746) (xy 439.572908 -9.032748) (xy 439.957972 -9.032748)
			(xy 439.957972 -7.617206) (xy 439.9788 -7.596632) (xy 440.149488 -7.596632) (xy 440.172856 -7.619746)
			(xy 440.172856 -9.032748) (xy 440.97448 -9.032748) (xy 441.20308 -8.804148) (xy 441.20308 -6.975348)
			(xy 440.89828 -6.670548) (xy 437.49468 -6.670548) (xy 437.18988 -6.975348) (xy 437.18988 -8.981948)
			(xy 437.24068 -9.032748) (xy 437.55818 -9.032748)
		)
		(stroke
			(width 0)
			(type solid)
		)
		(fill yes)
		(layer "F.Cu")
		(net "GND")
	)
	(gr_poly
		(pts
			(xy 272.219674 -74.647298) (xy 272.219674 -60.907422) (xy 271.90319 -60.590938) (xy 260.285484 -60.590938)
			(xy 260.262624 -60.614052) (xy 258.820666 -60.614052)
			(arc
				(start 258.199128 -61.235336)
				(mid 258.095658 -61.304536)
				(end 257.973576 -61.328808)
			)
			(xy 249.773186 -61.328808) (xy 249.773186 -69.547232) (xy 249.776488 -69.550534) (xy 249.776488 -70.433692)
			(xy 249.790966 -70.447916) (xy 252.166882 -70.447916) (xy 252.168914 -70.445884) (xy 262.990076 -70.445884)
			(xy 262.999982 -70.435978) (xy 262.999982 -68.749672) (xy 262.999474 -68.749418) (xy 262.999474 -67.92341)
			(xy 262.714994 -67.63893) (xy 261.724902 -67.63893) (xy 261.497572 -67.4116) (xy 261.497572 -66.7004)
			(xy 262.538972 -65.659) (xy 264.164572 -65.659) (xy 264.418572 -65.913) (xy 264.418572 -68.8848)
			(xy 264.621772 -69.088) (xy 269.828772 -69.088) (xy 270.133572 -69.3928) (xy 270.133572 -74.3204)
			(xy 270.565372 -74.7522) (xy 272.114772 -74.7522)
		)
		(stroke
			(width 0)
			(type solid)
		)
		(fill yes)
		(layer "F.Cu")
		(net "GND")
	)
	(gr_poly
		(pts
			(xy 439.83148 -20.615148) (xy 439.83148 -17.389348) (xy 440.237372 -16.983456) (xy 440.237372 -14.468094)
			(xy 440.03468 -14.265148) (xy 439.32348 -14.265148) (xy 439.065162 -14.523466)
			(arc
				(start 439.064908 -14.54404)
				(mid 439.03892 -14.697327)
				(end 438.96788 -14.835632)
			)
			(xy 438.96788 -16.779748) (xy 438.651904 -17.095724)
			(arc
				(start 438.651904 -17.211548)
				(mid 438.628286 -17.341636)
				(end 438.560464 -17.455134)
			)
			(arc
				(start 438.560464 -17.455134)
				(mid 438.420996 -17.593311)
				(end 438.23128 -17.643856)
			)
			(arc
				(start 438.23128 -17.643856)
				(mid 438.188725 -17.641532)
				(end 438.146698 -17.634458)
			)
			(xy 438.11952 -17.628108) (xy 437.18988 -18.557748) (xy 437.18988 -20.970748) (xy 437.49468 -21.275548)
			(xy 439.17108 -21.275548)
		)
		(stroke
			(width 0)
			(type solid)
		)
		(fill yes)
		(layer "F.Cu")
		(net "GND")
	)
	(gr_poly
		(pts
			(arc
				(start 467.755986 -155.36545)
				(mid 467.780281 -155.346866)
				(end 467.789514 -155.317698)
			)
			(arc
				(start 467.789514 -86.859872)
				(mid 467.774635 -86.823951)
				(end 467.738714 -86.809072)
			)
			(arc
				(start 467.332822 -86.809072)
				(mid 467.297155 -86.823951)
				(end 467.282276 -86.859618)
			)
			(xy 467.282276 -115.104926) (xy 467.284816 -115.116356)
			(arc
				(start 467.287864 -115.121944)
				(mid 467.319142 -115.206449)
				(end 467.329774 -115.295934)
			)
			(arc
				(start 467.329774 -115.295934)
				(mid 467.31919 -115.38543)
				(end 467.287864 -115.469924)
			)
			(xy 467.284816 -115.475512) (xy 467.282276 -115.486942)
			(arc
				(start 467.282276 -154.992832)
				(mid 467.285886 -155.011388)
				(end 467.295992 -155.027376)
			)
			(arc
				(start 467.295992 -155.027376)
				(mid 467.4556 -155.202721)
				(end 467.609936 -155.382722)
			)
			(xy 467.620096 -155.395168) (xy 467.651084 -155.40355)
		)
		(stroke
			(width 0)
			(type solid)
		)
		(fill yes)
		(layer "F.Cu")
		(net "GND")
	)
	(gr_poly
		(pts
			(xy 369.064794 -260.177026) (xy 369.064794 -247.987312) (xy 368.930682 -247.8532) (xy 367.86312 -247.8532)
			(xy 367.858294 -247.848374) (xy 363.784896 -247.848374) (xy 363.137704 -248.495566) (xy 363.137704 -249.341386)
			(xy 363.203998 -249.40768) (xy 363.996478 -249.40768) (xy 364.207552 -249.196606) (xy 367.802922 -249.196606)
			(xy 368.057176 -249.451114) (xy 368.057176 -251.297186) (xy 367.80724 -251.547122) (xy 363.478826 -251.547122)
			(xy 363.175804 -251.850144) (xy 363.175804 -252.887226) (xy 363.226604 -252.938026) (xy 363.646212 -252.938026)
			(xy 363.731048 -252.85319) (xy 367.890044 -252.85319) (xy 368.100864 -253.06401) (xy 368.100864 -254.97409)
			(xy 367.905284 -255.16967) (xy 363.28096 -255.16967) (xy 363.165644 -255.284986) (xy 363.165644 -256.490978)
			(xy 363.204252 -256.529586) (xy 367.785904 -256.529586) (xy 368.019584 -256.763266) (xy 368.019584 -258.633976)
			(xy 367.823242 -258.830318) (xy 363.294168 -258.830318) (xy 363.135164 -258.989322) (xy 363.135164 -260.040882)
			(xy 363.335824 -260.241542) (xy 368.03584 -260.241542) (xy 368.036094 -260.241796) (xy 369.000024 -260.241796)
		)
		(stroke
			(width 0)
			(type solid)
		)
		(fill yes)
		(layer "F.Cu")
		(net "GND")
	)
	(gr_poly
		(pts
			(xy 121.12498 -260.17728) (xy 121.12498 -247.987566) (xy 120.990868 -247.853454) (xy 119.923306 -247.853454)
			(xy 119.91848 -247.848628) (xy 115.845082 -247.848628) (xy 115.19789 -248.49582) (xy 115.19789 -249.34164)
			(xy 115.264184 -249.407934) (xy 116.056664 -249.407934) (xy 116.267738 -249.19686) (xy 119.863108 -249.19686)
			(xy 120.117362 -249.451368) (xy 120.117362 -251.29744) (xy 119.867426 -251.547376) (xy 115.539012 -251.547376)
			(xy 115.23599 -251.850398) (xy 115.23599 -252.88748) (xy 115.28679 -252.93828) (xy 115.706398 -252.93828)
			(xy 115.791234 -252.853444) (xy 119.95023 -252.853444) (xy 120.16105 -253.064264) (xy 120.16105 -254.974344)
			(xy 119.96547 -255.169924) (xy 115.341146 -255.169924) (xy 115.22583 -255.28524) (xy 115.22583 -256.491232)
			(xy 115.240816 -256.506218) (xy 115.240816 -256.506726) (xy 115.26393 -256.52984) (xy 119.84609 -256.52984)
			(xy 120.07977 -256.76352) (xy 120.07977 -258.63423) (xy 119.883428 -258.830572) (xy 115.354354 -258.830572)
			(xy 115.19535 -258.989576) (xy 115.19535 -260.041136) (xy 115.39601 -260.241796) (xy 120.096026 -260.241796)
			(xy 120.09628 -260.24205) (xy 121.06021 -260.24205)
		)
		(stroke
			(width 0)
			(type solid)
		)
		(fill yes)
		(layer "F.Cu")
		(net "GND")
	)
	(gr_poly
		(pts
			(xy 254.56388 -51.942746) (xy 254.56388 -48.056546) (xy 255.12268 -47.497746) (xy 258.70408 -47.497746)
			(xy 259.18668 -47.015146) (xy 259.18668 -46.684946) (xy 259.44068 -46.430946) (xy 260.38048 -46.430946)
			(xy 260.50748 -46.303946) (xy 260.50748 -39.786306) (xy 260.50748 -39.588948) (xy 260.389878 -39.471346)
			(xy 260.19252 -39.471346) (xy 258.39928 -39.471346) (xy 258.28752 -39.583106) (xy 258.28752 -40.238426)
			(xy 258.1148 -40.411146) (xy 252.04928 -40.411146) (xy 251.97308 -40.487346) (xy 251.97308 -40.588946)
			(xy 252.02388 -40.639746) (xy 253.92888 -40.639746) (xy 254.00508 -40.715946) (xy 254.00508 -41.350946)
			(xy 253.92888 -41.427146) (xy 252.55728 -41.427146) (xy 252.45568 -41.528746) (xy 252.45568 -41.604946)
			(xy 252.50648 -41.655746) (xy 255.80848 -41.655746) (xy 256.13868 -41.985946) (xy 256.90068 -41.985946)
			(xy 256.98958 -42.074846) (xy 256.98958 -44.449746) (xy 254.88138 -46.557946) (xy 253.42088 -46.557946)
			(xy 253.19228 -46.786546) (xy 253.19228 -52.018946) (xy 253.16688 -52.044346) (xy 253.16688 -52.095146)
			(xy 253.21768 -52.145946) (xy 254.36068 -52.145946)
		)
		(stroke
			(width 0)
			(type solid)
		)
		(fill yes)
		(layer "F.Cu")
		(net "P12V_AUX")
	)
	(gr_poly
		(pts
			(xy 437.08828 -108.039408) (xy 437.08828 -107.353608) (xy 437.100726 -107.341162) (xy 437.100726 -104.69499)
			(xy 433.878736 -104.69499)
			(arc
				(start 433.872386 -104.696514)
				(mid 433.824649 -104.705795)
				(end 433.77612 -104.70896)
			)
			(arc
				(start 433.77612 -104.70896)
				(mid 433.727586 -104.705828)
				(end 433.679854 -104.696514)
			)
			(xy 433.673504 -104.69499) (xy 432.2572 -104.69499) (xy 432.246786 -104.705404) (xy 431.023268 -104.705404)
			(xy 430.962816 -104.76611) (xy 430.962816 -104.88041) (xy 431.016156 -104.93375) (xy 432.669696 -104.93375)
			(xy 432.692048 -104.956356) (xy 432.742086 -104.956356) (xy 432.954684 -105.1687) (xy 432.954684 -105.4989)
			(xy 432.938936 -105.514394) (xy 432.938936 -105.51795) (xy 432.748436 -105.70845) (xy 432.74488 -105.70845)
			(xy 432.744626 -105.708704) (xy 431.513488 -105.708704) (xy 431.465736 -105.75671) (xy 431.465736 -105.91419)
			(xy 431.498756 -105.94721) (xy 433.871116 -105.94721) (xy 434.214524 -106.290364) (xy 435.872636 -106.290364)
			(xy 436.09768 -106.515408) (xy 436.09768 -107.324144) (xy 436.098188 -107.324398) (xy 436.098188 -108.014262)
			(xy 436.25008 -108.166408) (xy 436.96128 -108.166408)
		)
		(stroke
			(width 0)
			(type solid)
		)
		(fill yes)
		(layer "F.Cu")
		(net "P3V3_AUX")
	)
	(gr_poly
		(pts
			(xy 453.624188 -343.484708) (xy 453.624188 -335.86928) (xy 453.492108 -335.7372) (xy 449.731892 -335.7372)
			(arc
				(start 449.731892 -338.160614)
				(mid 449.718962 -338.259063)
				(end 449.681092 -338.35086)
			)
			(arc
				(start 449.681092 -338.719414)
				(mid 449.64382 -338.809396)
				(end 449.553838 -338.846668)
			)
			(arc
				(start 449.147438 -338.846668)
				(mid 449.057456 -338.809396)
				(end 449.020184 -338.719414)
			)
			(arc
				(start 449.020184 -338.35086)
				(mid 448.982265 -338.259076)
				(end 448.969384 -338.160614)
			)
			(xy 448.969384 -335.79308) (xy 447.233548 -335.79308) (xy 447.128138 -335.89849) (xy 447.128138 -336.05089)
			(xy 446.957958 -336.22107) (xy 446.275968 -336.22107) (xy 446.065148 -336.43189) (xy 446.065148 -344.183716)
			(xy 446.44564 -344.564208) (xy 452.544688 -344.564208)
		)
		(stroke
			(width 0)
			(type solid)
		)
		(fill yes)
		(layer "F.Cu")
		(net "P12V_AUX")
	)
	(gr_poly
		(pts
			(arc
				(start 20.944078 -112.771682)
				(mid 21.005375 -112.736626)
				(end 21.072094 -112.713516)
			)
			(xy 21.08581 -112.70996) (xy 21.233384 -112.562386)
			(arc
				(start 21.233384 -111.704374)
				(mid 21.05858 -111.383826)
				(end 21.233384 -111.063278)
			)
			(xy 21.233384 -110.688882) (xy 21.461984 -110.460282) (xy 24.281384 -110.460282) (xy 25.576784 -109.164882)
			(xy 27.659584 -109.164882) (xy 27.684984 -109.139482) (xy 27.684984 -108.885482) (xy 27.659584 -108.860082)
			(xy 26.110184 -108.860082) (xy 25.957784 -108.707682) (xy 24.382984 -108.707682) (xy 24.154384 -108.479082)
			(xy 22.985984 -108.479082) (xy 22.909784 -108.555282) (xy 22.909784 -109.215682) (xy 22.757384 -109.368082)
			(xy 20.496784 -109.368082) (xy 20.293584 -109.571282) (xy 20.293584 -112.644682) (xy 20.420584 -112.771682)
		)
		(stroke
			(width 0)
			(type solid)
		)
		(fill yes)
		(layer "F.Cu")
		(net "P3V3_ADC128_VCC")
	)
	(gr_poly
		(pts
			(xy 222.453962 -77.677518) (xy 222.453962 -70.081394) (xy 222.389446 -70.017132) (xy 222.255588 -70.017132)
			(xy 222.215202 -70.057518) (xy 222.215202 -71.711058) (xy 222.178372 -71.747888) (xy 222.178372 -71.774304)
			(xy 221.986602 -71.966328) (xy 221.959932 -71.966328) (xy 221.945962 -71.980298) (xy 221.631002 -71.980298)
			(xy 221.617032 -71.966328) (xy 221.603316 -71.966328) (xy 221.389956 -71.752714) (xy 221.389956 -70.507098)
			(xy 221.234762 -70.507098) (xy 221.201742 -70.540118) (xy 221.201742 -72.912478) (xy 220.73108 -73.38314)
			(xy 220.73108 -73.6346) (xy 220.730572 -73.648062) (xy 220.730572 -74.431652)
			(arc
				(start 220.73235 -74.438256)
				(mid 220.738271 -74.467711)
				(end 220.740224 -74.497692)
			)
			(xy 220.740224 -74.765408) (xy 220.730572 -74.765408) (xy 220.730572 -74.971656) (xy 220.68028 -75.021948)
			(xy 220.68028 -75.030076) (xy 220.672152 -75.030076) (xy 220.65488 -75.047348) (xy 219.795344 -75.047348)
			(xy 219.74429 -75.098656) (xy 218.876372 -75.098656) (xy 218.77528 -75.199748) (xy 218.77528 -75.936348)
			(xy 218.859354 -76.020422) (xy 218.859354 -77.297788) (xy 219.610432 -78.048866) (xy 222.082614 -78.048866)
		)
		(stroke
			(width 0)
			(type solid)
		)
		(fill yes)
		(layer "F.Cu")
		(net "P3V3_AUX")
	)
	(gr_poly
		(pts
			(xy 454.669652 -28.660598) (xy 454.669652 -26.497788) (xy 454.583292 -26.411428) (xy 452.43242 -26.411428)
			(xy 452.07682 -26.055828) (xy 452.07682 -25.265888) (xy 452.1073 -25.235408) (xy 452.1073 -20.163028)
			(xy 452.084948 -20.140676) (xy 451.926452 -20.140676) (xy 451.87616 -20.190968) (xy 451.87616 -21.885148)
			(xy 451.72884 -22.032468) (xy 451.725284 -22.032468) (xy 451.66407 -22.093936) (xy 451.33641 -22.093936)
			(xy 451.275196 -22.032468) (xy 451.20052 -22.032468) (xy 451.09892 -21.930868) (xy 451.09892 -20.655788)
			(xy 451.06082 -20.617688) (xy 450.93636 -20.617688) (xy 450.86778 -20.686268) (xy 450.86778 -22.33549)
			(arc
				(start 450.86905 -22.341332)
				(mid 450.876279 -22.383605)
				(end 450.878702 -22.426422)
			)
			(arc
				(start 450.878702 -22.426422)
				(mid 450.876263 -22.469237)
				(end 450.86905 -22.511512)
			)
			(xy 450.86778 -22.517354) (xy 450.86778 -24.788368) (xy 450.4182 -25.237948) (xy 448.92468 -25.237948)
			(xy 448.08648 -26.076148) (xy 446.309242 -26.076148) (xy 444.909702 -27.475688) (xy 440.667902 -27.475688)
			(xy 440.592972 -27.550618) (xy 440.592972 -28.795218) (xy 440.669172 -28.871418) (xy 445.161416 -28.871418)
			(xy 446.304416 -30.014418) (xy 453.315832 -30.014418)
		)
		(stroke
			(width 0)
			(type solid)
		)
		(fill yes)
		(layer "F.Cu")
		(net "P12V_AUX")
	)
	(gr_poly
		(pts
			(xy 458.6478 -57.622948) (xy 458.6478 -50.7619) (xy 458.2668 -50.3809) (xy 447.063622 -50.3809) (xy 446.044574 -51.399948)
			(xy 436.69458 -51.399948) (xy 436.18658 -51.907948) (xy 436.18658 -52.738528) (xy 448.662552 -52.738528)
			(xy 448.662552 -51.214528) (xy 448.663053 -51.201147) (xy 448.669971 -51.175296) (xy 448.683345 -51.152116)
			(xy 448.702262 -51.133186) (xy 448.725433 -51.119798) (xy 448.75128 -51.112862) (xy 448.76466 -51.11242)
			(xy 450.28866 -51.11242) (xy 450.302051 -51.112825) (xy 450.327922 -51.119749) (xy 450.351118 -51.133136)
			(xy 450.370057 -51.152072) (xy 450.383446 -51.175267) (xy 450.390374 -51.201137) (xy 450.390768 -51.214528)
			(xy 450.390768 -52.738528) (xy 450.390434 -52.751923) (xy 450.383493 -52.777798) (xy 450.370091 -52.800995)
			(xy 450.351141 -52.819932) (xy 450.327935 -52.833319) (xy 450.302055 -52.840243) (xy 450.28866 -52.840636)
			(xy 448.76466 -52.840636) (xy 448.751275 -52.840206) (xy 448.72542 -52.833271) (xy 448.702239 -52.819882)
			(xy 448.683311 -52.800952) (xy 448.669925 -52.777769) (xy 448.662992 -52.751913) (xy 448.662552 -52.738528)
			(xy 436.18658 -52.738528) (xy 436.18658 -57.602882) (xy 436.605172 -58.021728) (xy 458.24902 -58.021728)
		)
		(stroke
			(width 0)
			(type solid)
		)
		(fill yes)
		(layer "F.Cu")
		(net "P3V3_AUX")
	)
	(gr_poly
		(pts
			(xy 105.675938 -237.93831) (xy 105.675938 -237.32871) (xy 106.170476 -236.834172) (xy 108.83011 -236.834172)
			(xy 108.956094 -236.708188) (xy 108.956094 -235.826046) (xy 108.313982 -235.183934)
			(arc
				(start 106.63682 -235.183934)
				(mid 106.553746 -235.227042)
				(end 106.541062 -235.319824)
			)
			(arc
				(start 106.541062 -235.319824)
				(mid 106.555676 -235.374858)
				(end 106.56062 -235.431584)
			)
			(arc
				(start 106.56062 -235.431584)
				(mid 106.463832 -235.66525)
				(end 106.230166 -235.762038)
			)
			(arc
				(start 106.230166 -235.762038)
				(mid 106.062222 -235.71618)
				(end 105.94086 -235.59135)
			)
			(xy 105.926382 -235.565188) (xy 104.483662 -235.565188) (xy 104.365044 -235.683806) (xy 104.365044 -236.730286)
			(xy 104.913938 -237.27918) (xy 104.913938 -237.93831) (xy 105.066338 -238.09071) (xy 105.523538 -238.09071)
		)
		(stroke
			(width 0)
			(type solid)
		)
		(fill yes)
		(layer "F.Cu")
		(net "PVNN_MAIN_CPU1")
	)
	(gr_poly
		(pts
			(arc
				(start 261.18058 -96.068896)
				(mid 261.244497 -96.046145)
				(end 261.311898 -96.038416)
			)
			(xy 262.210042 -96.038416)
			(arc
				(start 262.217916 -96.035876)
				(mid 262.269369 -96.022612)
				(end 262.32231 -96.018096)
			)
			(xy 262.769096 -96.018096) (xy 263.518142 -95.269304) (xy 263.518142 -93.184472) (xy 263.307322 -92.973652)
			(xy 262.129524 -92.973652) (xy 261.944104 -93.159072) (xy 261.944104 -94.276164) (xy 261.936992 -94.283276)
			(xy 261.936992 -94.46514) (xy 261.935468 -94.466664)
			(arc
				(start 261.934706 -94.486222)
				(mid 261.777187 -94.829194)
				(end 261.426706 -94.96933)
			)
			(xy 261.394956 -94.968314) (xy 261.372096 -94.96679) (xy 261.184644 -95.153988)
			(arc
				(start 261.184644 -95.340678)
				(mid 261.160345 -95.462749)
				(end 261.091172 -95.56623)
			)
			(xy 260.872224 -95.785432) (xy 260.872224 -95.809308) (xy 261.147814 -96.084898)
		)
		(stroke
			(width 0)
			(type solid)
		)
		(fill yes)
		(layer "F.Cu")
		(net "P3V3_AUX_CLK_GEN_VDD_CK440")
	)
	(gr_poly
		(pts
			(xy 353.615752 -237.938056) (xy 353.615752 -237.328456) (xy 354.11029 -236.833918) (xy 356.769924 -236.833918)
			(xy 356.895908 -236.707934) (xy 356.895908 -235.825792) (xy 356.253796 -235.18368)
			(arc
				(start 354.809298 -235.18368)
				(mid 354.738632 -235.21228)
				(end 354.707698 -235.281978)
			)
			(arc
				(start 354.707698 -235.281978)
				(mid 354.607304 -235.50866)
				(end 354.377498 -235.601764)
			)
			(arc
				(start 354.377498 -235.601764)
				(mid 354.226 -235.56499)
				(end 354.108258 -235.462826)
			)
			(arc
				(start 354.108258 -235.462826)
				(mid 354.033925 -235.420476)
				(end 353.953572 -235.449872)
			)
			(xy 353.83851 -235.564934) (xy 352.423476 -235.564934) (xy 352.304858 -235.683552) (xy 352.304858 -236.730032)
			(xy 352.853752 -237.278926) (xy 352.853752 -237.938056) (xy 353.006152 -238.090456) (xy 353.463352 -238.090456)
		)
		(stroke
			(width 0)
			(type solid)
		)
		(fill yes)
		(layer "F.Cu")
		(net "PVNN_MAIN_CPU0")
	)
	(gr_poly
		(pts
			(xy 253.31547 -46.303692) (xy 254.742188 -46.303692) (xy 256.735072 -44.3103) (xy 256.735072 -43.09745)
			(xy 256.676144 -43.038522) (xy 255.17729 -43.038522) (xy 255.12649 -43.089322) (xy 255.12649 -44.725336)
			(xy 254.84328 -45.008546) (xy 254.368554 -45.008546) (xy 254.22987 -44.869862) (xy 252.83287 -44.869862)
			(xy 252.814836 -44.851828) (xy 252.772164 -44.851828) (xy 252.772164 -44.809156) (xy 252.70333 -44.740322)
			(xy 252.70333 -42.266362) (xy 252.81255 -42.157142) (xy 253.13259 -42.157142) (xy 253.20625 -42.083482)
			(xy 253.20625 -41.999662) (xy 253.13005 -41.923462) (xy 252.51029 -41.923462) (xy 252.46965 -41.964102)
			(xy 252.46965 -42.685462) (xy 251.808488 -43.346624)
			(arc
				(start 251.808488 -43.742864)
				(mid 251.854849 -43.842845)
				(end 251.870718 -43.951906)
			)
			(arc
				(start 251.870718 -43.951906)
				(mid 251.854871 -44.060974)
				(end 251.808488 -44.160948)
			)
			(arc
				(start 251.808488 -44.441872)
				(mid 251.804753 -44.49006)
				(end 251.793756 -44.537122)
			)
			(xy 251.79147 -44.544742) (xy 251.79147 -44.909994) (xy 251.653802 -45.047662) (xy 251.02947 -45.047662)
			(xy 250.97867 -45.098462) (xy 250.97867 -45.893736) (xy 251.38888 -46.303946) (xy 253.315216 -46.303946)
		)
		(stroke
			(width 0)
			(type solid)
		)
		(fill yes)
		(layer "F.Cu")
		(net "GND")
	)
	(gr_poly
		(pts
			(arc
				(start 184.18048 -403.693884)
				(mid 184.169624 -403.644112)
				(end 184.166002 -403.5933)
			)
			(arc
				(start 184.166002 -403.5933)
				(mid 184.169645 -403.542491)
				(end 184.18048 -403.492716)
			)
			(xy 184.18048 -402.440648) (xy 183.19877 -402.440648) (xy 183.079898 -402.321522)
			(arc
				(start 182.861458 -402.321522)
				(mid 182.773238 -402.363684)
				(end 182.676546 -402.378164)
			)
			(arc
				(start 182.676546 -402.378164)
				(mid 182.595454 -402.368004)
				(end 182.51932 -402.338286)
			)
			(xy 182.50789 -402.331936)
			(arc
				(start 182.240428 -402.331936)
				(mid 182.201559 -402.329762)
				(end 182.163212 -402.323046)
			)
			(xy 182.15737 -402.321522) (xy 181.851808 -402.321522) (xy 181.765448 -402.407882) (xy 181.765448 -402.47824)
			(xy 181.951376 -402.664168)
			(arc
				(start 182.23865 -402.664168)
				(mid 182.357191 -402.591463)
				(end 182.49392 -402.566124)
			)
			(arc
				(start 182.6768 -402.566124)
				(mid 182.865704 -402.616213)
				(end 183.004968 -402.753322)
			)
			(xy 183.114188 -402.753322) (xy 183.177688 -402.816822) (xy 183.177688 -404.439882) (xy 183.213248 -404.475442)
			(xy 184.18048 -404.475442)
		)
		(stroke
			(width 0)
			(type solid)
		)
		(fill yes)
		(layer "F.Cu")
		(net "AGND_HSC")
	)
	(gr_poly
		(pts
			(xy 105.692956 -258.521454)
			(arc
				(start 105.692956 -258.103878)
				(mid 105.651126 -258.021465)
				(end 105.55986 -258.007104)
			)
			(arc
				(start 105.55986 -258.007104)
				(mid 105.509079 -258.019435)
				(end 105.45699 -258.023614)
			)
			(arc
				(start 105.45699 -258.023614)
				(mid 105.126536 -257.69316)
				(end 105.45699 -257.362706)
			)
			(arc
				(start 105.45699 -257.362706)
				(mid 105.509081 -257.366878)
				(end 105.55986 -257.379216)
			)
			(arc
				(start 105.55986 -257.379216)
				(mid 105.651084 -257.364798)
				(end 105.692956 -257.282442)
			)
			(xy 105.692956 -256.929636) (xy 105.550716 -256.787396) (xy 103.01605 -256.787396) (xy 102.74935 -257.054096)
			(xy 102.74935 -258.512564) (xy 102.84714 -258.610354) (xy 105.604056 -258.610354)
		)
		(stroke
			(width 0)
			(type solid)
		)
		(fill yes)
		(layer "F.Cu")
		(net "PVCCFA_EHV_CPU1")
	)
	(gr_poly
		(pts
			(xy 235.27512 -252.705108) (xy 235.27512 -251.978668) (xy 235.39196 -251.861828) (xy 236.71276 -251.861828)
			(xy 236.85246 -252.001528) (xy 237.5154 -252.001528) (xy 237.55604 -251.960888) (xy 237.55604 -251.800868)
			(xy 237.50778 -251.752608) (xy 237.01248 -251.752608) (xy 236.9566 -251.696728) (xy 236.9566 -251.562108)
			(xy 237.00232 -251.516388) (xy 237.47984 -251.516388) (xy 237.54334 -251.452888) (xy 237.54334 -251.295408)
			(xy 237.50524 -251.257308) (xy 236.73562 -251.257308) (xy 236.59084 -251.112528) (xy 236.59084 -249.466608)
			(xy 236.78388 -249.273568) (xy 236.78388 -248.547128) (xy 236.74324 -248.506488) (xy 236.59084 -248.506488)
			(xy 236.5121 -248.585228) (xy 236.5121 -249.070368) (xy 236.41304 -249.169428) (xy 235.38434 -249.169428)
			(xy 235.2802 -249.065288) (xy 235.2802 -248.524268) (xy 235.23956 -248.483628) (xy 235.1024 -248.483628)
			(xy 235.02112 -248.564908) (xy 235.02112 -249.128788) (xy 234.74934 -249.400568) (xy 234.2642 -249.400568)
			(xy 234.188 -249.476768) (xy 234.188 -250.609608) (xy 234.03814 -250.759468) (xy 233.32694 -250.759468)
			(xy 233.25836 -250.828048) (xy 233.25836 -250.975368) (xy 233.29392 -251.010928) (xy 233.98988 -251.010928)
			(xy 234.188 -251.209048) (xy 234.188 -251.788168) (xy 234.24642 -251.846588) (xy 234.93984 -251.846588)
			(xy 235.04906 -251.955808) (xy 235.04906 -252.727968) (xy 235.0897 -252.768608) (xy 235.21162 -252.768608)
		)
		(stroke
			(width 0)
			(type solid)
		)
		(fill yes)
		(layer "F.Cu")
		(net "GND")
	)
	(gr_poly
		(pts
			(xy 353.63277 -258.5212)
			(arc
				(start 353.63277 -258.103624)
				(mid 353.59094 -258.021211)
				(end 353.499674 -258.00685)
			)
			(arc
				(start 353.499674 -258.00685)
				(mid 353.448893 -258.019181)
				(end 353.396804 -258.02336)
			)
			(arc
				(start 353.396804 -258.02336)
				(mid 353.06635 -257.692906)
				(end 353.396804 -257.362452)
			)
			(arc
				(start 353.396804 -257.362452)
				(mid 353.448895 -257.366624)
				(end 353.499674 -257.378962)
			)
			(arc
				(start 353.499674 -257.378962)
				(mid 353.590898 -257.364544)
				(end 353.63277 -257.282188)
			)
			(xy 353.63277 -256.929382) (xy 353.49053 -256.787142) (xy 350.955864 -256.787142) (xy 350.689164 -257.053842)
			(xy 350.689164 -258.51231) (xy 350.786954 -258.6101) (xy 353.54387 -258.6101)
		)
		(stroke
			(width 0)
			(type solid)
		)
		(fill yes)
		(layer "F.Cu")
		(net "PVCCFA_EHV_CPU0")
	)
	(gr_poly
		(pts
			(xy 22.583902 -392.18743) (xy 22.583902 -391.58799) (xy 22.731222 -391.44067) (xy 23.493222 -391.44067)
			(xy 23.676102 -391.25779) (xy 23.676102 -390.93267) (xy 23.856442 -390.75233) (xy 24.407622 -390.75233)
			(xy 24.445722 -390.71423) (xy 24.445722 -390.63041) (xy 24.415242 -390.59993) (xy 23.876762 -390.59993)
			(xy 23.729442 -390.45261) (xy 23.729442 -389.98525) (xy 23.612602 -389.86841) (xy 22.743922 -389.86841)
			(xy 22.583902 -389.70839) (xy 22.583902 -389.16991) (xy 22.550882 -389.13689) (xy 22.083522 -389.13689)
			(xy 22.045422 -389.17499) (xy 22.045422 -389.75665) (xy 21.928582 -389.87349) (xy 21.545042 -389.87349)
			(xy 21.392642 -389.72109) (xy 21.392642 -389.18769) (xy 21.352002 -389.14705) (xy 21.273262 -389.14705)
			(xy 21.232622 -389.18769) (xy 21.232622 -389.78713) (xy 21.148802 -389.87095) (xy 20.521422 -389.87095)
			(xy 20.320762 -390.07161) (xy 20.320762 -390.41959) (xy 20.122642 -390.61771) (xy 19.398742 -390.61771)
			(xy 19.375882 -390.64057) (xy 19.375882 -390.71677) (xy 19.396202 -390.73709) (xy 20.104862 -390.73709)
			(xy 20.236942 -390.86917) (xy 20.236942 -391.28827) (xy 20.343622 -391.39495) (xy 20.993862 -391.39495)
			(xy 21.245322 -391.64641) (xy 21.245322 -392.18235) (xy 21.268182 -392.20521) (xy 21.357082 -392.20521)
			(xy 21.379942 -392.18235) (xy 21.379942 -391.61339) (xy 21.580602 -391.41273) (xy 22.266402 -391.41273)
			(xy 22.446742 -391.59307) (xy 22.446742 -392.17981) (xy 22.474682 -392.20775) (xy 22.563582 -392.20775)
		)
		(stroke
			(width 0)
			(type solid)
		)
		(fill yes)
		(layer "F.Cu")
		(net "GND")
	)
	(gr_poly
		(pts
			(xy 427.797976 -108.535216) (xy 427.797976 -106.99623) (xy 429.339756 -105.45445) (xy 430.207928 -105.45445)
			(arc
				(start 430.212754 -105.453434)
				(mid 430.250536 -105.447712)
				(end 430.2887 -105.445814)
			)
			(arc
				(start 430.2887 -105.445814)
				(mid 430.326863 -105.447728)
				(end 430.364646 -105.453434)
			)
			(xy 430.369472 -105.45445) (xy 432.639216 -105.45445) (xy 432.700176 -105.39349) (xy 432.700176 -105.27411)
			(xy 432.636676 -105.21061) (xy 430.782476 -105.21061) (xy 430.599596 -105.02773) (xy 430.599596 -104.62895)
			(xy 430.777396 -104.45115) (xy 432.141376 -104.45115) (xy 432.197256 -104.39527) (xy 432.197256 -104.25049)
			(xy 432.148996 -104.20223) (xy 430.945036 -104.20223) (xy 430.665636 -103.92283) (xy 428.03064 -103.92283)
			(xy 427.22038 -103.11257) (xy 427.22038 -100.330508) (xy 427.47438 -100.076508) (xy 429.74514 -100.076508)
			(xy 430.39792 -99.423728) (xy 430.39792 -96.553528) (xy 431.3809 -95.570548) (xy 431.3809 -94.496128)
			(xy 431.62474 -94.252288) (xy 432.33848 -94.252288) (xy 432.48072 -94.110048) (xy 432.48072 -93.723968)
			(xy 432.35372 -93.596968) (xy 425.19092 -93.596968) (xy 422.7957 -95.992188) (xy 422.7957 -99.357688)
			(xy 423.43324 -99.995228) (xy 423.43324 -103.482648) (xy 422.10482 -104.811068) (xy 420.84244 -104.811068)
			(xy 420.807388 -104.846374) (xy 420.807388 -105.570528) (xy 421.56126 -105.570528) (xy 421.73398 -105.743248)
			(xy 424.553888 -105.743248) (xy 424.779948 -105.969308) (xy 424.779948 -108.813346) (xy 424.942508 -108.975906)
			(xy 427.357286 -108.975906)
		)
		(stroke
			(width 0)
			(type solid)
		)
		(fill yes)
		(layer "F.Cu")
		(net "P3V3_OCP_SFF_R")
	)
	(gr_poly
		(pts
			(xy 108.61675 -256.413) (xy 108.61675 -255.30048) (xy 108.502958 -255.186688) (xy 103.760778 -255.186688)
			(xy 103.50373 -254.92964) (xy 103.50373 -253.103126) (xy 103.78567 -252.821186) (xy 108.553504 -252.821186)
			(xy 108.63453 -252.74016) (xy 108.63453 -251.59462) (xy 108.544868 -251.504958) (xy 103.756968 -251.504958)
			(xy 103.51389 -251.26188) (xy 103.51389 -249.42673) (xy 103.74757 -249.19305) (xy 108.5596 -249.19305)
			(xy 108.62945 -249.1232) (xy 108.62945 -247.9548) (xy 108.515912 -247.841262) (xy 103.283766 -247.841262)
			(xy 103.277162 -247.847866) (xy 102.667816 -247.847866) (xy 102.617778 -247.897904) (xy 102.617778 -248.003822)
			(xy 102.611428 -248.010172)
			(arc
				(start 102.611428 -253.141734)
				(mid 102.682049 -253.253716)
				(end 102.706678 -253.383796)
			)
			(xy 102.706678 -253.906274) (xy 102.706932 -253.90729)
			(arc
				(start 102.707186 -253.919736)
				(mid 102.682399 -254.05003)
				(end 102.611428 -254.162052)
			)
			(arc
				(start 102.611428 -254.76962)
				(mid 102.682306 -254.881679)
				(end 102.707186 -255.011936)
			)
			(arc
				(start 102.707186 -255.547622)
				(mid 102.682399 -255.677916)
				(end 102.611428 -255.789938)
			)
			(xy 102.611428 -256.33807) (xy 102.78491 -256.511552) (xy 108.518198 -256.511552)
		)
		(stroke
			(width 0)
			(type solid)
		)
		(fill yes)
		(layer "F.Cu")
		(net "GND")
	)
	(gr_poly
		(pts
			(xy 356.556564 -256.412746) (xy 356.556564 -255.300226) (xy 356.442772 -255.186434) (xy 351.700592 -255.186434)
			(xy 351.443544 -254.929386) (xy 351.443544 -253.102872) (xy 351.725484 -252.820932) (xy 356.493318 -252.820932)
			(xy 356.574344 -252.739906) (xy 356.574344 -251.594366) (xy 356.484682 -251.504704) (xy 351.696782 -251.504704)
			(xy 351.453704 -251.261626) (xy 351.453704 -249.426476) (xy 351.687384 -249.192796) (xy 356.499414 -249.192796)
			(xy 356.569264 -249.122946) (xy 356.569264 -247.954546) (xy 356.455726 -247.841008) (xy 351.22358 -247.841008)
			(xy 351.216976 -247.847612) (xy 350.60763 -247.847612) (xy 350.557592 -247.89765) (xy 350.557592 -248.003568)
			(xy 350.551242 -248.009918)
			(arc
				(start 350.551242 -253.14148)
				(mid 350.62204 -253.253553)
				(end 350.646746 -253.383796)
			)
			(xy 350.646746 -253.906274) (xy 350.647 -253.90729)
			(arc
				(start 350.647254 -253.919736)
				(mid 350.62232 -254.050147)
				(end 350.551242 -254.162306)
			)
			(arc
				(start 350.551242 -254.769366)
				(mid 350.622378 -254.881502)
				(end 350.647254 -255.011936)
			)
			(arc
				(start 350.647254 -255.547622)
				(mid 350.62232 -255.678033)
				(end 350.551242 -255.790192)
			)
			(xy 350.551242 -256.337816) (xy 350.724724 -256.511298) (xy 356.458012 -256.511298)
		)
		(stroke
			(width 0)
			(type solid)
		)
		(fill yes)
		(layer "F.Cu")
		(net "GND")
	)
	(gr_poly
		(pts
			(xy 87.66175 -57.2135) (xy 88.350598 -57.2135) (xy 88.57234 -56.992012) (xy 88.57234 -54.800246)
			(xy 83.728814 -54.800246) (xy 83.7184 -54.81066) (xy 82.495136 -54.81066) (xy 82.43443 -54.871366)
			(xy 82.43443 -54.985666) (xy 82.48777 -55.039006) (xy 84.14131 -55.039006) (xy 84.163916 -55.061612)
			(xy 84.2137 -55.061612) (xy 84.426044 -55.273956) (xy 84.426044 -55.604156) (xy 84.41055 -55.61965)
			(xy 84.41055 -55.623206) (xy 84.22005 -55.813706) (xy 84.216494 -55.813706) (xy 84.21624 -55.81396)
			(xy 82.985356 -55.81396) (xy 82.93735 -55.861966) (xy 82.93735 -56.019446) (xy 82.97037 -56.052466)
			(xy 85.163406 -56.052466) (xy 85.165438 -56.052212) (xy 85.194648 -56.051196) (xy 85.223858 -56.052212)
			(xy 85.22589 -56.052466) (xy 85.34273 -56.052466) (xy 85.403944 -56.11368)
			(arc
				(start 85.443314 -56.11368)
				(mid 85.565385 -56.137979)
				(end 85.668866 -56.207152)
			)
			(xy 85.985096 -56.523128)
			(arc
				(start 86.064852 -56.523128)
				(mid 86.225688 -56.588798)
				(end 86.292436 -56.749188)
			)
			(xy 86.292436 -56.779922) (xy 86.508336 -56.995568)
			(arc
				(start 86.541356 -56.995568)
				(mid 86.66347 -57.01997)
				(end 86.766908 -57.089294)
			)
			(xy 86.95436 -57.276492) (xy 87.599012 -57.276492)
		)
		(stroke
			(width 0)
			(type solid)
		)
		(fill yes)
		(layer "F.Cu")
		(net "P3V3_AUX")
	)
	(gr_poly
		(pts
			(xy 79.988918 -28.375102) (xy 79.988918 -22.762464)
			(arc
				(start 79.987394 -22.756114)
				(mid 79.978113 -22.708377)
				(end 79.974948 -22.659848)
			)
			(arc
				(start 79.974948 -22.659848)
				(mid 79.97808 -22.611314)
				(end 79.987394 -22.563582)
			)
			(xy 79.988918 -22.557232) (xy 79.988918 -21.122386) (xy 79.978504 -21.111972) (xy 79.978504 -19.888708)
			(xy 79.917798 -19.828002) (xy 79.803498 -19.828002) (xy 79.750158 -19.881342) (xy 79.750158 -21.534882)
			(xy 79.727552 -21.557488) (xy 79.727552 -21.607272) (xy 79.515208 -21.819616) (xy 79.185008 -21.819616)
			(xy 79.169514 -21.804122) (xy 79.165958 -21.804122) (xy 78.975458 -21.613622) (xy 78.975458 -21.610066)
			(xy 78.975204 -21.609812) (xy 78.975204 -20.378928) (xy 78.927198 -20.330922) (xy 78.769718 -20.330922)
			(xy 78.736698 -20.363942) (xy 78.736698 -22.736302) (xy 78.467966 -23.005034)
			(arc
				(start 78.467966 -24.056594)
				(mid 78.541961 -24.175902)
				(end 78.567788 -24.313896)
			)
			(arc
				(start 78.567788 -24.313896)
				(mid 78.545072 -24.443532)
				(end 78.47965 -24.557736)
			)
			(xy 78.467966 -24.57196) (xy 78.467966 -24.626062) (xy 78.23708 -24.856948) (xy 76.30668 -24.856948)
			(xy 74.939906 -26.223722) (xy 71.195438 -26.223722) (xy 70.271132 -27.148028) (xy 69.914516 -27.148028)
			(xy 69.906388 -27.156156) (xy 66.021204 -27.156156) (xy 65.912238 -27.265122) (xy 65.912238 -28.509722)
			(xy 66.003424 -28.600908) (xy 70.495668 -28.600908) (xy 71.623682 -29.728922) (xy 78.635098 -29.728922)
		)
		(stroke
			(width 0)
			(type solid)
		)
		(fill yes)
		(layer "F.Cu")
		(net "P12V_AUX")
	)
	(gr_poly
		(pts
			(xy 108.62945 -245.4275) (xy 108.62945 -244.2591) (xy 108.521246 -244.150896) (xy 103.685086 -244.150896)
			(xy 103.53675 -244.00256) (xy 103.53675 -242.020344) (xy 103.72725 -241.829844) (xy 108.493306 -241.829844)
			(xy 108.62183 -241.70132) (xy 108.62183 -240.49736) (xy 108.513626 -240.389156) (xy 103.232966 -240.389156)
			(xy 102.92207 -240.07826) (xy 102.64013 -240.07826) (xy 102.580694 -240.137696) (xy 102.580694 -240.488216)
			(arc
				(start 102.593648 -240.518442)
				(mid 102.616236 -240.591218)
				(end 102.623874 -240.667032)
			)
			(arc
				(start 102.623874 -241.203734)
				(mid 102.601114 -241.333235)
				(end 102.535736 -241.44732)
			)
			(arc
				(start 102.535736 -242.051078)
				(mid 102.601139 -242.165154)
				(end 102.623874 -242.294664)
			)
			(arc
				(start 102.623874 -242.83162)
				(mid 102.601114 -242.961121)
				(end 102.535736 -243.075206)
			)
			(arc
				(start 102.535736 -243.720874)
				(mid 102.582425 -243.817079)
				(end 102.598474 -243.922804)
			)
			(arc
				(start 102.598474 -243.922804)
				(mid 102.59598 -243.964627)
				(end 102.588568 -244.005862)
			)
			(xy 102.587298 -244.01145)
			(arc
				(start 102.587298 -244.458744)
				(mid 102.574121 -244.552883)
				(end 102.535736 -244.639846)
			)
			(xy 102.535736 -245.235476) (xy 102.811834 -245.511574) (xy 108.545376 -245.511574)
		)
		(stroke
			(width 0)
			(type solid)
		)
		(fill yes)
		(layer "F.Cu")
		(net "GND")
	)
	(gr_poly
		(pts
			(xy 356.569264 -245.427246) (xy 356.569264 -244.258846) (xy 356.46106 -244.150642) (xy 351.6249 -244.150642)
			(xy 351.476564 -244.002306) (xy 351.476564 -242.02009) (xy 351.667064 -241.82959) (xy 356.43312 -241.82959)
			(xy 356.561644 -241.701066) (xy 356.561644 -240.497106) (xy 356.45344 -240.388902) (xy 351.17278 -240.388902)
			(xy 350.861884 -240.078006) (xy 350.579944 -240.078006) (xy 350.520508 -240.137442) (xy 350.520508 -240.487962)
			(arc
				(start 350.533462 -240.518188)
				(mid 350.55605 -240.590964)
				(end 350.563688 -240.666778)
			)
			(arc
				(start 350.563688 -241.20348)
				(mid 350.540928 -241.332981)
				(end 350.47555 -241.447066)
			)
			(arc
				(start 350.47555 -242.050824)
				(mid 350.540953 -242.1649)
				(end 350.563688 -242.29441)
			)
			(arc
				(start 350.563688 -242.831366)
				(mid 350.540928 -242.960867)
				(end 350.47555 -243.074952)
			)
			(arc
				(start 350.47555 -243.72062)
				(mid 350.522444 -243.816916)
				(end 350.538542 -243.922804)
			)
			(arc
				(start 350.538542 -243.922804)
				(mid 350.536093 -243.965011)
				(end 350.528636 -244.006624)
			)
			(xy 350.527112 -244.012466)
			(arc
				(start 350.527112 -244.45849)
				(mid 350.513935 -244.552629)
				(end 350.47555 -244.639592)
			)
			(xy 350.47555 -245.235222) (xy 350.751648 -245.51132) (xy 356.48519 -245.51132)
		)
		(stroke
			(width 0)
			(type solid)
		)
		(fill yes)
		(layer "F.Cu")
		(net "GND")
	)
	(gr_poly
		(pts
			(xy 446.56502 -24.933148) (xy 449.40728 -24.933148) (xy 449.498212 -24.842216) (xy 449.498212 -23.324058)
			(xy 449.447412 -23.273258) (xy 447.110612 -23.273258) (xy 447.076322 -23.238968)
			(arc
				(start 447.063114 -23.235412)
				(mid 446.858931 -23.099237)
				(end 446.779904 -22.866858)
			)
			(arc
				(start 446.779904 -22.866858)
				(mid 446.84871 -22.648225)
				(end 447.030348 -22.508464)
			)
			(xy 447.041016 -22.504654) (xy 447.059812 -22.485858) (xy 447.14287 -22.485858) (xy 447.161412 -22.48535)
			(xy 447.179954 -22.485858) (xy 447.557652 -22.485858) (xy 447.666872 -22.376638) (xy 447.666872 -20.979638)
			(xy 447.684652 -20.961604) (xy 447.684652 -20.918932) (xy 447.727832 -20.918932) (xy 447.796412 -20.850098)
			(xy 450.270372 -20.850098) (xy 450.379592 -20.959318) (xy 450.379592 -21.279358) (xy 450.453252 -21.353018)
			(xy 450.537072 -21.353018) (xy 450.613272 -21.276818) (xy 450.613272 -20.657058) (xy 450.572632 -20.616418)
			(xy 449.851272 -20.616418) (xy 449.173092 -19.938238) (xy 447.62674 -19.938238) (xy 447.489072 -19.80057)
			(xy 447.489072 -19.176238) (xy 447.438272 -19.125438) (xy 446.113408 -19.125438) (xy 446.113408 -24.042878)
			(xy 445.87541 -24.280876) (xy 445.81064 -24.280876) (xy 445.29375 -24.797512) (xy 445.214502 -24.797512)
			(xy 444.74638 -25.265888) (xy 444.74638 -25.745948) (xy 445.75222 -25.745948)
		)
		(stroke
			(width 0)
			(type solid)
		)
		(fill yes)
		(layer "F.Cu")
		(net "GND")
	)
	(gr_poly
		(pts
			(xy 66.22288 -9.25068) (xy 66.22288 -9.035288) (xy 66.4591 -8.799068) (xy 66.4591 -6.713728) (xy 66.3829 -6.637528)
			(xy 63.38316 -6.637528) (xy 62.65672 -7.363968) (xy 62.65672 -9.03986) (xy 63.0555 -9.03986) (xy 63.0555 -7.6327)
			(xy 63.09106 -7.59714) (xy 63.25616 -7.59714) (xy 63.27394 -7.61492) (xy 63.27394 -9.0297) (xy 63.26378 -9.03986)
			(xy 63.65748 -9.03986) (xy 63.65748 -7.61492) (xy 63.68034 -7.59206) (xy 63.84544 -7.59206) (xy 63.87084 -7.61746)
			(xy 63.87084 -9.01954) (xy 63.85814 -9.03224) (xy 64.25692 -9.03224) (xy 64.25692 -7.59968) (xy 64.27216 -7.58444)
			(xy 64.45504 -7.58444) (xy 64.47282 -7.60222) (xy 64.47282 -9.03224) (xy 64.472566 -9.032494) (xy 64.858392 -9.032494)
			(xy 64.858392 -7.617206) (xy 64.878966 -7.596632) (xy 65.049654 -7.596632) (xy 65.072768 -7.619746)
			(xy 65.072768 -9.014714) (xy 65.054988 -9.032494) (xy 65.45834 -9.032494) (xy 65.45834 -7.617206)
			(xy 65.478914 -7.596632) (xy 65.649602 -7.596632) (xy 65.672716 -7.619746) (xy 65.672716 -9.014714)
			(xy 65.644522 -9.042908) (xy 65.468754 -9.042908) (xy 65.45834 -9.032494) (xy 65.054988 -9.032494)
			(xy 65.044574 -9.042908) (xy 64.868806 -9.042908) (xy 64.858392 -9.032494) (xy 64.472566 -9.032494)
			(xy 64.45758 -9.04748) (xy 64.27216 -9.04748) (xy 64.25692 -9.03224) (xy 63.85814 -9.03224) (xy 63.84544 -9.04494)
			(xy 63.66256 -9.04494) (xy 63.65748 -9.03986) (xy 63.26378 -9.03986) (xy 63.2587 -9.04494) (xy 63.06058 -9.04494)
			(xy 63.0555 -9.03986) (xy 62.65672 -9.03986) (xy 62.65672 -9.23036) (xy 62.7634 -9.33704) (xy 66.13652 -9.33704)
		)
		(stroke
			(width 0)
			(type solid)
		)
		(fill yes)
		(layer "F.Cu")
		(net "GND")
	)
	(gr_poly
		(pts
			(arc
				(start 159.50692 -129.230374)
				(mid 159.88792 -128.869393)
				(end 160.26892 -129.230374)
			)
			(xy 160.27146 -129.27838) (xy 160.400746 -129.27838) (xy 160.400746 -129.225548)
			(arc
				(start 160.400492 -129.2098)
				(mid 160.512233 -128.940033)
				(end 160.782 -128.828292)
			)
			(arc
				(start 160.782 -128.828292)
				(mid 161.04235 -128.930934)
				(end 161.162492 -129.183638)
			)
			(arc
				(start 161.162492 -129.183638)
				(mid 161.194572 -129.251078)
				(end 161.264092 -129.27838)
			)
			(xy 162.18916 -129.27838) (xy 162.41776 -129.04978) (xy 162.41776 -127.16764) (xy 162.16884 -126.91872)
			(xy 154.49296 -126.91872) (xy 154.23388 -127.1778) (xy 154.23388 -129.01168) (xy 154.50058 -129.27838)
			(xy 159.50438 -129.27838)
		)
		(stroke
			(width 0)
			(type solid)
		)
		(fill yes)
		(layer "F.Cu")
		(net "P5V")
	)
	(gr_poly
		(pts
			(xy 193.46926 -17.709388) (xy 193.46926 -13.274548) (xy 192.603374 -12.408662) (xy 192.579244 -12.410948)
			(xy 192.530658 -12.415251) (xy 192.433112 -12.415239) (xy 192.336065 -12.405395) (xy 192.28816 -12.396216)
			(xy 192.28308 -12.3952) (xy 190.48984 -12.3952) (xy 190.29426 -12.59078) (xy 190.29426 -13.600176)
			(xy 190.29372 -13.629508) (xy 190.285696 -13.687622) (xy 190.278258 -13.716) (xy 190.27648 -13.722604)
			(xy 190.27648 -14.242288) (xy 190.346838 -14.312646) (xy 190.653416 -14.312646) (xy 190.653416 -12.897358)
			(xy 190.67399 -12.876784) (xy 190.844678 -12.876784) (xy 190.867792 -12.899898) (xy 190.867792 -14.294866)
			(xy 190.839598 -14.32306) (xy 190.66383 -14.32306) (xy 190.653416 -14.312646) (xy 190.346838 -14.312646)
			(xy 190.366904 -14.332712) (xy 190.386462 -14.333728) (xy 190.415436 -14.335739) (xy 190.472325 -14.347433)
			(xy 190.526782 -14.367618) (xy 190.577549 -14.395827) (xy 190.623452 -14.431408) (xy 190.663429 -14.473538)
			(xy 190.696556 -14.521241) (xy 190.709804 -14.547088) (xy 191.46774 -14.547088) (xy 191.65062 -14.729968)
			(xy 191.65062 -15.11554) (xy 191.580008 -15.186152) (xy 191.576452 -15.192756) (xy 191.56077 -15.22086)
			(xy 191.522423 -15.272543) (xy 191.476915 -15.318048) (xy 191.425228 -15.35639) (xy 191.397128 -15.37208)
			(xy 191.390524 -15.375636) (xy 191.20358 -15.56258) (xy 190.561468 -15.56258) (xy 190.28156 -15.842488)
			(xy 190.28156 -17.262602) (xy 190.653416 -17.262602) (xy 190.653416 -15.847314) (xy 190.67399 -15.82674)
			(xy 190.844678 -15.82674) (xy 190.867792 -15.849854) (xy 190.867792 -17.244822) (xy 190.839598 -17.273016)
			(xy 190.66383 -17.273016) (xy 190.653416 -17.262602) (xy 190.28156 -17.262602) (xy 190.28156 -17.772888)
			(xy 190.62192 -18.113248) (xy 193.0654 -18.113248)
		)
		(stroke
			(width 0)
			(type solid)
		)
		(fill yes)
		(layer "F.Cu")
		(net "P12V_SCM")
	)
	(gr_poly
		(pts
			(xy 71.424038 -34.097722) (xy 71.424038 -32.091122) (xy 71.271638 -31.938722) (xy 70.369684 -31.938722)
			(xy 70.369684 -32.150304) (xy 70.429628 -32.150304)
			(arc
				(start 70.429628 -32.41802)
				(mid 70.414649 -32.498939)
				(end 70.371716 -32.56915)
			)
			(xy 70.371716 -32.706818)
			(arc
				(start 70.378828 -32.71901)
				(mid 70.419906 -32.813917)
				(end 70.433946 -32.916368)
			)
			(arc
				(start 70.433946 -32.916368)
				(mid 70.052438 -33.297876)
				(end 69.67093 -32.916368)
			)
			(arc
				(start 69.67093 -32.916368)
				(mid 69.685011 -32.813928)
				(end 69.726048 -32.71901)
			)
			(xy 69.73316 -32.706818)
			(arc
				(start 69.73316 -32.56915)
				(mid 69.690204 -32.498947)
				(end 69.675248 -32.41802)
			)
			(xy 69.675248 -32.150304) (xy 69.735192 -32.150304) (xy 69.735192 -31.938722) (xy 68.782438 -31.938722)
			(xy 68.655438 -32.065722) (xy 68.655438 -32.624522) (xy 68.376038 -32.903922) (xy 66.877438 -32.903922)
			(xy 66.725038 -32.751522) (xy 66.725038 -32.116522) (xy 66.648838 -32.040322) (xy 63.316358 -32.040322)
			(xy 63.229998 -32.126682) (xy 63.229998 -34.209482) (xy 63.372238 -34.351722) (xy 71.170038 -34.351722)
		)
		(stroke
			(width 0)
			(type solid)
		)
		(fill yes)
		(layer "F.Cu")
		(net "GND")
	)
	(gr_poly
		(pts
			(xy 76.15428 -24.602948) (xy 76.201016 -24.602948) (xy 76.20127 -24.60244) (xy 76.916534 -24.60244)
			(xy 77.09408 -24.425148) (xy 77.09408 -23.053548) (xy 77.028294 -22.987762) (xy 74.969878 -22.987762)
			(xy 74.935588 -22.953472)
			(arc
				(start 74.92238 -22.949916)
				(mid 74.718197 -22.813741)
				(end 74.63917 -22.581362)
			)
			(arc
				(start 74.63917 -22.581362)
				(mid 74.707976 -22.362729)
				(end 74.889614 -22.222968)
			)
			(xy 74.900282 -22.219158) (xy 74.919078 -22.200362) (xy 75.002136 -22.200362) (xy 75.020678 -22.199854)
			(xy 75.03922 -22.200362) (xy 75.416918 -22.200362) (xy 75.526138 -22.091142) (xy 75.526138 -20.694142)
			(xy 75.544172 -20.676108) (xy 75.544172 -20.633436) (xy 75.586844 -20.633436) (xy 75.655678 -20.564602)
			(xy 76.56703 -20.564602) (xy 76.56957 -20.564348) (xy 76.6064 -20.56257) (xy 76.64323 -20.564348)
			(xy 76.64577 -20.564602) (xy 78.129638 -20.564602) (xy 78.238858 -20.673822) (xy 78.238858 -20.993862)
			(xy 78.312518 -21.067522) (xy 78.396338 -21.067522) (xy 78.472538 -20.991322) (xy 78.472538 -20.371562)
			(xy 78.431898 -20.330922) (xy 77.710538 -20.330922) (xy 77.032358 -19.652742) (xy 75.486006 -19.652742)
			(xy 75.348338 -19.515074) (xy 75.348338 -18.890742) (xy 75.297538 -18.839942) (xy 73.885298 -18.839942)
			(xy 73.801478 -18.923762) (xy 73.801478 -23.825962) (xy 73.115678 -24.511762) (xy 72.967342 -24.511762)
			(xy 72.967088 -24.512016) (xy 70.533768 -24.512016) (xy 70.067678 -24.978106) (xy 70.067678 -25.400762)
			(xy 70.550278 -25.883362) (xy 74.873866 -25.883362)
		)
		(stroke
			(width 0)
			(type solid)
		)
		(fill yes)
		(layer "F.Cu")
		(net "GND")
	)
	(gr_poly
		(pts
			(xy 117.312948 -239.529874) (xy 117.32867 -239.525631) (xy 117.360927 -239.521172) (xy 117.37721 -239.520984)
			(xy 117.676422 -239.520984) (xy 117.692706 -239.521157) (xy 117.724965 -239.525617) (xy 117.740684 -239.529874)
			(xy 117.747542 -239.531906) (xy 118.32209 -239.531906) (xy 118.328948 -239.529874) (xy 118.34467 -239.525631)
			(xy 118.376927 -239.521172) (xy 118.39321 -239.520984) (xy 118.67896 -239.520984) (xy 118.789196 -239.410748)
			(xy 118.789196 -239.084358) (xy 119.02313 -238.850424) (xy 120.976898 -238.850424) (xy 121.184162 -238.64316)
			(xy 121.184162 -238.29137) (xy 121.1834 -238.286798) (xy 121.180682 -238.27164) (xy 121.17776 -238.240982)
			(xy 121.177558 -238.225584) (xy 121.177774 -238.210187) (xy 121.180704 -238.179531) (xy 121.1834 -238.16437)
			(xy 121.184162 -238.159798) (xy 121.184162 -237.247684) (xy 121.181622 -237.240064) (xy 121.173805 -237.21422)
			(xy 121.165392 -237.160888) (xy 121.164858 -237.133892) (xy 121.165342 -237.106893) (xy 121.173768 -237.053557)
			(xy 121.181622 -237.02772) (xy 121.184162 -237.0201) (xy 121.184162 -236.663738) (xy 121.1834 -236.659166)
			(xy 121.180678 -236.644009) (xy 121.177751 -236.613351) (xy 121.177558 -236.597952) (xy 121.177771 -236.582554)
			(xy 121.180694 -236.551897) (xy 121.1834 -236.536738) (xy 121.184162 -236.532166) (xy 121.184162 -235.619798)
			(xy 121.181622 -235.612178) (xy 121.174256 -235.586016) (xy 121.170954 -235.572046) (xy 120.700292 -235.101384)
			(xy 115.12169 -235.101384) (xy 114.879374 -235.3437) (xy 114.879374 -237.867698) (xy 116.06276 -237.867698)
			(xy 116.06276 -235.838238) (xy 116.442236 -235.458508) (xy 119.667274 -235.458508) (xy 120.209564 -236.001052)
			(xy 120.209564 -237.854236) (xy 119.898668 -238.165132) (xy 116.244116 -238.165132) (xy 116.244116 -238.049054)
			(xy 116.06276 -237.867698) (xy 114.879374 -237.867698) (xy 114.879374 -237.969044) (xy 114.95151 -238.04118)
			(xy 115.582954 -238.04118) (xy 117.07368 -239.531906) (xy 117.30609 -239.531906)
		)
		(stroke
			(width 0)
			(type solid)
		)
		(fill yes)
		(layer "F.Cu")
		(net "GND")
	)
	(gr_poly
		(pts
			(xy 187.739782 -29.486606) (xy 187.739782 -27.987752) (xy 187.688982 -27.936952) (xy 185.352182 -27.936952)
			(xy 185.317892 -27.902662)
			(arc
				(start 185.304684 -27.899106)
				(mid 185.100501 -27.762931)
				(end 185.021474 -27.530552)
			)
			(arc
				(start 185.021474 -27.530552)
				(mid 185.09028 -27.311919)
				(end 185.271918 -27.172158)
			)
			(xy 185.282586 -27.168348) (xy 185.301382 -27.149552) (xy 185.38444 -27.149552) (xy 185.402982 -27.149044)
			(xy 185.421524 -27.149552) (xy 185.799222 -27.149552) (xy 185.908442 -27.040332) (xy 185.908442 -25.643332)
			(xy 185.926476 -25.625552) (xy 185.926476 -25.582372) (xy 185.969148 -25.582372) (xy 186.037982 -25.513792)
			(arc
				(start 186.902344 -25.513792)
				(mid 187.12688 -25.440655)
				(end 187.351416 -25.513792)
			)
			(xy 188.511942 -25.513792) (xy 188.621162 -25.623012) (xy 188.621162 -25.943052) (xy 188.694822 -26.016712)
			(xy 188.778642 -26.016712) (xy 188.854842 -25.940512) (xy 188.854842 -25.320752) (xy 188.814202 -25.280112)
			(xy 188.092842 -25.280112) (xy 187.414662 -24.601932) (xy 185.86831 -24.601932) (xy 185.730642 -24.464264)
			(xy 185.730642 -23.839932) (xy 185.679842 -23.789132) (xy 184.267602 -23.789132) (xy 184.183782 -23.872952)
			(xy 184.183782 -28.61183) (xy 184.38368 -28.811728) (xy 186.40044 -28.811728) (xy 186.62396 -29.035248)
			(xy 186.62396 -29.383228) (xy 186.91098 -29.670248) (xy 187.55614 -29.670248)
		)
		(stroke
			(width 0)
			(type solid)
		)
		(fill yes)
		(layer "F.Cu")
		(net "GND")
	)
	(gr_poly
		(pts
			(xy 365.252762 -239.52962) (xy 365.268484 -239.525378) (xy 365.300741 -239.520923) (xy 365.317024 -239.52073)
			(xy 365.317024 -239.520984) (xy 365.616236 -239.520984) (xy 365.616236 -239.52073) (xy 365.63252 -239.520904)
			(xy 365.664778 -239.525367) (xy 365.680498 -239.52962) (xy 365.687356 -239.531652) (xy 366.261904 -239.531652)
			(xy 366.268762 -239.52962) (xy 366.284484 -239.525378) (xy 366.316741 -239.520923) (xy 366.333024 -239.52073)
			(xy 366.333024 -239.520984) (xy 366.618774 -239.520984) (xy 366.72901 -239.410494) (xy 366.72901 -239.084104)
			(xy 366.962944 -238.85017) (xy 368.916712 -238.85017) (xy 369.123976 -238.642906) (xy 369.123976 -238.2901)
			(xy 369.123214 -238.285528) (xy 369.120628 -238.270676) (xy 369.117831 -238.240658) (xy 369.117626 -238.225584)
			(xy 369.117815 -238.210509) (xy 369.120612 -238.18049) (xy 369.123214 -238.16564) (xy 369.123976 -238.161068)
			(xy 369.123976 -237.246922) (xy 369.121436 -237.239302) (xy 369.11372 -237.213635) (xy 369.105425 -237.160689)
			(xy 369.104926 -237.133892) (xy 369.10542 -237.107095) (xy 369.113714 -237.054147) (xy 369.121436 -237.028482)
			(xy 369.123976 -237.020862) (xy 369.123976 -236.659928) (xy 369.123214 -236.65561) (xy 369.120842 -236.641314)
			(xy 369.118302 -236.612443) (xy 369.118134 -236.597952) (xy 369.11829 -236.583461) (xy 369.120834 -236.55459)
			(xy 369.123214 -236.540294) (xy 369.123976 -236.535976) (xy 369.123976 -235.619036) (xy 369.121436 -235.611416)
			(xy 369.114324 -235.586016) (xy 369.111022 -235.572046) (xy 368.640106 -235.10113) (xy 363.061504 -235.10113)
			(xy 362.819188 -235.343446) (xy 362.819188 -237.867444) (xy 364.00232 -237.867444) (xy 364.00232 -235.837984)
			(xy 364.38205 -235.458508) (xy 367.607088 -235.458508) (xy 368.149632 -236.000798) (xy 368.149632 -237.853982)
			(xy 367.838482 -238.165132) (xy 364.300262 -238.165132) (xy 364.300008 -238.164624) (xy 364.184184 -238.164624)
			(xy 364.184184 -238.0488) (xy 364.00232 -237.867444) (xy 362.819188 -237.867444) (xy 362.819188 -237.96879)
			(xy 362.891324 -238.040926) (xy 363.522768 -238.040926) (xy 365.013494 -239.531652) (xy 365.245904 -239.531652)
		)
		(stroke
			(width 0)
			(type solid)
		)
		(fill yes)
		(layer "F.Cu")
		(net "GND")
	)
	(gr_poly
		(pts
			(xy 435.83098 -111.735108) (xy 435.83098 -110.744508) (xy 435.84368 -110.731808) (xy 435.84368 -107.429808)
			(xy 435.740302 -107.32643) (xy 434.173376 -107.32643) (xy 434.122576 -107.37723) (xy 434.122576 -109.71403)
			(xy 434.088286 -109.74832)
			(arc
				(start 434.08473 -109.761528)
				(mid 433.948498 -109.965583)
				(end 433.716176 -110.044484)
			)
			(arc
				(start 433.716176 -110.044484)
				(mid 433.497724 -109.975749)
				(end 433.358036 -109.794294)
			)
			(xy 433.354226 -109.78388) (xy 433.335176 -109.76483) (xy 433.335176 -109.679232) (xy 433.334668 -109.66323)
			(xy 433.334668 -109.266482) (xy 433.225956 -109.15777) (xy 431.828956 -109.15777) (xy 431.811176 -109.139736)
			(xy 431.767996 -109.139736) (xy 431.767996 -109.097064) (xy 431.699416 -109.02823) (xy 431.699416 -106.55427)
			(xy 431.808636 -106.44505) (xy 432.128676 -106.44505) (xy 432.202336 -106.37139) (xy 432.202336 -106.28757)
			(xy 432.126136 -106.21137) (xy 431.506376 -106.21137) (xy 431.465736 -106.25201) (xy 431.465736 -106.97337)
			(arc
				(start 430.954942 -107.484164)
				(mid 430.91669 -107.529324)
				(end 430.871884 -107.567984)
			)
			(xy 430.868836 -107.57027) (xy 430.787556 -107.65155) (xy 430.787556 -109.197902) (xy 430.649888 -109.33557)
			(xy 430.025556 -109.33557) (xy 429.974756 -109.38637) (xy 429.974756 -110.79861) (xy 429.965358 -110.808008)
			(xy 428.73168 -110.808008) (xy 428.65548 -110.731808) (xy 428.65548 -109.715808) (xy 428.45228 -109.512608)
			(xy 425.68368 -109.512608) (xy 425.48048 -109.309408) (xy 424.74388 -109.309408) (xy 424.33748 -108.903008)
			(xy 424.33748 -106.794808) (xy 424.10888 -106.566208) (xy 423.09288 -106.566208) (xy 422.96588 -106.693208)
			(xy 422.96588 -111.620808) (xy 423.34688 -112.001808) (xy 435.56428 -112.001808)
		)
		(stroke
			(width 0)
			(type solid)
		)
		(fill yes)
		(layer "F.Cu")
		(net "GND")
	)
	(gr_poly
		(pts
			(xy 170.31208 -56.302148) (xy 170.31208 -55.514748) (xy 170.21048 -55.413148) (xy 168.63568 -55.413148)
			(xy 168.40708 -55.184548)
			(arc
				(start 168.40708 -54.877462)
				(mid 168.376146 -54.804462)
				(end 168.302178 -54.775862)
			)
			(arc
				(start 168.29024 -54.776116)
				(mid 168.020473 -54.664375)
				(end 167.908732 -54.394608)
			)
			(arc
				(start 167.908732 -54.394608)
				(mid 167.989973 -54.159349)
				(end 168.199054 -54.024276)
			)
			(xy 168.21277 -54.02072)
			(arc
				(start 168.409366 -53.824378)
				(mid 168.457642 -53.784619)
				(end 168.512744 -53.755036)
			)
			(xy 168.522142 -53.751226) (xy 168.58488 -53.688488) (xy 170.24096 -53.688488) (xy 170.36034 -53.569108)
			(xy 170.36034 -51.991768) (xy 170.2689 -51.900328) (xy 168.73728 -51.900328) (xy 168.38168 -51.544728)
			(xy 168.38168 -49.886108) (xy 167.864536 -49.368964)
			(arc
				(start 165.61562 -49.368964)
				(mid 165.493549 -49.344665)
				(end 165.390068 -49.275492)
			)
			(xy 165.31717 -49.202848) (xy 160.99282 -49.202848)
			(arc
				(start 160.73374 -49.461928)
				(mid 160.613693 -49.542048)
				(end 160.47212 -49.570132)
			)
			(xy 159.43834 -49.570132) (xy 159.43834 -53.142388) (xy 159.50184 -53.205888) (xy 160.4772 -53.205888)
			(xy 160.92424 -52.758848) (xy 164.13988 -52.758848) (xy 164.13988 -52.771548) (xy 165.15588 -53.787548)
			(xy 165.15588 -56.378348) (xy 165.25748 -56.479948) (xy 170.13428 -56.479948)
		)
		(stroke
			(width 0)
			(type solid)
		)
		(fill yes)
		(layer "F.Cu")
		(net "P3V3_M2_0")
	)
	(gr_poly
		(pts
			(arc
				(start 258.673346 -54.808882)
				(mid 258.76633 -54.748228)
				(end 258.748276 -54.638702)
			)
			(arc
				(start 258.748276 -54.638702)
				(mid 258.674107 -54.519302)
				(end 258.6482 -54.381146)
			)
			(arc
				(start 258.6482 -54.381146)
				(mid 258.759941 -54.111379)
				(end 259.029708 -53.999638)
			)
			(arc
				(start 259.029708 -53.999638)
				(mid 259.069163 -54.001657)
				(end 259.108194 -54.007766)
			)
			(arc
				(start 259.108194 -54.007766)
				(mid 259.19318 -53.987345)
				(end 259.230876 -53.908452)
			)
			(arc
				(start 259.230876 -50.033682)
				(mid 259.236913 -49.971404)
				(end 259.255006 -49.911508)
			)
			(arc
				(start 259.586476 -49.111408)
				(mid 259.577038 -49.01602)
				(end 259.492496 -48.970946)
			)
			(xy 258.19608 -48.970946)
			(arc
				(start 258.072128 -49.094898)
				(mid 258.061149 -49.150094)
				(end 258.107942 -49.181512)
			)
			(xy 258.113276 -49.181512) (xy 258.113276 -49.241456) (xy 258.377944 -49.241456) (xy 258.377944 -49.876456)
			(xy 258.113276 -49.876456) (xy 258.113276 -49.9364) (xy 257.91033 -49.9364) (xy 257.91033 -50.18786)
			(xy 258.111244 -50.18786) (xy 258.111244 -50.247804) (xy 258.37642 -50.247804) (xy 258.37642 -50.882804)
			(xy 258.111244 -50.882804) (xy 258.111244 -50.942748) (xy 257.91033 -50.942748) (xy 257.91033 -52.063396)
			(xy 258.01193 -52.164996) (xy 258.01193 -54.722522) (xy 258.09829 -54.808882)
		)
		(stroke
			(width 0)
			(type solid)
		)
		(fill yes)
		(layer "F.Cu")
		(net "GND")
	)
	(gr_poly
		(pts
			(xy 136.305798 -366.64265) (xy 136.305798 -365.411512) (xy 134.491984 -363.597698) (xy 129.33426 -363.597698)
			(xy 127.803656 -365.128302) (xy 121.10847 -365.128302) (xy 121.072402 -365.16437) (xy 121.072402 -365.747808)
			(xy 132.860799 -365.747808) (xy 132.864835 -365.664361) (xy 132.876907 -365.581693) (xy 132.8969 -365.500576)
			(xy 132.924629 -365.421767) (xy 132.959835 -365.346002) (xy 133.002189 -365.273989) (xy 133.051295 -365.2064)
			(xy 133.106696 -365.143866) (xy 133.167873 -365.086971) (xy 133.234256 -365.036245) (xy 133.305224 -364.992164)
			(xy 133.380116 -364.955138) (xy 133.458232 -364.925512) (xy 133.538842 -364.903564) (xy 133.621194 -364.889499)
			(xy 133.70452 -364.883447) (xy 133.78804 -364.885466) (xy 133.870976 -364.895536) (xy 133.952552 -364.913564)
			(xy 134.032008 -364.939381) (xy 134.108601 -364.972746) (xy 134.181617 -365.013347) (xy 134.250373 -365.060806)
			(xy 134.314227 -365.114679) (xy 134.372584 -365.174464) (xy 134.424899 -365.239601) (xy 134.470682 -365.309484)
			(xy 134.509507 -365.383459) (xy 134.541012 -365.460836) (xy 134.564901 -365.540893) (xy 134.580952 -365.622881)
			(xy 134.589015 -365.706036) (xy 134.58952 -365.747808) (xy 134.589015 -365.78958) (xy 134.580952 -365.872735)
			(xy 134.564901 -365.954723) (xy 134.541012 -366.03478) (xy 134.509507 -366.112157) (xy 134.470682 -366.186132)
			(xy 134.424899 -366.256015) (xy 134.372584 -366.321152) (xy 134.314227 -366.380937) (xy 134.250373 -366.43481)
			(xy 134.181617 -366.482269) (xy 134.108601 -366.52287) (xy 134.032008 -366.556235) (xy 133.952552 -366.582052)
			(xy 133.870976 -366.60008) (xy 133.78804 -366.61015) (xy 133.70452 -366.612169) (xy 133.621194 -366.606117)
			(xy 133.538842 -366.592052) (xy 133.458232 -366.570104) (xy 133.380116 -366.540478) (xy 133.305224 -366.503452)
			(xy 133.234256 -366.459371) (xy 133.167873 -366.408645) (xy 133.106696 -366.35175) (xy 133.051295 -366.289216)
			(xy 133.002189 -366.221627) (xy 132.959835 -366.149614) (xy 132.924629 -366.073849) (xy 132.8969 -365.99504)
			(xy 132.876907 -365.913923) (xy 132.864835 -365.831255) (xy 132.860799 -365.747808) (xy 121.072402 -365.747808)
			(xy 121.072402 -366.563402) (xy 121.134632 -366.625632) (xy 130.994912 -366.625632) (xy 131.237228 -366.867948)
			(xy 136.0805 -366.867948)
		)
		(stroke
			(width 0)
			(type solid)
		)
		(fill yes)
		(layer "F.Cu")
		(net "GND")
	)
	(gr_poly
		(pts
			(arc
				(start 187.227718 -34.63544)
				(mid 187.6044 -34.314817)
				(end 187.981082 -34.63544)
			)
			(xy 187.98794 -34.678112) (xy 189.017402 -34.678112) (xy 190.371222 -33.324292)
			(arc
				(start 190.371222 -27.314144)
				(mid 190.296285 -27.087068)
				(end 190.371222 -26.859992)
			)
			(xy 190.371222 -26.071576) (xy 190.360808 -26.061162) (xy 190.360808 -24.837644) (xy 190.300102 -24.777192)
			(xy 190.185802 -24.777192) (xy 190.132462 -24.830532) (xy 190.132462 -26.484072) (xy 190.109856 -26.506424)
			(xy 190.109856 -26.556462) (xy 189.897512 -26.76906) (xy 189.567312 -26.76906) (xy 189.551818 -26.753312)
			(xy 189.548262 -26.753312) (xy 189.357762 -26.562812) (xy 189.357762 -26.559256) (xy 189.357508 -26.559002)
			(xy 189.357508 -25.327864) (xy 189.309502 -25.280112) (xy 189.152022 -25.280112) (xy 189.119002 -25.313132)
			(xy 189.119002 -27.685492) (xy 188.64834 -28.156408) (xy 188.64834 -28.407614) (xy 188.647832 -28.421076)
			(xy 188.647832 -29.155136)
			(arc
				(start 188.650118 -29.162502)
				(mid 188.65752 -29.195027)
				(end 188.660024 -29.228288)
			)
			(xy 188.660024 -29.496004) (xy 188.647832 -29.496004) (xy 188.647832 -29.734256) (xy 188.42228 -29.959808)
			(xy 184.85866 -29.959808) (xy 183.12638 -28.227528) (xy 176.0601 -28.227528) (xy 175.90008 -28.387548)
			(xy 175.90008 -29.461968) (xy 176.0601 -29.621988) (xy 177.74666 -29.621988) (xy 177.7619 -29.606748)
			(xy 180.0606 -29.606748) (xy 181.707028 -31.253176) (xy 181.707028 -34.3789) (xy 182.005986 -34.678112)
			(xy 187.22086 -34.678112)
		)
		(stroke
			(width 0)
			(type solid)
		)
		(fill yes)
		(layer "F.Cu")
		(net "P12V_AUX")
	)
	(gr_poly
		(pts
			(xy 219.822522 -74.660506) (xy 219.822522 -73.214738) (xy 219.771722 -73.163938) (xy 217.434922 -73.163938)
			(xy 217.400632 -73.129648)
			(arc
				(start 217.387424 -73.126092)
				(mid 217.183241 -72.989917)
				(end 217.104214 -72.757538)
			)
			(arc
				(start 217.104214 -72.757538)
				(mid 217.17302 -72.538905)
				(end 217.354658 -72.399144)
			)
			(xy 217.365326 -72.395334) (xy 217.384122 -72.376538) (xy 217.46718 -72.376538) (xy 217.485722 -72.37603)
			(xy 217.504264 -72.376538) (xy 217.881962 -72.376538) (xy 217.991182 -72.267318) (xy 217.991182 -70.870318)
			(xy 218.009216 -70.852284) (xy 218.009216 -70.809612) (xy 218.051888 -70.809612) (xy 218.120722 -70.740778)
			(xy 220.594682 -70.740778) (xy 220.703902 -70.849998) (xy 220.703902 -71.170038) (xy 220.777562 -71.243698)
			(xy 220.861382 -71.243698) (xy 220.937582 -71.167498) (xy 220.937582 -70.547738) (xy 220.896942 -70.507098)
			(xy 220.175582 -70.507098) (xy 219.514928 -69.846444)
			(arc
				(start 219.122752 -69.846444)
				(mid 219.022796 -69.892969)
				(end 218.91371 -69.908928)
			)
			(arc
				(start 218.91371 -69.908928)
				(mid 218.804636 -69.892928)
				(end 218.704668 -69.846444)
			)
			(arc
				(start 218.419934 -69.846444)
				(mid 218.370587 -69.842727)
				(end 218.322398 -69.831458)
			)
			(xy 218.315032 -69.828918) (xy 217.95105 -69.828918) (xy 217.813382 -69.69125) (xy 217.813382 -69.066918)
			(xy 217.762582 -69.016118) (xy 216.350342 -69.016118) (xy 216.266522 -69.099938)
			(arc
				(start 216.266522 -72.517254)
				(mid 216.343198 -72.650946)
				(end 216.3699 -72.80275)
			)
			(xy 216.3699 -74.652632) (xy 216.51468 -74.797412) (xy 216.51468 -74.818748) (xy 216.54008 -74.844148)
			(xy 219.63888 -74.844148)
		)
		(stroke
			(width 0)
			(type solid)
		)
		(fill yes)
		(layer "F.Cu")
		(net "GND")
	)
	(gr_poly
		(pts
			(xy 288.45764 -395.31544) (xy 288.45764 -394.34262) (xy 288.28746 -394.17244) (xy 288.28746 -391.3251)
			(xy 288.74466 -390.8679) (xy 288.74466 -386.72008) (xy 288.45764 -386.43306) (xy 285.46044 -386.43306)
			(xy 285.115 -386.7785) (xy 285.115 -389.402263) (xy 286.566352 -389.402263) (xy 286.566352 -389.317541)
			(xy 286.574405 -389.233204) (xy 286.590439 -389.150014) (xy 286.614307 -389.068724) (xy 286.645795 -388.990072)
			(xy 286.684617 -388.914769) (xy 286.73042 -388.843497) (xy 286.782791 -388.776901) (xy 286.841256 -388.715586)
			(xy 286.905284 -388.660105) (xy 286.974296 -388.610962) (xy 287.047666 -388.568602) (xy 287.124731 -388.533407)
			(xy 287.204793 -388.505698) (xy 287.287126 -388.485724) (xy 287.370985 -388.473667) (xy 287.45561 -388.469636)
			(xy 287.540235 -388.473667) (xy 287.624094 -388.485724) (xy 287.706427 -388.505698) (xy 287.786489 -388.533407)
			(xy 287.863554 -388.568602) (xy 287.936924 -388.610962) (xy 288.005936 -388.660105) (xy 288.069964 -388.715586)
			(xy 288.128429 -388.776901) (xy 288.1808 -388.843497) (xy 288.226603 -388.914769) (xy 288.265425 -388.990072)
			(xy 288.296913 -389.068724) (xy 288.320781 -389.150014) (xy 288.336815 -389.233204) (xy 288.344868 -389.317541)
			(xy 288.345372 -389.359902) (xy 288.344868 -389.402263) (xy 288.336815 -389.4866) (xy 288.320781 -389.56979)
			(xy 288.296913 -389.65108) (xy 288.265425 -389.729732) (xy 288.226603 -389.805035) (xy 288.1808 -389.876307)
			(xy 288.128429 -389.942903) (xy 288.069964 -390.004218) (xy 288.005936 -390.059699) (xy 287.936924 -390.108842)
			(xy 287.863554 -390.151202) (xy 287.786489 -390.186397) (xy 287.706427 -390.214106) (xy 287.624094 -390.23408)
			(xy 287.540235 -390.246137) (xy 287.45561 -390.250169) (xy 287.370985 -390.246137) (xy 287.287126 -390.23408)
			(xy 287.204793 -390.214106) (xy 287.124731 -390.186397) (xy 287.047666 -390.151202) (xy 286.974296 -390.108842)
			(xy 286.905284 -390.059699) (xy 286.841256 -390.004218) (xy 286.782791 -389.942903) (xy 286.73042 -389.876307)
			(xy 286.684617 -389.805035) (xy 286.645795 -389.729732) (xy 286.614307 -389.65108) (xy 286.590439 -389.56979)
			(xy 286.574405 -389.4866) (xy 286.566352 -389.402263) (xy 285.115 -389.402263) (xy 285.115 -395.37386)
			(xy 285.29534 -395.5542) (xy 288.21888 -395.5542)
		)
		(stroke
			(width 0)
			(type solid)
		)
		(fill yes)
		(layer "F.Cu")
		(net "GND")
	)
	(gr_poly
		(pts
			(xy 79.18704 -62.972188) (xy 79.18704 -60.621926) (xy 79.22768 -60.581286) (xy 79.26959 -60.581286)
			(xy 79.26959 -57.101486) (xy 79.380334 -56.990742)
			(arc
				(start 79.364078 -56.957976)
				(mid 79.324248 -56.847787)
				(end 79.310738 -56.731408)
			)
			(arc
				(start 79.310738 -56.731408)
				(mid 79.459677 -56.371839)
				(end 79.819246 -56.2229)
			)
			(xy 79.835756 -56.223154) (xy 79.8576 -56.223916)
			(arc
				(start 80.374744 -55.707026)
				(mid 80.478199 -55.637743)
				(end 80.600296 -55.6133)
			)
			(xy 80.757522 -55.6133) (xy 80.81137 -55.559706) (xy 84.11083 -55.559706) (xy 84.17179 -55.498746)
			(xy 84.17179 -55.379366) (xy 84.10829 -55.315866) (xy 82.25409 -55.315866) (xy 82.07121 -55.132986)
			(xy 82.07121 -54.734206) (xy 82.24901 -54.556406) (xy 83.61299 -54.556406) (xy 83.66887 -54.500526)
			(xy 83.66887 -54.355746) (xy 83.62061 -54.307486) (xy 82.41665 -54.307486) (xy 82.13725 -54.028086)
			(xy 79.45628 -54.028086) (xy 79.1464 -53.718206) (xy 79.1464 -50.843688) (xy 79.76616 -50.223928)
			(xy 81.88198 -50.223928) (xy 82.2833 -49.822608) (xy 82.2833 -47.158148) (xy 82.3087 -47.132748)
			(xy 82.3087 -46.297088) (xy 81.79308 -45.781468) (xy 77.34808 -45.781468) (xy 73.914 -49.215548)
			(xy 73.914 -55.491888) (xy 72.85482 -56.551068) (xy 69.72808 -56.551068)
			(arc
				(start 69.715634 -56.558688)
				(mid 69.683532 -56.572705)
				(end 69.648832 -56.577484)
			)
			(xy 69.511164 -56.577484) (xy 69.24548 -56.843168) (xy 69.24548 -57.353708) (xy 69.42836 -57.536588)
			(xy 71.96074 -57.536588) (xy 72.29602 -57.871868) (xy 72.29602 -58.461148) (xy 72.42556 -58.590688)
			(xy 73.46442 -58.590688) (xy 75.0443 -60.170568) (xy 75.0443 -62.931548) (xy 75.54722 -63.434468)
			(xy 78.72476 -63.434468)
		)
		(stroke
			(width 0)
			(type solid)
		)
		(fill yes)
		(layer "F.Cu")
		(net "P3V3_OCP_V3_2_R")
	)
	(gr_poly
		(pts
			(xy 7.175246 -430.115218)
			(arc
				(start 7.186168 -430.103788)
				(mid 7.34195 -429.943594)
				(end 7.502144 -429.787812)
			)
			(arc
				(start 7.502144 -429.787812)
				(mid 7.513871 -429.770902)
				(end 7.517892 -429.750728)
			)
			(arc
				(start 7.517892 -409.528264)
				(mid 7.287997 -408.373534)
				(end 6.633718 -407.394664)
			)
			(arc
				(start 3.305302 -404.066248)
				(mid 3.092653 -403.747712)
				(end 3.018028 -403.372066)
			)
			(arc
				(start 3.018028 -350.93529)
				(mid 3.016904 -350.924912)
				(end 3.01371 -350.91497)
			)
			(arc
				(start 3.01371 -350.91497)
				(mid 2.850331 -350.513714)
				(end 2.70891 -350.104202)
			)
			(xy 2.703322 -350.086168) (xy 2.671572 -350.066356)
			(arc
				(start 2.553716 -350.08439)
				(mid 2.522768 -350.101518)
				(end 2.510536 -350.134682)
			)
			(arc
				(start 2.510536 -403.371812)
				(mid 2.62388 -403.941719)
				(end 2.946654 -404.424896)
			)
			(arc
				(start 6.27507 -407.753312)
				(mid 6.819424 -408.567623)
				(end 7.010654 -409.528264)
			)
			(arc
				(start 7.010654 -430.034192)
				(mid 7.019486 -430.062562)
				(end 7.042658 -430.081182)
			)
			(xy 7.14502 -430.122076)
		)
		(stroke
			(width 0)
			(type solid)
		)
		(fill yes)
		(layer "F.Cu")
		(net "GND")
	)
	(gr_poly
		(pts
			(xy 221.924118 -71.668894) (xy 221.924118 -69.859398) (xy 222.020892 -69.762624) (xy 222.494856 -69.762624)
			(xy 222.72117 -69.988938) (xy 222.72117 -71.184262) (xy 222.785686 -71.248778) (xy 222.850456 -71.248778)
			(xy 222.949008 -71.15048) (xy 222.949008 -70.945248) (xy 222.979488 -70.914768) (xy 222.979488 -66.634868)
			(xy 223.235266 -66.37909) (xy 226.826318 -66.37909) (xy 227.74021 -65.465198) (xy 227.74021 -60.244482)
			(xy 226.193604 -58.697876) (xy 225.104706 -57.609232) (xy 220.431106 -57.609232) (xy 220.278706 -57.761632)
			(xy 220.278706 -58.345832) (xy 219.796106 -58.828432) (xy 218.780106 -58.828432) (xy 218.373706 -59.234832)
			(xy 218.373706 -62.224158) (xy 218.370404 -62.22746) (xy 218.370404 -62.260734) (xy 218.061032 -62.570106)
			(xy 218.061032 -62.583568) (xy 198.08444 -62.583568) (xy 195.18376 -65.484248) (xy 195.18376 -65.557908)
			(xy 195.612002 -65.557908) (xy 195.616073 -65.502286) (xy 195.628199 -65.447849) (xy 195.648122 -65.395758)
			(xy 195.675418 -65.347123) (xy 195.709504 -65.30298) (xy 195.749653 -65.264271) (xy 195.795011 -65.23182)
			(xy 195.844611 -65.206319) (xy 195.897395 -65.188312) (xy 195.952238 -65.178182) (xy 196.007972 -65.176145)
			(xy 196.063409 -65.182245) (xy 196.117366 -65.196351) (xy 196.168695 -65.218163) (xy 196.216301 -65.247217)
			(xy 196.259169 -65.282892) (xy 196.296386 -65.324429) (xy 196.327159 -65.370942) (xy 196.350831 -65.421439)
			(xy 196.366899 -65.474846) (xy 196.375019 -65.530022) (xy 196.375528 -65.557908) (xy 196.375019 -65.585794)
			(xy 196.366899 -65.64097) (xy 196.350831 -65.694377) (xy 196.327159 -65.744874) (xy 196.296386 -65.791387)
			(xy 196.259169 -65.832924) (xy 196.216301 -65.868599) (xy 196.168695 -65.897653) (xy 196.117366 -65.919465)
			(xy 196.063409 -65.933571) (xy 196.007972 -65.939671) (xy 195.952238 -65.937634) (xy 195.897395 -65.927504)
			(xy 195.844611 -65.909497) (xy 195.795011 -65.883996) (xy 195.749653 -65.851545) (xy 195.709504 -65.812836)
			(xy 195.675418 -65.768693) (xy 195.648122 -65.720058) (xy 195.628199 -65.667967) (xy 195.616073 -65.61353)
			(xy 195.612002 -65.557908) (xy 195.18376 -65.557908) (xy 195.18376 -67.457828) (xy 195.43268 -67.706748)
			(xy 196.1007 -67.706748) (xy 197.2564 -66.551048) (xy 220.915738 -66.551048) (xy 221.510098 -67.145408)
			(xy 221.514924 -67.145408) (xy 221.64421 -67.274694) (xy 221.64421 -71.647304) (xy 221.708726 -71.71182)
			(xy 221.881192 -71.71182)
		)
		(stroke
			(width 0)
			(type solid)
		)
		(fill yes)
		(layer "F.Cu")
		(net "P3V3_E1S_0_R")
	)
	(gr_poly
		(pts
			(xy 50.261012 -108.549948) (xy 50.283137 -108.530147) (xy 50.33177 -108.496085) (xy 50.384566 -108.46892)
			(xy 50.440552 -108.44915) (xy 50.4987 -108.437141) (xy 50.557938 -108.433113) (xy 50.617176 -108.437141)
			(xy 50.675324 -108.44915) (xy 50.73131 -108.46892) (xy 50.784106 -108.496085) (xy 50.832739 -108.530147)
			(xy 50.854864 -108.549948) (xy 51.27498 -108.549948) (xy 51.45024 -108.374688) (xy 51.45024 -106.652822)
			(xy 51.262026 -106.464608) (xy 48.82896 -106.464608) (xy 48.43526 -106.070908) (xy 48.43526 -105.501948)
			(xy 48.37684 -105.443528) (xy 47.046642 -105.443528) (xy 46.997874 -105.492296) (xy 46.997874 -106.416856)
			(xy 46.73092 -106.68381) (xy 46.73092 -107.441911) (xy 50.144428 -107.441911) (xy 50.144428 -107.382145)
			(xy 50.152566 -107.322935) (xy 50.168691 -107.265385) (xy 50.192502 -107.210566) (xy 50.223556 -107.1595)
			(xy 50.261274 -107.113139) (xy 50.304953 -107.072345) (xy 50.353781 -107.037879) (xy 50.406847 -107.010382)
			(xy 50.463162 -106.990367) (xy 50.521679 -106.978208) (xy 50.581306 -106.974129) (xy 50.640933 -106.978208)
			(xy 50.69945 -106.990367) (xy 50.755765 -107.010382) (xy 50.808831 -107.037879) (xy 50.857659 -107.072345)
			(xy 50.901338 -107.113139) (xy 50.939056 -107.1595) (xy 50.97011 -107.210566) (xy 50.993921 -107.265385)
			(xy 51.010046 -107.322935) (xy 51.018184 -107.382145) (xy 51.018694 -107.412028) (xy 51.018184 -107.441911)
			(xy 51.010046 -107.501121) (xy 50.993921 -107.558671) (xy 50.97011 -107.61349) (xy 50.939056 -107.664556)
			(xy 50.901338 -107.710917) (xy 50.857659 -107.751711) (xy 50.808831 -107.786177) (xy 50.755765 -107.813674)
			(xy 50.69945 -107.833689) (xy 50.640933 -107.845848) (xy 50.581306 -107.849927) (xy 50.521679 -107.845848)
			(xy 50.463162 -107.833689) (xy 50.406847 -107.813674) (xy 50.353781 -107.786177) (xy 50.304953 -107.751711)
			(xy 50.261274 -107.710917) (xy 50.223556 -107.664556) (xy 50.192502 -107.61349) (xy 50.168691 -107.558671)
			(xy 50.152566 -107.501121) (xy 50.144428 -107.441911) (xy 46.73092 -107.441911) (xy 46.73092 -107.599988)
			(xy 46.789848 -107.658916) (xy 46.82109 -107.64647) (xy 46.846859 -107.636573) (xy 46.900277 -107.622657)
			(xy 46.955033 -107.615657) (xy 46.982634 -107.615228) (xy 47.592234 -107.615228) (xy 47.62051 -107.615692)
			(xy 47.676579 -107.623075) (xy 47.731206 -107.63771) (xy 47.783456 -107.659346) (xy 47.832437 -107.687615)
			(xy 47.87731 -107.722032) (xy 47.91731 -107.76201) (xy 47.951753 -107.806865) (xy 47.980048 -107.85583)
			(xy 48.001714 -107.908069) (xy 48.016379 -107.962687) (xy 48.023792 -108.018752) (xy 48.024288 -108.047028)
			(xy 48.024542 -108.06811) (xy 48.50638 -108.549948)
		)
		(stroke
			(width 0)
			(type solid)
		)
		(fill yes)
		(layer "F.Cu")
		(net "P3V3_AUX")
	)
	(gr_poly
		(pts
			(xy 186.938666 -344.132662) (xy 186.938666 -336.771234) (xy 186.76366 -336.596228) (xy 184.23509 -336.596228)
			(xy 184.23509 -336.65541)
			(arc
				(start 184.237884 -336.663538)
				(mid 184.242013 -336.679693)
				(end 184.243472 -336.696304)
			)
			(arc
				(start 184.243472 -338.271358)
				(mid 184.21355 -338.343469)
				(end 184.141364 -338.373212)
			)
			(arc
				(start 182.561484 -338.373212)
				(mid 182.492766 -338.341742)
				(end 182.464456 -338.271612)
			)
			(arc
				(start 182.464456 -336.696304)
				(mid 182.4659 -336.67969)
				(end 182.470044 -336.663538)
			)
			(xy 182.472838 -336.65541) (xy 182.472838 -336.596228) (xy 178.03749 -336.596228) (xy 178.03749 -336.65541)
			(arc
				(start 178.040284 -336.663538)
				(mid 178.044413 -336.679693)
				(end 178.045872 -336.696304)
			)
			(arc
				(start 178.045872 -338.271358)
				(mid 178.01595 -338.343469)
				(end 177.943764 -338.373212)
			)
			(arc
				(start 176.363884 -338.373212)
				(mid 176.295166 -338.341742)
				(end 176.266856 -338.271612)
			)
			(arc
				(start 176.266856 -336.696304)
				(mid 176.2683 -336.67969)
				(end 176.272444 -336.663538)
			)
			(xy 176.275238 -336.65541) (xy 176.275238 -336.596228)
			(arc
				(start 171.89958 -336.596228)
				(mid 171.858867 -336.616645)
				(end 171.850812 -336.661506)
			)
			(arc
				(start 171.850812 -336.661506)
				(mid 171.853865 -336.675712)
				(end 171.854876 -336.690208)
			)
			(xy 171.854876 -337.371182)
			(arc
				(start 171.85513 -338.265008)
				(mid 171.825313 -338.337119)
				(end 171.753276 -338.367116)
			)
			(arc
				(start 170.178222 -338.367116)
				(mid 170.106111 -338.337194)
				(end 170.076368 -338.265008)
			)
			(arc
				(start 170.076368 -336.690208)
				(mid 170.077369 -336.675711)
				(end 170.080432 -336.661506)
			)
			(arc
				(start 170.080432 -336.661506)
				(mid 170.072434 -336.616603)
				(end 170.031664 -336.596228)
			)
			(xy 166.82974 -336.596228) (xy 166.67734 -336.748628) (xy 166.67734 -344.18143) (xy 166.908988 -344.413078)
			(xy 186.65825 -344.413078)
		)
		(stroke
			(width 0)
			(type solid)
		)
		(fill yes)
		(layer "F.Cu")
		(net "PVCCFA_EHV_FIVRA_CPU1")
	)
	(gr_poly
		(pts
			(xy 121.199402 -245.78818) (xy 121.199402 -245.423182)
			(arc
				(start 121.19483 -245.413022)
				(mid 121.172439 -245.344373)
				(end 121.164858 -245.27256)
			)
			(arc
				(start 121.164858 -245.27256)
				(mid 121.172398 -245.200738)
				(end 121.19483 -245.132098)
			)
			(xy 121.199402 -245.121938) (xy 121.199402 -244.854984)
			(arc
				(start 121.196608 -244.846856)
				(mid 121.182399 -244.792549)
				(end 121.177558 -244.73662)
			)
			(arc
				(start 121.177558 -244.73662)
				(mid 121.18237 -244.680686)
				(end 121.196608 -244.626384)
			)
			(xy 121.199402 -244.618256) (xy 121.199402 -243.79555)
			(arc
				(start 121.19483 -243.78539)
				(mid 121.172439 -243.716741)
				(end 121.164858 -243.644928)
			)
			(arc
				(start 121.164858 -243.644928)
				(mid 121.172398 -243.573106)
				(end 121.19483 -243.504466)
			)
			(xy 121.199402 -243.494306) (xy 121.199402 -243.227352)
			(arc
				(start 121.196608 -243.219224)
				(mid 121.182399 -243.164917)
				(end 121.177558 -243.108988)
			)
			(arc
				(start 121.177558 -243.108988)
				(mid 121.18237 -243.053054)
				(end 121.196608 -242.998752)
			)
			(xy 121.199402 -242.990624) (xy 121.199402 -242.167664)
			(arc
				(start 121.19483 -242.157504)
				(mid 121.172439 -242.088855)
				(end 121.164858 -242.017042)
			)
			(arc
				(start 121.164858 -242.017042)
				(mid 121.172398 -241.94522)
				(end 121.19483 -241.87658)
			)
			(xy 121.199402 -241.86642) (xy 121.199402 -241.599466)
			(arc
				(start 121.196608 -241.591338)
				(mid 121.182399 -241.537031)
				(end 121.177558 -241.481102)
			)
			(arc
				(start 121.177558 -241.481102)
				(mid 121.18237 -241.425168)
				(end 121.196608 -241.370866)
			)
			(xy 121.199402 -241.362738) (xy 121.199402 -241.090958) (xy 121.63298 -240.65738)
			(arc
				(start 121.63298 -240.284762)
				(mid 121.601216 -240.210969)
				(end 121.525792 -240.183416)
			)
			(arc
				(start 121.508012 -240.183924)
				(mid 121.291688 -240.103277)
				(end 121.18086 -239.900714)
			)
			(xy 121.17451 -239.85728) (xy 120.733312 -239.85728) (xy 120.146826 -240.443766) (xy 115.322604 -240.443766)
			(xy 115.23091 -240.53546) (xy 115.23091 -241.80292) (xy 115.254786 -241.826796) (xy 119.817896 -241.826796)
			(xy 119.892064 -241.900964) (xy 120.118378 -242.127532) (xy 120.118378 -244.004592) (xy 119.93499 -244.18798)
			(xy 115.546886 -244.18798) (xy 115.23599 -244.498876) (xy 115.23599 -245.49862) (xy 115.28933 -245.55196)
			(xy 119.99976 -245.55196) (xy 120.3071 -245.8593) (xy 121.128282 -245.8593)
		)
		(stroke
			(width 0)
			(type solid)
		)
		(fill yes)
		(layer "F.Cu")
		(net "GND")
	)
	(gr_poly
		(pts
			(xy 247.819672 -52.604416) (xy 247.819672 -52.097686) (xy 251.87148 -52.097686) (xy 251.97816 -51.991006)
			(xy 252.78842 -51.991006) (xy 252.84938 -51.930046) (xy 252.84938 -48.310546) (xy 252.77064 -48.231806)
			(xy 250.59132 -48.231806) (xy 249.755152 -47.395384) (xy 249.710956 -47.395384) (xy 249.710956 -47.351696)
			(xy 248.6406 -46.281086) (xy 248.6406 -44.397422) (xy 248.480072 -44.397422) (xy 247.77065 -43.688)
			(xy 247.77065 -43.131486) (xy 248.168922 -42.733214) (xy 249.19178 -42.733214) (xy 250.703588 -41.221406)
			(xy 250.934474 -41.221406) (xy 250.936506 -41.221152) (xy 250.961652 -41.220136) (xy 252.082808 -41.220136)
			(xy 252.107954 -41.221152) (xy 252.109986 -41.221406) (xy 252.403356 -41.221406) (xy 252.45187 -41.172892)
			(xy 253.665228 -41.172892) (xy 253.72314 -41.114726) (xy 253.72314 -40.992806) (xy 253.63932 -40.908986)
			(xy 251.85624 -40.908986) (xy 251.714 -40.766746) (xy 251.714 -40.393366) (xy 251.718572 -40.38854)
			(xy 251.718572 -40.381936) (xy 251.94387 -40.156892) (xy 253.192788 -40.156892) (xy 253.21006 -40.139366)
			(xy 253.21006 -39.928546) (xy 253.193804 -39.912036) (xy 252.9078 -39.912036) (xy 252.86589 -39.870126)
			(xy 251.882402 -39.870126) (xy 251.870972 -39.858696)
			(arc
				(start 251.723144 -39.858696)
				(mid 251.611226 -39.838326)
				(end 251.513594 -39.779956)
			)
			(arc
				(start 250.746768 -39.779956)
				(mid 250.646812 -39.826481)
				(end 250.537726 -39.84244)
			)
			(arc
				(start 250.537726 -39.84244)
				(mid 250.302467 -39.761199)
				(end 250.167394 -39.552118)
			)
			(xy 250.163838 -39.538402)
			(arc
				(start 250.091448 -39.465758)
				(mid 250.078601 -39.452276)
				(end 250.066556 -39.438072)
			)
			(xy 250.064778 -39.435786) (xy 249.951748 -39.322756) (xy 248.000012 -39.322756) (xy 247.301512 -40.021256)
			(xy 245.375176 -40.021256) (xy 244.523006 -40.873426) (xy 243.18214 -40.873426) (xy 242.62334 -41.432226)
			(xy 242.62334 -42.082466) (xy 242.28806 -42.417746) (xy 237.5662 -42.417746) (xy 237.22584 -42.077386)
			(xy 235.7882 -42.077386) (xy 235.66882 -42.196766) (xy 235.66882 -45.625766) (xy 235.84662 -45.803566)
			(xy 238.43488 -45.803566) (xy 238.43996 -45.798486) (xy 240.95202 -45.798486) (xy 241.63528 -46.481746)
			(xy 241.63528 -49.811686) (xy 241.7826 -49.959006) (xy 244.57152 -49.959006) (xy 245.19636 -50.583846)
			(xy 245.19636 -52.51831) (xy 245.467886 -52.789836) (xy 247.634252 -52.789836)
		)
		(stroke
			(width 0)
			(type solid)
		)
		(fill yes)
		(layer "F.Cu")
		(net "P12V_E1S_0")
	)
	(gr_poly
		(pts
			(xy 369.139216 -245.787926) (xy 369.139216 -245.42242)
			(arc
				(start 369.134898 -245.412768)
				(mid 369.112534 -245.344244)
				(end 369.104926 -245.27256)
			)
			(arc
				(start 369.104926 -245.27256)
				(mid 369.112493 -245.200868)
				(end 369.134898 -245.132352)
			)
			(xy 369.139216 -245.1227) (xy 369.139216 -244.854476)
			(arc
				(start 369.136422 -244.846348)
				(mid 369.12235 -244.792283)
				(end 369.117626 -244.73662)
			)
			(arc
				(start 369.117626 -244.73662)
				(mid 369.12239 -244.680964)
				(end 369.136422 -244.626892)
			)
			(xy 369.139216 -244.618764) (xy 369.139216 -243.794788)
			(arc
				(start 369.134898 -243.785136)
				(mid 369.112534 -243.716612)
				(end 369.104926 -243.644928)
			)
			(arc
				(start 369.104926 -243.644928)
				(mid 369.112493 -243.573236)
				(end 369.134898 -243.50472)
			)
			(xy 369.139216 -243.495068) (xy 369.139216 -243.226844)
			(arc
				(start 369.136422 -243.218716)
				(mid 369.12235 -243.164651)
				(end 369.117626 -243.108988)
			)
			(arc
				(start 369.117626 -243.108988)
				(mid 369.12239 -243.053332)
				(end 369.136422 -242.99926)
			)
			(xy 369.139216 -242.991132) (xy 369.139216 -242.166902)
			(arc
				(start 369.134898 -242.15725)
				(mid 369.112534 -242.088726)
				(end 369.104926 -242.017042)
			)
			(arc
				(start 369.104926 -242.017042)
				(mid 369.112493 -241.94535)
				(end 369.134898 -241.876834)
			)
			(xy 369.139216 -241.867182) (xy 369.139216 -241.598958)
			(arc
				(start 369.136422 -241.59083)
				(mid 369.12235 -241.536765)
				(end 369.117626 -241.481102)
			)
			(arc
				(start 369.117626 -241.481102)
				(mid 369.12239 -241.425446)
				(end 369.136422 -241.371374)
			)
			(xy 369.139216 -241.363246) (xy 369.139216 -241.090704) (xy 369.572794 -240.657126)
			(arc
				(start 369.572794 -240.285016)
				(mid 369.541215 -240.211143)
				(end 369.46586 -240.183416)
			)
			(arc
				(start 369.44808 -240.183924)
				(mid 369.231576 -240.103204)
				(end 369.120674 -239.90046)
			)
			(xy 369.114578 -239.857026) (xy 368.673126 -239.857026) (xy 368.08664 -240.443512) (xy 363.262418 -240.443512)
			(xy 363.170724 -240.535206) (xy 363.170724 -241.802666) (xy 363.1946 -241.826542) (xy 367.75771 -241.826542)
			(xy 367.831878 -241.90071) (xy 368.058192 -242.127278) (xy 368.058192 -244.004338) (xy 367.874804 -244.187726)
			(xy 363.4867 -244.187726) (xy 363.175804 -244.498622) (xy 363.175804 -245.498366) (xy 363.229144 -245.551706)
			(xy 367.939574 -245.551706) (xy 368.246914 -245.859046) (xy 369.068096 -245.859046)
		)
		(stroke
			(width 0)
			(type solid)
		)
		(fill yes)
		(layer "F.Cu")
		(net "GND")
	)
	(gr_poly
		(pts
			(arc
				(start 467.738714 -84.724748)
				(mid 467.774635 -84.709869)
				(end 467.789514 -84.673948)
			)
			(arc
				(start 467.789514 -82.82813)
				(mid 467.980666 -81.867526)
				(end 468.524844 -81.053178)
			)
			(arc
				(start 470.853262 -78.72476)
				(mid 471.176045 -78.241587)
				(end 471.28938 -77.671676)
			)
			(arc
				(start 471.28938 -27.283918)
				(mid 471.279932 -27.254411)
				(end 471.25509 -27.235912)
			)
			(xy 471.148664 -27.199336) (xy 471.117676 -27.20848)
			(arc
				(start 471.10777 -27.221434)
				(mid 470.954188 -27.412169)
				(end 470.794842 -27.598116)
			)
			(arc
				(start 470.794842 -27.598116)
				(mid 470.785288 -27.61382)
				(end 470.781888 -27.631898)
			)
			(arc
				(start 470.781888 -31.515812)
				(mid 470.782457 -31.523393)
				(end 470.784174 -31.530798)
			)
			(arc
				(start 470.784174 -31.530798)
				(mid 470.871375 -31.910971)
				(end 470.90076 -32.29991)
			)
			(arc
				(start 470.90076 -33.899856)
				(mid 470.871397 -34.288798)
				(end 470.784174 -34.668968)
			)
			(arc
				(start 470.784174 -34.668968)
				(mid 470.782481 -34.676376)
				(end 470.781888 -34.683954)
			)
			(arc
				(start 470.781888 -77.67193)
				(mid 470.707224 -78.04756)
				(end 470.494614 -78.366112)
			)
			(arc
				(start 468.166196 -80.69453)
				(mid 467.512084 -81.673433)
				(end 467.282276 -82.82813)
			)
			(arc
				(start 467.282276 -84.673948)
				(mid 467.297155 -84.709869)
				(end 467.333076 -84.724748)
			)
		)
		(stroke
			(width 0)
			(type solid)
		)
		(fill yes)
		(layer "F.Cu")
		(net "GND")
	)
	(gr_poly
		(pts
			(xy 2.703322 -158.11373)
			(arc
				(start 2.70891 -158.095696)
				(mid 2.85033 -157.686184)
				(end 3.01371 -157.284928)
			)
			(arc
				(start 3.01371 -157.284928)
				(mid 3.016934 -157.274993)
				(end 3.018028 -157.264608)
			)
			(arc
				(start 3.018028 -81.32826)
				(mid 2.901459 -80.49816)
				(end 2.561082 -79.732124)
			)
			(xy 2.55397 -79.723234)
			(arc
				(start 1.492758 -78.661768)
				(mid 1.432047 -78.577085)
				(end 1.401826 -78.477364)
			)
			(xy 1.40081 -78.468982) (xy 1.393444 -78.45425)
			(arc
				(start 1.305306 -78.366112)
				(mid 1.092705 -78.047693)
				(end 1.018032 -77.672184)
			)
			(xy 1.018032 -42.244772) (xy 1.018032 -41.622472) (xy 1.018032 -41.222422) (xy 1.018032 -40.600122)
			(xy 1.018032 -40.167814) (xy 1.018032 -39.48049) (xy 1.018032 -39.099998) (xy 1.018032 -38.477698)
			(xy 1.018032 -38.110414) (xy 1.018032 -37.368226) (xy 1.018032 -37.067236) (xy 1.018032 -36.325048)
			(xy 1.018032 -36.059364) (xy 1.018032 -35.172904)
			(arc
				(start 1.018032 -27.631898)
				(mid 1.014806 -27.613828)
				(end 1.005332 -27.598116)
			)
			(arc
				(start 1.005332 -27.598116)
				(mid 0.845857 -27.412173)
				(end 0.69215 -27.221434)
			)
			(xy 0.682244 -27.208734) (xy 0.651256 -27.199336)
			(arc
				(start 0.54483 -27.236166)
				(mid 0.520016 -27.254685)
				(end 0.51054 -27.284172)
			)
			(arc
				(start 0.51054 -77.671676)
				(mid 0.623884 -78.241583)
				(end 0.946658 -78.72476)
			)
			(arc
				(start 1.775206 -79.553308)
				(mid 2.319424 -80.367648)
				(end 2.510536 -81.32826)
			)
			(arc
				(start 2.510536 -158.065216)
				(mid 2.522818 -158.098337)
				(end 2.553716 -158.115508)
			)
			(xy 2.671572 -158.133542)
		)
		(stroke
			(width 0)
			(type solid)
		)
		(fill yes)
		(layer "F.Cu")
		(net "GND")
	)
	(gr_poly
		(pts
			(xy 303.678844 -374.438926) (xy 303.678844 -363.136688) (xy 303.53508 -362.992924) (xy 298.886118 -362.992924)
			(xy 298.82084 -363.057948) (xy 298.82084 -365.10087) (xy 298.84624 -365.12627) (xy 300.199552 -365.12627)
			(xy 300.367192 -365.29391) (xy 300.367192 -365.957104) (xy 300.756828 -366.34674) (xy 300.756828 -368.196876)
			(xy 299.890688 -369.063016) (xy 294.077898 -369.063016) (xy 293.159942 -368.14506) (xy 293.159942 -365.625126)
			(xy 293.660068 -365.125) (xy 293.660068 -363.043724) (xy 293.609268 -362.992924) (xy 289.154108 -362.992924)
			(xy 289.140392 -363.00664) (xy 289.140392 -365.065818) (xy 289.199066 -365.124492) (xy 290.55695 -365.124492)
			(xy 290.688268 -365.25581) (xy 290.688268 -365.369856) (xy 290.688522 -365.37519) (xy 290.688522 -365.975392)
			(xy 290.68649 -366.002824) (xy 290.682934 -366.02797) (xy 291.072824 -366.418114) (xy 291.072824 -369.123976)
			(xy 291.854128 -369.90528) (xy 291.854128 -372.49855) (xy 298.442376 -372.49855) (xy 298.442376 -372.413854)
			(xy 298.450427 -372.32954) (xy 298.466456 -372.246374) (xy 298.490317 -372.165107) (xy 298.521796 -372.086477)
			(xy 298.560607 -372.011196) (xy 298.606397 -371.939944) (xy 298.658753 -371.873368) (xy 298.717201 -371.81207)
			(xy 298.781211 -371.756605) (xy 298.850203 -371.707476) (xy 298.923553 -371.665127) (xy 299.000596 -371.629943)
			(xy 299.080635 -371.602241) (xy 299.162944 -371.582273) (xy 299.246779 -371.57022) (xy 299.33138 -371.56619)
			(xy 299.415981 -371.57022) (xy 299.499816 -371.582273) (xy 299.582125 -371.602241) (xy 299.662164 -371.629943)
			(xy 299.739207 -371.665127) (xy 299.812557 -371.707476) (xy 299.881549 -371.756605) (xy 299.945559 -371.81207)
			(xy 300.004007 -371.873368) (xy 300.056363 -371.939944) (xy 300.102153 -372.011196) (xy 300.140964 -372.086477)
			(xy 300.172443 -372.165107) (xy 300.196304 -372.246374) (xy 300.212333 -372.32954) (xy 300.220384 -372.413854)
			(xy 300.220888 -372.456202) (xy 300.220384 -372.49855) (xy 300.212333 -372.582864) (xy 300.196304 -372.66603)
			(xy 300.172443 -372.747297) (xy 300.140964 -372.825927) (xy 300.102153 -372.901208) (xy 300.056363 -372.97246)
			(xy 300.004007 -373.039036) (xy 299.945559 -373.100334) (xy 299.881549 -373.155799) (xy 299.812557 -373.204928)
			(xy 299.739207 -373.247277) (xy 299.662164 -373.282461) (xy 299.582125 -373.310163) (xy 299.499816 -373.330131)
			(xy 299.415981 -373.342184) (xy 299.33138 -373.346215) (xy 299.246779 -373.342184) (xy 299.162944 -373.330131)
			(xy 299.080635 -373.310163) (xy 299.000596 -373.282461) (xy 298.923553 -373.247277) (xy 298.850203 -373.204928)
			(xy 298.781211 -373.155799) (xy 298.717201 -373.100334) (xy 298.658753 -373.039036) (xy 298.606397 -372.97246)
			(xy 298.560607 -372.901208) (xy 298.521796 -372.825927) (xy 298.490317 -372.747297) (xy 298.466456 -372.66603)
			(xy 298.450427 -372.582864) (xy 298.442376 -372.49855) (xy 291.854128 -372.49855) (xy 291.854128 -374.467374)
			(xy 292.601396 -375.214642) (xy 302.903128 -375.214642)
		)
		(stroke
			(width 0)
			(type solid)
		)
		(fill yes)
		(layer "F.Cu")
		(net "SW_P12V_PVCCFA_EHV_FIVRA_CPU0_L")
	)
	(gr_poly
		(pts
			(arc
				(start 337.054952 -60.629038)
				(mid 337.089842 -60.601431)
				(end 337.130136 -60.582556)
			)
			(xy 337.130644 -60.582048) (xy 337.130644 -59.385708)
			(arc
				(start 336.996786 -59.385708)
				(mid 337.020139 -59.347779)
				(end 337.028028 -59.30392)
			)
			(arc
				(start 337.028028 -59.226958)
				(mid 337.020493 -59.183007)
				(end 336.997294 -59.144916)
			)
			(xy 337.189318 -59.144916) (xy 337.244182 -59.090306) (xy 337.207606 -59.05373)
			(arc
				(start 337.207352 -59.053222)
				(mid 337.142783 -58.960737)
				(end 337.119976 -58.850276)
			)
			(arc
				(start 337.119976 -58.850276)
				(mid 337.160425 -58.705264)
				(end 337.27009 -58.602118)
			)
			(xy 337.276948 -58.598562) (xy 337.318604 -58.55716)
			(arc
				(start 337.278472 -58.517028)
				(mid 337.260532 -58.495982)
				(end 337.246214 -58.472324)
			)
			(xy 337.235038 -58.449972)
			(arc
				(start 337.234276 -58.449718)
				(mid 337.195994 -58.457184)
				(end 337.174332 -58.489596)
			)
			(arc
				(start 337.174332 -58.489596)
				(mid 337.077425 -58.651527)
				(end 336.899758 -58.715148)
			)
			(arc
				(start 336.899758 -58.715148)
				(mid 336.822458 -58.704273)
				(end 336.751168 -58.672476)
			)
			(arc
				(start 336.751168 -58.672476)
				(mid 336.729024 -58.69897)
				(end 336.72907 -58.733436)
			)
			(arc
				(start 336.72907 -58.733436)
				(mid 336.744091 -58.790872)
				(end 336.749136 -58.850022)
			)
			(xy 336.749136 -59.14517)
			(arc
				(start 336.803238 -59.14517)
				(mid 336.779882 -59.182968)
				(end 336.771996 -59.226704)
			)
			(arc
				(start 336.771996 -59.303666)
				(mid 336.779531 -59.347617)
				(end 336.80273 -59.385708)
			)
			(xy 336.749136 -59.385708)
			(arc
				(start 336.749136 -59.816238)
				(mid 336.822462 -59.928487)
				(end 336.848196 -60.060078)
			)
			(arc
				(start 336.848196 -60.237878)
				(mid 336.825786 -60.360807)
				(end 336.761582 -60.468002)
			)
			(xy 336.749136 -60.48248)
			(arc
				(start 336.749136 -60.514738)
				(mid 336.736626 -60.607192)
				(end 336.700114 -60.693046)
			)
			(arc
				(start 336.700114 -60.693046)
				(mid 336.69899 -60.795253)
				(end 336.787236 -60.846716)
			)
			(xy 336.837528 -60.846716)
		)
		(stroke
			(width 0)
			(type solid)
		)
		(fill yes)
		(layer "F.Cu")
		(net "GND")
	)
	(gr_poly
		(pts
			(xy 163.9062 -126.18212) (xy 163.9062 -123.76912) (xy 163.68522 -123.54814) (xy 160.28797 -123.54814)
			(xy 160.274624 -123.548543) (xy 160.248847 -123.555473) (xy 160.22575 -123.568851) (xy 160.206912 -123.587761)
			(xy 160.193623 -123.61091) (xy 160.186792 -123.636714) (xy 160.186887 -123.663405) (xy 160.189926 -123.67641)
			(xy 160.196199 -123.701018) (xy 160.202952 -123.751349) (xy 160.203388 -123.77674) (xy 160.202902 -123.803991)
			(xy 160.195146 -123.857939) (xy 160.179791 -123.910234) (xy 160.157149 -123.959811) (xy 160.127683 -124.005661)
			(xy 160.091992 -124.046852) (xy 160.050801 -124.082543) (xy 160.004951 -124.112009) (xy 159.955374 -124.134651)
			(xy 159.903079 -124.150006) (xy 159.849131 -124.157762) (xy 159.794629 -124.157762) (xy 159.740681 -124.150006)
			(xy 159.688386 -124.134651) (xy 159.638809 -124.112009) (xy 159.592959 -124.082543) (xy 159.551768 -124.046852)
			(xy 159.516077 -124.005661) (xy 159.486611 -123.959811) (xy 159.463969 -123.910234) (xy 159.448614 -123.857939)
			(xy 159.440858 -123.803991) (xy 159.440372 -123.77674) (xy 159.440768 -123.751346) (xy 159.447519 -123.701009)
			(xy 159.453834 -123.67641) (xy 159.456959 -123.663419) (xy 159.457055 -123.636707) (xy 159.450218 -123.610885)
			(xy 159.436917 -123.587721) (xy 159.418062 -123.5688) (xy 159.394944 -123.555418) (xy 159.369146 -123.548491)
			(xy 159.35579 -123.54814) (xy 158.88462 -123.54814) (xy 158.840424 -123.503944) (xy 158.77286 -123.503944)
			(xy 158.749777 -123.503512) (xy 158.704174 -123.496333) (xy 158.660254 -123.482111) (xy 158.619099 -123.461196)
			(xy 158.581721 -123.434102) (xy 158.565088 -123.418092) (xy 158.042356 -122.89536) (xy 154.36342 -122.89536)
			(xy 154.26182 -122.99696) (xy 154.26182 -123.77674) (xy 157.824422 -123.77674) (xy 157.828493 -123.721118)
			(xy 157.840619 -123.666681) (xy 157.860542 -123.61459) (xy 157.887838 -123.565955) (xy 157.921924 -123.521812)
			(xy 157.962073 -123.483103) (xy 158.007431 -123.450652) (xy 158.057031 -123.425151) (xy 158.109815 -123.407144)
			(xy 158.164658 -123.397014) (xy 158.220392 -123.394977) (xy 158.275829 -123.401077) (xy 158.329786 -123.415183)
			(xy 158.381115 -123.436995) (xy 158.428721 -123.466049) (xy 158.471589 -123.501724) (xy 158.508806 -123.543261)
			(xy 158.539579 -123.589774) (xy 158.563251 -123.640271) (xy 158.579319 -123.693678) (xy 158.587439 -123.748854)
			(xy 158.587948 -123.77674) (xy 158.587439 -123.804626) (xy 158.579319 -123.859802) (xy 158.563251 -123.913209)
			(xy 158.539579 -123.963706) (xy 158.508806 -124.010219) (xy 158.471589 -124.051756) (xy 158.428721 -124.087431)
			(xy 158.381115 -124.116485) (xy 158.329786 -124.138297) (xy 158.275829 -124.152403) (xy 158.220392 -124.158503)
			(xy 158.164658 -124.156466) (xy 158.109815 -124.146336) (xy 158.057031 -124.128329) (xy 158.007431 -124.102828)
			(xy 157.962073 -124.070377) (xy 157.921924 -124.031668) (xy 157.887838 -123.987525) (xy 157.860542 -123.93889)
			(xy 157.840619 -123.886799) (xy 157.828493 -123.832362) (xy 157.824422 -123.77674) (xy 154.26182 -123.77674)
			(xy 154.26182 -126.14656) (xy 154.51074 -126.39548) (xy 163.69284 -126.39548)
		)
		(stroke
			(width 0)
			(type solid)
		)
		(fill yes)
		(layer "F.Cu")
		(net "VR_P5V_EN_D")
	)
	(gr_poly
		(pts
			(xy 433.917598 -352.52533) (xy 433.917598 -345.322906) (xy 433.58054 -344.985848) (xy 412.091378 -344.985848)
			(xy 411.702758 -345.374468) (xy 411.702758 -346.798392) (xy 414.212532 -346.798392) (xy 414.212532 -345.223592)
			(xy 414.212919 -345.210224) (xy 414.219832 -345.184397) (xy 414.233185 -345.161235) (xy 414.252071 -345.142311)
			(xy 414.275206 -345.128911) (xy 414.301019 -345.121946) (xy 414.314386 -345.121484) (xy 415.889186 -345.121484)
			(xy 415.902567 -345.121858) (xy 415.928414 -345.128794) (xy 415.951578 -345.142194) (xy 415.970476 -345.161143)
			(xy 415.983813 -345.184344) (xy 415.990678 -345.21021) (xy 415.99104 -345.223592) (xy 415.99104 -346.798392)
			(xy 415.990816 -346.804742) (xy 420.40302 -346.804742) (xy 420.40302 -345.229942) (xy 420.403482 -345.216568)
			(xy 420.410405 -345.190731) (xy 420.42379 -345.167573) (xy 420.442721 -345.148677) (xy 420.465904 -345.135334)
			(xy 420.491753 -345.128458) (xy 420.505128 -345.128088) (xy 422.079928 -345.128088) (xy 422.093293 -345.128501)
			(xy 422.119114 -345.135415) (xy 422.142272 -345.148765) (xy 422.161195 -345.167645) (xy 422.174597 -345.190773)
			(xy 422.181568 -345.216578) (xy 422.182036 -345.229942) (xy 422.182036 -346.804742) (xy 426.60062 -346.804742)
			(xy 426.60062 -345.229942) (xy 426.601082 -345.216568) (xy 426.608005 -345.190731) (xy 426.62139 -345.167573)
			(xy 426.640321 -345.148677) (xy 426.663504 -345.135334) (xy 426.689353 -345.128458) (xy 426.702728 -345.128088)
			(xy 428.277528 -345.128088) (xy 428.290893 -345.128501) (xy 428.316714 -345.135415) (xy 428.339872 -345.148765)
			(xy 428.358795 -345.167645) (xy 428.372197 -345.190773) (xy 428.379168 -345.216578) (xy 428.379636 -345.229942)
			(xy 428.379636 -346.804742) (xy 428.379291 -346.818124) (xy 428.372344 -346.84397) (xy 428.358935 -346.867132)
			(xy 428.339982 -346.886027) (xy 428.316778 -346.899365) (xy 428.290911 -346.906232) (xy 428.277528 -346.906596)
			(xy 426.702728 -346.906596) (xy 426.689364 -346.90615) (xy 426.663543 -346.899248) (xy 426.640383 -346.885907)
			(xy 426.621458 -346.867032) (xy 426.608056 -346.843908) (xy 426.601086 -346.818105) (xy 426.60062 -346.804742)
			(xy 422.182036 -346.804742) (xy 422.181691 -346.818124) (xy 422.174744 -346.84397) (xy 422.161335 -346.867132)
			(xy 422.142382 -346.886027) (xy 422.119178 -346.899365) (xy 422.093311 -346.906232) (xy 422.079928 -346.906596)
			(xy 420.505128 -346.906596) (xy 420.491764 -346.90615) (xy 420.465943 -346.899248) (xy 420.442783 -346.885907)
			(xy 420.423858 -346.867032) (xy 420.410456 -346.843908) (xy 420.403486 -346.818105) (xy 420.40302 -346.804742)
			(xy 415.990816 -346.804742) (xy 415.990568 -346.811753) (xy 415.983665 -346.837569) (xy 415.970327 -346.860724)
			(xy 415.951458 -346.879647) (xy 415.928341 -346.893052) (xy 415.902546 -346.900029) (xy 415.889186 -346.9005)
			(xy 414.314386 -346.9005) (xy 414.301011 -346.900068) (xy 414.275175 -346.893132) (xy 414.252019 -346.879739)
			(xy 414.233125 -346.860804) (xy 414.219782 -346.837618) (xy 414.212903 -346.811768) (xy 414.212532 -346.798392)
			(xy 411.702758 -346.798392) (xy 411.702758 -352.70059) (xy 411.94863 -352.946462) (xy 433.496466 -352.946462)
		)
		(stroke
			(width 0)
			(type solid)
		)
		(fill yes)
		(layer "F.Cu")
		(net "PVCCFA_EHV_FIVRA_CPU0")
	)
	(gr_poly
		(pts
			(arc
				(start 464.757516 -430.081436)
				(mid 464.780726 -430.062842)
				(end 464.78952 -430.034446)
			)
			(arc
				(start 464.78952 -409.528264)
				(mid 464.980687 -408.567674)
				(end 465.52485 -407.753312)
			)
			(arc
				(start 467.353396 -405.924766)
				(mid 467.676179 -405.441593)
				(end 467.789514 -404.871682)
			)
			(arc
				(start 467.789514 -352.8822)
				(mid 467.780298 -352.853021)
				(end 467.755986 -352.834448)
			)
			(xy 467.651084 -352.796348) (xy 467.620096 -352.80473)
			(arc
				(start 467.609936 -352.817176)
				(mid 467.455595 -352.997173)
				(end 467.295992 -353.172522)
			)
			(arc
				(start 467.295992 -353.172522)
				(mid 467.28579 -353.188608)
				(end 467.282276 -353.20732)
			)
			(arc
				(start 467.282276 -358.935274)
				(mid 467.282971 -358.943649)
				(end 467.28507 -358.951784)
			)
			(arc
				(start 467.28507 -358.951784)
				(mid 467.514143 -359.844958)
				(end 467.59114 -360.76382)
			)
			(arc
				(start 467.59114 -360.76382)
				(mid 467.514149 -361.682683)
				(end 467.28507 -362.575856)
			)
			(arc
				(start 467.28507 -362.575856)
				(mid 467.283005 -362.583996)
				(end 467.282276 -362.592366)
			)
			(arc
				(start 467.282276 -404.871936)
				(mid 467.207495 -405.247595)
				(end 466.994748 -405.566118)
			)
			(arc
				(start 465.166202 -407.394664)
				(mid 464.512036 -408.373553)
				(end 464.282282 -409.528264)
			)
			(xy 464.282028 -409.528264)
			(arc
				(start 464.282028 -429.750982)
				(mid 464.28621 -429.771166)
				(end 464.29803 -429.788066)
			)
			(arc
				(start 464.29803 -429.788066)
				(mid 464.458224 -429.943848)
				(end 464.614006 -430.104042)
			)
			(xy 464.624928 -430.115472) (xy 464.655154 -430.12233)
		)
		(stroke
			(width 0)
			(type solid)
		)
		(fill yes)
		(layer "F.Cu")
		(net "GND")
	)
	(gr_poly
		(pts
			(xy 431.05324 -373.756428) (xy 431.05324 -362.435394) (xy 430.922938 -362.305092) (xy 426.260514 -362.305092)
			(xy 426.200062 -362.365544) (xy 426.200062 -364.357412) (xy 426.281088 -364.438438) (xy 427.573948 -364.438438)
			(xy 427.581822 -364.446566) (xy 427.582076 -364.446566) (xy 427.741588 -364.606078) (xy 427.741588 -365.269272)
			(xy 428.108618 -365.636302) (xy 428.108618 -367.463324) (xy 427.349158 -368.222784) (xy 421.299894 -368.222784)
			(xy 420.534338 -367.457228) (xy 420.534338 -364.937294) (xy 421.034464 -364.437168) (xy 421.034464 -362.355892)
			(xy 420.983664 -362.305092) (xy 416.51682 -362.305092) (xy 416.50666 -362.315252) (xy 416.50666 -364.370366)
			(xy 416.573462 -364.43666) (xy 417.931346 -364.43666) (xy 417.940998 -364.446566) (xy 417.941252 -364.446566)
			(xy 418.062664 -364.567978) (xy 418.062664 -364.680754) (xy 418.062918 -364.687358) (xy 418.062918 -365.28756)
			(xy 418.060886 -365.315246) (xy 418.05733 -365.340138) (xy 418.44722 -365.730282) (xy 418.44722 -368.731292)
			(xy 419.308788 -369.59286) (xy 419.308788 -371.7684) (xy 425.815757 -371.7684) (xy 425.819788 -371.683798)
			(xy 425.831841 -371.599961) (xy 425.851809 -371.51765) (xy 425.879511 -371.43761) (xy 425.914695 -371.360565)
			(xy 425.957044 -371.287214) (xy 426.006173 -371.21822) (xy 426.061638 -371.154209) (xy 426.122936 -371.095759)
			(xy 426.189513 -371.043401) (xy 426.260765 -370.997609) (xy 426.336047 -370.958796) (xy 426.414678 -370.927315)
			(xy 426.495945 -370.903451) (xy 426.579112 -370.88742) (xy 426.663427 -370.879367) (xy 426.705776 -370.878862)
			(xy 426.750257 -370.879419) (xy 426.838774 -370.888305) (xy 426.925961 -370.905983) (xy 427.010949 -370.932274)
			(xy 427.092889 -370.966917) (xy 427.170961 -371.009565) (xy 427.244388 -371.059792) (xy 427.312434 -371.117098)
			(xy 427.374421 -371.180908) (xy 427.402498 -371.215412) (xy 427.40707 -371.220746) (xy 427.432617 -371.254266)
			(xy 427.477972 -371.325309) (xy 427.516406 -371.400322) (xy 427.547576 -371.478633) (xy 427.571201 -371.55954)
			(xy 427.587071 -371.642319) (xy 427.595043 -371.726227) (xy 427.595538 -371.76837) (xy 427.59507 -371.810514)
			(xy 427.5871 -371.894425) (xy 427.571231 -371.977205) (xy 427.547602 -372.058114) (xy 427.516427 -372.136425)
			(xy 427.477985 -372.211436) (xy 427.432621 -372.282475) (xy 427.40707 -372.315994) (xy 427.402498 -372.321328)
			(xy 427.374419 -372.355832) (xy 427.312439 -372.419652) (xy 427.244397 -372.476966) (xy 427.170973 -372.527199)
			(xy 427.0929 -372.569851) (xy 427.010959 -372.604495) (xy 426.925968 -372.630785) (xy 426.838777 -372.648459)
			(xy 426.750258 -372.657338) (xy 426.705776 -372.657878) (xy 426.663427 -372.657433) (xy 426.579112 -372.64938)
			(xy 426.495945 -372.633349) (xy 426.414678 -372.609485) (xy 426.336047 -372.578004) (xy 426.260765 -372.539191)
			(xy 426.189513 -372.493399) (xy 426.122936 -372.441041) (xy 426.061638 -372.382591) (xy 426.006173 -372.31858)
			(xy 425.957044 -372.249586) (xy 425.914695 -372.176235) (xy 425.879511 -372.09919) (xy 425.851809 -372.01915)
			(xy 425.831841 -371.936839) (xy 425.819788 -371.853002) (xy 425.815757 -371.7684) (xy 419.308788 -371.7684)
			(xy 419.308788 -374.43156) (xy 419.604952 -374.727724) (xy 430.081944 -374.727724)
		)
		(stroke
			(width 0)
			(type solid)
		)
		(fill yes)
		(layer "F.Cu")
		(net "SW_P12V_PVCCFA_EHV_FIVRA_CPU0_R")
	)
	(gr_poly
		(pts
			(xy 244.369336 -406.508204) (xy 244.36959 -406.503886) (xy 244.36959 -406.502616) (xy 244.36959 -406.477216)
			(xy 244.373908 -406.472898)
			(arc
				(start 244.377718 -406.462738)
				(mid 244.406767 -406.417959)
				(end 244.451632 -406.389078)
			)
			(xy 244.461792 -406.385014) (xy 244.592856 -406.25395) (xy 244.908832 -406.25395) (xy 245.039896 -406.385014)
			(arc
				(start 245.050056 -406.389078)
				(mid 245.098992 -406.422493)
				(end 245.127526 -406.474422)
			)
			(xy 245.12778 -406.475184) (xy 245.128796 -406.478486) (xy 245.132098 -406.486614) (xy 245.132098 -406.502616)
			(xy 245.132098 -406.503886) (xy 245.132352 -406.508204) (xy 245.132352 -406.781) (xy 252.398784 -406.781)
			(xy 252.398784 -406.512268) (xy 252.399038 -406.50668) (xy 252.399038 -406.50541) (xy 252.399038 -406.48128)
			(xy 252.403102 -406.477216) (xy 252.407166 -406.467056)
			(arc
				(start 252.407166 -406.466802)
				(mid 252.436215 -406.422023)
				(end 252.48108 -406.393142)
			)
			(xy 252.49124 -406.389078) (xy 252.622304 -406.258014) (xy 252.93828 -406.258014) (xy 253.069344 -406.389078)
			(arc
				(start 253.079504 -406.393142)
				(mid 253.128709 -406.426854)
				(end 253.157228 -406.479248)
			)
			(xy 253.158244 -406.48255) (xy 253.161546 -406.490678) (xy 253.161546 -406.50541) (xy 253.161546 -406.50668)
			(xy 253.1618 -406.512268) (xy 253.1618 -406.781) (xy 260.425184 -406.781) (xy 260.425184 -406.512014)
			(xy 260.425438 -406.50541) (xy 260.425438 -406.50414) (xy 260.425438 -406.48128) (xy 260.429502 -406.477216)
			(arc
				(start 260.433566 -406.467056)
				(mid 260.462594 -406.42217)
				(end 260.50748 -406.393142)
			)
			(xy 260.51764 -406.389078) (xy 260.648704 -406.258014) (xy 260.96468 -406.258014) (xy 261.095744 -406.389078)
			(arc
				(start 261.105904 -406.393142)
				(mid 261.155112 -406.426711)
				(end 261.183628 -406.478994)
			)
			(xy 261.18439 -406.482042) (xy 261.187946 -406.490678) (xy 261.187946 -406.50414) (xy 261.187946 -406.50541)
			(xy 261.1882 -406.512014) (xy 261.1882 -406.781) (xy 268.451838 -406.781) (xy 268.451838 -406.774396)
			(xy 268.451584 -406.766268) (xy 268.451584 -406.512268) (xy 268.451838 -406.50414) (xy 268.451838 -406.48128)
			(arc
				(start 268.456664 -406.476454)
				(mid 268.488894 -406.42207)
				(end 268.543278 -406.38984)
			)
			(xy 268.675104 -406.258014) (xy 268.99108 -406.258014)
			(arc
				(start 269.122906 -406.38984)
				(mid 269.179208 -406.42403)
				(end 269.21079 -406.481788)
			)
			(xy 269.214346 -406.490678) (xy 269.214346 -406.50414) (xy 269.2146 -406.512268) (xy 269.2146 -406.766268)
			(xy 269.214346 -406.774396) (xy 269.214346 -406.781) (xy 273.812 -406.781) (xy 274.32 -406.273) (xy 274.32 -397.637)
			(xy 274.066 -397.383) (xy 240.157 -397.383) (xy 239.649 -397.891) (xy 239.649 -406.527) (xy 239.903 -406.781)
			(xy 244.369336 -406.781)
		)
		(stroke
			(width 0)
			(type solid)
		)
		(fill yes)
		(layer "F.Cu")
		(net "P12V_MAIN_R")
	)
	(gr_poly
		(pts
			(arc
				(start 94.819978 -441.479432)
				(mid 94.848411 -441.470901)
				(end 94.867222 -441.447936)
			)
			(xy 94.908624 -441.346336) (xy 94.902274 -441.316364)
			(arc
				(start 94.891352 -441.305442)
				(mid 94.736646 -441.149171)
				(end 94.586298 -440.988704)
			)
			(arc
				(start 94.586298 -440.988704)
				(mid 94.569285 -440.976299)
				(end 94.548706 -440.97194)
			)
			(xy 87.81796 -440.97194)
			(arc
				(start 87.810086 -440.974734)
				(mid 87.7311 -440.993945)
				(end 87.650066 -441.000388)
			)
			(arc
				(start 87.650066 -441.000388)
				(mid 87.56903 -440.993957)
				(end 87.490046 -440.974734)
			)
			(xy 87.482172 -440.97194) (xy 83.817968 -440.97194)
			(arc
				(start 83.810094 -440.974734)
				(mid 83.731108 -440.993945)
				(end 83.650074 -441.000388)
			)
			(arc
				(start 83.650074 -441.000388)
				(mid 83.569038 -440.993957)
				(end 83.490054 -440.974734)
			)
			(xy 83.48218 -440.97194) (xy 79.817976 -440.97194)
			(arc
				(start 79.810102 -440.974734)
				(mid 79.731116 -440.993945)
				(end 79.650082 -441.000388)
			)
			(arc
				(start 79.650082 -441.000388)
				(mid 79.569046 -440.993957)
				(end 79.490062 -440.974734)
			)
			(xy 79.482188 -440.97194) (xy 76.122022 -440.97194) (xy 76.10856 -440.976004)
			(arc
				(start 76.10221 -440.980068)
				(mid 76.069259 -440.995208)
				(end 76.033376 -441.000388)
			)
			(arc
				(start 75.266804 -441.000388)
				(mid 75.230937 -440.995154)
				(end 75.19797 -440.980068)
			)
			(xy 75.19162 -440.976004) (xy 75.178158 -440.97194) (xy 70.817994 -440.97194)
			(arc
				(start 70.81012 -440.974734)
				(mid 70.731134 -440.993945)
				(end 70.6501 -441.000388)
			)
			(arc
				(start 70.6501 -441.000388)
				(mid 70.569064 -440.993957)
				(end 70.49008 -440.974734)
			)
			(xy 70.482206 -440.97194) (xy 66.818002 -440.97194)
			(arc
				(start 66.810128 -440.974734)
				(mid 66.731142 -440.993945)
				(end 66.650108 -441.000388)
			)
			(arc
				(start 66.650108 -441.000388)
				(mid 66.569072 -440.993957)
				(end 66.490088 -440.974734)
			)
			(xy 66.482214 -440.97194) (xy 62.81801 -440.97194)
			(arc
				(start 62.810136 -440.974734)
				(mid 62.73115 -440.993945)
				(end 62.650116 -441.000388)
			)
			(arc
				(start 62.650116 -441.000388)
				(mid 62.56908 -440.993957)
				(end 62.490096 -440.974734)
			)
			(xy 62.482222 -440.97194) (xy 59.122056 -440.97194) (xy 59.108594 -440.976004)
			(arc
				(start 59.102244 -440.980068)
				(mid 59.069171 -440.995244)
				(end 59.033156 -441.000388)
			)
			(arc
				(start 58.267092 -441.000388)
				(mid 58.231093 -440.99519)
				(end 58.198004 -440.980068)
			)
			(xy 58.191654 -440.976004) (xy 58.178192 -440.97194)
			(arc
				(start 18.951448 -440.97194)
				(mid 18.93091 -440.976389)
				(end 18.913856 -440.988704)
			)
			(arc
				(start 18.913856 -440.988704)
				(mid 18.763504 -441.149167)
				(end 18.608802 -441.305442)
			)
			(xy 18.59788 -441.316364) (xy 18.59153 -441.346336)
			(arc
				(start 18.632932 -441.447936)
				(mid 18.651743 -441.470901)
				(end 18.680176 -441.479432)
			)
		)
		(stroke
			(width 0)
			(type solid)
		)
		(fill yes)
		(layer "F.Cu")
		(net "GND")
	)
	(gr_poly
		(pts
			(arc
				(start 174.069756 -441.479432)
				(mid 174.098189 -441.470901)
				(end 174.117 -441.447936)
			)
			(xy 174.158402 -441.346336) (xy 174.152052 -441.316364)
			(arc
				(start 174.14113 -441.305442)
				(mid 173.986424 -441.149171)
				(end 173.836076 -440.988704)
			)
			(arc
				(start 173.836076 -440.988704)
				(mid 173.819063 -440.976299)
				(end 173.798484 -440.97194)
			)
			(xy 154.917902 -440.97194)
			(arc
				(start 154.910028 -440.974734)
				(mid 154.831042 -440.993945)
				(end 154.750008 -441.000388)
			)
			(arc
				(start 154.750008 -441.000388)
				(mid 154.668972 -440.993957)
				(end 154.589988 -440.974734)
			)
			(xy 154.582114 -440.97194) (xy 150.91791 -440.97194)
			(arc
				(start 150.910036 -440.974734)
				(mid 150.83105 -440.993945)
				(end 150.750016 -441.000388)
			)
			(arc
				(start 150.750016 -441.000388)
				(mid 150.66898 -440.993957)
				(end 150.589996 -440.974734)
			)
			(xy 150.582122 -440.97194) (xy 146.917918 -440.97194)
			(arc
				(start 146.910044 -440.974734)
				(mid 146.831058 -440.993945)
				(end 146.750024 -441.000388)
			)
			(arc
				(start 146.750024 -441.000388)
				(mid 146.668988 -440.993957)
				(end 146.590004 -440.974734)
			)
			(xy 146.58213 -440.97194) (xy 143.221964 -440.97194) (xy 143.208502 -440.976004)
			(arc
				(start 143.202152 -440.980068)
				(mid 143.169079 -440.995244)
				(end 143.133064 -441.000388)
			)
			(arc
				(start 142.367 -441.000388)
				(mid 142.331001 -440.99519)
				(end 142.297912 -440.980068)
			)
			(xy 142.291562 -440.976004) (xy 142.2781 -440.97194) (xy 137.917936 -440.97194)
			(arc
				(start 137.910062 -440.974734)
				(mid 137.831076 -440.993945)
				(end 137.750042 -441.000388)
			)
			(arc
				(start 137.750042 -441.000388)
				(mid 137.669006 -440.993957)
				(end 137.590022 -440.974734)
			)
			(xy 137.582148 -440.97194) (xy 133.917944 -440.97194)
			(arc
				(start 133.91007 -440.974734)
				(mid 133.831084 -440.993945)
				(end 133.75005 -441.000388)
			)
			(arc
				(start 133.75005 -441.000388)
				(mid 133.669014 -440.993957)
				(end 133.59003 -440.974734)
			)
			(xy 133.582156 -440.97194) (xy 129.917952 -440.97194)
			(arc
				(start 129.910078 -440.974734)
				(mid 129.831092 -440.993945)
				(end 129.750058 -441.000388)
			)
			(arc
				(start 129.750058 -441.000388)
				(mid 129.669022 -440.993957)
				(end 129.590038 -440.974734)
			)
			(xy 129.582164 -440.97194) (xy 126.221998 -440.97194) (xy 126.208536 -440.976004)
			(arc
				(start 126.202186 -440.980068)
				(mid 126.169235 -440.995208)
				(end 126.133352 -441.000388)
			)
			(arc
				(start 125.36678 -441.000388)
				(mid 125.330913 -440.995154)
				(end 125.297946 -440.980068)
			)
			(xy 125.291596 -440.976004) (xy 125.278134 -440.97194)
			(arc
				(start 106.451654 -440.97194)
				(mid 106.431116 -440.976389)
				(end 106.414062 -440.988704)
			)
			(arc
				(start 106.414062 -440.988704)
				(mid 106.26371 -441.149167)
				(end 106.109008 -441.305442)
			)
			(xy 106.098086 -441.316364) (xy 106.091736 -441.346336)
			(arc
				(start 106.133138 -441.447936)
				(mid 106.151949 -441.470901)
				(end 106.180382 -441.479432)
			)
		)
		(stroke
			(width 0)
			(type solid)
		)
		(fill yes)
		(layer "F.Cu")
		(net "GND")
	)
	(gr_poly
		(pts
			(arc
				(start 453.119744 -441.479432)
				(mid 453.148177 -441.470901)
				(end 453.166988 -441.447936)
			)
			(xy 453.20839 -441.346336) (xy 453.20204 -441.316364)
			(arc
				(start 453.191118 -441.305442)
				(mid 453.036412 -441.149171)
				(end 452.886064 -440.988704)
			)
			(arc
				(start 452.886064 -440.988704)
				(mid 452.869051 -440.976299)
				(end 452.848472 -440.97194)
			)
			(xy 410.917898 -440.97194)
			(arc
				(start 410.910024 -440.974734)
				(mid 410.831038 -440.993945)
				(end 410.750004 -441.000388)
			)
			(arc
				(start 410.750004 -441.000388)
				(mid 410.668968 -440.993957)
				(end 410.589984 -440.974734)
			)
			(xy 410.58211 -440.97194) (xy 406.917906 -440.97194)
			(arc
				(start 406.910032 -440.974734)
				(mid 406.831046 -440.993945)
				(end 406.750012 -441.000388)
			)
			(arc
				(start 406.750012 -441.000388)
				(mid 406.668976 -440.993957)
				(end 406.589992 -440.974734)
			)
			(xy 406.582118 -440.97194) (xy 402.917914 -440.97194)
			(arc
				(start 402.91004 -440.974734)
				(mid 402.831054 -440.993945)
				(end 402.75002 -441.000388)
			)
			(arc
				(start 402.75002 -441.000388)
				(mid 402.668984 -440.993957)
				(end 402.59 -440.974734)
			)
			(xy 402.582126 -440.97194) (xy 399.22196 -440.97194) (xy 399.208498 -440.976004)
			(arc
				(start 399.202148 -440.980068)
				(mid 399.169075 -440.995244)
				(end 399.13306 -441.000388)
			)
			(arc
				(start 398.366996 -441.000388)
				(mid 398.330997 -440.99519)
				(end 398.297908 -440.980068)
			)
			(xy 398.291558 -440.976004) (xy 398.278096 -440.97194) (xy 393.917932 -440.97194)
			(arc
				(start 393.910058 -440.974734)
				(mid 393.831072 -440.993945)
				(end 393.750038 -441.000388)
			)
			(arc
				(start 393.750038 -441.000388)
				(mid 393.669002 -440.993957)
				(end 393.590018 -440.974734)
			)
			(xy 393.582144 -440.97194) (xy 389.91794 -440.97194)
			(arc
				(start 389.910066 -440.974734)
				(mid 389.83108 -440.993945)
				(end 389.750046 -441.000388)
			)
			(arc
				(start 389.750046 -441.000388)
				(mid 389.66901 -440.993957)
				(end 389.590026 -440.974734)
			)
			(xy 389.582152 -440.97194) (xy 385.917948 -440.97194)
			(arc
				(start 385.910074 -440.974734)
				(mid 385.831088 -440.993945)
				(end 385.750054 -441.000388)
			)
			(arc
				(start 385.750054 -441.000388)
				(mid 385.669018 -440.993957)
				(end 385.590034 -440.974734)
			)
			(xy 385.58216 -440.97194) (xy 382.221994 -440.97194) (xy 382.208532 -440.976004)
			(arc
				(start 382.202182 -440.980068)
				(mid 382.169231 -440.995208)
				(end 382.133348 -441.000388)
			)
			(arc
				(start 381.366776 -441.000388)
				(mid 381.330909 -440.995154)
				(end 381.297942 -440.980068)
			)
			(xy 381.291592 -440.976004) (xy 381.27813 -440.97194)
			(arc
				(start 377.249944 -440.97194)
				(mid 377.229406 -440.976389)
				(end 377.212352 -440.988704)
			)
			(arc
				(start 377.212352 -440.988704)
				(mid 377.062 -441.149167)
				(end 376.907298 -441.305442)
			)
			(xy 376.896376 -441.316364) (xy 376.890026 -441.346336)
			(arc
				(start 376.931428 -441.447936)
				(mid 376.950239 -441.470901)
				(end 376.978672 -441.479432)
			)
		)
		(stroke
			(width 0)
			(type solid)
		)
		(fill yes)
		(layer "F.Cu")
		(net "GND")
	)
	(gr_poly
		(pts
			(xy 88.48979 -60.533026) (xy 88.48979 -57.682638) (xy 88.27516 -57.468008) (xy 87.76716 -57.468008)
			(xy 87.62492 -57.610248) (xy 87.62492 -58.151268) (xy 87.531702 -58.244486) (xy 86.73719 -58.244486)
			(xy 86.43239 -57.939686) (xy 86.43239 -57.657238) (xy 86.409276 -57.634124)
			(arc
				(start 86.376256 -57.634124)
				(mid 86.254142 -57.609722)
				(end 86.150704 -57.540398)
			)
			(xy 86.041738 -57.431686) (xy 85.64499 -57.431686) (xy 85.59419 -57.482486) (xy 85.59419 -59.819286)
			(xy 85.5599 -59.853576)
			(arc
				(start 85.556344 -59.866784)
				(mid 85.420169 -60.070967)
				(end 85.18779 -60.149994)
			)
			(arc
				(start 85.18779 -60.149994)
				(mid 84.969157 -60.081188)
				(end 84.829396 -59.89955)
			)
			(xy 84.825586 -59.888882) (xy 84.80679 -59.870086) (xy 84.80679 -59.787028) (xy 84.806282 -59.768486)
			(xy 84.80679 -59.749944) (xy 84.80679 -59.372246) (xy 84.69757 -59.263026) (xy 83.30057 -59.263026)
			(xy 83.282536 -59.244992) (xy 83.239864 -59.244992) (xy 83.239864 -59.20232) (xy 83.17103 -59.133486)
			(xy 83.17103 -58.240676) (xy 83.170776 -58.238136) (xy 83.168998 -58.201306) (xy 83.170776 -58.164476)
			(xy 83.17103 -58.161936) (xy 83.17103 -56.659526) (xy 83.28025 -56.550306) (xy 83.60029 -56.550306)
			(xy 83.67395 -56.476646) (xy 83.67395 -56.392826) (xy 83.59775 -56.316626) (xy 82.97799 -56.316626)
			(xy 82.93735 -56.357266) (xy 82.93735 -57.078626) (xy 82.274156 -57.74182)
			(arc
				(start 82.274156 -58.021474)
				(mid 82.320681 -58.12143)
				(end 82.33664 -58.230516)
			)
			(arc
				(start 82.33664 -58.230516)
				(mid 82.32064 -58.33959)
				(end 82.274156 -58.439558)
			)
			(arc
				(start 82.274156 -58.836814)
				(mid 82.270924 -58.882366)
				(end 82.261202 -58.926984)
			)
			(xy 82.25917 -58.934096) (xy 82.25917 -59.303158) (xy 82.121502 -59.440826) (xy 81.49717 -59.440826)
			(xy 81.44637 -59.491626)
			(arc
				(start 81.44637 -60.064396)
				(mid 81.474003 -60.134048)
				(end 81.541874 -60.165742)
			)
			(arc
				(start 81.541874 -60.165742)
				(mid 81.796536 -60.285064)
				(end 81.900268 -60.546488)
			)
			(arc
				(start 81.900268 -60.546488)
				(mid 81.871638 -60.691489)
				(end 81.790032 -60.814712)
			)
			(arc
				(start 81.790032 -60.814712)
				(mid 81.768639 -60.925321)
				(end 81.862422 -60.987686)
			)
			(xy 86.43239 -60.987686) (xy 86.467696 -61.022992) (xy 87.999824 -61.022992)
		)
		(stroke
			(width 0)
			(type solid)
		)
		(fill yes)
		(layer "F.Cu")
		(net "GND")
	)
	(gr_poly
		(pts
			(xy 303.521872 -353.53244) (xy 303.521872 -346.583508) (xy 303.502547 -346.552639) (xy 303.470302 -346.487334)
			(xy 303.445732 -346.418772) (xy 303.429161 -346.34785) (xy 303.420804 -346.2755) (xy 303.420272 -346.239084)
			(xy 303.420957 -346.19744) (xy 303.431915 -346.114874) (xy 303.442116 -346.074492) (xy 303.445195 -346.06152)
			(xy 303.44522 -346.034868) (xy 303.438345 -346.009118) (xy 303.425038 -345.986025) (xy 303.406208 -345.967163)
			(xy 303.383137 -345.953819) (xy 303.357398 -345.946902) (xy 303.344072 -345.946476) (xy 302.351948 -345.946476)
			(xy 302.02378 -345.618308) (xy 281.402028 -345.618308) (xy 281.087068 -345.933268) (xy 281.087068 -347.487748)
			(xy 286.409892 -347.487748) (xy 286.409892 -345.912948) (xy 286.410331 -345.89956) (xy 286.417252 -345.873693)
			(xy 286.430632 -345.8505) (xy 286.449562 -345.831562) (xy 286.472749 -345.81817) (xy 286.498612 -345.811238)
			(xy 286.512 -345.81084) (xy 288.0868 -345.81084) (xy 288.100194 -345.81119) (xy 288.12607 -345.818126)
			(xy 288.149268 -345.831524) (xy 288.168206 -345.850471) (xy 288.181593 -345.873675) (xy 288.188516 -345.899553)
			(xy 288.188908 -345.912948) (xy 288.188908 -347.487748) (xy 292.607492 -347.487748) (xy 292.607492 -345.912948)
			(xy 292.607931 -345.89956) (xy 292.614852 -345.873693) (xy 292.628232 -345.8505) (xy 292.647162 -345.831562)
			(xy 292.670349 -345.81817) (xy 292.696212 -345.811238) (xy 292.7096 -345.81084) (xy 294.2844 -345.81084)
			(xy 294.297794 -345.81119) (xy 294.32367 -345.818126) (xy 294.346868 -345.831524) (xy 294.365806 -345.850471)
			(xy 294.379193 -345.873675) (xy 294.386116 -345.899553) (xy 294.386508 -345.912948) (xy 294.386508 -347.487748)
			(xy 298.805092 -347.487748) (xy 298.805092 -345.912948) (xy 298.805531 -345.89956) (xy 298.812452 -345.873693)
			(xy 298.825832 -345.8505) (xy 298.844762 -345.831562) (xy 298.867949 -345.81817) (xy 298.893812 -345.811238)
			(xy 298.9072 -345.81084) (xy 300.482 -345.81084) (xy 300.495394 -345.81119) (xy 300.52127 -345.818126)
			(xy 300.544468 -345.831524) (xy 300.563406 -345.850471) (xy 300.576793 -345.873675) (xy 300.583716 -345.899553)
			(xy 300.584108 -345.912948) (xy 300.584108 -347.487748) (xy 300.583713 -347.501135) (xy 300.576773 -347.526996)
			(xy 300.563379 -347.550179) (xy 300.544441 -347.569108) (xy 300.521251 -347.582492) (xy 300.495388 -347.58942)
			(xy 300.482 -347.589856) (xy 298.9072 -347.589856) (xy 298.893819 -347.589372) (xy 298.867968 -347.582447)
			(xy 298.844788 -347.569069) (xy 298.82586 -347.55015) (xy 298.812471 -347.526977) (xy 298.805535 -347.501129)
			(xy 298.805092 -347.487748) (xy 294.386508 -347.487748) (xy 294.386113 -347.501135) (xy 294.379173 -347.526996)
			(xy 294.365779 -347.550179) (xy 294.346841 -347.569108) (xy 294.323651 -347.582492) (xy 294.297788 -347.58942)
			(xy 294.2844 -347.589856) (xy 292.7096 -347.589856) (xy 292.696219 -347.589372) (xy 292.670368 -347.582447)
			(xy 292.647188 -347.569069) (xy 292.62826 -347.55015) (xy 292.614871 -347.526977) (xy 292.607935 -347.501129)
			(xy 292.607492 -347.487748) (xy 288.188908 -347.487748) (xy 288.188513 -347.501135) (xy 288.181573 -347.526996)
			(xy 288.168179 -347.550179) (xy 288.149241 -347.569108) (xy 288.126051 -347.582492) (xy 288.100188 -347.58942)
			(xy 288.0868 -347.589856) (xy 286.512 -347.589856) (xy 286.498619 -347.589372) (xy 286.472768 -347.582447)
			(xy 286.449588 -347.569069) (xy 286.43066 -347.55015) (xy 286.417271 -347.526977) (xy 286.410335 -347.501129)
			(xy 286.409892 -347.487748) (xy 281.087068 -347.487748) (xy 281.087068 -353.479608) (xy 281.241754 -353.634294)
			(xy 303.420018 -353.634294)
		)
		(stroke
			(width 0)
			(type solid)
		)
		(fill yes)
		(layer "F.Cu")
		(net "PVCCFA_EHV_FIVRA_CPU0")
	)
	(gr_poly
		(pts
			(xy 56.887618 -344.19413) (xy 56.887618 -337.457796) (xy 56.864873 -337.433009) (xy 56.824177 -337.379436)
			(xy 56.789373 -337.32186) (xy 56.760853 -337.260927) (xy 56.738934 -337.19732) (xy 56.723864 -337.131753)
			(xy 56.71581 -337.064959) (xy 56.714898 -337.03133) (xy 56.714644 -337.022186) (xy 56.715411 -336.978103)
			(xy 56.727643 -336.89079) (xy 56.739028 -336.848196) (xy 56.745886 -336.823812) (xy 56.681878 -336.738976)
			(xy 56.674237 -336.729944) (xy 56.653054 -336.71947) (xy 56.641238 -336.71891) (xy 56.05018 -336.71891)
			(xy 56.040111 -336.718484) (xy 56.021511 -336.710765) (xy 56.014112 -336.703924) (xy 55.749698 -336.43951)
			(xy 34.225738 -336.43951) (xy 33.83788 -336.827368) (xy 33.83788 -338.258658) (xy 39.616888 -338.258658)
			(xy 39.616888 -336.683858) (xy 39.617209 -336.670474) (xy 39.624158 -336.644625) (xy 39.637571 -336.62146)
			(xy 39.656529 -336.602564) (xy 39.679739 -336.589228) (xy 39.705611 -336.582365) (xy 39.718996 -336.582004)
			(xy 41.293796 -336.582004) (xy 41.307161 -336.582429) (xy 41.332983 -336.589337) (xy 41.356143 -336.602683)
			(xy 41.375067 -336.621561) (xy 41.388469 -336.644689) (xy 41.395438 -336.670494) (xy 41.395904 -336.683858)
			(xy 41.395904 -338.258658) (xy 41.395721 -338.265008) (xy 45.807884 -338.265008) (xy 45.807884 -336.690208)
			(xy 45.808333 -336.676845) (xy 45.815237 -336.651026) (xy 45.828579 -336.627868) (xy 45.847453 -336.608944)
			(xy 45.870575 -336.595541) (xy 45.896376 -336.588568) (xy 45.909738 -336.5881) (xy 47.484538 -336.5881)
			(xy 47.497914 -336.588511) (xy 47.52375 -336.595452) (xy 47.546906 -336.60885) (xy 47.5658 -336.62779)
			(xy 47.579142 -336.650978) (xy 47.586021 -336.676831) (xy 47.586392 -336.690208) (xy 47.586392 -338.265008)
			(xy 52.005484 -338.265008) (xy 52.005484 -336.690208) (xy 52.005933 -336.676845) (xy 52.012837 -336.651026)
			(xy 52.026179 -336.627868) (xy 52.045053 -336.608944) (xy 52.068175 -336.595541) (xy 52.093976 -336.588568)
			(xy 52.107338 -336.5881) (xy 53.682138 -336.5881) (xy 53.695514 -336.588511) (xy 53.72135 -336.595452)
			(xy 53.744506 -336.60885) (xy 53.7634 -336.62779) (xy 53.776742 -336.650978) (xy 53.783621 -336.676831)
			(xy 53.783992 -336.690208) (xy 53.783992 -338.265008) (xy 53.783581 -338.278374) (xy 53.776671 -338.304197)
			(xy 53.763322 -338.327357) (xy 53.744441 -338.346281) (xy 53.72131 -338.359682) (xy 53.695503 -338.366651)
			(xy 53.682138 -338.367116) (xy 52.107338 -338.367116) (xy 52.093958 -338.366721) (xy 52.068112 -338.359791)
			(xy 52.044948 -338.346395) (xy 52.02605 -338.32745) (xy 52.012711 -338.304252) (xy 52.005846 -338.278389)
			(xy 52.005484 -338.265008) (xy 47.586392 -338.265008) (xy 47.585981 -338.278374) (xy 47.579071 -338.304197)
			(xy 47.565722 -338.327357) (xy 47.546841 -338.346281) (xy 47.52371 -338.359682) (xy 47.497903 -338.366651)
			(xy 47.484538 -338.367116) (xy 45.909738 -338.367116) (xy 45.896358 -338.366721) (xy 45.870512 -338.359791)
			(xy 45.847348 -338.346395) (xy 45.82845 -338.32745) (xy 45.815111 -338.304252) (xy 45.808246 -338.278389)
			(xy 45.807884 -338.265008) (xy 41.395721 -338.265008) (xy 41.395518 -338.272039) (xy 41.388587 -338.297886)
			(xy 41.37519 -338.321052) (xy 41.356243 -338.339951) (xy 41.333043 -338.353288) (xy 41.307178 -338.360152)
			(xy 41.293796 -338.360512) (xy 39.718996 -338.360512) (xy 39.705632 -338.360078) (xy 39.679812 -338.35317)
			(xy 39.656654 -338.339825) (xy 39.63773 -338.320949) (xy 39.624328 -338.297824) (xy 39.617356 -338.272021)
			(xy 39.616888 -338.258658) (xy 33.83788 -338.258658) (xy 33.83788 -344.084148) (xy 34.16046 -344.406728)
			(xy 56.67502 -344.406728)
		)
		(stroke
			(width 0)
			(type solid)
		)
		(fill yes)
		(layer "F.Cu")
		(net "PVCCFA_EHV_FIVRA_CPU1")
	)
	(gr_poly
		(pts
			(xy 435.19598 -57.498488) (xy 435.19598 -54.290468) (xy 435.058058 -54.152546) (xy 433.625498 -54.152546)
			(xy 433.1335 -53.660548) (xy 433.1335 -46.942248) (xy 432.602894 -46.411642) (xy 423.02176 -46.411642)
			(xy 422.319704 -47.113698) (xy 422.319704 -47.977298) (xy 422.472104 -48.129698) (xy 423.084752 -48.129698)
			(xy 423.61993 -48.664876) (xy 423.61993 -48.837342) (xy 423.638784 -48.85858) (xy 423.67064 -48.905593)
			(xy 423.695167 -48.956812) (xy 423.711823 -49.011104) (xy 423.72024 -49.067265) (xy 423.720768 -49.09566)
			(xy 423.72031 -49.122255) (xy 423.712928 -49.17493) (xy 423.698301 -49.22607) (xy 423.676713 -49.274682)
			(xy 423.648583 -49.319825) (xy 423.631868 -49.340516) (xy 423.61993 -49.35474) (xy 423.61993 -49.41697)
			(xy 423.55516 -49.48174) (xy 423.29862 -49.48174) (xy 423.29354 -49.47666) (xy 422.36644 -49.47666)
			(xy 422.24706 -49.59604) (xy 422.24706 -50.136044) (xy 422.407334 -50.296318) (xy 423.882312 -50.296318)
			(xy 423.89992 -50.317036) (xy 423.9311 -50.361583) (xy 423.944542 -50.385218) (xy 424.781472 -50.385218)
			(xy 425.069 -50.672746) (xy 425.069 -52.10048) (xy 430.840132 -52.10048) (xy 430.844203 -52.044858)
			(xy 430.856329 -51.990421) (xy 430.876252 -51.93833) (xy 430.903548 -51.889695) (xy 430.937634 -51.845552)
			(xy 430.977783 -51.806843) (xy 431.023141 -51.774392) (xy 431.072741 -51.748891) (xy 431.125525 -51.730884)
			(xy 431.180368 -51.720754) (xy 431.236102 -51.718717) (xy 431.291539 -51.724817) (xy 431.345496 -51.738923)
			(xy 431.396825 -51.760735) (xy 431.444431 -51.789789) (xy 431.487299 -51.825464) (xy 431.524516 -51.867001)
			(xy 431.555289 -51.913514) (xy 431.578961 -51.964011) (xy 431.594037 -52.01412) (xy 432.050442 -52.01412)
			(xy 432.054513 -51.958498) (xy 432.066639 -51.904061) (xy 432.086562 -51.85197) (xy 432.113858 -51.803335)
			(xy 432.147944 -51.759192) (xy 432.188093 -51.720483) (xy 432.233451 -51.688032) (xy 432.283051 -51.662531)
			(xy 432.335835 -51.644524) (xy 432.390678 -51.634394) (xy 432.446412 -51.632357) (xy 432.501849 -51.638457)
			(xy 432.555806 -51.652563) (xy 432.607135 -51.674375) (xy 432.654741 -51.703429) (xy 432.697609 -51.739104)
			(xy 432.734826 -51.780641) (xy 432.765599 -51.827154) (xy 432.789271 -51.877651) (xy 432.805339 -51.931058)
			(xy 432.813459 -51.986234) (xy 432.813968 -52.01412) (xy 432.813459 -52.042006) (xy 432.805339 -52.097182)
			(xy 432.789271 -52.150589) (xy 432.765599 -52.201086) (xy 432.734826 -52.247599) (xy 432.697609 -52.289136)
			(xy 432.654741 -52.324811) (xy 432.607135 -52.353865) (xy 432.555806 -52.375677) (xy 432.501849 -52.389783)
			(xy 432.446412 -52.395883) (xy 432.390678 -52.393846) (xy 432.335835 -52.383716) (xy 432.283051 -52.365709)
			(xy 432.233451 -52.340208) (xy 432.188093 -52.307757) (xy 432.147944 -52.269048) (xy 432.113858 -52.224905)
			(xy 432.086562 -52.17627) (xy 432.066639 -52.124179) (xy 432.054513 -52.069742) (xy 432.050442 -52.01412)
			(xy 431.594037 -52.01412) (xy 431.595029 -52.017418) (xy 431.603149 -52.072594) (xy 431.603658 -52.10048)
			(xy 431.603149 -52.128366) (xy 431.595029 -52.183542) (xy 431.578961 -52.236949) (xy 431.555289 -52.287446)
			(xy 431.524516 -52.333959) (xy 431.487299 -52.375496) (xy 431.444431 -52.411171) (xy 431.396825 -52.440225)
			(xy 431.345496 -52.462037) (xy 431.291539 -52.476143) (xy 431.236102 -52.482243) (xy 431.180368 -52.480206)
			(xy 431.125525 -52.470076) (xy 431.072741 -52.452069) (xy 431.023141 -52.426568) (xy 430.977783 -52.394117)
			(xy 430.937634 -52.355408) (xy 430.903548 -52.311265) (xy 430.876252 -52.26263) (xy 430.856329 -52.210539)
			(xy 430.844203 -52.156102) (xy 430.840132 -52.10048) (xy 425.069 -52.10048) (xy 425.069 -53.474366)
			(xy 425.337478 -53.742844) (xy 427.283118 -53.742844) (xy 427.622208 -54.081934) (xy 427.622208 -57.005982)
			(xy 428.427388 -57.811162) (xy 434.883306 -57.811162)
		)
		(stroke
			(width 0)
			(type solid)
		)
		(fill yes)
		(layer "F.Cu")
		(net "P3V3")
	)
	(gr_poly
		(pts
			(xy 399.647156 -156.476954) (xy 399.651594 -156.434948) (xy 399.66722 -156.351931) (xy 399.690432 -156.270709)
			(xy 399.721032 -156.191972) (xy 399.758759 -156.11639) (xy 399.803293 -156.044609) (xy 399.854254 -155.977237)
			(xy 399.911208 -155.91485) (xy 399.973671 -155.857979) (xy 400.041109 -155.807107) (xy 400.11295 -155.762669)
			(xy 400.188581 -155.725041) (xy 400.267359 -155.694546) (xy 400.348612 -155.671442) (xy 400.431649 -155.655926)
			(xy 400.515763 -155.64813) (xy 400.558 -155.647644) (xy 400.602743 -155.648197) (xy 400.691798 -155.656954)
			(xy 400.779573 -155.674366) (xy 400.865229 -155.700266) (xy 400.947946 -155.734406) (xy 401.026933 -155.77646)
			(xy 401.064476 -155.800806) (xy 401.07743 -155.809188) (xy 401.30095 -155.809188) (xy 402.01469 -156.522928)
			(xy 409.27782 -156.522928) (xy 409.467812 -156.332936) (xy 409.467812 -148.54428) (xy 409.18638 -148.262848)
			(xy 398.00276 -148.262848) (xy 397.83258 -148.433028) (xy 397.83258 -150.339552) (xy 399.642589 -150.339552)
			(xy 399.646611 -150.253832) (xy 399.658642 -150.168864) (xy 399.678578 -150.085397) (xy 399.706241 -150.004163)
			(xy 399.74139 -149.925877) (xy 399.783716 -149.851226) (xy 399.832845 -149.780867) (xy 399.888348 -149.715417)
			(xy 399.949735 -149.655453) (xy 400.016468 -149.6015) (xy 400.08796 -149.554033) (xy 400.163582 -149.513469)
			(xy 400.242671 -149.480165) (xy 400.324531 -149.454413) (xy 400.408442 -149.43644) (xy 400.493668 -149.426404)
			(xy 400.57946 -149.424392) (xy 400.665062 -149.430423) (xy 400.749724 -149.444443) (xy 400.832701 -149.466329)
			(xy 400.913264 -149.49589) (xy 400.990704 -149.532864) (xy 401.064343 -149.576928) (xy 401.133531 -149.627694)
			(xy 401.197662 -149.684715) (xy 401.256171 -149.747491) (xy 401.308544 -149.815471) (xy 401.354322 -149.888056)
			(xy 401.393102 -149.964608) (xy 401.424543 -150.044456) (xy 401.448369 -150.126897) (xy 401.46437 -150.211207)
			(xy 401.472405 -150.296645) (xy 401.472908 -150.339552) (xy 401.472405 -150.382459) (xy 401.46437 -150.467897)
			(xy 401.448369 -150.552207) (xy 401.424543 -150.634648) (xy 401.393102 -150.714496) (xy 401.354322 -150.791048)
			(xy 401.308544 -150.863633) (xy 401.256171 -150.931613) (xy 401.197662 -150.994389) (xy 401.133531 -151.05141)
			(xy 401.064343 -151.102176) (xy 400.990704 -151.14624) (xy 400.913264 -151.183214) (xy 400.832701 -151.212775)
			(xy 400.749724 -151.234661) (xy 400.665062 -151.248681) (xy 400.57946 -151.254712) (xy 400.493668 -151.2527)
			(xy 400.408442 -151.242664) (xy 400.324531 -151.224691) (xy 400.242671 -151.198939) (xy 400.163582 -151.165635)
			(xy 400.08796 -151.125071) (xy 400.016468 -151.077604) (xy 399.949735 -151.023651) (xy 399.888348 -150.963687)
			(xy 399.832845 -150.898237) (xy 399.783716 -150.827878) (xy 399.74139 -150.753227) (xy 399.706241 -150.674941)
			(xy 399.678578 -150.593707) (xy 399.658642 -150.51024) (xy 399.646611 -150.425272) (xy 399.642589 -150.339552)
			(xy 397.83258 -150.339552) (xy 397.83258 -153.126948) (xy 399.668492 -153.126948) (xy 399.668492 -151.552148)
			(xy 399.668931 -151.53876) (xy 399.675852 -151.512893) (xy 399.689232 -151.4897) (xy 399.708162 -151.470762)
			(xy 399.731349 -151.45737) (xy 399.757212 -151.450438) (xy 399.7706 -151.45004) (xy 401.3454 -151.45004)
			(xy 401.358794 -151.45039) (xy 401.38467 -151.457326) (xy 401.407868 -151.470724) (xy 401.426806 -151.489671)
			(xy 401.440193 -151.512875) (xy 401.447116 -151.538753) (xy 401.447508 -151.552148) (xy 401.447508 -153.126948)
			(xy 401.447113 -153.140335) (xy 401.440173 -153.166196) (xy 401.426779 -153.189379) (xy 401.407841 -153.208308)
			(xy 401.384651 -153.221692) (xy 401.358788 -153.22862) (xy 401.3454 -153.229056) (xy 399.7706 -153.229056)
			(xy 399.757219 -153.228572) (xy 399.731368 -153.221647) (xy 399.708188 -153.208269) (xy 399.68926 -153.18935)
			(xy 399.675871 -153.166177) (xy 399.668935 -153.140329) (xy 399.668492 -153.126948) (xy 397.83258 -153.126948)
			(xy 397.83258 -155.80233) (xy 398.553178 -156.522928) (xy 399.642838 -156.522928)
		)
		(stroke
			(width 0)
			(type solid)
		)
		(fill yes)
		(layer "F.Cu")
		(net "PVCCFA_EHV_CPU0")
	)
	(gr_poly
		(pts
			(xy 71.00189 -178.952398) (xy 71.012093 -178.94147) (xy 71.026226 -178.91514) (xy 71.032137 -178.885847)
			(xy 71.02932 -178.856097) (xy 71.018016 -178.828434) (xy 70.999193 -178.805225) (xy 70.974459 -178.788455)
			(xy 70.945931 -178.779557) (xy 70.916049 -178.779294) (xy 70.90156 -178.78298) (xy 70.859653 -178.794746)
			(xy 70.77418 -178.811228) (xy 70.687528 -178.819521) (xy 70.644004 -178.820064) (xy 70.600882 -178.819566)
			(xy 70.51502 -178.81145) (xy 70.430303 -178.79529) (xy 70.347482 -178.771229) (xy 70.267294 -178.739481)
			(xy 70.190449 -178.700327) (xy 70.117631 -178.654115) (xy 70.049484 -178.601255) (xy 69.986614 -178.542217)
			(xy 69.929579 -178.477524) (xy 69.878885 -178.407751) (xy 69.834983 -178.333517) (xy 69.798261 -178.255481)
			(xy 69.769047 -178.174335) (xy 69.747598 -178.0908) (xy 69.734106 -178.005617) (xy 69.72869 -177.919543)
			(xy 69.731399 -177.833341) (xy 69.742208 -177.747776) (xy 69.761021 -177.663609) (xy 69.787672 -177.581585)
			(xy 69.821924 -177.502433) (xy 69.863472 -177.426856) (xy 69.911948 -177.355525) (xy 69.966922 -177.289072)
			(xy 70.027906 -177.228088) (xy 70.094359 -177.173113) (xy 70.16569 -177.124636) (xy 70.241266 -177.083087)
			(xy 70.320417 -177.048835) (xy 70.402441 -177.022183) (xy 70.486608 -177.003369) (xy 70.572173 -176.99256)
			(xy 70.658375 -176.98985) (xy 70.744449 -176.995265) (xy 70.829632 -177.008757) (xy 70.913167 -177.030204)
			(xy 70.994313 -177.059418) (xy 71.07235 -177.096139) (xy 71.146584 -177.140041) (xy 71.216358 -177.190734)
			(xy 71.281051 -177.247768) (xy 71.34009 -177.310638) (xy 71.39295 -177.378784) (xy 71.439163 -177.451603)
			(xy 71.478317 -177.528447) (xy 71.510067 -177.608635) (xy 71.534128 -177.691455) (xy 71.550289 -177.776172)
			(xy 71.558406 -177.862034) (xy 71.558912 -177.905156) (xy 71.558382 -177.94868) (xy 71.550086 -178.035332)
			(xy 71.533591 -178.120804) (xy 71.521828 -178.162712) (xy 71.518159 -178.17719) (xy 71.518459 -178.207043)
			(xy 71.527374 -178.235534) (xy 71.544143 -178.260234) (xy 71.567334 -178.279033) (xy 71.594969 -178.290328)
			(xy 71.624688 -178.293155) (xy 71.653957 -178.287272) (xy 71.680276 -178.273181) (xy 71.691246 -178.263042)
			(xy 72.689974 -177.264314) (xy 72.689974 -175.664114) (xy 72.70496 -175.628046) (xy 72.70496 -174.513748)
			(xy 72.85736 -174.361348) (xy 73.2028 -174.361348) (xy 73.316592 -174.247556) (xy 73.306178 -174.21733)
			(xy 73.29496 -174.183591) (xy 73.279231 -174.114249) (xy 73.271338 -174.043586) (xy 73.270872 -174.008034)
			(xy 73.271481 -173.968218) (xy 73.281403 -173.889206) (xy 73.30111 -173.812051) (xy 73.330293 -173.737959)
			(xy 73.34885 -173.702726) (xy 73.3552 -173.691296) (xy 73.3552 -173.399196) (xy 72.884792 -172.928788)
			(xy 67.861688 -172.928788) (xy 65.8368 -170.9039) (xy 62.357 -170.9039) (xy 62.103508 -171.157646)
			(xy 62.103508 -178.692556) (xy 67.7545 -178.692556) (xy 67.7545 -177.117756) (xy 67.754891 -177.104368)
			(xy 67.76183 -177.078507) (xy 67.775226 -177.055323) (xy 67.794164 -177.036394) (xy 67.817355 -177.02301)
			(xy 67.84322 -177.016084) (xy 67.856608 -177.015648) (xy 69.431408 -177.015648) (xy 69.44479 -177.016121)
			(xy 69.470642 -177.023048) (xy 69.493822 -177.036428) (xy 69.51275 -177.05535) (xy 69.526138 -177.078525)
			(xy 69.533074 -177.104374) (xy 69.533516 -177.117756) (xy 69.533516 -178.692556) (xy 69.533072 -178.705944)
			(xy 69.526152 -178.731809) (xy 69.512771 -178.755002) (xy 69.493843 -178.77394) (xy 69.470658 -178.787332)
			(xy 69.444796 -178.794265) (xy 69.431408 -178.794664) (xy 67.856608 -178.794664) (xy 67.843214 -178.794303)
			(xy 67.81734 -178.78737) (xy 67.794142 -178.773974) (xy 67.775204 -178.755029) (xy 67.761817 -178.731827)
			(xy 67.754892 -178.70595) (xy 67.7545 -178.692556) (xy 62.103508 -178.692556) (xy 62.103508 -179.140358)
			(xy 62.103 -179.140612) (xy 62.103 -179.570888) (xy 62.2554 -179.723288) (xy 70.231 -179.723288)
		)
		(stroke
			(width 0)
			(type solid)
		)
		(fill yes)
		(layer "F.Cu")
		(net "PVCCFA_EHV_CPU1")
	)
	(gr_poly
		(pts
			(xy 436.206138 -372.97233) (xy 437.9087 -371.269768) (xy 437.9087 -354.102416) (xy 437.06288 -353.256596)
			(xy 411.887416 -353.256596) (xy 411.650688 -353.493324) (xy 411.650688 -359.826814) (xy 413.620204 -359.826814)
			(xy 413.620204 -354.683314) (xy 413.866838 -354.43668) (xy 418.386006 -354.43668) (xy 418.702236 -354.75291)
			(xy 418.702236 -359.808272) (xy 418.683694 -359.826814) (xy 423.308526 -359.826814) (xy 423.308526 -354.683314)
			(xy 423.55516 -354.43668) (xy 428.074328 -354.43668) (xy 428.390558 -354.75291) (xy 428.390558 -359.825798)
			(xy 428.361348 -359.855008) (xy 423.33672 -359.855008) (xy 423.308526 -359.826814) (xy 418.683694 -359.826814)
			(xy 418.66312 -359.847388) (xy 413.640778 -359.847388) (xy 413.620204 -359.826814) (xy 411.650688 -359.826814)
			(xy 411.650688 -361.561888) (xy 411.856428 -361.767628) (xy 413.195008 -361.767628) (xy 413.624776 -361.33786)
			(xy 415.170112 -361.33786) (xy 415.209482 -361.37723) (xy 415.21634 -361.384088) (xy 415.21634 -362.28274)
			(xy 415.214562 -362.284518) (xy 415.214562 -362.312712) (xy 415.157412 -362.369862) (xy 414.188656 -362.369862)
			(xy 414.172908 -362.38561) (xy 414.10763 -362.450888) (xy 413.7787 -362.450888) (xy 413.74822 -362.481368)
			(xy 413.74822 -362.643928) (xy 413.78632 -362.682028) (xy 414.206944 -362.682028) (xy 414.276032 -362.751116)
			(xy 414.346136 -362.821474) (xy 414.361122 -362.857542) (xy 414.361122 -363.700314) (xy 414.346136 -363.736382)
			(xy 414.325308 -363.75721) (xy 414.28924 -363.772196) (xy 413.518604 -363.772196) (xy 413.482536 -363.787182)
			(xy 413.479742 -363.789976) (xy 413.472122 -363.808518) (xy 413.472122 -364.009178) (xy 413.487108 -364.045246)
			(xy 413.489902 -364.04804) (xy 413.508444 -364.05566) (xy 414.28924 -364.05566) (xy 414.325308 -364.070646)
			(xy 414.346136 -364.091474) (xy 414.361122 -364.127542) (xy 414.361122 -364.313978) (xy 414.376108 -364.350046)
			(xy 414.396936 -364.370874) (xy 414.433004 -364.38586) (xy 416.11804 -364.38586) (xy 416.154108 -364.370874)
			(xy 416.200336 -364.324646) (xy 416.203625 -364.321238) (xy 416.209002 -364.313443) (xy 416.211004 -364.309152)
			(xy 416.211004 -362.14939) (xy 416.32505 -362.035344) (xy 421.113712 -362.035344) (xy 421.309038 -362.23067)
			(xy 421.309038 -364.552738) (xy 420.777162 -365.084614) (xy 420.777162 -367.311686) (xy 421.39108 -367.925604)
			(xy 421.958516 -367.925604) (xy 422.018714 -367.865406) (xy 422.018714 -365.48568) (xy 421.865298 -365.332264)
			(xy 421.865298 -361.93857) (xy 422.020238 -361.78363) (xy 422.858438 -361.78363) (xy 423.304208 -361.33786)
			(xy 424.872912 -361.33786) (xy 424.90898 -361.373928) (xy 424.90898 -362.278422) (xy 424.897804 -362.289598)
			(xy 424.864784 -362.322618) (xy 424.838114 -362.349288) (xy 423.897552 -362.349288) (xy 423.86123 -362.38561)
			(xy 423.795952 -362.450888) (xy 423.46118 -362.450888) (xy 423.43324 -362.478828) (xy 423.43324 -362.654088)
			(xy 423.4561 -362.676948) (xy 423.889932 -362.676948) (xy 423.96283 -362.749846) (xy 424.034458 -362.821474)
			(xy 424.049444 -362.857542) (xy 424.049444 -363.700314) (xy 424.034458 -363.736382) (xy 424.01363 -363.75721)
			(xy 423.977562 -363.772196) (xy 423.206926 -363.772196) (xy 423.170858 -363.787182) (xy 423.168064 -363.789976)
			(xy 423.160444 -363.808518) (xy 423.160444 -364.009178) (xy 423.17543 -364.045246) (xy 423.178224 -364.04804)
			(xy 423.196766 -364.05566) (xy 423.977562 -364.05566) (xy 424.01363 -364.070646) (xy 424.034458 -364.091474)
			(xy 424.049444 -364.127542) (xy 424.049444 -364.313978) (xy 424.06443 -364.350046) (xy 424.085258 -364.370874)
			(xy 424.121326 -364.38586) (xy 425.806362 -364.38586) (xy 425.84243 -364.370874) (xy 425.888658 -364.324646)
			(xy 425.891946 -364.321238) (xy 425.89732 -364.313442) (xy 425.899326 -364.309152) (xy 425.899326 -362.14939)
			(xy 426.000418 -362.048298) (xy 426.00118 -362.048298) (xy 426.02023 -362.029248) (xy 428.36338 -362.029248)
			(xy 428.38243 -362.048298) (xy 429.535082 -362.048298) (xy 429.537876 -362.045758) (xy 429.539654 -362.047536)
			(xy 431.227484 -362.047536) (xy 431.392838 -362.21289) (xy 431.392838 -368.42065) (xy 431.395378 -368.42319)
			(xy 431.395378 -372.65991) (xy 431.997358 -373.26189) (xy 435.572408 -373.26189)
		)
		(stroke
			(width 0)
			(type solid)
		)
		(fill yes)
		(layer "F.Cu")
		(net "GND")
	)
	(gr_poly
		(pts
			(xy 64.07912 -362.897928) (xy 64.07912 -345.191588) (xy 63.604394 -344.716862) (xy 59.53887 -344.716862)
			(xy 35.285426 -344.716862) (xy 34.078926 -344.716862) (xy 33.81756 -344.978228) (xy 33.81756 -351.28708)
			(xy 39.024814 -351.28708) (xy 39.024814 -346.14358) (xy 39.271448 -345.896946) (xy 43.790616 -345.896946)
			(xy 44.106846 -346.213176) (xy 44.106846 -351.286064) (xy 44.10583 -351.28708) (xy 48.713136 -351.28708)
			(xy 48.713136 -346.14358) (xy 48.95977 -345.896946) (xy 53.478938 -345.896946) (xy 53.795168 -346.213176)
			(xy 53.795168 -351.286064) (xy 53.793644 -351.287588) (xy 48.713644 -351.287588) (xy 48.713136 -351.28708)
			(xy 44.10583 -351.28708) (xy 44.105322 -351.287588) (xy 39.025322 -351.287588) (xy 39.024814 -351.28708)
			(xy 33.81756 -351.28708) (xy 33.81756 -352.704908) (xy 34.134806 -353.022154) (xy 35.517582 -353.022154)
			(xy 37.055298 -353.022154) (xy 37.261038 -353.227894) (xy 38.599618 -353.227894) (xy 39.029386 -352.798126)
			(xy 40.574722 -352.798126) (xy 40.614092 -352.837496) (xy 40.63492 -352.858324) (xy 40.63492 -353.729036)
			(xy 40.63492 -353.759008) (xy 40.57904 -353.814888) (xy 39.79926 -353.814888) (xy 39.70274 -353.911408)
			(xy 39.19474 -353.911408) (xy 39.16426 -353.941888) (xy 39.16426 -354.117148) (xy 39.18458 -354.137468)
			(xy 39.606474 -354.137468) (xy 39.679118 -354.210112) (xy 39.750746 -354.28174) (xy 39.765732 -354.317808)
			(xy 39.765732 -355.16058) (xy 39.750746 -355.196648) (xy 39.729918 -355.217476) (xy 39.69385 -355.232462)
			(xy 38.923214 -355.232462) (xy 38.887146 -355.247448) (xy 38.884352 -355.250242) (xy 38.876732 -355.268784)
			(xy 38.876732 -355.469444) (xy 38.891718 -355.505512) (xy 38.894512 -355.508306) (xy 38.913054 -355.515926)
			(xy 39.69385 -355.515926) (xy 39.729918 -355.530912) (xy 39.750746 -355.55174) (xy 39.765732 -355.587808)
			(xy 39.765732 -355.774244) (xy 39.780718 -355.810312) (xy 39.801546 -355.83114) (xy 39.837614 -355.846126)
			(xy 41.52265 -355.846126) (xy 41.558718 -355.83114) (xy 41.604946 -355.784912) (xy 41.608232 -355.781503)
			(xy 41.613603 -355.773705) (xy 41.615614 -355.769418) (xy 41.615614 -353.609656) (xy 41.716706 -353.508564)
			(xy 41.732962 -353.492308) (xy 44.07154 -353.492308) (xy 44.087796 -353.508564) (xy 45.25137 -353.508564)
			(xy 45.254164 -353.506024) (xy 45.255942 -353.507802) (xy 46.530514 -353.507802) (xy 46.713648 -353.690936)
			(xy 46.713648 -356.013004) (xy 46.181772 -356.54488) (xy 46.181772 -358.771952) (xy 46.79569 -359.38587)
			(xy 47.363126 -359.38587) (xy 47.423324 -359.325672) (xy 47.423324 -356.945946) (xy 47.269908 -356.79253)
			(xy 47.269908 -353.398836) (xy 47.424848 -353.243896) (xy 48.221392 -353.243896) (xy 48.667162 -352.798126)
			(xy 50.263044 -352.798126) (xy 50.278538 -352.798126) (xy 50.3174 -352.836988) (xy 50.3174 -353.781868)
			(xy 50.29708 -353.802188) (xy 49.309528 -353.802188) (xy 49.26584 -353.845876) (xy 49.202848 -353.908868)
			(xy 48.87976 -353.908868) (xy 48.85182 -353.936808) (xy 48.85182 -354.109528) (xy 48.8823 -354.140008)
			(xy 49.297336 -354.140008) (xy 49.36744 -354.210112) (xy 49.439068 -354.28174) (xy 49.454054 -354.317808)
			(xy 49.454054 -355.16058) (xy 49.439068 -355.196648) (xy 49.41824 -355.217476) (xy 49.382172 -355.232462)
			(xy 48.611536 -355.232462) (xy 48.575468 -355.247448) (xy 48.572674 -355.250242) (xy 48.565054 -355.268784)
			(xy 48.565054 -355.469444) (xy 48.58004 -355.505512) (xy 48.582834 -355.508306) (xy 48.601376 -355.515926)
			(xy 49.382172 -355.515926) (xy 49.41824 -355.530912) (xy 49.439068 -355.55174) (xy 49.454054 -355.587808)
			(xy 49.454054 -355.774244) (xy 49.46904 -355.810312) (xy 49.489868 -355.83114) (xy 49.525936 -355.846126)
			(xy 51.210972 -355.846126) (xy 51.24704 -355.83114) (xy 51.293268 -355.784912) (xy 51.296553 -355.781502)
			(xy 51.301922 -355.773704) (xy 51.303936 -355.769418) (xy 51.303936 -353.609656) (xy 51.405028 -353.508564)
			(xy 51.428904 -353.484688) (xy 53.74894 -353.484688) (xy 53.772816 -353.508564) (xy 54.939692 -353.508564)
			(xy 54.942486 -353.506024) (xy 54.944264 -353.507802) (xy 56.44261 -353.507802) (xy 56.641238 -353.70643)
			(xy 56.641238 -363.732826) (xy 57.00268 -364.094268) (xy 62.88278 -364.094268)
		)
		(stroke
			(width 0)
			(type solid)
		)
		(fill yes)
		(layer "F.Cu")
		(net "GND")
	)
	(gr_poly
		(pts
			(xy 61.849 -179.034948) (xy 61.849 -170.906948) (xy 62.9158 -169.840148) (xy 62.9158 -142.916148)
			(xy 62.611 -142.611348) (xy 55.5498 -142.611348) (xy 55.1942 -142.966948) (xy 55.1942 -144.828768)
			(xy 55.7276 -145.362168) (xy 55.7276 -146.903948) (xy 55.7022 -146.929348) (xy 54.9148 -146.929348)
			(xy 54.5846 -146.599148) (xy 54.5846 -146.218148) (xy 54.53888 -146.172428) (xy 54.53888 -145.441924)
			(xy 54.31536 -145.441924) (xy 54.31536 -146.080988) (xy 54.2798 -146.116548) (xy 53.2384 -146.116548)
			(xy 53.1876 -146.065748) (xy 53.1876 -145.202148) (xy 53.1368 -145.151348) (xy 52.9844 -145.151348)
			(xy 52.959 -145.176748) (xy 52.959 -146.065748) (xy 52.9082 -146.116548) (xy 52.7558 -146.116548)
			(xy 52.6542 -146.218148) (xy 52.6542 -147.767548) (xy 52.7304 -147.843748) (xy 54.7878 -147.843748)
			(xy 54.991 -148.046948) (xy 54.991 -150.152862) (xy 57.15 -150.152862) (xy 57.15 -145.547334) (xy 57.36336 -145.333974)
			(xy 61.14034 -145.333974) (xy 61.374274 -145.567908) (xy 61.374274 -150.188168) (xy 61.214 -150.348442)
			(xy 57.34558 -150.348442) (xy 57.15 -150.152862) (xy 54.991 -150.152862) (xy 54.991 -151.958548)
			(xy 55.2196 -152.187148) (xy 55.2196 -153.279348) (xy 55.7022 -153.761948) (xy 55.7022 -155.539948)
			(xy 55.6514 -155.590748) (xy 54.9656 -155.590748) (xy 54.61 -155.235148) (xy 54.61 -154.777948) (xy 54.5338 -154.701748)
			(xy 54.5338 -154.076908) (xy 54.31282 -154.076908) (xy 54.31282 -154.643328) (xy 54.2036 -154.752548)
			(xy 53.2892 -154.752548) (xy 53.1876 -154.650948) (xy 53.1876 -153.838148) (xy 53.1368 -153.787348)
			(xy 53.0098 -153.787348) (xy 52.959 -153.838148) (xy 52.959 -154.635708) (xy 52.84216 -154.752548)
			(xy 52.7304 -154.752548) (xy 52.6542 -154.828748) (xy 52.6542 -156.403548) (xy 52.705 -156.454348)
			(xy 54.7116 -156.454348) (xy 55.0164 -156.759148) (xy 55.0164 -158.788862) (xy 57.15 -158.788862)
			(xy 57.15 -154.183334) (xy 57.36336 -153.969974) (xy 61.14034 -153.969974) (xy 61.374274 -154.203908)
			(xy 61.374274 -158.824168) (xy 61.214 -158.984442) (xy 57.34558 -158.984442) (xy 57.15 -158.788862)
			(xy 55.0164 -158.788862) (xy 55.0164 -160.391348) (xy 55.2196 -160.594548) (xy 55.2196 -162.068002)
			(xy 55.7276 -162.576002) (xy 55.7276 -164.150548) (xy 55.626 -164.252148) (xy 54.864 -164.252148)
			(xy 54.5846 -163.972748) (xy 54.5846 -163.490148) (xy 54.5338 -163.439348) (xy 54.5338 -162.713924)
			(xy 54.3052 -162.713924) (xy 54.3052 -163.337748) (xy 54.2544 -163.388548) (xy 53.2384 -163.388548)
			(xy 53.1876 -163.337748) (xy 53.1876 -162.474148) (xy 53.1114 -162.397948) (xy 53.0098 -162.397948)
			(xy 52.959 -162.448748) (xy 52.959 -163.337748) (xy 52.9082 -163.388548) (xy 52.705 -163.388548)
			(xy 52.6288 -163.464748) (xy 52.6288 -164.963348) (xy 52.7812 -165.115748) (xy 54.7116 -165.115748)
			(xy 55.0164 -165.420548) (xy 55.0164 -167.424862) (xy 57.150254 -167.424862) (xy 57.150254 -162.819334)
			(xy 57.36336 -162.606228) (xy 61.14034 -162.606228) (xy 61.37402 -162.839908) (xy 61.37402 -167.460168)
			(xy 61.214 -167.620188) (xy 57.34558 -167.620188) (xy 57.150254 -167.424862) (xy 55.0164 -167.424862)
			(xy 55.0164 -170.271948) (xy 54.2798 -171.008548) (xy 54.2798 -171.872148) (xy 54.1274 -172.024548)
			(xy 54.1274 -173.777148) (xy 54.102 -173.802548) (xy 53.3146 -173.802548) (xy 53.0352 -173.523148)
			(xy 53.0352 -172.938948) (xy 52.959 -172.862748) (xy 51.562 -172.862748) (xy 51.3334 -173.091348)
			(xy 51.3334 -174.513748) (xy 51.435 -174.615348) (xy 53.2638 -174.615348) (xy 53.4162 -174.767748)
			(xy 53.4162 -176.012856) (xy 54.991508 -176.012856) (xy 54.991508 -172.42536) (xy 55.308754 -172.108114)
			(xy 59.682126 -172.108114) (xy 60.07608 -172.502068) (xy 60.07608 -175.992028) (xy 59.73064 -176.337468)
			(xy 55.31612 -176.337468) (xy 54.991508 -176.012856) (xy 53.4162 -176.012856) (xy 53.4162 -177.841148)
			(xy 53.0352 -178.222148) (xy 46.5328 -178.222148) (xy 46.4058 -178.349148) (xy 46.4058 -179.365148)
			(xy 46.5328 -179.492148) (xy 61.3918 -179.492148)
		)
		(stroke
			(width 0)
			(type solid)
		)
		(fill yes)
		(layer "F.Cu")
		(net "GND")
	)
	(gr_poly
		(pts
			(xy 307.6956 -368.701828) (xy 308.567328 -367.8301) (xy 308.567328 -362.308648) (xy 308.567328 -354.256848)
			(xy 308.254908 -353.944428) (xy 302.867568 -353.944428) (xy 284.51302 -353.944428) (xy 281.338528 -353.944428)
			(xy 281.249628 -353.944428) (xy 281.228038 -353.966018) (xy 281.117548 -354.076508) (xy 281.117548 -360.514646)
			(xy 286.245808 -360.514646) (xy 286.245808 -355.371146) (xy 286.492442 -355.124512) (xy 291.01161 -355.124512)
			(xy 291.32784 -355.440742) (xy 291.32784 -360.51363) (xy 291.326824 -360.514646) (xy 295.93413 -360.514646)
			(xy 295.93413 -355.371146) (xy 296.180764 -355.124512) (xy 300.699932 -355.124512) (xy 301.016162 -355.440742)
			(xy 301.016162 -360.51363) (xy 301.014638 -360.515154) (xy 295.934638 -360.515154) (xy 295.93413 -360.514646)
			(xy 291.326824 -360.514646) (xy 291.326316 -360.515154) (xy 286.246316 -360.515154) (xy 286.245808 -360.514646)
			(xy 281.117548 -360.514646) (xy 281.117548 -361.051348) (xy 281.623008 -361.556808) (xy 283.939488 -361.556808)
			(xy 284.276292 -361.893612) (xy 284.276292 -362.24972) (xy 284.482032 -362.45546) (xy 285.820612 -362.45546)
			(xy 286.25038 -362.025692) (xy 287.795716 -362.025692) (xy 287.835086 -362.065062) (xy 287.85566 -362.085636)
			(xy 287.85566 -362.956856) (xy 287.835086 -362.97743) (xy 287.802066 -363.01045) (xy 287.782508 -363.030008)
			(xy 286.841946 -363.030008) (xy 286.798512 -363.073442) (xy 286.732726 -363.139228) (xy 286.3977 -363.139228)
			(xy 286.37738 -363.159548) (xy 286.37738 -363.344968) (xy 286.40278 -363.370368) (xy 286.833056 -363.370368)
			(xy 286.903668 -363.44098) (xy 286.97174 -363.509306) (xy 286.986726 -363.545374) (xy 286.986726 -364.388146)
			(xy 286.97174 -364.424214) (xy 286.950912 -364.445042) (xy 286.914844 -364.460028) (xy 286.144208 -364.460028)
			(xy 286.10814 -364.475014) (xy 286.105346 -364.477808) (xy 286.097726 -364.49635) (xy 286.097726 -364.69701)
			(xy 286.112712 -364.733078) (xy 286.115506 -364.735872) (xy 286.134048 -364.743492) (xy 286.914844 -364.743492)
			(xy 286.950912 -364.758478) (xy 286.97174 -364.779306) (xy 286.986726 -364.815374) (xy 286.986726 -365.00181)
			(xy 287.001712 -365.037878) (xy 287.02254 -365.058706) (xy 287.058608 -365.073692) (xy 288.743644 -365.073692)
			(xy 288.779712 -365.058706) (xy 288.82594 -365.012478) (xy 288.829224 -365.009067) (xy 288.834591 -365.001268)
			(xy 288.836608 -364.996984) (xy 288.836608 -362.837222) (xy 288.9377 -362.73613) (xy 288.958782 -362.715048)
			(xy 291.28974 -362.715048) (xy 291.310822 -362.73613) (xy 292.472364 -362.73613) (xy 292.475158 -362.73359)
			(xy 292.476936 -362.735368) (xy 293.691564 -362.735368) (xy 293.751508 -362.735368) (xy 293.934642 -362.918502)
			(xy 293.934642 -362.978446) (xy 293.934642 -365.24057) (xy 293.898574 -365.276638) (xy 293.402766 -365.772446)
			(xy 293.402766 -367.999518) (xy 294.016684 -368.613436) (xy 294.58412 -368.613436) (xy 294.644318 -368.553238)
			(xy 294.644318 -366.173512) (xy 294.540178 -366.069372) (xy 294.490902 -366.020096) (xy 294.490902 -364.132622)
			(xy 294.490902 -362.626402) (xy 294.645842 -362.471462) (xy 295.464738 -362.471462) (xy 295.910508 -362.025692)
			(xy 297.496484 -362.025692) (xy 297.52544 -362.054648) (xy 297.52544 -362.093256) (xy 297.52544 -362.981748)
			(xy 297.48226 -363.024928) (xy 296.53865 -363.024928) (xy 296.533062 -363.027214) (xy 296.486834 -363.073442)
			(xy 296.423588 -363.136688) (xy 296.08018 -363.136688) (xy 296.0624 -363.154468) (xy 296.0624 -363.347508)
			(xy 296.08018 -363.365288) (xy 296.516044 -363.365288) (xy 296.588434 -363.437678) (xy 296.660062 -363.509306)
			(xy 296.675048 -363.545374) (xy 296.675048 -364.388146) (xy 296.660062 -364.424214) (xy 296.639234 -364.445042)
			(xy 296.603166 -364.460028) (xy 295.83253 -364.460028) (xy 295.796462 -364.475014) (xy 295.793668 -364.477808)
			(xy 295.786048 -364.49635) (xy 295.786048 -364.69701) (xy 295.801034 -364.733078) (xy 295.803828 -364.735872)
			(xy 295.82237 -364.743492) (xy 296.603166 -364.743492) (xy 296.639234 -364.758478) (xy 296.660062 -364.779306)
			(xy 296.675048 -364.815374) (xy 296.675048 -365.00181) (xy 296.690034 -365.037878) (xy 296.710862 -365.058706)
			(xy 296.74693 -365.073692) (xy 298.431966 -365.073692) (xy 298.468034 -365.058706) (xy 298.514262 -365.012478)
			(xy 298.517545 -365.009067) (xy 298.52291 -365.001266) (xy 298.52493 -364.996984) (xy 298.52493 -362.837222)
			(xy 298.626022 -362.73613) (xy 298.639484 -362.722668) (xy 300.98492 -362.722668) (xy 300.998382 -362.73613)
			(xy 302.160686 -362.73613) (xy 302.16348 -362.73359) (xy 302.165258 -362.735368) (xy 303.501044 -362.735368)
			(xy 303.675288 -362.735368) (xy 303.977548 -363.037628) (xy 303.977548 -368.412268) (xy 303.977548 -370.246656)
			(xy 304.17008 -370.439188) (xy 305.95824 -370.439188)
		)
		(stroke
			(width 0)
			(type solid)
		)
		(fill yes)
		(layer "F.Cu")
		(net "GND")
	)
	(gr_poly
		(pts
			(xy 399.060162 -166.266368) (xy 407.07564 -166.266368) (xy 407.30424 -166.494968) (xy 407.69794 -166.494968)
			(xy 407.735532 -166.457122) (xy 407.735532 -157.50794) (xy 407.73858 -157.500574) (xy 407.73858 -157.302708)
			(xy 407.4668 -157.030928) (xy 403.99716 -157.030928) (xy 403.369018 -157.65907) (xy 401.548346 -157.65907)
			(xy 401.53442 -157.659495) (xy 401.507599 -157.667006) (xy 401.483804 -157.681482) (xy 401.464804 -157.701848)
			(xy 401.452011 -157.726589) (xy 401.446376 -157.753865) (xy 401.447 -157.767782) (xy 401.447508 -157.775148)
			(xy 401.447508 -159.349948) (xy 401.447065 -159.363329) (xy 401.440129 -159.389177) (xy 401.42674 -159.41235)
			(xy 401.407812 -159.431269) (xy 401.384632 -159.444647) (xy 401.358781 -159.451572) (xy 401.3454 -159.452056)
			(xy 399.7706 -159.452056) (xy 399.757212 -159.45162) (xy 399.731349 -159.444692) (xy 399.708159 -159.431308)
			(xy 399.689221 -159.412379) (xy 399.675827 -159.389196) (xy 399.668887 -159.363335) (xy 399.668492 -159.349948)
			(xy 399.668492 -157.775148) (xy 399.669 -157.767782) (xy 399.669541 -157.753866) (xy 399.663912 -157.726602)
			(xy 399.651132 -157.701869) (xy 399.63215 -157.681504) (xy 399.608375 -157.66702) (xy 399.581573 -157.659491)
			(xy 399.567654 -157.65907) (xy 397.677386 -157.65907) (xy 396.92834 -158.408116) (xy 396.92834 -162.785552)
			(xy 399.642589 -162.785552) (xy 399.646611 -162.699832) (xy 399.658642 -162.614864) (xy 399.678578 -162.531397)
			(xy 399.706241 -162.450163) (xy 399.74139 -162.371877) (xy 399.783716 -162.297226) (xy 399.832845 -162.226867)
			(xy 399.888348 -162.161417) (xy 399.949735 -162.101453) (xy 400.016468 -162.0475) (xy 400.08796 -162.000033)
			(xy 400.163582 -161.959469) (xy 400.242671 -161.926165) (xy 400.324531 -161.900413) (xy 400.408442 -161.88244)
			(xy 400.493668 -161.872404) (xy 400.57946 -161.870392) (xy 400.665062 -161.876423) (xy 400.749724 -161.890443)
			(xy 400.832701 -161.912329) (xy 400.913264 -161.94189) (xy 400.990704 -161.978864) (xy 401.064343 -162.022928)
			(xy 401.133531 -162.073694) (xy 401.197662 -162.130715) (xy 401.256171 -162.193491) (xy 401.308544 -162.261471)
			(xy 401.354322 -162.334056) (xy 401.393102 -162.410608) (xy 401.424543 -162.490456) (xy 401.448369 -162.572897)
			(xy 401.46437 -162.657207) (xy 401.472405 -162.742645) (xy 401.472908 -162.785552) (xy 401.472405 -162.828459)
			(xy 401.46437 -162.913897) (xy 401.448369 -162.998207) (xy 401.424543 -163.080648) (xy 401.393102 -163.160496)
			(xy 401.354322 -163.237048) (xy 401.308544 -163.309633) (xy 401.256171 -163.377613) (xy 401.197662 -163.440389)
			(xy 401.133531 -163.49741) (xy 401.064343 -163.548176) (xy 400.990704 -163.59224) (xy 400.913264 -163.629214)
			(xy 400.832701 -163.658775) (xy 400.749724 -163.680661) (xy 400.665062 -163.694681) (xy 400.57946 -163.700712)
			(xy 400.493668 -163.6987) (xy 400.408442 -163.688664) (xy 400.324531 -163.670691) (xy 400.242671 -163.644939)
			(xy 400.163582 -163.611635) (xy 400.08796 -163.571071) (xy 400.016468 -163.523604) (xy 399.949735 -163.469651)
			(xy 399.888348 -163.409687) (xy 399.832845 -163.344237) (xy 399.783716 -163.273878) (xy 399.74139 -163.199227)
			(xy 399.706241 -163.120941) (xy 399.678578 -163.039707) (xy 399.658642 -162.95624) (xy 399.646611 -162.871272)
			(xy 399.642589 -162.785552) (xy 396.92834 -162.785552) (xy 396.92834 -165.550088) (xy 396.9512 -165.572948)
			(xy 399.668492 -165.572948) (xy 399.668492 -163.998148) (xy 399.668931 -163.98476) (xy 399.675852 -163.958893)
			(xy 399.689232 -163.9357) (xy 399.708162 -163.916762) (xy 399.731349 -163.90337) (xy 399.757212 -163.896438)
			(xy 399.7706 -163.89604) (xy 401.3454 -163.89604) (xy 401.358794 -163.89639) (xy 401.38467 -163.903326)
			(xy 401.407868 -163.916724) (xy 401.426806 -163.935671) (xy 401.440193 -163.958875) (xy 401.447116 -163.984753)
			(xy 401.447508 -163.998148) (xy 401.447508 -165.572948) (xy 401.447113 -165.586335) (xy 401.440173 -165.612196)
			(xy 401.426779 -165.635379) (xy 401.407841 -165.654308) (xy 401.384651 -165.667692) (xy 401.358788 -165.67462)
			(xy 401.3454 -165.675056) (xy 399.7706 -165.675056) (xy 399.757219 -165.674572) (xy 399.731368 -165.667647)
			(xy 399.708188 -165.654269) (xy 399.68926 -165.63535) (xy 399.675871 -165.612177) (xy 399.668935 -165.586329)
			(xy 399.668492 -165.572948) (xy 396.9512 -165.572948) (xy 397.28394 -165.905688) (xy 397.291052 -165.909498)
			(xy 397.322007 -165.925757) (xy 397.380496 -165.964077) (xy 397.434421 -166.00859) (xy 397.48313 -166.058759)
			(xy 397.526032 -166.113975) (xy 397.562608 -166.17357) (xy 397.592416 -166.236822) (xy 397.615094 -166.302966)
			(xy 397.630369 -166.371202) (xy 397.638055 -166.440702) (xy 397.638524 -166.475664) (xy 397.638055 -166.509517)
			(xy 397.630826 -166.576837) (xy 397.616487 -166.643009) (xy 397.595201 -166.707283) (xy 397.581628 -166.7383)
			(xy 397.566896 -166.770304) (xy 397.64716 -166.850568) (xy 398.475708 -166.850568)
		)
		(stroke
			(width 0)
			(type solid)
		)
		(fill yes)
		(layer "F.Cu")
		(net "PVCCD_HV_CPU0")
	)
	(gr_poly
		(pts
			(xy 469.6968 -76.241148) (xy 469.6968 -64.201548) (xy 468.5284 -63.033148) (xy 462.407 -63.033148)
			(xy 461.837786 -63.602362) (xy 461.837786 -65.761362) (xy 461.8228 -65.776348) (xy 461.8228 -68.56215)
			(xy 465.517988 -68.56215) (xy 465.517988 -68.477454) (xy 465.526039 -68.39314) (xy 465.542068 -68.309974)
			(xy 465.565929 -68.228707) (xy 465.597408 -68.150077) (xy 465.636219 -68.074796) (xy 465.682009 -68.003544)
			(xy 465.734365 -67.936968) (xy 465.792813 -67.87567) (xy 465.856823 -67.820205) (xy 465.925815 -67.771076)
			(xy 465.999165 -67.728727) (xy 466.076208 -67.693543) (xy 466.156247 -67.665841) (xy 466.238556 -67.645873)
			(xy 466.322391 -67.63382) (xy 466.406992 -67.62979) (xy 466.491593 -67.63382) (xy 466.575428 -67.645873)
			(xy 466.657737 -67.665841) (xy 466.737776 -67.693543) (xy 466.814819 -67.728727) (xy 466.888169 -67.771076)
			(xy 466.957161 -67.820205) (xy 467.021171 -67.87567) (xy 467.079619 -67.936968) (xy 467.131975 -68.003544)
			(xy 467.177765 -68.074796) (xy 467.216576 -68.150077) (xy 467.248055 -68.228707) (xy 467.271916 -68.309974)
			(xy 467.287945 -68.39314) (xy 467.295996 -68.477454) (xy 467.2965 -68.519802) (xy 467.295996 -68.56215)
			(xy 467.287945 -68.646464) (xy 467.271916 -68.72963) (xy 467.248055 -68.810897) (xy 467.216576 -68.889527)
			(xy 467.177765 -68.964808) (xy 467.131975 -69.03606) (xy 467.079619 -69.102636) (xy 467.021171 -69.163934)
			(xy 466.957161 -69.219399) (xy 466.888169 -69.268528) (xy 466.814819 -69.310877) (xy 466.737776 -69.346061)
			(xy 466.657737 -69.373763) (xy 466.575428 -69.393731) (xy 466.491593 -69.405784) (xy 466.406992 -69.409815)
			(xy 466.322391 -69.405784) (xy 466.238556 -69.393731) (xy 466.156247 -69.373763) (xy 466.076208 -69.346061)
			(xy 465.999165 -69.310877) (xy 465.925815 -69.268528) (xy 465.856823 -69.219399) (xy 465.792813 -69.163934)
			(xy 465.734365 -69.102636) (xy 465.682009 -69.03606) (xy 465.636219 -68.964808) (xy 465.597408 -68.889527)
			(xy 465.565929 -68.810897) (xy 465.542068 -68.72963) (xy 465.526039 -68.646464) (xy 465.517988 -68.56215)
			(xy 461.8228 -68.56215) (xy 461.8228 -69.997066) (xy 461.822365 -70.007131) (xy 461.814633 -70.025718)
			(xy 461.807814 -70.033134) (xy 461.507586 -70.333362) (xy 461.500189 -70.34021) (xy 461.48159 -70.347946)
			(xy 461.471518 -70.348348) (xy 456.5904 -70.348348) (xy 455.821288 -71.11746) (xy 455.813891 -71.124309)
			(xy 455.795292 -71.132045) (xy 455.78522 -71.132446) (xy 452.644002 -71.132446) (xy 452.607172 -71.169276)
			(xy 449.491608 -71.169276) (xy 449.347336 -71.313548) (xy 449.347336 -73.323196) (xy 449.378832 -73.357486)
			(xy 450.049646 -73.357486) (xy 450.061076 -73.354692) (xy 450.43598 -73.354692) (xy 450.505576 -73.424288)
			(xy 452.159878 -73.424288) (xy 452.167244 -73.42759) (xy 453.170036 -73.42759) (xy 453.180104 -73.428019)
			(xy 453.1987 -73.435742) (xy 453.206104 -73.442576) (xy 453.812148 -74.04862) (xy 453.812148 -76.002572)
			(xy 465.517988 -76.002572) (xy 465.517988 -75.917876) (xy 465.526039 -75.833562) (xy 465.542068 -75.750396)
			(xy 465.565929 -75.669129) (xy 465.597408 -75.590499) (xy 465.636219 -75.515218) (xy 465.682009 -75.443966)
			(xy 465.734365 -75.37739) (xy 465.792813 -75.316092) (xy 465.856823 -75.260627) (xy 465.925815 -75.211498)
			(xy 465.999165 -75.169149) (xy 466.076208 -75.133965) (xy 466.156247 -75.106263) (xy 466.238556 -75.086295)
			(xy 466.322391 -75.074242) (xy 466.406992 -75.070212) (xy 466.491593 -75.074242) (xy 466.575428 -75.086295)
			(xy 466.657737 -75.106263) (xy 466.737776 -75.133965) (xy 466.814819 -75.169149) (xy 466.888169 -75.211498)
			(xy 466.957161 -75.260627) (xy 467.021171 -75.316092) (xy 467.079619 -75.37739) (xy 467.131975 -75.443966)
			(xy 467.177765 -75.515218) (xy 467.216576 -75.590499) (xy 467.248055 -75.669129) (xy 467.271916 -75.750396)
			(xy 467.287945 -75.833562) (xy 467.295996 -75.917876) (xy 467.2965 -75.960224) (xy 467.295996 -76.002572)
			(xy 467.287945 -76.086886) (xy 467.271916 -76.170052) (xy 467.248055 -76.251319) (xy 467.216576 -76.329949)
			(xy 467.177765 -76.40523) (xy 467.131975 -76.476482) (xy 467.079619 -76.543058) (xy 467.021171 -76.604356)
			(xy 466.957161 -76.659821) (xy 466.888169 -76.70895) (xy 466.814819 -76.751299) (xy 466.737776 -76.786483)
			(xy 466.657737 -76.814185) (xy 466.575428 -76.834153) (xy 466.491593 -76.846206) (xy 466.406992 -76.850237)
			(xy 466.322391 -76.846206) (xy 466.238556 -76.834153) (xy 466.156247 -76.814185) (xy 466.076208 -76.786483)
			(xy 465.999165 -76.751299) (xy 465.925815 -76.70895) (xy 465.856823 -76.659821) (xy 465.792813 -76.604356)
			(xy 465.734365 -76.543058) (xy 465.682009 -76.476482) (xy 465.636219 -76.40523) (xy 465.597408 -76.329949)
			(xy 465.565929 -76.251319) (xy 465.542068 -76.170052) (xy 465.526039 -76.086886) (xy 465.517988 -76.002572)
			(xy 453.812148 -76.002572) (xy 453.812148 -76.178156) (xy 454.2282 -76.594208) (xy 460.925418 -76.594208)
			(xy 461.664558 -77.333348) (xy 468.6046 -77.333348)
		)
		(stroke
			(width 0)
			(type solid)
		)
		(fill yes)
		(layer "F.Cu")
		(net "SW_P3V3_AUX_FLT")
	)
	(gr_poly
		(pts
			(xy 131.05892 -28.550108) (xy 131.05892 -26.666952)
			(arc
				(start 131.053078 -26.65603)
				(mid 131.021025 -26.570603)
				(end 131.010152 -26.480008)
			)
			(arc
				(start 131.010152 -26.480008)
				(mid 131.021004 -26.389408)
				(end 131.053078 -26.303986)
			)
			(xy 131.05892 -26.293064) (xy 131.05892 -23.986744)
			(arc
				(start 131.021836 -23.97633)
				(mid 130.924608 -23.934023)
				(end 130.842766 -23.866602)
			)
			(arc
				(start 130.842766 -23.866602)
				(mid 130.773653 -23.834028)
				(end 130.701288 -23.858728)
			)
			(arc
				(start 130.701288 -23.858728)
				(mid 130.584546 -23.928248)
				(end 130.450844 -23.952454)
			)
			(arc
				(start 130.450844 -23.952454)
				(mid 130.283508 -23.913797)
				(end 130.150108 -23.805642)
			)
			(arc
				(start 130.150108 -23.805642)
				(mid 130.070558 -23.76641)
				(end 129.990596 -23.804626)
			)
			(arc
				(start 129.990596 -23.804626)
				(mid 129.85787 -23.910406)
				(end 129.6924 -23.948136)
			)
			(arc
				(start 129.6924 -23.948136)
				(mid 129.590233 -23.934131)
				(end 129.49555 -23.893272)
			)
			(arc
				(start 129.49555 -23.893272)
				(mid 129.444334 -23.892624)
				(end 129.418588 -23.93696)
			)
			(xy 129.418588 -24.017732)
			(arc
				(start 129.442464 -24.032718)
				(mid 129.48639 -24.078939)
				(end 129.502408 -24.140668)
			)
			(xy 129.502408 -24.665178) (xy 129.623312 -24.786336) (xy 129.623312 -26.152348) (xy 129.722372 -26.251408)
			(xy 130.131312 -26.251408) (xy 130.404108 -26.524204) (xy 130.404108 -27.11831) (xy 130.066796 -27.455876)
			(xy 129.14757 -27.455876) (xy 128.65735 -27.946096) (xy 127.86487 -27.946096) (xy 127.479552 -27.560778)
			(arc
				(start 127.479552 -27.191462)
				(mid 127.450775 -27.120614)
				(end 127.380746 -27.089862)
			)
			(arc
				(start 127.380746 -27.089862)
				(mid 127.009764 -26.708608)
				(end 127.380746 -26.327354)
			)
			(arc
				(start 127.380746 -26.327354)
				(mid 127.450802 -26.296628)
				(end 127.479552 -26.225754)
			)
			(xy 127.479552 -24.27605) (xy 127.29083 -24.087328) (xy 127.27178 -24.087328) (xy 127.27178 -24.068278)
			(xy 127.235204 -24.031702) (xy 127.235204 -23.481538) (xy 127.43815 -23.278592) (xy 128.039622 -23.278592)
			(xy 128.27889 -23.51786) (xy 128.99263 -23.51786)
			(arc
				(start 129.138172 -23.663402)
				(mid 129.251296 -23.684435)
				(end 129.3114 -23.58644)
			)
			(arc
				(start 129.310892 -23.566628)
				(mid 129.422633 -23.296861)
				(end 129.6924 -23.18512)
			)
			(arc
				(start 129.6924 -23.18512)
				(mid 129.88786 -23.238952)
				(end 130.028188 -23.385272)
			)
			(arc
				(start 130.028188 -23.385272)
				(mid 130.072608 -23.411942)
				(end 130.117342 -23.38578)
			)
			(xy 130.13182 -23.361904) (xy 130.13182 -22.789388) (xy 129.67208 -22.329648)
			(arc
				(start 128.218184 -22.329648)
				(mid 128.105855 -22.379238)
				(end 127.98425 -22.396196)
			)
			(arc
				(start 127.98425 -22.396196)
				(mid 127.862659 -22.37919)
				(end 127.750316 -22.329648)
			)
			(xy 126.78156 -22.329648) (xy 126.602744 -22.508464)
			(arc
				(start 126.598934 -22.519386)
				(mid 126.508252 -22.664162)
				(end 126.363476 -22.754844)
			)
			(xy 126.352554 -22.758654) (xy 126.25578 -22.855428) (xy 126.25578 -28.763468) (xy 126.37008 -28.877768)
			(xy 130.73126 -28.877768)
		)
		(stroke
			(width 0)
			(type solid)
		)
		(fill yes)
		(layer "F.Cu")
		(net "P3V3_AUX_USB_BUF")
	)
	(gr_poly
		(pts
			(arc
				(start 328.780394 -37.101018)
				(mid 328.864881 -37.055849)
				(end 328.87412 -36.960556)
			)
			(xy 328.62266 -36.353496)
			(arc
				(start 327.917556 -35.648392)
				(mid 327.881479 -35.594305)
				(end 327.868788 -35.530536)
			)
			(arc
				(start 327.868788 -35.330384)
				(mid 327.717172 -35.197567)
				(end 327.654412 -35.006026)
			)
			(arc
				(start 327.654412 -35.006026)
				(mid 327.624375 -34.938571)
				(end 327.556622 -34.909252)
			)
			(arc
				(start 327.556622 -34.909252)
				(mid 327.474392 -34.890668)
				(end 327.40473 -34.843212)
			)
			(xy 327.2155 -34.654236) (xy 327.258172 -34.611818) (xy 327.074276 -34.427414) (xy 327.074022 -34.427668)
			(xy 326.88657 -34.240216) (xy 326.844152 -34.282888)
			(arc
				(start 326.655176 -34.093404)
				(mid 326.589075 -33.93274)
				(end 326.656446 -33.772602)
			)
			(xy 326.70242 -33.726628) (xy 326.65416 -33.678368)
			(arc
				(start 326.636634 -33.676082)
				(mid 326.416493 -33.571128)
				(end 326.30491 -33.354264)
			)
			(xy 326.30237 -33.337754) (xy 326.254618 -33.290002)
			(arc
				(start 326.214994 -33.329626)
				(mid 326.05433 -33.395727)
				(end 325.894192 -33.328356)
			)
			(arc
				(start 325.682864 -33.117028)
				(mid 325.615487 -32.95689)
				(end 325.681594 -32.796226)
			)
			(xy 325.742046 -32.735774) (xy 325.493634 -32.487362)
			(arc
				(start 325.461122 -32.503618)
				(mid 325.383982 -32.51507)
				(end 325.314564 -32.479488)
			)
			(arc
				(start 324.811644 -31.976568)
				(mid 324.774474 -31.886562)
				(end 324.811644 -31.796482)
			)
			(xy 325.263256 -31.34487) (xy 325.263256 -31.301182) (xy 324.91172 -30.9499)
			(arc
				(start 324.594474 -31.267146)
				(mid 324.542658 -31.298483)
				(end 324.482206 -31.302452)
			)
			(xy 324.456298 -31.29788)
			(arc
				(start 323.67347 -32.080708)
				(mid 323.662413 -32.136296)
				(end 323.709538 -32.167576)
			)
			(arc
				(start 323.783452 -32.167576)
				(mid 323.85699 -32.18211)
				(end 323.919342 -32.22371)
			)
			(xy 324.151752 -32.456374)
			(arc
				(start 324.344538 -32.263588)
				(mid 324.434618 -32.226238)
				(end 324.524624 -32.263588)
			)
			(arc
				(start 325.027544 -32.766508)
				(mid 325.064894 -32.856588)
				(end 325.027544 -32.946594)
			)
			(xy 324.774814 -33.199324) (xy 325.073264 -33.49752)
			(arc
				(start 325.103998 -33.485836)
				(mid 325.232751 -33.476061)
				(end 325.345806 -33.538414)
			)
			(arc
				(start 325.557134 -33.749742)
				(mid 325.605388 -33.819631)
				(end 325.624444 -33.902396)
			)
			(xy 325.625206 -33.922462) (xy 325.724012 -34.021268)
			(arc
				(start 325.750428 -34.016442)
				(mid 325.786079 -34.011309)
				(end 325.822056 -34.009584)
			)
			(arc
				(start 325.822056 -34.009584)
				(mid 326.091823 -34.121325)
				(end 326.203564 -34.391092)
			)
			(arc
				(start 326.203564 -34.391092)
				(mid 326.201816 -34.427066)
				(end 326.196706 -34.46272)
			)
			(xy 326.19188 -34.489136) (xy 326.97293 -35.270186)
			(arc
				(start 326.992996 -35.270948)
				(mid 327.063094 -35.286707)
				(end 327.122536 -35.327082)
			)
			(arc
				(start 327.939654 -36.1442)
				(mid 327.98123 -36.206562)
				(end 327.995788 -36.28009)
			)
			(arc
				(start 327.995788 -36.28009)
				(mid 327.991774 -36.319401)
				(end 327.979786 -36.357052)
			)
			(xy 327.975468 -36.366704) (xy 327.975468 -36.58997) (xy 328.48677 -37.101018)
		)
		(stroke
			(width 0)
			(type solid)
		)
		(fill yes)
		(layer "F.Cu")
		(net "GND")
	)
	(gr_poly
		(pts
			(xy 461.137 -86.274148) (xy 461.137 -77.282548) (xy 460.756 -76.901548) (xy 454.112122 -76.901548)
			(xy 451.217284 -79.796386) (xy 450.59219 -79.796386) (xy 443.556644 -79.796386) (xy 442.286644 -78.526386)
			(xy 442.286644 -70.60311) (xy 442.794644 -70.09511) (xy 443.6872 -70.09511) (xy 444.04407 -70.45198)
			(xy 445.971676 -70.45198) (xy 445.981328 -70.45198) (xy 445.981328 -65.949576) (xy 446.328546 -65.602612)
			(xy 451.339966 -65.602612) (xy 451.557644 -65.820036) (xy 451.557644 -70.430136) (xy 451.29704 -70.69074)
			(xy 450.2912 -70.69074) (xy 450.275706 -70.70598) (xy 446.183766 -70.70598) (xy 445.981328 -70.503796)
			(xy 445.981328 -70.461632) (xy 445.971676 -70.45198) (xy 444.04407 -70.45198) (xy 444.267336 -70.675246)
			(xy 444.267336 -71.521066) (xy 444.348616 -71.602346) (xy 445.641476 -71.602346) (xy 445.760856 -71.721726)
			(xy 445.760856 -72.420226) (xy 445.765936 -72.425306) (xy 447.394076 -72.425306) (xy 447.396616 -72.427846)
			(xy 447.396616 -73.327006) (xy 447.394076 -73.329546) (xy 446.647316 -73.329546) (xy 446.644776 -73.332086)
			(xy 446.644776 -75.295506) (xy 446.649856 -75.300586) (xy 450.190616 -75.300586) (xy 450.193156 -75.298046)
			(xy 450.193156 -73.629266) (xy 449.045076 -73.629266) (xy 449.042536 -73.626726) (xy 449.042536 -70.962266)
			(xy 449.045076 -70.959726) (xy 450.480176 -70.959726) (xy 450.513196 -70.926706) (xy 455.676 -70.926706)
			(xy 456.559158 -70.043548) (xy 461.158844 -70.043548) (xy 461.336644 -69.865748) (xy 461.336644 -59.158632)
			(xy 461.31988 -59.141868) (xy 461.31988 -47.366428) (xy 461.1624 -47.208948) (xy 447.4972 -47.208948)
			(xy 445.7446 -48.961548) (xy 440.8678 -48.961548) (xy 440.69 -49.139348) (xy 440.69 -50.847752) (xy 440.987688 -51.14544)
			(xy 445.846708 -51.14544) (xy 446.9638 -50.028348) (xy 448.672458 -50.028348) (xy 448.687399 -50.027829)
			(xy 448.716005 -50.019191) (xy 448.740886 -50.002643) (xy 448.759912 -49.979601) (xy 448.771454 -49.952039)
			(xy 448.774523 -49.922315) (xy 448.768857 -49.892976) (xy 448.762374 -49.879504) (xy 448.743242 -49.842172)
			(xy 448.711475 -49.764526) (xy 448.687384 -49.684166) (xy 448.671196 -49.60185) (xy 448.663064 -49.518352)
			(xy 448.662552 -49.476406) (xy 448.663041 -49.435267) (xy 448.670862 -49.353361) (xy 448.686434 -49.272569)
			(xy 448.709614 -49.193624) (xy 448.740194 -49.117239) (xy 448.777896 -49.044107) (xy 448.822379 -48.97489)
			(xy 448.87324 -48.910215) (xy 448.930019 -48.850667) (xy 448.992201 -48.796786) (xy 449.059223 -48.74906)
			(xy 449.130478 -48.707921) (xy 449.205321 -48.673741) (xy 449.283075 -48.64683) (xy 449.363034 -48.627432)
			(xy 449.444475 -48.615723) (xy 449.52666 -48.611808) (xy 449.608845 -48.615723) (xy 449.690286 -48.627432)
			(xy 449.770245 -48.64683) (xy 449.847999 -48.673741) (xy 449.922842 -48.707921) (xy 449.994097 -48.74906)
			(xy 450.061119 -48.796786) (xy 450.123301 -48.850667) (xy 450.18008 -48.910215) (xy 450.230941 -48.97489)
			(xy 450.275424 -49.044107) (xy 450.313126 -49.117239) (xy 450.343706 -49.193624) (xy 450.366886 -49.272569)
			(xy 450.382458 -49.353361) (xy 450.390279 -49.435267) (xy 450.390768 -49.476406) (xy 450.39027 -49.518353)
			(xy 450.382136 -49.601851) (xy 450.365945 -49.684167) (xy 450.341849 -49.764526) (xy 450.310076 -49.84217)
			(xy 450.290946 -49.879504) (xy 450.284472 -49.892969) (xy 450.278838 -49.922296) (xy 450.281925 -49.951998)
			(xy 450.29347 -49.979539) (xy 450.312485 -50.002565) (xy 450.337347 -50.019108) (xy 450.365931 -50.027754)
			(xy 450.380862 -50.028348) (xy 456.180698 -50.028348) (xy 456.195635 -50.027824) (xy 456.22423 -50.019179)
			(xy 456.2491 -50.00263) (xy 456.268117 -49.979592) (xy 456.279654 -49.952036) (xy 456.282723 -49.922321)
			(xy 456.277062 -49.892989) (xy 456.270614 -49.879504) (xy 456.251481 -49.842172) (xy 456.219713 -49.764526)
			(xy 456.195621 -49.684167) (xy 456.179432 -49.601851) (xy 456.171299 -49.518353) (xy 456.170792 -49.476406)
			(xy 456.171281 -49.435267) (xy 456.179102 -49.353361) (xy 456.194674 -49.272569) (xy 456.217854 -49.193624)
			(xy 456.248434 -49.117239) (xy 456.286136 -49.044107) (xy 456.330619 -48.97489) (xy 456.38148 -48.910215)
			(xy 456.438259 -48.850667) (xy 456.500441 -48.796786) (xy 456.567463 -48.74906) (xy 456.638718 -48.707921)
			(xy 456.713561 -48.673741) (xy 456.791315 -48.64683) (xy 456.871274 -48.627432) (xy 456.952715 -48.615723)
			(xy 457.0349 -48.611808) (xy 457.117085 -48.615723) (xy 457.198526 -48.627432) (xy 457.278485 -48.64683)
			(xy 457.356239 -48.673741) (xy 457.431082 -48.707921) (xy 457.502337 -48.74906) (xy 457.569359 -48.796786)
			(xy 457.631541 -48.850667) (xy 457.68832 -48.910215) (xy 457.739181 -48.97489) (xy 457.783664 -49.044107)
			(xy 457.821366 -49.117239) (xy 457.851946 -49.193624) (xy 457.875126 -49.272569) (xy 457.890698 -49.353361)
			(xy 457.898519 -49.435267) (xy 457.899008 -49.476406) (xy 457.89851 -49.518353) (xy 457.890375 -49.601851)
			(xy 457.874183 -49.684166) (xy 457.850086 -49.764524) (xy 457.818311 -49.842167) (xy 457.799186 -49.879504)
			(xy 457.792711 -49.892967) (xy 457.787074 -49.922291) (xy 457.79016 -49.951992) (xy 457.801706 -49.97953)
			(xy 457.820723 -50.002551) (xy 457.845587 -50.019087) (xy 457.874172 -50.027724) (xy 457.889102 -50.028348)
			(xy 458.4446 -50.028348) (xy 459.105 -50.688748) (xy 459.105 -57.639712) (xy 458.3176 -58.427112)
			(xy 436.660036 -58.427112) (xy 436.0672 -59.019948) (xy 436.0672 -85.461348) (xy 437.2102 -86.604348)
			(xy 460.8068 -86.604348)
		)
		(stroke
			(width 0)
			(type solid)
		)
		(fill yes)
		(layer "F.Cu")
		(net "GND")
	)
	(gr_poly
		(pts
			(arc
				(start 251.159264 -96.891348)
				(mid 251.25313 -96.828629)
				(end 251.231146 -96.717866)
			)
			(xy 249.881644 -95.368364)
			(arc
				(start 249.861832 -95.367602)
				(mid 249.602251 -95.250539)
				(end 249.496072 -94.986348)
			)
			(arc
				(start 249.496072 -94.986348)
				(mid 249.546822 -94.796223)
				(end 249.685556 -94.656656)
			)
			(xy 249.685556 -94.260924) (xy 249.668538 -94.24416)
			(arc
				(start 248.66854 -94.24416)
				(mid 248.594973 -94.229509)
				(end 248.53265 -94.187772)
			)
			(arc
				(start 248.40311 -94.058232)
				(mid 248.361534 -93.99587)
				(end 248.346976 -93.922342)
			)
			(arc
				(start 248.346976 -93.315282)
				(mid 248.36151 -93.241744)
				(end 248.40311 -93.179392)
			)
			(arc
				(start 248.53265 -93.049852)
				(mid 248.594983 -93.008139)
				(end 248.66854 -92.993464)
			)
			(xy 249.668538 -92.993464) (xy 249.685556 -92.9767)
			(arc
				(start 249.685556 -92.917264)
				(mid 249.649021 -92.839231)
				(end 249.565668 -92.817188)
			)
			(arc
				(start 249.565668 -92.817188)
				(mid 249.544929 -92.820065)
				(end 249.524012 -92.820998)
			)
			(xy 249.524012 -92.820744) (xy 249.2248 -92.820744)
			(arc
				(start 249.2248 -92.820998)
				(mid 249.063964 -92.755328)
				(end 248.997216 -92.594938)
			)
			(xy 248.997216 -92.327476) (xy 249.05716 -92.327476)
			(arc
				(start 249.05716 -92.22105)
				(mid 249.025717 -92.174083)
				(end 248.970292 -92.185236)
			)
			(arc
				(start 248.95429 -92.201238)
				(mid 248.891928 -92.242814)
				(end 248.8184 -92.257372)
			)
			(arc
				(start 248.741692 -92.257372)
				(mid 248.602139 -92.396131)
				(end 248.412 -92.446856)
			)
			(arc
				(start 248.412 -92.446856)
				(mid 248.142233 -92.335115)
				(end 248.030492 -92.065348)
			)
			(arc
				(start 248.030492 -92.065348)
				(mid 248.033692 -92.016295)
				(end 248.043192 -91.968066)
			)
			(arc
				(start 248.043192 -91.968066)
				(mid 248.004792 -91.907335)
				(end 247.991376 -91.836748)
			)
			(xy 247.991376 -90.86088)
			(arc
				(start 247.990106 -90.855546)
				(mid 247.985863 -90.830305)
				(end 247.984518 -90.804746)
			)
			(xy 247.984772 -90.804746) (xy 247.984772 -90.505534)
			(arc
				(start 247.984518 -90.505534)
				(mid 248.050097 -90.344532)
				(end 248.210578 -90.277696)
			)
			(xy 248.266712 -90.277696)
			(arc
				(start 248.490486 -90.053922)
				(mid 248.512522 -89.943138)
				(end 248.418604 -89.88044)
			)
			(arc
				(start 247.938036 -89.88044)
				(mid 247.91237 -89.877929)
				(end 247.887744 -89.87028)
			)
			(xy 247.878092 -89.865962) (xy 247.816624 -89.865962)
			(arc
				(start 247.816624 -89.957148)
				(mid 247.80209 -90.030686)
				(end 247.76049 -90.093038)
			)
			(xy 247.494806 -90.358722)
			(arc
				(start 247.513094 -90.391996)
				(mid 247.533957 -90.445221)
				(end 247.54078 -90.501978)
			)
			(arc
				(start 247.54078 -90.80119)
				(mid 247.504793 -90.925098)
				(end 247.406922 -91.009216)
			)
			(xy 247.376696 -91.022678) (xy 247.376696 -93.555058) (xy 247.784366 -94.5388) (xy 248.76252 -95.516954)
			(arc
				(start 248.788936 -95.512128)
				(mid 248.824587 -95.506995)
				(end 248.860564 -95.50527)
			)
			(arc
				(start 248.860564 -95.50527)
				(mid 249.050625 -95.555945)
				(end 249.190256 -95.6945)
			)
			(arc
				(start 249.801126 -95.6945)
				(mid 249.874693 -95.709151)
				(end 249.937016 -95.750888)
			)
			(arc
				(start 250.833636 -96.647508)
				(mid 250.858481 -96.678192)
				(end 250.876562 -96.713294)
			)
			(xy 250.880626 -96.7232) (xy 251.04852 -96.891348)
		)
		(stroke
			(width 0)
			(type solid)
		)
		(fill yes)
		(layer "F.Cu")
		(net "GND")
	)
	(gr_poly
		(pts
			(xy 56.829198 -336.20583) (xy 56.829198 -334.33385) (xy 56.704738 -334.20939) (xy 39.557198 -334.20939)
			(xy 39.023798 -334.74279) (xy 39.023798 -335.995772) (xy 39.126414 -336.098134)
			(arc
				(start 39.66591 -336.098134)
				(mid 39.75478 -336.045775)
				(end 39.752016 -335.942686)
			)
			(arc
				(start 39.752016 -335.942686)
				(mid 39.651293 -335.716474)
				(end 39.616888 -335.471262)
			)
			(arc
				(start 39.616888 -335.471262)
				(mid 40.506396 -334.581754)
				(end 41.395904 -335.471262)
			)
			(arc
				(start 41.395904 -335.471262)
				(mid 41.361442 -335.716458)
				(end 41.260776 -335.942686)
			)
			(arc
				(start 41.260776 -335.942686)
				(mid 41.258049 -336.045754)
				(end 41.346882 -336.098134)
			)
			(arc
				(start 45.852842 -336.098134)
				(mid 45.941298 -336.046064)
				(end 45.939202 -335.943448)
			)
			(arc
				(start 45.939202 -335.943448)
				(mid 45.841116 -335.719652)
				(end 45.80763 -335.477612)
			)
			(arc
				(start 45.80763 -335.477612)
				(mid 46.697138 -334.588104)
				(end 47.586646 -335.477612)
			)
			(arc
				(start 47.586646 -335.477612)
				(mid 47.553155 -335.719651)
				(end 47.455074 -335.943448)
			)
			(arc
				(start 47.455074 -335.943448)
				(mid 47.452989 -336.046058)
				(end 47.541434 -336.098134)
			)
			(arc
				(start 52.050442 -336.098134)
				(mid 52.138898 -336.046064)
				(end 52.136802 -335.943448)
			)
			(arc
				(start 52.136802 -335.943448)
				(mid 52.038716 -335.719652)
				(end 52.00523 -335.477612)
			)
			(arc
				(start 52.00523 -335.477612)
				(mid 52.894738 -334.588104)
				(end 53.784246 -335.477612)
			)
			(arc
				(start 53.784246 -335.477612)
				(mid 53.750755 -335.719651)
				(end 53.652674 -335.943448)
			)
			(arc
				(start 53.652674 -335.943448)
				(mid 53.650589 -336.046058)
				(end 53.739034 -336.098134)
			)
			(xy 55.88762 -336.098134) (xy 56.036718 -336.247232) (xy 56.787796 -336.247232)
		)
		(stroke
			(width 0)
			(type solid)
		)
		(fill yes)
		(layer "F.Cu")
		(net "GND")
	)
	(gr_poly
		(pts
			(xy 283.31414 -360.004868) (xy 283.31414 -355.511608) (xy 281.7495 -353.946968) (xy 281.12212 -353.946968)
			(xy 280.76144 -353.586288) (xy 280.76144 -345.605608) (xy 281.06116 -345.305888)
			(arc
				(start 286.44596 -345.305888)
				(mid 286.534189 -345.254669)
				(end 286.533336 -345.152726)
			)
			(arc
				(start 286.533336 -345.152726)
				(mid 286.441257 -344.934821)
				(end 286.409892 -344.700352)
			)
			(arc
				(start 286.409892 -344.700352)
				(mid 287.2994 -343.810844)
				(end 288.188908 -344.700352)
			)
			(arc
				(start 288.188908 -344.700352)
				(mid 288.15752 -344.934815)
				(end 288.065464 -345.152726)
			)
			(arc
				(start 288.065464 -345.152726)
				(mid 288.064737 -345.254597)
				(end 288.15284 -345.305888)
			)
			(arc
				(start 292.64356 -345.305888)
				(mid 292.731789 -345.254669)
				(end 292.730936 -345.152726)
			)
			(arc
				(start 292.730936 -345.152726)
				(mid 292.638857 -344.934821)
				(end 292.607492 -344.700352)
			)
			(arc
				(start 292.607492 -344.700352)
				(mid 293.497 -343.810844)
				(end 294.386508 -344.700352)
			)
			(arc
				(start 294.386508 -344.700352)
				(mid 294.35512 -344.934815)
				(end 294.263064 -345.152726)
			)
			(arc
				(start 294.263064 -345.152726)
				(mid 294.262337 -345.254597)
				(end 294.35044 -345.305888)
			)
			(arc
				(start 298.84116 -345.305888)
				(mid 298.929389 -345.254669)
				(end 298.928536 -345.152726)
			)
			(arc
				(start 298.928536 -345.152726)
				(mid 298.836457 -344.934821)
				(end 298.805092 -344.700352)
			)
			(arc
				(start 298.805092 -344.700352)
				(mid 299.6946 -343.810844)
				(end 300.584108 -344.700352)
			)
			(arc
				(start 300.584108 -344.700352)
				(mid 300.55272 -344.934815)
				(end 300.460664 -345.152726)
			)
			(arc
				(start 300.460664 -345.152726)
				(mid 300.459937 -345.254597)
				(end 300.54804 -345.305888)
			)
			(xy 302.199548 -345.305888) (xy 302.496728 -345.603068) (xy 303.464468 -345.603068) (xy 303.521872 -345.545664)
			(xy 303.521872 -342.681306) (xy 303.116234 -342.275668) (xy 274.0152 -342.275668) (xy 273.48434 -342.806528)
			(xy 273.48434 -360.812588) (xy 274.22856 -361.556808) (xy 281.7622 -361.556808)
		)
		(stroke
			(width 0)
			(type solid)
		)
		(fill yes)
		(layer "F.Cu")
		(net "GND")
	)
	(gr_poly
		(pts
			(arc
				(start 194.443604 -441.479432)
				(mid 194.479525 -441.464553)
				(end 194.494404 -441.428632)
			)
			(arc
				(start 194.494404 -441.17006)
				(mid 194.790421 -440.455411)
				(end 195.50507 -440.159394)
			)
			(arc
				(start 276.314916 -440.159394)
				(mid 277.029565 -440.455411)
				(end 277.325582 -441.17006)
			)
			(arc
				(start 277.325582 -441.428632)
				(mid 277.340461 -441.464553)
				(end 277.376382 -441.479432)
			)
			(xy 287.86963 -441.479432) (xy 287.870138 -441.479432)
			(arc
				(start 365.618268 -441.479432)
				(mid 365.646701 -441.470901)
				(end 365.665512 -441.447936)
			)
			(xy 365.706914 -441.346336) (xy 365.700564 -441.316364)
			(arc
				(start 365.689642 -441.305442)
				(mid 365.534936 -441.149171)
				(end 365.384588 -440.988704)
			)
			(arc
				(start 365.384588 -440.988704)
				(mid 365.367575 -440.976299)
				(end 365.346996 -440.97194)
			)
			(xy 343.817956 -440.97194)
			(arc
				(start 343.810082 -440.974734)
				(mid 343.731096 -440.993945)
				(end 343.650062 -441.000388)
			)
			(arc
				(start 343.650062 -441.000388)
				(mid 343.569026 -440.993957)
				(end 343.490042 -440.974734)
			)
			(xy 343.482168 -440.97194) (xy 339.817964 -440.97194)
			(arc
				(start 339.81009 -440.974734)
				(mid 339.731104 -440.993945)
				(end 339.65007 -441.000388)
			)
			(arc
				(start 339.65007 -441.000388)
				(mid 339.569034 -440.993957)
				(end 339.49005 -440.974734)
			)
			(xy 339.482176 -440.97194) (xy 335.817972 -440.97194)
			(arc
				(start 335.810098 -440.974734)
				(mid 335.731112 -440.993945)
				(end 335.650078 -441.000388)
			)
			(arc
				(start 335.650078 -441.000388)
				(mid 335.569042 -440.993957)
				(end 335.490058 -440.974734)
			)
			(xy 335.482184 -440.97194) (xy 332.122018 -440.97194) (xy 332.108556 -440.976004)
			(arc
				(start 332.102206 -440.980068)
				(mid 332.069255 -440.995208)
				(end 332.033372 -441.000388)
			)
			(arc
				(start 331.2668 -441.000388)
				(mid 331.230933 -440.995154)
				(end 331.197966 -440.980068)
			)
			(xy 331.191616 -440.976004) (xy 331.178154 -440.97194) (xy 326.81799 -440.97194)
			(arc
				(start 326.810116 -440.974734)
				(mid 326.73113 -440.993945)
				(end 326.650096 -441.000388)
			)
			(arc
				(start 326.650096 -441.000388)
				(mid 326.56906 -440.993957)
				(end 326.490076 -440.974734)
			)
			(xy 326.482202 -440.97194) (xy 322.817998 -440.97194)
			(arc
				(start 322.810124 -440.974734)
				(mid 322.731138 -440.993945)
				(end 322.650104 -441.000388)
			)
			(arc
				(start 322.650104 -441.000388)
				(mid 322.569068 -440.993957)
				(end 322.490084 -440.974734)
			)
			(xy 322.48221 -440.97194) (xy 318.818006 -440.97194)
			(arc
				(start 318.810132 -440.974734)
				(mid 318.731146 -440.993945)
				(end 318.650112 -441.000388)
			)
			(arc
				(start 318.650112 -441.000388)
				(mid 318.569076 -440.993957)
				(end 318.490092 -440.974734)
			)
			(xy 318.482218 -440.97194) (xy 315.122052 -440.97194) (xy 315.10859 -440.976004)
			(arc
				(start 315.10224 -440.980068)
				(mid 315.069289 -440.995208)
				(end 315.033406 -441.000388)
			)
			(arc
				(start 314.266834 -441.000388)
				(mid 314.230967 -440.995154)
				(end 314.198 -440.980068)
			)
			(xy 314.19165 -440.976004) (xy 314.178188 -440.97194)
			(arc
				(start 277.82012 -440.97194)
				(mid 277.31587 -440.028787)
				(end 276.314916 -439.652156)
			)
			(arc
				(start 195.50507 -439.652156)
				(mid 194.504157 -440.028834)
				(end 193.999866 -440.97194)
			)
			(arc
				(start 185.701432 -440.97194)
				(mid 185.680894 -440.976389)
				(end 185.66384 -440.988704)
			)
			(arc
				(start 185.66384 -440.988704)
				(mid 185.513488 -441.149167)
				(end 185.358786 -441.305442)
			)
			(xy 185.347864 -441.316364) (xy 185.341514 -441.346336)
			(arc
				(start 185.382916 -441.447936)
				(mid 185.401727 -441.470901)
				(end 185.43016 -441.479432)
			)
		)
		(stroke
			(width 0)
			(type solid)
		)
		(fill yes)
		(layer "F.Cu")
		(net "GND")
	)
	(gr_poly
		(pts
			(xy 451.301866 -435.59984) (xy 451.301365 -435.529025) (xy 451.293352 -435.387622) (xy 451.277352 -435.246898)
			(xy 451.253417 -435.107305) (xy 451.221622 -434.96929) (xy 451.18207 -434.833294) (xy 451.134887 -434.699755)
			(xy 451.080225 -434.569098) (xy 451.018259 -434.441743) (xy 450.949186 -434.318098) (xy 450.873229 -434.198559)
			(xy 450.790631 -434.083508) (xy 450.701656 -433.973315) (xy 450.60659 -433.868331) (xy 450.505736 -433.768895)
			(xy 450.399418 -433.675323) (xy 450.287977 -433.587917) (xy 450.171769 -433.506955) (xy 450.051167 -433.432697)
			(xy 449.926556 -433.365381) (xy 449.798337 -433.305223) (xy 449.66692 -433.252416) (xy 449.532726 -433.207127)
			(xy 449.396185 -433.169504) (xy 449.257733 -433.139665) (xy 449.117816 -433.117707) (xy 448.97688 -433.103701)
			(xy 448.835377 -433.09769) (xy 448.693761 -433.099694) (xy 448.552485 -433.109707) (xy 448.412002 -433.127696)
			(xy 448.272762 -433.153605) (xy 448.135211 -433.187349) (xy 447.999788 -433.228822) (xy 447.86693 -433.27789)
			(xy 447.73706 -433.334395) (xy 447.610594 -433.398158) (xy 447.487939 -433.468973) (xy 447.369486 -433.546614)
			(xy 447.255616 -433.630832) (xy 447.146693 -433.721357) (xy 447.043066 -433.8179) (xy 446.945066 -433.92015)
			(xy 446.853009 -434.027782) (xy 446.767188 -434.140449) (xy 446.687878 -434.257791) (xy 446.615335 -434.379432)
			(xy 446.549789 -434.504982) (xy 446.491451 -434.634039) (xy 446.440509 -434.766191) (xy 446.397124 -434.901012)
			(xy 446.361436 -435.038072) (xy 446.33356 -435.176932) (xy 446.313584 -435.317147) (xy 446.301573 -435.458267)
			(xy 446.297565 -435.59984) (xy 446.739528 -435.59984) (xy 446.743513 -435.471743) (xy 446.755455 -435.344142)
			(xy 446.775307 -435.21753) (xy 446.802991 -435.092397) (xy 446.838402 -434.969228) (xy 446.881401 -434.848498)
			(xy 446.931823 -434.730675) (xy 446.989472 -434.616214) (xy 447.054126 -434.505559) (xy 447.125534 -434.399138)
			(xy 447.203421 -434.297362) (xy 447.287484 -434.200625) (xy 447.377398 -434.109301) (xy 447.472816 -434.023744)
			(xy 447.573369 -433.944284) (xy 447.678667 -433.871229) (xy 447.788303 -433.804862) (xy 447.901853 -433.74544)
			(xy 448.018878 -433.693192) (xy 448.138924 -433.64832) (xy 448.261528 -433.610998) (xy 448.386215 -433.581371)
			(xy 448.512503 -433.559553) (xy 448.639903 -433.545628) (xy 448.767922 -433.539651) (xy 448.896066 -433.541644)
			(xy 449.023837 -433.5516) (xy 449.150742 -433.56948) (xy 449.276291 -433.595215) (xy 449.399996 -433.628706)
			(xy 449.52138 -433.669822) (xy 449.639973 -433.718406) (xy 449.755316 -433.774268) (xy 449.866963 -433.837193)
			(xy 449.974482 -433.906938) (xy 450.077458 -433.983232) (xy 450.17549 -434.06578) (xy 450.268201 -434.154263)
			(xy 450.355232 -434.248339) (xy 450.436246 -434.347644) (xy 450.510929 -434.451793) (xy 450.578993 -434.560384)
			(xy 450.640175 -434.672996) (xy 450.694236 -434.789194) (xy 450.74097 -434.908529) (xy 450.780194 -435.030537)
			(xy 450.811756 -435.154749) (xy 450.835536 -435.280682) (xy 450.85144 -435.40785) (xy 450.859408 -435.535761)
			(xy 450.859906 -435.59984) (xy 450.859408 -435.663919) (xy 450.85144 -435.79183) (xy 450.835536 -435.918998)
			(xy 450.811756 -436.044931) (xy 450.780194 -436.169143) (xy 450.74097 -436.291151) (xy 450.694236 -436.410486)
			(xy 450.640175 -436.526684) (xy 450.578993 -436.639296) (xy 450.510929 -436.747887) (xy 450.436246 -436.852036)
			(xy 450.355232 -436.951341) (xy 450.268201 -437.045417) (xy 450.17549 -437.1339) (xy 450.077458 -437.216448)
			(xy 449.974482 -437.292742) (xy 449.866963 -437.362487) (xy 449.755316 -437.425412) (xy 449.639973 -437.481274)
			(xy 449.52138 -437.529858) (xy 449.399996 -437.570974) (xy 449.276291 -437.604465) (xy 449.150742 -437.6302)
			(xy 449.023837 -437.64808) (xy 448.896066 -437.658036) (xy 448.767922 -437.660029) (xy 448.639903 -437.654052)
			(xy 448.512503 -437.640127) (xy 448.386215 -437.618309) (xy 448.261528 -437.588682) (xy 448.138924 -437.55136)
			(xy 448.018878 -437.506488) (xy 447.901853 -437.45424) (xy 447.788303 -437.394818) (xy 447.678667 -437.328451)
			(xy 447.573369 -437.255396) (xy 447.472816 -437.175936) (xy 447.377398 -437.090379) (xy 447.287484 -436.999055)
			(xy 447.203421 -436.902318) (xy 447.125534 -436.800542) (xy 447.054126 -436.694121) (xy 446.989472 -436.583466)
			(xy 446.931823 -436.469005) (xy 446.881401 -436.351182) (xy 446.838402 -436.230452) (xy 446.802991 -436.107283)
			(xy 446.775307 -435.98215) (xy 446.755455 -435.855538) (xy 446.743513 -435.727937) (xy 446.739528 -435.59984)
			(xy 446.297565 -435.59984) (xy 446.301573 -435.741413) (xy 446.313584 -435.882533) (xy 446.33356 -436.022748)
			(xy 446.361436 -436.161608) (xy 446.397124 -436.298668) (xy 446.440509 -436.433489) (xy 446.491451 -436.565641)
			(xy 446.549789 -436.694698) (xy 446.615335 -436.820248) (xy 446.687878 -436.941889) (xy 446.767188 -437.059231)
			(xy 446.853009 -437.171898) (xy 446.945066 -437.27953) (xy 447.043066 -437.38178) (xy 447.146693 -437.478323)
			(xy 447.255616 -437.568848) (xy 447.369486 -437.653066) (xy 447.487939 -437.730707) (xy 447.610594 -437.801522)
			(xy 447.73706 -437.865285) (xy 447.86693 -437.92179) (xy 447.999788 -437.970858) (xy 448.135211 -438.012331)
			(xy 448.272762 -438.046075) (xy 448.412002 -438.071984) (xy 448.552485 -438.089973) (xy 448.693761 -438.099986)
			(xy 448.835377 -438.10199) (xy 448.97688 -438.095979) (xy 449.117816 -438.081973) (xy 449.257733 -438.060015)
			(xy 449.396185 -438.030176) (xy 449.532726 -437.992553) (xy 449.66692 -437.947264) (xy 449.798337 -437.894457)
			(xy 449.926556 -437.834299) (xy 450.051167 -437.766983) (xy 450.171769 -437.692725) (xy 450.287977 -437.611763)
			(xy 450.399418 -437.524357) (xy 450.505736 -437.430785) (xy 450.60659 -437.331349) (xy 450.701656 -437.226365)
			(xy 450.790631 -437.116172) (xy 450.873229 -437.001121) (xy 450.949186 -436.881582) (xy 451.018259 -436.757937)
			(xy 451.080225 -436.630582) (xy 451.134887 -436.499925) (xy 451.18207 -436.366386) (xy 451.221622 -436.23039)
			(xy 451.253417 -436.092375) (xy 451.277352 -435.952782) (xy 451.293352 -435.812058) (xy 451.301365 -435.670655)
		)
		(stroke
			(width 0)
			(type solid)
		)
		(fill yes)
		(layer "F.Cu")
		(net "Net_8632")
	)
	(gr_poly
		(pts
			(xy 69.751194 -172.357288) (xy 69.766215 -172.35671) (xy 69.794938 -172.347895) (xy 69.81986 -172.331113)
			(xy 69.838829 -172.307813) (xy 69.850208 -172.280005) (xy 69.853014 -172.250091) (xy 69.847006 -172.220652)
			(xy 69.840348 -172.207174) (xy 69.819068 -172.166857) (xy 69.783691 -172.08283) (xy 69.756838 -171.995704)
			(xy 69.738776 -171.906341) (xy 69.729683 -171.815625) (xy 69.729096 -171.77004) (xy 69.729584 -171.727764)
			(xy 69.737386 -171.643572) (xy 69.752922 -171.560459) (xy 69.776061 -171.479135) (xy 69.806605 -171.400292)
			(xy 69.844293 -171.324604) (xy 69.888804 -171.252716) (xy 69.939758 -171.185242) (xy 69.996721 -171.122757)
			(xy 70.059206 -171.065794) (xy 70.12668 -171.01484) (xy 70.198568 -170.970329) (xy 70.274256 -170.932641)
			(xy 70.353099 -170.902097) (xy 70.434423 -170.878958) (xy 70.517536 -170.863422) (xy 70.601728 -170.85562)
			(xy 70.68628 -170.85562) (xy 70.770472 -170.863422) (xy 70.853585 -170.878958) (xy 70.934909 -170.902097)
			(xy 71.013752 -170.932641) (xy 71.08944 -170.970329) (xy 71.161328 -171.01484) (xy 71.228802 -171.065794)
			(xy 71.291287 -171.122757) (xy 71.34825 -171.185242) (xy 71.399204 -171.252716) (xy 71.443715 -171.324604)
			(xy 71.481403 -171.400292) (xy 71.511947 -171.479135) (xy 71.535086 -171.560459) (xy 71.550622 -171.643572)
			(xy 71.558424 -171.727764) (xy 71.558912 -171.77004) (xy 71.55837 -171.815629) (xy 71.549307 -171.906354)
			(xy 71.531255 -171.995726) (xy 71.504392 -172.082856) (xy 71.468988 -172.166878) (xy 71.44766 -172.207174)
			(xy 71.440951 -172.22064) (xy 71.4349 -172.250094) (xy 71.437687 -172.280034) (xy 71.44907 -172.307866)
			(xy 71.468063 -172.331177) (xy 71.49302 -172.347949) (xy 71.52178 -172.356729) (xy 71.536814 -172.357288)
			(xy 71.85406 -172.357288) (xy 73.4314 -170.779948) (xy 73.4314 -161.488882) (xy 73.38695 -161.483548)
			(xy 73.366556 -161.480611) (xy 73.327237 -161.468312) (xy 73.290798 -161.449091) (xy 73.258446 -161.423584)
			(xy 73.231252 -161.392636) (xy 73.210117 -161.357273) (xy 73.195741 -161.318664) (xy 73.1886 -161.27809)
			(xy 73.188322 -161.257488) (xy 73.188576 -161.257488) (xy 73.188576 -161.03346) (xy 72.42302 -161.03346)
			(xy 71.932292 -161.524188) (xy 71.939912 -161.524188) (xy 71.25716 -162.20694) (xy 68.90004 -162.20694)
			(xy 68.217288 -161.524188) (xy 64.991488 -161.524188) (xy 64.011556 -160.544256) (xy 63.187834 -160.544256)
			(xy 63.170308 -160.562036) (xy 63.170308 -164.634926) (xy 69.007995 -164.634926) (xy 69.012017 -164.549206)
			(xy 69.024048 -164.464238) (xy 69.043984 -164.380771) (xy 69.071647 -164.299537) (xy 69.106796 -164.221251)
			(xy 69.149122 -164.1466) (xy 69.198251 -164.076241) (xy 69.253754 -164.010791) (xy 69.315141 -163.950827)
			(xy 69.381874 -163.896874) (xy 69.453366 -163.849407) (xy 69.528988 -163.808843) (xy 69.608077 -163.775539)
			(xy 69.689937 -163.749787) (xy 69.773848 -163.731814) (xy 69.859074 -163.721778) (xy 69.944866 -163.719766)
			(xy 70.030468 -163.725797) (xy 70.11513 -163.739817) (xy 70.198107 -163.761703) (xy 70.27867 -163.791264)
			(xy 70.35611 -163.828238) (xy 70.429749 -163.872302) (xy 70.498937 -163.923068) (xy 70.563068 -163.980089)
			(xy 70.621577 -164.042865) (xy 70.67395 -164.110845) (xy 70.719728 -164.18343) (xy 70.758508 -164.259982)
			(xy 70.789949 -164.33983) (xy 70.813775 -164.422271) (xy 70.829776 -164.506581) (xy 70.837811 -164.592019)
			(xy 70.838314 -164.634926) (xy 70.837811 -164.677833) (xy 70.829776 -164.763271) (xy 70.813775 -164.847581)
			(xy 70.789949 -164.930022) (xy 70.758508 -165.00987) (xy 70.719728 -165.086422) (xy 70.67395 -165.159007)
			(xy 70.621577 -165.226987) (xy 70.563068 -165.289763) (xy 70.498937 -165.346784) (xy 70.429749 -165.39755)
			(xy 70.35611 -165.441614) (xy 70.27867 -165.478588) (xy 70.198107 -165.508149) (xy 70.11513 -165.530035)
			(xy 70.030468 -165.544055) (xy 69.944866 -165.550086) (xy 69.859074 -165.548074) (xy 69.773848 -165.538038)
			(xy 69.689937 -165.520065) (xy 69.608077 -165.494313) (xy 69.528988 -165.461009) (xy 69.453366 -165.420445)
			(xy 69.381874 -165.372978) (xy 69.315141 -165.319025) (xy 69.253754 -165.259061) (xy 69.198251 -165.193611)
			(xy 69.149122 -165.123252) (xy 69.106796 -165.048601) (xy 69.071647 -164.970315) (xy 69.043984 -164.889081)
			(xy 69.024048 -164.805614) (xy 69.012017 -164.720646) (xy 69.007995 -164.634926) (xy 63.170308 -164.634926)
			(xy 63.170308 -167.422322) (xy 69.034152 -167.422322) (xy 69.034152 -165.847522) (xy 69.034562 -165.834165)
			(xy 69.041472 -165.808361) (xy 69.054825 -165.785226) (xy 69.073713 -165.766335) (xy 69.096847 -165.752978)
			(xy 69.122649 -165.746064) (xy 69.136006 -165.745668) (xy 70.710806 -165.745668) (xy 70.724165 -165.746037)
			(xy 70.749973 -165.752955) (xy 70.77311 -165.766317) (xy 70.792 -165.785212) (xy 70.805356 -165.808353)
			(xy 70.812266 -165.834163) (xy 70.81266 -165.847522) (xy 70.81266 -167.422322) (xy 70.812238 -167.435674)
			(xy 70.805321 -167.461468) (xy 70.791966 -167.484594) (xy 70.773081 -167.503476) (xy 70.749954 -167.516828)
			(xy 70.724159 -167.52374) (xy 70.710806 -167.524176) (xy 69.136006 -167.524176) (xy 69.122656 -167.523713)
			(xy 69.096866 -167.516805) (xy 69.073741 -167.503458) (xy 69.054859 -167.484581) (xy 69.041506 -167.46146)
			(xy 69.03459 -167.435672) (xy 69.034152 -167.422322) (xy 63.170308 -167.422322) (xy 63.170308 -169.945558)
			(xy 63.123572 -169.99204) (xy 63.123572 -170.201844) (xy 63.284608 -170.36288) (xy 66.072512 -170.36288)
			(xy 67.581272 -171.87164) (xy 67.592255 -171.881815) (xy 67.618679 -171.89586) (xy 67.648039 -171.901647)
			(xy 67.677816 -171.898678) (xy 67.705455 -171.887208) (xy 67.728586 -171.868221) (xy 67.745222 -171.843347)
			(xy 67.753938 -171.81472) (xy 67.7545 -171.799758) (xy 67.7545 -170.98264) (xy 67.754893 -170.969246)
			(xy 67.761818 -170.94337) (xy 67.775206 -170.920169) (xy 67.794144 -170.901225) (xy 67.817341 -170.88783)
			(xy 67.843215 -170.880897) (xy 67.856608 -170.880532) (xy 69.431408 -170.880532) (xy 69.444796 -170.880931)
			(xy 69.470658 -170.887864) (xy 69.493844 -170.901256) (xy 69.512773 -170.920194) (xy 69.526154 -170.943386)
			(xy 69.533076 -170.969252) (xy 69.533516 -170.98264) (xy 69.533516 -172.357288)
		)
		(stroke
			(width 0)
			(type solid)
		)
		(fill yes)
		(layer "F.Cu")
		(net "PVCCD_HV_CPU1")
	)
	(gr_poly
		(pts
			(xy 230.38054 -434.93182) (xy 230.380794 -432.48834) (xy 230.41102 -432.458114) (xy 230.41102 -423.3164)
			(xy 230.41229 -423.31513) (xy 230.41229 -422.599358) (xy 232.369868 -420.64178) (xy 232.3719 -420.64178)
			(xy 232.518458 -420.495222) (xy 232.553764 -420.459916) (xy 233.946192 -420.459916) (xy 234.25531 -420.459916)
			(xy 234.437174 -420.64178) (xy 235.090208 -420.64178) (xy 270.34998 -420.64178) (xy 275.54936 -415.4424)
			(xy 279.79624 -415.4424) (xy 280.19756 -415.04108) (xy 280.19756 -408.29992) (xy 279.96896 -408.07132)
			(xy 278.240998 -408.07132) (xy 278.240998 -410.259784) (xy 278.189944 -410.310838)
			(arc
				(start 278.189944 -410.660596)
				(mid 278.152747 -410.750399)
				(end 278.062944 -410.787596)
			)
			(arc
				(start 277.656544 -410.787596)
				(mid 277.566741 -410.750399)
				(end 277.529544 -410.660596)
			)
			(xy 277.529544 -410.310838) (xy 277.47849 -410.259784) (xy 277.47849 -408.07132) (xy 269.2146 -408.07132)
			(xy 269.2146 -408.319732) (xy 269.214346 -408.32405) (xy 269.214346 -408.35072) (xy 269.210028 -408.355038)
			(arc
				(start 269.206218 -408.365198)
				(mid 269.177169 -408.409977)
				(end 269.132304 -408.438858)
			)
			(xy 269.122144 -408.442922) (xy 268.99108 -408.573986) (xy 268.675104 -408.573986) (xy 268.54404 -408.442922)
			(arc
				(start 268.53388 -408.438858)
				(mid 268.489185 -408.409893)
				(end 268.46022 -408.365198)
			)
			(xy 268.45641 -408.355292) (xy 268.451838 -408.35072) (xy 268.451838 -408.32405) (xy 268.451584 -408.319732)
			(xy 268.451584 -408.07132) (xy 261.1882 -408.07132) (xy 261.1882 -408.319732) (xy 261.187946 -408.32532)
			(xy 261.187946 -408.35072) (xy 261.183882 -408.354784) (xy 261.179818 -408.364944)
			(arc
				(start 261.179818 -408.365198)
				(mid 261.150769 -408.409977)
				(end 261.105904 -408.438858)
			)
			(xy 261.095744 -408.442922) (xy 260.96468 -408.573986) (xy 260.648704 -408.573986) (xy 260.51764 -408.442922)
			(arc
				(start 260.50748 -408.438858)
				(mid 260.458275 -408.405146)
				(end 260.429756 -408.352752)
			)
			(xy 260.42874 -408.34945) (xy 260.425438 -408.341322) (xy 260.425438 -408.32532) (xy 260.425184 -408.319732)
			(xy 260.425184 -408.07132) (xy 253.1618 -408.07132) (xy 253.1618 -408.319986) (xy 253.161546 -408.32659)
			(xy 253.161546 -408.35072) (xy 253.157482 -408.354784)
			(arc
				(start 253.153418 -408.364944)
				(mid 253.12439 -408.40983)
				(end 253.079504 -408.438858)
			)
			(xy 253.069344 -408.442922) (xy 252.93828 -408.573986) (xy 252.622304 -408.573986) (xy 252.49124 -408.442922)
			(arc
				(start 252.48108 -408.438858)
				(mid 252.436385 -408.409893)
				(end 252.40742 -408.365198)
			)
			(xy 252.403356 -408.355038) (xy 252.399038 -408.35072) (xy 252.399038 -408.32659) (xy 252.398784 -408.319986)
			(xy 252.398784 -408.07132) (xy 245.132352 -408.07132) (xy 245.132352 -408.315668) (xy 245.132098 -408.323796)
			(xy 245.132098 -408.346656)
			(arc
				(start 245.127272 -408.351482)
				(mid 245.095042 -408.405866)
				(end 245.040658 -408.438096)
			)
			(xy 244.908832 -408.569922) (xy 244.592856 -408.569922)
			(arc
				(start 244.46103 -408.438096)
				(mid 244.404728 -408.403906)
				(end 244.373146 -408.346148)
			)
			(xy 244.36959 -408.337258) (xy 244.36959 -408.323796) (xy 244.369336 -408.315668) (xy 244.369336 -408.07132)
			(xy 239.56772 -408.07132) (xy 237.61446 -406.11806) (xy 235.38942 -406.11806) (xy 233.88066 -404.6093)
			(xy 233.88066 -401.03298) (xy 233.86542 -401.01774) (xy 230.47706 -401.01774) (xy 230.46182 -401.03298)
			(xy 230.46182 -404.604728) (xy 230.256588 -404.80996) (xy 230.256588 -407.522172) (xy 228.0666 -409.71216)
			(xy 225.575368 -409.71216) (xy 223.398588 -407.53538) (xy 223.398588 -404.79218) (xy 223.21774 -404.611332)
			(xy 223.21774 -401.04568) (xy 223.19234 -401.02028) (xy 219.81414 -401.02028) (xy 219.79636 -401.03806)
			(xy 219.79636 -404.622508) (xy 219.613988 -404.80488) (xy 219.613988 -407.3906) (xy 217.404188 -409.6004)
			(xy 214.66302 -409.6004) (xy 212.71992 -407.6573) (xy 212.71992 -404.79472) (xy 212.54212 -404.61692)
			(xy 212.54212 -401.02536) (xy 212.53704 -401.02028) (xy 209.14106 -401.02028) (xy 209.13598 -401.02536)
			(xy 209.13598 -404.584408) (xy 208.945988 -404.7744) (xy 208.945988 -407.435812) (xy 206.67726 -409.70454)
			(xy 204.028548 -409.70454) (xy 202.062588 -407.73858) (xy 202.062588 -404.779988) (xy 201.87666 -404.59406)
			(xy 201.87666 -401.03298) (xy 201.86396 -401.02028) (xy 198.47306 -401.02028) (xy 198.46798 -401.02536)
			(xy 198.46798 -404.61946) (xy 197.10146 -405.98598) (xy 190.73876 -405.98598) (xy 189.362588 -404.609554)
			(xy 189.362588 -404.328122) (xy 189.21222 -404.177754) (xy 189.014608 -404.177754) (xy 188.989208 -404.152354)
			(xy 188.981588 -404.152354)
			(arc
				(start 188.905642 -404.076408)
				(mid 188.870884 -404.05173)
				(end 188.846206 -404.016972)
			)
			(xy 188.61786 -403.788626) (xy 188.61786 -401.02028) (xy 188.600588 -401.002754) (xy 185.196988 -401.002754)
			(xy 185.196988 -404.659592)
			(arc
				(start 185.213752 -404.674578)
				(mid 185.232001 -404.694969)
				(end 185.245502 -404.718774)
			)
			(xy 185.249312 -404.727664) (xy 185.344562 -404.822914) (xy 185.344562 -406.636728) (xy 185.527188 -406.819354)
			(xy 185.527188 -406.871678) (xy 185.531252 -406.89149) (xy 185.531252 -406.891744) (xy 185.531506 -406.892506)
			(arc
				(start 185.533284 -406.897078)
				(mid 185.541458 -406.918945)
				(end 185.54827 -406.941274)
			)
			(xy 185.575702 -406.968706) (xy 185.575702 -407.724102) (xy 185.527188 -407.772616) (xy 185.527188 -408.419554)
			(xy 185.323988 -408.622754) (xy 185.323988 -413.055054) (xy 192.871344 -420.602156) (xy 197.539356 -420.602156)
			(xy 206.49184 -429.55464) (xy 206.49184 -435.39156) (xy 207.63484 -436.53456) (xy 228.7778 -436.53456)
		)
		(stroke
			(width 0)
			(type solid)
		)
		(fill yes)
		(layer "F.Cu")
		(net "P12V_PSU")
	)
	(gr_poly
		(pts
			(xy 319.33134 -190.950342) (xy 319.33007 -190.9445) (xy 319.326343 -190.927887) (xy 319.32151 -190.894181)
			(xy 319.320418 -190.87719) (xy 319.319039 -190.861924) (xy 319.308338 -190.833216) (xy 319.289618 -190.808963)
			(xy 319.264556 -190.79134) (xy 319.235399 -190.781927) (xy 319.220088 -190.781178) (xy 319.193015 -190.780433)
			(xy 319.139481 -190.772239) (xy 319.087644 -190.756556) (xy 319.038546 -190.7337) (xy 318.993174 -190.70413)
			(xy 318.95244 -190.66844) (xy 318.917162 -190.627348) (xy 318.888051 -190.581681) (xy 318.86569 -190.532355)
			(xy 318.85053 -190.480363) (xy 318.842875 -190.426749) (xy 318.84239 -190.39967) (xy 318.842878 -190.37242)
			(xy 318.850638 -190.318476) (xy 318.865995 -190.266184) (xy 318.888638 -190.216611) (xy 318.918105 -190.170764)
			(xy 318.953797 -190.129577) (xy 318.994986 -190.093889) (xy 319.040835 -190.064425) (xy 319.090411 -190.041786)
			(xy 319.142703 -190.026432) (xy 319.196648 -190.018676) (xy 319.223898 -190.018162) (xy 319.252861 -190.0187)
			(xy 319.310121 -190.027455) (xy 319.3654 -190.044766) (xy 319.417426 -190.070234) (xy 319.465005 -190.103274)
			(xy 319.507043 -190.143126) (xy 319.542574 -190.188875) (xy 319.570781 -190.239469) (xy 319.591015 -190.293746)
			(xy 319.602813 -190.350457) (xy 319.604898 -190.37935) (xy 319.60627 -190.394621) (xy 319.616961 -190.423343)
			(xy 319.63568 -190.447608) (xy 319.660747 -190.46524) (xy 319.689912 -190.474655) (xy 319.705228 -190.475362)
			(xy 319.732299 -190.476108) (xy 319.785829 -190.484304) (xy 319.837662 -190.499989) (xy 319.886755 -190.522847)
			(xy 319.932123 -190.552418) (xy 319.972852 -190.588108) (xy 320.008124 -190.6292) (xy 320.03723 -190.674867)
			(xy 320.059585 -190.724192) (xy 320.074739 -190.776182) (xy 320.082388 -190.829793) (xy 320.082926 -190.85687)
			(xy 320.082624 -190.878981) (xy 320.07753 -190.922907) (xy 320.072766 -190.9445) (xy 320.071496 -190.950342)
			(xy 320.071496 -191.277851) (xy 321.367648 -191.277851) (xy 321.367648 -191.223349) (xy 321.375404 -191.1694)
			(xy 321.390758 -191.117105) (xy 321.413398 -191.067526) (xy 321.442863 -191.021674) (xy 321.478552 -190.980482)
			(xy 321.519741 -190.944788) (xy 321.56559 -190.915318) (xy 321.615165 -190.892673) (xy 321.667459 -190.877313)
			(xy 321.721407 -190.869551) (xy 321.748658 -190.869062) (xy 321.770768 -190.869382) (xy 321.814693 -190.87447)
			(xy 321.836288 -190.879222) (xy 321.84213 -190.880492) (xy 327.453752 -190.880492) (xy 327.453752 -190.742824)
			(xy 328.088244 -190.742824) (xy 328.088244 -190.775336) (xy 328.596752 -190.775336) (xy 328.596752 -190.638938)
			(xy 328.58456 -190.624714) (xy 328.565291 -190.601163) (xy 328.53283 -190.549696) (xy 328.507903 -190.494187)
			(xy 328.491004 -190.435731) (xy 328.482466 -190.375484) (xy 328.481944 -190.34506) (xy 328.481944 -189.72911)
			(xy 328.482447 -189.699591) (xy 328.490486 -189.641103) (xy 328.506415 -189.584255) (xy 328.529935 -189.530105)
			(xy 328.56061 -189.479662) (xy 328.597868 -189.433865) (xy 328.641015 -189.393569) (xy 328.689247 -189.359523)
			(xy 328.741666 -189.332362) (xy 328.797295 -189.312591) (xy 328.855098 -189.30058) (xy 328.913998 -189.296551)
			(xy 328.972898 -189.30058) (xy 329.030701 -189.312591) (xy 329.08633 -189.332362) (xy 329.138749 -189.359523)
			(xy 329.186981 -189.393569) (xy 329.230128 -189.433865) (xy 329.267386 -189.479662) (xy 329.298061 -189.530105)
			(xy 329.321581 -189.584255) (xy 329.33751 -189.641103) (xy 329.345549 -189.699591) (xy 329.346052 -189.72911)
			(xy 329.346052 -190.34506) (xy 329.345432 -190.37732) (xy 329.335837 -190.441122) (xy 329.316869 -190.502791)
			(xy 329.288949 -190.560957) (xy 329.252696 -190.614329) (xy 329.231244 -190.63843) (xy 329.231244 -190.955168)
			(xy 329.244706 -190.979552) (xy 329.25893 -191.007492) (xy 329.291188 -191.007492) (xy 329.291188 -191.275208)
			(xy 329.290655 -191.297517) (xy 329.281913 -191.34127) (xy 329.264769 -191.382463) (xy 329.239888 -191.419499)
			(xy 329.208233 -191.450944) (xy 329.171032 -191.475578) (xy 329.129726 -191.492447) (xy 329.085916 -191.500898)
			(xy 329.063604 -191.501268) (xy 329.014836 -191.501268) (xy 329.008486 -191.502792) (xy 328.985283 -191.508505)
			(xy 328.937891 -191.514617) (xy 328.913998 -191.514984) (xy 327.92416 -191.514984) (xy 327.903311 -191.534656)
			(xy 327.856675 -191.56798) (xy 327.805453 -191.593706) (xy 327.750875 -191.611217) (xy 327.694247 -191.620094)
			(xy 327.665588 -191.620648) (xy 321.84213 -191.620648) (xy 321.836288 -191.621918) (xy 321.814695 -191.626684)
			(xy 321.770769 -191.631777) (xy 321.748658 -191.632078) (xy 321.721407 -191.631649) (xy 321.667459 -191.623887)
			(xy 321.615165 -191.608527) (xy 321.565589 -191.585882) (xy 321.519741 -191.556412) (xy 321.478552 -191.520718)
			(xy 321.442863 -191.479526) (xy 321.413398 -191.433674) (xy 321.390758 -191.384095) (xy 321.375404 -191.3318)
			(xy 321.367648 -191.277851) (xy 320.071496 -191.277851) (xy 320.071496 -193.34607) (xy 336.262218 -193.34607)
			(xy 338.088224 -191.520064) (xy 338.088224 -173.260004) (xy 350.778318 -160.56991) (xy 361.804458 -160.56991)
			(xy 365.752634 -156.621734) (xy 365.752634 -153.583894) (xy 364.038134 -151.869394) (xy 359.786174 -151.869394)
			(xy 359.447338 -152.20823) (xy 348.251018 -152.20823) (xy 313.653678 -186.80557) (xy 313.653678 -187.518548)
			(xy 332.718662 -187.518548) (xy 332.722733 -187.462926) (xy 332.734859 -187.408489) (xy 332.754782 -187.356398)
			(xy 332.782078 -187.307763) (xy 332.816164 -187.26362) (xy 332.856313 -187.224911) (xy 332.901671 -187.19246)
			(xy 332.951271 -187.166959) (xy 333.004055 -187.148952) (xy 333.058898 -187.138822) (xy 333.114632 -187.136785)
			(xy 333.170069 -187.142885) (xy 333.224026 -187.156991) (xy 333.275355 -187.178803) (xy 333.322961 -187.207857)
			(xy 333.365829 -187.243532) (xy 333.403046 -187.285069) (xy 333.433819 -187.331582) (xy 333.457491 -187.382079)
			(xy 333.473559 -187.435486) (xy 333.481679 -187.490662) (xy 333.482188 -187.518548) (xy 333.481679 -187.546434)
			(xy 333.473559 -187.60161) (xy 333.457491 -187.655017) (xy 333.433819 -187.705514) (xy 333.403046 -187.752027)
			(xy 333.365829 -187.793564) (xy 333.322961 -187.829239) (xy 333.275355 -187.858293) (xy 333.224026 -187.880105)
			(xy 333.170069 -187.894211) (xy 333.114632 -187.900311) (xy 333.058898 -187.898274) (xy 333.004055 -187.888144)
			(xy 332.951271 -187.870137) (xy 332.901671 -187.844636) (xy 332.856313 -187.812185) (xy 332.816164 -187.773476)
			(xy 332.782078 -187.729333) (xy 332.754782 -187.680698) (xy 332.734859 -187.628607) (xy 332.722733 -187.57417)
			(xy 332.718662 -187.518548) (xy 313.653678 -187.518548) (xy 313.653678 -189.69101) (xy 311.664858 -191.67983)
			(xy 311.664858 -193.01333) (xy 311.997598 -193.34607) (xy 319.33134 -193.34607)
		)
		(stroke
			(width 0)
			(type solid)
		)
		(fill yes)
		(layer "F.Cu")
		(net "PVNN_TERM_CPU0")
	)
	(gr_poly
		(pts
			(xy 438.83834 -367.149888) (xy 438.83834 -341.353648) (xy 438.516014 -341.031322) (xy 402.954998 -341.031322)
			(xy 402.54174 -341.44458) (xy 402.54174 -357.0097) (xy 403.083268 -357.551228) (xy 410.59354 -357.551228)
			(xy 411.14726 -358.104948) (xy 411.14726 -360.360468) (xy 411.82798 -361.041188)
			(arc
				(start 412.03245 -360.836718)
				(mid 412.007981 -360.764073)
				(end 411.999684 -360.687874)
			)
			(arc
				(start 411.999684 -360.687112)
				(mid 412.103986 -360.435306)
				(end 412.355792 -360.331004)
			)
			(arc
				(start 412.389574 -360.332528)
				(mid 412.428555 -360.319553)
				(end 412.4452 -360.281982)
			)
			(xy 412.4452 -353.657408) (xy 412.49854 -353.604068) (xy 412.14802 -353.253548) (xy 411.81782 -353.253548)
			(xy 411.37078 -352.806508) (xy 411.37078 -345.003628) (xy 411.69336 -344.681048)
			(arc
				(start 414.290002 -344.681048)
				(mid 414.379895 -344.626311)
				(end 414.37306 -344.521282)
			)
			(arc
				(start 414.37306 -344.521282)
				(mid 414.253446 -344.278633)
				(end 414.212278 -344.01125)
			)
			(arc
				(start 414.212278 -344.010996)
				(mid 415.101786 -343.121488)
				(end 415.991294 -344.010996)
			)
			(arc
				(start 415.991294 -344.01125)
				(mid 415.950153 -344.278641)
				(end 415.830512 -344.521282)
			)
			(arc
				(start 415.830512 -344.521282)
				(mid 415.82367 -344.626314)
				(end 415.91357 -344.681048)
			)
			(arc
				(start 420.476426 -344.681048)
				(mid 420.566156 -344.626624)
				(end 420.559992 -344.52179)
			)
			(arc
				(start 420.559992 -344.52179)
				(mid 420.443163 -344.281495)
				(end 420.40302 -344.017346)
			)
			(arc
				(start 420.40302 -344.017346)
				(mid 421.292528 -343.127838)
				(end 422.182036 -344.017346)
			)
			(arc
				(start 422.182036 -344.017346)
				(mid 422.141837 -344.281477)
				(end 422.025064 -344.52179)
			)
			(arc
				(start 422.025064 -344.52179)
				(mid 422.01878 -344.626687)
				(end 422.10863 -344.681048)
			)
			(arc
				(start 426.674026 -344.681048)
				(mid 426.763756 -344.626624)
				(end 426.757592 -344.52179)
			)
			(arc
				(start 426.757592 -344.52179)
				(mid 426.640763 -344.281495)
				(end 426.60062 -344.017346)
			)
			(arc
				(start 426.60062 -344.017346)
				(mid 427.490128 -343.127838)
				(end 428.379636 -344.017346)
			)
			(arc
				(start 428.379636 -344.017346)
				(mid 428.339437 -344.281477)
				(end 428.222664 -344.52179)
			)
			(arc
				(start 428.222664 -344.52179)
				(mid 428.21638 -344.626687)
				(end 428.30623 -344.681048)
			)
			(xy 434.0987 -344.681048) (xy 434.47462 -345.056968) (xy 434.47462 -352.636328) (xy 433.1335 -353.977448)
			(xy 433.1335 -363.786928) (xy 437.6674 -368.320828)
		)
		(stroke
			(width 0)
			(type solid)
		)
		(fill yes)
		(layer "F.Cu")
		(net "GND")
	)
	(gr_poly
		(pts
			(xy 217.68816 -360.76382) (xy 217.687662 -360.674399) (xy 217.679695 -360.495735) (xy 217.663777 -360.317602)
			(xy 217.63994 -360.140356) (xy 217.60823 -359.964348) (xy 217.568712 -359.789926) (xy 217.521463 -359.617439)
			(xy 217.466576 -359.447227) (xy 217.404162 -359.27963) (xy 217.334344 -359.114979) (xy 217.257261 -358.953602)
			(xy 217.173065 -358.795818) (xy 217.081925 -358.641942) (xy 216.984019 -358.492279) (xy 216.879545 -358.347126)
			(xy 216.768707 -358.206771) (xy 216.651728 -358.071493) (xy 216.528838 -357.94156) (xy 216.400282 -357.81723)
			(xy 216.266315 -357.698751) (xy 216.127204 -357.586357) (xy 215.983223 -357.480271) (xy 215.83466 -357.380705)
			(xy 215.681809 -357.287856) (xy 215.524974 -357.201907) (xy 215.364465 -357.123031) (xy 215.200602 -357.051383)
			(xy 215.03371 -356.987106) (xy 214.864121 -356.930327) (xy 214.69217 -356.881159) (xy 214.5182 -356.8397)
			(xy 214.342556 -356.806032) (xy 214.165586 -356.780221) (xy 213.987642 -356.76232) (xy 213.809078 -356.752363)
			(xy 213.630247 -356.750371) (xy 213.451505 -356.756347) (xy 213.273206 -356.77028) (xy 213.095705 -356.792141)
			(xy 212.919355 -356.821887) (xy 212.744504 -356.85946) (xy 212.571501 -356.904785) (xy 212.400688 -356.957772)
			(xy 212.232406 -357.018315) (xy 212.066987 -357.086294) (xy 211.904761 -357.161575) (xy 211.74605 -357.244008)
			(xy 211.591168 -357.333429) (xy 211.440424 -357.429661) (xy 211.294116 -357.532512) (xy 211.152535 -357.641779)
			(xy 211.015961 -357.757244) (xy 210.884668 -357.878679) (xy 210.758914 -358.005842) (xy 210.638949 -358.13848)
			(xy 210.525012 -358.276331) (xy 210.417329 -358.419121) (xy 210.316114 -358.566565) (xy 210.221568 -358.718373)
			(xy 210.133878 -358.874241) (xy 210.053218 -359.033861) (xy 209.979749 -359.196915) (xy 209.913617 -359.363081)
			(xy 209.854952 -359.532027) (xy 209.803872 -359.703419) (xy 209.760477 -359.876917) (xy 209.724855 -360.052175)
			(xy 209.697074 -360.228846) (xy 209.677192 -360.40658) (xy 209.665246 -360.585022) (xy 209.661262 -360.76382)
			(xy 211.159857 -360.76382) (xy 211.163885 -360.621528) (xy 211.175957 -360.479692) (xy 211.196034 -360.338765)
			(xy 211.224052 -360.199201) (xy 211.259921 -360.061445) (xy 211.303526 -359.925939) (xy 211.354727 -359.793117)
			(xy 211.413361 -359.663404) (xy 211.479239 -359.537217) (xy 211.552151 -359.414958) (xy 211.631863 -359.297021)
			(xy 211.71812 -359.183782) (xy 211.810644 -359.075604) (xy 211.909141 -358.972834) (xy 212.013295 -358.875801)
			(xy 212.122771 -358.784817) (xy 212.237219 -358.700171) (xy 212.356273 -358.622136) (xy 212.479551 -358.550962)
			(xy 212.606658 -358.486875) (xy 212.737187 -358.430083) (xy 212.870721 -358.380766) (xy 213.00683 -358.339083)
			(xy 213.14508 -358.305167) (xy 213.285027 -358.279127) (xy 213.426223 -358.261046) (xy 213.568216 -358.250983)
			(xy 213.710551 -358.248968) (xy 213.852772 -358.25501) (xy 213.994423 -358.269088) (xy 214.135051 -358.291157)
			(xy 214.274205 -358.321147) (xy 214.41144 -358.358962) (xy 214.546315 -358.40448) (xy 214.678399 -358.457556)
			(xy 214.807269 -358.518019) (xy 214.932512 -358.585676) (xy 215.053726 -358.660311) (xy 215.170524 -358.741684)
			(xy 215.282531 -358.829534) (xy 215.389389 -358.923581) (xy 215.490754 -359.023522) (xy 215.586303 -359.129038)
			(xy 215.67573 -359.239791) (xy 215.758748 -359.355425) (xy 215.83509 -359.475572) (xy 215.904513 -359.599844)
			(xy 215.966794 -359.727846) (xy 216.021734 -359.859166) (xy 216.069156 -359.993383) (xy 216.108909 -360.130069)
			(xy 216.140865 -360.268785) (xy 216.164922 -360.409086) (xy 216.181003 -360.550524) (xy 216.189056 -360.692645)
			(xy 216.18956 -360.76382) (xy 216.189056 -360.834995) (xy 216.181003 -360.977116) (xy 216.164922 -361.118554)
			(xy 216.140865 -361.258855) (xy 216.108909 -361.397571) (xy 216.069156 -361.534257) (xy 216.021734 -361.668474)
			(xy 215.966794 -361.799794) (xy 215.904513 -361.927796) (xy 215.83509 -362.052068) (xy 215.758748 -362.172215)
			(xy 215.67573 -362.287849) (xy 215.586303 -362.398602) (xy 215.490754 -362.504118) (xy 215.389389 -362.604059)
			(xy 215.282531 -362.698106) (xy 215.170524 -362.785956) (xy 215.053726 -362.867329) (xy 214.932512 -362.941964)
			(xy 214.807269 -363.009621) (xy 214.678399 -363.070084) (xy 214.546315 -363.12316) (xy 214.41144 -363.168678)
			(xy 214.274205 -363.206493) (xy 214.135051 -363.236483) (xy 213.994423 -363.258552) (xy 213.852772 -363.27263)
			(xy 213.710551 -363.278672) (xy 213.568216 -363.276657) (xy 213.426223 -363.266594) (xy 213.285027 -363.248513)
			(xy 213.14508 -363.222473) (xy 213.00683 -363.188557) (xy 212.870721 -363.146874) (xy 212.737187 -363.097557)
			(xy 212.606658 -363.040765) (xy 212.479551 -362.976678) (xy 212.356273 -362.905504) (xy 212.237219 -362.827469)
			(xy 212.122771 -362.742823) (xy 212.013295 -362.651839) (xy 211.909141 -362.554806) (xy 211.810644 -362.452036)
			(xy 211.71812 -362.343858) (xy 211.631863 -362.230619) (xy 211.552151 -362.112682) (xy 211.479239 -361.990423)
			(xy 211.413361 -361.864236) (xy 211.354727 -361.734523) (xy 211.303526 -361.601701) (xy 211.259921 -361.466195)
			(xy 211.224052 -361.328439) (xy 211.196034 -361.188875) (xy 211.175957 -361.047948) (xy 211.163885 -360.906112)
			(xy 211.159857 -360.76382) (xy 209.661262 -360.76382) (xy 209.665246 -360.942618) (xy 209.677192 -361.12106)
			(xy 209.697074 -361.298794) (xy 209.724855 -361.475465) (xy 209.760477 -361.650723) (xy 209.803872 -361.824221)
			(xy 209.854952 -361.995613) (xy 209.913617 -362.164559) (xy 209.979749 -362.330725) (xy 210.053218 -362.493779)
			(xy 210.133878 -362.653399) (xy 210.221568 -362.809267) (xy 210.316114 -362.961075) (xy 210.417329 -363.108519)
			(xy 210.525012 -363.251309) (xy 210.638949 -363.38916) (xy 210.758914 -363.521798) (xy 210.884668 -363.648961)
			(xy 211.015961 -363.770396) (xy 211.152535 -363.885861) (xy 211.294116 -363.995128) (xy 211.440424 -364.097979)
			(xy 211.591168 -364.194211) (xy 211.74605 -364.283632) (xy 211.904761 -364.366065) (xy 212.066987 -364.441346)
			(xy 212.232406 -364.509325) (xy 212.400688 -364.569868) (xy 212.571501 -364.622855) (xy 212.744504 -364.66818)
			(xy 212.919355 -364.705753) (xy 213.095705 -364.735499) (xy 213.273206 -364.75736) (xy 213.451505 -364.771293)
			(xy 213.630247 -364.777269) (xy 213.809078 -364.775277) (xy 213.987642 -364.76532) (xy 214.165586 -364.747419)
			(xy 214.342556 -364.721608) (xy 214.5182 -364.68794) (xy 214.69217 -364.646481) (xy 214.864121 -364.597313)
			(xy 215.03371 -364.540534) (xy 215.200602 -364.476257) (xy 215.364465 -364.404609) (xy 215.524974 -364.325733)
			(xy 215.681809 -364.239784) (xy 215.83466 -364.146935) (xy 215.983223 -364.047369) (xy 216.127204 -363.941283)
			(xy 216.266315 -363.828889) (xy 216.400282 -363.71041) (xy 216.528838 -363.58608) (xy 216.651728 -363.456147)
			(xy 216.768707 -363.320869) (xy 216.879545 -363.180514) (xy 216.984019 -363.035361) (xy 217.081925 -362.885698)
			(xy 217.173065 -362.731822) (xy 217.257261 -362.574038) (xy 217.334344 -362.412661) (xy 217.404162 -362.24801)
			(xy 217.466576 -362.080413) (xy 217.521463 -361.910201) (xy 217.568712 -361.737714) (xy 217.60823 -361.563292)
			(xy 217.63994 -361.387284) (xy 217.663777 -361.210038) (xy 217.679695 -361.031905) (xy 217.687662 -360.853241)
		)
		(stroke
			(width 0)
			(type solid)
		)
		(fill yes)
		(layer "F.Cu")
		(net "GND")
	)
	(gr_poly
		(pts
			(xy 262.13816 -360.76382) (xy 262.137662 -360.674399) (xy 262.129695 -360.495735) (xy 262.113777 -360.317602)
			(xy 262.08994 -360.140356) (xy 262.05823 -359.964348) (xy 262.018712 -359.789926) (xy 261.971463 -359.617439)
			(xy 261.916576 -359.447227) (xy 261.854162 -359.27963) (xy 261.784344 -359.114979) (xy 261.707261 -358.953602)
			(xy 261.623065 -358.795818) (xy 261.531925 -358.641942) (xy 261.434019 -358.492279) (xy 261.329545 -358.347126)
			(xy 261.218707 -358.206771) (xy 261.101728 -358.071493) (xy 260.978838 -357.94156) (xy 260.850282 -357.81723)
			(xy 260.716315 -357.698751) (xy 260.577204 -357.586357) (xy 260.433223 -357.480271) (xy 260.28466 -357.380705)
			(xy 260.131809 -357.287856) (xy 259.974974 -357.201907) (xy 259.814465 -357.123031) (xy 259.650602 -357.051383)
			(xy 259.48371 -356.987106) (xy 259.314121 -356.930327) (xy 259.14217 -356.881159) (xy 258.9682 -356.8397)
			(xy 258.792556 -356.806032) (xy 258.615586 -356.780221) (xy 258.437642 -356.76232) (xy 258.259078 -356.752363)
			(xy 258.080247 -356.750371) (xy 257.901505 -356.756347) (xy 257.723206 -356.77028) (xy 257.545705 -356.792141)
			(xy 257.369355 -356.821887) (xy 257.194504 -356.85946) (xy 257.021501 -356.904785) (xy 256.850688 -356.957772)
			(xy 256.682406 -357.018315) (xy 256.516987 -357.086294) (xy 256.354761 -357.161575) (xy 256.19605 -357.244008)
			(xy 256.041168 -357.333429) (xy 255.890424 -357.429661) (xy 255.744116 -357.532512) (xy 255.602535 -357.641779)
			(xy 255.465961 -357.757244) (xy 255.334668 -357.878679) (xy 255.208914 -358.005842) (xy 255.088949 -358.13848)
			(xy 254.975012 -358.276331) (xy 254.867329 -358.419121) (xy 254.766114 -358.566565) (xy 254.671568 -358.718373)
			(xy 254.583878 -358.874241) (xy 254.503218 -359.033861) (xy 254.429749 -359.196915) (xy 254.363617 -359.363081)
			(xy 254.304952 -359.532027) (xy 254.253872 -359.703419) (xy 254.210477 -359.876917) (xy 254.174855 -360.052175)
			(xy 254.147074 -360.228846) (xy 254.127192 -360.40658) (xy 254.115246 -360.585022) (xy 254.111262 -360.76382)
			(xy 255.609857 -360.76382) (xy 255.613885 -360.621528) (xy 255.625957 -360.479692) (xy 255.646034 -360.338765)
			(xy 255.674052 -360.199201) (xy 255.709921 -360.061445) (xy 255.753526 -359.925939) (xy 255.804727 -359.793117)
			(xy 255.863361 -359.663404) (xy 255.929239 -359.537217) (xy 256.002151 -359.414958) (xy 256.081863 -359.297021)
			(xy 256.16812 -359.183782) (xy 256.260644 -359.075604) (xy 256.359141 -358.972834) (xy 256.463295 -358.875801)
			(xy 256.572771 -358.784817) (xy 256.687219 -358.700171) (xy 256.806273 -358.622136) (xy 256.929551 -358.550962)
			(xy 257.056658 -358.486875) (xy 257.187187 -358.430083) (xy 257.320721 -358.380766) (xy 257.45683 -358.339083)
			(xy 257.59508 -358.305167) (xy 257.735027 -358.279127) (xy 257.876223 -358.261046) (xy 258.018216 -358.250983)
			(xy 258.160551 -358.248968) (xy 258.302772 -358.25501) (xy 258.444423 -358.269088) (xy 258.585051 -358.291157)
			(xy 258.724205 -358.321147) (xy 258.86144 -358.358962) (xy 258.996315 -358.40448) (xy 259.128399 -358.457556)
			(xy 259.257269 -358.518019) (xy 259.382512 -358.585676) (xy 259.503726 -358.660311) (xy 259.620524 -358.741684)
			(xy 259.732531 -358.829534) (xy 259.839389 -358.923581) (xy 259.940754 -359.023522) (xy 260.036303 -359.129038)
			(xy 260.12573 -359.239791) (xy 260.208748 -359.355425) (xy 260.28509 -359.475572) (xy 260.354513 -359.599844)
			(xy 260.416794 -359.727846) (xy 260.471734 -359.859166) (xy 260.519156 -359.993383) (xy 260.558909 -360.130069)
			(xy 260.590865 -360.268785) (xy 260.614922 -360.409086) (xy 260.631003 -360.550524) (xy 260.639056 -360.692645)
			(xy 260.63956 -360.76382) (xy 260.639056 -360.834995) (xy 260.631003 -360.977116) (xy 260.614922 -361.118554)
			(xy 260.590865 -361.258855) (xy 260.558909 -361.397571) (xy 260.519156 -361.534257) (xy 260.471734 -361.668474)
			(xy 260.416794 -361.799794) (xy 260.354513 -361.927796) (xy 260.28509 -362.052068) (xy 260.208748 -362.172215)
			(xy 260.12573 -362.287849) (xy 260.036303 -362.398602) (xy 259.940754 -362.504118) (xy 259.839389 -362.604059)
			(xy 259.732531 -362.698106) (xy 259.620524 -362.785956) (xy 259.503726 -362.867329) (xy 259.382512 -362.941964)
			(xy 259.257269 -363.009621) (xy 259.128399 -363.070084) (xy 258.996315 -363.12316) (xy 258.86144 -363.168678)
			(xy 258.724205 -363.206493) (xy 258.585051 -363.236483) (xy 258.444423 -363.258552) (xy 258.302772 -363.27263)
			(xy 258.160551 -363.278672) (xy 258.018216 -363.276657) (xy 257.876223 -363.266594) (xy 257.735027 -363.248513)
			(xy 257.59508 -363.222473) (xy 257.45683 -363.188557) (xy 257.320721 -363.146874) (xy 257.187187 -363.097557)
			(xy 257.056658 -363.040765) (xy 256.929551 -362.976678) (xy 256.806273 -362.905504) (xy 256.687219 -362.827469)
			(xy 256.572771 -362.742823) (xy 256.463295 -362.651839) (xy 256.359141 -362.554806) (xy 256.260644 -362.452036)
			(xy 256.16812 -362.343858) (xy 256.081863 -362.230619) (xy 256.002151 -362.112682) (xy 255.929239 -361.990423)
			(xy 255.863361 -361.864236) (xy 255.804727 -361.734523) (xy 255.753526 -361.601701) (xy 255.709921 -361.466195)
			(xy 255.674052 -361.328439) (xy 255.646034 -361.188875) (xy 255.625957 -361.047948) (xy 255.613885 -360.906112)
			(xy 255.609857 -360.76382) (xy 254.111262 -360.76382) (xy 254.115246 -360.942618) (xy 254.127192 -361.12106)
			(xy 254.147074 -361.298794) (xy 254.174855 -361.475465) (xy 254.210477 -361.650723) (xy 254.253872 -361.824221)
			(xy 254.304952 -361.995613) (xy 254.363617 -362.164559) (xy 254.429749 -362.330725) (xy 254.503218 -362.493779)
			(xy 254.583878 -362.653399) (xy 254.671568 -362.809267) (xy 254.766114 -362.961075) (xy 254.867329 -363.108519)
			(xy 254.975012 -363.251309) (xy 255.088949 -363.38916) (xy 255.208914 -363.521798) (xy 255.334668 -363.648961)
			(xy 255.465961 -363.770396) (xy 255.602535 -363.885861) (xy 255.744116 -363.995128) (xy 255.890424 -364.097979)
			(xy 256.041168 -364.194211) (xy 256.19605 -364.283632) (xy 256.354761 -364.366065) (xy 256.516987 -364.441346)
			(xy 256.682406 -364.509325) (xy 256.850688 -364.569868) (xy 257.021501 -364.622855) (xy 257.194504 -364.66818)
			(xy 257.369355 -364.705753) (xy 257.545705 -364.735499) (xy 257.723206 -364.75736) (xy 257.901505 -364.771293)
			(xy 258.080247 -364.777269) (xy 258.259078 -364.775277) (xy 258.437642 -364.76532) (xy 258.615586 -364.747419)
			(xy 258.792556 -364.721608) (xy 258.9682 -364.68794) (xy 259.14217 -364.646481) (xy 259.314121 -364.597313)
			(xy 259.48371 -364.540534) (xy 259.650602 -364.476257) (xy 259.814465 -364.404609) (xy 259.974974 -364.325733)
			(xy 260.131809 -364.239784) (xy 260.28466 -364.146935) (xy 260.433223 -364.047369) (xy 260.577204 -363.941283)
			(xy 260.716315 -363.828889) (xy 260.850282 -363.71041) (xy 260.978838 -363.58608) (xy 261.101728 -363.456147)
			(xy 261.218707 -363.320869) (xy 261.329545 -363.180514) (xy 261.434019 -363.035361) (xy 261.531925 -362.885698)
			(xy 261.623065 -362.731822) (xy 261.707261 -362.574038) (xy 261.784344 -362.412661) (xy 261.854162 -362.24801)
			(xy 261.916576 -362.080413) (xy 261.971463 -361.910201) (xy 262.018712 -361.737714) (xy 262.05823 -361.563292)
			(xy 262.08994 -361.387284) (xy 262.113777 -361.210038) (xy 262.129695 -361.031905) (xy 262.137662 -360.853241)
		)
		(stroke
			(width 0)
			(type solid)
		)
		(fill yes)
		(layer "F.Cu")
		(net "GND")
	)
	(gr_poly
		(pts
			(xy 21.632672 -180.057552) (xy 21.786342 -180.057552) (xy 21.813266 -180.030628) (xy 23.08352 -180.030628)
			(xy 23.113746 -180.000402) (xy 23.113746 -179.817014) (xy 23.09368 -179.796948) (xy 20.955 -179.796948)
			(xy 20.1676 -179.009548) (xy 19.3548 -179.009548) (xy 18.6944 -178.349148) (xy 18.6944 -173.3423)
			(xy 19.100546 -172.936154) (xy 25.968706 -172.936154) (xy 36.467034 -172.936154) (xy 37.003228 -173.472348)
			(xy 41.369488 -173.472348) (xy 43.152314 -175.255428) (xy 43.152314 -177.432462) (xy 43.655488 -177.935636)
			(xy 52.705 -177.935636) (xy 52.8574 -177.783236) (xy 52.8574 -175.00219) (xy 52.8066 -174.95139)
			(xy 51.454558 -174.95139) (xy 51.3588 -175.047148) (xy 51.3588 -176.47793) (xy 51.181 -176.65573)
			(xy 48.065182 -176.65573) (xy 47.90567 -176.496218) (xy 47.90567 -169.917618) (xy 48.241966 -169.581322)
			(xy 50.05324 -169.581322) (xy 50.553874 -169.080688) (xy 54.486556 -169.080688) (xy 54.682136 -168.885108)
			(xy 54.682136 -165.466268) (xy 52.61102 -165.466268) (xy 52.565554 -165.511988) (xy 52.550568 -165.526974)
			(xy 52.550568 -166.80942) (xy 52.550141 -166.819488) (xy 52.542417 -166.838084) (xy 52.535582 -166.845488)
			(xy 52.336446 -167.044624) (xy 52.329048 -167.05147) (xy 52.310449 -167.059197) (xy 52.300378 -167.05961)
			(xy 51.384708 -167.05961) (xy 51.134518 -167.3098) (xy 51.127115 -167.316633) (xy 51.108517 -167.324338)
			(xy 51.09845 -167.324786) (xy 49.567338 -167.324786) (xy 48.36668 -166.124128) (xy 48.36668 -161.8488)
			(xy 49.5046 -160.71088) (xy 54.350666 -160.71088) (xy 54.682136 -160.37941) (xy 54.682136 -156.867098)
			(xy 54.681697 -156.857308) (xy 54.674393 -156.839141) (xy 54.667912 -156.831792) (xy 52.610004 -156.831792)
			(xy 52.550568 -156.890974) (xy 52.550568 -158.17342) (xy 52.550141 -158.183488) (xy 52.542417 -158.202084)
			(xy 52.535582 -158.209488) (xy 52.336446 -158.408624) (xy 52.329048 -158.41547) (xy 52.310449 -158.423197)
			(xy 52.300378 -158.42361) (xy 51.384708 -158.42361) (xy 51.134518 -158.6738) (xy 51.127115 -158.680633)
			(xy 51.108517 -158.688338) (xy 51.09845 -158.688786) (xy 49.7713 -158.688786) (xy 48.36668 -157.284166)
			(xy 48.36668 -153.289) (xy 49.5808 -152.07488) (xy 54.350666 -152.07488) (xy 54.682136 -151.74341)
			(xy 54.682136 -148.231098) (xy 54.681749 -148.222175) (xy 54.67565 -148.205404) (xy 54.670198 -148.198332)
			(xy 52.607464 -148.198332) (xy 52.550568 -148.254974) (xy 52.550568 -149.53742) (xy 52.550141 -149.547488)
			(xy 52.542417 -149.566084) (xy 52.535582 -149.573488) (xy 52.336446 -149.772624) (xy 52.329048 -149.77947)
			(xy 52.310449 -149.787197) (xy 52.300378 -149.78761) (xy 51.384708 -149.78761) (xy 51.134518 -150.0378)
			(xy 51.127115 -150.044633) (xy 51.108517 -150.052338) (xy 51.09845 -150.052786) (xy 43.99153 -150.052786)
			(xy 43.986704 -150.057612) (xy 39.658036 -150.057612) (xy 39.207186 -150.508462) (xy 39.207186 -161.89452)
			(xy 43.480228 -161.89452) (xy 43.480228 -161.891218) (xy 43.480732 -161.848857) (xy 43.488785 -161.76452)
			(xy 43.504819 -161.68133) (xy 43.528687 -161.60004) (xy 43.560175 -161.521388) (xy 43.598997 -161.446085)
			(xy 43.6448 -161.374813) (xy 43.697171 -161.308217) (xy 43.755636 -161.246902) (xy 43.819664 -161.191421)
			(xy 43.888676 -161.142278) (xy 43.962046 -161.099918) (xy 44.039111 -161.064723) (xy 44.119173 -161.037014)
			(xy 44.201506 -161.01704) (xy 44.285365 -161.004983) (xy 44.36999 -161.000952) (xy 44.454615 -161.004983)
			(xy 44.538474 -161.01704) (xy 44.620807 -161.037014) (xy 44.700869 -161.064723) (xy 44.777934 -161.099918)
			(xy 44.851304 -161.142278) (xy 44.920316 -161.191421) (xy 44.984344 -161.246902) (xy 45.042809 -161.308217)
			(xy 45.09518 -161.374813) (xy 45.140983 -161.446085) (xy 45.179805 -161.521388) (xy 45.211293 -161.60004)
			(xy 45.235161 -161.68133) (xy 45.251195 -161.76452) (xy 45.259248 -161.848857) (xy 45.259752 -161.891218)
			(xy 45.259752 -161.89452) (xy 45.259244 -161.914078) (xy 45.257688 -161.955709) (xy 45.247768 -162.038431)
			(xy 45.230157 -162.119863) (xy 45.205009 -162.199291) (xy 45.172544 -162.27602) (xy 45.133047 -162.349378)
			(xy 45.086864 -162.41872) (xy 45.034399 -162.483441) (xy 44.976112 -162.542972) (xy 44.912514 -162.596792)
			(xy 44.844162 -162.644429) (xy 44.771655 -162.685467) (xy 44.695629 -162.719545) (xy 44.616749 -162.746365)
			(xy 44.535707 -162.765692) (xy 44.453213 -162.777356) (xy 44.36999 -162.781255) (xy 44.286767 -162.777356)
			(xy 44.204273 -162.765692) (xy 44.123231 -162.746365) (xy 44.044351 -162.719545) (xy 43.968325 -162.685467)
			(xy 43.895818 -162.644429) (xy 43.827466 -162.596792) (xy 43.763868 -162.542972) (xy 43.705581 -162.483441)
			(xy 43.653116 -162.41872) (xy 43.606933 -162.349378) (xy 43.567436 -162.27602) (xy 43.534971 -162.199291)
			(xy 43.509823 -162.119863) (xy 43.492212 -162.038431) (xy 43.482292 -161.955709) (xy 43.480736 -161.914078)
			(xy 43.480228 -161.89452) (xy 39.207186 -161.89452) (xy 39.207186 -169.387774) (xy 38.750818 -169.844142)
			(xy 43.406818 -169.844142) (xy 43.406818 -169.759446) (xy 43.414869 -169.675132) (xy 43.430898 -169.591966)
			(xy 43.454759 -169.510699) (xy 43.486238 -169.432069) (xy 43.525049 -169.356788) (xy 43.570839 -169.285536)
			(xy 43.623195 -169.21896) (xy 43.681643 -169.157662) (xy 43.745653 -169.102197) (xy 43.814645 -169.053068)
			(xy 43.887995 -169.010719) (xy 43.965038 -168.975535) (xy 44.045077 -168.947833) (xy 44.127386 -168.927865)
			(xy 44.211221 -168.915812) (xy 44.295822 -168.911782) (xy 44.380423 -168.915812) (xy 44.464258 -168.927865)
			(xy 44.546567 -168.947833) (xy 44.626606 -168.975535) (xy 44.703649 -169.010719) (xy 44.776999 -169.053068)
			(xy 44.845991 -169.102197) (xy 44.910001 -169.157662) (xy 44.968449 -169.21896) (xy 45.020805 -169.285536)
			(xy 45.066595 -169.356788) (xy 45.105406 -169.432069) (xy 45.136885 -169.510699) (xy 45.160746 -169.591966)
			(xy 45.176775 -169.675132) (xy 45.184826 -169.759446) (xy 45.18533 -169.801794) (xy 45.184826 -169.844142)
			(xy 45.176775 -169.928456) (xy 45.160746 -170.011622) (xy 45.136885 -170.092889) (xy 45.105406 -170.171519)
			(xy 45.066595 -170.2468) (xy 45.020805 -170.318052) (xy 44.968449 -170.384628) (xy 44.910001 -170.445926)
			(xy 44.845991 -170.501391) (xy 44.776999 -170.55052) (xy 44.703649 -170.592869) (xy 44.626606 -170.628053)
			(xy 44.546567 -170.655755) (xy 44.464258 -170.675723) (xy 44.380423 -170.687776) (xy 44.295822 -170.691807)
			(xy 44.211221 -170.687776) (xy 44.127386 -170.675723) (xy 44.045077 -170.655755) (xy 43.965038 -170.628053)
			(xy 43.887995 -170.592869) (xy 43.814645 -170.55052) (xy 43.745653 -170.501391) (xy 43.681643 -170.445926)
			(xy 43.623195 -170.384628) (xy 43.570839 -170.318052) (xy 43.525049 -170.2468) (xy 43.486238 -170.171519)
			(xy 43.454759 -170.092889) (xy 43.430898 -170.011622) (xy 43.414869 -169.928456) (xy 43.406818 -169.844142)
			(xy 38.750818 -169.844142) (xy 36.966652 -171.628308) (xy 17.4244 -171.628308) (xy 16.5608 -172.491908)
			(xy 16.5608 -180.101748) (xy 17.013174 -180.554122) (xy 21.136102 -180.554122)
		)
		(stroke
			(width 0)
			(type solid)
		)
		(fill yes)
		(layer "F.Cu")
		(net "SW_P12V_PVCCINFAON_CPU1_FLT")
	)
	(gr_poly
		(pts
			(xy 250.40463 -96.986344)
			(arc
				(start 250.41987 -96.979994)
				(mid 250.483316 -96.906315)
				(end 250.455684 -96.813116)
			)
			(xy 249.721624 -96.079056)
			(arc
				(start 249.190256 -96.079056)
				(mid 249.05064 -96.217638)
				(end 248.860564 -96.268286)
			)
			(arc
				(start 248.860564 -96.268286)
				(mid 248.590797 -96.156545)
				(end 248.479056 -95.886778)
			)
			(arc
				(start 248.479056 -95.886778)
				(mid 248.480804 -95.850804)
				(end 248.485914 -95.81515)
			)
			(xy 248.49074 -95.788734)
			(arc
				(start 247.485662 -94.783656)
				(mid 247.461793 -94.754579)
				(end 247.444006 -94.721426)
			)
			(arc
				(start 247.007126 -93.666818)
				(mid 246.996252 -93.630702)
				(end 246.992648 -93.593158)
			)
			(xy 246.992648 -90.969084) (xy 246.782336 -90.969084) (xy 246.782336 -90.334084) (xy 247.000522 -90.334084)
			(arc
				(start 247.014746 -90.30716)
				(mid 247.030057 -90.282911)
				(end 247.048782 -90.261186)
			)
			(xy 247.432576 -89.877646) (xy 247.432576 -88.487504) (xy 247.225312 -88.28024)
			(arc
				(start 245.818152 -88.28024)
				(mid 245.72808 -88.242984)
				(end 245.690644 -88.152986)
			)
			(arc
				(start 245.690644 -86.933786)
				(mid 245.728006 -86.843714)
				(end 245.818152 -86.806532)
			)
			(arc
				(start 247.316752 -86.806532)
				(mid 247.406824 -86.843788)
				(end 247.44426 -86.933786)
			)
			(xy 247.44426 -87.955882)
			(arc
				(start 247.76049 -88.272112)
				(mid 247.786725 -88.30496)
				(end 247.805194 -88.342724)
			)
			(arc
				(start 247.805194 -88.342724)
				(mid 247.849388 -88.395671)
				(end 247.917208 -88.408256)
			)
			(xy 247.938036 -88.406732)
			(arc
				(start 249.436636 -88.406732)
				(mid 249.526708 -88.443988)
				(end 249.564144 -88.533986)
			)
			(arc
				(start 249.564144 -89.753186)
				(mid 249.528209 -89.841812)
				(end 249.4407 -89.88044)
			)
			(arc
				(start 249.4407 -89.88044)
				(mid 249.406108 -89.895483)
				(end 249.391424 -89.930224)
			)
			(arc
				(start 249.391424 -89.930224)
				(mid 249.365798 -90.048588)
				(end 249.297952 -90.148918)
			)
			(xy 248.743216 -90.703908) (xy 248.743216 -90.97264) (xy 248.47804 -90.97264) (xy 248.47804 -91.032584)
			(xy 248.375424 -91.032584)
			(arc
				(start 248.375424 -91.633294)
				(mid 248.389768 -91.668672)
				(end 248.4247 -91.684094)
			)
			(arc
				(start 248.4247 -91.684094)
				(mid 248.561518 -91.714406)
				(end 248.678192 -91.792044)
			)
			(arc
				(start 248.678192 -91.792044)
				(mid 248.749776 -91.82081)
				(end 248.82094 -91.791028)
			)
			(xy 248.997216 -91.615006)
			(arc
				(start 248.997216 -91.534742)
				(mid 249.063967 -91.374356)
				(end 249.2248 -91.308682)
			)
			(xy 249.2248 -91.308936) (xy 249.524012 -91.308936)
			(arc
				(start 249.524012 -91.308682)
				(mid 249.684848 -91.374352)
				(end 249.751596 -91.534742)
			)
			(xy 249.751596 -91.802204) (xy 249.691652 -91.802204) (xy 249.691652 -92.268294)
			(arc
				(start 249.733816 -92.27566)
				(mid 249.789219 -92.294445)
				(end 249.836432 -92.329)
			)
			(arc
				(start 250.01347 -92.506038)
				(mid 250.055046 -92.5684)
				(end 250.069604 -92.641928)
			)
			(arc
				(start 250.069604 -93.056202)
				(mid 250.05507 -93.12974)
				(end 250.01347 -93.192092)
			)
			(arc
				(start 249.88393 -93.321632)
				(mid 249.821597 -93.363345)
				(end 249.74804 -93.37802)
			)
			(xy 248.748042 -93.37802) (xy 248.731024 -93.394784) (xy 248.731024 -93.84284) (xy 248.748042 -93.859604)
			(arc
				(start 249.74804 -93.859604)
				(mid 249.821607 -93.874255)
				(end 249.88393 -93.915992)
			)
			(arc
				(start 250.01347 -94.045532)
				(mid 250.055046 -94.107894)
				(end 250.069604 -94.181422)
			)
			(arc
				(start 250.069604 -94.656656)
				(mid 250.208363 -94.796209)
				(end 250.259088 -94.986348)
			)
			(arc
				(start 250.259088 -94.986348)
				(mid 250.251941 -95.059592)
				(end 250.230894 -95.130112)
			)
			(xy 250.218194 -95.161354) (xy 251.677678 -96.621092) (xy 251.807726 -96.621092) (xy 251.827284 -96.621854)
			(xy 251.829824 -96.622108) (xy 251.975366 -96.622108) (xy 252.22454 -96.373188) (xy 251.77496 -95.923608)
			(xy 251.77496 -95.466408) (xy 251.55144 -95.242888) (xy 251.13488 -95.242888) (xy 251.107956 -95.215964)
			(arc
				(start 251.093986 -95.212662)
				(mid 250.912846 -95.111354)
				(end 250.811538 -94.930214)
			)
			(xy 250.808236 -94.916244) (xy 250.7488 -94.856808) (xy 250.7488 -91.196668) (xy 250.45416 -90.902028)
			(xy 250.45416 -87.249508) (xy 249.34672 -86.142068) (xy 245.6942 -86.142068) (xy 245.16588 -86.670388)
			(xy 245.16588 -92.913708) (xy 249.060716 -96.808544)
			(arc
				(start 249.457464 -96.808544)
				(mid 249.567119 -96.827889)
				(end 249.663458 -96.883728)
			)
			(xy 249.92584 -96.883728) (xy 250.03252 -96.990408) (xy 250.394978 -96.990408)
		)
		(stroke
			(width 0)
			(type solid)
		)
		(fill yes)
		(layer "F.Cu")
		(net "GND")
	)
	(gr_poly
		(pts
			(xy 429.25238 -181.389528) (xy 431.26152 -181.389528) (xy 431.55108 -181.099968) (xy 432.88458 -181.099968)
			(xy 432.91506 -181.069488) (xy 432.91506 -181.011068) (xy 432.91252 -181.008528) (xy 432.91252 -180.924708)
			(xy 432.86934 -180.881528) (xy 430.834038 -180.881528) (xy 430.000918 -180.048408) (xy 429.47844 -180.048408)
			(xy 429.46955 -180.057298) (xy 428.06747 -180.057298) (xy 427.176184 -179.166012) (xy 427.176184 -177.247042)
			(xy 428.52848 -175.894492) (xy 428.52848 -174.132748) (xy 429.5013 -173.159928) (xy 429.5013 -161.308288)
			(xy 430.95164 -159.857948) (xy 430.95164 -149.733508) (xy 430.482756 -149.264624) (xy 418.85108 -149.264624)
			(xy 418.7952 -149.320504) (xy 418.7952 -152.210008) (xy 418.89172 -152.306528) (xy 420.20744 -152.306528)
			(xy 420.32936 -152.184608) (xy 420.32936 -150.868888) (xy 420.489634 -150.708614) (xy 423.542206 -150.708614)
			(xy 424.83532 -152.001728) (xy 424.83532 -157.016196) (xy 426.56252 -157.016196) (xy 426.563082 -156.971941)
			(xy 426.571894 -156.883871) (xy 426.589411 -156.797112) (xy 426.61546 -156.712522) (xy 426.632116 -156.671518)
			(xy 426.63491 -156.664152) (xy 426.652452 -156.624712) (xy 426.69412 -156.549111) (xy 426.742915 -156.4779)
			(xy 426.798377 -156.411751) (xy 426.859986 -156.351284) (xy 426.927162 -156.297069) (xy 426.999273 -156.249616)
			(xy 427.075641 -156.209369) (xy 427.155548 -156.176709) (xy 427.238243 -156.151942) (xy 427.322948 -156.135302)
			(xy 427.408866 -156.126943) (xy 427.452028 -156.126434) (xy 427.495189 -156.126929) (xy 427.581105 -156.1353)
			(xy 427.665806 -156.151951) (xy 427.748496 -156.176726) (xy 427.8284 -156.209391) (xy 427.904765 -156.24964)
			(xy 427.976873 -156.297094) (xy 428.044048 -156.351307) (xy 428.105657 -156.411771) (xy 428.161122 -156.477916)
			(xy 428.209922 -156.54912) (xy 428.251598 -156.624716) (xy 428.269146 -156.664152) (xy 428.27194 -156.671518)
			(xy 428.288583 -156.712528) (xy 428.314633 -156.797116) (xy 428.332154 -156.883873) (xy 428.340974 -156.971942)
			(xy 428.341536 -157.016196) (xy 428.341105 -157.057534) (xy 428.333416 -157.139853) (xy 428.318123 -157.221104)
			(xy 428.295358 -157.300585) (xy 428.265317 -157.377611) (xy 428.22826 -157.451518) (xy 428.184505 -157.521668)
			(xy 428.134431 -157.587456) (xy 428.078469 -157.648314) (xy 428.017102 -157.703718) (xy 427.95086 -157.75319)
			(xy 427.915832 -157.775148) (xy 427.892586 -157.789115) (xy 427.844673 -157.814532) (xy 427.820074 -157.825948)
			(xy 427.776631 -157.845031) (xy 427.686562 -157.874894) (xy 427.593825 -157.894992) (xy 427.499473 -157.905094)
			(xy 427.452028 -157.905704) (xy 427.404584 -157.905082) (xy 427.310237 -157.894962) (xy 427.217501 -157.874865)
			(xy 427.127428 -157.84502) (xy 427.083982 -157.825948) (xy 427.05938 -157.814537) (xy 427.011466 -157.789122)
			(xy 426.988224 -157.775148) (xy 426.953173 -157.753226) (xy 426.886922 -157.70376) (xy 426.825549 -157.648359)
			(xy 426.769583 -157.5875) (xy 426.719508 -157.521708) (xy 426.675756 -157.451553) (xy 426.638705 -157.377639)
			(xy 426.608675 -157.300606) (xy 426.585925 -157.221117) (xy 426.570652 -157.13986) (xy 426.562987 -157.057536)
			(xy 426.56252 -157.016196) (xy 424.83532 -157.016196) (xy 424.83532 -157.325568) (xy 424.00474 -158.156148)
			(xy 416.355276 -158.156148) (xy 416.227006 -158.284418) (xy 416.227006 -161.79673) (xy 416.227154 -161.802803)
			(xy 416.229985 -161.814612) (xy 416.232594 -161.820098) (xy 418.31133 -161.820098) (xy 418.358574 -161.772854)
			(xy 418.358574 -160.490408) (xy 418.358995 -160.480337) (xy 418.366704 -160.461728) (xy 418.37356 -160.45434)
			(xy 418.572696 -160.255204) (xy 418.580094 -160.248356) (xy 418.598692 -160.24062) (xy 418.608764 -160.240218)
			(xy 419.524434 -160.240218) (xy 419.774624 -159.990028) (xy 419.782022 -159.983182) (xy 419.800621 -159.975452)
			(xy 419.810692 -159.975042) (xy 421.39616 -159.975042) (xy 422.56456 -161.143442) (xy 422.56456 -165.611048)
			(xy 421.58666 -166.588948) (xy 416.558476 -166.588948) (xy 416.227006 -166.920418) (xy 416.227006 -170.43273)
			(xy 416.227435 -170.442798) (xy 416.235158 -170.461394) (xy 416.241992 -170.468798) (xy 418.29863 -170.468798)
			(xy 418.358574 -170.408854) (xy 418.358574 -169.126408) (xy 418.358995 -169.116337) (xy 418.366704 -169.097728)
			(xy 418.37356 -169.09034) (xy 418.572696 -168.891204) (xy 418.580094 -168.884356) (xy 418.598692 -168.87662)
			(xy 418.608764 -168.876218) (xy 419.524434 -168.876218) (xy 419.774624 -168.626028) (xy 419.782022 -168.619182)
			(xy 419.800621 -168.611452) (xy 419.810692 -168.611042) (xy 421.350694 -168.611042) (xy 422.53408 -169.794428)
			(xy 422.53408 -169.953686) (xy 426.562266 -169.953686) (xy 426.56277 -169.911325) (xy 426.570823 -169.826988)
			(xy 426.586857 -169.743798) (xy 426.610725 -169.662508) (xy 426.642213 -169.583856) (xy 426.681035 -169.508553)
			(xy 426.726838 -169.437281) (xy 426.779209 -169.370685) (xy 426.837674 -169.30937) (xy 426.901702 -169.253889)
			(xy 426.970714 -169.204746) (xy 427.044084 -169.162386) (xy 427.121149 -169.127191) (xy 427.201211 -169.099482)
			(xy 427.283544 -169.079508) (xy 427.367403 -169.067451) (xy 427.452028 -169.06342) (xy 427.536653 -169.067451)
			(xy 427.620512 -169.079508) (xy 427.702845 -169.099482) (xy 427.782907 -169.127191) (xy 427.859972 -169.162386)
			(xy 427.933342 -169.204746) (xy 428.002354 -169.253889) (xy 428.066382 -169.30937) (xy 428.124847 -169.370685)
			(xy 428.177218 -169.437281) (xy 428.223021 -169.508553) (xy 428.261843 -169.583856) (xy 428.293331 -169.662508)
			(xy 428.317199 -169.743798) (xy 428.333233 -169.826988) (xy 428.341286 -169.911325) (xy 428.34179 -169.953686)
			(xy 428.34131 -169.994499) (xy 428.333807 -170.075781) (xy 428.326804 -170.115992) (xy 428.322994 -170.134534)
			(xy 428.314001 -170.175471) (xy 428.289314 -170.255575) (xy 428.257202 -170.333002) (xy 428.217948 -170.407064)
			(xy 428.171902 -170.477106) (xy 428.11947 -170.542505) (xy 428.061119 -170.602681) (xy 427.997366 -170.657102)
			(xy 427.928776 -170.705283) (xy 427.855957 -170.746799) (xy 427.779556 -170.78128) (xy 427.70025 -170.808421)
			(xy 427.618743 -170.827982) (xy 427.535757 -170.839788) (xy 427.452028 -170.843735) (xy 427.368299 -170.839788)
			(xy 427.285313 -170.827982) (xy 427.203806 -170.808421) (xy 427.1245 -170.78128) (xy 427.048099 -170.746799)
			(xy 426.97528 -170.705283) (xy 426.90669 -170.657102) (xy 426.842937 -170.602681) (xy 426.784586 -170.542505)
			(xy 426.732154 -170.477106) (xy 426.686108 -170.407064) (xy 426.646854 -170.333002) (xy 426.614742 -170.255575)
			(xy 426.590055 -170.175471) (xy 426.581062 -170.134534) (xy 426.577252 -170.115992) (xy 426.570241 -170.075782)
			(xy 426.562737 -169.9945) (xy 426.562266 -169.953686) (xy 422.53408 -169.953686) (xy 422.53408 -174.330868)
			(xy 421.64 -175.224948) (xy 416.558476 -175.224948) (xy 416.227006 -175.556418) (xy 416.227006 -179.109624)
			(xy 418.293804 -179.109624) (xy 418.358574 -179.044854) (xy 418.358574 -177.762408) (xy 418.358995 -177.752337)
			(xy 418.366704 -177.733728) (xy 418.37356 -177.72634) (xy 418.572696 -177.527204) (xy 418.580094 -177.520356)
			(xy 418.598692 -177.51262) (xy 418.608764 -177.512218) (xy 419.524434 -177.512218) (xy 419.774624 -177.262028)
			(xy 419.782022 -177.255182) (xy 419.800621 -177.247452) (xy 419.810692 -177.247042) (xy 423.448734 -177.247042)
			(xy 423.864278 -177.662586) (xy 423.864278 -180.408326) (xy 424.85564 -181.399688) (xy 429.24222 -181.399688)
		)
		(stroke
			(width 0)
			(type solid)
		)
		(fill yes)
		(layer "F.Cu")
		(net "SW_P12V_PVCCINFAON_CPU0_FLT")
	)
	(gr_poly
		(pts
			(xy 281.424634 -74.735182) (xy 282.937966 -74.735182) (xy 283.6164 -74.056748) (xy 283.6164 -58.435748)
			(xy 282.9814 -57.800748) (xy 274.4978 -57.800748) (xy 272.504916 -59.793632) (xy 272.504916 -62.26556)
			(xy 278.771602 -62.26556) (xy 278.775673 -62.209938) (xy 278.787799 -62.155501) (xy 278.807722 -62.10341)
			(xy 278.835018 -62.054775) (xy 278.869104 -62.010632) (xy 278.909253 -61.971923) (xy 278.954611 -61.939472)
			(xy 279.004211 -61.913971) (xy 279.056995 -61.895964) (xy 279.111838 -61.885834) (xy 279.167572 -61.883797)
			(xy 279.223009 -61.889897) (xy 279.276966 -61.904003) (xy 279.328295 -61.925815) (xy 279.375901 -61.954869)
			(xy 279.418769 -61.990544) (xy 279.455986 -62.032081) (xy 279.486759 -62.078594) (xy 279.510431 -62.129091)
			(xy 279.526499 -62.182498) (xy 279.534619 -62.237674) (xy 279.535128 -62.26556) (xy 279.534619 -62.293446)
			(xy 279.526499 -62.348622) (xy 279.510431 -62.402029) (xy 279.486759 -62.452526) (xy 279.455986 -62.499039)
			(xy 279.418769 -62.540576) (xy 279.375901 -62.576251) (xy 279.328295 -62.605305) (xy 279.276966 -62.627117)
			(xy 279.223009 -62.641223) (xy 279.167572 -62.647323) (xy 279.111838 -62.645286) (xy 279.056995 -62.635156)
			(xy 279.004211 -62.617149) (xy 278.954611 -62.591648) (xy 278.909253 -62.559197) (xy 278.869104 -62.520488)
			(xy 278.835018 -62.476345) (xy 278.807722 -62.42771) (xy 278.787799 -62.375619) (xy 278.775673 -62.321182)
			(xy 278.771602 -62.26556) (xy 272.504916 -62.26556) (xy 272.504916 -63.877952) (xy 278.687789 -63.877952)
			(xy 278.691811 -63.792232) (xy 278.703842 -63.707264) (xy 278.723778 -63.623797) (xy 278.751441 -63.542563)
			(xy 278.78659 -63.464277) (xy 278.828916 -63.389626) (xy 278.878045 -63.319267) (xy 278.933548 -63.253817)
			(xy 278.994935 -63.193853) (xy 279.061668 -63.1399) (xy 279.13316 -63.092433) (xy 279.208782 -63.051869)
			(xy 279.287871 -63.018565) (xy 279.369731 -62.992813) (xy 279.453642 -62.97484) (xy 279.538868 -62.964804)
			(xy 279.62466 -62.962792) (xy 279.710262 -62.968823) (xy 279.794924 -62.982843) (xy 279.877901 -63.004729)
			(xy 279.958464 -63.03429) (xy 280.035904 -63.071264) (xy 280.109543 -63.115328) (xy 280.178731 -63.166094)
			(xy 280.242862 -63.223115) (xy 280.301371 -63.285891) (xy 280.353744 -63.353871) (xy 280.399522 -63.426456)
			(xy 280.438302 -63.503008) (xy 280.469743 -63.582856) (xy 280.493569 -63.665297) (xy 280.50957 -63.749607)
			(xy 280.517605 -63.835045) (xy 280.518108 -63.877952) (xy 280.517605 -63.920859) (xy 280.50957 -64.006297)
			(xy 280.493569 -64.090607) (xy 280.469743 -64.173048) (xy 280.438302 -64.252896) (xy 280.399522 -64.329448)
			(xy 280.353744 -64.402033) (xy 280.301371 -64.470013) (xy 280.242862 -64.532789) (xy 280.178731 -64.58981)
			(xy 280.109543 -64.640576) (xy 280.035904 -64.68464) (xy 279.958464 -64.721614) (xy 279.877901 -64.751175)
			(xy 279.794924 -64.773061) (xy 279.710262 -64.787081) (xy 279.62466 -64.793112) (xy 279.538868 -64.7911)
			(xy 279.453642 -64.781064) (xy 279.369731 -64.763091) (xy 279.287871 -64.737339) (xy 279.208782 -64.704035)
			(xy 279.13316 -64.663471) (xy 279.061668 -64.616004) (xy 278.994935 -64.562051) (xy 278.933548 -64.502087)
			(xy 278.878045 -64.436637) (xy 278.828916 -64.366278) (xy 278.78659 -64.291627) (xy 278.751441 -64.213341)
			(xy 278.723778 -64.132107) (xy 278.703842 -64.04864) (xy 278.691811 -63.963672) (xy 278.687789 -63.877952)
			(xy 272.504916 -63.877952) (xy 272.504916 -66.665348) (xy 278.713692 -66.665348) (xy 278.713692 -65.090548)
			(xy 278.714131 -65.07716) (xy 278.721052 -65.051293) (xy 278.734432 -65.0281) (xy 278.753362 -65.009162)
			(xy 278.776549 -64.99577) (xy 278.802412 -64.988838) (xy 278.8158 -64.98844) (xy 280.3906 -64.98844)
			(xy 280.403994 -64.98879) (xy 280.42987 -64.995726) (xy 280.453068 -65.009124) (xy 280.472006 -65.028071)
			(xy 280.485393 -65.051275) (xy 280.492316 -65.077153) (xy 280.492708 -65.090548) (xy 280.492708 -66.665348)
			(xy 280.492313 -66.678735) (xy 280.485373 -66.704596) (xy 280.471979 -66.727779) (xy 280.453041 -66.746708)
			(xy 280.429851 -66.760092) (xy 280.403988 -66.76702) (xy 280.3906 -66.767456) (xy 278.8158 -66.767456)
			(xy 278.802419 -66.766972) (xy 278.776568 -66.760047) (xy 278.753388 -66.746669) (xy 278.73446 -66.72775)
			(xy 278.721071 -66.704577) (xy 278.714135 -66.678729) (xy 278.713692 -66.665348) (xy 272.504916 -66.665348)
			(xy 272.504916 -70.050152) (xy 278.662389 -70.050152) (xy 278.666411 -69.964432) (xy 278.678442 -69.879464)
			(xy 278.698378 -69.795997) (xy 278.726041 -69.714763) (xy 278.76119 -69.636477) (xy 278.803516 -69.561826)
			(xy 278.852645 -69.491467) (xy 278.908148 -69.426017) (xy 278.969535 -69.366053) (xy 279.036268 -69.3121)
			(xy 279.10776 -69.264633) (xy 279.183382 -69.224069) (xy 279.262471 -69.190765) (xy 279.344331 -69.165013)
			(xy 279.428242 -69.14704) (xy 279.513468 -69.137004) (xy 279.59926 -69.134992) (xy 279.684862 -69.141023)
			(xy 279.769524 -69.155043) (xy 279.852501 -69.176929) (xy 279.933064 -69.20649) (xy 280.010504 -69.243464)
			(xy 280.084143 -69.287528) (xy 280.153331 -69.338294) (xy 280.217462 -69.395315) (xy 280.275971 -69.458091)
			(xy 280.328344 -69.526071) (xy 280.374122 -69.598656) (xy 280.412902 -69.675208) (xy 280.444343 -69.755056)
			(xy 280.468169 -69.837497) (xy 280.48417 -69.921807) (xy 280.492205 -70.007245) (xy 280.492708 -70.050152)
			(xy 280.492205 -70.093059) (xy 280.48417 -70.178497) (xy 280.468169 -70.262807) (xy 280.444343 -70.345248)
			(xy 280.412902 -70.425096) (xy 280.374122 -70.501648) (xy 280.328344 -70.574233) (xy 280.275971 -70.642213)
			(xy 280.217462 -70.704989) (xy 280.153331 -70.76201) (xy 280.084143 -70.812776) (xy 280.010504 -70.85684)
			(xy 279.933064 -70.893814) (xy 279.852501 -70.923375) (xy 279.769524 -70.945261) (xy 279.684862 -70.959281)
			(xy 279.59926 -70.965312) (xy 279.513468 -70.9633) (xy 279.428242 -70.953264) (xy 279.344331 -70.935291)
			(xy 279.262471 -70.909539) (xy 279.183382 -70.876235) (xy 279.10776 -70.835671) (xy 279.036268 -70.788204)
			(xy 278.969535 -70.734251) (xy 278.908148 -70.674287) (xy 278.852645 -70.608837) (xy 278.803516 -70.538478)
			(xy 278.76119 -70.463827) (xy 278.726041 -70.385541) (xy 278.698378 -70.304307) (xy 278.678442 -70.22084)
			(xy 278.666411 -70.135872) (xy 278.662389 -70.050152) (xy 272.504916 -70.050152) (xy 272.504916 -72.837548)
			(xy 278.688292 -72.837548) (xy 278.688292 -71.262748) (xy 278.688731 -71.24936) (xy 278.695652 -71.223493)
			(xy 278.709032 -71.2003) (xy 278.727962 -71.181362) (xy 278.751149 -71.16797) (xy 278.777012 -71.161038)
			(xy 278.7904 -71.16064) (xy 280.3652 -71.16064) (xy 280.378594 -71.16099) (xy 280.40447 -71.167926)
			(xy 280.427668 -71.181324) (xy 280.446606 -71.200271) (xy 280.459993 -71.223475) (xy 280.466916 -71.249353)
			(xy 280.467308 -71.262748) (xy 280.467308 -72.837548) (xy 280.466913 -72.850935) (xy 280.459973 -72.876796)
			(xy 280.446579 -72.899979) (xy 280.427641 -72.918908) (xy 280.404451 -72.932292) (xy 280.378588 -72.93922)
			(xy 280.3652 -72.939656) (xy 278.7904 -72.939656) (xy 278.777019 -72.939172) (xy 278.751168 -72.932247)
			(xy 278.727988 -72.918869) (xy 278.70906 -72.89995) (xy 278.695671 -72.876777) (xy 278.688735 -72.850929)
			(xy 278.688292 -72.837548) (xy 272.504916 -72.837548) (xy 272.504916 -74.630026) (xy 272.620486 -74.745596)
			(xy 281.41422 -74.745596)
		)
		(stroke
			(width 0)
			(type solid)
		)
		(fill yes)
		(layer "F.Cu")
		(net "P1V05_PCH_AUX")
	)
	(gr_poly
		(pts
			(xy 240.899696 -81.699862) (xy 240.899195 -81.599808) (xy 240.891189 -81.399861) (xy 240.87519 -81.200394)
			(xy 240.851222 -81.001726) (xy 240.819325 -80.804177) (xy 240.77955 -80.608062) (xy 240.73196 -80.413696)
			(xy 240.676632 -80.221389) (xy 240.613654 -80.03145) (xy 240.543127 -79.844183) (xy 240.465164 -79.659887)
			(xy 240.37989 -79.478858) (xy 240.287441 -79.301386) (xy 240.187966 -79.127755) (xy 240.081623 -78.958243)
			(xy 239.968584 -78.793122) (xy 239.849028 -78.632655) (xy 239.723148 -78.4771) (xy 239.591145 -78.326706)
			(xy 239.453231 -78.181714) (xy 239.309626 -78.042356) (xy 239.16056 -77.908855) (xy 239.006272 -77.781425)
			(xy 238.84701 -77.66027) (xy 238.683027 -77.545584) (xy 238.514588 -77.437551) (xy 238.341961 -77.336343)
			(xy 238.165422 -77.242123) (xy 237.985256 -77.155042) (xy 237.801749 -77.075239) (xy 237.615197 -77.002842)
			(xy 237.425898 -76.937967) (xy 237.234154 -76.880717) (xy 237.040273 -76.831185) (xy 236.844566 -76.78945)
			(xy 236.647346 -76.755578) (xy 236.448929 -76.729625) (xy 236.249632 -76.71163) (xy 236.049774 -76.701624)
			(xy 235.849677 -76.699622) (xy 235.649659 -76.705627) (xy 235.450042 -76.71963) (xy 235.251145 -76.741609)
			(xy 235.053286 -76.771528) (xy 234.856783 -76.809339) (xy 234.66195 -76.854982) (xy 234.4691 -76.908383)
			(xy 234.27854 -76.969458) (xy 234.090577 -77.038107) (xy 233.90551 -77.114223) (xy 233.723637 -77.197681)
			(xy 233.545249 -77.28835) (xy 233.370632 -77.386083) (xy 233.200064 -77.490724) (xy 233.03382 -77.602106)
			(xy 232.872165 -77.72005) (xy 232.715358 -77.844368) (xy 232.563651 -77.974859) (xy 232.417287 -78.111316)
			(xy 232.276499 -78.25352) (xy 232.141513 -78.401243) (xy 232.012546 -78.554248) (xy 231.889803 -78.71229)
			(xy 231.773483 -78.875117) (xy 231.66377 -79.042467) (xy 231.56084 -79.214073) (xy 231.464859 -79.38966)
			(xy 231.375979 -79.568946) (xy 231.294344 -79.751645) (xy 231.220085 -79.937464) (xy 231.153319 -80.126105)
			(xy 231.094154 -80.317266) (xy 231.042684 -80.510641) (xy 230.998993 -80.705921) (xy 230.96315 -80.902792)
			(xy 230.935212 -81.10094) (xy 230.915225 -81.300047) (xy 230.903219 -81.499794) (xy 230.899389 -81.691235)
			(xy 232.138513 -81.691235) (xy 232.142937 -81.517286) (xy 232.155401 -81.343727) (xy 232.17588 -81.170931)
			(xy 232.204328 -80.999267) (xy 232.240686 -80.829102) (xy 232.284875 -80.660801) (xy 232.336801 -80.494724)
			(xy 232.396352 -80.331227) (xy 232.463402 -80.170658) (xy 232.537806 -80.013363) (xy 232.619406 -79.859677)
			(xy 232.708027 -79.709929) (xy 232.803478 -79.564441) (xy 232.905557 -79.423523) (xy 233.014043 -79.287477)
			(xy 233.128706 -79.156594) (xy 233.2493 -79.031155) (xy 233.375566 -78.911427) (xy 233.507235 -78.797668)
			(xy 233.644024 -78.69012) (xy 233.714544 -78.639162) (xy 238.084868 -78.639162) (xy 238.155388 -78.69012)
			(xy 238.292177 -78.797668) (xy 238.423846 -78.911427) (xy 238.550112 -79.031155) (xy 238.670706 -79.156594)
			(xy 238.785369 -79.287477) (xy 238.893855 -79.423523) (xy 238.995934 -79.564441) (xy 239.091385 -79.709929)
			(xy 239.180006 -79.859677) (xy 239.261606 -80.013363) (xy 239.33601 -80.170658) (xy 239.40306 -80.331227)
			(xy 239.462611 -80.494724) (xy 239.514537 -80.660801) (xy 239.558726 -80.829102) (xy 239.595084 -80.999267)
			(xy 239.623532 -81.170931) (xy 239.644011 -81.343727) (xy 239.656475 -81.517286) (xy 239.660899 -81.691235)
			(xy 239.657273 -81.865202) (xy 239.645605 -82.038816) (xy 239.62592 -82.211704) (xy 239.598259 -82.383497)
			(xy 239.562682 -82.553827) (xy 239.519266 -82.722329) (xy 239.468102 -82.888642) (xy 239.409301 -83.052411)
			(xy 239.342989 -83.213286) (xy 239.269307 -83.370921) (xy 239.188413 -83.52498) (xy 239.100481 -83.675132)
			(xy 239.005697 -83.821057) (xy 238.904267 -83.962441) (xy 238.796405 -84.098984) (xy 238.682344 -84.230391)
			(xy 238.562327 -84.356382) (xy 238.436611 -84.476688) (xy 238.305466 -84.59105) (xy 238.169171 -84.699225)
			(xy 238.028019 -84.80098) (xy 237.882313 -84.896097) (xy 237.732362 -84.984374) (xy 237.57849 -85.065621)
			(xy 237.421024 -85.139665) (xy 237.260302 -85.206346) (xy 237.096668 -85.265522) (xy 236.930472 -85.317067)
			(xy 236.762071 -85.36087) (xy 236.591823 -85.396837) (xy 236.420094 -85.424892) (xy 236.247251 -85.444974)
			(xy 236.073665 -85.45704) (xy 235.899706 -85.461065) (xy 235.725747 -85.45704) (xy 235.552161 -85.444974)
			(xy 235.379318 -85.424892) (xy 235.207589 -85.396837) (xy 235.037341 -85.36087) (xy 234.86894 -85.317067)
			(xy 234.702744 -85.265522) (xy 234.53911 -85.206346) (xy 234.378388 -85.139665) (xy 234.220922 -85.065621)
			(xy 234.06705 -84.984374) (xy 233.917099 -84.896097) (xy 233.771393 -84.80098) (xy 233.630241 -84.699225)
			(xy 233.493946 -84.59105) (xy 233.362801 -84.476688) (xy 233.237085 -84.356382) (xy 233.117068 -84.230391)
			(xy 233.003007 -84.098984) (xy 232.895145 -83.962441) (xy 232.793715 -83.821057) (xy 232.698931 -83.675132)
			(xy 232.610999 -83.52498) (xy 232.530105 -83.370921) (xy 232.456423 -83.213286) (xy 232.390111 -83.052411)
			(xy 232.33131 -82.888642) (xy 232.280146 -82.722329) (xy 232.23673 -82.553827) (xy 232.201153 -82.383497)
			(xy 232.173492 -82.211704) (xy 232.153807 -82.038816) (xy 232.142139 -81.865202) (xy 232.138513 -81.691235)
			(xy 230.899389 -81.691235) (xy 230.899216 -81.699862) (xy 230.903219 -81.89993) (xy 230.915225 -82.099677)
			(xy 230.935212 -82.298784) (xy 230.96315 -82.496932) (xy 230.998993 -82.693803) (xy 231.042684 -82.889083)
			(xy 231.094154 -83.082458) (xy 231.153319 -83.273619) (xy 231.220085 -83.46226) (xy 231.294344 -83.648079)
			(xy 231.375979 -83.830778) (xy 231.464859 -84.010064) (xy 231.56084 -84.185651) (xy 231.66377 -84.357257)
			(xy 231.773483 -84.524607) (xy 231.889803 -84.687434) (xy 232.012546 -84.845476) (xy 232.141513 -84.998481)
			(xy 232.276499 -85.146204) (xy 232.417287 -85.288408) (xy 232.563651 -85.424865) (xy 232.715358 -85.555356)
			(xy 232.872165 -85.679674) (xy 233.03382 -85.797618) (xy 233.200064 -85.909) (xy 233.370632 -86.013641)
			(xy 233.545249 -86.111374) (xy 233.723637 -86.202043) (xy 233.90551 -86.285501) (xy 234.090577 -86.361617)
			(xy 234.27854 -86.430266) (xy 234.4691 -86.491341) (xy 234.66195 -86.544742) (xy 234.856783 -86.590385)
			(xy 235.053286 -86.628196) (xy 235.251145 -86.658115) (xy 235.450042 -86.680094) (xy 235.649659 -86.694097)
			(xy 235.849677 -86.700102) (xy 236.049774 -86.6981) (xy 236.249632 -86.688094) (xy 236.448929 -86.670099)
			(xy 236.647346 -86.644146) (xy 236.844566 -86.610274) (xy 237.040273 -86.568539) (xy 237.234154 -86.519007)
			(xy 237.425898 -86.461757) (xy 237.615197 -86.396882) (xy 237.801749 -86.324485) (xy 237.985256 -86.244682)
			(xy 238.165422 -86.157601) (xy 238.341961 -86.063381) (xy 238.514588 -85.962173) (xy 238.683027 -85.85414)
			(xy 238.84701 -85.739454) (xy 239.006272 -85.618299) (xy 239.16056 -85.490869) (xy 239.309626 -85.357368)
			(xy 239.453231 -85.21801) (xy 239.591145 -85.073018) (xy 239.723148 -84.922624) (xy 239.849028 -84.767069)
			(xy 239.968584 -84.606602) (xy 240.081623 -84.441481) (xy 240.187966 -84.271969) (xy 240.287441 -84.098338)
			(xy 240.37989 -83.920866) (xy 240.465164 -83.739837) (xy 240.543127 -83.555541) (xy 240.613654 -83.368274)
			(xy 240.676632 -83.178335) (xy 240.73196 -82.986028) (xy 240.77955 -82.791662) (xy 240.819325 -82.595547)
			(xy 240.851222 -82.397998) (xy 240.87519 -82.19933) (xy 240.891189 -81.999863) (xy 240.899195 -81.799916)
		)
		(stroke
			(width 0)
			(type solid)
		)
		(fill yes)
		(layer "F.Cu")
		(net "GND")
	)
	(gr_poly
		(pts
			(xy 69.811138 -26.891742) (xy 69.811138 -24.874982) (xy 70.428358 -24.257762) (xy 72.861678 -24.257762)
			(xy 73.496678 -23.622762) (xy 73.496678 -17.374362) (xy 74.207878 -16.663162) (xy 77.687678 -16.663162)
			(xy 79.229458 -18.204942) (xy 79.229458 -19.195796) (xy 79.230474 -19.200622) (xy 79.234049 -19.219404)
			(xy 79.237863 -19.25745) (xy 79.238094 -19.276568) (xy 79.23786 -19.295686) (xy 79.234044 -19.333731)
			(xy 79.230474 -19.352514) (xy 79.229458 -19.35734) (xy 79.229458 -21.504402) (xy 79.290418 -21.565362)
			(xy 79.409798 -21.565362) (xy 79.473298 -21.501862) (xy 79.473298 -19.647662) (xy 79.656178 -19.464782)
			(xy 80.054958 -19.464782) (xy 80.232758 -19.642582) (xy 80.232758 -21.006562) (xy 80.288638 -21.062442)
			(xy 80.433418 -21.062442) (xy 80.481678 -21.014182) (xy 80.481678 -19.810222) (xy 80.761078 -19.530822)
			(xy 80.761078 -13.645134) (xy 77.37221 -13.645134) (xy 77.365098 -13.64742) (xy 77.327549 -13.658269)
			(xy 77.250817 -13.673153) (xy 77.211936 -13.677138) (xy 77.194208 -13.71086) (xy 77.152977 -13.774932)
			(xy 77.10556 -13.834571) (xy 77.05243 -13.889182) (xy 76.994118 -13.938221) (xy 76.931205 -13.981199)
			(xy 76.864319 -14.017686) (xy 76.794126 -14.04732) (xy 76.721327 -14.069803) (xy 76.646649 -14.084912)
			(xy 76.570836 -14.092497) (xy 76.53274 -14.092936) (xy 76.494023 -14.092456) (xy 76.416987 -14.084602)
			(xy 76.341145 -14.068981) (xy 76.267276 -14.045753) (xy 76.196141 -14.015158) (xy 76.128474 -13.977512)
			(xy 76.06497 -13.933201) (xy 76.006285 -13.882682) (xy 75.979274 -13.854938) (xy 75.942755 -13.861699)
			(xy 75.868836 -13.868949) (xy 75.8317 -13.869416) (xy 75.795935 -13.86898) (xy 75.724723 -13.862254)
			(xy 75.654451 -13.848899) (xy 75.585736 -13.829032) (xy 75.5523 -13.81633) (xy 75.522888 -13.840305)
			(xy 75.46012 -13.882951) (xy 75.393427 -13.919154) (xy 75.323469 -13.948556) (xy 75.250937 -13.970865)
			(xy 75.176549 -13.985861) (xy 75.101039 -13.993396) (xy 75.063096 -13.993876) (xy 75.027155 -13.993458)
			(xy 74.955593 -13.986693) (xy 74.884984 -13.973233) (xy 74.815952 -13.953196) (xy 74.749108 -13.92676)
			(xy 74.716894 -13.910818) (xy 74.702623 -13.938216) (xy 74.667657 -13.989143) (xy 74.625995 -14.034755)
			(xy 74.578435 -14.074179) (xy 74.525888 -14.10666) (xy 74.46936 -14.131576) (xy 74.409934 -14.14845)
			(xy 74.348748 -14.156959) (xy 74.31786 -14.157452) (xy 74.289578 -14.157026) (xy 74.233465 -14.149903)
			(xy 74.178701 -14.135751) (xy 74.126162 -14.114797) (xy 74.07669 -14.087375) (xy 74.031077 -14.053926)
			(xy 74.010266 -14.03477) (xy 73.999703 -14.025313) (xy 73.974619 -14.012119) (xy 73.946872 -14.006347)
			(xy 73.918608 -14.008443) (xy 73.892015 -14.018245) (xy 73.869152 -14.034993) (xy 73.860152 -14.045946)
			(xy 73.841973 -14.068594) (xy 73.8007 -14.109452) (xy 73.754473 -14.144606) (xy 73.704074 -14.173463)
			(xy 73.650356 -14.195534) (xy 73.594227 -14.210445) (xy 73.536638 -14.217945) (xy 73.5076 -14.218412)
			(xy 73.478396 -14.217955) (xy 73.420489 -14.210331) (xy 73.364071 -14.195214) (xy 73.31011 -14.172862)
			(xy 73.259528 -14.143658) (xy 73.213191 -14.108101) (xy 73.171891 -14.0668) (xy 73.136336 -14.020462)
			(xy 73.107133 -13.969879) (xy 73.084782 -13.915917) (xy 73.069667 -13.8595) (xy 73.062044 -13.801592)
			(xy 73.061576 -13.772388) (xy 73.061576 -13.750544) (xy 73.061018 -13.739895) (xy 73.05237 -13.720431)
			(xy 73.036579 -13.706139) (xy 73.016352 -13.699467) (xy 72.995157 -13.70156) (xy 72.98563 -13.706348)
			(xy 72.960982 -13.71976) (xy 72.908982 -13.740853) (xy 72.854709 -13.755116) (xy 72.799058 -13.762312)
			(xy 72.771 -13.762736) (xy 72.743642 -13.762295) (xy 72.689358 -13.755437) (xy 72.636352 -13.741865)
			(xy 72.585451 -13.721791) (xy 72.537449 -13.695529) (xy 72.493096 -13.663488) (xy 72.472804 -13.645134)
			(xy 70.479666 -13.645134) (xy 67.841114 -11.006582) (xy 67.819778 -11.006836) (xy 67.81546 -11.006836)
			(xy 67.78821 -11.006348) (xy 67.734265 -10.998587) (xy 67.681973 -10.983228) (xy 67.632399 -10.960585)
			(xy 67.586552 -10.931118) (xy 67.545364 -10.895427) (xy 67.509675 -10.854238) (xy 67.480209 -10.80839)
			(xy 67.457568 -10.758815) (xy 67.442211 -10.706523) (xy 67.434452 -10.652578) (xy 67.433952 -10.625328)
			(xy 67.433952 -10.62101) (xy 67.434206 -10.599674) (xy 67.228212 -10.39368) (xy 64.554862 -10.39368)
			(xy 64.5287 -10.394696) (xy 64.502538 -10.39368) (xy 62.931548 -10.39368) (xy 62.69228 -10.632948)
			(xy 62.69228 -11.98245) (xy 63.05804 -11.98245) (xy 63.05804 -10.567162) (xy 63.078868 -10.546588)
			(xy 63.249556 -10.546588) (xy 63.272924 -10.569702) (xy 63.272924 -11.96467) (xy 63.254984 -11.98245)
			(xy 63.657988 -11.98245) (xy 63.657988 -10.567162) (xy 63.678816 -10.546588) (xy 63.849504 -10.546588)
			(xy 63.872872 -10.569702) (xy 63.872872 -11.96467) (xy 63.854932 -11.98245) (xy 64.257936 -11.98245)
			(xy 64.257936 -10.567162) (xy 64.278764 -10.546588) (xy 64.449452 -10.546588) (xy 64.47282 -10.569702)
			(xy 64.47282 -11.96467) (xy 64.45488 -11.98245) (xy 64.858392 -11.98245) (xy 64.858392 -10.567162)
			(xy 64.878966 -10.546588) (xy 65.049654 -10.546588) (xy 65.072768 -10.569702) (xy 65.072768 -11.96467)
			(xy 65.054988 -11.98245) (xy 65.45834 -11.98245) (xy 65.45834 -10.567162) (xy 65.478914 -10.546588)
			(xy 65.649602 -10.546588) (xy 65.672716 -10.569702) (xy 65.672716 -11.96467) (xy 65.644522 -11.992864)
			(xy 65.468754 -11.992864) (xy 65.45834 -11.98245) (xy 65.054988 -11.98245) (xy 65.044574 -11.992864)
			(xy 64.868806 -11.992864) (xy 64.858392 -11.98245) (xy 64.45488 -11.98245) (xy 64.444372 -11.992864)
			(xy 64.268604 -11.992864) (xy 64.257936 -11.98245) (xy 63.854932 -11.98245) (xy 63.844424 -11.992864)
			(xy 63.668656 -11.992864) (xy 63.657988 -11.98245) (xy 63.254984 -11.98245) (xy 63.244476 -11.992864)
			(xy 63.068708 -11.992864) (xy 63.05804 -11.98245) (xy 62.69228 -11.98245) (xy 62.69228 -12.74699)
			(xy 63.448438 -13.503148) (xy 65.99174 -13.503148) (xy 66.32702 -13.838428) (xy 66.32702 -15.285631)
			(xy 72.664322 -15.285631) (xy 72.664322 -15.225865) (xy 72.67246 -15.166655) (xy 72.688585 -15.109105)
			(xy 72.712396 -15.054286) (xy 72.74345 -15.00322) (xy 72.781168 -14.956859) (xy 72.824847 -14.916065)
			(xy 72.873675 -14.881599) (xy 72.926741 -14.854102) (xy 72.983056 -14.834087) (xy 73.041573 -14.821928)
			(xy 73.1012 -14.817849) (xy 73.160827 -14.821928) (xy 73.219344 -14.834087) (xy 73.275659 -14.854102)
			(xy 73.328725 -14.881599) (xy 73.377553 -14.916065) (xy 73.421232 -14.956859) (xy 73.45895 -15.00322)
			(xy 73.490004 -15.054286) (xy 73.513815 -15.109105) (xy 73.52994 -15.166655) (xy 73.538078 -15.225865)
			(xy 73.538588 -15.255748) (xy 73.538078 -15.285631) (xy 73.52994 -15.344841) (xy 73.513815 -15.402391)
			(xy 73.490004 -15.45721) (xy 73.45895 -15.508276) (xy 73.421232 -15.554637) (xy 73.377553 -15.595431)
			(xy 73.328725 -15.629897) (xy 73.275659 -15.657394) (xy 73.219344 -15.677409) (xy 73.160827 -15.689568)
			(xy 73.1012 -15.693647) (xy 73.041573 -15.689568) (xy 72.983056 -15.677409) (xy 72.926741 -15.657394)
			(xy 72.873675 -15.629897) (xy 72.824847 -15.595431) (xy 72.781168 -15.554637) (xy 72.74345 -15.508276)
			(xy 72.712396 -15.45721) (xy 72.688585 -15.402391) (xy 72.67246 -15.344841) (xy 72.664322 -15.285631)
			(xy 66.32702 -15.285631) (xy 66.32702 -16.955008) (xy 66.04508 -17.236948) (xy 66.04508 -21.021548)
			(xy 66.09588 -21.072348) (xy 66.09588 -21.83638) (xy 66.041778 -21.890482) (xy 66.041778 -26.894282)
			(xy 66.049398 -26.901902) (xy 69.800978 -26.901902)
		)
		(stroke
			(width 0)
			(type solid)
		)
		(fill yes)
		(layer "F.Cu")
		(net "P12V_OCP_V3_2")
	)
	(gr_poly
		(pts
			(xy 209.64525 -51.999896) (xy 209.644749 -51.899842) (xy 209.636743 -51.699895) (xy 209.620744 -51.500428)
			(xy 209.596776 -51.30176) (xy 209.564879 -51.104211) (xy 209.525104 -50.908096) (xy 209.477514 -50.71373)
			(xy 209.422186 -50.521423) (xy 209.359208 -50.331484) (xy 209.288681 -50.144217) (xy 209.210718 -49.959921)
			(xy 209.125444 -49.778892) (xy 209.032995 -49.60142) (xy 208.93352 -49.427789) (xy 208.827177 -49.258277)
			(xy 208.714138 -49.093156) (xy 208.594582 -48.932689) (xy 208.468702 -48.777134) (xy 208.336699 -48.62674)
			(xy 208.198785 -48.481748) (xy 208.05518 -48.34239) (xy 207.906114 -48.208889) (xy 207.751826 -48.081459)
			(xy 207.592564 -47.960304) (xy 207.428581 -47.845618) (xy 207.260142 -47.737585) (xy 207.087515 -47.636377)
			(xy 206.910976 -47.542157) (xy 206.73081 -47.455076) (xy 206.547303 -47.375273) (xy 206.360751 -47.302876)
			(xy 206.171452 -47.238001) (xy 205.979708 -47.180751) (xy 205.785827 -47.131219) (xy 205.59012 -47.089484)
			(xy 205.3929 -47.055612) (xy 205.194483 -47.029659) (xy 204.995186 -47.011664) (xy 204.795328 -47.001658)
			(xy 204.595231 -46.999656) (xy 204.395213 -47.005661) (xy 204.195596 -47.019664) (xy 203.996699 -47.041643)
			(xy 203.79884 -47.071562) (xy 203.602337 -47.109373) (xy 203.407504 -47.155016) (xy 203.214654 -47.208417)
			(xy 203.024094 -47.269492) (xy 202.836131 -47.338141) (xy 202.651064 -47.414257) (xy 202.469191 -47.497715)
			(xy 202.290803 -47.588384) (xy 202.116186 -47.686117) (xy 201.945618 -47.790758) (xy 201.779374 -47.90214)
			(xy 201.617719 -48.020084) (xy 201.460912 -48.144402) (xy 201.309205 -48.274893) (xy 201.162841 -48.41135)
			(xy 201.022053 -48.553554) (xy 200.887067 -48.701277) (xy 200.7581 -48.854282) (xy 200.635357 -49.012324)
			(xy 200.519037 -49.175151) (xy 200.409324 -49.342501) (xy 200.306394 -49.514107) (xy 200.210413 -49.689694)
			(xy 200.121533 -49.86898) (xy 200.039898 -50.051679) (xy 199.965639 -50.237498) (xy 199.898873 -50.426139)
			(xy 199.839708 -50.6173) (xy 199.788238 -50.810675) (xy 199.744547 -51.005955) (xy 199.708704 -51.202826)
			(xy 199.680766 -51.400974) (xy 199.660779 -51.600081) (xy 199.648773 -51.799828) (xy 199.64477 -51.999896)
			(xy 201.365618 -51.999896) (xy 201.369631 -51.837706) (xy 201.38166 -51.675912) (xy 201.401675 -51.514911)
			(xy 201.429628 -51.355097) (xy 201.465451 -51.196861) (xy 201.509055 -51.04059) (xy 201.560333 -50.886667)
			(xy 201.619161 -50.735468) (xy 201.685395 -50.587364) (xy 201.758871 -50.442716) (xy 201.839411 -50.301878)
			(xy 201.926818 -50.165196) (xy 202.020877 -50.033004) (xy 202.121358 -49.905625) (xy 202.228016 -49.783371)
			(xy 202.340589 -49.666542) (xy 202.458802 -49.555422) (xy 202.582365 -49.450285) (xy 202.710977 -49.351387)
			(xy 202.844323 -49.25897) (xy 202.982075 -49.173261) (xy 203.123898 -49.094468) (xy 203.269444 -49.022786)
			(xy 203.418356 -48.95839) (xy 203.570271 -48.901437) (xy 203.724817 -48.852066) (xy 203.881615 -48.810398)
			(xy 204.040282 -48.776535) (xy 204.200429 -48.750561) (xy 204.361665 -48.732538) (xy 204.523595 -48.722511)
			(xy 204.685823 -48.720505) (xy 204.847952 -48.726523) (xy 205.009584 -48.740553) (xy 205.170325 -48.762558)
			(xy 205.329781 -48.792485) (xy 205.487562 -48.830262) (xy 205.643281 -48.875795) (xy 205.796558 -48.928974)
			(xy 205.947018 -48.989667) (xy 206.094293 -49.057727) (xy 206.238021 -49.132987) (xy 206.377851 -49.215263)
			(xy 206.513442 -49.304354) (xy 206.64446 -49.40004) (xy 206.770587 -49.502089) (xy 206.891512 -49.610251)
			(xy 207.00694 -49.72426) (xy 207.116589 -49.843839) (xy 207.22019 -49.968693) (xy 207.31749 -50.098518)
			(xy 207.408251 -50.232997) (xy 207.49225 -50.371799) (xy 207.569282 -50.514585) (xy 207.639158 -50.661006)
			(xy 207.701708 -50.810704) (xy 207.756778 -50.963312) (xy 207.804234 -51.118456) (xy 207.843959 -51.275758)
			(xy 207.875856 -51.434831) (xy 207.899848 -51.595288) (xy 207.915875 -51.756734) (xy 207.923899 -51.918776)
			(xy 207.9244 -51.999896) (xy 207.923899 -52.081016) (xy 207.915875 -52.243058) (xy 207.899848 -52.404504)
			(xy 207.875856 -52.564961) (xy 207.843959 -52.724034) (xy 207.804234 -52.881336) (xy 207.756778 -53.03648)
			(xy 207.701708 -53.189088) (xy 207.639158 -53.338786) (xy 207.569282 -53.485207) (xy 207.49225 -53.627993)
			(xy 207.408251 -53.766795) (xy 207.31749 -53.901274) (xy 207.22019 -54.031099) (xy 207.116589 -54.155953)
			(xy 207.00694 -54.275532) (xy 206.891512 -54.389541) (xy 206.770587 -54.497703) (xy 206.64446 -54.599752)
			(xy 206.513442 -54.695438) (xy 206.377851 -54.784529) (xy 206.238021 -54.866805) (xy 206.094293 -54.942065)
			(xy 205.947018 -55.010125) (xy 205.796558 -55.070818) (xy 205.643281 -55.123997) (xy 205.487562 -55.16953)
			(xy 205.329781 -55.207307) (xy 205.170325 -55.237234) (xy 205.009584 -55.259239) (xy 204.847952 -55.273269)
			(xy 204.685823 -55.279287) (xy 204.523595 -55.277281) (xy 204.361665 -55.267254) (xy 204.200429 -55.249231)
			(xy 204.040282 -55.223257) (xy 203.881615 -55.189394) (xy 203.724817 -55.147726) (xy 203.570271 -55.098355)
			(xy 203.418356 -55.041402) (xy 203.269444 -54.977006) (xy 203.123898 -54.905324) (xy 202.982075 -54.826531)
			(xy 202.844323 -54.740822) (xy 202.710977 -54.648405) (xy 202.582365 -54.549507) (xy 202.458802 -54.44437)
			(xy 202.340589 -54.33325) (xy 202.228016 -54.216421) (xy 202.121358 -54.094167) (xy 202.020877 -53.966788)
			(xy 201.926818 -53.834596) (xy 201.839411 -53.697914) (xy 201.758871 -53.557076) (xy 201.685395 -53.412428)
			(xy 201.619161 -53.264324) (xy 201.560333 -53.113125) (xy 201.509055 -52.959202) (xy 201.465451 -52.802931)
			(xy 201.429628 -52.644695) (xy 201.401675 -52.484881) (xy 201.38166 -52.32388) (xy 201.369631 -52.162086)
			(xy 201.365618 -51.999896) (xy 199.64477 -51.999896) (xy 199.648773 -52.199964) (xy 199.660779 -52.399711)
			(xy 199.680766 -52.598818) (xy 199.708704 -52.796966) (xy 199.744547 -52.993837) (xy 199.788238 -53.189117)
			(xy 199.839708 -53.382492) (xy 199.898873 -53.573653) (xy 199.965639 -53.762294) (xy 200.039898 -53.948113)
			(xy 200.121533 -54.130812) (xy 200.210413 -54.310098) (xy 200.306394 -54.485685) (xy 200.409324 -54.657291)
			(xy 200.519037 -54.824641) (xy 200.635357 -54.987468) (xy 200.7581 -55.14551) (xy 200.887067 -55.298515)
			(xy 201.022053 -55.446238) (xy 201.162841 -55.588442) (xy 201.309205 -55.724899) (xy 201.460912 -55.85539)
			(xy 201.617719 -55.979708) (xy 201.779374 -56.097652) (xy 201.945618 -56.209034) (xy 202.116186 -56.313675)
			(xy 202.290803 -56.411408) (xy 202.469191 -56.502077) (xy 202.651064 -56.585535) (xy 202.836131 -56.661651)
			(xy 203.024094 -56.7303) (xy 203.214654 -56.791375) (xy 203.407504 -56.844776) (xy 203.602337 -56.890419)
			(xy 203.79884 -56.92823) (xy 203.996699 -56.958149) (xy 204.195596 -56.980128) (xy 204.395213 -56.994131)
			(xy 204.595231 -57.000136) (xy 204.795328 -56.998134) (xy 204.995186 -56.988128) (xy 205.194483 -56.970133)
			(xy 205.3929 -56.94418) (xy 205.59012 -56.910308) (xy 205.785827 -56.868573) (xy 205.979708 -56.819041)
			(xy 206.171452 -56.761791) (xy 206.360751 -56.696916) (xy 206.547303 -56.624519) (xy 206.73081 -56.544716)
			(xy 206.910976 -56.457635) (xy 207.087515 -56.363415) (xy 207.260142 -56.262207) (xy 207.428581 -56.154174)
			(xy 207.592564 -56.039488) (xy 207.751826 -55.918333) (xy 207.906114 -55.790903) (xy 208.05518 -55.657402)
			(xy 208.198785 -55.518044) (xy 208.336699 -55.373052) (xy 208.468702 -55.222658) (xy 208.594582 -55.067103)
			(xy 208.714138 -54.906636) (xy 208.827177 -54.741515) (xy 208.93352 -54.572003) (xy 209.032995 -54.398372)
			(xy 209.125444 -54.2209) (xy 209.210718 -54.039871) (xy 209.288681 -53.855575) (xy 209.359208 -53.668308)
			(xy 209.422186 -53.478369) (xy 209.477514 -53.286062) (xy 209.525104 -53.091696) (xy 209.564879 -52.895581)
			(xy 209.596776 -52.698032) (xy 209.620744 -52.499364) (xy 209.636743 -52.299897) (xy 209.644749 -52.09995)
		)
		(stroke
			(width 0)
			(type solid)
		)
		(fill yes)
		(layer "F.Cu")
		(net "GND")
	)
	(gr_poly
		(pts
			(xy 273.645122 -51.999896) (xy 273.644621 -51.899842) (xy 273.636615 -51.699895) (xy 273.620616 -51.500428)
			(xy 273.596648 -51.30176) (xy 273.564751 -51.104211) (xy 273.524976 -50.908096) (xy 273.477386 -50.71373)
			(xy 273.422058 -50.521423) (xy 273.35908 -50.331484) (xy 273.288553 -50.144217) (xy 273.21059 -49.959921)
			(xy 273.125316 -49.778892) (xy 273.032867 -49.60142) (xy 272.933392 -49.427789) (xy 272.827049 -49.258277)
			(xy 272.71401 -49.093156) (xy 272.594454 -48.932689) (xy 272.468574 -48.777134) (xy 272.336571 -48.62674)
			(xy 272.198657 -48.481748) (xy 272.055052 -48.34239) (xy 271.905986 -48.208889) (xy 271.751698 -48.081459)
			(xy 271.592436 -47.960304) (xy 271.428453 -47.845618) (xy 271.260014 -47.737585) (xy 271.087387 -47.636377)
			(xy 270.910848 -47.542157) (xy 270.730682 -47.455076) (xy 270.547175 -47.375273) (xy 270.360623 -47.302876)
			(xy 270.171324 -47.238001) (xy 269.97958 -47.180751) (xy 269.785699 -47.131219) (xy 269.589992 -47.089484)
			(xy 269.392772 -47.055612) (xy 269.194355 -47.029659) (xy 268.995058 -47.011664) (xy 268.7952 -47.001658)
			(xy 268.595103 -46.999656) (xy 268.395085 -47.005661) (xy 268.195468 -47.019664) (xy 267.996571 -47.041643)
			(xy 267.798712 -47.071562) (xy 267.602209 -47.109373) (xy 267.407376 -47.155016) (xy 267.214526 -47.208417)
			(xy 267.023966 -47.269492) (xy 266.836003 -47.338141) (xy 266.650936 -47.414257) (xy 266.469063 -47.497715)
			(xy 266.290675 -47.588384) (xy 266.116058 -47.686117) (xy 265.94549 -47.790758) (xy 265.779246 -47.90214)
			(xy 265.617591 -48.020084) (xy 265.460784 -48.144402) (xy 265.309077 -48.274893) (xy 265.162713 -48.41135)
			(xy 265.021925 -48.553554) (xy 264.886939 -48.701277) (xy 264.757972 -48.854282) (xy 264.635229 -49.012324)
			(xy 264.518909 -49.175151) (xy 264.409196 -49.342501) (xy 264.306266 -49.514107) (xy 264.210285 -49.689694)
			(xy 264.121405 -49.86898) (xy 264.03977 -50.051679) (xy 263.965511 -50.237498) (xy 263.898745 -50.426139)
			(xy 263.83958 -50.6173) (xy 263.78811 -50.810675) (xy 263.744419 -51.005955) (xy 263.708576 -51.202826)
			(xy 263.680638 -51.400974) (xy 263.660651 -51.600081) (xy 263.648645 -51.799828) (xy 263.644642 -51.999896)
			(xy 265.36549 -51.999896) (xy 265.369503 -51.837706) (xy 265.381532 -51.675912) (xy 265.401547 -51.514911)
			(xy 265.4295 -51.355097) (xy 265.465323 -51.196861) (xy 265.508927 -51.04059) (xy 265.560205 -50.886667)
			(xy 265.619033 -50.735468) (xy 265.685267 -50.587364) (xy 265.758743 -50.442716) (xy 265.839283 -50.301878)
			(xy 265.92669 -50.165196) (xy 266.020749 -50.033004) (xy 266.12123 -49.905625) (xy 266.227888 -49.783371)
			(xy 266.340461 -49.666542) (xy 266.458674 -49.555422) (xy 266.582237 -49.450285) (xy 266.710849 -49.351387)
			(xy 266.844195 -49.25897) (xy 266.981947 -49.173261) (xy 267.12377 -49.094468) (xy 267.269316 -49.022786)
			(xy 267.418228 -48.95839) (xy 267.570143 -48.901437) (xy 267.724689 -48.852066) (xy 267.881487 -48.810398)
			(xy 268.040154 -48.776535) (xy 268.200301 -48.750561) (xy 268.361537 -48.732538) (xy 268.523467 -48.722511)
			(xy 268.685695 -48.720505) (xy 268.847824 -48.726523) (xy 269.009456 -48.740553) (xy 269.170197 -48.762558)
			(xy 269.329653 -48.792485) (xy 269.487434 -48.830262) (xy 269.643153 -48.875795) (xy 269.79643 -48.928974)
			(xy 269.94689 -48.989667) (xy 270.094165 -49.057727) (xy 270.237893 -49.132987) (xy 270.377723 -49.215263)
			(xy 270.513314 -49.304354) (xy 270.644332 -49.40004) (xy 270.770459 -49.502089) (xy 270.891384 -49.610251)
			(xy 271.006812 -49.72426) (xy 271.116461 -49.843839) (xy 271.220062 -49.968693) (xy 271.317362 -50.098518)
			(xy 271.408123 -50.232997) (xy 271.492122 -50.371799) (xy 271.569154 -50.514585) (xy 271.63903 -50.661006)
			(xy 271.70158 -50.810704) (xy 271.75665 -50.963312) (xy 271.804106 -51.118456) (xy 271.843831 -51.275758)
			(xy 271.875728 -51.434831) (xy 271.89972 -51.595288) (xy 271.915747 -51.756734) (xy 271.923771 -51.918776)
			(xy 271.924272 -51.999896) (xy 271.923771 -52.081016) (xy 271.915747 -52.243058) (xy 271.89972 -52.404504)
			(xy 271.875728 -52.564961) (xy 271.843831 -52.724034) (xy 271.804106 -52.881336) (xy 271.75665 -53.03648)
			(xy 271.70158 -53.189088) (xy 271.63903 -53.338786) (xy 271.569154 -53.485207) (xy 271.492122 -53.627993)
			(xy 271.408123 -53.766795) (xy 271.317362 -53.901274) (xy 271.220062 -54.031099) (xy 271.116461 -54.155953)
			(xy 271.006812 -54.275532) (xy 270.891384 -54.389541) (xy 270.770459 -54.497703) (xy 270.644332 -54.599752)
			(xy 270.513314 -54.695438) (xy 270.377723 -54.784529) (xy 270.237893 -54.866805) (xy 270.094165 -54.942065)
			(xy 269.94689 -55.010125) (xy 269.79643 -55.070818) (xy 269.643153 -55.123997) (xy 269.487434 -55.16953)
			(xy 269.329653 -55.207307) (xy 269.170197 -55.237234) (xy 269.009456 -55.259239) (xy 268.847824 -55.273269)
			(xy 268.685695 -55.279287) (xy 268.523467 -55.277281) (xy 268.361537 -55.267254) (xy 268.200301 -55.249231)
			(xy 268.040154 -55.223257) (xy 267.881487 -55.189394) (xy 267.724689 -55.147726) (xy 267.570143 -55.098355)
			(xy 267.418228 -55.041402) (xy 267.269316 -54.977006) (xy 267.12377 -54.905324) (xy 266.981947 -54.826531)
			(xy 266.844195 -54.740822) (xy 266.710849 -54.648405) (xy 266.582237 -54.549507) (xy 266.458674 -54.44437)
			(xy 266.340461 -54.33325) (xy 266.227888 -54.216421) (xy 266.12123 -54.094167) (xy 266.020749 -53.966788)
			(xy 265.92669 -53.834596) (xy 265.839283 -53.697914) (xy 265.758743 -53.557076) (xy 265.685267 -53.412428)
			(xy 265.619033 -53.264324) (xy 265.560205 -53.113125) (xy 265.508927 -52.959202) (xy 265.465323 -52.802931)
			(xy 265.4295 -52.644695) (xy 265.401547 -52.484881) (xy 265.381532 -52.32388) (xy 265.369503 -52.162086)
			(xy 265.36549 -51.999896) (xy 263.644642 -51.999896) (xy 263.648645 -52.199964) (xy 263.660651 -52.399711)
			(xy 263.680638 -52.598818) (xy 263.708576 -52.796966) (xy 263.744419 -52.993837) (xy 263.78811 -53.189117)
			(xy 263.83958 -53.382492) (xy 263.898745 -53.573653) (xy 263.965511 -53.762294) (xy 264.03977 -53.948113)
			(xy 264.121405 -54.130812) (xy 264.210285 -54.310098) (xy 264.306266 -54.485685) (xy 264.409196 -54.657291)
			(xy 264.518909 -54.824641) (xy 264.635229 -54.987468) (xy 264.757972 -55.14551) (xy 264.886939 -55.298515)
			(xy 265.021925 -55.446238) (xy 265.162713 -55.588442) (xy 265.309077 -55.724899) (xy 265.460784 -55.85539)
			(xy 265.617591 -55.979708) (xy 265.779246 -56.097652) (xy 265.94549 -56.209034) (xy 266.116058 -56.313675)
			(xy 266.290675 -56.411408) (xy 266.469063 -56.502077) (xy 266.650936 -56.585535) (xy 266.836003 -56.661651)
			(xy 267.023966 -56.7303) (xy 267.214526 -56.791375) (xy 267.407376 -56.844776) (xy 267.602209 -56.890419)
			(xy 267.798712 -56.92823) (xy 267.996571 -56.958149) (xy 268.195468 -56.980128) (xy 268.395085 -56.994131)
			(xy 268.595103 -57.000136) (xy 268.7952 -56.998134) (xy 268.995058 -56.988128) (xy 269.194355 -56.970133)
			(xy 269.392772 -56.94418) (xy 269.589992 -56.910308) (xy 269.785699 -56.868573) (xy 269.97958 -56.819041)
			(xy 270.171324 -56.761791) (xy 270.360623 -56.696916) (xy 270.547175 -56.624519) (xy 270.730682 -56.544716)
			(xy 270.910848 -56.457635) (xy 271.087387 -56.363415) (xy 271.260014 -56.262207) (xy 271.428453 -56.154174)
			(xy 271.592436 -56.039488) (xy 271.751698 -55.918333) (xy 271.905986 -55.790903) (xy 272.055052 -55.657402)
			(xy 272.198657 -55.518044) (xy 272.336571 -55.373052) (xy 272.468574 -55.222658) (xy 272.594454 -55.067103)
			(xy 272.71401 -54.906636) (xy 272.827049 -54.741515) (xy 272.933392 -54.572003) (xy 273.032867 -54.398372)
			(xy 273.125316 -54.2209) (xy 273.21059 -54.039871) (xy 273.288553 -53.855575) (xy 273.35908 -53.668308)
			(xy 273.422058 -53.478369) (xy 273.477386 -53.286062) (xy 273.524976 -53.091696) (xy 273.564751 -52.895581)
			(xy 273.596648 -52.698032) (xy 273.620616 -52.499364) (xy 273.636615 -52.299897) (xy 273.644621 -52.09995)
		)
		(stroke
			(width 0)
			(type solid)
		)
		(fill yes)
		(layer "F.Cu")
		(net "GND")
	)
	(gr_poly
		(pts
			(xy 54.333394 -365.829596) (xy 54.333394 -363.910626) (xy 54.825138 -363.418882) (xy 56.150764 -363.418882)
			(xy 56.338978 -363.230668) (xy 56.338978 -353.887278) (xy 56.217058 -353.765358) (xy 51.683666 -353.765358)
			(xy 51.661822 -353.76739) (xy 51.648614 -353.781614) (xy 51.61407 -353.816158) (xy 51.61407 -355.89083)
			(xy 51.62027 -355.894463) (xy 51.634066 -355.898458) (xy 51.641248 -355.898704) (xy 52.957476 -355.898704)
			(xy 52.96754 -355.899141) (xy 52.986124 -355.906875) (xy 52.993544 -355.91369) (xy 53.131212 -356.051358)
			(xy 53.138059 -356.058755) (xy 53.145786 -356.077355) (xy 53.146198 -356.087426) (xy 53.146198 -356.107746)
			(xy 55.435246 -356.107746) (xy 55.435703 -356.081367) (xy 55.442961 -356.029112) (xy 55.457347 -355.978353)
			(xy 55.478585 -355.930059) (xy 55.50627 -355.88515) (xy 55.539877 -355.844481) (xy 55.578763 -355.808828)
			(xy 55.622189 -355.778869) (xy 55.645558 -355.766624) (xy 55.657968 -355.759986) (xy 55.678726 -355.74099)
			(xy 55.693518 -355.717053) (xy 55.701223 -355.689991) (xy 55.701257 -355.661852) (xy 55.693617 -355.634771)
			(xy 55.678882 -355.6108) (xy 55.65817 -355.591754) (xy 55.645812 -355.585014) (xy 55.622446 -355.57279)
			(xy 55.57902 -355.542873) (xy 55.540131 -355.507257) (xy 55.506521 -355.466622) (xy 55.478831 -355.421744)
			(xy 55.457589 -355.373477) (xy 55.443202 -355.322744) (xy 55.435942 -355.270513) (xy 55.4355 -355.244146)
			(xy 55.435986 -355.216895) (xy 55.443742 -355.162947) (xy 55.459097 -355.110652) (xy 55.481739 -355.061075)
			(xy 55.511205 -355.015225) (xy 55.546896 -354.974034) (xy 55.588087 -354.938343) (xy 55.633937 -354.908877)
			(xy 55.683514 -354.886235) (xy 55.735809 -354.87088) (xy 55.789757 -354.863124) (xy 55.844259 -354.863124)
			(xy 55.898207 -354.87088) (xy 55.950502 -354.886235) (xy 56.000079 -354.908877) (xy 56.045929 -354.938343)
			(xy 56.08712 -354.974034) (xy 56.122811 -355.015225) (xy 56.152277 -355.061075) (xy 56.174919 -355.110652)
			(xy 56.190274 -355.162947) (xy 56.19803 -355.216895) (xy 56.198516 -355.244146) (xy 56.198068 -355.27051)
			(xy 56.190788 -355.322735) (xy 56.176388 -355.373459) (xy 56.155142 -355.421719) (xy 56.127454 -355.466593)
			(xy 56.093851 -355.507229) (xy 56.054974 -355.542851) (xy 56.011564 -355.572782) (xy 55.988204 -355.585014)
			(xy 55.975871 -355.591804) (xy 55.955132 -355.610819) (xy 55.940375 -355.634776) (xy 55.932723 -355.661853)
			(xy 55.932756 -355.68999) (xy 55.940474 -355.717048) (xy 55.955288 -355.74097) (xy 55.976073 -355.759935)
			(xy 55.988458 -355.766624) (xy 56.011819 -355.778882) (xy 56.05524 -355.808844) (xy 56.094124 -355.844498)
			(xy 56.127729 -355.885166) (xy 56.155417 -355.930072) (xy 56.176659 -355.978362) (xy 56.191052 -356.029116)
			(xy 56.198321 -356.081368) (xy 56.19877 -356.107746) (xy 56.198284 -356.135015) (xy 56.190522 -356.188999)
			(xy 56.175157 -356.241329) (xy 56.1525 -356.290939) (xy 56.123014 -356.33682) (xy 56.087299 -356.378037)
			(xy 56.046082 -356.413752) (xy 56.000201 -356.443238) (xy 55.950591 -356.465895) (xy 55.898261 -356.48126)
			(xy 55.844277 -356.489022) (xy 55.789739 -356.489022) (xy 55.735755 -356.48126) (xy 55.683425 -356.465895)
			(xy 55.633815 -356.443238) (xy 55.587934 -356.413752) (xy 55.546717 -356.378037) (xy 55.511002 -356.33682)
			(xy 55.481516 -356.290939) (xy 55.458859 -356.241329) (xy 55.443494 -356.188999) (xy 55.435732 -356.135015)
			(xy 55.435246 -356.107746) (xy 53.146198 -356.107746) (xy 53.146198 -356.71887) (xy 53.154834 -356.739698)
			(xy 53.156609 -356.744326) (xy 53.158529 -356.754047) (xy 53.158644 -356.759002) (xy 53.158644 -356.996746)
			(xy 55.434736 -356.996746) (xy 55.438809 -356.941087) (xy 55.450944 -356.886614) (xy 55.47088 -356.834488)
			(xy 55.498194 -356.78582) (xy 55.532302 -356.741648) (xy 55.572479 -356.702913) (xy 55.617867 -356.670441)
			(xy 55.667499 -356.644923) (xy 55.720319 -356.626904) (xy 55.775198 -356.616767) (xy 55.830969 -356.614729)
			(xy 55.886443 -356.620832) (xy 55.940436 -356.634948) (xy 55.991799 -356.656775) (xy 56.039437 -356.685848)
			(xy 56.082333 -356.721547) (xy 56.119575 -356.763111) (xy 56.150369 -356.809655) (xy 56.174057 -356.860186)
			(xy 56.190135 -356.913628) (xy 56.198261 -356.968842) (xy 56.19877 -356.996746) (xy 56.198261 -357.02465)
			(xy 56.190135 -357.079864) (xy 56.174057 -357.133306) (xy 56.150369 -357.183837) (xy 56.119575 -357.230381)
			(xy 56.082333 -357.271945) (xy 56.039437 -357.307644) (xy 55.991799 -357.336717) (xy 55.940436 -357.358544)
			(xy 55.886443 -357.37266) (xy 55.830969 -357.378763) (xy 55.775198 -357.376725) (xy 55.720319 -357.366588)
			(xy 55.667499 -357.348569) (xy 55.617867 -357.323051) (xy 55.572479 -357.290579) (xy 55.532302 -357.251844)
			(xy 55.498194 -357.207672) (xy 55.47088 -357.159004) (xy 55.450944 -357.106878) (xy 55.438809 -357.052405)
			(xy 55.434736 -356.996746) (xy 53.158644 -356.996746) (xy 53.158644 -359.232962) (xy 53.158208 -359.243026)
			(xy 53.150472 -359.261609) (xy 53.143658 -359.26903) (xy 52.744624 -359.668064) (xy 52.737223 -359.674902)
			(xy 52.718624 -359.682615) (xy 52.708556 -359.68305) (xy 46.725586 -359.68305) (xy 46.715518 -359.682623)
			(xy 46.696922 -359.674899) (xy 46.689518 -359.668064) (xy 45.953934 -358.93248) (xy 45.947087 -358.925082)
			(xy 45.939354 -358.906484) (xy 45.938948 -358.896412) (xy 45.938948 -356.418642) (xy 45.939383 -356.408578)
			(xy 45.947118 -356.389993) (xy 45.953934 -356.382574) (xy 46.424342 -355.912166) (xy 46.439074 -355.89718)
			(xy 46.439074 -353.816158) (xy 46.388274 -353.765358) (xy 41.918128 -353.765358) (xy 41.918128 -355.836982)
			(xy 41.96334 -355.882194) (xy 41.978326 -355.896926) (xy 43.314874 -355.896926) (xy 43.324938 -355.897363)
			(xy 43.34352 -355.905099) (xy 43.350942 -355.911912) (xy 43.452288 -356.013258) (xy 43.459127 -356.020659)
			(xy 43.466842 -356.039257) (xy 43.467274 -356.049326) (xy 43.467274 -356.14483) (xy 43.467528 -356.14737)
			(xy 43.467528 -356.747826) (xy 43.465496 -356.775258) (xy 43.46194 -356.800404) (xy 43.836844 -357.175562)
			(xy 43.843687 -357.182961) (xy 43.851408 -357.20156) (xy 43.85183 -357.21163) (xy 43.85183 -363.270984)
			(xy 51.221382 -363.270984) (xy 51.221382 -363.186288) (xy 51.229433 -363.101974) (xy 51.245462 -363.018808)
			(xy 51.269323 -362.937541) (xy 51.300802 -362.858911) (xy 51.339613 -362.78363) (xy 51.385403 -362.712378)
			(xy 51.437759 -362.645802) (xy 51.496207 -362.584504) (xy 51.560217 -362.529039) (xy 51.629209 -362.47991)
			(xy 51.702559 -362.437561) (xy 51.779602 -362.402377) (xy 51.859641 -362.374675) (xy 51.94195 -362.354707)
			(xy 52.025785 -362.342654) (xy 52.110386 -362.338624) (xy 52.194987 -362.342654) (xy 52.278822 -362.354707)
			(xy 52.361131 -362.374675) (xy 52.44117 -362.402377) (xy 52.518213 -362.437561) (xy 52.591563 -362.47991)
			(xy 52.660555 -362.529039) (xy 52.724565 -362.584504) (xy 52.783013 -362.645802) (xy 52.835369 -362.712378)
			(xy 52.881159 -362.78363) (xy 52.91997 -362.858911) (xy 52.951449 -362.937541) (xy 52.97531 -363.018808)
			(xy 52.991339 -363.101974) (xy 52.99939 -363.186288) (xy 52.999894 -363.228636) (xy 52.99939 -363.270984)
			(xy 52.991339 -363.355298) (xy 52.97531 -363.438464) (xy 52.951449 -363.519731) (xy 52.91997 -363.598361)
			(xy 52.881159 -363.673642) (xy 52.835369 -363.744894) (xy 52.783013 -363.81147) (xy 52.724565 -363.872768)
			(xy 52.660555 -363.928233) (xy 52.591563 -363.977362) (xy 52.518213 -364.019711) (xy 52.44117 -364.054895)
			(xy 52.361131 -364.082597) (xy 52.278822 -364.102565) (xy 52.194987 -364.114618) (xy 52.110386 -364.118649)
			(xy 52.025785 -364.114618) (xy 51.94195 -364.102565) (xy 51.859641 -364.082597) (xy 51.779602 -364.054895)
			(xy 51.702559 -364.019711) (xy 51.629209 -363.977362) (xy 51.560217 -363.928233) (xy 51.496207 -363.872768)
			(xy 51.437759 -363.81147) (xy 51.385403 -363.744894) (xy 51.339613 -363.673642) (xy 51.300802 -363.598361)
			(xy 51.269323 -363.519731) (xy 51.245462 -363.438464) (xy 51.229433 -363.355298) (xy 51.221382 -363.270984)
			(xy 43.85183 -363.270984) (xy 43.85183 -365.938562) (xy 44.086526 -366.173258) (xy 44.101512 -366.18799)
			(xy 53.975 -366.18799)
		)
		(stroke
			(width 0)
			(type solid)
		)
		(fill yes)
		(layer "F.Cu")
		(net "SW_P12V_PVCCFA_EHV_FIVRA_CPU1_L")
	)
	(gr_poly
		(pts
			(xy 444.491872 -27.177238) (xy 444.491872 -25.160478) (xy 445.109092 -24.543258) (xy 445.18834 -24.543258)
			(xy 445.70523 -24.026368) (xy 445.77 -24.026368) (xy 445.8589 -23.937468) (xy 445.8589 -17.150588)
			(xy 446.06083 -16.948658) (xy 450.6976 -16.948658) (xy 450.6976 -16.955008) (xy 451.38594 -17.643348)
			(xy 451.38594 -21.783548) (xy 451.44182 -21.839428) (xy 451.55866 -21.839428) (xy 451.60692 -21.791168)
			(xy 451.60692 -20.000468) (xy 451.72122 -19.886168) (xy 452.247 -19.886168) (xy 452.3867 -20.025868)
			(xy 452.3867 -21.285708) (xy 452.44258 -21.341588) (xy 452.5518 -21.341588) (xy 452.624444 -21.268944)
			(xy 452.624444 -21.054568) (xy 452.628 -21.051266) (xy 452.628 -18.590768) (xy 454.27011 -16.948658)
			(xy 455.262742 -16.948658) (xy 455.441812 -16.769588) (xy 455.441812 -14.13764) (xy 455.23404 -13.929868)
			(xy 452.941436 -13.929868) (xy 452.929244 -13.963396) (xy 452.919435 -13.989045) (xy 452.893507 -14.037453)
			(xy 452.860906 -14.081643) (xy 452.822306 -14.120702) (xy 452.778505 -14.153823) (xy 452.730408 -14.180321)
			(xy 452.679008 -14.19965) (xy 452.625368 -14.211409) (xy 452.570596 -14.215356) (xy 452.515824 -14.211409)
			(xy 452.462184 -14.19965) (xy 452.410784 -14.180321) (xy 452.362687 -14.153823) (xy 452.318886 -14.120702)
			(xy 452.280286 -14.081643) (xy 452.247685 -14.037453) (xy 452.221757 -13.989045) (xy 452.211948 -13.963396)
			(xy 452.199756 -13.929868) (xy 451.97395 -13.929868) (xy 451.9568 -13.9651) (xy 451.916309 -14.032189)
			(xy 451.869147 -14.094769) (xy 451.815812 -14.152179) (xy 451.756867 -14.203812) (xy 451.692935 -14.249125)
			(xy 451.62469 -14.287638) (xy 451.552854 -14.318944) (xy 451.478185 -14.342713) (xy 451.40147 -14.358695)
			(xy 451.323521 -14.36672) (xy 451.28434 -14.367256) (xy 451.246789 -14.366803) (xy 451.172052 -14.359418)
			(xy 451.098403 -14.344723) (xy 451.026554 -14.322863) (xy 450.9572 -14.294048) (xy 450.891014 -14.258557)
			(xy 450.828636 -14.216734) (xy 450.77067 -14.168984) (xy 450.743828 -14.14272) (xy 450.733787 -14.133311)
			(xy 450.709858 -14.119748) (xy 450.683178 -14.113059) (xy 450.655681 -14.11373) (xy 450.629359 -14.121712)
			(xy 450.606121 -14.136428) (xy 450.596508 -14.146276) (xy 450.569406 -14.175517) (xy 450.51009 -14.228795)
			(xy 450.445537 -14.275592) (xy 450.376453 -14.315397) (xy 450.303593 -14.347775) (xy 450.227751 -14.372374)
			(xy 450.149757 -14.388923) (xy 450.070461 -14.397243) (xy 450.030596 -14.397736) (xy 449.989891 -14.39721)
			(xy 449.908944 -14.388537) (xy 449.829382 -14.371292) (xy 449.752109 -14.345671) (xy 449.678004 -14.311964)
			(xy 449.607912 -14.270555) (xy 449.54263 -14.221916) (xy 449.482899 -14.1666) (xy 449.429401 -14.105236)
			(xy 449.382743 -14.038523) (xy 449.343457 -13.967219) (xy 449.32727 -13.929868) (xy 449.10629 -13.929868)
			(xy 449.094606 -13.936472) (xy 449.069287 -13.950355) (xy 449.015835 -13.972203) (xy 448.960013 -13.986978)
			(xy 448.902752 -13.994432) (xy 448.87388 -13.994892) (xy 448.84335 -13.994411) (xy 448.782856 -13.986121)
			(xy 448.724057 -13.969658) (xy 448.668054 -13.945329) (xy 448.641724 -13.929868) (xy 447.930778 -13.929868)
			(xy 447.920618 -13.93444) (xy 447.891414 -13.947124) (xy 447.830312 -13.965015) (xy 447.767286 -13.974034)
			(xy 447.735452 -13.974572) (xy 447.703618 -13.974024) (xy 447.640593 -13.965007) (xy 447.57949 -13.947121)
			(xy 447.550286 -13.93444) (xy 447.540126 -13.929868) (xy 445.87668 -13.929868) (xy 444.16218 -12.215368)
			(xy 444.16218 -10.104628) (xy 443.926214 -9.868662) (xy 443.917324 -9.864852) (xy 443.891048 -9.852744)
			(xy 443.841659 -9.82261) (xy 443.79667 -9.786233) (xy 443.756866 -9.744246) (xy 443.739524 -9.721088)
			(xy 437.4642 -9.721088) (xy 437.19242 -9.992868) (xy 437.19242 -11.98245) (xy 437.55818 -11.98245)
			(xy 437.55818 -10.567162) (xy 437.578754 -10.546588) (xy 437.749442 -10.546588) (xy 437.772556 -10.569702)
			(xy 437.772556 -11.96467) (xy 437.754776 -11.98245) (xy 438.158128 -11.98245) (xy 438.158128 -10.567162)
			(xy 438.178702 -10.546588) (xy 438.34939 -10.546588) (xy 438.372504 -10.569702) (xy 438.372504 -11.96467)
			(xy 438.354724 -11.98245) (xy 438.758076 -11.98245) (xy 438.758076 -10.567162) (xy 438.77865 -10.546588)
			(xy 438.949338 -10.546588) (xy 438.972452 -10.569702) (xy 438.972452 -11.96467) (xy 438.954672 -11.98245)
			(xy 439.358024 -11.98245) (xy 439.358024 -10.567162) (xy 439.378852 -10.546588) (xy 439.54954 -10.546588)
			(xy 439.572908 -10.569702) (xy 439.572908 -11.96467) (xy 439.554968 -11.98245) (xy 439.957972 -11.98245)
			(xy 439.957972 -10.567162) (xy 439.9788 -10.546588) (xy 440.149488 -10.546588) (xy 440.172856 -10.569702)
			(xy 440.172856 -11.96467) (xy 440.144408 -11.992864) (xy 439.96864 -11.992864) (xy 439.957972 -11.98245)
			(xy 439.554968 -11.98245) (xy 439.54446 -11.992864) (xy 439.368692 -11.992864) (xy 439.358024 -11.98245)
			(xy 438.954672 -11.98245) (xy 438.944258 -11.992864) (xy 438.76849 -11.992864) (xy 438.758076 -11.98245)
			(xy 438.354724 -11.98245) (xy 438.34431 -11.992864) (xy 438.168542 -11.992864) (xy 438.158128 -11.98245)
			(xy 437.754776 -11.98245) (xy 437.744362 -11.992864) (xy 437.568594 -11.992864) (xy 437.55818 -11.98245)
			(xy 437.19242 -11.98245) (xy 437.19242 -12.26693) (xy 438.598818 -13.673328) (xy 440.2328 -13.673328)
			(xy 440.49188 -13.932408) (xy 440.49188 -14.676031) (xy 446.526922 -14.676031) (xy 446.526922 -14.616265)
			(xy 446.53506 -14.557055) (xy 446.551185 -14.499505) (xy 446.574996 -14.444686) (xy 446.60605 -14.39362)
			(xy 446.643768 -14.347259) (xy 446.687447 -14.306465) (xy 446.736275 -14.271999) (xy 446.789341 -14.244502)
			(xy 446.845656 -14.224487) (xy 446.904173 -14.212328) (xy 446.9638 -14.208249) (xy 447.023427 -14.212328)
			(xy 447.081944 -14.224487) (xy 447.138259 -14.244502) (xy 447.191325 -14.271999) (xy 447.240153 -14.306465)
			(xy 447.283832 -14.347259) (xy 447.32155 -14.39362) (xy 447.352604 -14.444686) (xy 447.376415 -14.499505)
			(xy 447.39254 -14.557055) (xy 447.400678 -14.616265) (xy 447.400831 -14.625231) (xy 447.720722 -14.625231)
			(xy 447.720722 -14.565465) (xy 447.72886 -14.506255) (xy 447.744985 -14.448705) (xy 447.768796 -14.393886)
			(xy 447.79985 -14.34282) (xy 447.837568 -14.296459) (xy 447.881247 -14.255665) (xy 447.930075 -14.221199)
			(xy 447.983141 -14.193702) (xy 448.039456 -14.173687) (xy 448.097973 -14.161528) (xy 448.1576 -14.157449)
			(xy 448.217227 -14.161528) (xy 448.275744 -14.173687) (xy 448.332059 -14.193702) (xy 448.385125 -14.221199)
			(xy 448.433953 -14.255665) (xy 448.477632 -14.296459) (xy 448.51535 -14.34282) (xy 448.546404 -14.393886)
			(xy 448.570215 -14.448705) (xy 448.58634 -14.506255) (xy 448.594478 -14.565465) (xy 448.594988 -14.595348)
			(xy 448.594478 -14.625231) (xy 448.58634 -14.684441) (xy 448.570215 -14.741991) (xy 448.546404 -14.79681)
			(xy 448.51535 -14.847876) (xy 448.477632 -14.894237) (xy 448.433953 -14.935031) (xy 448.385125 -14.969497)
			(xy 448.332059 -14.996994) (xy 448.275744 -15.017009) (xy 448.217227 -15.029168) (xy 448.1576 -15.033247)
			(xy 448.097973 -15.029168) (xy 448.039456 -15.017009) (xy 447.983141 -14.996994) (xy 447.930075 -14.969497)
			(xy 447.881247 -14.935031) (xy 447.837568 -14.894237) (xy 447.79985 -14.847876) (xy 447.768796 -14.79681)
			(xy 447.744985 -14.741991) (xy 447.72886 -14.684441) (xy 447.720722 -14.625231) (xy 447.400831 -14.625231)
			(xy 447.401188 -14.646148) (xy 447.400678 -14.676031) (xy 447.39254 -14.735241) (xy 447.376415 -14.792791)
			(xy 447.352604 -14.84761) (xy 447.32155 -14.898676) (xy 447.283832 -14.945037) (xy 447.240153 -14.985831)
			(xy 447.191325 -15.020297) (xy 447.138259 -15.047794) (xy 447.081944 -15.067809) (xy 447.023427 -15.079968)
			(xy 446.9638 -15.084047) (xy 446.904173 -15.079968) (xy 446.845656 -15.067809) (xy 446.789341 -15.047794)
			(xy 446.736275 -15.020297) (xy 446.687447 -14.985831) (xy 446.643768 -14.945037) (xy 446.60605 -14.898676)
			(xy 446.574996 -14.84761) (xy 446.551185 -14.792791) (xy 446.53506 -14.735241) (xy 446.526922 -14.676031)
			(xy 440.49188 -14.676031) (xy 440.49188 -21.945346) (xy 440.722512 -22.175978) (xy 440.722512 -27.179778)
			(xy 440.730132 -27.187398) (xy 444.481712 -27.187398)
		)
		(stroke
			(width 0)
			(type solid)
		)
		(fill yes)
		(layer "F.Cu")
		(net "P12V_OCP_SFF")
	)
	(gr_poly
		(pts
			(xy 186.917076 -362.976414) (xy 186.917076 -353.771708) (xy 182.12435 -353.771708) (xy 182.056532 -353.839272)
			(xy 182.056532 -355.882194) (xy 182.079392 -355.905054) (xy 183.437784 -355.905054) (xy 183.605424 -356.072694)
			(xy 183.605424 -356.735888) (xy 183.97982 -357.110284) (xy 183.97982 -359.0671) (xy 183.35752 -359.6894)
			(xy 177.16373 -359.6894) (xy 176.398174 -358.923844) (xy 176.398174 -356.40391) (xy 176.8983 -355.903784)
			(xy 176.8983 -353.822508) (xy 176.8475 -353.771708) (xy 172.39234 -353.771708) (xy 172.368464 -353.795838)
			(xy 172.368464 -355.769164) (xy 172.381694 -355.797311) (xy 172.406212 -355.854478) (xy 172.417486 -355.883464)
			(xy 172.437298 -355.903276) (xy 173.795182 -355.903276) (xy 173.926754 -356.034848) (xy 173.926754 -356.754176)
			(xy 173.924722 -356.781608) (xy 173.921166 -356.806754) (xy 174.311056 -357.196898) (xy 174.311056 -360.25709)
			(xy 175.056038 -361.002072) (xy 175.056038 -363.155414) (xy 181.645048 -363.155414) (xy 181.645048 -363.070718)
			(xy 181.653099 -362.986404) (xy 181.669128 -362.903238) (xy 181.692989 -362.821971) (xy 181.724468 -362.743341)
			(xy 181.763279 -362.66806) (xy 181.809069 -362.596808) (xy 181.861425 -362.530232) (xy 181.919873 -362.468934)
			(xy 181.983883 -362.413469) (xy 182.052875 -362.36434) (xy 182.126225 -362.321991) (xy 182.203268 -362.286807)
			(xy 182.283307 -362.259105) (xy 182.365616 -362.239137) (xy 182.449451 -362.227084) (xy 182.534052 -362.223054)
			(xy 182.618653 -362.227084) (xy 182.702488 -362.239137) (xy 182.784797 -362.259105) (xy 182.864836 -362.286807)
			(xy 182.941879 -362.321991) (xy 183.015229 -362.36434) (xy 183.084221 -362.413469) (xy 183.148231 -362.468934)
			(xy 183.206679 -362.530232) (xy 183.259035 -362.596808) (xy 183.304825 -362.66806) (xy 183.343636 -362.743341)
			(xy 183.375115 -362.821971) (xy 183.398976 -362.903238) (xy 183.415005 -362.986404) (xy 183.423056 -363.070718)
			(xy 183.42356 -363.113066) (xy 183.423056 -363.155414) (xy 183.415005 -363.239728) (xy 183.398976 -363.322894)
			(xy 183.375115 -363.404161) (xy 183.343636 -363.482791) (xy 183.304825 -363.558072) (xy 183.259035 -363.629324)
			(xy 183.206679 -363.6959) (xy 183.148231 -363.757198) (xy 183.084221 -363.812663) (xy 183.015229 -363.861792)
			(xy 182.941879 -363.904141) (xy 182.864836 -363.939325) (xy 182.784797 -363.967027) (xy 182.702488 -363.986995)
			(xy 182.618653 -363.999048) (xy 182.534052 -364.003079) (xy 182.449451 -363.999048) (xy 182.365616 -363.986995)
			(xy 182.283307 -363.967027) (xy 182.203268 -363.939325) (xy 182.126225 -363.904141) (xy 182.052875 -363.861792)
			(xy 181.983883 -363.812663) (xy 181.919873 -363.757198) (xy 181.861425 -363.6959) (xy 181.809069 -363.629324)
			(xy 181.763279 -363.558072) (xy 181.724468 -363.482791) (xy 181.692989 -363.404161) (xy 181.669128 -363.322894)
			(xy 181.653099 -363.239728) (xy 181.645048 -363.155414) (xy 175.056038 -363.155414) (xy 175.056038 -365.24057)
			(xy 176.640742 -365.24057) (xy 176.644813 -365.184948) (xy 176.656939 -365.130511) (xy 176.676862 -365.07842)
			(xy 176.704158 -365.029785) (xy 176.738244 -364.985642) (xy 176.778393 -364.946933) (xy 176.823751 -364.914482)
			(xy 176.873351 -364.888981) (xy 176.926135 -364.870974) (xy 176.980978 -364.860844) (xy 177.036712 -364.858807)
			(xy 177.092149 -364.864907) (xy 177.146106 -364.879013) (xy 177.197435 -364.900825) (xy 177.245041 -364.929879)
			(xy 177.287909 -364.965554) (xy 177.325126 -365.007091) (xy 177.355899 -365.053604) (xy 177.379571 -365.104101)
			(xy 177.395639 -365.157508) (xy 177.403759 -365.212684) (xy 177.403804 -365.21517) (xy 177.857402 -365.21517)
			(xy 177.861473 -365.159548) (xy 177.873599 -365.105111) (xy 177.893522 -365.05302) (xy 177.920818 -365.004385)
			(xy 177.954904 -364.960242) (xy 177.995053 -364.921533) (xy 178.040411 -364.889082) (xy 178.090011 -364.863581)
			(xy 178.142795 -364.845574) (xy 178.197638 -364.835444) (xy 178.253372 -364.833407) (xy 178.308809 -364.839507)
			(xy 178.362766 -364.853613) (xy 178.414095 -364.875425) (xy 178.461701 -364.904479) (xy 178.504569 -364.940154)
			(xy 178.541786 -364.981691) (xy 178.572559 -365.028204) (xy 178.596231 -365.078701) (xy 178.612299 -365.132108)
			(xy 178.612561 -365.13389) (xy 179.114702 -365.13389) (xy 179.118773 -365.078268) (xy 179.130899 -365.023831)
			(xy 179.150822 -364.97174) (xy 179.178118 -364.923105) (xy 179.212204 -364.878962) (xy 179.252353 -364.840253)
			(xy 179.297711 -364.807802) (xy 179.347311 -364.782301) (xy 179.400095 -364.764294) (xy 179.454938 -364.754164)
			(xy 179.510672 -364.752127) (xy 179.566109 -364.758227) (xy 179.620066 -364.772333) (xy 179.671395 -364.794145)
			(xy 179.719001 -364.823199) (xy 179.761869 -364.858874) (xy 179.799086 -364.900411) (xy 179.829859 -364.946924)
			(xy 179.842491 -364.97387) (xy 180.324252 -364.97387) (xy 180.324732 -364.947296) (xy 180.332113 -364.894662)
			(xy 180.346728 -364.843562) (xy 180.368295 -364.794985) (xy 180.396394 -364.749872) (xy 180.430484 -364.709095)
			(xy 180.469903 -364.673445) (xy 180.491638 -364.658148) (xy 180.512938 -364.6442) (xy 180.558506 -364.62149)
			(xy 180.606696 -364.605058) (xy 180.631592 -364.599728) (xy 180.635656 -364.598966) (xy 180.653019 -364.59589)
			(xy 180.688128 -364.592582) (xy 180.70576 -364.592362) (xy 180.723391 -364.592601) (xy 180.758499 -364.595905)
			(xy 180.775864 -364.598966) (xy 180.779928 -364.599728) (xy 180.804816 -364.605085) (xy 180.852998 -364.621528)
			(xy 180.898569 -364.644224) (xy 180.919882 -364.658148) (xy 180.941635 -364.673424) (xy 180.981064 -364.70907)
			(xy 181.01516 -364.749847) (xy 181.043264 -364.794964) (xy 181.06483 -364.843546) (xy 181.079441 -364.894653)
			(xy 181.086812 -364.947293) (xy 181.087268 -364.97387) (xy 181.086782 -365.001121) (xy 181.079026 -365.055069)
			(xy 181.063671 -365.107364) (xy 181.041029 -365.156941) (xy 181.011563 -365.202791) (xy 180.975872 -365.243982)
			(xy 180.934681 -365.279673) (xy 180.888831 -365.309139) (xy 180.839254 -365.331781) (xy 180.786959 -365.347136)
			(xy 180.733011 -365.354892) (xy 180.678509 -365.354892) (xy 180.624561 -365.347136) (xy 180.572266 -365.331781)
			(xy 180.522689 -365.309139) (xy 180.476839 -365.279673) (xy 180.435648 -365.243982) (xy 180.399957 -365.202791)
			(xy 180.370491 -365.156941) (xy 180.347849 -365.107364) (xy 180.332494 -365.055069) (xy 180.324738 -365.001121)
			(xy 180.324252 -364.97387) (xy 179.842491 -364.97387) (xy 179.853531 -364.997421) (xy 179.869599 -365.050828)
			(xy 179.877719 -365.106004) (xy 179.878228 -365.13389) (xy 179.877719 -365.161776) (xy 179.869599 -365.216952)
			(xy 179.853531 -365.270359) (xy 179.829859 -365.320856) (xy 179.799086 -365.367369) (xy 179.761869 -365.408906)
			(xy 179.719001 -365.444581) (xy 179.671395 -365.473635) (xy 179.620066 -365.495447) (xy 179.566109 -365.509553)
			(xy 179.510672 -365.515653) (xy 179.454938 -365.513616) (xy 179.400095 -365.503486) (xy 179.347311 -365.485479)
			(xy 179.297711 -365.459978) (xy 179.252353 -365.427527) (xy 179.212204 -365.388818) (xy 179.178118 -365.344675)
			(xy 179.150822 -365.29604) (xy 179.130899 -365.243949) (xy 179.118773 -365.189512) (xy 179.114702 -365.13389)
			(xy 178.612561 -365.13389) (xy 178.620419 -365.187284) (xy 178.620928 -365.21517) (xy 178.620419 -365.243056)
			(xy 178.612299 -365.298232) (xy 178.596231 -365.351639) (xy 178.572559 -365.402136) (xy 178.541786 -365.448649)
			(xy 178.504569 -365.490186) (xy 178.461701 -365.525861) (xy 178.414095 -365.554915) (xy 178.362766 -365.576727)
			(xy 178.308809 -365.590833) (xy 178.253372 -365.596933) (xy 178.197638 -365.594896) (xy 178.142795 -365.584766)
			(xy 178.090011 -365.566759) (xy 178.040411 -365.541258) (xy 177.995053 -365.508807) (xy 177.954904 -365.470098)
			(xy 177.920818 -365.425955) (xy 177.893522 -365.37732) (xy 177.873599 -365.325229) (xy 177.861473 -365.270792)
			(xy 177.857402 -365.21517) (xy 177.403804 -365.21517) (xy 177.404268 -365.24057) (xy 177.403759 -365.268456)
			(xy 177.395639 -365.323632) (xy 177.379571 -365.377039) (xy 177.355899 -365.427536) (xy 177.325126 -365.474049)
			(xy 177.287909 -365.515586) (xy 177.245041 -365.551261) (xy 177.197435 -365.580315) (xy 177.146106 -365.602127)
			(xy 177.092149 -365.616233) (xy 177.036712 -365.622333) (xy 176.980978 -365.620296) (xy 176.926135 -365.610166)
			(xy 176.873351 -365.592159) (xy 176.823751 -365.566658) (xy 176.778393 -365.534207) (xy 176.738244 -365.495498)
			(xy 176.704158 -365.451355) (xy 176.676862 -365.40272) (xy 176.656939 -365.350629) (xy 176.644813 -365.296192)
			(xy 176.640742 -365.24057) (xy 175.056038 -365.24057) (xy 175.056038 -365.37265) (xy 175.416972 -365.733838)
			(xy 176.313084 -366.62995) (xy 183.26354 -366.62995)
		)
		(stroke
			(width 0)
			(type solid)
		)
		(fill yes)
		(layer "F.Cu")
		(net "SW_P12V_PVCCFA_EHV_FIVRA_CPU1_R")
	)
	(gr_poly
		(pts
			(arc
				(start 329.150218 -36.755578)
				(mid 329.226184 -36.816806)
				(end 329.31862 -36.785804)
			)
			(arc
				(start 329.31862 -36.785804)
				(mid 329.442726 -36.697785)
				(end 329.59167 -36.666678)
			)
			(arc
				(start 329.59167 -36.666678)
				(mid 329.7007 -36.682975)
				(end 329.800204 -36.730432)
			)
			(xy 329.812904 -36.739068) (xy 329.879452 -36.739068) (xy 329.879452 -36.655502)
			(arc
				(start 329.325732 -36.102036)
				(mid 329.294045 -36.054474)
				(end 329.28306 -35.998404)
			)
			(xy 329.28306 -34.90976) (xy 328.781918 -34.408618) (xy 328.781918 -34.302954) (xy 328.303382 -33.824418)
			(arc
				(start 328.292714 -33.820608)
				(mid 328.260116 -33.804503)
				(end 328.231754 -33.781746)
			)
			(arc
				(start 327.425812 -32.974534)
				(mid 327.389735 -32.920447)
				(end 327.377044 -32.856678)
			)
			(xy 327.377044 -32.614108) (xy 327.137522 -32.374332)
			(arc
				(start 327.120758 -32.371792)
				(mid 326.966258 -32.313329)
				(end 326.85101 -32.195008)
			)
			(xy 326.847962 -32.189928)
			(arc
				(start 326.642476 -31.984442)
				(mid 326.573066 -31.887928)
				(end 326.537828 -31.774384)
			)
			(xy 326.535288 -31.75762)
			(arc
				(start 326.06488 -31.287212)
				(mid 326.040514 -31.260275)
				(end 326.018906 -31.231078)
			)
			(xy 325.700898 -30.755336) (xy 325.68388 -30.738318) (xy 325.68388 -30.729936) (xy 325.028306 -29.748988)
			(xy 323.841618 -28.5623) (xy 323.602096 -28.5623) (xy 321.952874 -30.211522) (xy 321.949064 -30.222952)
			(xy 321.940428 -30.245812)
			(arc
				(start 321.657472 -30.929072)
				(mid 321.641909 -30.961924)
				(end 321.623182 -30.99308)
			)
			(xy 321.15379 -31.695644) (xy 321.15379 -32.126682)
			(arc
				(start 321.371976 -32.344868)
				(mid 321.452096 -32.464915)
				(end 321.48018 -32.606488)
			)
			(xy 321.48018 -33.2232) (xy 322.154042 -33.897062) (xy 322.466716 -33.584388) (xy 322.631816 -33.584388)
			(xy 324.410832 -35.363404) (xy 324.472808 -35.363404)
			(arc
				(start 324.47865 -35.36188)
				(mid 324.522171 -35.354268)
				(end 324.56628 -35.35172)
			)
			(arc
				(start 324.56628 -35.35172)
				(mid 324.610391 -35.354249)
				(end 324.65391 -35.36188)
			)
			(xy 324.659752 -35.363404)
			(arc
				(start 325.199756 -35.363404)
				(mid 325.341335 -35.391472)
				(end 325.461376 -35.471608)
			)
			(xy 326.135238 -36.145724)
			(arc
				(start 326.718422 -36.145724)
				(mid 326.775886 -36.150176)
				(end 326.83196 -36.163504)
			)
			(xy 326.83958 -36.166044)
			(arc
				(start 327.204324 -36.166044)
				(mid 327.25045 -36.169101)
				(end 327.295764 -36.178236)
			)
			(xy 327.324212 -36.185856) (xy 327.381108 -36.129214) (xy 326.907652 -35.655758)
			(arc
				(start 326.887586 -35.654996)
				(mid 326.817488 -35.639237)
				(end 326.758046 -35.598862)
			)
			(xy 325.9201 -34.760916)
			(arc
				(start 325.893684 -34.765742)
				(mid 325.858033 -34.770875)
				(end 325.822056 -34.7726)
			)
			(arc
				(start 325.822056 -34.7726)
				(mid 325.552289 -34.660859)
				(end 325.440548 -34.391092)
			)
			(arc
				(start 325.440548 -34.391092)
				(mid 325.442296 -34.355118)
				(end 325.447406 -34.319464)
			)
			(xy 325.452232 -34.293048) (xy 325.39432 -34.235136) (xy 325.369428 -34.260028) (xy 325.32701 -34.217356)
			(xy 325.139558 -34.404808) (xy 324.69074 -33.95599) (xy 324.83933 -33.807146) (xy 324.503288 -33.47085)
			(arc
				(start 324.452742 -33.521396)
				(mid 324.362736 -33.558566)
				(end 324.272656 -33.521396)
			)
			(arc
				(start 323.769736 -33.018476)
				(mid 323.732566 -32.92847)
				(end 323.769736 -32.83839)
			)
			(xy 323.880226 -32.7279) (xy 323.70395 -32.551624) (xy 323.309742 -32.551624)
			(arc
				(start 322.826634 -33.034986)
				(mid 322.736464 -33.07241)
				(end 322.646294 -33.034986)
			)
			(arc
				(start 321.371214 -31.759906)
				(mid 321.33379 -31.669736)
				(end 321.371214 -31.579566)
			)
			(arc
				(start 322.089526 -30.861254)
				(mid 322.141342 -30.829917)
				(end 322.201794 -30.825948)
			)
			(xy 322.227702 -30.83052) (xy 323.10832 -29.949902)
			(arc
				(start 323.103748 -29.923994)
				(mid 323.107611 -29.863509)
				(end 323.139054 -29.811726)
			)
			(arc
				(start 323.857366 -29.093414)
				(mid 323.947536 -29.05599)
				(end 324.037706 -29.093414)
			)
			(arc
				(start 325.312786 -30.368494)
				(mid 325.35021 -30.458664)
				(end 325.312786 -30.548834)
			)
			(xy 325.1835 -30.67812)
			(arc
				(start 325.59117 -31.08579)
				(mid 325.632746 -31.148152)
				(end 325.647304 -31.22168)
			)
			(xy 325.647304 -31.302706)
			(arc
				(start 326.069452 -31.7246)
				(mid 326.106802 -31.81468)
				(end 326.069452 -31.904686)
			)
			(xy 325.761858 -32.21228) (xy 326.05599 -32.506158) (xy 326.10044 -32.461962) (xy 326.433688 -32.79521)
			(arc
				(start 326.441054 -32.798766)
				(mid 326.467814 -32.814859)
				(end 326.4916 -32.835088)
			)
			(xy 326.584056 -32.927544)
			(arc
				(start 326.610472 -32.922718)
				(mid 326.646123 -32.917585)
				(end 326.6821 -32.91586)
			)
			(arc
				(start 326.6821 -32.91586)
				(mid 326.951867 -33.027601)
				(end 327.063608 -33.297368)
			)
			(arc
				(start 327.063608 -33.297368)
				(mid 327.06186 -33.333342)
				(end 327.05675 -33.368996)
			)
			(xy 327.051924 -33.395412)
			(arc
				(start 327.149714 -33.493202)
				(mid 327.174184 -33.523314)
				(end 327.192132 -33.557718)
			)
			(xy 327.196196 -33.56737) (xy 327.37806 -33.74898) (xy 327.335388 -33.791398) (xy 327.52284 -33.97885)
			(xy 327.522586 -33.979104) (xy 327.70699 -34.163) (xy 327.749408 -34.120328)
			(arc
				(start 327.938384 -34.309558)
				(mid 327.992329 -34.395691)
				(end 328.003154 -34.496756)
			)
			(arc
				(start 328.003154 -34.496756)
				(mid 328.023363 -34.570722)
				(end 328.089514 -34.609532)
			)
			(arc
				(start 328.089514 -34.609532)
				(mid 328.323705 -34.73729)
				(end 328.41692 -34.98723)
			)
			(arc
				(start 328.41692 -34.98723)
				(mid 328.358772 -35.189682)
				(end 328.202036 -35.330384)
			)
			(xy 328.202036 -35.461448)
			(arc
				(start 328.88174 -36.141152)
				(mid 328.902441 -36.166426)
				(end 328.917808 -36.195254)
			)
		)
		(stroke
			(width 0)
			(type solid)
		)
		(fill yes)
		(layer "F.Cu")
		(net "GND")
	)
	(gr_poly
		(pts
			(xy 301.84598 -440.76366) (xy 301.84598 -429.17872) (xy 300.80458 -428.13732) (xy 294.55618 -428.13732)
			(xy 293.36238 -426.94352) (xy 293.36238 -417.66998) (xy 292.8112 -417.1188) (xy 290.24072 -417.1188)
			(xy 289.41014 -416.28822) (xy 285.23946 -416.28822) (xy 283.34716 -418.18052) (xy 283.34716 -425.98086)
			(xy 281.12466 -428.20336) (xy 276.9108 -428.20336) (xy 270.81226 -422.10482) (xy 246.11584 -422.10482)
			(xy 241.09426 -427.1264) (xy 241.09426 -433.04206) (xy 267.01141 -433.04206) (xy 267.01543 -432.866756)
			(xy 267.027484 -432.69182) (xy 267.047545 -432.517622) (xy 267.075571 -432.344526) (xy 267.111504 -432.172897)
			(xy 267.155267 -432.003095) (xy 267.20677 -431.835479) (xy 267.265903 -431.6704) (xy 267.332542 -431.508206)
			(xy 267.406547 -431.349238) (xy 267.487762 -431.19383) (xy 267.576017 -431.042308) (xy 267.671126 -430.894992)
			(xy 267.772888 -430.752191) (xy 267.881091 -430.614206) (xy 267.995506 -430.481327) (xy 268.115893 -430.353833)
			(xy 268.241998 -430.231992) (xy 268.373557 -430.116061) (xy 268.510292 -430.006284) (xy 268.651917 -429.902891)
			(xy 268.798133 -429.806099) (xy 268.948632 -429.716113) (xy 269.103099 -429.633121) (xy 269.261209 -429.557298)
			(xy 269.422628 -429.488804) (xy 269.587018 -429.427782) (xy 269.754033 -429.374362) (xy 269.923321 -429.328654)
			(xy 270.094527 -429.290756) (xy 270.26729 -429.260747) (xy 270.441247 -429.23869) (xy 270.616033 -429.224631)
			(xy 270.79128 -429.218601) (xy 270.966618 -429.220611) (xy 271.14168 -429.230658) (xy 271.316098 -429.248721)
			(xy 271.489504 -429.274761) (xy 271.661533 -429.308723) (xy 271.831825 -429.350537) (xy 272.000021 -429.400114)
			(xy 272.165767 -429.457351) (xy 272.328714 -429.522126) (xy 272.488521 -429.594303) (xy 272.64485 -429.673731)
			(xy 272.797374 -429.760243) (xy 272.94577 -429.853656) (xy 273.089728 -429.953775) (xy 273.228945 -430.060389)
			(xy 273.363127 -430.173273) (xy 273.491993 -430.29219) (xy 273.615272 -430.41689) (xy 273.732703 -430.547111)
			(xy 273.844042 -430.682578) (xy 273.949052 -430.823008) (xy 274.047513 -430.968105) (xy 274.139219 -431.117563)
			(xy 274.223977 -431.271068) (xy 274.301607 -431.428298) (xy 274.371948 -431.588921) (xy 274.43485 -431.752601)
			(xy 274.490182 -431.918992) (xy 274.537828 -432.087745) (xy 274.577686 -432.258505) (xy 274.609674 -432.430913)
			(xy 274.633724 -432.604606) (xy 274.649786 -432.779219) (xy 274.657825 -432.954385) (xy 274.658328 -433.04206)
			(xy 274.657825 -433.129735) (xy 274.649786 -433.304901) (xy 274.633724 -433.479514) (xy 274.609674 -433.653207)
			(xy 274.577686 -433.825615) (xy 274.537828 -433.996375) (xy 274.490182 -434.165128) (xy 274.43485 -434.331519)
			(xy 274.371948 -434.495199) (xy 274.301607 -434.655822) (xy 274.223977 -434.813052) (xy 274.139219 -434.966557)
			(xy 274.047513 -435.116015) (xy 273.949052 -435.261112) (xy 273.844042 -435.401542) (xy 273.732703 -435.537009)
			(xy 273.615272 -435.66723) (xy 273.491993 -435.79193) (xy 273.363127 -435.910847) (xy 273.228945 -436.023731)
			(xy 273.089728 -436.130345) (xy 272.94577 -436.230464) (xy 272.797374 -436.323877) (xy 272.64485 -436.410389)
			(xy 272.488521 -436.489817) (xy 272.328714 -436.561994) (xy 272.165767 -436.626769) (xy 272.000021 -436.684006)
			(xy 271.831825 -436.733583) (xy 271.661533 -436.775397) (xy 271.489504 -436.809359) (xy 271.316098 -436.835399)
			(xy 271.14168 -436.853462) (xy 270.966618 -436.863509) (xy 270.79128 -436.865519) (xy 270.616033 -436.859489)
			(xy 270.441247 -436.84543) (xy 270.26729 -436.823373) (xy 270.094527 -436.793364) (xy 269.923321 -436.755466)
			(xy 269.754033 -436.709758) (xy 269.587018 -436.656338) (xy 269.422628 -436.595316) (xy 269.261209 -436.526822)
			(xy 269.103099 -436.450999) (xy 268.948632 -436.368007) (xy 268.798133 -436.278021) (xy 268.651917 -436.181229)
			(xy 268.510292 -436.077836) (xy 268.373557 -435.968059) (xy 268.241998 -435.852128) (xy 268.115893 -435.730287)
			(xy 267.995506 -435.602793) (xy 267.881091 -435.469914) (xy 267.772888 -435.331929) (xy 267.671126 -435.189128)
			(xy 267.576017 -435.041812) (xy 267.487762 -434.89029) (xy 267.406547 -434.734882) (xy 267.332542 -434.575914)
			(xy 267.265903 -434.41372) (xy 267.20677 -434.248641) (xy 267.155267 -434.081025) (xy 267.111504 -433.911223)
			(xy 267.075571 -433.739594) (xy 267.047545 -433.566498) (xy 267.027484 -433.3923) (xy 267.01543 -433.217364)
			(xy 267.01141 -433.04206) (xy 241.09426 -433.04206) (xy 241.09426 -437.3372) (xy 242.254532 -438.497472)
			(xy 277.7871 -438.497472) (xy 277.7871 -434.086) (xy 278.18842 -433.68468) (xy 280.62428 -433.68468)
			(xy 281.66568 -432.64328) (xy 282.915106 -432.64328) (xy 283.216858 -432.945032) (xy 283.216858 -434.800756)
			(xy 283.460444 -435.044342) (xy 283.460444 -438.714896) (xy 283.322522 -438.852818) (xy 278.142446 -438.852818)
			(xy 277.7871 -438.497472) (xy 242.254532 -438.497472) (xy 242.84432 -439.08726) (xy 276.95398 -439.08726)
			(xy 277.36292 -439.4962) (xy 283.895292 -439.4962) (xy 283.895717 -439.470224) (xy 283.90276 -439.418751)
			(xy 283.916731 -439.368713) (xy 283.937369 -439.321036) (xy 283.964293 -439.276604) (xy 283.997002 -439.236242)
			(xy 284.034891 -439.200697) (xy 284.05582 -439.185304) (xy 284.066833 -439.176895) (xy 284.084255 -439.155363)
			(xy 284.095248 -439.129941) (xy 284.099005 -439.1025) (xy 284.095248 -439.075059) (xy 284.084255 -439.049637)
			(xy 284.066833 -439.028105) (xy 284.05582 -439.019696) (xy 284.034878 -439.004323) (xy 283.997003 -438.968765)
			(xy 283.964305 -438.928395) (xy 283.93739 -438.88396) (xy 283.916755 -438.836282) (xy 283.902783 -438.786246)
			(xy 283.895731 -438.734775) (xy 283.895292 -438.7088) (xy 283.895749 -438.681934) (xy 283.903276 -438.628732)
			(xy 283.918196 -438.577113) (xy 283.940213 -438.528099) (xy 283.968892 -438.48266) (xy 284.003663 -438.441696)
			(xy 284.04384 -438.406018) (xy 284.06598 -438.390792) (xy 284.077295 -438.382758) (xy 284.095473 -438.361805)
			(xy 284.107329 -438.336728) (xy 284.111986 -438.309383) (xy 284.109099 -438.281795) (xy 284.098882 -438.256006)
			(xy 284.082091 -438.233927) (xy 284.071314 -438.225184) (xy 284.048329 -438.207012) (xy 284.007658 -438.164837)
			(xy 283.973912 -438.116941) (xy 283.947882 -438.06445) (xy 283.930182 -438.008597) (xy 283.921226 -437.950695)
			(xy 283.920692 -437.9214) (xy 283.921178 -437.894149) (xy 283.928934 -437.840201) (xy 283.944289 -437.787906)
			(xy 283.966931 -437.738329) (xy 283.996397 -437.692479) (xy 284.032088 -437.651288) (xy 284.073279 -437.615597)
			(xy 284.119129 -437.586131) (xy 284.168706 -437.563489) (xy 284.221001 -437.548134) (xy 284.274949 -437.540378)
			(xy 284.329451 -437.540378) (xy 284.383399 -437.548134) (xy 284.435694 -437.563489) (xy 284.485271 -437.586131)
			(xy 284.531121 -437.615597) (xy 284.572312 -437.651288) (xy 284.608003 -437.692479) (xy 284.637469 -437.738329)
			(xy 284.660111 -437.787906) (xy 284.675466 -437.840201) (xy 284.683222 -437.894149) (xy 284.683708 -437.9214)
			(xy 284.683251 -437.948266) (xy 284.675724 -438.001468) (xy 284.660804 -438.053087) (xy 284.638787 -438.102101)
			(xy 284.610108 -438.14754) (xy 284.575337 -438.188504) (xy 284.53516 -438.224182) (xy 284.51302 -438.239408)
			(xy 284.501705 -438.247442) (xy 284.483527 -438.268395) (xy 284.471671 -438.293472) (xy 284.467014 -438.320817)
			(xy 284.469901 -438.348405) (xy 284.480118 -438.374194) (xy 284.496909 -438.396273) (xy 284.507686 -438.405016)
			(xy 284.530671 -438.423188) (xy 284.571342 -438.465363) (xy 284.605088 -438.513259) (xy 284.631118 -438.56575)
			(xy 284.648818 -438.621603) (xy 284.657774 -438.679505) (xy 284.658308 -438.7088) (xy 284.657883 -438.734776)
			(xy 284.65084 -438.786249) (xy 284.636869 -438.836287) (xy 284.616231 -438.883964) (xy 284.589307 -438.928396)
			(xy 284.556598 -438.968758) (xy 284.518709 -439.004303) (xy 284.49778 -439.019696) (xy 284.486767 -439.028105)
			(xy 284.469345 -439.049637) (xy 284.458352 -439.075059) (xy 284.454595 -439.1025) (xy 284.458352 -439.129941)
			(xy 284.469345 -439.155363) (xy 284.486767 -439.176895) (xy 284.49778 -439.185304) (xy 284.518722 -439.200677)
			(xy 284.556597 -439.236235) (xy 284.589295 -439.276605) (xy 284.61621 -439.32104) (xy 284.636845 -439.368718)
			(xy 284.650817 -439.418754) (xy 284.657869 -439.470225) (xy 284.658308 -439.4962) (xy 284.657822 -439.523451)
			(xy 284.650066 -439.577399) (xy 284.634711 -439.629694) (xy 284.612069 -439.679271) (xy 284.582603 -439.725121)
			(xy 284.546912 -439.766312) (xy 284.505721 -439.802003) (xy 284.459871 -439.831469) (xy 284.410294 -439.854111)
			(xy 284.357999 -439.869466) (xy 284.304051 -439.877222) (xy 284.249549 -439.877222) (xy 284.195601 -439.869466)
			(xy 284.143306 -439.854111) (xy 284.093729 -439.831469) (xy 284.047879 -439.802003) (xy 284.006688 -439.766312)
			(xy 283.970997 -439.725121) (xy 283.941531 -439.679271) (xy 283.918889 -439.629694) (xy 283.903534 -439.577399)
			(xy 283.895778 -439.523451) (xy 283.895292 -439.4962) (xy 277.36292 -439.4962) (xy 279.21966 -441.35294)
			(xy 301.2567 -441.35294)
		)
		(stroke
			(width 0)
			(type solid)
		)
		(fill yes)
		(layer "F.Cu")
		(net "GND")
	)
	(gr_poly
		(pts
			(xy 400.49704 -187.736988) (xy 401.78736 -187.736988) (xy 402.0058 -187.518548) (xy 402.0058 -185.689748)
			(xy 402.68525 -185.010298) (xy 406.97658 -185.010298) (xy 407.26868 -184.718198) (xy 407.26868 -167.03802)
			(xy 406.95118 -166.72052) (xy 399.428208 -166.72052) (xy 398.453864 -167.694864) (xy 398.453864 -168.466516)
			(xy 398.0561 -168.86428) (xy 398.0561 -168.983152) (xy 399.642589 -168.983152) (xy 399.646611 -168.897432)
			(xy 399.658642 -168.812464) (xy 399.678578 -168.728997) (xy 399.706241 -168.647763) (xy 399.74139 -168.569477)
			(xy 399.783716 -168.494826) (xy 399.832845 -168.424467) (xy 399.888348 -168.359017) (xy 399.949735 -168.299053)
			(xy 400.016468 -168.2451) (xy 400.08796 -168.197633) (xy 400.163582 -168.157069) (xy 400.242671 -168.123765)
			(xy 400.324531 -168.098013) (xy 400.408442 -168.08004) (xy 400.493668 -168.070004) (xy 400.57946 -168.067992)
			(xy 400.665062 -168.074023) (xy 400.749724 -168.088043) (xy 400.832701 -168.109929) (xy 400.913264 -168.13949)
			(xy 400.990704 -168.176464) (xy 401.064343 -168.220528) (xy 401.133531 -168.271294) (xy 401.197662 -168.328315)
			(xy 401.256171 -168.391091) (xy 401.308544 -168.459071) (xy 401.354322 -168.531656) (xy 401.393102 -168.608208)
			(xy 401.424543 -168.688056) (xy 401.448369 -168.770497) (xy 401.46437 -168.854807) (xy 401.472405 -168.940245)
			(xy 401.472908 -168.983152) (xy 401.472405 -169.026059) (xy 401.46437 -169.111497) (xy 401.448369 -169.195807)
			(xy 401.424543 -169.278248) (xy 401.393102 -169.358096) (xy 401.354322 -169.434648) (xy 401.308544 -169.507233)
			(xy 401.256171 -169.575213) (xy 401.197662 -169.637989) (xy 401.133531 -169.69501) (xy 401.064343 -169.745776)
			(xy 400.990704 -169.78984) (xy 400.913264 -169.826814) (xy 400.832701 -169.856375) (xy 400.749724 -169.878261)
			(xy 400.665062 -169.892281) (xy 400.57946 -169.898312) (xy 400.493668 -169.8963) (xy 400.408442 -169.886264)
			(xy 400.324531 -169.868291) (xy 400.242671 -169.842539) (xy 400.163582 -169.809235) (xy 400.08796 -169.768671)
			(xy 400.016468 -169.721204) (xy 399.949735 -169.667251) (xy 399.888348 -169.607287) (xy 399.832845 -169.541837)
			(xy 399.783716 -169.471478) (xy 399.74139 -169.396827) (xy 399.706241 -169.318541) (xy 399.678578 -169.237307)
			(xy 399.658642 -169.15384) (xy 399.646611 -169.068872) (xy 399.642589 -168.983152) (xy 398.0561 -168.983152)
			(xy 398.0561 -171.770548) (xy 399.668492 -171.770548) (xy 399.668492 -170.195748) (xy 399.668931 -170.18236)
			(xy 399.675852 -170.156493) (xy 399.689232 -170.1333) (xy 399.708162 -170.114362) (xy 399.731349 -170.10097)
			(xy 399.757212 -170.094038) (xy 399.7706 -170.09364) (xy 401.3454 -170.09364) (xy 401.358794 -170.09399)
			(xy 401.38467 -170.100926) (xy 401.407868 -170.114324) (xy 401.426806 -170.133271) (xy 401.440193 -170.156475)
			(xy 401.447116 -170.182353) (xy 401.447508 -170.195748) (xy 401.447508 -171.770548) (xy 401.447113 -171.783935)
			(xy 401.440173 -171.809796) (xy 401.426779 -171.832979) (xy 401.407841 -171.851908) (xy 401.384651 -171.865292)
			(xy 401.358788 -171.87222) (xy 401.3454 -171.872656) (xy 399.7706 -171.872656) (xy 399.757219 -171.872172)
			(xy 399.731368 -171.865247) (xy 399.708188 -171.851869) (xy 399.68926 -171.83295) (xy 399.675871 -171.809777)
			(xy 399.668935 -171.783929) (xy 399.668492 -171.770548) (xy 398.0561 -171.770548) (xy 398.0561 -175.206152)
			(xy 399.642589 -175.206152) (xy 399.646611 -175.120432) (xy 399.658642 -175.035464) (xy 399.678578 -174.951997)
			(xy 399.706241 -174.870763) (xy 399.74139 -174.792477) (xy 399.783716 -174.717826) (xy 399.832845 -174.647467)
			(xy 399.888348 -174.582017) (xy 399.949735 -174.522053) (xy 400.016468 -174.4681) (xy 400.08796 -174.420633)
			(xy 400.163582 -174.380069) (xy 400.242671 -174.346765) (xy 400.324531 -174.321013) (xy 400.408442 -174.30304)
			(xy 400.493668 -174.293004) (xy 400.57946 -174.290992) (xy 400.665062 -174.297023) (xy 400.749724 -174.311043)
			(xy 400.832701 -174.332929) (xy 400.913264 -174.36249) (xy 400.990704 -174.399464) (xy 401.064343 -174.443528)
			(xy 401.133531 -174.494294) (xy 401.197662 -174.551315) (xy 401.256171 -174.614091) (xy 401.308544 -174.682071)
			(xy 401.354322 -174.754656) (xy 401.393102 -174.831208) (xy 401.424543 -174.911056) (xy 401.448369 -174.993497)
			(xy 401.46437 -175.077807) (xy 401.472405 -175.163245) (xy 401.472908 -175.206152) (xy 401.472405 -175.249059)
			(xy 401.46437 -175.334497) (xy 401.448369 -175.418807) (xy 401.424543 -175.501248) (xy 401.393102 -175.581096)
			(xy 401.354322 -175.657648) (xy 401.308544 -175.730233) (xy 401.256171 -175.798213) (xy 401.197662 -175.860989)
			(xy 401.133531 -175.91801) (xy 401.064343 -175.968776) (xy 400.990704 -176.01284) (xy 400.913264 -176.049814)
			(xy 400.832701 -176.079375) (xy 400.749724 -176.101261) (xy 400.665062 -176.115281) (xy 400.57946 -176.121312)
			(xy 400.493668 -176.1193) (xy 400.408442 -176.109264) (xy 400.324531 -176.091291) (xy 400.242671 -176.065539)
			(xy 400.163582 -176.032235) (xy 400.08796 -175.991671) (xy 400.016468 -175.944204) (xy 399.949735 -175.890251)
			(xy 399.888348 -175.830287) (xy 399.832845 -175.764837) (xy 399.783716 -175.694478) (xy 399.74139 -175.619827)
			(xy 399.706241 -175.541541) (xy 399.678578 -175.460307) (xy 399.658642 -175.37684) (xy 399.646611 -175.291872)
			(xy 399.642589 -175.206152) (xy 398.0561 -175.206152) (xy 398.0561 -177.993548) (xy 399.668492 -177.993548)
			(xy 399.668492 -176.418748) (xy 399.668931 -176.40536) (xy 399.675852 -176.379493) (xy 399.689232 -176.3563)
			(xy 399.708162 -176.337362) (xy 399.731349 -176.32397) (xy 399.757212 -176.317038) (xy 399.7706 -176.31664)
			(xy 401.3454 -176.31664) (xy 401.358794 -176.31699) (xy 401.38467 -176.323926) (xy 401.407868 -176.337324)
			(xy 401.426806 -176.356271) (xy 401.440193 -176.379475) (xy 401.447116 -176.405353) (xy 401.447508 -176.418748)
			(xy 401.447508 -177.993548) (xy 401.447113 -178.006935) (xy 401.440173 -178.032796) (xy 401.426779 -178.055979)
			(xy 401.407841 -178.074908) (xy 401.384651 -178.088292) (xy 401.358788 -178.09522) (xy 401.3454 -178.095656)
			(xy 399.7706 -178.095656) (xy 399.757219 -178.095172) (xy 399.731368 -178.088247) (xy 399.708188 -178.074869)
			(xy 399.68926 -178.05595) (xy 399.675871 -178.032777) (xy 399.668935 -178.006929) (xy 399.668492 -177.993548)
			(xy 398.0561 -177.993548) (xy 398.0561 -181.429152) (xy 399.642589 -181.429152) (xy 399.646611 -181.343432)
			(xy 399.658642 -181.258464) (xy 399.678578 -181.174997) (xy 399.706241 -181.093763) (xy 399.74139 -181.015477)
			(xy 399.783716 -180.940826) (xy 399.832845 -180.870467) (xy 399.888348 -180.805017) (xy 399.949735 -180.745053)
			(xy 400.016468 -180.6911) (xy 400.08796 -180.643633) (xy 400.163582 -180.603069) (xy 400.242671 -180.569765)
			(xy 400.324531 -180.544013) (xy 400.408442 -180.52604) (xy 400.493668 -180.516004) (xy 400.57946 -180.513992)
			(xy 400.665062 -180.520023) (xy 400.749724 -180.534043) (xy 400.832701 -180.555929) (xy 400.913264 -180.58549)
			(xy 400.990704 -180.622464) (xy 401.064343 -180.666528) (xy 401.133531 -180.717294) (xy 401.197662 -180.774315)
			(xy 401.256171 -180.837091) (xy 401.308544 -180.905071) (xy 401.354322 -180.977656) (xy 401.393102 -181.054208)
			(xy 401.424543 -181.134056) (xy 401.448369 -181.216497) (xy 401.46437 -181.300807) (xy 401.472405 -181.386245)
			(xy 401.472908 -181.429152) (xy 401.472405 -181.472059) (xy 401.46437 -181.557497) (xy 401.448369 -181.641807)
			(xy 401.424543 -181.724248) (xy 401.393102 -181.804096) (xy 401.354322 -181.880648) (xy 401.308544 -181.953233)
			(xy 401.256171 -182.021213) (xy 401.197662 -182.083989) (xy 401.133531 -182.14101) (xy 401.064343 -182.191776)
			(xy 400.990704 -182.23584) (xy 400.913264 -182.272814) (xy 400.832701 -182.302375) (xy 400.749724 -182.324261)
			(xy 400.665062 -182.338281) (xy 400.57946 -182.344312) (xy 400.493668 -182.3423) (xy 400.408442 -182.332264)
			(xy 400.324531 -182.314291) (xy 400.242671 -182.288539) (xy 400.163582 -182.255235) (xy 400.08796 -182.214671)
			(xy 400.016468 -182.167204) (xy 399.949735 -182.113251) (xy 399.888348 -182.053287) (xy 399.832845 -181.987837)
			(xy 399.783716 -181.917478) (xy 399.74139 -181.842827) (xy 399.706241 -181.764541) (xy 399.678578 -181.683307)
			(xy 399.658642 -181.59984) (xy 399.646611 -181.514872) (xy 399.642589 -181.429152) (xy 398.0561 -181.429152)
			(xy 398.0561 -183.515508) (xy 398.75714 -184.216548) (xy 399.668492 -184.216548) (xy 399.668492 -182.641748)
			(xy 399.668931 -182.62836) (xy 399.675852 -182.602493) (xy 399.689232 -182.5793) (xy 399.708162 -182.560362)
			(xy 399.731349 -182.54697) (xy 399.757212 -182.540038) (xy 399.7706 -182.53964) (xy 401.3454 -182.53964)
			(xy 401.358794 -182.53999) (xy 401.38467 -182.546926) (xy 401.407868 -182.560324) (xy 401.426806 -182.579271)
			(xy 401.440193 -182.602475) (xy 401.447116 -182.628353) (xy 401.447508 -182.641748) (xy 401.447508 -184.216548)
			(xy 401.447113 -184.229935) (xy 401.440173 -184.255796) (xy 401.426779 -184.278979) (xy 401.407841 -184.297908)
			(xy 401.384651 -184.311292) (xy 401.358788 -184.31822) (xy 401.3454 -184.318656) (xy 399.7706 -184.318656)
			(xy 399.757219 -184.318172) (xy 399.731368 -184.311247) (xy 399.708188 -184.297869) (xy 399.68926 -184.27895)
			(xy 399.675871 -184.255777) (xy 399.668935 -184.229929) (xy 399.668492 -184.216548) (xy 398.75714 -184.216548)
			(xy 399.547334 -185.006742) (xy 399.547334 -186.273694) (xy 399.24228 -186.578748) (xy 398.50568 -186.578748)
			(xy 398.42948 -186.654948) (xy 398.42948 -187.467748) (xy 398.70888 -187.747148) (xy 400.48688 -187.747148)
		)
		(stroke
			(width 0)
			(type solid)
		)
		(fill yes)
		(layer "F.Cu")
		(net "PVCCINFAON_CPU0")
	)
	(gr_poly
		(pts
			(xy 0.69215 -17.378426)
			(arc
				(start 0.700532 -17.367758)
				(mid 0.847878 -17.185221)
				(end 1.000506 -17.007078)
			)
			(xy 1.005586 -17.001236) (xy 1.017524 -16.974312)
			(arc
				(start 1.017524 -13.780008)
				(mid 1.305283 -13.085295)
				(end 1.999996 -12.797536)
			)
			(arc
				(start 11.102594 -12.797536)
				(mid 13.236139 -11.913635)
				(end 14.11986 -9.780016)
			)
			(xy 14.11986 -3.945382)
			(arc
				(start 14.100302 -3.907282)
				(mid 13.825775 -3.583115)
				(end 13.727176 -3.16992)
			)
			(arc
				(start 13.727176 -3.16992)
				(mid 13.823565 -2.761102)
				(end 14.092428 -2.4384)
			)
			(xy 14.099286 -2.433066) (xy 14.11986 -2.392934) (xy 14.11986 -1.016) (xy 80.684116 -1.016) (xy 80.684116 -2.39141)
			(xy 80.704944 -2.431796)
			(arc
				(start 80.714088 -2.438908)
				(mid 81.077921 -3.169158)
				(end 80.714088 -3.899408)
			)
			(xy 80.704944 -3.90652) (xy 80.684116 -3.946906)
			(arc
				(start 80.684116 -9.780016)
				(mid 81.568091 -11.91374)
				(end 83.70189 -12.797536)
			)
			(arc
				(start 124.102622 -12.797536)
				(mid 126.236167 -11.913635)
				(end 127.119888 -9.780016)
			)
			(arc
				(start 127.119888 -9.20115)
				(mid 126.849337 -8.906833)
				(end 126.729998 -8.525256)
			)
			(xy 126.728982 -8.512048) (xy 126.69774 -8.465566)
			(arc
				(start 126.675642 -8.460232)
				(mid 126.632162 -8.469535)
				(end 126.61265 -8.509508)
			)
			(arc
				(start 126.61265 -9.780016)
				(mid 125.877331 -11.555233)
				(end 124.102114 -12.290552)
			)
			(arc
				(start 83.70189 -12.290552)
				(mid 81.926673 -11.555233)
				(end 81.191354 -9.780016)
			)
			(xy 81.191354 -1.22682) (xy 81.19364 -1.22682)
			(arc
				(start 81.19364 -0.999998)
				(mid 81.049612 -0.652282)
				(end 80.701896 -0.508254)
			)
			(arc
				(start 14.10208 -0.508254)
				(mid 13.754364 -0.652282)
				(end 13.610336 -0.999998)
			)
			(xy 13.610336 -1.22682) (xy 13.612622 -1.22682)
			(arc
				(start 13.612622 -9.780016)
				(mid 12.877303 -11.555233)
				(end 11.102086 -12.290552)
			)
			(arc
				(start 1.999996 -12.290552)
				(mid 0.946792 -12.726804)
				(end 0.51054 -13.780008)
			)
			(xy 0.51054 -17.351756) (xy 0.669798 -17.406874)
		)
		(stroke
			(width 0)
			(type solid)
		)
		(fill yes)
		(layer "F.Cu")
		(net "GND")
	)
	(gr_poly
		(pts
			(arc
				(start 256.800096 -36.291012)
				(mid 258.932727 -35.407647)
				(end 259.816092 -33.275016)
			)
			(xy 259.817616 -32.293306) (xy 259.817616 -32.275018) (xy 259.817616 -27.790902) (xy 259.804662 -27.762962)
			(arc
				(start 259.799074 -27.75712)
				(mid 259.645885 -27.588073)
				(end 259.497576 -27.414728)
			)
			(xy 259.490464 -27.406092)
			(arc
				(start 259.451348 -27.387804)
				(mid 259.442973 -27.388499)
				(end 259.434838 -27.390598)
			)
			(arc
				(start 259.34416 -27.42311)
				(mid 259.319865 -27.441694)
				(end 259.310632 -27.470862)
			)
			(arc
				(start 259.310632 -32.275018)
				(mid 259.308727 -32.775015)
				(end 259.308092 -33.275016)
			)
			(arc
				(start 259.308092 -33.275016)
				(mid 258.573517 -35.048437)
				(end 256.800096 -35.783012)
			)
			(arc
				(start 225.300032 -35.783012)
				(mid 223.526611 -35.048437)
				(end 222.792036 -33.275016)
			)
			(arc
				(start 222.792036 -33.275016)
				(mid 222.790131 -32.775019)
				(end 222.789496 -32.275018)
			)
			(arc
				(start 222.789496 -13.780008)
				(mid 222.353244 -12.726804)
				(end 221.30004 -12.290552)
			)
			(arc
				(start 196.701918 -12.290552)
				(mid 194.926701 -11.555233)
				(end 194.191382 -9.780016)
			)
			(xy 194.191382 -6.6167) (xy 194.193668 -6.6167)
			(arc
				(start 194.193668 -6.279896)
				(mid 194.04964 -5.93218)
				(end 193.701924 -5.788152)
			)
			(arc
				(start 127.102108 -5.788152)
				(mid 126.754392 -5.93218)
				(end 126.610364 -6.279896)
			)
			(xy 126.610364 -6.6167) (xy 126.61265 -6.6167)
			(arc
				(start 126.61265 -7.742428)
				(mid 126.632138 -7.782431)
				(end 126.675642 -7.791704)
			)
			(xy 126.687072 -7.78891)
			(arc
				(start 126.692406 -7.786116)
				(mid 126.776788 -7.754853)
				(end 126.866142 -7.744206)
			)
			(arc
				(start 126.86665 -7.744206)
				(mid 126.931475 -7.749794)
				(end 126.994412 -7.766304)
			)
			(arc
				(start 126.994412 -7.766304)
				(mid 127.018761 -7.768701)
				(end 127.041402 -7.759446)
			)
			(xy 127.087884 -7.721854) (xy 127.094234 -7.717028) (xy 127.099314 -7.713218) (xy 127.119888 -7.672832)
			(xy 127.119888 -6.897624) (xy 127.11811 -6.895846) (xy 127.11811 -6.295898) (xy 193.684144 -6.295898)
			(xy 193.684144 -7.673086) (xy 193.704718 -7.713218)
			(arc
				(start 193.712592 -7.719314)
				(mid 194.076628 -8.449818)
				(end 193.712592 -9.180322)
			)
			(xy 193.704718 -9.186418) (xy 193.684144 -9.22655)
			(arc
				(start 193.684144 -9.780016)
				(mid 193.705812 -10.141002)
				(end 193.770504 -10.496804)
			)
			(arc
				(start 193.770504 -10.496804)
				(mid 193.775484 -10.507844)
				(end 193.78295 -10.517378)
			)
			(arc
				(start 194.0941 -10.828528)
				(mid 194.174123 -10.948341)
				(end 194.202304 -11.08964)
			)
			(arc
				(start 194.202304 -11.4554)
				(mid 194.203953 -11.467988)
				(end 194.208654 -11.479784)
			)
			(arc
				(start 194.208654 -11.479784)
				(mid 195.291874 -12.447852)
				(end 196.701918 -12.797536)
			)
			(arc
				(start 221.30004 -12.797536)
				(mid 221.994753 -13.085295)
				(end 222.282512 -13.780008)
			)
			(xy 222.282512 -32.275018)
			(arc
				(start 222.284036 -33.275016)
				(mid 223.167401 -35.407647)
				(end 225.300032 -36.291012)
			)
		)
		(stroke
			(width 0)
			(type solid)
		)
		(fill yes)
		(layer "F.Cu")
		(net "GND")
	)
	(gr_poly
		(pts
			(xy 189.55512 -401.574) (xy 189.55512 -401.06854) (xy 190.13932 -400.48434) (xy 192.28054 -400.48434)
			(xy 194.3608 -398.40408) (xy 196.6722 -398.40408) (xy 198.0565 -399.78838) (xy 198.0565 -400.48688)
			(xy 198.25208 -400.68246) (xy 202.04938 -400.68246) (xy 202.21702 -400.8501) (xy 202.21702 -401.5994)
			(xy 202.21956 -401.60194) (xy 202.70978 -401.60194) (xy 202.819 -401.49272) (xy 202.819 -400.51228)
			(xy 204.3684 -398.96288) (xy 207.29956 -398.96288) (xy 209.0166 -400.67992) (xy 212.7631 -400.67992)
			(xy 212.88502 -400.80184) (xy 212.88502 -401.5994) (xy 212.8901 -401.60448) (xy 213.34222 -401.60448)
			(xy 213.46922 -401.47748) (xy 213.46922 -400.44878) (xy 215.0618 -398.8562) (xy 217.95994 -398.8562)
			(xy 219.60078 -400.49704) (xy 219.60078 -400.63674) (xy 219.64142 -400.67738) (xy 223.4946 -400.67738)
			(xy 223.55048 -400.73326) (xy 223.55048 -401.59432) (xy 223.56064 -401.60448) (xy 224.03816 -401.60448)
			(xy 224.14484 -401.4978) (xy 224.14484 -400.52498) (xy 225.63328 -399.03654) (xy 228.7397 -399.03654)
			(xy 230.38308 -400.67992) (xy 234.08132 -400.67992) (xy 234.21848 -400.81708) (xy 234.21848 -401.59432)
			(xy 234.2261 -401.60194) (xy 234.69854 -401.60194) (xy 234.81538 -401.4851) (xy 234.81538 -401.03044)
			(xy 235.43387 -400.41195) (xy 238.85779 -400.41195) (xy 239.0775 -400.19224) (xy 239.0775 -396.76832)
			(xy 239.45342 -396.3924) (xy 243.2685 -396.3924) (xy 243.3574 -396.3035) (xy 243.3574 -393.57808)
			(xy 243.55552 -393.37996) (xy 245.71198 -393.37996) (xy 245.90248 -393.57046) (xy 245.90248 -396.31874)
			(xy 246.00154 -396.4178) (xy 249.18924 -396.4178) (xy 249.2756 -396.33144) (xy 249.2756 -393.55522)
			(xy 249.44324 -393.38758) (xy 251.70638 -393.38758) (xy 251.84354 -393.52474) (xy 251.84354 -396.30096)
			(xy 251.93498 -396.3924) (xy 254.313436 -396.3924) (xy 254.313436 -396.38986) (xy 255.15062 -396.38986)
			(xy 255.2192 -396.32128) (xy 255.2192 -393.5222) (xy 255.36144 -393.37996) (xy 257.63474 -393.37996)
			(xy 257.8354 -393.58062) (xy 257.8354 -396.31366) (xy 257.91414 -396.3924) (xy 261.06882 -396.3924)
			(xy 261.1628 -396.29842) (xy 261.1628 -393.55522) (xy 261.4041 -393.31392) (xy 263.43864 -393.31392)
			(xy 263.7282 -393.60348) (xy 263.7282 -396.23746) (xy 263.88314 -396.3924) (xy 266.99464 -396.3924)
			(xy 267.1064 -396.28064) (xy 267.1064 -393.48664) (xy 267.34516 -393.24788) (xy 269.33144 -393.24788)
			(xy 269.63878 -393.55522) (xy 269.63878 -396.3035) (xy 269.72768 -396.3924) (xy 272.90522 -396.3924)
			(xy 272.9992 -396.29842) (xy 272.9992 -393.53236) (xy 273.29384 -393.23772) (xy 275.30552 -393.23772)
			(xy 275.56206 -393.49426) (xy 275.56206 -396.26032) (xy 275.69414 -396.3924) (xy 276.783292 -396.3924)
			(xy 276.783292 -396.38986) (xy 276.785832 -396.3924) (xy 278.053292 -396.3924) (xy 278.053292 -396.3797)
			(xy 278.80818 -396.3797) (xy 278.9428 -396.24508) (xy 278.9428 -385.8387) (xy 280.42235 -384.35915)
			(xy 413.7152 -384.35915) (xy 417.598098 -380.476252) (xy 417.598098 -370.037868) (xy 417.42106 -369.86083)
			(xy 388.126478 -369.86083) (xy 385.360672 -372.626636) (xy 385.353275 -372.633485) (xy 385.334676 -372.641219)
			(xy 385.324604 -372.641622) (xy 347.784674 -372.641622) (xy 345.258898 -370.115846) (xy 345.258898 -355.14661)
			(xy 345.22156 -355.109272) (xy 335.03108 -355.109272) (xy 335.020583 -355.110105) (xy 335.001569 -355.119101)
			(xy 334.987748 -355.134957) (xy 334.98409 -355.144832) (xy 334.952581 -355.242987) (xy 334.883005 -355.437068)
			(xy 334.806042 -355.628339) (xy 334.721807 -355.816521) (xy 334.630421 -356.001337) (xy 334.532021 -356.182515)
			(xy 334.42675 -356.359789) (xy 334.314763 -356.532898) (xy 334.196224 -356.701589) (xy 334.071308 -356.865614)
			(xy 333.940198 -357.024731) (xy 333.803087 -357.178707) (xy 333.660176 -357.327315) (xy 333.511675 -357.470338)
			(xy 333.357802 -357.607565) (xy 333.198784 -357.738795) (xy 333.034853 -357.863834) (xy 332.866251 -357.9825)
			(xy 332.693226 -358.094617) (xy 332.516031 -358.200021) (xy 332.334927 -358.298558) (xy 332.150181 -358.390082)
			(xy 331.962062 -358.474459) (xy 331.770848 -358.551565) (xy 331.57682 -358.621287) (xy 331.380263 -358.683522)
			(xy 331.181465 -358.73818) (xy 330.980718 -358.785179) (xy 330.778318 -358.82445) (xy 330.574562 -358.855937)
			(xy 330.369748 -358.879592) (xy 330.164179 -358.895381) (xy 329.958155 -358.90328) (xy 329.855068 -358.903778)
			(xy 329.752506 -358.903285) (xy 329.547532 -358.895448) (xy 329.343006 -358.879801) (xy 329.139225 -358.856368)
			(xy 328.936486 -358.825182) (xy 328.735083 -358.786289) (xy 328.53531 -358.739745) (xy 328.337457 -358.685618)
			(xy 328.141811 -358.623986) (xy 327.948657 -358.55494) (xy 327.853294 -358.51719) (xy 327.84872 -358.515484)
			(xy 327.839125 -358.513688) (xy 327.834244 -358.513634) (xy 309.852314 -358.513634) (xy 309.27802 -359.087928)
			(xy 309.27802 -367.73739) (xy 307.873146 -369.142264) (xy 307.837078 -369.15725) (xy 305.203352 -371.790976)
			(xy 305.203352 -375.115836) (xy 303.530508 -376.78868) (xy 290.87064 -376.78868) (xy 290.25596 -376.174)
			(xy 290.25596 -375.63044) (xy 290.2966 -375.5898) (xy 290.2966 -370.7384) (xy 289.9918 -370.4336)
			(xy 199.69988 -370.4336) (xy 186.386044 -383.747436) (xy 271.90979 -383.747436) (xy 271.90979 -383.662764)
			(xy 271.917838 -383.578474) (xy 271.933863 -383.495332) (xy 271.957718 -383.414089) (xy 271.989188 -383.335481)
			(xy 272.027987 -383.260221) (xy 272.073765 -383.18899) (xy 272.126106 -383.122432) (xy 272.184537 -383.061152)
			(xy 272.248528 -383.005703) (xy 272.317501 -382.956588) (xy 272.390829 -382.914252) (xy 272.46785 -382.879077)
			(xy 272.547866 -382.851383) (xy 272.630152 -382.831421) (xy 272.713963 -382.819371) (xy 272.79854 -382.815342)
			(xy 272.883117 -382.819371) (xy 272.966928 -382.831421) (xy 273.049214 -382.851383) (xy 273.12923 -382.879077)
			(xy 273.206251 -382.914252) (xy 273.279579 -382.956588) (xy 273.348552 -383.005703) (xy 273.412543 -383.061152)
			(xy 273.470974 -383.122432) (xy 273.523315 -383.18899) (xy 273.569093 -383.260221) (xy 273.607892 -383.335481)
			(xy 273.639362 -383.414089) (xy 273.663217 -383.495332) (xy 273.679242 -383.578474) (xy 273.68729 -383.662764)
			(xy 273.687794 -383.7051) (xy 273.68729 -383.747436) (xy 273.679242 -383.831726) (xy 273.663217 -383.914868)
			(xy 273.639362 -383.996111) (xy 273.607892 -384.074719) (xy 273.569093 -384.149979) (xy 273.523315 -384.22121)
			(xy 273.470974 -384.287768) (xy 273.412543 -384.349048) (xy 273.348552 -384.404497) (xy 273.279579 -384.453612)
			(xy 273.206251 -384.495948) (xy 273.12923 -384.531123) (xy 273.049214 -384.558817) (xy 272.966928 -384.578779)
			(xy 272.883117 -384.590829) (xy 272.79854 -384.594858) (xy 272.713963 -384.590829) (xy 272.630152 -384.578779)
			(xy 272.547866 -384.558817) (xy 272.46785 -384.531123) (xy 272.390829 -384.495948) (xy 272.317501 -384.453612)
			(xy 272.248528 -384.404497) (xy 272.184537 -384.349048) (xy 272.126106 -384.287768) (xy 272.073765 -384.22121)
			(xy 272.027987 -384.149979) (xy 271.989188 -384.074719) (xy 271.957718 -383.996111) (xy 271.933863 -383.914868)
			(xy 271.917838 -383.831726) (xy 271.90979 -383.747436) (xy 186.386044 -383.747436) (xy 185.25236 -384.88112)
			(xy 185.25236 -386.144688) (xy 269.992598 -386.144688) (xy 269.992598 -386.060016) (xy 270.000646 -385.975726)
			(xy 270.016671 -385.892584) (xy 270.040526 -385.811341) (xy 270.071996 -385.732733) (xy 270.110795 -385.657473)
			(xy 270.156573 -385.586242) (xy 270.208914 -385.519684) (xy 270.267345 -385.458404) (xy 270.331336 -385.402955)
			(xy 270.400309 -385.35384) (xy 270.473637 -385.311504) (xy 270.550658 -385.276329) (xy 270.630674 -385.248635)
			(xy 270.71296 -385.228673) (xy 270.796771 -385.216623) (xy 270.881348 -385.212594) (xy 270.965925 -385.216623)
			(xy 271.049736 -385.228673) (xy 271.132022 -385.248635) (xy 271.212038 -385.276329) (xy 271.289059 -385.311504)
			(xy 271.362387 -385.35384) (xy 271.43136 -385.402955) (xy 271.495351 -385.458404) (xy 271.553782 -385.519684)
			(xy 271.606123 -385.586242) (xy 271.651901 -385.657473) (xy 271.6907 -385.732733) (xy 271.72217 -385.811341)
			(xy 271.746025 -385.892584) (xy 271.76205 -385.975726) (xy 271.770098 -386.060016) (xy 271.770602 -386.102352)
			(xy 271.770098 -386.144688) (xy 271.76205 -386.228978) (xy 271.746025 -386.31212) (xy 271.72217 -386.393363)
			(xy 271.6907 -386.471971) (xy 271.651901 -386.547231) (xy 271.606123 -386.618462) (xy 271.553782 -386.68502)
			(xy 271.495351 -386.7463) (xy 271.43136 -386.801749) (xy 271.362387 -386.850864) (xy 271.289059 -386.8932)
			(xy 271.212038 -386.928375) (xy 271.132022 -386.956069) (xy 271.049736 -386.976031) (xy 270.965925 -386.988081)
			(xy 270.881348 -386.99211) (xy 270.796771 -386.988081) (xy 270.71296 -386.976031) (xy 270.630674 -386.956069)
			(xy 270.550658 -386.928375) (xy 270.473637 -386.8932) (xy 270.400309 -386.850864) (xy 270.331336 -386.801749)
			(xy 270.267345 -386.7463) (xy 270.208914 -386.68502) (xy 270.156573 -386.618462) (xy 270.110795 -386.547231)
			(xy 270.071996 -386.471971) (xy 270.040526 -386.393363) (xy 270.016671 -386.31212) (xy 270.000646 -386.228978)
			(xy 269.992598 -386.144688) (xy 185.25236 -386.144688) (xy 185.25236 -389.67537) (xy 233.572558 -389.67537)
			(xy 233.572558 -386.94995) (xy 234.19943 -386.323078) (xy 238.84763 -386.323078) (xy 239.144302 -386.61975)
			(xy 239.144302 -389.58139) (xy 238.77651 -389.949182) (xy 233.84637 -389.949182) (xy 233.572558 -389.67537)
			(xy 185.25236 -389.67537) (xy 185.25236 -396.90294) (xy 185.93308 -397.58366) (xy 185.93308 -398.9832)
			(xy 185.58002 -399.33626) (xy 185.58002 -400.06778) (xy 185.34634 -400.30146) (xy 185.34634 -400.6596)
			(xy 185.36158 -400.67484) (xy 188.83376 -400.67484) (xy 188.9506 -400.79168) (xy 188.9506 -401.70354)
			(xy 188.95822 -401.71116) (xy 189.41796 -401.71116)
		)
		(stroke
			(width 0)
			(type solid)
		)
		(fill yes)
		(layer "F.Cu")
		(net "P12V_AUX")
	)
	(gr_poly
		(pts
			(arc
				(start 471.25509 -17.363694)
				(mid 471.279904 -17.345175)
				(end 471.28938 -17.315688)
			)
			(arc
				(start 471.28938 -13.780008)
				(mid 470.853128 -12.726804)
				(end 469.799924 -12.290552)
			)
			(arc
				(start 458.20203 -12.290552)
				(mid 456.426813 -11.555233)
				(end 455.691494 -9.780016)
			)
			(xy 455.691494 -1.26492) (xy 455.69378 -1.26492)
			(arc
				(start 455.69378 -0.999998)
				(mid 455.549752 -0.652282)
				(end 455.202036 -0.508254)
			)
			(arc
				(start 388.601966 -0.508254)
				(mid 388.25425 -0.652282)
				(end 388.110222 -0.999998)
			)
			(xy 388.110222 -1.26492) (xy 388.112508 -1.26492)
			(arc
				(start 388.112508 -9.780016)
				(mid 387.377189 -11.555233)
				(end 385.601972 -12.290552)
			)
			(arc
				(start 260.800088 -12.290552)
				(mid 259.746884 -12.726804)
				(end 259.310632 -13.780008)
			)
			(arc
				(start 259.310632 -17.128998)
				(mid 259.319848 -17.158177)
				(end 259.34416 -17.17675)
			)
			(arc
				(start 259.434076 -17.209008)
				(mid 259.44258 -17.211273)
				(end 259.451348 -17.212056)
			)
			(arc
				(start 259.490464 -17.193768)
				(mid 259.644793 -17.013259)
				(end 259.804408 -16.837406)
			)
			(xy 259.817616 -16.808958)
			(arc
				(start 259.817616 -13.780008)
				(mid 260.105375 -13.085295)
				(end 260.800088 -12.797536)
			)
			(arc
				(start 296.924222 -12.797536)
				(mid 296.940299 -12.792794)
				(end 296.95394 -12.783058)
			)
			(arc
				(start 297.069002 -12.667996)
				(mid 297.172472 -12.598796)
				(end 297.294554 -12.574524)
			)
			(arc
				(start 299.96511 -12.574524)
				(mid 300.087181 -12.598823)
				(end 300.190662 -12.667996)
			)
			(arc
				(start 300.305724 -12.783058)
				(mid 300.31937 -12.792784)
				(end 300.335442 -12.797536)
			)
			(arc
				(start 319.519808 -12.797536)
				(mid 319.535885 -12.792794)
				(end 319.549526 -12.783058)
			)
			(arc
				(start 319.583054 -12.74953)
				(mid 319.599588 -12.738419)
				(end 319.619122 -12.734544)
			)
			(arc
				(start 321.966336 -12.734544)
				(mid 321.985859 -12.738445)
				(end 322.002404 -12.74953)
			)
			(arc
				(start 322.035932 -12.783058)
				(mid 322.049578 -12.792784)
				(end 322.06565 -12.797536)
			)
			(arc
				(start 322.595748 -12.797536)
				(mid 322.611825 -12.792794)
				(end 322.625466 -12.783058)
			)
			(arc
				(start 322.71081 -12.697714)
				(mid 322.727344 -12.686603)
				(end 322.746878 -12.682728)
			)
			(arc
				(start 326.9234 -12.682728)
				(mid 326.942923 -12.686629)
				(end 326.959468 -12.697714)
			)
			(arc
				(start 327.044812 -12.783058)
				(mid 327.058458 -12.792784)
				(end 327.07453 -12.797536)
			)
			(arc
				(start 344.356944 -12.797536)
				(mid 344.373021 -12.792794)
				(end 344.386662 -12.783058)
			)
			(arc
				(start 344.532458 -12.637008)
				(mid 344.627565 -12.573493)
				(end 344.739722 -12.551156)
			)
			(arc
				(start 360.019854 -12.551156)
				(mid 360.131999 -12.573521)
				(end 360.227118 -12.637008)
			)
			(arc
				(start 360.372914 -12.783058)
				(mid 360.38656 -12.792784)
				(end 360.402632 -12.797536)
			)
			(arc
				(start 385.601972 -12.797536)
				(mid 387.735681 -11.913725)
				(end 388.619492 -9.780016)
			)
			(xy 388.619492 -3.928364)
			(arc
				(start 388.614158 -3.917442)
				(mid 388.329377 -3.590886)
				(end 388.226808 -3.16992)
			)
			(arc
				(start 388.226808 -3.16992)
				(mid 388.275543 -2.875216)
				(end 388.416546 -2.611882)
			)
			(arc
				(start 388.416546 -2.611882)
				(mid 388.501545 -2.513276)
				(end 388.59968 -2.427732)
			)
			(xy 388.619492 -2.388108) (xy 388.619492 -1.016) (xy 455.184256 -1.016) (xy 455.184256 -2.375154)
			(arc
				(start 455.205338 -2.416048)
				(mid 455.573689 -3.012402)
				(end 455.41184 -3.69443)
			)
			(arc
				(start 455.41184 -3.69443)
				(mid 455.315091 -3.810755)
				(end 455.200512 -3.909568)
			)
			(xy 455.184256 -3.941318)
			(arc
				(start 455.184256 -9.780016)
				(mid 456.068231 -11.91374)
				(end 458.20203 -12.797536)
			)
			(arc
				(start 469.799924 -12.797536)
				(mid 470.494637 -13.085295)
				(end 470.782396 -13.780008)
			)
			(xy 470.782396 -16.974312)
			(arc
				(start 470.794588 -17.001744)
				(mid 470.954063 -17.187687)
				(end 471.10777 -17.378426)
			)
			(xy 471.117676 -17.391126) (xy 471.148664 -17.400524)
		)
		(stroke
			(width 0)
			(type solid)
		)
		(fill yes)
		(layer "F.Cu")
		(net "GND")
	)
	(gr_poly
		(pts
			(xy 172.786294 -380.14529) (xy 173.531784 -379.3998) (xy 173.531784 -361.754928) (xy 172.537628 -360.760772)
			(xy 169.7228 -360.760772) (xy 161.926524 -368.557048) (xy 167.537128 -368.557048) (xy 167.541201 -368.501389)
			(xy 167.553336 -368.446916) (xy 167.573272 -368.39479) (xy 167.600586 -368.346122) (xy 167.634694 -368.30195)
			(xy 167.674871 -368.263215) (xy 167.720259 -368.230743) (xy 167.769891 -368.205225) (xy 167.822711 -368.187206)
			(xy 167.87759 -368.177069) (xy 167.933361 -368.175031) (xy 167.988835 -368.181134) (xy 168.042828 -368.19525)
			(xy 168.094191 -368.217077) (xy 168.141829 -368.24615) (xy 168.184725 -368.281849) (xy 168.221967 -368.323413)
			(xy 168.252761 -368.369957) (xy 168.276449 -368.420488) (xy 168.292527 -368.47393) (xy 168.300653 -368.529144)
			(xy 168.301162 -368.557048) (xy 168.300653 -368.584952) (xy 168.292527 -368.640166) (xy 168.276449 -368.693608)
			(xy 168.252761 -368.744139) (xy 168.221967 -368.790683) (xy 168.184725 -368.832247) (xy 168.141829 -368.867946)
			(xy 168.094191 -368.897019) (xy 168.042828 -368.918846) (xy 167.988835 -368.932962) (xy 167.933361 -368.939065)
			(xy 167.87759 -368.937027) (xy 167.822711 -368.92689) (xy 167.769891 -368.908871) (xy 167.720259 -368.883353)
			(xy 167.674871 -368.850881) (xy 167.634694 -368.812146) (xy 167.600586 -368.767974) (xy 167.573272 -368.719306)
			(xy 167.553336 -368.66718) (xy 167.541201 -368.612707) (xy 167.537128 -368.557048) (xy 161.926524 -368.557048)
			(xy 156.93517 -373.548402) (xy 102.117398 -373.548402) (xy 102.107328 -373.547978) (xy 102.088724 -373.540264)
			(xy 102.08133 -373.533416) (xy 96.37395 -367.826036) (xy 96.367108 -367.818636) (xy 96.359389 -367.800038)
			(xy 96.358964 -367.789968) (xy 96.358964 -360.793284) (xy 98.398838 -358.75341) (xy 98.398838 -355.091238)
			(xy 98.321368 -355.013768) (xy 87.201248 -355.013768) (xy 87.103204 -355.111812) (xy 87.099394 -355.12375)
			(xy 87.068104 -355.223494) (xy 86.998835 -355.420757) (xy 86.922018 -355.615205) (xy 86.837768 -355.806549)
			(xy 86.746208 -355.994505) (xy 86.647476 -356.178795) (xy 86.541718 -356.359145) (xy 86.42909 -356.535286)
			(xy 86.309761 -356.706958) (xy 86.183906 -356.873905) (xy 86.051714 -357.03588) (xy 85.91338 -357.192643)
			(xy 85.769109 -357.34396) (xy 85.619117 -357.489606) (xy 85.463625 -357.629367) (xy 85.302864 -357.763033)
			(xy 85.137073 -357.890407) (xy 84.966499 -358.0113) (xy 84.791393 -358.125532) (xy 84.612017 -358.232934)
			(xy 84.428637 -358.333345) (xy 84.241525 -358.426618) (xy 84.050958 -358.512613) (xy 83.85722 -358.591203)
			(xy 83.660599 -358.662271) (xy 83.461385 -358.725711) (xy 83.259876 -358.781431) (xy 83.056369 -358.829346)
			(xy 82.851168 -358.869385) (xy 82.644576 -358.90149) (xy 82.436901 -358.925612) (xy 82.228451 -358.941717)
			(xy 82.019536 -358.949778) (xy 81.915 -358.95026) (xy 75.278488 -358.95026) (xy 75.25004 -358.978708)
			(xy 65.59042 -358.978708) (xy 65.12052 -359.448608) (xy 65.12052 -363.487208) (xy 57.80278 -370.804948)
			(xy 43.815 -370.804948) (xy 42.342562 -369.33251) (xy 42.342562 -368.662204) (xy 42.335196 -368.650012)
			(xy 42.331719 -368.643896) (xy 42.327862 -368.630372) (xy 42.327576 -368.623342) (xy 42.327576 -364.384844)
			(xy 42.327068 -364.384336) (xy 42.327068 -361.00512) (xy 42.081958 -360.76001) (xy 35.39236 -360.76001)
			(xy 32.714692 -358.082596) (xy 32.714692 -338.21624) (xy 32.433006 -337.934554) (xy 24.652986 -337.934554)
			(xy 24.638 -337.919568) (xy 21.826728 -337.919568) (xy 21.826728 -338.605114) (xy 21.826158 -338.635293)
			(xy 21.816648 -338.694898) (xy 21.797853 -338.752256) (xy 21.784564 -338.779358) (xy 21.78177 -338.784692)
			(xy 21.775928 -338.80806) (xy 21.775928 -339.163914) (xy 21.775385 -339.180572) (xy 21.766768 -339.212755)
			(xy 21.750125 -339.241617) (xy 21.726587 -339.265195) (xy 21.697753 -339.281886) (xy 21.665585 -339.290556)
			(xy 21.648928 -339.291168) (xy 21.24202 -339.291168) (xy 21.225326 -339.290628) (xy 21.193073 -339.282)
			(xy 21.164148 -339.265325) (xy 21.140518 -339.241738) (xy 21.12379 -339.212844) (xy 21.115103 -339.180607)
			(xy 21.114512 -339.163914) (xy 21.114512 -338.80806) (xy 21.10867 -338.784692) (xy 21.105876 -338.779358)
			(xy 21.092603 -338.75225) (xy 21.073824 -338.69489) (xy 21.064292 -338.635291) (xy 21.063712 -338.605114)
			(xy 21.063712 -337.919568) (xy 17.2593 -337.919568) (xy 16.93672 -338.242148) (xy 16.93672 -343.157302)
			(xy 16.94561 -343.186004) (xy 16.949928 -343.192354) (xy 17.020509 -343.29674) (xy 17.15586 -343.509325)
			(xy 17.284448 -343.726068) (xy 17.406145 -343.946753) (xy 17.520832 -344.171161) (xy 17.628394 -344.39907)
			(xy 17.728724 -344.630254) (xy 17.821723 -344.864483) (xy 17.907299 -345.101524) (xy 17.985367 -345.341144)
			(xy 18.055849 -345.583103) (xy 18.118675 -345.827163) (xy 18.173783 -346.07308) (xy 18.221119 -346.32061)
			(xy 18.260635 -346.569509) (xy 18.292292 -346.819529) (xy 18.316059 -347.070422) (xy 18.331912 -347.321939)
			(xy 18.339836 -347.57383) (xy 18.340324 -347.699838) (xy 18.339833 -347.825846) (xy 18.331903 -348.077736)
			(xy 18.316044 -348.329252) (xy 18.292271 -348.580144) (xy 18.26061 -348.830162) (xy 18.22109 -349.079059)
			(xy 18.173752 -349.326589) (xy 18.118642 -349.572505) (xy 18.055814 -349.816563) (xy 17.985332 -350.058521)
			(xy 17.907265 -350.29814) (xy 17.821691 -350.535182) (xy 17.728694 -350.769411) (xy 17.628366 -351.000595)
			(xy 17.520808 -351.228505) (xy 17.406126 -351.452915) (xy 17.284434 -351.673602) (xy 17.155851 -351.890347)
			(xy 17.020507 -352.102935) (xy 16.949928 -352.207322) (xy 16.94561 -352.213672) (xy 16.93672 -352.242374)
			(xy 16.93672 -361.136946) (xy 15.94104 -362.132626) (xy 15.94104 -377.058428) (xy 22.101808 -377.058428)
			(xy 22.105881 -377.002769) (xy 22.118016 -376.948296) (xy 22.137952 -376.89617) (xy 22.165266 -376.847502)
			(xy 22.199374 -376.80333) (xy 22.239551 -376.764595) (xy 22.284939 -376.732123) (xy 22.334571 -376.706605)
			(xy 22.387391 -376.688586) (xy 22.44227 -376.678449) (xy 22.498041 -376.676411) (xy 22.553515 -376.682514)
			(xy 22.607508 -376.69663) (xy 22.658871 -376.718457) (xy 22.706509 -376.74753) (xy 22.749405 -376.783229)
			(xy 22.786647 -376.824793) (xy 22.817441 -376.871337) (xy 22.841129 -376.921868) (xy 22.857207 -376.97531)
			(xy 22.865333 -377.030524) (xy 22.865842 -377.058428) (xy 22.865333 -377.086332) (xy 22.857207 -377.141546)
			(xy 22.841129 -377.194988) (xy 22.817441 -377.245519) (xy 22.786647 -377.292063) (xy 22.749405 -377.333627)
			(xy 22.706509 -377.369326) (xy 22.658871 -377.398399) (xy 22.607508 -377.420226) (xy 22.553515 -377.434342)
			(xy 22.498041 -377.440445) (xy 22.44227 -377.438407) (xy 22.387391 -377.42827) (xy 22.334571 -377.410251)
			(xy 22.284939 -377.384733) (xy 22.239551 -377.352261) (xy 22.199374 -377.313526) (xy 22.165266 -377.269354)
			(xy 22.137952 -377.220686) (xy 22.118016 -377.16856) (xy 22.105881 -377.114087) (xy 22.101808 -377.058428)
			(xy 15.94104 -377.058428) (xy 15.94104 -377.947428) (xy 22.101808 -377.947428) (xy 22.105881 -377.891769)
			(xy 22.118016 -377.837296) (xy 22.137952 -377.78517) (xy 22.165266 -377.736502) (xy 22.199374 -377.69233)
			(xy 22.239551 -377.653595) (xy 22.284939 -377.621123) (xy 22.334571 -377.595605) (xy 22.387391 -377.577586)
			(xy 22.44227 -377.567449) (xy 22.498041 -377.565411) (xy 22.553515 -377.571514) (xy 22.607508 -377.58563)
			(xy 22.658871 -377.607457) (xy 22.706509 -377.63653) (xy 22.749405 -377.672229) (xy 22.786647 -377.713793)
			(xy 22.817441 -377.760337) (xy 22.841129 -377.810868) (xy 22.857207 -377.86431) (xy 22.865333 -377.919524)
			(xy 22.865842 -377.947428) (xy 22.865333 -377.975332) (xy 22.857207 -378.030546) (xy 22.841129 -378.083988)
			(xy 22.817441 -378.134519) (xy 22.786647 -378.181063) (xy 22.749405 -378.222627) (xy 22.706509 -378.258326)
			(xy 22.658871 -378.287399) (xy 22.607508 -378.309226) (xy 22.553515 -378.323342) (xy 22.498041 -378.329445)
			(xy 22.44227 -378.327407) (xy 22.387391 -378.31727) (xy 22.334571 -378.299251) (xy 22.284939 -378.273733)
			(xy 22.239551 -378.241261) (xy 22.199374 -378.202526) (xy 22.165266 -378.158354) (xy 22.137952 -378.109686)
			(xy 22.118016 -378.05756) (xy 22.105881 -378.003087) (xy 22.101808 -377.947428) (xy 15.94104 -377.947428)
			(xy 15.94104 -378.836428) (xy 22.101808 -378.836428) (xy 22.105881 -378.780769) (xy 22.118016 -378.726296)
			(xy 22.137952 -378.67417) (xy 22.165266 -378.625502) (xy 22.199374 -378.58133) (xy 22.239551 -378.542595)
			(xy 22.284939 -378.510123) (xy 22.334571 -378.484605) (xy 22.387391 -378.466586) (xy 22.44227 -378.456449)
			(xy 22.498041 -378.454411) (xy 22.553515 -378.460514) (xy 22.607508 -378.47463) (xy 22.658871 -378.496457)
			(xy 22.706509 -378.52553) (xy 22.749405 -378.561229) (xy 22.786647 -378.602793) (xy 22.817441 -378.649337)
			(xy 22.841129 -378.699868) (xy 22.857207 -378.75331) (xy 22.865333 -378.808524) (xy 22.865842 -378.836428)
			(xy 22.865333 -378.864332) (xy 22.857207 -378.919546) (xy 22.841129 -378.972988) (xy 22.817441 -379.023519)
			(xy 22.786647 -379.070063) (xy 22.749405 -379.111627) (xy 22.706509 -379.147326) (xy 22.658871 -379.176399)
			(xy 22.618507 -379.193552) (xy 23.003762 -379.193552) (xy 23.007835 -379.137893) (xy 23.01997 -379.08342)
			(xy 23.039906 -379.031294) (xy 23.06722 -378.982626) (xy 23.101328 -378.938454) (xy 23.141505 -378.899719)
			(xy 23.186893 -378.867247) (xy 23.236525 -378.841729) (xy 23.289345 -378.82371) (xy 23.344224 -378.813573)
			(xy 23.399995 -378.811535) (xy 23.455469 -378.817638) (xy 23.509462 -378.831754) (xy 23.560825 -378.853581)
			(xy 23.608463 -378.882654) (xy 23.651359 -378.918353) (xy 23.688601 -378.959917) (xy 23.719395 -379.006461)
			(xy 23.743083 -379.056992) (xy 23.759161 -379.110434) (xy 23.767287 -379.165648) (xy 23.767796 -379.193552)
			(xy 23.767287 -379.221456) (xy 23.759161 -379.27667) (xy 23.743083 -379.330112) (xy 23.719395 -379.380643)
			(xy 23.688601 -379.427187) (xy 23.651359 -379.468751) (xy 23.608463 -379.50445) (xy 23.560825 -379.533523)
			(xy 23.509462 -379.55535) (xy 23.455469 -379.569466) (xy 23.399995 -379.575569) (xy 23.344224 -379.573531)
			(xy 23.289345 -379.563394) (xy 23.236525 -379.545375) (xy 23.186893 -379.519857) (xy 23.141505 -379.487385)
			(xy 23.101328 -379.44865) (xy 23.06722 -379.404478) (xy 23.039906 -379.35581) (xy 23.01997 -379.303684)
			(xy 23.007835 -379.249211) (xy 23.003762 -379.193552) (xy 22.618507 -379.193552) (xy 22.607508 -379.198226)
			(xy 22.553515 -379.212342) (xy 22.498041 -379.218445) (xy 22.44227 -379.216407) (xy 22.387391 -379.20627)
			(xy 22.334571 -379.188251) (xy 22.284939 -379.162733) (xy 22.239551 -379.130261) (xy 22.199374 -379.091526)
			(xy 22.165266 -379.047354) (xy 22.137952 -378.998686) (xy 22.118016 -378.94656) (xy 22.105881 -378.892087)
			(xy 22.101808 -378.836428) (xy 15.94104 -378.836428) (xy 15.94104 -379.410468) (xy 16.70812 -380.177548)
			(xy 22.18563 -380.177548) (xy 22.246082 -380.02591) (xy 22.22119 -380.002288) (xy 22.202755 -379.984201)
			(xy 22.170433 -379.94392) (xy 22.14384 -379.899648) (xy 22.12346 -379.852194) (xy 22.109666 -379.802425)
			(xy 22.10271 -379.751251) (xy 22.102318 -379.725428) (xy 22.102804 -379.698159) (xy 22.110566 -379.644175)
			(xy 22.125931 -379.591845) (xy 22.148588 -379.542235) (xy 22.178074 -379.496354) (xy 22.213789 -379.455137)
			(xy 22.255006 -379.419422) (xy 22.300887 -379.389936) (xy 22.350497 -379.367279) (xy 22.402827 -379.351914)
			(xy 22.456811 -379.344152) (xy 22.511349 -379.344152) (xy 22.565333 -379.351914) (xy 22.617663 -379.367279)
			(xy 22.667273 -379.389936) (xy 22.713154 -379.419422) (xy 22.754371 -379.455137) (xy 22.790086 -379.496354)
			(xy 22.819572 -379.542235) (xy 22.842229 -379.591845) (xy 22.857594 -379.644175) (xy 22.865356 -379.698159)
			(xy 22.865842 -379.725428) (xy 22.865413 -379.751248) (xy 22.858451 -379.802418) (xy 22.844658 -379.852183)
			(xy 22.824286 -379.899636) (xy 22.797705 -379.943911) (xy 22.765401 -379.9842) (xy 22.74697 -380.002288)
			(xy 22.722078 -380.02591) (xy 22.78253 -380.177548) (xy 35.95624 -380.177548) (xy 36.196524 -380.417832)
			(xy 36.196778 -380.417832) (xy 37.248084 -381.468884) (xy 165.82136 -381.468884)
		)
		(stroke
			(width 0)
			(type solid)
		)
		(fill yes)
		(layer "F.Cu")
		(net "P12V_AUX")
	)
	(gr_poly
		(pts
			(xy 72.082152 -160.746948) (xy 72.226932 -160.746948) (xy 72.263 -160.71088) (xy 72.620632 -160.71088)
			(xy 72.63003 -160.70707) (xy 72.648889 -160.699705) (xy 72.687689 -160.688131) (xy 72.7075 -160.683956)
			(xy 72.748394 -160.634172) (xy 72.70877 -160.584642) (xy 72.680912 -160.577902) (xy 72.627466 -160.5572)
			(xy 72.577719 -160.528734) (xy 72.532791 -160.493148) (xy 72.493691 -160.45124) (xy 72.461301 -160.403955)
			(xy 72.436349 -160.352357) (xy 72.419397 -160.297606) (xy 72.410826 -160.240936) (xy 72.41032 -160.212278)
			(xy 72.410785 -160.185027) (xy 72.418545 -160.13108) (xy 72.433903 -160.078786) (xy 72.456547 -160.029211)
			(xy 72.486016 -159.983362) (xy 72.52171 -159.942175) (xy 72.562902 -159.906486) (xy 72.608755 -159.877023)
			(xy 72.658333 -159.854385) (xy 72.710629 -159.839034) (xy 72.764577 -159.831281) (xy 72.791828 -159.83077)
			(xy 72.822533 -159.831403) (xy 72.883144 -159.841276) (xy 72.941392 -159.86073) (xy 72.995771 -159.889263)
			(xy 73.020682 -159.907224) (xy 73.249028 -159.907224) (xy 73.265253 -159.890604) (xy 73.303139 -159.863749)
			(xy 73.345705 -159.845184) (xy 73.391163 -159.835689) (xy 73.414382 -159.835088) (xy 73.681844 -159.835088)
			(xy 73.736454 -159.857694) (xy 74.0664 -159.527748) (xy 74.0664 -157.267148) (xy 73.152 -156.352748)
			(xy 73.152 -145.01241) (xy 73.133712 -144.982692) (xy 73.021444 -144.982692) (xy 73.021444 -145.042636)
			(xy 72.753982 -145.042636) (xy 72.730766 -145.042035) (xy 72.685318 -145.032517) (xy 72.64276 -145.013945)
			(xy 72.604875 -144.987096) (xy 72.588628 -144.9705) (xy 72.48779 -144.9705) (xy 72.474836 -144.97939)
			(xy 72.450837 -144.995278) (xy 72.399068 -145.020427) (xy 72.344108 -145.037512) (xy 72.287205 -145.046148)
			(xy 72.258428 -145.0467) (xy 72.231174 -145.046239) (xy 72.177222 -145.038485) (xy 72.124921 -145.023132)
			(xy 72.075339 -145.000491) (xy 72.029483 -144.971025) (xy 71.988288 -144.935332) (xy 71.952592 -144.894139)
			(xy 71.923122 -144.848286) (xy 71.900478 -144.798705) (xy 71.885121 -144.746406) (xy 71.877363 -144.692454)
			(xy 71.877363 -144.637946) (xy 71.885121 -144.583994) (xy 71.900478 -144.531695) (xy 71.923122 -144.482114)
			(xy 71.952592 -144.436261) (xy 71.988288 -144.395068) (xy 72.029483 -144.359375) (xy 72.075339 -144.329909)
			(xy 72.124921 -144.307268) (xy 72.177222 -144.291915) (xy 72.231174 -144.284161) (xy 72.258428 -144.283684)
			(xy 72.287206 -144.28421) (xy 72.344109 -144.292857) (xy 72.399067 -144.309952) (xy 72.450836 -144.335106)
			(xy 72.474836 -144.350994) (xy 72.48779 -144.359884) (xy 72.588628 -144.359884) (xy 72.604851 -144.34326)
			(xy 72.642735 -144.316398) (xy 72.685302 -144.297828) (xy 72.730762 -144.288331) (xy 72.753982 -144.287748)
			(xy 73.021444 -144.287748) (xy 73.021444 -144.347692) (xy 73.133712 -144.347692) (xy 73.152 -144.317974)
			(xy 73.152 -144.11706) (xy 73.14438 -144.104868) (xy 73.126157 -144.074602) (xy 73.095783 -144.010814)
			(xy 73.072677 -143.944049) (xy 73.057124 -143.875131) (xy 73.049317 -143.804913) (xy 73.048876 -143.769588)
			(xy 73.049383 -143.732846) (xy 73.057829 -143.65985) (xy 73.074642 -143.588316) (xy 73.099597 -143.5192)
			(xy 73.13236 -143.453426) (xy 73.152 -143.42237) (xy 73.152 -142.789148) (xy 72.9996 -142.636748)
			(xy 63.2968 -142.636748) (xy 63.146432 -142.787116) (xy 63.170308 -142.810738) (xy 63.170308 -146.228308)
			(xy 69.007995 -146.228308) (xy 69.012017 -146.142588) (xy 69.024048 -146.05762) (xy 69.043984 -145.974153)
			(xy 69.071647 -145.892919) (xy 69.106796 -145.814633) (xy 69.149122 -145.739982) (xy 69.198251 -145.669623)
			(xy 69.253754 -145.604173) (xy 69.315141 -145.544209) (xy 69.381874 -145.490256) (xy 69.453366 -145.442789)
			(xy 69.528988 -145.402225) (xy 69.608077 -145.368921) (xy 69.689937 -145.343169) (xy 69.773848 -145.325196)
			(xy 69.859074 -145.31516) (xy 69.944866 -145.313148) (xy 70.030468 -145.319179) (xy 70.11513 -145.333199)
			(xy 70.198107 -145.355085) (xy 70.27867 -145.384646) (xy 70.35611 -145.42162) (xy 70.429749 -145.465684)
			(xy 70.498937 -145.51645) (xy 70.563068 -145.573471) (xy 70.621577 -145.636247) (xy 70.67395 -145.704227)
			(xy 70.719728 -145.776812) (xy 70.758508 -145.853364) (xy 70.789949 -145.933212) (xy 70.813775 -146.015653)
			(xy 70.829776 -146.099963) (xy 70.837811 -146.185401) (xy 70.838314 -146.228308) (xy 70.837811 -146.271215)
			(xy 70.829776 -146.356653) (xy 70.813775 -146.440963) (xy 70.789949 -146.523404) (xy 70.758508 -146.603252)
			(xy 70.719728 -146.679804) (xy 70.67395 -146.752389) (xy 70.621577 -146.820369) (xy 70.563068 -146.883145)
			(xy 70.498937 -146.940166) (xy 70.429749 -146.990932) (xy 70.35611 -147.034996) (xy 70.27867 -147.07197)
			(xy 70.198107 -147.101531) (xy 70.11513 -147.123417) (xy 70.030468 -147.137437) (xy 69.944866 -147.143468)
			(xy 69.859074 -147.141456) (xy 69.773848 -147.13142) (xy 69.689937 -147.113447) (xy 69.608077 -147.087695)
			(xy 69.528988 -147.054391) (xy 69.453366 -147.013827) (xy 69.381874 -146.96636) (xy 69.315141 -146.912407)
			(xy 69.253754 -146.852443) (xy 69.198251 -146.786993) (xy 69.149122 -146.716634) (xy 69.106796 -146.641983)
			(xy 69.071647 -146.563697) (xy 69.043984 -146.482463) (xy 69.024048 -146.398996) (xy 69.012017 -146.314028)
			(xy 69.007995 -146.228308) (xy 63.170308 -146.228308) (xy 63.170308 -149.015704) (xy 69.034152 -149.015704)
			(xy 69.034152 -147.440904) (xy 69.034629 -147.427543) (xy 69.041531 -147.401729) (xy 69.054869 -147.378574)
			(xy 69.073737 -147.359652) (xy 69.096852 -147.346246) (xy 69.122647 -147.339268) (xy 69.136006 -147.338796)
			(xy 70.710806 -147.338796) (xy 70.724189 -147.33914) (xy 70.750038 -147.346082) (xy 70.773204 -147.359488)
			(xy 70.792101 -147.378443) (xy 70.805437 -147.40165) (xy 70.8123 -147.42752) (xy 70.81266 -147.440904)
			(xy 70.81266 -149.015704) (xy 70.812277 -149.029072) (xy 70.805365 -149.0549) (xy 70.792012 -149.078064)
			(xy 70.773125 -149.096988) (xy 70.749988 -149.110387) (xy 70.724173 -149.11735) (xy 70.710806 -149.117812)
			(xy 69.136006 -149.117812) (xy 69.122625 -149.117449) (xy 69.096776 -149.110511) (xy 69.073612 -149.097108)
			(xy 69.054714 -149.078157) (xy 69.041377 -149.054954) (xy 69.034513 -149.029087) (xy 69.034152 -149.015704)
			(xy 63.170308 -149.015704) (xy 63.170308 -152.364694) (xy 69.007995 -152.364694) (xy 69.012017 -152.278974)
			(xy 69.024048 -152.194006) (xy 69.043984 -152.110539) (xy 69.071647 -152.029305) (xy 69.106796 -151.951019)
			(xy 69.149122 -151.876368) (xy 69.198251 -151.806009) (xy 69.253754 -151.740559) (xy 69.315141 -151.680595)
			(xy 69.381874 -151.626642) (xy 69.453366 -151.579175) (xy 69.528988 -151.538611) (xy 69.608077 -151.505307)
			(xy 69.689937 -151.479555) (xy 69.773848 -151.461582) (xy 69.859074 -151.451546) (xy 69.944866 -151.449534)
			(xy 70.030468 -151.455565) (xy 70.11513 -151.469585) (xy 70.198107 -151.491471) (xy 70.27867 -151.521032)
			(xy 70.35611 -151.558006) (xy 70.429749 -151.60207) (xy 70.498937 -151.652836) (xy 70.563068 -151.709857)
			(xy 70.621577 -151.772633) (xy 70.67395 -151.840613) (xy 70.719728 -151.913198) (xy 70.758508 -151.98975)
			(xy 70.789949 -152.069598) (xy 70.813775 -152.152039) (xy 70.829776 -152.236349) (xy 70.837811 -152.321787)
			(xy 70.838314 -152.364694) (xy 70.837811 -152.407601) (xy 70.829776 -152.493039) (xy 70.813775 -152.577349)
			(xy 70.789949 -152.65979) (xy 70.758508 -152.739638) (xy 70.719728 -152.81619) (xy 70.67395 -152.888775)
			(xy 70.621577 -152.956755) (xy 70.563068 -153.019531) (xy 70.498937 -153.076552) (xy 70.429749 -153.127318)
			(xy 70.35611 -153.171382) (xy 70.27867 -153.208356) (xy 70.198107 -153.237917) (xy 70.11513 -153.259803)
			(xy 70.030468 -153.273823) (xy 69.944866 -153.279854) (xy 69.859074 -153.277842) (xy 69.773848 -153.267806)
			(xy 69.689937 -153.249833) (xy 69.608077 -153.224081) (xy 69.528988 -153.190777) (xy 69.453366 -153.150213)
			(xy 69.381874 -153.102746) (xy 69.315141 -153.048793) (xy 69.253754 -152.988829) (xy 69.198251 -152.923379)
			(xy 69.149122 -152.85302) (xy 69.106796 -152.778369) (xy 69.071647 -152.700083) (xy 69.043984 -152.618849)
			(xy 69.024048 -152.535382) (xy 69.012017 -152.450414) (xy 69.007995 -152.364694) (xy 63.170308 -152.364694)
			(xy 63.170308 -155.15209) (xy 69.034152 -155.15209) (xy 69.034152 -153.57729) (xy 69.034573 -153.563937)
			(xy 69.041487 -153.538142) (xy 69.054842 -153.515015) (xy 69.073728 -153.496132) (xy 69.096857 -153.482781)
			(xy 69.122653 -153.475871) (xy 69.136006 -153.475436) (xy 70.710806 -153.475436) (xy 70.724157 -153.475876)
			(xy 70.74995 -153.482788) (xy 70.773075 -153.49614) (xy 70.791958 -153.515021) (xy 70.80531 -153.538146)
			(xy 70.812223 -153.563939) (xy 70.81266 -153.57729) (xy 70.81266 -155.15209) (xy 70.812248 -155.165446)
			(xy 70.805337 -155.191249) (xy 70.791983 -155.214383) (xy 70.773096 -155.233273) (xy 70.749964 -155.246631)
			(xy 70.724162 -155.253546) (xy 70.710806 -155.253944) (xy 69.136006 -155.253944) (xy 69.122648 -155.253552)
			(xy 69.096843 -155.246639) (xy 69.073707 -155.233281) (xy 69.054816 -155.21439) (xy 69.04146 -155.191253)
			(xy 69.034547 -155.165448) (xy 69.034152 -155.15209) (xy 63.170308 -155.15209) (xy 63.170308 -158.49981)
			(xy 69.007995 -158.49981) (xy 69.012017 -158.41409) (xy 69.024048 -158.329122) (xy 69.043984 -158.245655)
			(xy 69.071647 -158.164421) (xy 69.106796 -158.086135) (xy 69.149122 -158.011484) (xy 69.198251 -157.941125)
			(xy 69.253754 -157.875675) (xy 69.315141 -157.815711) (xy 69.381874 -157.761758) (xy 69.453366 -157.714291)
			(xy 69.528988 -157.673727) (xy 69.608077 -157.640423) (xy 69.689937 -157.614671) (xy 69.773848 -157.596698)
			(xy 69.859074 -157.586662) (xy 69.944866 -157.58465) (xy 70.030468 -157.590681) (xy 70.11513 -157.604701)
			(xy 70.198107 -157.626587) (xy 70.27867 -157.656148) (xy 70.35611 -157.693122) (xy 70.429749 -157.737186)
			(xy 70.498937 -157.787952) (xy 70.563068 -157.844973) (xy 70.621577 -157.907749) (xy 70.67395 -157.975729)
			(xy 70.719728 -158.048314) (xy 70.758508 -158.124866) (xy 70.789949 -158.204714) (xy 70.813775 -158.287155)
			(xy 70.829776 -158.371465) (xy 70.837811 -158.456903) (xy 70.838314 -158.49981) (xy 70.837811 -158.542717)
			(xy 70.829776 -158.628155) (xy 70.813775 -158.712465) (xy 70.789949 -158.794906) (xy 70.758508 -158.874754)
			(xy 70.719728 -158.951306) (xy 70.67395 -159.023891) (xy 70.621577 -159.091871) (xy 70.563068 -159.154647)
			(xy 70.498937 -159.211668) (xy 70.429749 -159.262434) (xy 70.35611 -159.306498) (xy 70.27867 -159.343472)
			(xy 70.198107 -159.373033) (xy 70.11513 -159.394919) (xy 70.030468 -159.408939) (xy 69.944866 -159.41497)
			(xy 69.859074 -159.412958) (xy 69.773848 -159.402922) (xy 69.689937 -159.384949) (xy 69.608077 -159.359197)
			(xy 69.528988 -159.325893) (xy 69.453366 -159.285329) (xy 69.381874 -159.237862) (xy 69.315141 -159.183909)
			(xy 69.253754 -159.123945) (xy 69.198251 -159.058495) (xy 69.149122 -158.988136) (xy 69.106796 -158.913485)
			(xy 69.071647 -158.835199) (xy 69.043984 -158.753965) (xy 69.024048 -158.670498) (xy 69.012017 -158.58553)
			(xy 69.007995 -158.49981) (xy 63.170308 -158.49981) (xy 63.170308 -159.18815) (xy 64.728852 -160.746948)
			(xy 67.904868 -160.746948) (xy 68.445126 -161.287206) (xy 69.034152 -161.287206) (xy 69.034152 -159.712406)
			(xy 69.034548 -159.699049) (xy 69.041461 -159.673244) (xy 69.054818 -159.650108) (xy 69.073708 -159.631218)
			(xy 69.096844 -159.617861) (xy 69.122649 -159.610948) (xy 69.136006 -159.610552) (xy 70.710806 -159.610552)
			(xy 70.724159 -159.610976) (xy 70.749954 -159.61789) (xy 70.773081 -159.631244) (xy 70.791963 -159.650129)
			(xy 70.805315 -159.673257) (xy 70.812225 -159.699053) (xy 70.81266 -159.712406) (xy 70.81266 -161.287206)
			(xy 70.812224 -161.300558) (xy 70.805311 -161.326351) (xy 70.791959 -161.349477) (xy 70.773077 -161.368359)
			(xy 70.749951 -161.381711) (xy 70.724158 -161.388624) (xy 70.710806 -161.38906) (xy 69.136006 -161.38906)
			(xy 69.122655 -161.388613) (xy 69.096862 -161.381704) (xy 69.073736 -161.368354) (xy 69.054854 -161.349473)
			(xy 69.041501 -161.326349) (xy 69.034588 -161.300557) (xy 69.034152 -161.287206) (xy 68.445126 -161.287206)
			(xy 68.99402 -161.8361) (xy 70.993 -161.8361)
		)
		(stroke
			(width 0)
			(type solid)
		)
		(fill yes)
		(layer "F.Cu")
		(net "PVCCINFAON_CPU1")
	)
	(gr_poly
		(pts
			(xy 415.299398 -185.044588) (xy 415.309468 -185.044165) (xy 415.328072 -185.03645) (xy 415.335466 -185.029602)
			(xy 415.648394 -184.716674) (xy 415.655237 -184.709274) (xy 415.662963 -184.690676) (xy 415.66338 -184.680606)
			(xy 415.66338 -182.51297) (xy 415.662951 -182.502903) (xy 415.655227 -182.484308) (xy 415.648394 -182.476902)
			(xy 415.216086 -182.044594) (xy 415.209231 -182.037199) (xy 415.201485 -182.0186) (xy 415.2011 -182.008526)
			(xy 415.2011 -180.38445) (xy 415.201532 -180.374384) (xy 415.20926 -180.355793) (xy 415.216086 -180.348382)
			(xy 415.216594 -180.347874) (xy 415.223988 -180.341018) (xy 415.242587 -180.33327) (xy 415.252662 -180.332888)
			(xy 416.249358 -180.332888) (xy 416.259424 -180.333321) (xy 416.278014 -180.341049) (xy 416.285426 -180.347874)
			(xy 416.296094 -180.358542) (xy 416.302935 -180.365943) (xy 416.310655 -180.384541) (xy 416.31108 -180.39461)
			(xy 416.31108 -181.243986) (xy 416.311587 -181.254036) (xy 416.31931 -181.272594) (xy 416.326066 -181.280054)
			(xy 416.351974 -181.305962) (xy 416.358813 -181.313363) (xy 416.366529 -181.331961) (xy 416.36696 -181.34203)
			(xy 416.36696 -181.857904) (xy 416.59302 -181.857904) (xy 416.59302 -181.31663) (xy 416.593456 -181.306566)
			(xy 416.601191 -181.287982) (xy 416.608006 -181.280562) (xy 416.664394 -181.224174) (xy 416.671788 -181.217318)
			(xy 416.690387 -181.20957) (xy 416.700462 -181.209188) (xy 417.669218 -181.209188) (xy 417.679287 -181.209614)
			(xy 417.697888 -181.217332) (xy 417.705286 -181.224174) (xy 417.705794 -181.224682) (xy 417.712628 -181.232085)
			(xy 417.720334 -181.250683) (xy 417.72078 -181.26075) (xy 417.72078 -182.098188) (xy 417.721265 -182.108199)
			(xy 417.728922 -182.126698) (xy 417.743075 -182.14086) (xy 417.76157 -182.148528) (xy 417.77158 -182.148988)
			(xy 417.8935 -182.148988) (xy 417.90352 -182.148568) (xy 417.922035 -182.140898) (xy 417.936205 -182.126725)
			(xy 417.943871 -182.108209) (xy 417.9443 -182.098188) (xy 417.9443 -181.26583) (xy 417.944736 -181.255765)
			(xy 417.952468 -181.23718) (xy 417.959286 -181.229762) (xy 417.969954 -181.219094) (xy 417.977356 -181.212257)
			(xy 417.995954 -181.204543) (xy 418.006022 -181.204108) (xy 418.156898 -181.204108) (xy 418.166969 -181.203686)
			(xy 418.185574 -181.195973) (xy 418.192966 -181.189122) (xy 418.223954 -181.158134) (xy 418.230795 -181.150734)
			(xy 418.238513 -181.132135) (xy 418.23894 -181.122066) (xy 418.23894 -179.56403) (xy 418.238502 -179.553967)
			(xy 418.230763 -179.535386) (xy 418.223954 -179.527962) (xy 418.177726 -179.481734) (xy 418.170614 -179.474368)
			(xy 418.151818 -179.466748) (xy 416.156902 -179.466748) (xy 416.146833 -179.466324) (xy 416.128233 -179.458604)
			(xy 416.120834 -179.451762) (xy 415.917126 -179.248054) (xy 415.910284 -179.240654) (xy 415.902562 -179.222056)
			(xy 415.90214 -179.211986) (xy 415.90214 -174.92599) (xy 415.901713 -174.915922) (xy 415.89399 -174.897326)
			(xy 415.887154 -174.889922) (xy 415.719006 -174.721774) (xy 415.712163 -174.714374) (xy 415.704437 -174.695776)
			(xy 415.70402 -174.685706) (xy 415.70402 -174.120048) (xy 415.75482 -174.069248) (xy 415.75482 -173.850808)
			(xy 415.67608 -173.772068) (xy 415.42716 -173.772068) (xy 415.218626 -173.563534) (xy 415.211787 -173.556133)
			(xy 415.204073 -173.537535) (xy 415.20364 -173.527466) (xy 415.20364 -171.76623) (xy 415.204077 -171.756166)
			(xy 415.211814 -171.737584) (xy 415.218626 -171.730162) (xy 415.254694 -171.694094) (xy 415.262093 -171.687247)
			(xy 415.28069 -171.679512) (xy 415.290762 -171.679108) (xy 416.256978 -171.679108) (xy 416.267042 -171.679546)
			(xy 416.285625 -171.687281) (xy 416.293046 -171.694094) (xy 416.321494 -171.722542) (xy 416.328335 -171.729943)
			(xy 416.336055 -171.748541) (xy 416.33648 -171.75861) (xy 416.33648 -172.496226) (xy 416.336907 -172.506295)
			(xy 416.344626 -172.524894) (xy 416.351466 -172.532294) (xy 416.369754 -172.550582) (xy 416.376593 -172.557983)
			(xy 416.384305 -172.576582) (xy 416.38474 -172.58665) (xy 416.38474 -173.236128) (xy 416.59556 -173.236128)
			(xy 416.59556 -172.60951) (xy 416.595983 -172.59944) (xy 416.603701 -172.580839) (xy 416.610546 -172.573442)
			(xy 416.641534 -172.542454) (xy 416.648932 -172.535607) (xy 416.667531 -172.527877) (xy 416.677602 -172.527468)
			(xy 417.643818 -172.527468) (xy 417.653887 -172.527894) (xy 417.67249 -172.535609) (xy 417.679886 -172.542454)
			(xy 417.710874 -172.573442) (xy 417.717717 -172.580841) (xy 417.72544 -172.59944) (xy 417.72586 -172.60951)
			(xy 417.72586 -173.457108) (xy 417.726349 -173.467118) (xy 417.734008 -173.485613) (xy 417.74816 -173.499774)
			(xy 417.766651 -173.507445) (xy 417.77666 -173.507908) (xy 417.880038 -173.507908) (xy 417.890105 -173.507478)
			(xy 417.908701 -173.499755) (xy 417.916106 -173.492922) (xy 417.926774 -173.482254) (xy 417.933616 -173.474854)
			(xy 417.941338 -173.456256) (xy 417.94176 -173.446186) (xy 417.94176 -172.59427) (xy 417.94219 -172.584204)
			(xy 417.949919 -172.565613) (xy 417.956746 -172.558202) (xy 417.972494 -172.542454) (xy 417.97989 -172.535601)
			(xy 417.998488 -172.527856) (xy 418.008562 -172.527468) (xy 418.134038 -172.527468) (xy 418.144104 -172.527037)
			(xy 418.162696 -172.51931) (xy 418.170106 -172.512482) (xy 418.223954 -172.458634) (xy 418.230795 -172.451234)
			(xy 418.238513 -172.432635) (xy 418.23894 -172.422566) (xy 418.23894 -170.96105) (xy 418.238506 -170.950985)
			(xy 418.230772 -170.9324) (xy 418.223954 -170.924982) (xy 418.139626 -170.840654) (xy 418.132514 -170.833288)
			(xy 418.113718 -170.825668) (xy 416.207702 -170.825668) (xy 416.197632 -170.825245) (xy 416.17903 -170.817527)
			(xy 416.171634 -170.810682) (xy 415.899346 -170.538394) (xy 415.892495 -170.530997) (xy 415.884756 -170.512399)
			(xy 415.88436 -170.502326) (xy 415.88436 -170.421808) (xy 415.88944 -170.416728) (xy 415.88944 -166.49065)
			(xy 415.889006 -166.480585) (xy 415.881272 -166.462) (xy 415.874454 -166.454582) (xy 415.724086 -166.304214)
			(xy 415.717244 -166.296815) (xy 415.709527 -166.278216) (xy 415.7091 -166.268146) (xy 415.7091 -165.522148)
			(xy 415.74212 -165.489128) (xy 415.74212 -165.153848) (xy 415.6202 -165.031928) (xy 415.52876 -165.031928)
			(xy 415.36874 -165.031928) (xy 415.208466 -164.871654) (xy 415.20162 -164.864256) (xy 415.193891 -164.845657)
			(xy 415.19348 -164.835586) (xy 415.19348 -163.11499) (xy 415.193904 -163.10492) (xy 415.201619 -163.086316)
			(xy 415.208466 -163.078922) (xy 415.2138 -163.073588) (xy 415.222944 -163.069778) (xy 415.227572 -163.068008)
			(xy 415.237294 -163.066095) (xy 415.242248 -163.065968) (xy 416.048698 -163.065968) (xy 416.058769 -163.06639)
			(xy 416.077377 -163.0741) (xy 416.084766 -163.080954) (xy 416.311334 -163.307522) (xy 416.318184 -163.314919)
			(xy 416.325921 -163.333517) (xy 416.32632 -163.34359) (xy 416.32632 -163.938966) (xy 416.326756 -163.94903)
			(xy 416.334489 -163.967616) (xy 416.341306 -163.975034) (xy 416.354514 -163.988242) (xy 416.361363 -163.995638)
			(xy 416.369096 -164.014238) (xy 416.3695 -164.02431) (xy 416.3695 -164.610288) (xy 416.5981 -164.610288)
			(xy 416.5981 -164.03955) (xy 416.598532 -164.029484) (xy 416.60626 -164.010893) (xy 416.613086 -164.003482)
			(xy 416.692334 -163.924234) (xy 416.699733 -163.917389) (xy 416.718331 -163.909662) (xy 416.728402 -163.909248)
			(xy 417.664138 -163.909248) (xy 417.674204 -163.909679) (xy 417.692794 -163.917409) (xy 417.700206 -163.924234)
			(xy 417.726114 -163.950142) (xy 417.732963 -163.957538) (xy 417.740696 -163.976138) (xy 417.7411 -163.98621)
			(xy 417.7411 -164.818568) (xy 417.741514 -164.828594) (xy 417.749178 -164.847121) (xy 417.763352 -164.861304)
			(xy 417.781875 -164.86898) (xy 417.7919 -164.869368) (xy 417.880038 -164.869368) (xy 417.890104 -164.868937)
			(xy 417.908696 -164.86121) (xy 417.916106 -164.854382) (xy 417.926774 -164.843714) (xy 417.93361 -164.836312)
			(xy 417.941317 -164.817714) (xy 417.94176 -164.807646) (xy 417.94176 -163.98621) (xy 417.942183 -163.97614)
			(xy 417.949901 -163.957539) (xy 417.956746 -163.950142) (xy 417.987734 -163.919154) (xy 417.995132 -163.912307)
			(xy 418.013731 -163.904577) (xy 418.023802 -163.904168) (xy 418.131498 -163.904168) (xy 418.141568 -163.903745)
			(xy 418.16017 -163.896027) (xy 418.167566 -163.889182) (xy 418.216334 -163.840414) (xy 418.223174 -163.833014)
			(xy 418.230887 -163.814415) (xy 418.23132 -163.804346) (xy 418.23132 -162.34029) (xy 418.230896 -162.33022)
			(xy 418.223181 -162.311616) (xy 418.216334 -162.304222) (xy 418.142166 -162.230054) (xy 418.135054 -162.222688)
			(xy 418.116258 -162.215068) (xy 416.319462 -162.215068) (xy 416.309396 -162.214637) (xy 416.290804 -162.20691)
			(xy 416.283394 -162.200082) (xy 415.901886 -161.818574) (xy 415.895034 -161.811178) (xy 415.887296 -161.792579)
			(xy 415.8869 -161.782506) (xy 415.8869 -158.06801) (xy 415.887321 -158.057939) (xy 415.895033 -158.039332)
			(xy 415.901886 -158.031942) (xy 416.181794 -157.752034) (xy 416.189191 -157.745183) (xy 416.207789 -157.737441)
			(xy 416.217862 -157.737048) (xy 417.250118 -157.737048) (xy 417.260186 -157.73662) (xy 417.27878 -157.728895)
			(xy 417.286186 -157.722062) (xy 417.510214 -157.498034) (xy 417.51758 -157.490922) (xy 417.5252 -157.472126)
			(xy 417.5252 -153.70175) (xy 417.525632 -153.691684) (xy 417.53336 -153.673093) (xy 417.540186 -153.665682)
			(xy 417.667694 -153.538174) (xy 417.675088 -153.531318) (xy 417.693687 -153.52357) (xy 417.703762 -153.523188)
			(xy 418.393118 -153.523188) (xy 418.403187 -153.523614) (xy 418.421788 -153.531332) (xy 418.429186 -153.538174)
			(xy 418.620194 -153.729182) (xy 418.627028 -153.736585) (xy 418.634734 -153.755183) (xy 418.63518 -153.76525)
			(xy 418.63518 -154.292046) (xy 418.635611 -154.302113) (xy 418.643335 -154.320707) (xy 418.650166 -154.328114)
			(xy 418.739574 -154.417522) (xy 418.746973 -154.424365) (xy 418.765572 -154.432085) (xy 418.775642 -154.432508)
			(xy 420.120318 -154.432508) (xy 420.130387 -154.432082) (xy 420.148988 -154.424364) (xy 420.156386 -154.417522)
			(xy 420.329614 -154.244294) (xy 420.33698 -154.237182) (xy 420.3446 -154.218386) (xy 420.3446 -152.79243)
			(xy 420.344164 -152.782365) (xy 420.336432 -152.76378) (xy 420.329614 -152.756362) (xy 420.278306 -152.705054)
			(xy 420.271194 -152.697688) (xy 420.252398 -152.690068) (xy 418.498782 -152.690068) (xy 418.488714 -152.689641)
			(xy 418.470117 -152.681918) (xy 418.462714 -152.675082) (xy 418.256466 -152.468834) (xy 418.249623 -152.461435)
			(xy 418.241902 -152.442836) (xy 418.24148 -152.432766) (xy 418.24148 -149.27199) (xy 418.241904 -149.26192)
			(xy 418.249619 -149.243316) (xy 418.256466 -149.235922) (xy 418.422074 -149.070314) (xy 418.429476 -149.063478)
			(xy 418.448074 -149.055768) (xy 418.458142 -149.055328) (xy 424.786298 -149.055328) (xy 424.796369 -149.054906)
			(xy 424.814977 -149.047195) (xy 424.822366 -149.040342) (xy 425.236894 -148.625814) (xy 425.243727 -148.618411)
			(xy 425.251431 -148.599813) (xy 425.25188 -148.589746) (xy 425.25188 -147.16633) (xy 425.251444 -147.156266)
			(xy 425.243709 -147.137682) (xy 425.236894 -147.130262) (xy 425.111926 -147.005294) (xy 425.104814 -146.997928)
			(xy 425.086018 -146.990308) (xy 410.172662 -146.990308) (xy 410.162595 -146.990738) (xy 410.144001 -146.998463)
			(xy 410.136594 -147.005294) (xy 409.737306 -147.404582) (xy 409.72994 -147.411694) (xy 409.72232 -147.43049)
			(xy 409.72232 -155.164028) (xy 411.56128 -155.164028) (xy 411.56128 -151.247348) (xy 411.86862 -150.940008)
			(xy 416.6108 -150.940008) (xy 416.68446 -151.013668) (xy 416.68446 -155.250388) (xy 416.32886 -155.605988)
			(xy 412.00324 -155.605988) (xy 411.56128 -155.164028) (xy 409.72232 -155.164028) (xy 409.72232 -156.547566)
			(xy 409.721885 -156.557631) (xy 409.714156 -156.57622) (xy 409.707334 -156.583634) (xy 409.358846 -156.932122)
			(xy 409.351448 -156.938969) (xy 409.332849 -156.946696) (xy 409.322778 -156.947108) (xy 408.988768 -156.947108)
			(xy 408.980078 -156.946757) (xy 408.963712 -156.94091) (xy 408.956764 -156.935678) (xy 408.949802 -156.930475)
			(xy 408.933443 -156.924633) (xy 408.92476 -156.924248) (xy 408.633422 -156.924248) (xy 408.623359 -156.924687)
			(xy 408.60478 -156.932426) (xy 408.597354 -156.939234) (xy 408.005026 -157.531562) (xy 407.99766 -157.538674)
			(xy 407.99004 -157.55747) (xy 407.99004 -164.45992) (xy 409.534868 -164.45992) (xy 409.534868 -159.83966)
			(xy 409.695142 -159.679386) (xy 413.563562 -159.679386) (xy 413.759142 -159.874966) (xy 413.759142 -164.480494)
			(xy 413.545782 -164.693854) (xy 409.768802 -164.693854) (xy 409.534868 -164.45992) (xy 407.99004 -164.45992)
			(xy 407.99004 -173.09592) (xy 409.534868 -173.09592) (xy 409.534868 -168.47566) (xy 409.695142 -168.315386)
			(xy 413.563562 -168.315386) (xy 413.759142 -168.510966) (xy 413.759142 -173.116494) (xy 413.545782 -173.329854)
			(xy 409.768802 -173.329854) (xy 409.534868 -173.09592) (xy 407.99004 -173.09592) (xy 407.99004 -181.73192)
			(xy 409.534868 -181.73192) (xy 409.534868 -177.11166) (xy 409.695142 -176.951386) (xy 413.563562 -176.951386)
			(xy 413.759142 -177.146966) (xy 413.759142 -181.752494) (xy 413.545782 -181.965854) (xy 409.768802 -181.965854)
			(xy 409.534868 -181.73192) (xy 407.99004 -181.73192) (xy 407.99004 -182.704486) (xy 407.9896 -182.714548)
			(xy 407.981856 -182.733124) (xy 407.975054 -182.740554) (xy 407.560526 -183.155082) (xy 407.55316 -183.162194)
			(xy 407.54554 -183.18099) (xy 407.54554 -184.835546) (xy 407.545973 -184.845612) (xy 407.553703 -184.8642)
			(xy 407.560526 -184.871614) (xy 407.718514 -185.029602) (xy 407.725914 -185.036446) (xy 407.744511 -185.044175)
			(xy 407.754582 -185.044588)
		)
		(stroke
			(width 0)
			(type solid)
		)
		(fill yes)
		(layer "F.Cu")
		(net "GND")
	)
	(gr_poly
		(pts
			(xy 190.62065 -360.740198) (xy 191.323468 -360.03738) (xy 191.3382 -360.022394) (xy 191.3382 -349.02775)
			(xy 191.338632 -349.017684) (xy 191.34636 -348.999093) (xy 191.353186 -348.991682) (xy 192.02908 -348.315788)
			(xy 192.036479 -348.308945) (xy 192.055078 -348.301225) (xy 192.065148 -348.300802) (xy 194.301872 -348.300802)
			(xy 194.316858 -348.28607) (xy 194.706748 -347.89618) (xy 194.72148 -347.881194) (xy 194.72148 -333.980028)
			(xy 194.706494 -333.965042) (xy 194.220846 -333.479394) (xy 194.20586 -333.464408) (xy 156.60878 -333.464408)
			(xy 156.593794 -333.479394) (xy 156.240226 -333.832962) (xy 156.22524 -333.847948) (xy 156.22524 -344.360246)
			(xy 166.1414 -344.360246) (xy 166.1414 -336.61477) (xy 166.141783 -336.604695) (xy 166.149531 -336.586097)
			(xy 166.156386 -336.578702) (xy 166.403274 -336.331814) (xy 166.410691 -336.324995) (xy 166.429277 -336.317262)
			(xy 166.439342 -336.316828) (xy 170.338242 -336.316828) (xy 170.39717 -336.162904) (xy 170.371262 -336.139536)
			(xy 170.340728 -336.111453) (xy 170.284419 -336.050523) (xy 170.234026 -335.984618) (xy 170.189985 -335.914308)
			(xy 170.152679 -335.840204) (xy 170.122433 -335.76295) (xy 170.099507 -335.683217) (xy 170.084102 -335.601695)
			(xy 170.076352 -335.519094) (xy 170.07586 -335.477612) (xy 170.076364 -335.435251) (xy 170.084417 -335.350914)
			(xy 170.100451 -335.267724) (xy 170.124319 -335.186434) (xy 170.155807 -335.107782) (xy 170.194629 -335.032479)
			(xy 170.240432 -334.961207) (xy 170.292803 -334.894611) (xy 170.351268 -334.833296) (xy 170.415296 -334.777815)
			(xy 170.484308 -334.728672) (xy 170.557678 -334.686312) (xy 170.634743 -334.651117) (xy 170.714805 -334.623408)
			(xy 170.797138 -334.603434) (xy 170.880997 -334.591377) (xy 170.965622 -334.587346) (xy 171.050247 -334.591377)
			(xy 171.134106 -334.603434) (xy 171.216439 -334.623408) (xy 171.296501 -334.651117) (xy 171.373566 -334.686312)
			(xy 171.446936 -334.728672) (xy 171.515948 -334.777815) (xy 171.579976 -334.833296) (xy 171.638441 -334.894611)
			(xy 171.690812 -334.961207) (xy 171.736615 -335.032479) (xy 171.775437 -335.107782) (xy 171.806925 -335.186434)
			(xy 171.830793 -335.267724) (xy 171.846827 -335.350914) (xy 171.85488 -335.435251) (xy 171.855384 -335.477612)
			(xy 171.854892 -335.519095) (xy 171.847156 -335.601701) (xy 171.831763 -335.683227) (xy 171.808845 -335.762966)
			(xy 171.778601 -335.840224) (xy 171.741296 -335.914331) (xy 171.697252 -335.984642) (xy 171.646853 -336.050547)
			(xy 171.590536 -336.111472) (xy 171.559982 -336.139536) (xy 171.534074 -336.162904) (xy 171.593002 -336.316828)
			(xy 176.521872 -336.316828) (xy 176.581308 -336.163666) (xy 176.555654 -336.140298) (xy 176.525711 -336.112262)
			(xy 176.470547 -336.051548) (xy 176.421207 -335.986012) (xy 176.378111 -335.916212) (xy 176.341623 -335.84274)
			(xy 176.312055 -335.766222) (xy 176.289657 -335.687306) (xy 176.27462 -335.606663) (xy 176.267071 -335.524978)
			(xy 176.266602 -335.483962) (xy 176.267106 -335.441601) (xy 176.275159 -335.357264) (xy 176.291193 -335.274074)
			(xy 176.315061 -335.192784) (xy 176.346549 -335.114132) (xy 176.385371 -335.038829) (xy 176.431174 -334.967557)
			(xy 176.483545 -334.900961) (xy 176.54201 -334.839646) (xy 176.606038 -334.784165) (xy 176.67505 -334.735022)
			(xy 176.74842 -334.692662) (xy 176.825485 -334.657467) (xy 176.905547 -334.629758) (xy 176.98788 -334.609784)
			(xy 177.071739 -334.597727) (xy 177.156364 -334.593696) (xy 177.240989 -334.597727) (xy 177.324848 -334.609784)
			(xy 177.407181 -334.629758) (xy 177.487243 -334.657467) (xy 177.564308 -334.692662) (xy 177.637678 -334.735022)
			(xy 177.70669 -334.784165) (xy 177.770718 -334.839646) (xy 177.829183 -334.900961) (xy 177.881554 -334.967557)
			(xy 177.927357 -335.038829) (xy 177.966179 -335.114132) (xy 177.997667 -335.192784) (xy 178.021535 -335.274074)
			(xy 178.037569 -335.357264) (xy 178.045622 -335.441601) (xy 178.046126 -335.483962) (xy 178.04562 -335.524977)
			(xy 178.038065 -335.606657) (xy 178.023024 -335.687296) (xy 178.000627 -335.766209) (xy 177.971061 -335.842725)
			(xy 177.93458 -335.916195) (xy 177.891491 -335.985997) (xy 177.842162 -336.051536) (xy 177.78701 -336.112258)
			(xy 177.757074 -336.140298) (xy 177.73142 -336.163666) (xy 177.790856 -336.316828) (xy 182.719472 -336.316828)
			(xy 182.778908 -336.163666) (xy 182.753254 -336.140298) (xy 182.723311 -336.112262) (xy 182.668147 -336.051548)
			(xy 182.618807 -335.986012) (xy 182.575711 -335.916212) (xy 182.539223 -335.84274) (xy 182.509655 -335.766222)
			(xy 182.487257 -335.687306) (xy 182.47222 -335.606663) (xy 182.464671 -335.524978) (xy 182.464202 -335.483962)
			(xy 182.464706 -335.441601) (xy 182.472759 -335.357264) (xy 182.488793 -335.274074) (xy 182.512661 -335.192784)
			(xy 182.544149 -335.114132) (xy 182.582971 -335.038829) (xy 182.628774 -334.967557) (xy 182.681145 -334.900961)
			(xy 182.73961 -334.839646) (xy 182.803638 -334.784165) (xy 182.87265 -334.735022) (xy 182.94602 -334.692662)
			(xy 183.023085 -334.657467) (xy 183.103147 -334.629758) (xy 183.18548 -334.609784) (xy 183.269339 -334.597727)
			(xy 183.353964 -334.593696) (xy 183.438589 -334.597727) (xy 183.522448 -334.609784) (xy 183.604781 -334.629758)
			(xy 183.684843 -334.657467) (xy 183.761908 -334.692662) (xy 183.835278 -334.735022) (xy 183.90429 -334.784165)
			(xy 183.968318 -334.839646) (xy 184.026783 -334.900961) (xy 184.079154 -334.967557) (xy 184.124957 -335.038829)
			(xy 184.163779 -335.114132) (xy 184.195267 -335.192784) (xy 184.219135 -335.274074) (xy 184.235169 -335.357264)
			(xy 184.243222 -335.441601) (xy 184.243726 -335.483962) (xy 184.24322 -335.524977) (xy 184.235665 -335.606657)
			(xy 184.220624 -335.687296) (xy 184.198227 -335.766209) (xy 184.168661 -335.842725) (xy 184.13218 -335.916195)
			(xy 184.089091 -335.985997) (xy 184.039762 -336.051536) (xy 183.98461 -336.112258) (xy 183.954674 -336.140298)
			(xy 183.92902 -336.163666) (xy 183.988456 -336.316828) (xy 187.03163 -336.316828) (xy 187.041702 -336.317231)
			(xy 187.0603 -336.324967) (xy 187.067698 -336.331814) (xy 187.398406 -336.662522) (xy 187.405249 -336.66992)
			(xy 187.412967 -336.688521) (xy 187.413392 -336.69859) (xy 187.413392 -344.275918) (xy 187.412978 -344.285989)
			(xy 187.40525 -344.304586) (xy 187.398406 -344.311986) (xy 187.002166 -344.708226) (xy 186.994775 -344.715077)
			(xy 186.976169 -344.72279) (xy 186.966098 -344.723212) (xy 166.504366 -344.723212) (xy 166.494292 -344.722828)
			(xy 166.475693 -344.715081) (xy 166.468298 -344.708226) (xy 166.156386 -344.396314) (xy 166.149558 -344.388905)
			(xy 166.141832 -344.370312) (xy 166.1414 -344.360246) (xy 156.22524 -344.360246) (xy 156.22524 -351.29343)
			(xy 169.48404 -351.29343) (xy 169.48404 -346.171012) (xy 169.484461 -346.160942) (xy 169.492183 -346.142344)
			(xy 169.499026 -346.134944) (xy 169.715688 -345.918282) (xy 169.723096 -345.911452) (xy 169.741689 -345.903727)
			(xy 169.751756 -345.903296) (xy 174.22876 -345.903296) (xy 174.23883 -345.903717) (xy 174.25743 -345.911438)
			(xy 174.264828 -345.918282) (xy 174.551086 -346.20454) (xy 174.557934 -346.211934) (xy 174.56565 -346.230538)
			(xy 174.566072 -346.240608) (xy 174.566072 -351.292414) (xy 174.565056 -351.29343) (xy 179.172362 -351.29343)
			(xy 179.172362 -346.171012) (xy 179.172777 -346.160941) (xy 179.180503 -346.142343) (xy 179.187348 -346.134944)
			(xy 179.40401 -345.918282) (xy 179.411411 -345.911443) (xy 179.43001 -345.903723) (xy 179.440078 -345.903296)
			(xy 183.917082 -345.903296) (xy 183.927154 -345.903705) (xy 183.945753 -345.911434) (xy 183.95315 -345.918282)
			(xy 184.239408 -346.20454) (xy 184.246259 -346.211931) (xy 184.253972 -346.230537) (xy 184.254394 -346.240608)
			(xy 184.254394 -351.292414) (xy 184.25287 -351.293938) (xy 179.17287 -351.293938) (xy 179.172362 -351.29343)
			(xy 174.565056 -351.29343) (xy 174.564548 -351.293938) (xy 169.484548 -351.293938) (xy 169.48404 -351.29343)
			(xy 156.22524 -351.29343) (xy 156.22524 -352.745294) (xy 156.239972 -352.76028) (xy 156.493464 -353.013772)
			(xy 156.50845 -353.028504) (xy 167.217598 -353.028504) (xy 167.227668 -353.028927) (xy 167.246273 -353.036641)
			(xy 167.253666 -353.04349) (xy 167.429688 -353.219512) (xy 167.444674 -353.234244) (xy 169.05859 -353.234244)
			(xy 169.073576 -353.219512) (xy 169.473626 -352.819462) (xy 169.481023 -352.812613) (xy 169.499622 -352.804878)
			(xy 169.509694 -352.804476) (xy 171.012866 -352.804476) (xy 171.022931 -352.80491) (xy 171.041521 -352.812639)
			(xy 171.048934 -352.819462) (xy 171.066714 -352.837242) (xy 171.073563 -352.844638) (xy 171.081296 -352.863238)
			(xy 171.0817 -352.87331) (xy 171.0817 -353.750626) (xy 171.081272 -353.760694) (xy 171.073551 -353.779292)
			(xy 171.066714 -353.786694) (xy 171.058586 -353.794822) (xy 171.05119 -353.801675) (xy 171.032592 -353.809416)
			(xy 171.022518 -353.809808) (xy 170.079162 -353.809808) (xy 170.064176 -353.824794) (xy 169.987468 -353.901502)
			(xy 169.980068 -353.908343) (xy 169.96147 -353.916066) (xy 169.9514 -353.916488) (xy 169.59834 -353.916488)
			(xy 169.59834 -354.142548) (xy 170.043602 -354.142548) (xy 170.053671 -354.142973) (xy 170.07227 -354.150693)
			(xy 170.07967 -354.157534) (xy 170.151552 -354.229416) (xy 170.20286 -354.280978) (xy 170.206258 -354.284551)
			(xy 170.211748 -354.292742) (xy 170.213782 -354.297234) (xy 170.221148 -354.31476) (xy 170.222926 -354.319387)
			(xy 170.224853 -354.329109) (xy 170.224958 -354.334064) (xy 170.224958 -354.334318) (xy 170.224958 -355.15677)
			(xy 170.224958 -355.157024) (xy 170.224837 -355.161978) (xy 170.222916 -355.171698) (xy 170.221148 -355.176328)
			(xy 170.213782 -355.1936) (xy 170.213782 -355.193854) (xy 170.211772 -355.198359) (xy 170.206272 -355.206547)
			(xy 170.20286 -355.21011) (xy 170.196256 -355.216714) (xy 170.192686 -355.220117) (xy 170.184499 -355.225616)
			(xy 170.18 -355.227636) (xy 170.179746 -355.227636) (xy 170.162474 -355.235002) (xy 170.157845 -355.236772)
			(xy 170.148124 -355.238685) (xy 170.14317 -355.238812) (xy 170.142916 -355.238812) (xy 169.3926 -355.238812)
			(xy 169.381932 -355.238812) (xy 169.335958 -355.258624) (xy 169.335958 -355.465634) (xy 169.335958 -355.476302)
			(xy 169.35577 -355.522276) (xy 170.142916 -355.522276) (xy 170.14317 -355.522276) (xy 170.148125 -355.522392)
			(xy 170.157849 -355.524304) (xy 170.162474 -355.526086) (xy 170.179746 -355.533452) (xy 170.18 -355.533452)
			(xy 170.184502 -355.535467) (xy 170.192682 -355.540974) (xy 170.196256 -355.544374) (xy 170.20286 -355.550978)
			(xy 170.206258 -355.554551) (xy 170.211748 -355.562742) (xy 170.213782 -355.567234) (xy 170.213782 -355.567488)
			(xy 170.221148 -355.58476) (xy 170.222926 -355.589387) (xy 170.224853 -355.599109) (xy 170.224958 -355.604064)
			(xy 170.224958 -355.604318) (xy 170.224958 -355.770434) (xy 170.224958 -355.780848) (xy 170.240198 -355.816916)
			(xy 170.260518 -355.837236) (xy 170.296586 -355.852476) (xy 170.307 -355.852476) (xy 171.971716 -355.852476)
			(xy 171.98213 -355.852476) (xy 172.018198 -355.837236) (xy 172.060108 -355.795326) (xy 172.07484 -355.78034)
			(xy 172.07484 -353.637088) (xy 172.075267 -353.62702) (xy 172.082989 -353.608422) (xy 172.089826 -353.60102)
			(xy 172.178472 -353.512374) (xy 172.185871 -353.505531) (xy 172.20447 -353.497811) (xy 172.21454 -353.497388)
			(xy 174.509938 -353.497388) (xy 174.517514 -353.497703) (xy 174.531978 -353.502224) (xy 174.538386 -353.506278)
			(xy 174.55134 -353.514914) (xy 175.710596 -353.514914) (xy 175.71339 -353.512374) (xy 175.715168 -353.514152)
			(xy 176.968658 -353.514152) (xy 176.978722 -353.514587) (xy 176.997307 -353.522322) (xy 177.004726 -353.529138)
			(xy 177.157888 -353.6823) (xy 177.164736 -353.689698) (xy 177.172472 -353.708296) (xy 177.172874 -353.718368)
			(xy 177.172874 -355.998272) (xy 177.172437 -356.008336) (xy 177.164701 -356.026919) (xy 177.157888 -356.03434)
			(xy 176.655984 -356.536244) (xy 176.640998 -356.55123) (xy 176.640998 -358.778048) (xy 176.65573 -358.793034)
			(xy 177.240184 -359.377488) (xy 177.25517 -359.39222) (xy 177.822098 -359.39222) (xy 177.837084 -359.377488)
			(xy 177.867818 -359.346754) (xy 177.88255 -359.331768) (xy 177.88255 -356.952296) (xy 177.867564 -356.93731)
			(xy 177.74412 -356.813866) (xy 177.737277 -356.806467) (xy 177.729551 -356.787868) (xy 177.729134 -356.777798)
			(xy 177.729134 -353.426268) (xy 177.729564 -353.416201) (xy 177.73729 -353.397608) (xy 177.74412 -353.3902)
			(xy 177.869088 -353.265232) (xy 177.876484 -353.25838) (xy 177.895083 -353.250637) (xy 177.905156 -353.250246)
			(xy 178.727608 -353.250246) (xy 178.742594 -353.235514) (xy 179.158646 -352.819462) (xy 179.166044 -352.812616)
			(xy 179.184643 -352.804889) (xy 179.194714 -352.804476) (xy 180.701188 -352.804476) (xy 180.71126 -352.804896)
			(xy 180.72987 -352.812605) (xy 180.737256 -352.819462) (xy 180.761894 -352.8441) (xy 180.768741 -352.851498)
			(xy 180.776477 -352.870096) (xy 180.77688 -352.880168) (xy 180.77688 -353.735386) (xy 180.776441 -353.745449)
			(xy 180.768702 -353.764029) (xy 180.761894 -353.771454) (xy 180.738526 -353.794822) (xy 180.731127 -353.801665)
			(xy 180.712528 -353.809385) (xy 180.702458 -353.809808) (xy 179.767484 -353.809808) (xy 179.752498 -353.824794)
			(xy 179.732178 -353.845114) (xy 179.728608 -353.848518) (xy 179.720424 -353.85402) (xy 179.715922 -353.856036)
			(xy 179.715668 -353.856036) (xy 179.698396 -353.863402) (xy 179.693768 -353.865174) (xy 179.684046 -353.867091)
			(xy 179.679092 -353.867212) (xy 179.678838 -353.867212) (xy 179.030122 -353.867212) (xy 179.019454 -353.867212)
			(xy 178.97348 -353.887024) (xy 178.97348 -354.119434) (xy 178.97348 -354.129848) (xy 178.98872 -354.165916)
			(xy 179.024026 -354.201222) (xy 179.612544 -354.201222) (xy 179.620672 -354.201476) (xy 179.621688 -354.201476)
			(xy 179.780438 -354.201476) (xy 179.780692 -354.201476) (xy 179.785647 -354.201594) (xy 179.795369 -354.20351)
			(xy 179.799996 -354.205286) (xy 179.817268 -354.212652) (xy 179.817522 -354.212652) (xy 179.822028 -354.214661)
			(xy 179.830217 -354.220159) (xy 179.833778 -354.223574) (xy 179.891182 -354.280978) (xy 179.894584 -354.284549)
			(xy 179.900082 -354.292736) (xy 179.902104 -354.297234) (xy 179.902104 -354.297488) (xy 179.90947 -354.31476)
			(xy 179.911247 -354.319387) (xy 179.913174 -354.329109) (xy 179.91328 -354.334064) (xy 179.91328 -354.334318)
			(xy 179.91328 -355.15677) (xy 179.91328 -355.157024) (xy 179.913159 -355.161978) (xy 179.911239 -355.171699)
			(xy 179.90947 -355.176328) (xy 179.902104 -355.1936) (xy 179.902104 -355.193854) (xy 179.900094 -355.19836)
			(xy 179.894597 -355.20655) (xy 179.891182 -355.21011) (xy 179.884578 -355.216714) (xy 179.881008 -355.220118)
			(xy 179.872824 -355.22562) (xy 179.868322 -355.227636) (xy 179.868068 -355.227636) (xy 179.850796 -355.235002)
			(xy 179.846168 -355.236774) (xy 179.836446 -355.238691) (xy 179.831492 -355.238812) (xy 179.831238 -355.238812)
			(xy 179.080922 -355.238812) (xy 179.070254 -355.238812) (xy 179.02428 -355.258624) (xy 179.02428 -355.465634)
			(xy 179.02428 -355.476302) (xy 179.044092 -355.522276) (xy 179.831238 -355.522276) (xy 179.831492 -355.522276)
			(xy 179.836447 -355.522394) (xy 179.846169 -355.52431) (xy 179.850796 -355.526086) (xy 179.868068 -355.533452)
			(xy 179.868322 -355.533452) (xy 179.872828 -355.535461) (xy 179.881017 -355.540959) (xy 179.884578 -355.544374)
			(xy 179.891182 -355.550978) (xy 179.894584 -355.554549) (xy 179.900082 -355.562736) (xy 179.902104 -355.567234)
			(xy 179.902104 -355.567488) (xy 179.90947 -355.58476) (xy 179.911247 -355.589387) (xy 179.913174 -355.599109)
			(xy 179.91328 -355.604064) (xy 179.91328 -355.604318) (xy 179.91328 -355.770434) (xy 179.91328 -355.780848)
			(xy 179.92852 -355.816916) (xy 179.94884 -355.837236) (xy 179.984908 -355.852476) (xy 179.995322 -355.852476)
			(xy 181.660038 -355.852476) (xy 181.670452 -355.852476) (xy 181.70652 -355.837236) (xy 181.74843 -355.795326)
			(xy 181.763162 -355.78034) (xy 181.763162 -353.637088) (xy 181.763589 -353.62702) (xy 181.771313 -353.608425)
			(xy 181.778148 -353.60102) (xy 181.864254 -353.514914) (xy 181.871655 -353.508074) (xy 181.890253 -353.500357)
			(xy 181.900322 -353.499928) (xy 184.187338 -353.499928) (xy 184.194376 -353.500155) (xy 184.207908 -353.504028)
			(xy 184.214008 -353.507548) (xy 184.2262 -353.514914) (xy 185.398918 -353.514914) (xy 185.401712 -353.512374)
			(xy 185.40349 -353.514152) (xy 186.88812 -353.514152) (xy 186.898187 -353.51458) (xy 186.916782 -353.522306)
			(xy 186.924188 -353.529138) (xy 187.170314 -353.775264) (xy 187.17716 -353.782662) (xy 187.184884 -353.801261)
			(xy 187.1853 -353.811332) (xy 187.1853 -360.399076) (xy 187.200032 -360.414062) (xy 187.526168 -360.740198)
			(xy 187.541154 -360.75493) (xy 190.605664 -360.75493)
		)
		(stroke
			(width 0)
			(type solid)
		)
		(fill yes)
		(layer "F.Cu")
		(net "GND")
	)
	(gr_poly
		(pts
			(xy 337.630262 -70.688708) (xy 337.701128 -70.517258)
			(arc
				(start 337.701128 -66.413126)
				(mid 337.715523 -66.310987)
				(end 337.757516 -66.216784)
			)
			(arc
				(start 337.757516 -65.79235)
				(mid 337.78412 -65.658601)
				(end 337.859878 -65.545208)
			)
			(xy 338.080096 -65.32499) (xy 338.080096 -60.411106) (xy 337.885532 -60.216542)
			(arc
				(start 337.873594 -60.204096)
				(mid 337.817521 -60.190608)
				(end 337.784948 -60.238132)
			)
			(xy 337.784948 -60.924694)
			(arc
				(start 337.789266 -60.934346)
				(mid 337.80124 -60.972)
				(end 337.805268 -61.011308)
			)
			(arc
				(start 337.805268 -62.77864)
				(mid 337.790734 -62.852178)
				(end 337.749134 -62.91453)
			)
			(xy 337.58632 -63.07709)
			(arc
				(start 337.58632 -64.015874)
				(mid 337.571786 -64.089412)
				(end 337.530186 -64.151764)
			)
			(xy 337.335876 -64.346074) (xy 337.335876 -64.532256)
			(arc
				(start 337.549998 -64.532256)
				(mid 337.64007 -64.569618)
				(end 337.677252 -64.659764)
			)
			(arc
				(start 337.677252 -65.370964)
				(mid 337.639996 -65.461036)
				(end 337.549998 -65.498472)
			)
			(xy 337.20405 -65.498472)
			(arc
				(start 337.199224 -65.543684)
				(mid 337.181538 -65.606169)
				(end 337.144106 -65.659254)
			)
			(xy 337.11515 -65.68821)
			(arc
				(start 337.119976 -65.714626)
				(mid 337.125109 -65.750277)
				(end 337.126834 -65.786254)
			)
			(arc
				(start 337.126834 -65.786254)
				(mid 337.07966 -65.970018)
				(end 336.949796 -66.108326)
			)
			(xy 336.949796 -66.742056) (xy 336.697066 -66.742056) (xy 336.68462 -66.755772) (xy 336.68462 -66.802)
			(xy 336.638646 -66.802) (xy 335.847944 -67.592448) (xy 335.847944 -68.959984) (xy 336.003138 -69.114924)
			(arc
				(start 337.319874 -69.114924)
				(mid 337.409946 -69.152286)
				(end 337.447128 -69.242432)
			)
			(arc
				(start 337.447128 -70.461632)
				(mid 337.409872 -70.551704)
				(end 337.319874 -70.58914)
			)
			(arc
				(start 335.897474 -70.58914)
				(mid 335.807402 -70.551778)
				(end 335.77022 -70.461632)
			)
			(xy 335.77022 -69.425312)
			(arc
				(start 335.52003 -69.175376)
				(mid 335.478454 -69.113014)
				(end 335.463896 -69.039486)
			)
			(arc
				(start 335.463896 -67.512946)
				(mid 335.47843 -67.439408)
				(end 335.52003 -67.377056)
			)
			(xy 336.215228 -66.681858)
			(arc
				(start 336.204306 -66.651632)
				(mid 336.194301 -66.613476)
				(end 336.191098 -66.574162)
			)
			(xy 336.191352 -66.574162) (xy 336.191352 -66.27495)
			(arc
				(start 336.191098 -66.27495)
				(mid 336.230036 -66.146576)
				(end 336.334862 -66.06286)
			)
			(arc
				(start 336.334862 -66.06286)
				(mid 336.391218 -66.008369)
				(end 336.392012 -65.930018)
			)
			(arc
				(start 336.392012 -65.930018)
				(mid 336.370934 -65.859504)
				(end 336.363818 -65.786254)
			)
			(arc
				(start 336.363818 -65.786254)
				(mid 336.423109 -65.582062)
				(end 336.582512 -65.441322)
			)
			(arc
				(start 336.582512 -65.441322)
				(mid 336.605437 -65.419565)
				(end 336.61096 -65.38849)
			)
			(xy 336.609944 -65.370964)
			(arc
				(start 336.609944 -64.659764)
				(mid 336.6472 -64.569692)
				(end 336.737198 -64.532256)
			)
			(xy 336.95132 -64.532256)
			(arc
				(start 336.95132 -64.266572)
				(mid 336.965971 -64.193005)
				(end 337.007708 -64.130682)
			)
			(xy 337.202272 -63.936372)
			(arc
				(start 337.202272 -62.997588)
				(mid 337.216806 -62.92405)
				(end 337.258406 -62.861698)
			)
			(xy 337.42122 -62.699138)
			(arc
				(start 337.42122 -61.011308)
				(mid 337.425234 -60.971997)
				(end 337.437222 -60.934346)
			)
			(xy 337.44154 -60.924694) (xy 337.44154 -60.852304) (xy 337.36407 -60.852304)
			(arc
				(start 337.34883 -60.874148)
				(mid 337.338389 -60.887988)
				(end 337.326732 -60.900818)
			)
			(arc
				(start 337.05292 -61.17463)
				(mid 336.990558 -61.216206)
				(end 336.91703 -61.230764)
			)
			(xy 336.538824 -61.230764) (xy 336.5373 -61.232542) (xy 336.5373 -61.454538) (xy 336.538824 -61.456316)
			(arc
				(start 336.840322 -61.456316)
				(mid 336.91386 -61.47085)
				(end 336.976212 -61.51245)
			)
			(arc
				(start 337.090512 -61.62675)
				(mid 337.132225 -61.689083)
				(end 337.1469 -61.76264)
			)
			(arc
				(start 337.1469 -62.108588)
				(mid 337.132249 -62.182155)
				(end 337.090512 -62.244478)
			)
			(arc
				(start 336.940906 -62.394084)
				(mid 336.878573 -62.435797)
				(end 336.805016 -62.450472)
			)
			(arc
				(start 336.60334 -62.450472)
				(mid 336.588304 -62.474038)
				(end 336.57159 -62.496446)
			)
			(arc
				(start 336.57159 -62.496446)
				(mid 336.55077 -62.575693)
				(end 336.595212 -62.644528)
			)
			(arc
				(start 336.595212 -62.644528)
				(mid 336.669803 -62.726082)
				(end 336.696812 -62.83325)
			)
			(xy 336.696812 -63.100712) (xy 336.636868 -63.100712) (xy 336.636868 -63.625984) (xy 336.696812 -63.625984)
			(arc
				(start 336.696812 -63.893446)
				(mid 336.630061 -64.053832)
				(end 336.469228 -64.119506)
			)
			(xy 336.469228 -64.119252) (xy 336.235294 -64.119252) (xy 336.12836 -64.226186) (xy 336.12836 -64.540384)
			(arc
				(start 336.14995 -64.555624)
				(mid 336.189727 -64.601084)
				(end 336.204052 -64.659764)
			)
			(arc
				(start 336.204052 -65.370964)
				(mid 336.166796 -65.461036)
				(end 336.076798 -65.498472)
			)
			(xy 335.863692 -65.498472)
			(arc
				(start 335.851754 -65.532254)
				(mid 335.833087 -65.571001)
				(end 335.806288 -65.604644)
			)
			(xy 335.748122 -65.66281)
			(arc
				(start 335.752948 -65.689226)
				(mid 335.758081 -65.724877)
				(end 335.759806 -65.760854)
			)
			(arc
				(start 335.759806 -65.760854)
				(mid 335.695292 -65.973134)
				(end 335.523586 -66.11366)
			)
			(arc
				(start 335.523586 -66.11366)
				(mid 335.46986 -66.165247)
				(end 335.465674 -66.239644)
			)
			(arc
				(start 335.465674 -66.239644)
				(mid 335.474534 -66.275611)
				(end 335.477358 -66.312542)
			)
			(xy 335.477104 -66.312542) (xy 335.477104 -66.611754)
			(arc
				(start 335.477358 -66.611754)
				(mid 335.411779 -66.772756)
				(end 335.251298 -66.839592)
			)
			(xy 335.015586 -66.839592)
			(arc
				(start 334.838548 -67.01663)
				(mid 334.776186 -67.058206)
				(end 334.702658 -67.072764)
			)
			(xy 334.023462 -67.072764) (xy 334.019144 -67.077082) (xy 334.019144 -67.415156)
			(arc
				(start 335.119726 -67.415156)
				(mid 335.209798 -67.452518)
				(end 335.24698 -67.542664)
			)
			(arc
				(start 335.24698 -68.761864)
				(mid 335.209724 -68.851936)
				(end 335.119726 -68.889372)
			)
			(arc
				(start 333.697326 -68.889372)
				(mid 333.607254 -68.85201)
				(end 333.570072 -68.761864)
			)
			(arc
				(start 333.570072 -67.542664)
				(mid 333.582273 -67.488291)
				(end 333.616554 -67.444366)
			)
			(xy 333.635096 -67.429126)
			(arc
				(start 333.635096 -66.99758)
				(mid 333.64963 -66.924042)
				(end 333.69123 -66.86169)
			)
			(arc
				(start 333.80807 -66.74485)
				(mid 333.870432 -66.703274)
				(end 333.94396 -66.688716)
			)
			(xy 334.623156 -66.688716) (xy 334.71866 -66.592958) (xy 334.71866 -66.144648) (xy 334.983836 -66.144648)
			(xy 334.983836 -66.084704) (xy 335.055972 -66.084704) (xy 335.055972 -65.965578)
			(arc
				(start 335.049114 -65.95364)
				(mid 335.010097 -65.860735)
				(end 334.99679 -65.760854)
			)
			(arc
				(start 334.99679 -65.760854)
				(mid 335.031659 -65.601513)
				(end 335.129886 -65.471294)
			)
			(arc
				(start 335.129886 -65.471294)
				(mid 335.146016 -65.445538)
				(end 335.144618 -65.41516)
			)
			(arc
				(start 335.144618 -65.41516)
				(mid 335.138695 -65.393414)
				(end 335.136744 -65.370964)
			)
			(arc
				(start 335.136744 -64.659764)
				(mid 335.174 -64.569692)
				(end 335.263998 -64.532256)
			)
			(xy 335.744312 -64.532256)
			(arc
				(start 335.744312 -64.146684)
				(mid 335.758846 -64.073146)
				(end 335.800446 -64.010794)
			)
			(xy 335.942432 -63.869062) (xy 335.942432 -63.625984) (xy 336.002376 -63.625984) (xy 336.002376 -63.100712)
			(xy 335.942432 -63.100712)
			(arc
				(start 335.942432 -62.83325)
				(mid 335.959448 -62.747458)
				(end 336.00771 -62.6745)
			)
			(arc
				(start 336.00771 -62.6745)
				(mid 336.036975 -62.602228)
				(end 336.00644 -62.530482)
			)
			(arc
				(start 336.00644 -62.530482)
				(mid 335.921881 -62.405845)
				(end 335.89214 -62.258194)
			)
			(arc
				(start 335.89214 -62.258194)
				(mid 336.003881 -61.988427)
				(end 336.273648 -61.876686)
			)
			(arc
				(start 336.291682 -61.877194)
				(mid 336.340889 -61.845998)
				(end 336.328512 -61.789056)
			)
			(xy 336.323432 -61.78423)
			(arc
				(start 336.209132 -61.66993)
				(mid 336.167419 -61.607597)
				(end 336.152744 -61.53404)
			)
			(arc
				(start 336.152744 -61.503306)
				(mid 336.126783 -61.458993)
				(end 336.075528 -61.460126)
			)
			(arc
				(start 336.075528 -61.460126)
				(mid 336.023501 -61.486363)
				(end 335.967832 -61.50356)
			)
			(arc
				(start 335.967832 -61.50356)
				(mid 335.932972 -61.596137)
				(end 335.873598 -61.675264)
			)
			(arc
				(start 335.747868 -61.800994)
				(mid 335.71095 -61.833199)
				(end 335.66989 -61.859922)
			)
			(arc
				(start 335.66989 -61.859922)
				(mid 335.679976 -61.907585)
				(end 335.683352 -61.956188)
			)
			(arc
				(start 335.683352 -62.133988)
				(mid 335.669444 -62.231856)
				(end 335.628742 -62.321948)
			)
			(arc
				(start 335.628742 -62.321948)
				(mid 335.669503 -62.412023)
				(end 335.683352 -62.509908)
			)
			(arc
				(start 335.683352 -62.687708)
				(mid 335.669444 -62.785576)
				(end 335.628742 -62.875668)
			)
			(arc
				(start 335.628742 -62.875668)
				(mid 335.669503 -62.965743)
				(end 335.683352 -63.063628)
			)
			(arc
				(start 335.683352 -63.241428)
				(mid 335.657648 -63.373031)
				(end 335.584292 -63.485268)
			)
			(arc
				(start 335.584292 -63.737744)
				(mid 335.557688 -63.871493)
				(end 335.48193 -63.984886)
			)
			(xy 335.459324 -64.007492)
			(arc
				(start 335.458308 -64.026542)
				(mid 335.427792 -64.147952)
				(end 335.356454 -64.250824)
			)
			(arc
				(start 335.230724 -64.376554)
				(mid 335.151609 -64.43595)
				(end 335.05902 -64.470788)
			)
			(arc
				(start 335.05902 -64.470788)
				(mid 335.02416 -64.563365)
				(end 334.964786 -64.642492)
			)
			(arc
				(start 334.839056 -64.768222)
				(mid 334.759941 -64.827618)
				(end 334.667352 -64.862456)
			)
			(arc
				(start 334.667352 -64.862456)
				(mid 334.632492 -64.955033)
				(end 334.573118 -65.03416)
			)
			(arc
				(start 334.447388 -65.15989)
				(mid 334.368273 -65.219286)
				(end 334.275684 -65.254124)
			)
			(arc
				(start 334.275684 -65.254124)
				(mid 334.240824 -65.346701)
				(end 334.18145 -65.425828)
			)
			(arc
				(start 334.05572 -65.551558)
				(mid 333.976605 -65.610954)
				(end 333.884016 -65.645792)
			)
			(arc
				(start 333.884016 -65.645792)
				(mid 333.849156 -65.738369)
				(end 333.789782 -65.817496)
			)
			(arc
				(start 333.664052 -65.943226)
				(mid 333.561182 -66.014569)
				(end 333.43977 -66.04508)
			)
			(xy 333.42072 -66.046096) (xy 333.338424 -66.128646)
			(arc
				(start 333.359506 -66.162682)
				(mid 333.398382 -66.250998)
				(end 333.411576 -66.346578)
			)
			(arc
				(start 333.411576 -66.524378)
				(mid 333.385872 -66.655981)
				(end 333.312516 -66.768218)
			)
			(arc
				(start 333.312516 -67.139312)
				(mid 333.354153 -67.233321)
				(end 333.368396 -67.335146)
			)
			(xy 333.368396 -70.724522) (xy 333.728822 -71.084948) (xy 337.234022 -71.084948)
		)
		(stroke
			(width 0)
			(type solid)
		)
		(fill yes)
		(layer "F.Cu")
		(net "GND")
	)
	(gr_poly
		(pts
			(xy 180.71846 -27.968448) (xy 183.510682 -27.968448) (xy 183.878982 -27.600148) (xy 183.878982 -22.323552)
			(xy 184.590182 -21.612352) (xy 184.914794 -21.612352) (xy 184.916572 -21.56333) (xy 184.91812 -21.533204)
			(xy 184.927775 -21.473658) (xy 184.944766 -21.415777) (xy 184.968829 -21.36046) (xy 184.99959 -21.308569)
			(xy 185.036571 -21.26091) (xy 185.057542 -21.239226) (xy 185.28665 -21.010118) (xy 185.309367 -20.988097)
			(xy 185.359559 -20.949579) (xy 185.414351 -20.917944) (xy 185.472804 -20.893735) (xy 185.533918 -20.877364)
			(xy 185.596646 -20.869114) (xy 185.62828 -20.86864) (xy 185.659912 -20.869134) (xy 185.722634 -20.87739)
			(xy 185.783743 -20.893762) (xy 185.842191 -20.917972) (xy 185.896979 -20.949604) (xy 185.947168 -20.988117)
			(xy 185.991901 -21.032853) (xy 186.030412 -21.083045) (xy 186.062041 -21.137834) (xy 186.086247 -21.196284)
			(xy 186.102616 -21.257393) (xy 186.110868 -21.320116) (xy 186.111388 -21.351748) (xy 186.110817 -21.385014)
			(xy 186.101642 -21.450911) (xy 186.0931 -21.483066) (xy 186.089827 -21.496099) (xy 186.08949 -21.522961)
			(xy 186.096174 -21.54898) (xy 186.109418 -21.572352) (xy 186.128303 -21.591458) (xy 186.151519 -21.604974)
			(xy 186.177458 -21.611962) (xy 186.19089 -21.612352) (xy 188.069982 -21.612352) (xy 189.611762 -23.154132)
			(xy 189.611762 -23.955756) (xy 189.612778 -23.960582) (xy 189.616355 -23.979364) (xy 189.620173 -24.01741)
			(xy 189.620398 -24.036528) (xy 189.620161 -24.055646) (xy 189.616339 -24.093689) (xy 189.612778 -24.112474)
			(xy 189.611762 -24.1173) (xy 189.611762 -26.453592) (xy 189.672722 -26.514552) (xy 189.792102 -26.514552)
			(xy 189.855602 -26.451052) (xy 189.855602 -24.596852) (xy 190.038482 -24.413972) (xy 190.437262 -24.413972)
			(xy 190.615062 -24.591772) (xy 190.615062 -25.955752) (xy 190.670942 -26.011632) (xy 190.815722 -26.011632)
			(xy 190.863982 -25.963372) (xy 190.863982 -24.759412) (xy 191.143382 -24.480012) (xy 191.143382 -19.06905)
			(xy 190.91148 -18.837148) (xy 185.39587 -18.837148) (xy 185.382231 -18.837587) (xy 185.355927 -18.844808)
			(xy 185.332468 -18.858728) (xy 185.313526 -18.878356) (xy 185.300448 -18.902295) (xy 185.294166 -18.928839)
			(xy 185.295127 -18.9561) (xy 185.298842 -18.969228) (xy 185.307019 -18.997093) (xy 185.315815 -19.054493)
			(xy 185.316368 -19.083528) (xy 185.315882 -19.110779) (xy 185.308126 -19.164727) (xy 185.292771 -19.217022)
			(xy 185.270129 -19.266599) (xy 185.240663 -19.312449) (xy 185.204972 -19.35364) (xy 185.163781 -19.389331)
			(xy 185.117931 -19.418797) (xy 185.068354 -19.441439) (xy 185.016059 -19.456794) (xy 184.962111 -19.46455)
			(xy 184.907609 -19.46455) (xy 184.853661 -19.456794) (xy 184.801366 -19.441439) (xy 184.751789 -19.418797)
			(xy 184.705939 -19.389331) (xy 184.664748 -19.35364) (xy 184.629057 -19.312449) (xy 184.599591 -19.266599)
			(xy 184.576949 -19.217022) (xy 184.561594 -19.164727) (xy 184.553838 -19.110779) (xy 184.553352 -19.083528)
			(xy 184.553893 -19.054492) (xy 184.562691 -18.997091) (xy 184.570878 -18.969228) (xy 184.57456 -18.956082)
			(xy 184.575571 -18.92881) (xy 184.569319 -18.902246) (xy 184.556249 -18.878288) (xy 184.537298 -18.858651)
			(xy 184.513821 -18.844738) (xy 184.487496 -18.837545) (xy 184.47385 -18.837148) (xy 178.289458 -18.837148)
			(xy 178.289458 -18.895568) (xy 178.291744 -18.902934) (xy 178.297332 -18.923762) (xy 178.300888 -18.937478)
			(xy 178.42103 -19.05762) (xy 178.54041 -19.05762) (xy 178.552094 -19.051016) (xy 178.569583 -19.041402)
			(xy 178.607109 -19.027825) (xy 178.646439 -19.021063) (xy 178.666394 -19.02079) (xy 178.666394 -19.021044)
			(xy 178.965606 -19.021044) (xy 178.965606 -19.02079) (xy 178.987935 -19.021132) (xy 179.031788 -19.02954)
			(xy 179.07314 -19.046384) (xy 179.110387 -19.071009) (xy 179.142082 -19.102461) (xy 179.166994 -19.139516)
			(xy 179.184157 -19.180738) (xy 179.192903 -19.224524) (xy 179.193444 -19.24685) (xy 179.193444 -19.514312)
			(xy 179.1335 -19.514312) (xy 179.1335 -19.86534) (xy 179.2351 -19.96694) (xy 179.91963 -19.96694)
			(xy 179.934946 -19.966414) (xy 179.964199 -19.957325) (xy 179.989444 -19.939973) (xy 180.00841 -19.915918)
			(xy 180.019393 -19.887322) (xy 180.021407 -19.856756) (xy 180.018436 -19.841718) (xy 180.012472 -19.815324)
			(xy 180.006109 -19.761587) (xy 180.005736 -19.73453) (xy 180.006226 -19.704562) (xy 180.014049 -19.64514)
			(xy 180.029562 -19.587247) (xy 180.052498 -19.531874) (xy 180.082465 -19.479968) (xy 180.118952 -19.432418)
			(xy 180.161332 -19.390038) (xy 180.208882 -19.353551) (xy 180.260788 -19.323584) (xy 180.316161 -19.300648)
			(xy 180.374054 -19.285135) (xy 180.433476 -19.277312) (xy 180.493412 -19.277312) (xy 180.552834 -19.285135)
			(xy 180.610727 -19.300648) (xy 180.6661 -19.323584) (xy 180.718006 -19.353551) (xy 180.765556 -19.390038)
			(xy 180.807936 -19.432418) (xy 180.844423 -19.479968) (xy 180.87439 -19.531874) (xy 180.897326 -19.587247)
			(xy 180.912839 -19.64514) (xy 180.920662 -19.704562) (xy 180.921152 -19.73453) (xy 180.921152 -19.739356)
			(xy 180.921462 -19.75459) (xy 180.929545 -19.782028) (xy 182.097932 -19.782028) (xy 182.102003 -19.726406)
			(xy 182.114129 -19.671969) (xy 182.134052 -19.619878) (xy 182.161348 -19.571243) (xy 182.195434 -19.5271)
			(xy 182.235583 -19.488391) (xy 182.280941 -19.45594) (xy 182.330541 -19.430439) (xy 182.383325 -19.412432)
			(xy 182.438168 -19.402302) (xy 182.493902 -19.400265) (xy 182.549339 -19.406365) (xy 182.603296 -19.420471)
			(xy 182.654625 -19.442283) (xy 182.702231 -19.471337) (xy 182.745099 -19.507012) (xy 182.782316 -19.548549)
			(xy 182.813089 -19.595062) (xy 182.836761 -19.645559) (xy 182.852829 -19.698966) (xy 182.860949 -19.754142)
			(xy 182.861365 -19.776948) (xy 183.111392 -19.776948) (xy 183.115463 -19.721326) (xy 183.127589 -19.666889)
			(xy 183.147512 -19.614798) (xy 183.174808 -19.566163) (xy 183.208894 -19.52202) (xy 183.249043 -19.483311)
			(xy 183.294401 -19.45086) (xy 183.344001 -19.425359) (xy 183.396785 -19.407352) (xy 183.451628 -19.397222)
			(xy 183.507362 -19.395185) (xy 183.562799 -19.401285) (xy 183.616756 -19.415391) (xy 183.668085 -19.437203)
			(xy 183.715691 -19.466257) (xy 183.758559 -19.501932) (xy 183.795776 -19.543469) (xy 183.826549 -19.589982)
			(xy 183.850221 -19.640479) (xy 183.866289 -19.693886) (xy 183.874409 -19.749062) (xy 183.874918 -19.776948)
			(xy 183.874409 -19.804834) (xy 183.866289 -19.86001) (xy 183.850221 -19.913417) (xy 183.826549 -19.963914)
			(xy 183.795776 -20.010427) (xy 183.758559 -20.051964) (xy 183.715691 -20.087639) (xy 183.668085 -20.116693)
			(xy 183.616756 -20.138505) (xy 183.562799 -20.152611) (xy 183.507362 -20.158711) (xy 183.451628 -20.156674)
			(xy 183.396785 -20.146544) (xy 183.344001 -20.128537) (xy 183.294401 -20.103036) (xy 183.249043 -20.070585)
			(xy 183.208894 -20.031876) (xy 183.174808 -19.987733) (xy 183.147512 -19.939098) (xy 183.127589 -19.887007)
			(xy 183.115463 -19.83257) (xy 183.111392 -19.776948) (xy 182.861365 -19.776948) (xy 182.861458 -19.782028)
			(xy 182.860949 -19.809914) (xy 182.852829 -19.86509) (xy 182.836761 -19.918497) (xy 182.813089 -19.968994)
			(xy 182.782316 -20.015507) (xy 182.745099 -20.057044) (xy 182.702231 -20.092719) (xy 182.654625 -20.121773)
			(xy 182.603296 -20.143585) (xy 182.549339 -20.157691) (xy 182.493902 -20.163791) (xy 182.438168 -20.161754)
			(xy 182.383325 -20.151624) (xy 182.330541 -20.133617) (xy 182.280941 -20.108116) (xy 182.235583 -20.075665)
			(xy 182.195434 -20.036956) (xy 182.161348 -19.992813) (xy 182.134052 -19.944178) (xy 182.114129 -19.892087)
			(xy 182.102003 -19.83765) (xy 182.097932 -19.782028) (xy 180.929545 -19.782028) (xy 180.930069 -19.783805)
			(xy 180.946918 -19.809177) (xy 180.970508 -19.828441) (xy 180.998735 -19.839881) (xy 181.013862 -19.841718)
			(xy 181.043715 -19.844835) (xy 181.102259 -19.858077) (xy 181.158493 -19.879067) (xy 181.211395 -19.907424)
			(xy 181.260006 -19.942634) (xy 181.303445 -19.984057) (xy 181.340922 -20.030942) (xy 181.371759 -20.082438)
			(xy 181.395395 -20.137611) (xy 181.411402 -20.195461) (xy 181.419489 -20.254937) (xy 181.420008 -20.284948)
			(xy 181.419541 -20.314078) (xy 181.411909 -20.371836) (xy 181.396796 -20.428101) (xy 181.37446 -20.481909)
			(xy 181.345284 -20.532337) (xy 181.309769 -20.578521) (xy 181.289452 -20.5994) (xy 181.162452 -20.7264)
			(xy 181.141533 -20.746669) (xy 181.095343 -20.782157) (xy 181.044918 -20.811316) (xy 180.99112 -20.833646)
			(xy 180.934868 -20.848766) (xy 180.877124 -20.856417) (xy 180.848 -20.856956) (xy 179.05095 -20.856956)
			(xy 179.02182 -20.856489) (xy 178.964062 -20.848858) (xy 178.907795 -20.833745) (xy 178.853986 -20.811411)
			(xy 178.803556 -20.782237) (xy 178.75737 -20.746725) (xy 178.736498 -20.7264) (xy 178.501548 -20.49145)
			(xy 178.481277 -20.470532) (xy 178.445785 -20.424343) (xy 178.416624 -20.373919) (xy 178.394292 -20.32012)
			(xy 178.37917 -20.263867) (xy 178.371518 -20.206122) (xy 178.370992 -20.176998) (xy 178.371568 -20.144333)
			(xy 178.381127 -20.079706) (xy 178.400037 -20.017173) (xy 178.427893 -19.95808) (xy 178.464095 -19.903698)
			(xy 178.485546 -19.879056) (xy 178.4985 -19.864578) (xy 178.4985 -19.696176) (xy 178.28895 -19.696176)
			(xy 178.263868 -19.695696) (xy 178.214325 -19.687815) (xy 178.166629 -19.672272) (xy 178.121955 -19.649451)
			(xy 178.081407 -19.619914) (xy 178.063398 -19.60245) (xy 177.84953 -19.388836) (xy 177.835814 -19.38528)
			(xy 177.808555 -19.378072) (xy 177.756371 -19.356721) (xy 177.707902 -19.327917) (xy 177.664205 -19.292286)
			(xy 177.626234 -19.250606) (xy 177.594817 -19.203788) (xy 177.57064 -19.152852) (xy 177.554231 -19.09891)
			(xy 177.545947 -19.043139) (xy 177.545492 -19.014948) (xy 177.545652 -18.999833) (xy 177.548071 -18.969698)
			(xy 177.550318 -18.95475) (xy 177.552157 -18.940183) (xy 177.548364 -18.91108) (xy 177.536453 -18.884257)
			(xy 177.517409 -18.861926) (xy 177.492802 -18.84593) (xy 177.464663 -18.83759) (xy 177.449988 -18.837148)
			(xy 176.30648 -18.837148) (xy 175.961802 -19.181826) (xy 175.961802 -19.817588) (xy 175.41748 -20.36191)
			(xy 175.41748 -21.121953) (xy 177.607155 -21.121953) (xy 177.607155 -21.067447) (xy 177.614913 -21.013494)
			(xy 177.630269 -20.961195) (xy 177.652913 -20.911614) (xy 177.682382 -20.865761) (xy 177.718077 -20.824568)
			(xy 177.759272 -20.788874) (xy 177.805127 -20.759406) (xy 177.854709 -20.736765) (xy 177.907008 -20.72141)
			(xy 177.96096 -20.713654) (xy 177.988214 -20.713192) (xy 178.01495 -20.713723) (xy 178.067896 -20.721205)
			(xy 178.119278 -20.736006) (xy 178.168091 -20.757837) (xy 178.213377 -20.786269) (xy 178.25425 -20.820747)
			(xy 178.289908 -20.860593) (xy 178.319653 -20.905028) (xy 178.342903 -20.953181) (xy 178.359201 -21.004109)
			(xy 178.368229 -21.056813) (xy 178.369468 -21.083524) (xy 178.370391 -21.09818) (xy 178.37959 -21.126055)
			(xy 178.396329 -21.150169) (xy 178.419228 -21.168535) (xy 178.446401 -21.179639) (xy 178.475609 -21.182567)
			(xy 178.490118 -21.180298) (xy 178.507917 -21.177104) (xy 178.543918 -21.173667) (xy 178.562 -21.17344)
			(xy 178.5885 -21.173845) (xy 178.640991 -21.181169) (xy 178.691963 -21.19569) (xy 178.740433 -21.217129)
			(xy 178.785467 -21.245073) (xy 178.826199 -21.278982) (xy 178.861844 -21.318205) (xy 178.891715 -21.361985)
			(xy 178.903884 -21.38553) (xy 178.911077 -21.398787) (xy 178.931754 -21.420723) (xy 178.957923 -21.435686)
			(xy 178.987316 -21.442379) (xy 179.017384 -21.44022) (xy 179.031646 -21.435314) (xy 179.053625 -21.42716)
			(xy 179.099093 -21.41574) (xy 179.14562 -21.409997) (xy 179.16906 -21.40966) (xy 179.196312 -21.410185)
			(xy 179.250263 -21.417936) (xy 179.302561 -21.433288) (xy 179.352142 -21.455926) (xy 179.397997 -21.48539)
			(xy 179.439191 -21.521081) (xy 179.474886 -21.562271) (xy 179.504355 -21.608122) (xy 179.526471 -21.656548)
			(xy 182.269382 -21.656548) (xy 182.273453 -21.600926) (xy 182.285579 -21.546489) (xy 182.305502 -21.494398)
			(xy 182.332798 -21.445763) (xy 182.366884 -21.40162) (xy 182.407033 -21.362911) (xy 182.452391 -21.33046)
			(xy 182.501991 -21.304959) (xy 182.554775 -21.286952) (xy 182.609618 -21.276822) (xy 182.665352 -21.274785)
			(xy 182.720789 -21.280885) (xy 182.774746 -21.294991) (xy 182.826075 -21.316803) (xy 182.873681 -21.345857)
			(xy 182.916549 -21.381532) (xy 182.953766 -21.423069) (xy 182.984539 -21.469582) (xy 183.008211 -21.520079)
			(xy 183.024279 -21.573486) (xy 183.032399 -21.628662) (xy 183.032908 -21.656548) (xy 183.032399 -21.684434)
			(xy 183.024279 -21.73961) (xy 183.008211 -21.793017) (xy 182.984539 -21.843514) (xy 182.953766 -21.890027)
			(xy 182.916549 -21.931564) (xy 182.873681 -21.967239) (xy 182.826075 -21.996293) (xy 182.774746 -22.018105)
			(xy 182.720789 -22.032211) (xy 182.665352 -22.038311) (xy 182.609618 -22.036274) (xy 182.554775 -22.026144)
			(xy 182.501991 -22.008137) (xy 182.452391 -21.982636) (xy 182.407033 -21.950185) (xy 182.366884 -21.911476)
			(xy 182.332798 -21.867333) (xy 182.305502 -21.818698) (xy 182.285579 -21.766607) (xy 182.273453 -21.71217)
			(xy 182.269382 -21.656548) (xy 179.526471 -21.656548) (xy 179.526998 -21.657701) (xy 179.542355 -21.709998)
			(xy 179.550113 -21.763948) (xy 179.550113 -21.818452) (xy 179.542355 -21.872402) (xy 179.526998 -21.924699)
			(xy 179.504355 -21.974278) (xy 179.474886 -22.020129) (xy 179.439191 -22.061319) (xy 179.397997 -22.09701)
			(xy 179.352142 -22.126474) (xy 179.302561 -22.149112) (xy 179.250263 -22.164464) (xy 179.196312 -22.172215)
			(xy 179.16906 -22.172676) (xy 179.142562 -22.172213) (xy 179.090074 -22.164897) (xy 179.039104 -22.150384)
			(xy 178.990635 -22.128954) (xy 178.9456 -22.101018) (xy 178.904867 -22.067116) (xy 178.86922 -22.027901)
			(xy 178.839346 -21.984128) (xy 178.827176 -21.960586) (xy 178.820019 -21.947307) (xy 178.799334 -21.925367)
			(xy 178.773155 -21.910406) (xy 178.743752 -21.903719) (xy 178.713678 -21.905889) (xy 178.699414 -21.910802)
			(xy 178.67743 -21.918939) (xy 178.631964 -21.930365) (xy 178.58544 -21.936116) (xy 178.562 -21.936456)
			(xy 178.53526 -21.936056) (xy 178.482307 -21.928561) (xy 178.430919 -21.913746) (xy 178.382102 -21.891902)
			(xy 178.336814 -21.863456) (xy 178.295941 -21.828965) (xy 178.260284 -21.789105) (xy 178.230541 -21.744658)
			(xy 178.207296 -21.696493) (xy 178.191003 -21.645554) (xy 178.181982 -21.59284) (xy 178.180746 -21.566124)
			(xy 178.179768 -21.551473) (xy 178.170582 -21.523601) (xy 178.153855 -21.499487) (xy 178.130966 -21.48112)
			(xy 178.103802 -21.470013) (xy 178.074601 -21.467083) (xy 178.060096 -21.46935) (xy 178.042297 -21.472543)
			(xy 178.006296 -21.475981) (xy 177.988214 -21.476208) (xy 177.96096 -21.475746) (xy 177.907008 -21.46799)
			(xy 177.854709 -21.452635) (xy 177.805127 -21.429994) (xy 177.759272 -21.400526) (xy 177.718077 -21.364832)
			(xy 177.682382 -21.323639) (xy 177.652913 -21.277786) (xy 177.630269 -21.228205) (xy 177.614913 -21.175906)
			(xy 177.607155 -21.121953) (xy 175.41748 -21.121953) (xy 175.41748 -21.912326) (xy 175.961802 -22.456648)
			(xy 175.961802 -26.377392) (xy 176.046892 -26.462736) (xy 176.046892 -26.557732) (xy 179.937156 -26.557732)
			(xy 179.937156 -25.922732) (xy 180.12791 -25.922732) (xy 180.138887 -25.915651) (xy 180.161638 -25.90281)
			(xy 180.173376 -25.897078) (xy 180.201824 -25.883108) (xy 180.201824 -25.862788) (xy 180.283866 -25.862788)
			(xy 180.287422 -25.862534) (xy 180.300371 -25.860803) (xy 180.326429 -25.858897) (xy 180.339492 -25.858724)
			(xy 180.957982 -25.858724) (xy 180.985238 -25.859122) (xy 181.039195 -25.866877) (xy 181.0915 -25.882233)
			(xy 181.141087 -25.904876) (xy 181.186946 -25.934346) (xy 181.228144 -25.970043) (xy 181.263843 -26.01124)
			(xy 181.293315 -26.057098) (xy 181.315961 -26.106683) (xy 181.331319 -26.158987) (xy 181.339077 -26.212944)
			(xy 181.339077 -26.267456) (xy 181.331319 -26.321413) (xy 181.315961 -26.373717) (xy 181.293315 -26.423302)
			(xy 181.263843 -26.46916) (xy 181.228144 -26.510357) (xy 181.186946 -26.546054) (xy 181.141087 -26.575524)
			(xy 181.0915 -26.598167) (xy 181.039195 -26.613523) (xy 180.985238 -26.621278) (xy 180.957982 -26.62174)
			(xy 180.339492 -26.62174) (xy 180.326429 -26.621576) (xy 180.300371 -26.619667) (xy 180.287422 -26.61793)
			(xy 180.283866 -26.617676) (xy 180.201824 -26.617676) (xy 180.201824 -26.597356) (xy 180.173376 -26.583386)
			(xy 180.161634 -26.577662) (xy 180.138879 -26.564826) (xy 180.12791 -26.557732) (xy 179.937156 -26.557732)
			(xy 176.046892 -26.557732) (xy 176.046892 -27.107388) (xy 180.539642 -27.107388) (xy 180.543713 -27.051766)
			(xy 180.555839 -26.997329) (xy 180.575762 -26.945238) (xy 180.603058 -26.896603) (xy 180.637144 -26.85246)
			(xy 180.677293 -26.813751) (xy 180.722651 -26.7813) (xy 180.772251 -26.755799) (xy 180.825035 -26.737792)
			(xy 180.879878 -26.727662) (xy 180.935612 -26.725625) (xy 180.991049 -26.731725) (xy 181.045006 -26.745831)
			(xy 181.096335 -26.767643) (xy 181.143941 -26.796697) (xy 181.186809 -26.832372) (xy 181.224026 -26.873909)
			(xy 181.254799 -26.920422) (xy 181.278471 -26.970919) (xy 181.294539 -27.024326) (xy 181.302659 -27.079502)
			(xy 181.303168 -27.107388) (xy 181.302659 -27.135274) (xy 181.294539 -27.19045) (xy 181.278471 -27.243857)
			(xy 181.254799 -27.294354) (xy 181.224026 -27.340867) (xy 181.186809 -27.382404) (xy 181.143941 -27.418079)
			(xy 181.096335 -27.447133) (xy 181.045006 -27.468945) (xy 180.991049 -27.483051) (xy 180.935612 -27.489151)
			(xy 180.879878 -27.487114) (xy 180.825035 -27.476984) (xy 180.772251 -27.458977) (xy 180.722651 -27.433476)
			(xy 180.677293 -27.401025) (xy 180.637144 -27.362316) (xy 180.603058 -27.318173) (xy 180.575762 -27.269538)
			(xy 180.555839 -27.217447) (xy 180.543713 -27.16301) (xy 180.539642 -27.107388) (xy 176.046892 -27.107388)
			(xy 176.046892 -27.87396) (xy 176.14392 -27.970988) (xy 180.71592 -27.970988)
		)
		(stroke
			(width 0)
			(type solid)
		)
		(fill yes)
		(layer "F.Cu")
		(net "P12V_SCM_R")
	)
	(gr_poly
		(pts
			(xy 138.176 -363.54131) (xy 141.807438 -363.54131) (xy 142.241778 -363.10697) (xy 142.241778 -361.85475)
			(xy 143.9037 -360.192828) (xy 154.09926 -360.192828) (xy 154.52344 -359.768648) (xy 154.52344 -338.358988)
			(xy 154.05608 -337.891628) (xy 143.18996 -337.891628) (xy 142.90294 -337.604608) (xy 142.90294 -336.827368)
			(xy 141.756384 -335.680812) (xy 135.700516 -335.680812) (xy 135.310626 -335.291176) (xy 135.310626 -334.151732)
			(xy 134.891526 -333.732632) (xy 133.301486 -333.732632) (xy 132.770626 -333.201772) (xy 132.770626 -330.811632)
			(xy 131.858258 -329.899264) (xy 127.419354 -329.899264) (xy 127.20574 -329.68565) (xy 127.20574 -329.685396)
			(xy 127.183642 -329.663298) (xy 127.183642 -328.145648) (xy 126.928626 -327.890632) (xy 124.812806 -327.890632)
			(xy 123.466606 -326.544432) (xy 94.365826 -326.544432) (xy 94.162626 -326.747632) (xy 94.162626 -329.287632)
			(xy 93.550994 -329.899264) (xy 86.057994 -329.899264) (xy 85.788246 -330.169012) (xy 85.788246 -334.125824)
			(xy 86.336378 -334.125824) (xy 86.377018 -334.125824) (xy 86.377018 -330.56068) (xy 86.514686 -330.423012)
			(xy 91.195906 -330.423012) (xy 91.292426 -330.519532) (xy 91.292426 -330.71562) (xy 94.49689 -330.71562)
			(xy 94.53753 -330.71562) (xy 94.53753 -327.203308) (xy 94.698566 -327.042272) (xy 99.273106 -327.042272)
			(xy 99.453446 -327.222612) (xy 99.453446 -328.264012) (xy 99.452938 -328.26452) (xy 99.452938 -330.71562)
			(xy 99.498658 -330.71562) (xy 102.657402 -330.71562) (xy 102.698042 -330.71562) (xy 102.698042 -327.236836)
			(xy 102.785926 -327.148952) (xy 107.446826 -327.148952) (xy 107.601766 -327.303892) (xy 107.601766 -328.044302)
			(xy 107.61345 -328.055986) (xy 107.61345 -330.71562) (xy 107.65917 -330.71562) (xy 110.817914 -330.71562)
			(xy 110.858554 -330.71562) (xy 110.858554 -327.283064) (xy 111.002826 -327.138792) (xy 115.704366 -327.138792)
			(xy 115.772946 -327.207372) (xy 115.772946 -328.221848) (xy 115.773962 -328.222864) (xy 115.773962 -330.71562)
			(xy 115.819682 -330.71562) (xy 118.978426 -330.71562) (xy 119.019066 -330.71562) (xy 119.019066 -327.242932)
			(xy 119.156226 -327.105772) (xy 123.611386 -327.105772) (xy 123.936506 -327.430892) (xy 123.936506 -328.256392)
			(xy 123.934474 -328.258424) (xy 123.934474 -330.71562) (xy 123.980194 -330.71562) (xy 123.980194 -331.465936)
			(xy 118.978426 -331.465936) (xy 118.978426 -330.71562) (xy 115.819682 -330.71562) (xy 115.819682 -331.465936)
			(xy 110.817914 -331.465936) (xy 110.817914 -330.71562) (xy 107.65917 -330.71562) (xy 107.65917 -331.465936)
			(xy 102.657402 -331.465936) (xy 102.657402 -330.71562) (xy 99.498658 -330.71562) (xy 99.498658 -331.465936)
			(xy 94.49689 -331.465936) (xy 94.49689 -330.71562) (xy 91.292426 -330.71562) (xy 91.292426 -334.125824)
			(xy 91.338146 -334.125824) (xy 91.338146 -334.87614) (xy 86.336378 -334.87614) (xy 86.336378 -334.125824)
			(xy 85.788246 -334.125824) (xy 85.788246 -334.775556) (xy 84.774278 -335.789524) (xy 78.264258 -335.789524)
			(xy 78.06563 -335.590896) (xy 78.06563 -334.042258) (xy 78.256384 -333.851504) (xy 82.855816 -333.851504)
			(xy 83.548982 -333.158338) (xy 83.548982 -332.208632) (xy 82.952082 -331.611732) (xy 70.506336 -331.611732)
			(xy 70.235318 -331.88275) (xy 70.235318 -332.227174) (xy 76.744066 -332.227174) (xy 76.748139 -332.171515)
			(xy 76.760274 -332.117042) (xy 76.78021 -332.064916) (xy 76.807524 -332.016248) (xy 76.841632 -331.972076)
			(xy 76.881809 -331.933341) (xy 76.927197 -331.900869) (xy 76.976829 -331.875351) (xy 77.029649 -331.857332)
			(xy 77.084528 -331.847195) (xy 77.140299 -331.845157) (xy 77.195773 -331.85126) (xy 77.249766 -331.865376)
			(xy 77.301129 -331.887203) (xy 77.348767 -331.916276) (xy 77.391663 -331.951975) (xy 77.428905 -331.993539)
			(xy 77.459699 -332.040083) (xy 77.483387 -332.090614) (xy 77.499465 -332.144056) (xy 77.507591 -332.19927)
			(xy 77.5081 -332.227174) (xy 77.507591 -332.255078) (xy 77.499465 -332.310292) (xy 77.483387 -332.363734)
			(xy 77.459699 -332.414265) (xy 77.428905 -332.460809) (xy 77.391663 -332.502373) (xy 77.348767 -332.538072)
			(xy 77.301129 -332.567145) (xy 77.249766 -332.588972) (xy 77.195773 -332.603088) (xy 77.140299 -332.609191)
			(xy 77.084528 -332.607153) (xy 77.029649 -332.597016) (xy 76.976829 -332.578997) (xy 76.927197 -332.553479)
			(xy 76.881809 -332.521007) (xy 76.841632 -332.482272) (xy 76.807524 -332.4381) (xy 76.78021 -332.389432)
			(xy 76.760274 -332.337306) (xy 76.748139 -332.282833) (xy 76.744066 -332.227174) (xy 70.235318 -332.227174)
			(xy 70.235318 -339.916516) (xy 78.175866 -339.916516) (xy 78.216506 -339.916516) (xy 78.216506 -336.389472)
			(xy 78.320646 -336.285332) (xy 82.979006 -336.285332) (xy 83.133946 -336.440272) (xy 83.133946 -337.423252)
			(xy 83.131914 -337.425284) (xy 83.131914 -339.916516) (xy 83.177634 -339.916516) (xy 83.177634 -340.666832)
			(xy 78.175866 -340.666832) (xy 78.175866 -339.916516) (xy 70.235318 -339.916516) (xy 70.235318 -342.02243)
			(xy 70.809866 -342.596978) (xy 77.7113 -342.596978) (xy 78.141068 -342.16721) (xy 78.175866 -342.16721)
			(xy 78.175866 -342.166956) (xy 79.72679 -342.166956) (xy 79.72679 -343.123774) (xy 79.686404 -343.16416)
			(xy 78.875382 -343.16416) (xy 78.875382 -343.209372) (xy 78.871826 -343.209372) (xy 78.803246 -343.277952)
			(xy 78.27264 -343.277952) (xy 78.27264 -343.498932) (xy 78.821026 -343.498932) (xy 78.875382 -343.553288)
			(xy 78.875382 -343.681812) (xy 78.877414 -343.686892) (xy 78.877414 -344.529664) (xy 78.875382 -344.534744)
			(xy 78.875382 -344.56751) (xy 78.874874 -344.56751) (xy 78.814422 -344.627962) (xy 77.996288 -344.627962)
			(xy 77.975206 -344.649044) (xy 77.975206 -344.840814) (xy 77.989176 -344.854784) (xy 78.856586 -344.854784)
			(xy 78.875382 -344.87358) (xy 78.875382 -344.951812) (xy 78.877414 -344.956892) (xy 78.877414 -345.143328)
			(xy 78.8924 -345.179396) (xy 78.913228 -345.200224) (xy 78.941676 -345.211908) (xy 78.958694 -345.207082)
			(xy 78.987666 -345.198952) (xy 79.046756 -345.187557) (xy 79.106659 -345.181808) (xy 79.136748 -345.181428)
			(xy 79.170071 -345.181862) (xy 79.236349 -345.188857) (xy 79.301532 -345.202743) (xy 79.333344 -345.21267)
			(xy 79.340964 -345.21521) (xy 80.634332 -345.21521) (xy 80.6704 -345.200224) (xy 80.727296 -345.143328)
			(xy 80.727296 -343.180162) (xy 80.731106 -343.176352) (xy 80.731106 -342.963754) (xy 80.82788 -342.86698)
			(xy 83.177634 -342.86698) (xy 83.177634 -342.877648) (xy 84.363052 -342.877648) (xy 84.365846 -342.875108)
			(xy 84.367624 -342.876886) (xy 84.543392 -342.876886) (xy 84.657946 -342.762332) (xy 84.657946 -337.006692)
			(xy 84.858352 -336.806286) (xy 85.871812 -336.806286) (xy 86.30158 -336.376518) (xy 86.336378 -336.376518)
			(xy 86.336378 -336.376264) (xy 87.887302 -336.376264) (xy 87.887302 -337.333082) (xy 87.846916 -337.373468)
			(xy 87.035894 -337.373468) (xy 87.035894 -337.468972) (xy 87.035386 -337.468972) (xy 87.002366 -337.501992)
			(xy 86.437216 -337.501992) (xy 86.437216 -337.715352) (xy 87.002366 -337.715352) (xy 87.035894 -337.74888)
			(xy 87.035894 -337.89112) (xy 87.037926 -337.8962) (xy 87.037926 -338.738972) (xy 87.035894 -338.744052)
			(xy 87.035894 -338.78012) (xy 87.034878 -338.78012) (xy 86.974426 -338.840572) (xy 86.41588 -338.840572)
			(xy 86.41588 -339.062314) (xy 87.020654 -339.062314) (xy 87.035894 -339.077554) (xy 87.035894 -339.16112)
			(xy 87.037926 -339.1662) (xy 87.037926 -339.352636) (xy 87.052912 -339.388704) (xy 87.07374 -339.409532)
			(xy 87.102188 -339.421216) (xy 87.119206 -339.41639) (xy 87.148178 -339.408261) (xy 87.207268 -339.396867)
			(xy 87.267171 -339.391119) (xy 87.29726 -339.390736) (xy 87.330583 -339.391171) (xy 87.39686 -339.398167)
			(xy 87.462043 -339.412054) (xy 87.493856 -339.421978) (xy 87.501476 -339.424518) (xy 88.794844 -339.424518)
			(xy 88.830912 -339.409532) (xy 88.887808 -339.352636) (xy 88.887808 -337.38947) (xy 88.891618 -337.38566)
			(xy 88.891618 -337.173062) (xy 88.988392 -337.076288) (xy 91.338146 -337.076288) (xy 91.338146 -337.086956)
			(xy 92.523564 -337.086956) (xy 92.526358 -337.084416) (xy 92.528136 -337.086194) (xy 92.703904 -337.086194)
			(xy 92.818458 -336.97164) (xy 92.818458 -333.549498) (xy 92.971874 -333.396082) (xy 94.032324 -333.396082)
			(xy 94.462092 -332.966314) (xy 94.49689 -332.966314) (xy 94.49689 -332.96606) (xy 96.047814 -332.96606)
			(xy 96.047814 -333.922878) (xy 96.007428 -333.963264) (xy 95.196406 -333.963264) (xy 95.196406 -334.060292)
			(xy 95.171006 -334.085692) (xy 94.5896 -334.085692) (xy 94.5896 -334.284828) (xy 95.144082 -334.284828)
			(xy 95.196406 -334.337152) (xy 95.196406 -334.480916) (xy 95.198438 -334.485996) (xy 95.198438 -335.328768)
			(xy 95.196406 -335.333848) (xy 95.196406 -335.369916) (xy 95.19285 -335.369916) (xy 95.112078 -335.450688)
			(xy 94.615 -335.450688) (xy 94.597728 -335.46796) (xy 94.597728 -335.606136) (xy 94.65056 -335.658968)
			(xy 95.145606 -335.658968) (xy 95.196406 -335.709768) (xy 95.196406 -335.750916) (xy 95.198438 -335.755996)
			(xy 95.198438 -335.942432) (xy 95.213424 -335.9785) (xy 95.234252 -335.999328) (xy 95.2627 -336.011012)
			(xy 95.279718 -336.006186) (xy 95.30869 -335.998057) (xy 95.36778 -335.986665) (xy 95.427683 -335.980918)
			(xy 95.457772 -335.980532) (xy 95.491095 -335.980968) (xy 95.557372 -335.987964) (xy 95.622554 -336.001853)
			(xy 95.654368 -336.011774) (xy 95.661988 -336.014314) (xy 96.955356 -336.014314) (xy 96.991424 -335.999328)
			(xy 97.04832 -335.942432) (xy 97.04832 -333.979266) (xy 97.05213 -333.975456) (xy 97.05213 -333.762858)
			(xy 97.148904 -333.666084) (xy 99.498658 -333.666084) (xy 99.498658 -333.676752) (xy 100.684076 -333.676752)
			(xy 100.68687 -333.674212) (xy 100.688648 -333.67599) (xy 100.97897 -333.67599) (xy 101.258878 -333.396082)
			(xy 102.192836 -333.396082) (xy 102.622604 -332.966314) (xy 102.657402 -332.966314) (xy 102.657402 -332.96606)
			(xy 104.208326 -332.96606) (xy 104.208326 -333.922878) (xy 104.16794 -333.963264) (xy 103.356918 -333.963264)
			(xy 103.356918 -334.062832) (xy 103.354886 -334.062832) (xy 103.332026 -334.085692) (xy 102.612698 -334.085692)
			(xy 102.584758 -334.113632) (xy 102.584758 -334.253332) (xy 102.638098 -334.306672) (xy 103.321866 -334.306672)
			(xy 103.356918 -334.341724) (xy 103.356918 -334.480916) (xy 103.35895 -334.485996) (xy 103.35895 -335.328768)
			(xy 103.356918 -335.333848) (xy 103.356918 -335.372964) (xy 103.353362 -335.372964) (xy 103.290878 -335.435448)
			(xy 102.47757 -335.435448) (xy 102.46233 -335.450688) (xy 102.46233 -335.63433) (xy 102.480364 -335.652364)
			(xy 103.33736 -335.652364) (xy 103.356918 -335.671922) (xy 103.356918 -335.750916) (xy 103.35895 -335.755996)
			(xy 103.35895 -335.942432) (xy 103.373936 -335.9785) (xy 103.394764 -335.999328) (xy 103.423212 -336.011012)
			(xy 103.44023 -336.006186) (xy 103.469202 -335.998058) (xy 103.528292 -335.986666) (xy 103.588195 -335.98092)
			(xy 103.618284 -335.980532) (xy 103.651606 -335.980968) (xy 103.717883 -335.987966) (xy 103.783065 -336.001856)
			(xy 103.81488 -336.011774) (xy 103.8225 -336.014314) (xy 105.115868 -336.014314) (xy 105.151936 -335.999328)
			(xy 105.208832 -335.942432) (xy 105.208832 -333.979266) (xy 105.212642 -333.975456) (xy 105.212642 -333.762858)
			(xy 105.309416 -333.666084) (xy 107.65917 -333.666084) (xy 107.65917 -333.676752) (xy 108.844588 -333.676752)
			(xy 108.847382 -333.674212) (xy 108.84916 -333.67599) (xy 109.139482 -333.67599) (xy 109.41939 -333.396082)
			(xy 110.353348 -333.396082) (xy 110.783116 -332.966314) (xy 110.817914 -332.966314) (xy 110.817914 -332.96606)
			(xy 112.368838 -332.96606) (xy 112.368838 -333.922878) (xy 112.328452 -333.963264) (xy 111.51743 -333.963264)
			(xy 111.51743 -334.060292) (xy 111.493046 -334.084676) (xy 111.493046 -334.085692) (xy 111.490506 -334.088232)
			(xy 110.9091 -334.088232) (xy 110.9091 -334.299052) (xy 111.508286 -334.299052) (xy 111.51743 -334.308196)
			(xy 111.51743 -334.480916) (xy 111.519462 -334.485996) (xy 111.519462 -335.328768) (xy 111.51743 -335.333848)
			(xy 111.51743 -335.37652) (xy 111.472726 -335.421224) (xy 111.472726 -335.42224) (xy 111.468662 -335.426304)
			(xy 110.918752 -335.426304) (xy 110.918752 -335.656428) (xy 111.501936 -335.656428) (xy 111.51743 -335.671922)
			(xy 111.51743 -335.750916) (xy 111.519462 -335.755996) (xy 111.519462 -335.942432) (xy 111.534448 -335.9785)
			(xy 111.555276 -335.999328) (xy 111.583724 -336.011012) (xy 111.600742 -336.006186) (xy 111.629715 -335.998058)
			(xy 111.688804 -335.986668) (xy 111.748707 -335.980923) (xy 111.778796 -335.980532) (xy 111.812118 -335.980969)
			(xy 111.878395 -335.987968) (xy 111.943576 -336.001859) (xy 111.975392 -336.011774) (xy 111.983012 -336.014314)
			(xy 113.27638 -336.014314) (xy 113.312448 -335.999328) (xy 113.369344 -335.942432) (xy 113.369344 -333.979266)
			(xy 113.373154 -333.975456) (xy 113.373154 -333.762858) (xy 113.469928 -333.666084) (xy 115.819682 -333.666084)
			(xy 115.819682 -333.676752) (xy 117.0051 -333.676752) (xy 117.007894 -333.674212) (xy 117.009672 -333.67599)
			(xy 117.299994 -333.67599) (xy 117.579902 -333.396082) (xy 118.51386 -333.396082) (xy 118.943628 -332.966314)
			(xy 118.978426 -332.966314) (xy 118.978426 -332.96606) (xy 120.52935 -332.96606) (xy 120.52935 -333.922878)
			(xy 120.488964 -333.963264) (xy 119.677942 -333.963264) (xy 119.677942 -334.050132) (xy 119.674386 -334.050132)
			(xy 119.638826 -334.085692) (xy 119.0752 -334.085692) (xy 119.0752 -334.291432) (xy 119.648986 -334.291432)
			(xy 119.677942 -334.320388) (xy 119.677942 -334.480916) (xy 119.679974 -334.485996) (xy 119.679974 -335.328768)
			(xy 119.677942 -335.333848) (xy 119.677942 -335.371948) (xy 119.67464 -335.371948) (xy 119.619014 -335.427574)
			(xy 119.05996 -335.427574) (xy 119.05996 -335.655412) (xy 119.651526 -335.655412) (xy 119.677942 -335.681828)
			(xy 119.677942 -335.750916) (xy 119.679974 -335.755996) (xy 119.679974 -335.942432) (xy 119.69496 -335.9785)
			(xy 119.715788 -335.999328) (xy 119.744236 -336.011012) (xy 119.761254 -336.006186) (xy 119.790226 -335.998054)
			(xy 119.849316 -335.986656) (xy 119.909219 -335.980903) (xy 119.939308 -335.980532) (xy 119.97263 -335.980969)
			(xy 120.038906 -335.98797) (xy 120.104087 -336.001862) (xy 120.135904 -336.011774) (xy 120.143524 -336.014314)
			(xy 121.436892 -336.014314) (xy 121.47296 -335.999328) (xy 121.529856 -335.942432) (xy 121.529856 -333.979266)
			(xy 121.533666 -333.975456) (xy 121.533666 -333.762858) (xy 121.63044 -333.666084) (xy 123.980194 -333.666084)
			(xy 123.980194 -333.676752) (xy 125.165612 -333.676752) (xy 125.168406 -333.674212) (xy 125.170184 -333.67599)
			(xy 125.460506 -333.67599) (xy 125.755654 -333.971138) (xy 125.755654 -334.125824) (xy 127.138938 -334.125824)
			(xy 127.179578 -334.125824) (xy 127.179578 -330.75118) (xy 127.411226 -330.519532) (xy 131.871466 -330.519532)
			(xy 132.094986 -330.743052) (xy 132.094986 -334.125824) (xy 132.140706 -334.125824) (xy 132.140706 -334.87614)
			(xy 127.138938 -334.87614) (xy 127.138938 -334.125824) (xy 125.755654 -334.125824) (xy 125.755654 -336.686906)
			(xy 125.875034 -336.806286) (xy 126.674372 -336.806286) (xy 127.10414 -336.376518) (xy 127.138938 -336.376518)
			(xy 127.138938 -336.376264) (xy 128.689862 -336.376264) (xy 128.689862 -337.333082) (xy 128.649476 -337.373468)
			(xy 127.838454 -337.373468) (xy 127.838454 -337.474052) (xy 127.815086 -337.49742) (xy 127.815086 -337.499452)
			(xy 127.810006 -337.504532) (xy 127.239776 -337.504532) (xy 127.239776 -337.707732) (xy 127.810006 -337.707732)
			(xy 127.838454 -337.73618) (xy 127.838454 -337.89112) (xy 127.840486 -337.8962) (xy 127.840486 -338.738972)
			(xy 127.838454 -338.744052) (xy 127.765048 -338.817458) (xy 127.765048 -338.817712) (xy 127.746506 -338.836254)
			(xy 127.22606 -338.836254) (xy 127.22606 -339.065616) (xy 127.813816 -339.065616) (xy 127.838454 -339.090254)
			(xy 127.838454 -339.16112) (xy 127.840486 -339.1662) (xy 127.840486 -339.352636) (xy 127.855472 -339.388704)
			(xy 127.8763 -339.409532) (xy 127.904748 -339.421216) (xy 127.921766 -339.41639) (xy 127.950738 -339.408259)
			(xy 128.009828 -339.396861) (xy 128.069731 -339.391109) (xy 128.09982 -339.390736) (xy 128.133142 -339.391174)
			(xy 128.199418 -339.398176) (xy 128.264598 -339.412069) (xy 128.296416 -339.421978) (xy 128.304036 -339.424518)
			(xy 129.597404 -339.424518) (xy 129.633472 -339.409532) (xy 129.690368 -339.352636) (xy 129.690368 -337.38947)
			(xy 129.694178 -337.38566) (xy 129.694178 -337.173062) (xy 129.790952 -337.076288) (xy 132.140706 -337.076288)
			(xy 132.140706 -337.086956) (xy 133.704838 -337.086956) (xy 133.966458 -337.348576) (xy 133.966458 -339.916516)
			(xy 135.29945 -339.916516) (xy 135.34009 -339.916516) (xy 135.34009 -336.339688) (xy 135.452866 -336.226912)
			(xy 140.156946 -336.226912) (xy 140.309346 -336.379312) (xy 140.309346 -337.402932) (xy 140.306298 -337.40598)
			(xy 140.306298 -339.23478) (xy 140.255498 -339.28558) (xy 140.255498 -339.916516) (xy 140.301218 -339.916516)
			(xy 140.301218 -340.666832) (xy 135.29945 -340.666832) (xy 135.29945 -339.916516) (xy 133.966458 -339.916516)
			(xy 133.966458 -342.530684) (xy 134.032752 -342.596978) (xy 134.834884 -342.596978) (xy 135.264652 -342.16721)
			(xy 135.29945 -342.16721) (xy 135.29945 -342.166956) (xy 136.850374 -342.166956) (xy 136.850374 -343.123774)
			(xy 136.809988 -343.16416) (xy 135.998966 -343.16416) (xy 135.998966 -343.242392) (xy 135.958326 -343.283032)
			(xy 135.400288 -343.283032) (xy 135.400288 -343.491312) (xy 135.960866 -343.491312) (xy 135.998966 -343.529412)
			(xy 135.998966 -343.681812) (xy 136.000998 -343.686892) (xy 136.000998 -344.529664) (xy 135.998966 -344.534744)
			(xy 135.994648 -344.534744) (xy 135.897874 -344.631518) (xy 135.117586 -344.631518) (xy 135.096504 -344.6526)
			(xy 135.096504 -344.824558) (xy 135.127746 -344.8558) (xy 135.971534 -344.8558) (xy 135.998966 -344.883232)
			(xy 135.998966 -344.951812) (xy 136.000998 -344.956892) (xy 136.000998 -345.143328) (xy 136.015984 -345.179396)
			(xy 136.036812 -345.200224) (xy 136.06526 -345.211908) (xy 136.082278 -345.207082) (xy 136.11125 -345.198951)
			(xy 136.17034 -345.187555) (xy 136.230243 -345.181804) (xy 136.260332 -345.181428) (xy 136.293654 -345.181867)
			(xy 136.359929 -345.188869) (xy 136.42511 -345.202763) (xy 136.456928 -345.21267) (xy 136.464548 -345.21521)
			(xy 137.757916 -345.21521) (xy 137.793984 -345.200224) (xy 137.85088 -345.143328) (xy 137.85088 -343.180162)
			(xy 137.85469 -343.176352) (xy 137.85469 -342.963754) (xy 137.951464 -342.86698) (xy 140.301218 -342.86698)
			(xy 140.301218 -342.877648) (xy 145.53692 -342.877648) (xy 145.88236 -343.223088) (xy 145.88236 -346.182188)
			(xy 145.3515 -346.713048) (xy 143.52016 -346.713048) (xy 143.3068 -346.926408) (xy 143.3068 -349.926148)
			(xy 142.82928 -350.403668) (xy 141.0081 -350.403668) (xy 141.00302 -350.408748) (xy 130.894328 -350.408748)
			(xy 130.523742 -350.038162) (xy 126.907544 -350.038162) (xy 126.704344 -350.241362) (xy 126.704344 -359.711498)
			(xy 126.724664 -359.731818) (xy 126.724664 -359.739692) (xy 126.752604 -359.767632) (xy 129.80416 -359.767632)
			(xy 130.153918 -360.11739) (xy 130.153918 -362.77804) (xy 129.18821 -363.743748) (xy 134.3152 -363.743748)
			(xy 136.144508 -365.573056)
		)
		(stroke
			(width 0)
			(type solid)
		)
		(fill yes)
		(layer "F.Cu")
		(net "GND")
	)
	(gr_poly
		(pts
			(xy 383.440178 -366.12957) (xy 383.440178 -364.06201) (xy 382.114298 -362.73613) (xy 382.114298 -361.11307)
			(xy 382.584198 -360.64317) (xy 389.850122 -360.64317) (xy 389.89 -360.683048) (xy 398.10436 -360.683048)
			(xy 400.44624 -358.341168) (xy 400.44624 -332.039468) (xy 399.977102 -331.57033) (xy 383.452878 -331.57033)
			(xy 383.277872 -331.745336) (xy 383.277872 -333.38897) (xy 383.591816 -333.70266) (xy 388.18693 -333.70266)
			(xy 388.512812 -334.028542) (xy 388.512812 -335.449926) (xy 388.204456 -335.758028) (xy 381.542544 -335.758028)
			(xy 380.444756 -334.660494) (xy 380.444756 -330.409042) (xy 380.03607 -330.000356) (xy 373.244364 -330.000356)
			(xy 372.444264 -329.200256) (xy 372.444264 -327.255632) (xy 371.809264 -326.620632) (xy 342.324182 -326.620632)
			(xy 341.054182 -327.890632) (xy 339.678264 -327.890632) (xy 339.424264 -328.144632) (xy 339.424264 -329.541632)
			(xy 339.043264 -329.922632) (xy 334.598264 -329.922632) (xy 333.582264 -330.938632) (xy 333.582264 -332.495398)
			(xy 332.34503 -333.732632) (xy 331.677772 -333.732632) (xy 331.423264 -333.98714) (xy 331.423264 -334.125824)
			(xy 334.276192 -334.125824) (xy 334.316832 -334.125824) (xy 334.316832 -330.806806) (xy 334.387698 -330.736194)
			(xy 334.38973 -330.733654) (xy 334.394739 -330.727394) (xy 334.406075 -330.716056) (xy 334.412336 -330.711048)
			(xy 334.414876 -330.709016) (xy 334.558894 -330.564744) (xy 338.856574 -330.564744) (xy 338.858098 -330.566268)
			(xy 339.15604 -330.566268) (xy 339.23224 -330.642468) (xy 339.23224 -330.71562) (xy 342.436704 -330.71562)
			(xy 342.477344 -330.71562) (xy 342.477344 -327.336912) (xy 342.569038 -327.245218) (xy 342.7095 -327.245218)
			(xy 342.712294 -327.242424) (xy 347.157294 -327.242424) (xy 347.392752 -327.477882) (xy 347.392752 -330.71562)
			(xy 347.438472 -330.71562) (xy 350.597216 -330.71562) (xy 350.637856 -330.71562) (xy 350.637856 -327.30694)
			(xy 350.709484 -327.235312) (xy 350.908366 -327.235312) (xy 350.908874 -327.234804) (xy 355.385116 -327.234804)
			(xy 355.551486 -327.401174) (xy 355.551486 -327.597516) (xy 355.553264 -327.599294) (xy 355.553264 -330.71562)
			(xy 355.598984 -330.71562) (xy 358.757728 -330.71562) (xy 358.798368 -330.71562) (xy 358.798368 -327.51395)
			(xy 359.059734 -327.252584) (xy 363.420914 -327.252584) (xy 363.422692 -327.254362) (xy 363.598714 -327.254362)
			(xy 363.70768 -327.363328) (xy 363.70768 -328.219562) (xy 363.713776 -328.225912) (xy 363.713776 -330.71562)
			(xy 363.759496 -330.71562) (xy 366.91824 -330.71562) (xy 366.95888 -330.71562) (xy 366.95888 -327.499218)
			(xy 367.205514 -327.252584) (xy 371.675914 -327.252584) (xy 371.936264 -327.512934) (xy 371.936264 -331.465936)
			(xy 366.91824 -331.465936) (xy 366.91824 -330.71562) (xy 363.759496 -330.71562) (xy 363.759496 -331.465936)
			(xy 358.757728 -331.465936) (xy 358.757728 -330.71562) (xy 355.598984 -330.71562) (xy 355.598984 -331.465936)
			(xy 350.597216 -331.465936) (xy 350.597216 -330.71562) (xy 347.438472 -330.71562) (xy 347.438472 -331.465936)
			(xy 342.436704 -331.465936) (xy 342.436704 -330.71562) (xy 339.23224 -330.71562) (xy 339.23224 -334.125824)
			(xy 339.27796 -334.125824) (xy 339.27796 -334.87614) (xy 334.276192 -334.87614) (xy 334.276192 -334.125824)
			(xy 331.423264 -334.125824) (xy 331.423264 -335.365344) (xy 331.023976 -335.764632) (xy 325.535798 -335.764632)
			(xy 322.92036 -338.38007) (xy 317.872364 -338.38007) (xy 317.453264 -338.79917) (xy 317.453264 -339.916516)
			(xy 326.11568 -339.916516) (xy 326.15632 -339.916516) (xy 326.15632 -336.694018) (xy 326.247252 -336.60334)
			(xy 326.250554 -336.597752) (xy 326.259167 -336.584042) (xy 326.282057 -336.561156) (xy 326.295766 -336.55254)
			(xy 326.301354 -336.549238) (xy 326.441054 -336.409284) (xy 330.937616 -336.409284) (xy 331.071728 -336.543396)
			(xy 331.071728 -339.916516) (xy 331.117448 -339.916516) (xy 331.117448 -340.666832) (xy 326.11568 -340.666832)
			(xy 326.11568 -339.916516) (xy 317.453264 -339.916516) (xy 317.453264 -342.241632) (xy 317.80861 -342.596978)
			(xy 325.651114 -342.596978) (xy 326.080882 -342.16721) (xy 326.11568 -342.16721) (xy 326.11568 -342.166956)
			(xy 327.697084 -342.166956) (xy 327.697084 -342.909652) (xy 327.382632 -343.224104) (xy 326.92848 -343.224104)
			(xy 326.845676 -343.306908) (xy 326.841612 -343.306908) (xy 326.806052 -343.342468) (xy 326.246998 -343.342468)
			(xy 326.246998 -343.563448) (xy 326.800972 -343.563448) (xy 326.845676 -343.608152) (xy 326.845676 -343.741756)
			(xy 326.847708 -343.746836) (xy 326.847708 -344.589608) (xy 326.845676 -344.594688) (xy 326.845676 -344.673428)
			(xy 326.844152 -344.673428) (xy 326.818752 -344.698828) (xy 325.978012 -344.698828) (xy 325.955152 -344.721688)
			(xy 325.955152 -344.886788) (xy 325.970392 -344.902028) (xy 326.821292 -344.902028) (xy 326.845676 -344.926412)
			(xy 326.845676 -345.011756) (xy 326.847708 -345.016836) (xy 326.847708 -345.203272) (xy 326.862694 -345.23934)
			(xy 326.883522 -345.260168) (xy 326.912224 -345.271852) (xy 326.929242 -345.267026) (xy 326.958173 -345.258908)
			(xy 327.017179 -345.247525) (xy 327.076996 -345.241772) (xy 327.107042 -345.241372) (xy 327.140364 -345.241811)
			(xy 327.206639 -345.248815) (xy 327.271818 -345.262711) (xy 327.303638 -345.272614) (xy 327.311512 -345.275154)
			(xy 328.604626 -345.275154) (xy 328.640694 -345.260168) (xy 328.69759 -345.203272) (xy 328.69759 -343.224104)
			(xy 328.688192 -343.214706) (xy 328.688192 -342.976708) (xy 328.79792 -342.86698) (xy 331.117448 -342.86698)
			(xy 331.117448 -342.877648) (xy 332.302866 -342.877648) (xy 332.30566 -342.875108) (xy 332.307438 -342.876886)
			(xy 332.483206 -342.876886) (xy 332.59776 -342.762332) (xy 332.59776 -337.006692) (xy 332.798166 -336.806286)
			(xy 333.811626 -336.806286) (xy 334.241394 -336.376518) (xy 334.276192 -336.376518) (xy 334.276192 -336.376264)
			(xy 335.752186 -336.376264) (xy 335.82864 -336.452718) (xy 335.82864 -337.091528) (xy 335.5467 -337.373468)
			(xy 335.058512 -337.373468) (xy 334.975708 -337.456272) (xy 334.971644 -337.456272) (xy 334.936084 -337.491832)
			(xy 334.36306 -337.491832) (xy 334.36306 -337.712812) (xy 334.931004 -337.712812) (xy 334.975708 -337.757516)
			(xy 334.975708 -337.89112) (xy 334.97774 -337.8962) (xy 334.97774 -338.738972) (xy 334.975708 -338.744052)
			(xy 334.975708 -338.822792) (xy 334.974184 -338.822792) (xy 334.948784 -338.848192) (xy 334.108044 -338.848192)
			(xy 334.085184 -338.871052) (xy 334.085184 -339.036152) (xy 334.100424 -339.051392) (xy 334.951324 -339.051392)
			(xy 334.975708 -339.075776) (xy 334.975708 -339.16112) (xy 334.97774 -339.1662) (xy 334.97774 -339.352636)
			(xy 334.992726 -339.388704) (xy 335.013554 -339.409532) (xy 335.042256 -339.421216) (xy 335.059274 -339.41639)
			(xy 335.088205 -339.408269) (xy 335.14721 -339.396881) (xy 335.207027 -339.391121) (xy 335.237074 -339.390736)
			(xy 335.270396 -339.391172) (xy 335.336674 -339.398169) (xy 335.401856 -339.412057) (xy 335.43367 -339.421978)
			(xy 335.441544 -339.424518) (xy 336.734658 -339.424518) (xy 336.770726 -339.409532) (xy 336.827622 -339.352636)
			(xy 336.827622 -337.373468) (xy 336.818224 -337.36407) (xy 336.818224 -337.126072) (xy 336.868008 -337.076288)
			(xy 339.27796 -337.076288) (xy 339.27796 -337.086956) (xy 340.463378 -337.086956) (xy 340.466172 -337.084416)
			(xy 340.46795 -337.086194) (xy 340.643718 -337.086194) (xy 340.758272 -336.97164) (xy 340.758272 -333.549498)
			(xy 340.911688 -333.396082) (xy 341.972138 -333.396082) (xy 342.401906 -332.966314) (xy 342.436704 -332.966314)
			(xy 342.436704 -332.96606) (xy 343.987628 -332.96606) (xy 343.987628 -333.666084) (xy 343.993724 -333.666084)
			(xy 343.993724 -333.673704) (xy 343.704164 -333.963264) (xy 343.13622 -333.963264) (xy 343.13622 -334.039972)
			(xy 343.132664 -334.039972) (xy 343.079324 -334.093312) (xy 342.52408 -334.093312) (xy 342.52408 -334.299052)
			(xy 343.07272 -334.299052) (xy 343.13622 -334.362552) (xy 343.13622 -334.480916) (xy 343.138252 -334.485996)
			(xy 343.138252 -335.328768) (xy 343.13622 -335.333848) (xy 343.13622 -335.416652) (xy 343.132664 -335.416652)
			(xy 343.107264 -335.442052) (xy 342.279224 -335.442052) (xy 342.241124 -335.480152) (xy 342.241124 -335.624932)
			(xy 342.258904 -335.642712) (xy 343.08034 -335.642712) (xy 343.13622 -335.698592) (xy 343.13622 -335.750916)
			(xy 343.138252 -335.755996) (xy 343.138252 -335.942432) (xy 343.153238 -335.9785) (xy 343.174066 -335.999328)
			(xy 343.202768 -336.011012) (xy 343.219786 -336.006186) (xy 343.248717 -335.998066) (xy 343.307722 -335.986678)
			(xy 343.36754 -335.98092) (xy 343.397586 -335.980532) (xy 343.430908 -335.980968) (xy 343.497185 -335.987966)
			(xy 343.562367 -336.001856) (xy 343.594182 -336.011774) (xy 343.602056 -336.014314) (xy 344.89517 -336.014314)
			(xy 344.931238 -335.999328) (xy 344.988134 -335.942432) (xy 344.988134 -333.749142) (xy 345.071192 -333.666084)
			(xy 347.438472 -333.666084) (xy 347.438472 -333.676752) (xy 348.62389 -333.676752) (xy 348.626684 -333.674212)
			(xy 348.628462 -333.67599) (xy 348.918784 -333.67599) (xy 349.198692 -333.396082) (xy 350.13265 -333.396082)
			(xy 350.562418 -332.966314) (xy 350.597216 -332.966314) (xy 350.597216 -332.96606) (xy 352.14814 -332.96606)
			(xy 352.1583 -332.97622) (xy 352.1583 -333.647288) (xy 351.842324 -333.963264) (xy 351.296732 -333.963264)
			(xy 351.296732 -334.045052) (xy 351.253044 -334.08874) (xy 351.253044 -334.090772) (xy 350.968564 -334.090772)
			(xy 350.966024 -334.088232) (xy 350.61398 -334.088232) (xy 350.61398 -334.309212) (xy 351.263712 -334.309212)
			(xy 351.296732 -334.342232) (xy 351.296732 -334.480916) (xy 351.298764 -334.485996) (xy 351.298764 -335.328768)
			(xy 351.296732 -335.333848) (xy 351.296732 -335.386172) (xy 351.296224 -335.386172) (xy 351.250504 -335.431892)
			(xy 350.417384 -335.431892) (xy 350.391984 -335.457292) (xy 350.391984 -335.624932) (xy 350.419924 -335.652872)
			(xy 351.250504 -335.652872) (xy 351.296732 -335.6991) (xy 351.296732 -335.750916) (xy 351.298764 -335.755996)
			(xy 351.298764 -335.942432) (xy 351.31375 -335.9785) (xy 351.334578 -335.999328) (xy 351.36328 -336.011012)
			(xy 351.380298 -336.006186) (xy 351.409229 -335.998066) (xy 351.468234 -335.98668) (xy 351.528052 -335.980923)
			(xy 351.558098 -335.980532) (xy 351.59142 -335.980969) (xy 351.657697 -335.987968) (xy 351.722878 -336.001859)
			(xy 351.754694 -336.011774) (xy 351.762568 -336.014314) (xy 353.055682 -336.014314) (xy 353.09175 -335.999328)
			(xy 353.148646 -335.942432) (xy 353.148646 -333.75473) (xy 353.237292 -333.666084) (xy 355.598984 -333.666084)
			(xy 355.598984 -333.676752) (xy 356.784402 -333.676752) (xy 356.787196 -333.674212) (xy 356.788974 -333.67599)
			(xy 357.079296 -333.67599) (xy 357.359204 -333.396082) (xy 358.293162 -333.396082) (xy 358.72293 -332.966314)
			(xy 358.757728 -332.966314) (xy 358.757728 -332.96606) (xy 360.308652 -332.96606) (xy 360.308652 -333.269844)
			(xy 360.308144 -333.270352) (xy 360.308144 -333.757524) (xy 360.102404 -333.963264) (xy 359.457244 -333.963264)
			(xy 359.457244 -334.045052) (xy 359.454704 -334.045052) (xy 359.421684 -334.078072) (xy 358.83088 -334.078072)
			(xy 358.83088 -334.304132) (xy 359.416604 -334.304132) (xy 359.457244 -334.344772) (xy 359.457244 -334.480916)
			(xy 359.459276 -334.485996) (xy 359.459276 -335.328768) (xy 359.457244 -335.333848) (xy 359.457244 -335.373472)
			(xy 359.393744 -335.436972) (xy 358.588564 -335.436972) (xy 358.560624 -335.464912) (xy 358.560624 -335.602072)
			(xy 358.608884 -335.650332) (xy 359.426764 -335.650332) (xy 359.457244 -335.680812) (xy 359.457244 -335.750916)
			(xy 359.459276 -335.755996) (xy 359.459276 -335.942432) (xy 359.474262 -335.9785) (xy 359.49509 -335.999328)
			(xy 359.523538 -336.011012) (xy 359.535222 -336.00771) (xy 359.551409 -336.002944) (xy 359.584192 -335.994939)
			(xy 359.600754 -335.991708) (xy 359.629377 -335.986604) (xy 359.687253 -335.98101) (xy 359.716324 -335.980532)
			(xy 359.722674 -335.980532) (xy 359.755357 -335.98116) (xy 359.820341 -335.988289) (xy 359.88425 -336.002051)
			(xy 359.91546 -336.011774) (xy 359.92308 -336.014314) (xy 361.216194 -336.014314) (xy 361.252262 -335.999328)
			(xy 361.309158 -335.942432) (xy 361.309158 -333.790798) (xy 361.433872 -333.666084) (xy 363.759496 -333.666084)
			(xy 363.759496 -333.676752) (xy 364.944914 -333.676752) (xy 364.947708 -333.674212) (xy 364.949486 -333.67599)
			(xy 365.239808 -333.67599) (xy 365.519716 -333.396082) (xy 366.453674 -333.396082) (xy 366.883442 -332.966314)
			(xy 366.91824 -332.966314) (xy 366.91824 -332.96606) (xy 368.469164 -332.96606) (xy 368.469164 -333.656432)
			(xy 368.164364 -333.961232) (xy 368.164364 -333.963264) (xy 367.617756 -333.963264) (xy 367.617756 -334.047592)
			(xy 367.613184 -334.047592) (xy 367.575084 -334.085692) (xy 367.01222 -334.085692) (xy 367.01222 -334.304132)
			(xy 367.579656 -334.304132) (xy 367.617756 -334.342232) (xy 367.617756 -334.480916) (xy 367.619788 -334.485996)
			(xy 367.619788 -335.328768) (xy 367.617756 -335.333848) (xy 367.617756 -335.373472) (xy 367.585244 -335.405984)
			(xy 367.585244 -335.409032) (xy 367.559844 -335.434432) (xy 366.752124 -335.434432) (xy 366.724184 -335.462372)
			(xy 366.724184 -335.596992) (xy 366.780064 -335.652872) (xy 367.579656 -335.652872) (xy 367.617756 -335.690972)
			(xy 367.617756 -335.750916) (xy 367.619788 -335.755996) (xy 367.619788 -335.942432) (xy 367.634774 -335.9785)
			(xy 367.655602 -335.999328) (xy 367.68405 -336.011012) (xy 367.695734 -336.00771) (xy 367.711921 -336.002944)
			(xy 367.744705 -335.99494) (xy 367.761266 -335.991708) (xy 367.789889 -335.986604) (xy 367.847765 -335.981012)
			(xy 367.876836 -335.980532) (xy 367.883186 -335.980532) (xy 367.915869 -335.981161) (xy 367.980853 -335.988291)
			(xy 368.044761 -336.002054) (xy 368.075972 -336.011774) (xy 368.083592 -336.014314) (xy 369.376706 -336.014314)
			(xy 369.412774 -335.999328) (xy 369.46967 -335.942432) (xy 369.46967 -333.748126) (xy 369.551712 -333.666084)
			(xy 371.920008 -333.666084) (xy 371.920008 -333.676752) (xy 373.105426 -333.676752) (xy 373.10822 -333.674212)
			(xy 373.109998 -333.67599) (xy 373.40032 -333.67599) (xy 373.695468 -333.971138) (xy 373.695468 -334.125824)
			(xy 375.078752 -334.125824) (xy 375.119392 -334.125824) (xy 375.119392 -330.867766) (xy 375.399554 -330.587604)
			(xy 379.681994 -330.587604) (xy 379.682756 -330.58862) (xy 379.919992 -330.58862) (xy 380.033784 -330.702412)
			(xy 380.033784 -330.939648) (xy 380.0348 -330.94041) (xy 380.0348 -334.125824) (xy 380.08052 -334.125824)
			(xy 380.08052 -334.87614) (xy 375.078752 -334.87614) (xy 375.078752 -334.125824) (xy 373.695468 -334.125824)
			(xy 373.695468 -336.686906) (xy 373.814848 -336.806286) (xy 374.614186 -336.806286) (xy 375.043954 -336.376518)
			(xy 375.078752 -336.376518) (xy 375.078752 -336.376264) (xy 376.629676 -336.376264) (xy 376.629676 -337.076288)
			(xy 376.637804 -337.076288) (xy 376.637804 -337.213448) (xy 376.477784 -337.373468) (xy 375.778268 -337.373468)
			(xy 375.778268 -337.463892) (xy 375.776744 -337.463892) (xy 375.751344 -337.489292) (xy 375.16562 -337.489292)
			(xy 375.16562 -337.707732) (xy 375.751344 -337.707732) (xy 375.778268 -337.734656) (xy 375.778268 -337.89112)
			(xy 375.7803 -337.8962) (xy 375.7803 -338.738972) (xy 375.778268 -338.744306) (xy 375.778268 -338.815172)
			(xy 375.746264 -338.847176) (xy 375.746264 -338.850732) (xy 375.471944 -338.850732) (xy 375.469404 -338.848192)
			(xy 374.895364 -338.848192) (xy 374.875044 -338.868512) (xy 374.875044 -339.033612) (xy 374.908064 -339.066632)
			(xy 375.751344 -339.066632) (xy 375.778268 -339.093556) (xy 375.778268 -339.16112) (xy 375.7803 -339.1662)
			(xy 375.7803 -339.352636) (xy 375.795286 -339.388704) (xy 375.816114 -339.409532) (xy 375.844562 -339.421216)
			(xy 375.856246 -339.417914) (xy 375.872433 -339.413149) (xy 375.905217 -339.405146) (xy 375.921778 -339.401912)
			(xy 375.950401 -339.396804) (xy 376.008277 -339.391204) (xy 376.037348 -339.390736) (xy 376.043698 -339.390736)
			(xy 376.076381 -339.391365) (xy 376.141364 -339.398496) (xy 376.205272 -339.412261) (xy 376.236484 -339.421978)
			(xy 376.244104 -339.424518) (xy 377.537218 -339.424518) (xy 377.573286 -339.409532) (xy 377.630182 -339.352636)
			(xy 377.630182 -337.387692) (xy 377.628404 -337.385914) (xy 377.628404 -337.141312) (xy 377.693428 -337.076288)
			(xy 380.08052 -337.076288) (xy 380.08052 -337.086956) (xy 381.644652 -337.086956) (xy 381.906272 -337.348576)
			(xy 381.906272 -339.916516) (xy 383.239264 -339.916516) (xy 383.279904 -339.916516) (xy 383.279904 -336.651854)
			(xy 383.575814 -336.355944) (xy 387.865874 -336.355944) (xy 387.866128 -336.356452) (xy 388.141464 -336.356452)
			(xy 388.245604 -336.460592) (xy 388.245604 -336.586576) (xy 388.246112 -336.594958) (xy 388.246112 -339.007958)
			(xy 388.245661 -339.022721) (xy 388.2389 -339.051464) (xy 388.225729 -339.07789) (xy 388.20685 -339.100592)
			(xy 388.195312 -339.109812) (xy 388.195312 -339.916516) (xy 388.241032 -339.916516) (xy 388.241032 -340.666832)
			(xy 383.239264 -340.666832) (xy 383.239264 -339.916516) (xy 381.906272 -339.916516) (xy 381.906272 -342.530684)
			(xy 381.972566 -342.596978) (xy 382.774698 -342.596978) (xy 383.204466 -342.16721) (xy 383.239264 -342.16721)
			(xy 383.239264 -342.166956) (xy 384.790188 -342.166956) (xy 384.790188 -342.791288) (xy 384.417316 -343.16416)
			(xy 383.93878 -343.16416) (xy 383.876804 -343.226136) (xy 383.876804 -343.229692) (xy 383.828544 -343.277952)
			(xy 383.33934 -343.277952) (xy 383.33934 -343.506552) (xy 383.589784 -343.506552) (xy 383.592324 -343.504012)
			(xy 383.88036 -343.504012) (xy 383.93878 -343.562432) (xy 383.93878 -343.681812) (xy 383.940812 -343.686892)
			(xy 383.940812 -344.529664) (xy 383.93878 -344.534998) (xy 383.93878 -344.575892) (xy 383.907284 -344.607388)
			(xy 383.907284 -344.608912) (xy 383.894584 -344.621612) (xy 383.058924 -344.621612) (xy 383.038604 -344.641932)
			(xy 383.038604 -344.824812) (xy 383.071624 -344.857832) (xy 383.90322 -344.857832) (xy 383.93878 -344.893392)
			(xy 383.93878 -344.951812) (xy 383.940812 -344.956892) (xy 383.940812 -345.143328) (xy 383.955798 -345.179396)
			(xy 383.976626 -345.200224) (xy 384.005074 -345.211908) (xy 384.016758 -345.208606) (xy 384.032945 -345.203841)
			(xy 384.065729 -345.195837) (xy 384.08229 -345.192604) (xy 384.110913 -345.187497) (xy 384.168789 -345.181898)
			(xy 384.19786 -345.181428) (xy 384.20421 -345.181428) (xy 384.236893 -345.182058) (xy 384.301876 -345.18919)
			(xy 384.365783 -345.202956) (xy 384.396996 -345.21267) (xy 384.404616 -345.21521) (xy 385.69773 -345.21521)
			(xy 385.733798 -345.200224) (xy 385.790694 -345.143328) (xy 385.790694 -343.168732) (xy 385.786884 -343.164922)
			(xy 385.789424 -343.162382) (xy 385.789424 -342.957912) (xy 385.880356 -342.86698) (xy 388.241032 -342.86698)
			(xy 388.241032 -342.877648) (xy 392.32332 -342.877648) (xy 392.52906 -343.083388) (xy 392.52906 -349.979488)
			(xy 392.04138 -350.467168) (xy 391.689336 -350.467168) (xy 391.649458 -350.42729) (xy 378.811282 -350.42729)
			(xy 378.74702 -350.363028) (xy 378.746766 -350.363028) (xy 378.501656 -350.117918) (xy 378.49425 -350.111223)
			(xy 378.475814 -350.103618) (xy 378.465842 -350.103186) (xy 374.752362 -350.103186) (xy 374.742397 -350.103667)
			(xy 374.723964 -350.111246) (xy 374.716548 -350.117918) (xy 374.65889 -350.175576) (xy 374.652203 -350.182985)
			(xy 374.644614 -350.201421) (xy 374.644158 -350.21139) (xy 374.644158 -359.720896) (xy 376.788934 -359.720896)
			(xy 376.799002 -359.721325) (xy 376.817597 -359.729048) (xy 376.825002 -359.735882) (xy 376.84202 -359.7529)
			(xy 376.84943 -359.759581) (xy 376.867867 -359.767156) (xy 376.877834 -359.767632) (xy 377.597162 -359.767632)
			(xy 377.607227 -359.768067) (xy 377.625812 -359.775801) (xy 377.63323 -359.782618) (xy 377.966478 -360.115866)
			(xy 377.973316 -360.123267) (xy 377.98103 -360.141866) (xy 377.981464 -360.151934) (xy 377.981464 -363.389418)
			(xy 377.981037 -363.399486) (xy 377.973314 -363.418082) (xy 377.966478 -363.425486) (xy 376.042682 -365.349282)
			(xy 376.035283 -365.356128) (xy 376.016685 -365.363858) (xy 376.006614 -365.364268) (xy 369.148868 -365.364268)
			(xy 369.138902 -365.364747) (xy 369.120466 -365.372323) (xy 369.113054 -365.379) (xy 369.099338 -365.392716)
			(xy 369.076478 -365.402114) (xy 369.076478 -365.64062) (xy 380.886211 -365.64062) (xy 380.890247 -365.557173)
			(xy 380.902319 -365.474505) (xy 380.922312 -365.393388) (xy 380.950041 -365.314579) (xy 380.985247 -365.238814)
			(xy 381.027601 -365.166801) (xy 381.076707 -365.099212) (xy 381.132108 -365.036678) (xy 381.193285 -364.979783)
			(xy 381.259668 -364.929057) (xy 381.330636 -364.884976) (xy 381.405528 -364.84795) (xy 381.483644 -364.818324)
			(xy 381.564254 -364.796376) (xy 381.646606 -364.782311) (xy 381.729932 -364.776259) (xy 381.813452 -364.778278)
			(xy 381.896388 -364.788348) (xy 381.977964 -364.806376) (xy 382.05742 -364.832193) (xy 382.134013 -364.865558)
			(xy 382.207029 -364.906159) (xy 382.275785 -364.953618) (xy 382.339639 -365.007491) (xy 382.397996 -365.067276)
			(xy 382.450311 -365.132413) (xy 382.496094 -365.202296) (xy 382.534919 -365.276271) (xy 382.566424 -365.353648)
			(xy 382.590313 -365.433705) (xy 382.606364 -365.515693) (xy 382.614427 -365.598848) (xy 382.614932 -365.64062)
			(xy 382.614427 -365.682392) (xy 382.606364 -365.765547) (xy 382.590313 -365.847535) (xy 382.566424 -365.927592)
			(xy 382.534919 -366.004969) (xy 382.496094 -366.078944) (xy 382.450311 -366.148827) (xy 382.397996 -366.213964)
			(xy 382.339639 -366.273749) (xy 382.275785 -366.327622) (xy 382.207029 -366.375081) (xy 382.134013 -366.415682)
			(xy 382.05742 -366.449047) (xy 381.977964 -366.474864) (xy 381.896388 -366.492892) (xy 381.813452 -366.502962)
			(xy 381.729932 -366.504981) (xy 381.646606 -366.498929) (xy 381.564254 -366.484864) (xy 381.483644 -366.462916)
			(xy 381.405528 -366.43329) (xy 381.330636 -366.396264) (xy 381.259668 -366.352183) (xy 381.193285 -366.301457)
			(xy 381.132108 -366.244562) (xy 381.076707 -366.182028) (xy 381.027601 -366.114439) (xy 380.985247 -366.042426)
			(xy 380.950041 -365.966661) (xy 380.922312 -365.887852) (xy 380.902319 -365.806735) (xy 380.890247 -365.724067)
			(xy 380.886211 -365.64062) (xy 369.076478 -365.64062) (xy 369.076478 -366.430306) (xy 369.076953 -366.440274)
			(xy 369.084522 -366.458716) (xy 369.09121 -366.46612) (xy 369.234974 -366.609884) (xy 369.242396 -366.616667)
			(xy 369.260993 -366.624273) (xy 369.271042 -366.624616) (xy 382.945132 -366.624616)
		)
		(stroke
			(width 0)
			(type solid)
		)
		(fill yes)
		(layer "F.Cu")
		(net "GND")
	)
	(gr_poly
		(pts
			(xy 125.568456 -361.975908) (xy 125.568456 -358.834182) (xy 125.569726 -358.832658) (xy 125.569726 -358.630982)
			(xy 125.713998 -358.48671) (xy 126.252478 -358.48671) (xy 126.359158 -358.38003) (xy 126.359158 -350.10979)
			(xy 126.676658 -349.79229) (xy 130.808984 -349.79229) (xy 131.145788 -350.129348) (xy 142.61338 -350.129348)
			(xy 142.87119 -349.871538) (xy 142.87119 -343.251028) (xy 142.75435 -343.134442) (xy 138.16838 -343.134442)
			(xy 138.15314 -343.149428) (xy 138.15314 -345.206066) (xy 138.213338 -345.26601) (xy 139.56411 -345.26601)
			(xy 139.70254 -345.40444) (xy 139.70254 -345.513152) (xy 139.702794 -345.513914) (xy 139.702794 -345.5162)
			(xy 139.702794 -346.175076) (xy 140.077698 -346.550234) (xy 140.077698 -348.293944) (xy 139.500356 -348.871286)
			(xy 134.457948 -348.871286) (xy 133.580886 -347.994224) (xy 133.580886 -342.374982) (xy 133.6675 -342.288368)
			(xy 133.6675 -337.551522) (xy 133.459728 -337.34375) (xy 130.007868 -337.34375) (xy 129.987548 -337.363816)
			(xy 129.987548 -339.410294) (xy 130.052826 -339.475318) (xy 131.45008 -339.475318) (xy 131.542028 -339.567266)
			(xy 131.542028 -339.72246) (xy 131.542282 -339.723222) (xy 131.542282 -339.725508) (xy 131.542282 -340.326218)
			(xy 131.542011 -340.339198) (xy 131.538571 -340.364931) (xy 131.535424 -340.377526) (xy 131.90855 -340.750652)
			(xy 131.90855 -342.491822) (xy 131.037838 -343.362534) (xy 126.862332 -343.362534) (xy 126.828133 -343.362064)
			(xy 126.760181 -343.35426) (xy 126.693564 -343.338751) (xy 126.629153 -343.315739) (xy 126.567789 -343.285526)
			(xy 126.510276 -343.248505) (xy 126.457364 -343.205162) (xy 126.409745 -343.156062) (xy 126.368042 -343.101847)
			(xy 126.3328 -343.043227) (xy 126.318264 -343.012268) (xy 126.314454 -343.003886) (xy 125.420374 -342.109806)
			(xy 125.420374 -335.198466) (xy 125.419866 -335.198212) (xy 125.419866 -335.079594) (xy 125.420374 -335.079086)
			(xy 125.420374 -334.028796) (xy 125.405642 -333.992728) (xy 125.34646 -333.933546) (xy 121.847356 -333.933546)
			(xy 121.82983 -333.950818) (xy 121.82983 -336.002884) (xy 121.892314 -336.065114) (xy 123.238514 -336.065114)
			(xy 123.381516 -336.208116) (xy 123.381516 -336.312256) (xy 123.38177 -336.313018) (xy 123.38177 -336.315304)
			(xy 123.38177 -336.916014) (xy 123.379738 -336.943446) (xy 123.37669 -336.965036) (xy 123.37669 -337.17611)
			(xy 123.746514 -337.545934) (xy 123.746514 -339.30209) (xy 123.056142 -339.992462) (xy 118.529608 -339.992462)
			(xy 117.259862 -338.722716) (xy 117.259862 -335.198466) (xy 117.259354 -335.198212) (xy 117.259354 -335.079594)
			(xy 117.259862 -335.079086) (xy 117.259862 -334.028796) (xy 117.24513 -333.992728) (xy 117.185948 -333.933546)
			(xy 113.686844 -333.933546) (xy 113.669064 -333.951072) (xy 113.669064 -336.00263) (xy 113.731802 -336.065114)
			(xy 115.03533 -336.065114) (xy 115.221004 -336.250788) (xy 115.221004 -336.312256) (xy 115.221258 -336.313018)
			(xy 115.221258 -336.315304) (xy 115.221258 -336.97418) (xy 115.265962 -337.018884) (xy 115.265962 -337.232498)
			(xy 115.529614 -337.49615) (xy 115.529614 -338.944458) (xy 114.743738 -339.730334) (xy 110.858808 -339.730334)
			(xy 110.833893 -339.752587) (xy 110.779619 -339.791538) (xy 110.721035 -339.823642) (xy 110.658999 -339.84843)
			(xy 110.594423 -339.865538) (xy 110.528252 -339.874714) (xy 110.461456 -339.875824) (xy 110.395017 -339.868853)
			(xy 110.329907 -339.853902) (xy 110.267082 -339.83119) (xy 110.207463 -339.801051) (xy 110.151924 -339.763926)
			(xy 110.126272 -339.742526) (xy 109.996478 -339.631274) (xy 108.87456 -338.509356) (xy 108.87456 -337.552284)
			(xy 109.09935 -337.327494) (xy 109.09935 -335.198466) (xy 109.098842 -335.198212) (xy 109.098842 -335.079594)
			(xy 109.09935 -335.079086) (xy 109.09935 -334.028796) (xy 109.084618 -333.992728) (xy 109.025436 -333.933546)
			(xy 105.526332 -333.933546) (xy 105.508298 -333.951326) (xy 105.508298 -336.002376) (xy 105.57129 -336.065114)
			(xy 106.92384 -336.065114) (xy 107.060492 -336.201766) (xy 107.060492 -336.312256) (xy 107.060746 -336.313018)
			(xy 107.060746 -336.315304) (xy 107.060746 -336.916014) (xy 107.060475 -336.928994) (xy 107.057037 -336.954727)
			(xy 107.053888 -336.967322) (xy 107.10545 -337.018884) (xy 107.10545 -337.025488) (xy 107.470956 -337.390994)
			(xy 107.470956 -338.900516) (xy 106.641138 -339.730334) (xy 102.762812 -339.730334) (xy 102.738348 -339.7524)
			(xy 102.684992 -339.79105) (xy 102.627331 -339.822923) (xy 102.566221 -339.847545) (xy 102.502571 -339.864552)
			(xy 102.437324 -339.87369) (xy 102.37145 -339.874824) (xy 102.305927 -339.867936) (xy 102.241728 -339.85313)
			(xy 102.179808 -339.830625) (xy 102.121084 -339.800756) (xy 102.06643 -339.763965) (xy 102.041198 -339.74278)
			(xy 101.957886 -339.669882) (xy 100.938838 -338.650834) (xy 100.938838 -335.198466) (xy 100.93833 -335.198212)
			(xy 100.93833 -335.079594) (xy 100.938838 -335.079086) (xy 100.938838 -334.028796) (xy 100.924106 -333.992728)
			(xy 100.864924 -333.933546) (xy 97.36582 -333.933546) (xy 97.346262 -333.95285) (xy 97.346262 -335.97977)
			(xy 97.431606 -336.065114) (xy 98.753676 -336.065114) (xy 98.89998 -336.211418) (xy 98.89998 -336.312256)
			(xy 98.900234 -336.313018) (xy 98.900234 -336.315304) (xy 98.900234 -336.916014) (xy 98.899963 -336.928994)
			(xy 98.896525 -336.954727) (xy 98.893376 -336.967322) (xy 99.545648 -337.619594) (xy 99.545648 -339.216746)
			(xy 99.126548 -339.635846) (xy 97.095818 -339.635846) (xy 97.09023 -339.641434) (xy 94.605602 -339.641434)
			(xy 94.58436 -339.666692) (xy 94.536534 -339.712173) (xy 94.483344 -339.751246) (xy 94.425643 -339.783284)
			(xy 94.364356 -339.807772) (xy 94.300465 -339.82432) (xy 94.234995 -339.83266) (xy 94.168997 -339.83266)
			(xy 94.103527 -339.82432) (xy 94.039636 -339.807772) (xy 93.978349 -339.783284) (xy 93.920648 -339.751246)
			(xy 93.867458 -339.712173) (xy 93.819632 -339.666692) (xy 93.79839 -339.641434) (xy 92.98051 -339.641434)
			(xy 92.728542 -339.389466) (xy 92.728542 -337.49615) (xy 92.576142 -337.34375) (xy 89.357454 -337.34375)
			(xy 89.248742 -337.452462) (xy 89.248742 -339.399118) (xy 89.278714 -339.42909) (xy 90.64117 -339.42909)
			(xy 90.798142 -339.586062) (xy 90.798142 -340.322662) (xy 91.204542 -340.729062) (xy 91.204542 -342.599772)
			(xy 90.713052 -343.091262) (xy 86.54923 -343.091262) (xy 86.529416 -343.118999) (xy 86.484165 -343.169978)
			(xy 86.433105 -343.215138) (xy 86.37698 -343.253822) (xy 86.316605 -343.285468) (xy 86.252859 -343.309615)
			(xy 86.18667 -343.325911) (xy 86.119001 -343.33412) (xy 86.084918 -343.334594) (xy 86.08441 -343.334594)
			(xy 86.071883 -343.334508) (xy 86.046855 -343.333366) (xy 86.034372 -343.332308) (xy 86.010496 -343.330276)
			(xy 85.72881 -343.611962) (xy 85.122258 -343.611962) (xy 84.644738 -343.134442) (xy 81.044796 -343.134442)
			(xy 81.030318 -343.148666) (xy 81.030318 -344.791284) (xy 96.474788 -344.791284) (xy 96.474788 -343.267284)
			(xy 96.475215 -343.253898) (xy 96.482147 -343.22804) (xy 96.495535 -343.204857) (xy 96.514466 -343.185927)
			(xy 96.537651 -343.172542) (xy 96.56351 -343.165613) (xy 96.576896 -343.165176) (xy 98.100896 -343.165176)
			(xy 98.11428 -343.165632) (xy 98.140136 -343.172559) (xy 98.163318 -343.18594) (xy 98.182247 -343.204866)
			(xy 98.195634 -343.228046) (xy 98.202565 -343.2539) (xy 98.203004 -343.267284) (xy 98.203004 -344.071632)
			(xy 98.950014 -344.071632) (xy 98.950014 -343.986936) (xy 98.958065 -343.902622) (xy 98.974094 -343.819456)
			(xy 98.997955 -343.738189) (xy 99.029434 -343.659559) (xy 99.068245 -343.584278) (xy 99.114035 -343.513026)
			(xy 99.166391 -343.44645) (xy 99.224839 -343.385152) (xy 99.288849 -343.329687) (xy 99.357841 -343.280558)
			(xy 99.431191 -343.238209) (xy 99.508234 -343.203025) (xy 99.588273 -343.175323) (xy 99.670582 -343.155355)
			(xy 99.754417 -343.143302) (xy 99.839018 -343.139272) (xy 99.923619 -343.143302) (xy 100.007454 -343.155355)
			(xy 100.089763 -343.175323) (xy 100.169802 -343.203025) (xy 100.246845 -343.238209) (xy 100.320195 -343.280558)
			(xy 100.389187 -343.329687) (xy 100.453197 -343.385152) (xy 100.511645 -343.44645) (xy 100.564001 -343.513026)
			(xy 100.609791 -343.584278) (xy 100.648602 -343.659559) (xy 100.680081 -343.738189) (xy 100.703942 -343.819456)
			(xy 100.719971 -343.902622) (xy 100.728022 -343.986936) (xy 100.728526 -344.029284) (xy 100.728022 -344.071632)
			(xy 100.719971 -344.155946) (xy 100.703942 -344.239112) (xy 100.680081 -344.320379) (xy 100.648602 -344.399009)
			(xy 100.609791 -344.47429) (xy 100.564001 -344.545542) (xy 100.511645 -344.612118) (xy 100.453197 -344.673416)
			(xy 100.389187 -344.728881) (xy 100.320195 -344.77801) (xy 100.297204 -344.791284) (xy 104.035352 -344.791284)
			(xy 104.035352 -343.267284) (xy 104.035814 -343.253901) (xy 104.042744 -343.228048) (xy 104.056126 -343.204869)
			(xy 104.075049 -343.18594) (xy 104.098226 -343.172553) (xy 104.124077 -343.165618) (xy 104.13746 -343.165176)
			(xy 105.66146 -343.165176) (xy 105.674847 -343.165624) (xy 105.700712 -343.172545) (xy 105.723903 -343.185925)
			(xy 105.742841 -343.204852) (xy 105.756234 -343.228036) (xy 105.763168 -343.253897) (xy 105.763568 -343.267284)
			(xy 105.763568 -344.071632) (xy 106.510578 -344.071632) (xy 106.510578 -343.986936) (xy 106.518629 -343.902622)
			(xy 106.534658 -343.819456) (xy 106.558519 -343.738189) (xy 106.589998 -343.659559) (xy 106.628809 -343.584278)
			(xy 106.674599 -343.513026) (xy 106.726955 -343.44645) (xy 106.785403 -343.385152) (xy 106.849413 -343.329687)
			(xy 106.918405 -343.280558) (xy 106.991755 -343.238209) (xy 107.068798 -343.203025) (xy 107.148837 -343.175323)
			(xy 107.231146 -343.155355) (xy 107.314981 -343.143302) (xy 107.399582 -343.139272) (xy 107.484183 -343.143302)
			(xy 107.568018 -343.155355) (xy 107.650327 -343.175323) (xy 107.730366 -343.203025) (xy 107.807409 -343.238209)
			(xy 107.880759 -343.280558) (xy 107.949751 -343.329687) (xy 108.013761 -343.385152) (xy 108.072209 -343.44645)
			(xy 108.124565 -343.513026) (xy 108.170355 -343.584278) (xy 108.209166 -343.659559) (xy 108.240645 -343.738189)
			(xy 108.264506 -343.819456) (xy 108.280535 -343.902622) (xy 108.288586 -343.986936) (xy 108.28909 -344.029284)
			(xy 108.288586 -344.071632) (xy 108.280535 -344.155946) (xy 108.264506 -344.239112) (xy 108.240645 -344.320379)
			(xy 108.209166 -344.399009) (xy 108.170355 -344.47429) (xy 108.124565 -344.545542) (xy 108.072209 -344.612118)
			(xy 108.013761 -344.673416) (xy 107.949751 -344.728881) (xy 107.880759 -344.77801) (xy 107.857768 -344.791284)
			(xy 111.740696 -344.791284) (xy 111.740696 -343.267284) (xy 111.741115 -343.253898) (xy 111.748048 -343.228038)
			(xy 111.761437 -343.204854) (xy 111.78037 -343.185925) (xy 111.803557 -343.17254) (xy 111.829418 -343.165612)
			(xy 111.842804 -343.165176) (xy 113.366804 -343.165176) (xy 113.380188 -343.165625) (xy 113.406044 -343.172553)
			(xy 113.429227 -343.185937) (xy 113.448156 -343.204864) (xy 113.461542 -343.228045) (xy 113.468473 -343.2539)
			(xy 113.468912 -343.267284) (xy 113.468912 -344.071632) (xy 114.215922 -344.071632) (xy 114.215922 -343.986936)
			(xy 114.223973 -343.902622) (xy 114.240002 -343.819456) (xy 114.263863 -343.738189) (xy 114.295342 -343.659559)
			(xy 114.334153 -343.584278) (xy 114.379943 -343.513026) (xy 114.432299 -343.44645) (xy 114.490747 -343.385152)
			(xy 114.554757 -343.329687) (xy 114.623749 -343.280558) (xy 114.697099 -343.238209) (xy 114.774142 -343.203025)
			(xy 114.854181 -343.175323) (xy 114.93649 -343.155355) (xy 115.020325 -343.143302) (xy 115.104926 -343.139272)
			(xy 115.189527 -343.143302) (xy 115.273362 -343.155355) (xy 115.355671 -343.175323) (xy 115.43571 -343.203025)
			(xy 115.512753 -343.238209) (xy 115.586103 -343.280558) (xy 115.655095 -343.329687) (xy 115.719105 -343.385152)
			(xy 115.777553 -343.44645) (xy 115.829909 -343.513026) (xy 115.875699 -343.584278) (xy 115.91451 -343.659559)
			(xy 115.945989 -343.738189) (xy 115.96985 -343.819456) (xy 115.985879 -343.902622) (xy 115.99393 -343.986936)
			(xy 115.994434 -344.029284) (xy 115.99393 -344.071632) (xy 115.985879 -344.155946) (xy 115.96985 -344.239112)
			(xy 115.945989 -344.320379) (xy 115.91451 -344.399009) (xy 115.875699 -344.47429) (xy 115.829909 -344.545542)
			(xy 115.777553 -344.612118) (xy 115.723937 -344.668348) (xy 119.201692 -344.668348) (xy 119.201692 -343.144348)
			(xy 119.202131 -343.13096) (xy 119.209052 -343.105093) (xy 119.222432 -343.0819) (xy 119.241362 -343.062962)
			(xy 119.264549 -343.04957) (xy 119.290412 -343.042638) (xy 119.3038 -343.04224) (xy 120.8278 -343.04224)
			(xy 120.841194 -343.04259) (xy 120.86707 -343.049526) (xy 120.890268 -343.062924) (xy 120.909206 -343.081871)
			(xy 120.922593 -343.105075) (xy 120.929516 -343.130953) (xy 120.929908 -343.144348) (xy 120.929908 -343.9063)
			(xy 121.67592 -343.9063) (xy 121.67995 -343.821701) (xy 121.692004 -343.737868) (xy 121.711972 -343.65556)
			(xy 121.739673 -343.575523) (xy 121.774857 -343.498482) (xy 121.817206 -343.425134) (xy 121.866334 -343.356144)
			(xy 121.921799 -343.292136) (xy 121.983096 -343.23369) (xy 122.049672 -343.181336) (xy 122.120923 -343.135547)
			(xy 122.196204 -343.096739) (xy 122.274832 -343.065262) (xy 122.356097 -343.041403) (xy 122.439262 -343.025376)
			(xy 122.523574 -343.017327) (xy 122.565922 -343.01684) (xy 122.607849 -343.017305) (xy 122.691331 -343.025201)
			(xy 122.773699 -343.04092) (xy 122.854221 -343.064324) (xy 122.932183 -343.095203) (xy 123.006891 -343.133285)
			(xy 123.077683 -343.17823) (xy 123.143929 -343.22964) (xy 123.205042 -343.287058) (xy 123.260478 -343.349973)
			(xy 123.285504 -343.383616) (xy 123.290584 -343.389966) (xy 123.313051 -343.422281) (xy 123.352875 -343.490172)
			(xy 123.386548 -343.561315) (xy 123.41381 -343.635153) (xy 123.434445 -343.71111) (xy 123.448294 -343.788591)
			(xy 123.455248 -343.866993) (xy 123.455684 -343.906348) (xy 123.455572 -343.926251) (xy 123.453796 -343.966017)
			(xy 123.452128 -343.98585) (xy 123.453398 -344.029284) (xy 123.452966 -344.066438) (xy 123.445992 -344.140418)
			(xy 123.432084 -344.213412) (xy 123.411368 -344.284774) (xy 123.384026 -344.353868) (xy 123.367546 -344.38717)
			(xy 123.351562 -344.387724) (xy 123.321167 -344.397632) (xy 123.295329 -344.416459) (xy 123.285504 -344.42908)
			(xy 123.260461 -344.462709) (xy 123.205027 -344.525624) (xy 123.143915 -344.58304) (xy 123.077671 -344.634449)
			(xy 123.006881 -344.679393) (xy 122.932174 -344.717474) (xy 122.854214 -344.748353) (xy 122.773694 -344.771756)
			(xy 122.691328 -344.787475) (xy 122.607848 -344.795371) (xy 122.565922 -344.795856) (xy 122.523574 -344.795273)
			(xy 122.439262 -344.787224) (xy 122.356097 -344.771197) (xy 122.274832 -344.747338) (xy 122.196204 -344.715861)
			(xy 122.120923 -344.677053) (xy 122.049672 -344.631264) (xy 121.983096 -344.57891) (xy 121.921799 -344.520464)
			(xy 121.866334 -344.456456) (xy 121.817206 -344.387466) (xy 121.774857 -344.314118) (xy 121.739673 -344.237077)
			(xy 121.711972 -344.15704) (xy 121.692004 -344.074732) (xy 121.67995 -343.990899) (xy 121.67592 -343.9063)
			(xy 120.929908 -343.9063) (xy 120.929908 -344.668348) (xy 120.929513 -344.681735) (xy 120.922573 -344.707596)
			(xy 120.909179 -344.730779) (xy 120.890241 -344.749708) (xy 120.867051 -344.763092) (xy 120.841188 -344.77002)
			(xy 120.8278 -344.770456) (xy 119.3038 -344.770456) (xy 119.290419 -344.769972) (xy 119.264568 -344.763047)
			(xy 119.241388 -344.749669) (xy 119.22246 -344.73075) (xy 119.209071 -344.707577) (xy 119.202135 -344.681729)
			(xy 119.201692 -344.668348) (xy 115.723937 -344.668348) (xy 115.719105 -344.673416) (xy 115.655095 -344.728881)
			(xy 115.586103 -344.77801) (xy 115.512753 -344.820359) (xy 115.43571 -344.855543) (xy 115.355671 -344.883245)
			(xy 115.273362 -344.903213) (xy 115.189527 -344.915266) (xy 115.104926 -344.919297) (xy 115.020325 -344.915266)
			(xy 114.93649 -344.903213) (xy 114.854181 -344.883245) (xy 114.774142 -344.855543) (xy 114.697099 -344.820359)
			(xy 114.623749 -344.77801) (xy 114.554757 -344.728881) (xy 114.490747 -344.673416) (xy 114.432299 -344.612118)
			(xy 114.379943 -344.545542) (xy 114.334153 -344.47429) (xy 114.295342 -344.399009) (xy 114.263863 -344.320379)
			(xy 114.240002 -344.239112) (xy 114.223973 -344.155946) (xy 114.215922 -344.071632) (xy 113.468912 -344.071632)
			(xy 113.468912 -344.791284) (xy 113.468496 -344.804673) (xy 113.461569 -344.830541) (xy 113.448183 -344.853733)
			(xy 113.429249 -344.87267) (xy 113.406059 -344.886061) (xy 113.380193 -344.892994) (xy 113.366804 -344.893392)
			(xy 111.842804 -344.893392) (xy 111.829412 -344.893007) (xy 111.803542 -344.886075) (xy 111.780347 -344.872683)
			(xy 111.76141 -344.853743) (xy 111.748021 -344.830547) (xy 111.741092 -344.804676) (xy 111.740696 -344.791284)
			(xy 107.857768 -344.791284) (xy 107.807409 -344.820359) (xy 107.730366 -344.855543) (xy 107.650327 -344.883245)
			(xy 107.568018 -344.903213) (xy 107.484183 -344.915266) (xy 107.399582 -344.919297) (xy 107.314981 -344.915266)
			(xy 107.231146 -344.903213) (xy 107.148837 -344.883245) (xy 107.068798 -344.855543) (xy 106.991755 -344.820359)
			(xy 106.918405 -344.77801) (xy 106.849413 -344.728881) (xy 106.785403 -344.673416) (xy 106.726955 -344.612118)
			(xy 106.674599 -344.545542) (xy 106.628809 -344.47429) (xy 106.589998 -344.399009) (xy 106.558519 -344.320379)
			(xy 106.534658 -344.239112) (xy 106.518629 -344.155946) (xy 106.510578 -344.071632) (xy 105.763568 -344.071632)
			(xy 105.763568 -344.791284) (xy 105.763196 -344.804677) (xy 105.756265 -344.830551) (xy 105.742871 -344.853748)
			(xy 105.723929 -344.872686) (xy 105.700728 -344.886074) (xy 105.674853 -344.892999) (xy 105.66146 -344.893392)
			(xy 104.13746 -344.893392) (xy 104.124072 -344.893006) (xy 104.09821 -344.886066) (xy 104.075024 -344.872671)
			(xy 104.056095 -344.853731) (xy 104.042712 -344.830539) (xy 104.035787 -344.804673) (xy 104.035352 -344.791284)
			(xy 100.297204 -344.791284) (xy 100.246845 -344.820359) (xy 100.169802 -344.855543) (xy 100.089763 -344.883245)
			(xy 100.007454 -344.903213) (xy 99.923619 -344.915266) (xy 99.839018 -344.919297) (xy 99.754417 -344.915266)
			(xy 99.670582 -344.903213) (xy 99.588273 -344.883245) (xy 99.508234 -344.855543) (xy 99.431191 -344.820359)
			(xy 99.357841 -344.77801) (xy 99.288849 -344.728881) (xy 99.224839 -344.673416) (xy 99.166391 -344.612118)
			(xy 99.114035 -344.545542) (xy 99.068245 -344.47429) (xy 99.029434 -344.399009) (xy 98.997955 -344.320379)
			(xy 98.974094 -344.239112) (xy 98.958065 -344.155946) (xy 98.950014 -344.071632) (xy 98.203004 -344.071632)
			(xy 98.203004 -344.791284) (xy 98.202596 -344.804674) (xy 98.195668 -344.830542) (xy 98.182281 -344.853736)
			(xy 98.163345 -344.872673) (xy 98.140154 -344.886064) (xy 98.114286 -344.892995) (xy 98.100896 -344.893392)
			(xy 96.576896 -344.893392) (xy 96.563504 -344.893014) (xy 96.537633 -344.88608) (xy 96.514439 -344.872686)
			(xy 96.495502 -344.853745) (xy 96.482112 -344.830548) (xy 96.475184 -344.804676) (xy 96.474788 -344.791284)
			(xy 81.030318 -344.791284) (xy 81.030318 -345.206828) (xy 81.089754 -345.26601) (xy 82.464656 -345.26601)
			(xy 82.581496 -345.38285) (xy 82.581496 -346.324428) (xy 82.927698 -346.67063) (xy 82.927698 -348.19463)
			(xy 83.030545 -348.21468) (xy 83.234762 -348.261715) (xy 83.43701 -348.316601) (xy 83.636988 -348.379256)
			(xy 83.834398 -348.449586) (xy 84.028944 -348.527488) (xy 84.220337 -348.612843) (xy 84.408291 -348.705527)
			(xy 84.592526 -348.805399) (xy 84.772766 -348.912311) (xy 84.948744 -349.026103) (xy 85.120196 -349.146606)
			(xy 85.286867 -349.273641) (xy 85.448508 -349.407016) (xy 85.604878 -349.546534) (xy 85.755744 -349.691987)
			(xy 85.90088 -349.843156) (xy 86.040071 -349.999818) (xy 86.173107 -350.161738) (xy 86.299793 -350.328674)
			(xy 86.419937 -350.500378) (xy 86.533361 -350.676594) (xy 86.639895 -350.857058) (xy 86.739381 -351.041501)
			(xy 86.831671 -351.229649) (xy 86.916626 -351.42122) (xy 86.99412 -351.615929) (xy 87.064037 -351.813485)
			(xy 87.126273 -352.013594) (xy 87.180736 -352.215957) (xy 87.227343 -352.420272) (xy 87.266026 -352.626234)
			(xy 87.296726 -352.833537) (xy 87.319398 -353.04187) (xy 87.327232 -353.14636) (xy 87.328502 -353.165156)
			(xy 87.564976 -353.40163) (xy 97.458784 -353.40163) (xy 101.148642 -349.711772) (xy 113.679478 -349.711772)
			(xy 114.5794 -350.611948) (xy 115.1636 -351.196148) (xy 115.620292 -351.196148) (xy 115.620292 -349.672148)
			(xy 115.620731 -349.65876) (xy 115.627652 -349.632893) (xy 115.641032 -349.6097) (xy 115.659962 -349.590762)
			(xy 115.683149 -349.57737) (xy 115.709012 -349.570438) (xy 115.7224 -349.57004) (xy 117.2464 -349.57004)
			(xy 117.259794 -349.57039) (xy 117.28567 -349.577326) (xy 117.308868 -349.590724) (xy 117.327806 -349.609671)
			(xy 117.341193 -349.632875) (xy 117.348116 -349.658753) (xy 117.348508 -349.672148) (xy 117.348508 -350.391507)
			(xy 118.095562 -350.391507) (xy 118.103717 -350.306638) (xy 118.119956 -350.222938) (xy 118.14413 -350.141176)
			(xy 118.176017 -350.062103) (xy 118.215325 -349.986444) (xy 118.261692 -349.914894) (xy 118.2878 -349.88119)
			(xy 118.2878 -349.880682) (xy 118.315921 -349.846224) (xy 118.377922 -349.782451) (xy 118.445975 -349.725182)
			(xy 118.519403 -349.674987) (xy 118.597471 -349.632367) (xy 118.679402 -349.597748) (xy 118.764377 -349.571475)
			(xy 118.85155 -349.55381) (xy 118.94005 -349.544929) (xy 118.984522 -349.544386) (xy 119.026884 -349.544795)
			(xy 119.111225 -349.55285) (xy 119.194418 -349.568886) (xy 119.27571 -349.592758) (xy 119.354365 -349.624248)
			(xy 119.42967 -349.663072) (xy 119.500944 -349.708879) (xy 119.567541 -349.761253) (xy 119.628858 -349.81972)
			(xy 119.68434 -349.883751) (xy 119.733485 -349.952766) (xy 119.775846 -350.02614) (xy 119.811041 -350.103208)
			(xy 119.838752 -350.183273) (xy 119.858726 -350.265609) (xy 119.870783 -350.349472) (xy 119.874815 -350.4341)
			(xy 119.870783 -350.518728) (xy 119.858726 -350.602591) (xy 119.838752 -350.684927) (xy 119.811041 -350.764992)
			(xy 119.775846 -350.84206) (xy 119.733485 -350.915434) (xy 119.68434 -350.984449) (xy 119.628858 -351.04848)
			(xy 119.567541 -351.106947) (xy 119.500944 -351.159321) (xy 119.42967 -351.205128) (xy 119.354365 -351.243952)
			(xy 119.27571 -351.275442) (xy 119.194418 -351.299314) (xy 119.111225 -351.31535) (xy 119.026884 -351.323405)
			(xy 118.984522 -351.32391) (xy 118.940047 -351.323377) (xy 118.851541 -351.314512) (xy 118.764362 -351.296859)
			(xy 118.679379 -351.270594) (xy 118.597442 -351.235979) (xy 118.519368 -351.193359) (xy 118.445938 -351.143161)
			(xy 118.377883 -351.085885) (xy 118.315885 -351.022103) (xy 118.2878 -350.987614) (xy 118.2878 -350.987106)
			(xy 118.261736 -350.953367) (xy 118.215363 -350.881821) (xy 118.176049 -350.806165) (xy 118.144155 -350.727095)
			(xy 118.119974 -350.645335) (xy 118.103728 -350.561637) (xy 118.095565 -350.476768) (xy 118.095562 -350.391507)
			(xy 117.348508 -350.391507) (xy 117.348508 -351.196148) (xy 117.348113 -351.209535) (xy 117.341173 -351.235396)
			(xy 117.327779 -351.258579) (xy 117.308841 -351.277508) (xy 117.285651 -351.290892) (xy 117.259788 -351.29782)
			(xy 117.2464 -351.298256) (xy 115.7224 -351.298256) (xy 115.709019 -351.297772) (xy 115.683168 -351.290847)
			(xy 115.659988 -351.277469) (xy 115.64106 -351.25855) (xy 115.627671 -351.235377) (xy 115.620735 -351.209529)
			(xy 115.620292 -351.196148) (xy 115.1636 -351.196148) (xy 115.5954 -351.627948) (xy 120.65 -351.627948)
			(xy 125.048772 -356.02672) (xy 125.048772 -361.959398) (xy 125.157484 -362.06811) (xy 125.476254 -362.06811)
		)
		(stroke
			(width 0)
			(type solid)
		)
		(fill yes)
		(layer "F.Cu")
		(net "SW_P12V_PVCCIN_CPU1_FLT")
	)
	(gr_poly
		(pts
			(xy 373.50827 -361.954572) (xy 373.50827 -358.832912) (xy 373.513604 -358.827832) (xy 373.513604 -358.388412)
			(xy 373.605044 -358.296972) (xy 374.143524 -358.296972) (xy 374.298972 -358.141524) (xy 374.298972 -350.909636)
			(xy 374.314466 -350.894142) (xy 374.314466 -350.04883) (xy 374.55475 -349.808546) (xy 378.725684 -349.808546)
			(xy 379.071886 -350.154748) (xy 391.79754 -350.154748) (xy 392.0744 -349.877888) (xy 392.0744 -343.225628)
			(xy 391.983214 -343.134442) (xy 386.1435 -343.134442) (xy 386.08762 -343.190322) (xy 386.08762 -344.51417)
			(xy 390.46226 -344.51417) (xy 390.466331 -344.458548) (xy 390.478457 -344.404111) (xy 390.49838 -344.35202)
			(xy 390.525676 -344.303385) (xy 390.559762 -344.259242) (xy 390.599911 -344.220533) (xy 390.645269 -344.188082)
			(xy 390.694869 -344.162581) (xy 390.747653 -344.144574) (xy 390.802496 -344.134444) (xy 390.85823 -344.132407)
			(xy 390.913667 -344.138507) (xy 390.967624 -344.152613) (xy 391.018953 -344.174425) (xy 391.066559 -344.203479)
			(xy 391.109427 -344.239154) (xy 391.146644 -344.280691) (xy 391.177417 -344.327204) (xy 391.201089 -344.377701)
			(xy 391.217157 -344.431108) (xy 391.225277 -344.486284) (xy 391.225786 -344.51417) (xy 391.225277 -344.542056)
			(xy 391.217157 -344.597232) (xy 391.201089 -344.650639) (xy 391.177417 -344.701136) (xy 391.146644 -344.747649)
			(xy 391.109427 -344.789186) (xy 391.066559 -344.824861) (xy 391.018953 -344.853915) (xy 390.967624 -344.875727)
			(xy 390.913667 -344.889833) (xy 390.85823 -344.895933) (xy 390.802496 -344.893896) (xy 390.747653 -344.883766)
			(xy 390.694869 -344.865759) (xy 390.645269 -344.840258) (xy 390.599911 -344.807807) (xy 390.559762 -344.769098)
			(xy 390.525676 -344.724955) (xy 390.49838 -344.67632) (xy 390.478457 -344.624229) (xy 390.466331 -344.569792)
			(xy 390.46226 -344.51417) (xy 386.08762 -344.51417) (xy 386.08762 -345.196668) (xy 386.156962 -345.26601)
			(xy 387.503924 -345.26601) (xy 387.642354 -345.40444) (xy 387.642354 -345.513152) (xy 387.642608 -345.513914)
			(xy 387.642608 -345.5162) (xy 387.642608 -345.65717) (xy 390.46226 -345.65717) (xy 390.466331 -345.601548)
			(xy 390.478457 -345.547111) (xy 390.49838 -345.49502) (xy 390.525676 -345.446385) (xy 390.559762 -345.402242)
			(xy 390.599911 -345.363533) (xy 390.645269 -345.331082) (xy 390.694869 -345.305581) (xy 390.747653 -345.287574)
			(xy 390.802496 -345.277444) (xy 390.85823 -345.275407) (xy 390.913667 -345.281507) (xy 390.967624 -345.295613)
			(xy 391.018953 -345.317425) (xy 391.066559 -345.346479) (xy 391.109427 -345.382154) (xy 391.146644 -345.423691)
			(xy 391.177417 -345.470204) (xy 391.201089 -345.520701) (xy 391.217157 -345.574108) (xy 391.225277 -345.629284)
			(xy 391.225786 -345.65717) (xy 391.225277 -345.685056) (xy 391.217157 -345.740232) (xy 391.201089 -345.793639)
			(xy 391.177417 -345.844136) (xy 391.146644 -345.890649) (xy 391.109427 -345.932186) (xy 391.066559 -345.967861)
			(xy 391.018953 -345.996915) (xy 390.967624 -346.018727) (xy 390.913667 -346.032833) (xy 390.85823 -346.038933)
			(xy 390.802496 -346.036896) (xy 390.747653 -346.026766) (xy 390.694869 -346.008759) (xy 390.645269 -345.983258)
			(xy 390.599911 -345.950807) (xy 390.559762 -345.912098) (xy 390.525676 -345.867955) (xy 390.49838 -345.81932)
			(xy 390.478457 -345.767229) (xy 390.466331 -345.712792) (xy 390.46226 -345.65717) (xy 387.642608 -345.65717)
			(xy 387.642608 -346.11691) (xy 387.640576 -346.144342) (xy 387.63702 -346.169488) (xy 388.017512 -346.550234)
			(xy 388.017512 -346.80017) (xy 390.46226 -346.80017) (xy 390.466331 -346.744548) (xy 390.478457 -346.690111)
			(xy 390.49838 -346.63802) (xy 390.525676 -346.589385) (xy 390.559762 -346.545242) (xy 390.599911 -346.506533)
			(xy 390.645269 -346.474082) (xy 390.694869 -346.448581) (xy 390.747653 -346.430574) (xy 390.802496 -346.420444)
			(xy 390.85823 -346.418407) (xy 390.913667 -346.424507) (xy 390.967624 -346.438613) (xy 391.018953 -346.460425)
			(xy 391.066559 -346.489479) (xy 391.109427 -346.525154) (xy 391.146644 -346.566691) (xy 391.177417 -346.613204)
			(xy 391.201089 -346.663701) (xy 391.217157 -346.717108) (xy 391.225277 -346.772284) (xy 391.225786 -346.80017)
			(xy 391.225277 -346.828056) (xy 391.217157 -346.883232) (xy 391.201089 -346.936639) (xy 391.177417 -346.987136)
			(xy 391.146644 -347.033649) (xy 391.109427 -347.075186) (xy 391.066559 -347.110861) (xy 391.018953 -347.139915)
			(xy 390.967624 -347.161727) (xy 390.913667 -347.175833) (xy 390.85823 -347.181933) (xy 390.802496 -347.179896)
			(xy 390.747653 -347.169766) (xy 390.694869 -347.151759) (xy 390.645269 -347.126258) (xy 390.599911 -347.093807)
			(xy 390.559762 -347.055098) (xy 390.525676 -347.010955) (xy 390.49838 -346.96232) (xy 390.478457 -346.910229)
			(xy 390.466331 -346.855792) (xy 390.46226 -346.80017) (xy 388.017512 -346.80017) (xy 388.017512 -348.293944)
			(xy 387.44017 -348.871286) (xy 382.397762 -348.871286) (xy 381.5207 -347.994224) (xy 381.5207 -342.374982)
			(xy 381.607314 -342.288368) (xy 381.607314 -337.551522) (xy 381.399542 -337.34375) (xy 377.947682 -337.34375)
			(xy 377.928632 -337.3628) (xy 377.928632 -339.41131) (xy 377.99264 -339.475318) (xy 379.389894 -339.475318)
			(xy 379.481842 -339.567266) (xy 379.481842 -339.72246) (xy 379.482096 -339.723222) (xy 379.482096 -339.725508)
			(xy 379.482096 -340.326218) (xy 379.480064 -340.35365) (xy 379.476508 -340.378796) (xy 379.848364 -340.750652)
			(xy 379.848364 -342.491822) (xy 378.977652 -343.362534) (xy 374.802146 -343.362534) (xy 374.767949 -343.362059)
			(xy 374.700004 -343.354247) (xy 374.633394 -343.33873) (xy 374.56899 -343.315713) (xy 374.507634 -343.285494)
			(xy 374.450129 -343.248471) (xy 374.397225 -343.205126) (xy 374.349614 -343.156025) (xy 374.307918 -343.101812)
			(xy 374.272682 -343.043193) (xy 374.258078 -343.012268) (xy 374.254268 -343.003886) (xy 373.360188 -342.109806)
			(xy 373.360188 -335.198466) (xy 373.35968 -335.198212) (xy 373.35968 -335.079594) (xy 373.360188 -335.079086)
			(xy 373.360188 -334.028796) (xy 373.345456 -333.992728) (xy 373.286274 -333.933546) (xy 369.78717 -333.933546)
			(xy 369.773454 -333.947262) (xy 369.773454 -336.00644) (xy 369.832128 -336.065114) (xy 371.178328 -336.065114)
			(xy 371.32133 -336.208116) (xy 371.32133 -336.312256) (xy 371.321584 -336.313018) (xy 371.321584 -336.315304)
			(xy 371.321584 -336.916014) (xy 371.319552 -336.943446) (xy 371.316504 -336.965036) (xy 371.316504 -337.17611)
			(xy 371.686328 -337.545934) (xy 371.686328 -339.30209) (xy 370.995956 -339.992462) (xy 366.469422 -339.992462)
			(xy 365.199676 -338.722716) (xy 365.199676 -335.198466) (xy 365.199168 -335.198212) (xy 365.199168 -335.079594)
			(xy 365.199676 -335.079086) (xy 365.199676 -334.028796) (xy 365.184944 -333.992728) (xy 365.125762 -333.933546)
			(xy 361.66044 -333.933546) (xy 361.62742 -333.966566) (xy 361.62742 -336.009488) (xy 361.683046 -336.065114)
			(xy 362.975144 -336.065114) (xy 363.160818 -336.250788) (xy 363.160818 -336.312256) (xy 363.161072 -336.313018)
			(xy 363.161072 -336.315304) (xy 363.161072 -336.916014) (xy 363.15904 -336.943446) (xy 363.155484 -336.968592)
			(xy 363.205776 -337.018884) (xy 363.205776 -337.232498) (xy 363.469428 -337.49615) (xy 363.469428 -338.944458)
			(xy 362.683552 -339.730334) (xy 358.798622 -339.730334) (xy 358.773707 -339.752588) (xy 358.719433 -339.79154)
			(xy 358.660848 -339.823646) (xy 358.598812 -339.848436) (xy 358.534235 -339.865545) (xy 358.468063 -339.874722)
			(xy 358.401266 -339.875834) (xy 358.334826 -339.868864) (xy 358.269714 -339.853914) (xy 358.206888 -339.831203)
			(xy 358.147267 -339.801064) (xy 358.091726 -339.76394) (xy 358.066086 -339.742526) (xy 357.936292 -339.631274)
			(xy 356.814374 -338.509356) (xy 356.814374 -337.552284) (xy 357.039164 -337.327494) (xy 357.039164 -335.198466)
			(xy 357.038656 -335.198212) (xy 357.038656 -335.079594) (xy 357.039164 -335.079086) (xy 357.039164 -334.028796)
			(xy 357.024432 -333.992728) (xy 356.96525 -333.933546) (xy 353.466146 -333.933546) (xy 353.460812 -333.93888)
			(xy 353.460812 -336.015076) (xy 353.511104 -336.065114) (xy 354.863654 -336.065114) (xy 355.000306 -336.201766)
			(xy 355.000306 -336.312256) (xy 355.00056 -336.313018) (xy 355.00056 -336.315304) (xy 355.00056 -336.916014)
			(xy 354.998528 -336.943446) (xy 354.994972 -336.968592) (xy 355.045264 -337.018884) (xy 355.045264 -337.025488)
			(xy 355.41077 -337.390994) (xy 355.41077 -338.900516) (xy 354.580952 -339.730334) (xy 350.702626 -339.730334)
			(xy 350.678162 -339.752401) (xy 350.624806 -339.791053) (xy 350.567145 -339.822927) (xy 350.506034 -339.847551)
			(xy 350.442383 -339.864559) (xy 350.377135 -339.873698) (xy 350.31126 -339.874834) (xy 350.245736 -339.867947)
			(xy 350.181536 -339.853142) (xy 350.119614 -339.830638) (xy 350.060888 -339.800769) (xy 350.006232 -339.763979)
			(xy 349.981012 -339.74278) (xy 349.8977 -339.669882) (xy 348.878652 -338.650834) (xy 348.878652 -335.198466)
			(xy 348.878144 -335.198212) (xy 348.878144 -335.079594) (xy 348.878652 -335.079086) (xy 348.878652 -334.028796)
			(xy 348.86392 -333.992728) (xy 348.804738 -333.933546) (xy 345.349322 -333.933546) (xy 345.29776 -333.985108)
			(xy 345.29776 -336.012028) (xy 345.350592 -336.065114) (xy 346.69349 -336.065114) (xy 346.839794 -336.211418)
			(xy 346.839794 -336.312256) (xy 346.840048 -336.313018) (xy 346.840048 -336.315304) (xy 346.840048 -336.916014)
			(xy 346.838016 -336.943446) (xy 346.83446 -336.968592) (xy 347.485462 -337.619594) (xy 347.485462 -339.216746)
			(xy 347.060774 -339.641434) (xy 342.545416 -339.641434) (xy 342.524174 -339.666692) (xy 342.476348 -339.712173)
			(xy 342.423158 -339.751246) (xy 342.365457 -339.783284) (xy 342.30417 -339.807772) (xy 342.240279 -339.82432)
			(xy 342.174809 -339.83266) (xy 342.108811 -339.83266) (xy 342.043341 -339.82432) (xy 341.97945 -339.807772)
			(xy 341.918163 -339.783284) (xy 341.860462 -339.751246) (xy 341.807272 -339.712173) (xy 341.759446 -339.666692)
			(xy 341.738204 -339.641434) (xy 340.920324 -339.641434) (xy 340.668356 -339.389466) (xy 340.668356 -337.49615)
			(xy 340.515956 -337.34375) (xy 337.297268 -337.34375) (xy 337.188556 -337.452462) (xy 337.188556 -339.399118)
			(xy 337.218528 -339.42909) (xy 338.580984 -339.42909) (xy 338.737956 -339.586062) (xy 338.737956 -340.322662)
			(xy 339.144356 -340.729062) (xy 339.144356 -342.599772) (xy 338.652866 -343.091262) (xy 334.489044 -343.091262)
			(xy 334.46923 -343.118999) (xy 334.423979 -343.169979) (xy 334.37292 -343.215141) (xy 334.316795 -343.253827)
			(xy 334.25642 -343.285474) (xy 334.192674 -343.309622) (xy 334.126485 -343.32592) (xy 334.058815 -343.334131)
			(xy 334.024732 -343.334594) (xy 334.024224 -343.334594) (xy 334.011697 -343.334508) (xy 333.986669 -343.333367)
			(xy 333.974186 -343.332308) (xy 333.95031 -343.330276) (xy 333.668624 -343.611962) (xy 333.062072 -343.611962)
			(xy 332.584552 -343.134442) (xy 331.218286 -343.134442) (xy 331.14996 -343.202768) (xy 329.04938 -343.202768)
			(xy 329.01128 -343.240868) (xy 329.01128 -344.664284) (xy 344.414856 -344.664284) (xy 344.414856 -343.140284)
			(xy 344.415311 -343.126922) (xy 344.422219 -343.101106) (xy 344.435562 -343.077951) (xy 344.454433 -343.059029)
			(xy 344.477552 -343.045625) (xy 344.503349 -343.038648) (xy 344.51671 -343.038176) (xy 346.04071 -343.038176)
			(xy 346.054091 -343.038536) (xy 346.079938 -343.045477) (xy 346.103102 -343.058882) (xy 346.121998 -343.077833)
			(xy 346.135336 -343.101035) (xy 346.142202 -343.126902) (xy 346.142564 -343.140284) (xy 346.142564 -343.944632)
			(xy 346.889828 -343.944632) (xy 346.889828 -343.859936) (xy 346.897879 -343.775622) (xy 346.913908 -343.692456)
			(xy 346.937769 -343.611189) (xy 346.969248 -343.532559) (xy 347.008059 -343.457278) (xy 347.053849 -343.386026)
			(xy 347.106205 -343.31945) (xy 347.164653 -343.258152) (xy 347.228663 -343.202687) (xy 347.297655 -343.153558)
			(xy 347.371005 -343.111209) (xy 347.448048 -343.076025) (xy 347.528087 -343.048323) (xy 347.610396 -343.028355)
			(xy 347.694231 -343.016302) (xy 347.778832 -343.012272) (xy 347.863433 -343.016302) (xy 347.947268 -343.028355)
			(xy 348.029577 -343.048323) (xy 348.109616 -343.076025) (xy 348.186659 -343.111209) (xy 348.260009 -343.153558)
			(xy 348.329001 -343.202687) (xy 348.393011 -343.258152) (xy 348.451459 -343.31945) (xy 348.503815 -343.386026)
			(xy 348.549605 -343.457278) (xy 348.588416 -343.532559) (xy 348.619895 -343.611189) (xy 348.643756 -343.692456)
			(xy 348.659785 -343.775622) (xy 348.667836 -343.859936) (xy 348.66834 -343.902284) (xy 348.667836 -343.944632)
			(xy 348.659785 -344.028946) (xy 348.643756 -344.112112) (xy 348.619895 -344.193379) (xy 348.588416 -344.272009)
			(xy 348.549605 -344.34729) (xy 348.503815 -344.418542) (xy 348.451459 -344.485118) (xy 348.393011 -344.546416)
			(xy 348.329001 -344.601881) (xy 348.260009 -344.65101) (xy 348.237018 -344.664284) (xy 351.97542 -344.664284)
			(xy 351.97542 -343.140284) (xy 351.975812 -343.126917) (xy 351.982725 -343.101091) (xy 351.996078 -343.07793)
			(xy 352.014963 -343.059006) (xy 352.038097 -343.045606) (xy 352.063908 -343.03864) (xy 352.077274 -343.038176)
			(xy 353.601274 -343.038176) (xy 353.614654 -343.038568) (xy 353.640499 -343.045501) (xy 353.663663 -343.058898)
			(xy 353.68256 -343.077843) (xy 353.695898 -343.101041) (xy 353.702765 -343.126903) (xy 353.703128 -343.140284)
			(xy 353.703128 -343.944632) (xy 354.450392 -343.944632) (xy 354.450392 -343.859936) (xy 354.458443 -343.775622)
			(xy 354.474472 -343.692456) (xy 354.498333 -343.611189) (xy 354.529812 -343.532559) (xy 354.568623 -343.457278)
			(xy 354.614413 -343.386026) (xy 354.666769 -343.31945) (xy 354.725217 -343.258152) (xy 354.789227 -343.202687)
			(xy 354.858219 -343.153558) (xy 354.931569 -343.111209) (xy 355.008612 -343.076025) (xy 355.088651 -343.048323)
			(xy 355.17096 -343.028355) (xy 355.254795 -343.016302) (xy 355.339396 -343.012272) (xy 355.423997 -343.016302)
			(xy 355.507832 -343.028355) (xy 355.590141 -343.048323) (xy 355.67018 -343.076025) (xy 355.747223 -343.111209)
			(xy 355.820573 -343.153558) (xy 355.889565 -343.202687) (xy 355.953575 -343.258152) (xy 356.012023 -343.31945)
			(xy 356.064379 -343.386026) (xy 356.110169 -343.457278) (xy 356.14898 -343.532559) (xy 356.180459 -343.611189)
			(xy 356.20432 -343.692456) (xy 356.220349 -343.775622) (xy 356.2284 -343.859936) (xy 356.228904 -343.902284)
			(xy 356.2284 -343.944632) (xy 356.220349 -344.028946) (xy 356.20432 -344.112112) (xy 356.180459 -344.193379)
			(xy 356.14898 -344.272009) (xy 356.110169 -344.34729) (xy 356.064379 -344.418542) (xy 356.012023 -344.485118)
			(xy 355.953575 -344.546416) (xy 355.889565 -344.601881) (xy 355.820573 -344.65101) (xy 355.797582 -344.664284)
			(xy 359.680764 -344.664284) (xy 359.680764 -343.140284) (xy 359.681211 -343.126921) (xy 359.68812 -343.101104)
			(xy 359.701464 -343.077949) (xy 359.720337 -343.059026) (xy 359.743458 -343.045622) (xy 359.769257 -343.038647)
			(xy 359.782618 -343.038176) (xy 361.306618 -343.038176) (xy 361.32 -343.03853) (xy 361.345847 -343.045472)
			(xy 361.36901 -343.058878) (xy 361.387907 -343.077831) (xy 361.401244 -343.101034) (xy 361.40811 -343.126901)
			(xy 361.408472 -343.140284) (xy 361.408472 -343.944632) (xy 362.155736 -343.944632) (xy 362.155736 -343.859936)
			(xy 362.163787 -343.775622) (xy 362.179816 -343.692456) (xy 362.203677 -343.611189) (xy 362.235156 -343.532559)
			(xy 362.273967 -343.457278) (xy 362.319757 -343.386026) (xy 362.372113 -343.31945) (xy 362.430561 -343.258152)
			(xy 362.494571 -343.202687) (xy 362.563563 -343.153558) (xy 362.636913 -343.111209) (xy 362.713956 -343.076025)
			(xy 362.793995 -343.048323) (xy 362.876304 -343.028355) (xy 362.960139 -343.016302) (xy 363.04474 -343.012272)
			(xy 363.129341 -343.016302) (xy 363.213176 -343.028355) (xy 363.295485 -343.048323) (xy 363.375524 -343.076025)
			(xy 363.452567 -343.111209) (xy 363.525917 -343.153558) (xy 363.594909 -343.202687) (xy 363.658919 -343.258152)
			(xy 363.717367 -343.31945) (xy 363.769723 -343.386026) (xy 363.815513 -343.457278) (xy 363.854324 -343.532559)
			(xy 363.885803 -343.611189) (xy 363.909664 -343.692456) (xy 363.925693 -343.775622) (xy 363.933744 -343.859936)
			(xy 363.934248 -343.902284) (xy 363.933744 -343.944632) (xy 363.925693 -344.028946) (xy 363.909664 -344.112112)
			(xy 363.885803 -344.193379) (xy 363.854324 -344.272009) (xy 363.815513 -344.34729) (xy 363.769723 -344.418542)
			(xy 363.717367 -344.485118) (xy 363.658919 -344.546416) (xy 363.594909 -344.601881) (xy 363.525917 -344.65101)
			(xy 363.502926 -344.664284) (xy 367.241328 -344.664284) (xy 367.241328 -343.140284) (xy 367.241712 -343.126916)
			(xy 367.248626 -343.10109) (xy 367.26198 -343.077928) (xy 367.280867 -343.059004) (xy 367.304002 -343.045604)
			(xy 367.329815 -343.038639) (xy 367.343182 -343.038176) (xy 368.867182 -343.038176) (xy 368.880562 -343.038561)
			(xy 368.906408 -343.045495) (xy 368.929571 -343.058894) (xy 368.948469 -343.077841) (xy 368.961807 -343.101039)
			(xy 368.968673 -343.126903) (xy 368.969036 -343.140284) (xy 368.969036 -343.944632) (xy 369.7163 -343.944632)
			(xy 369.7163 -343.859936) (xy 369.724351 -343.775622) (xy 369.74038 -343.692456) (xy 369.764241 -343.611189)
			(xy 369.79572 -343.532559) (xy 369.834531 -343.457278) (xy 369.880321 -343.386026) (xy 369.932677 -343.31945)
			(xy 369.991125 -343.258152) (xy 370.055135 -343.202687) (xy 370.124127 -343.153558) (xy 370.197477 -343.111209)
			(xy 370.27452 -343.076025) (xy 370.354559 -343.048323) (xy 370.436868 -343.028355) (xy 370.520703 -343.016302)
			(xy 370.605304 -343.012272) (xy 370.689905 -343.016302) (xy 370.77374 -343.028355) (xy 370.856049 -343.048323)
			(xy 370.936088 -343.076025) (xy 371.013131 -343.111209) (xy 371.086481 -343.153558) (xy 371.155473 -343.202687)
			(xy 371.219483 -343.258152) (xy 371.277931 -343.31945) (xy 371.330287 -343.386026) (xy 371.376077 -343.457278)
			(xy 371.414888 -343.532559) (xy 371.446367 -343.611189) (xy 371.470228 -343.692456) (xy 371.486257 -343.775622)
			(xy 371.494308 -343.859936) (xy 371.494812 -343.902284) (xy 371.494308 -343.944632) (xy 371.486257 -344.028946)
			(xy 371.470228 -344.112112) (xy 371.446367 -344.193379) (xy 371.414888 -344.272009) (xy 371.376077 -344.34729)
			(xy 371.330287 -344.418542) (xy 371.277931 -344.485118) (xy 371.219483 -344.546416) (xy 371.155473 -344.601881)
			(xy 371.086481 -344.65101) (xy 371.013131 -344.693359) (xy 370.936088 -344.728543) (xy 370.856049 -344.756245)
			(xy 370.77374 -344.776213) (xy 370.689905 -344.788266) (xy 370.605304 -344.792297) (xy 370.520703 -344.788266)
			(xy 370.436868 -344.776213) (xy 370.354559 -344.756245) (xy 370.27452 -344.728543) (xy 370.197477 -344.693359)
			(xy 370.124127 -344.65101) (xy 370.055135 -344.601881) (xy 369.991125 -344.546416) (xy 369.932677 -344.485118)
			(xy 369.880321 -344.418542) (xy 369.834531 -344.34729) (xy 369.79572 -344.272009) (xy 369.764241 -344.193379)
			(xy 369.74038 -344.112112) (xy 369.724351 -344.028946) (xy 369.7163 -343.944632) (xy 368.969036 -343.944632)
			(xy 368.969036 -344.664284) (xy 368.968561 -344.677645) (xy 368.96166 -344.703461) (xy 368.948322 -344.726617)
			(xy 368.929454 -344.74554) (xy 368.906338 -344.758945) (xy 368.880542 -344.765921) (xy 368.867182 -344.766392)
			(xy 367.343182 -344.766392) (xy 367.329806 -344.765971) (xy 367.303969 -344.759034) (xy 367.280812 -344.745639)
			(xy 367.261918 -344.726701) (xy 367.248576 -344.703514) (xy 367.241698 -344.677661) (xy 367.241328 -344.664284)
			(xy 363.502926 -344.664284) (xy 363.452567 -344.693359) (xy 363.375524 -344.728543) (xy 363.295485 -344.756245)
			(xy 363.213176 -344.776213) (xy 363.129341 -344.788266) (xy 363.04474 -344.792297) (xy 362.960139 -344.788266)
			(xy 362.876304 -344.776213) (xy 362.793995 -344.756245) (xy 362.713956 -344.728543) (xy 362.636913 -344.693359)
			(xy 362.563563 -344.65101) (xy 362.494571 -344.601881) (xy 362.430561 -344.546416) (xy 362.372113 -344.485118)
			(xy 362.319757 -344.418542) (xy 362.273967 -344.34729) (xy 362.235156 -344.272009) (xy 362.203677 -344.193379)
			(xy 362.179816 -344.112112) (xy 362.163787 -344.028946) (xy 362.155736 -343.944632) (xy 361.408472 -343.944632)
			(xy 361.408472 -344.664284) (xy 361.40806 -344.677651) (xy 361.401153 -344.703476) (xy 361.387806 -344.726638)
			(xy 361.368925 -344.745563) (xy 361.345793 -344.758963) (xy 361.319983 -344.765929) (xy 361.306618 -344.766392)
			(xy 359.782618 -344.766392) (xy 359.769244 -344.765939) (xy 359.743408 -344.759011) (xy 359.720251 -344.745623)
			(xy 359.701356 -344.726691) (xy 359.688013 -344.703508) (xy 359.681135 -344.677659) (xy 359.680764 -344.664284)
			(xy 355.797582 -344.664284) (xy 355.747223 -344.693359) (xy 355.67018 -344.728543) (xy 355.590141 -344.756245)
			(xy 355.507832 -344.776213) (xy 355.423997 -344.788266) (xy 355.339396 -344.792297) (xy 355.254795 -344.788266)
			(xy 355.17096 -344.776213) (xy 355.088651 -344.756245) (xy 355.008612 -344.728543) (xy 354.931569 -344.693359)
			(xy 354.858219 -344.65101) (xy 354.789227 -344.601881) (xy 354.725217 -344.546416) (xy 354.666769 -344.485118)
			(xy 354.614413 -344.418542) (xy 354.568623 -344.34729) (xy 354.529812 -344.272009) (xy 354.498333 -344.193379)
			(xy 354.474472 -344.112112) (xy 354.458443 -344.028946) (xy 354.450392 -343.944632) (xy 353.703128 -343.944632)
			(xy 353.703128 -344.664284) (xy 353.702661 -344.677646) (xy 353.695759 -344.703463) (xy 353.68242 -344.72662)
			(xy 353.663551 -344.745543) (xy 353.640432 -344.758947) (xy 353.614635 -344.765922) (xy 353.601274 -344.766392)
			(xy 352.077274 -344.766392) (xy 352.063898 -344.765978) (xy 352.038061 -344.759039) (xy 352.014904 -344.745643)
			(xy 351.996009 -344.726703) (xy 351.982668 -344.703515) (xy 351.97579 -344.677661) (xy 351.97542 -344.664284)
			(xy 348.237018 -344.664284) (xy 348.186659 -344.693359) (xy 348.109616 -344.728543) (xy 348.029577 -344.756245)
			(xy 347.947268 -344.776213) (xy 347.863433 -344.788266) (xy 347.778832 -344.792297) (xy 347.694231 -344.788266)
			(xy 347.610396 -344.776213) (xy 347.528087 -344.756245) (xy 347.448048 -344.728543) (xy 347.371005 -344.693359)
			(xy 347.297655 -344.65101) (xy 347.228663 -344.601881) (xy 347.164653 -344.546416) (xy 347.106205 -344.485118)
			(xy 347.053849 -344.418542) (xy 347.008059 -344.34729) (xy 346.969248 -344.272009) (xy 346.937769 -344.193379)
			(xy 346.913908 -344.112112) (xy 346.897879 -344.028946) (xy 346.889828 -343.944632) (xy 346.142564 -343.944632)
			(xy 346.142564 -344.664284) (xy 346.14216 -344.677651) (xy 346.135253 -344.703478) (xy 346.121904 -344.726641)
			(xy 346.103021 -344.745566) (xy 346.079887 -344.758966) (xy 346.054076 -344.76593) (xy 346.04071 -344.766392)
			(xy 344.51671 -344.766392) (xy 344.503335 -344.765946) (xy 344.4775 -344.759016) (xy 344.454343 -344.745627)
			(xy 344.435447 -344.726693) (xy 344.422105 -344.703509) (xy 344.415227 -344.677659) (xy 344.414856 -344.664284)
			(xy 329.01128 -344.664284) (xy 329.01128 -345.22537) (xy 329.05192 -345.26601) (xy 330.40447 -345.26601)
			(xy 330.52131 -345.38285) (xy 330.52131 -346.324428) (xy 331.09408 -346.897198) (xy 331.09408 -348.290642)
			(xy 331.193675 -348.314714) (xy 331.391144 -348.369479) (xy 331.586385 -348.431726) (xy 331.779113 -348.501364)
			(xy 331.969049 -348.578291) (xy 332.155917 -348.662396) (xy 332.339446 -348.753558) (xy 332.519371 -348.851643)
			(xy 332.695428 -348.95651) (xy 332.867365 -349.068006) (xy 333.03493 -349.18597) (xy 333.19788 -349.31023)
			(xy 333.35598 -349.440606) (xy 333.509 -349.576909) (xy 333.656717 -349.718941) (xy 333.798917 -349.866496)
			(xy 333.935395 -350.01936) (xy 334.065951 -350.177311) (xy 334.190397 -350.34012) (xy 334.308552 -350.50755)
			(xy 334.420245 -350.679359) (xy 334.525312 -350.855297) (xy 334.623603 -351.035109) (xy 334.714974 -351.218534)
			(xy 334.799293 -351.405306) (xy 334.876437 -351.595154) (xy 334.946294 -351.787803) (xy 335.008764 -351.982972)
			(xy 335.063755 -352.180379) (xy 335.111187 -352.379737) (xy 335.150993 -352.580757) (xy 335.183113 -352.783147)
			(xy 335.207501 -352.986613) (xy 335.216246 -353.088702) (xy 335.220056 -353.135438) (xy 345.261438 -353.135438)
			(xy 348.899988 -349.496888) (xy 361.24134 -349.496888) (xy 362.5342 -350.789748) (xy 362.8644 -351.119948)
			(xy 363.422692 -351.119948) (xy 363.422692 -349.595948) (xy 363.423131 -349.58256) (xy 363.430052 -349.556693)
			(xy 363.443432 -349.5335) (xy 363.462362 -349.514562) (xy 363.485549 -349.50117) (xy 363.511412 -349.494238)
			(xy 363.5248 -349.49384) (xy 365.0488 -349.49384) (xy 365.062194 -349.49419) (xy 365.08807 -349.501126)
			(xy 365.111268 -349.514524) (xy 365.130206 -349.533471) (xy 365.143593 -349.556675) (xy 365.150516 -349.582553)
			(xy 365.150908 -349.595948) (xy 365.150908 -350.3579) (xy 365.89692 -350.3579) (xy 365.90095 -350.273301)
			(xy 365.913004 -350.189468) (xy 365.932972 -350.10716) (xy 365.960673 -350.027123) (xy 365.995857 -349.950082)
			(xy 366.038206 -349.876734) (xy 366.087334 -349.807744) (xy 366.142799 -349.743736) (xy 366.204096 -349.68529)
			(xy 366.270672 -349.632936) (xy 366.341923 -349.587147) (xy 366.417204 -349.548339) (xy 366.495832 -349.516862)
			(xy 366.577097 -349.493003) (xy 366.660262 -349.476976) (xy 366.744574 -349.468927) (xy 366.786922 -349.46844)
			(xy 366.836171 -349.469149) (xy 366.93406 -349.480091) (xy 366.982248 -349.490284) (xy 366.990376 -349.491808)
			(xy 367.031735 -349.501998) (xy 367.112424 -349.529309) (xy 367.190133 -349.564208) (xy 367.264151 -349.606375)
			(xy 367.333799 -349.655423) (xy 367.398441 -349.710904) (xy 367.457483 -349.77231) (xy 367.510386 -349.839078)
			(xy 367.556664 -349.910597) (xy 367.595895 -349.986211) (xy 367.627718 -350.06523) (xy 367.651843 -350.146928)
			(xy 367.668049 -350.230559) (xy 367.676187 -350.315355) (xy 367.676684 -350.357948) (xy 367.676165 -350.400539)
			(xy 367.668019 -350.48533) (xy 367.651808 -350.568955) (xy 367.627679 -350.650647) (xy 367.595853 -350.72966)
			(xy 367.556621 -350.80527) (xy 367.510343 -350.876784) (xy 367.457442 -350.943547) (xy 367.398403 -351.00495)
			(xy 367.333766 -351.060429) (xy 367.264122 -351.109477) (xy 367.19011 -351.151645) (xy 367.112407 -351.186546)
			(xy 367.031724 -351.213862) (xy 366.990376 -351.224088) (xy 366.982248 -351.225612) (xy 366.934062 -351.235819)
			(xy 366.836172 -351.246766) (xy 366.786922 -351.247456) (xy 366.744574 -351.246873) (xy 366.660262 -351.238824)
			(xy 366.577097 -351.222797) (xy 366.495832 -351.198938) (xy 366.417204 -351.167461) (xy 366.341923 -351.128653)
			(xy 366.270672 -351.082864) (xy 366.204096 -351.03051) (xy 366.142799 -350.972064) (xy 366.087334 -350.908056)
			(xy 366.038206 -350.839066) (xy 365.995857 -350.765718) (xy 365.960673 -350.688677) (xy 365.932972 -350.60864)
			(xy 365.913004 -350.526332) (xy 365.90095 -350.442499) (xy 365.89692 -350.3579) (xy 365.150908 -350.3579)
			(xy 365.150908 -351.119948) (xy 365.150513 -351.133335) (xy 365.143573 -351.159196) (xy 365.130179 -351.182379)
			(xy 365.111241 -351.201308) (xy 365.088051 -351.214692) (xy 365.062188 -351.22162) (xy 365.0488 -351.222056)
			(xy 363.5248 -351.222056) (xy 363.511419 -351.221572) (xy 363.485568 -351.214647) (xy 363.462388 -351.201269)
			(xy 363.44346 -351.18235) (xy 363.430071 -351.159177) (xy 363.423135 -351.133329) (xy 363.422692 -351.119948)
			(xy 362.8644 -351.119948) (xy 363.4486 -351.704148) (xy 363.601 -351.856548) (xy 369.014756 -351.856548)
			(xy 373.089424 -355.931216) (xy 373.089424 -361.198414) (xy 372.988586 -361.299252) (xy 372.988586 -361.995466)
			(xy 373.037354 -362.044234) (xy 373.418608 -362.044234)
		)
		(stroke
			(width 0)
			(type solid)
		)
		(fill yes)
		(layer "F.Cu")
		(net "SW_P12V_PVCCIN_CPU0_FLT")
	)
	(gr_poly
		(pts
			(xy 405.430228 -193.799968) (xy 444.78702 -193.799968) (xy 446.575434 -192.011554) (xy 446.575434 -190.031624)
			(xy 445.900048 -190.031624) (xy 445.857769 -190.031153) (xy 445.773571 -190.023355) (xy 445.690452 -190.007821)
			(xy 445.609121 -189.984684) (xy 445.530272 -189.954142) (xy 445.454577 -189.916454) (xy 445.382683 -189.871942)
			(xy 445.315203 -189.820987) (xy 445.252712 -189.764022) (xy 445.195744 -189.701534) (xy 445.144785 -189.634057)
			(xy 445.10027 -189.562165) (xy 445.062578 -189.486472) (xy 445.032031 -189.407624) (xy 445.00889 -189.326295)
			(xy 444.993352 -189.243176) (xy 444.985549 -189.158979) (xy 444.985549 -189.074421) (xy 444.993352 -188.990224)
			(xy 445.00889 -188.907105) (xy 445.032031 -188.825776) (xy 445.062578 -188.746928) (xy 445.10027 -188.671235)
			(xy 445.144785 -188.599343) (xy 445.195744 -188.531866) (xy 445.252712 -188.469378) (xy 445.315203 -188.412413)
			(xy 445.382683 -188.361458) (xy 445.454577 -188.316946) (xy 445.530272 -188.279258) (xy 445.609121 -188.248716)
			(xy 445.690452 -188.225579) (xy 445.773571 -188.210045) (xy 445.857769 -188.202247) (xy 445.900048 -188.201808)
			(xy 446.575434 -188.201808) (xy 446.575434 -184.767474) (xy 446.61328 -184.729628) (xy 446.61328 -175.169068)
			(xy 446.34912 -174.904908) (xy 441.01766 -174.904908) (xy 440.64682 -175.275748) (xy 440.64682 -183.491886)
			(xy 438.47766 -185.661046) (xy 433.700428 -185.661046) (xy 433.677887 -185.691954) (xy 433.627547 -185.749563)
			(xy 433.571691 -185.801842) (xy 433.510881 -185.848264) (xy 433.445728 -185.888363) (xy 433.376886 -185.921735)
			(xy 433.305049 -185.948047) (xy 433.230938 -185.967032) (xy 433.155298 -185.978499) (xy 433.07889 -185.982335)
			(xy 433.002482 -185.978499) (xy 432.926842 -185.967032) (xy 432.852731 -185.948047) (xy 432.780894 -185.921735)
			(xy 432.712052 -185.888363) (xy 432.646899 -185.848264) (xy 432.586089 -185.801842) (xy 432.530233 -185.749563)
			(xy 432.479893 -185.691954) (xy 432.457352 -185.661046) (xy 407.192226 -185.661046) (xy 406.741884 -186.111388)
			(xy 406.741884 -189.158978) (xy 407.266581 -189.158978) (xy 407.266581 -189.074422) (xy 407.274383 -188.990228)
			(xy 407.289921 -188.907113) (xy 407.313061 -188.825786) (xy 407.343607 -188.746941) (xy 407.381298 -188.671251)
			(xy 407.425811 -188.599362) (xy 407.476769 -188.531886) (xy 407.533735 -188.469401) (xy 407.596223 -188.412438)
			(xy 407.663701 -188.361484) (xy 407.735593 -188.316974) (xy 407.811285 -188.279288) (xy 407.890131 -188.248746)
			(xy 407.97146 -188.22561) (xy 408.054576 -188.210077) (xy 408.13877 -188.202279) (xy 408.181048 -188.201808)
			(xy 409.425648 -188.201808) (xy 409.467923 -188.202266) (xy 409.552113 -188.210072) (xy 409.635224 -188.225612)
			(xy 409.716546 -188.248754) (xy 409.795387 -188.279301) (xy 409.871072 -188.316991) (xy 409.942957 -188.361504)
			(xy 410.010429 -188.412459) (xy 410.072911 -188.469423) (xy 410.129871 -188.531908) (xy 410.180823 -188.599382)
			(xy 410.225332 -188.67127) (xy 410.263019 -188.746957) (xy 410.293561 -188.825799) (xy 410.316699 -188.907123)
			(xy 410.332235 -188.990234) (xy 410.340036 -189.074424) (xy 410.340036 -189.158976) (xy 410.340036 -189.158978)
			(xy 414.810381 -189.158978) (xy 414.810381 -189.074422) (xy 414.818183 -188.990228) (xy 414.833721 -188.907113)
			(xy 414.856861 -188.825786) (xy 414.887407 -188.746941) (xy 414.925098 -188.671251) (xy 414.969611 -188.599362)
			(xy 415.020569 -188.531886) (xy 415.077535 -188.469401) (xy 415.140023 -188.412438) (xy 415.207501 -188.361484)
			(xy 415.279393 -188.316974) (xy 415.355085 -188.279288) (xy 415.433931 -188.248746) (xy 415.51526 -188.22561)
			(xy 415.598376 -188.210077) (xy 415.68257 -188.202279) (xy 415.724848 -188.201808) (xy 416.969448 -188.201808)
			(xy 417.011723 -188.202266) (xy 417.095913 -188.210072) (xy 417.179024 -188.225612) (xy 417.260346 -188.248754)
			(xy 417.339187 -188.279301) (xy 417.414872 -188.316991) (xy 417.486757 -188.361504) (xy 417.554229 -188.412459)
			(xy 417.616711 -188.469423) (xy 417.673671 -188.531908) (xy 417.724623 -188.599382) (xy 417.769132 -188.67127)
			(xy 417.806819 -188.746957) (xy 417.837361 -188.825799) (xy 417.860499 -188.907123) (xy 417.876035 -188.990234)
			(xy 417.883836 -189.074424) (xy 417.883836 -189.158976) (xy 417.883836 -189.158978) (xy 422.354181 -189.158978)
			(xy 422.354181 -189.074422) (xy 422.361983 -188.990228) (xy 422.377521 -188.907113) (xy 422.400661 -188.825786)
			(xy 422.431207 -188.746941) (xy 422.468898 -188.671251) (xy 422.513411 -188.599362) (xy 422.564369 -188.531886)
			(xy 422.621335 -188.469401) (xy 422.683823 -188.412438) (xy 422.751301 -188.361484) (xy 422.823193 -188.316974)
			(xy 422.898885 -188.279288) (xy 422.977731 -188.248746) (xy 423.05906 -188.22561) (xy 423.142176 -188.210077)
			(xy 423.22637 -188.202279) (xy 423.268648 -188.201808) (xy 424.513248 -188.201808) (xy 424.555523 -188.202266)
			(xy 424.639713 -188.210072) (xy 424.722824 -188.225612) (xy 424.804146 -188.248754) (xy 424.882987 -188.279301)
			(xy 424.958672 -188.316991) (xy 425.030557 -188.361504) (xy 425.098029 -188.412459) (xy 425.160511 -188.469423)
			(xy 425.217471 -188.531908) (xy 425.268423 -188.599382) (xy 425.312932 -188.67127) (xy 425.350619 -188.746957)
			(xy 425.381161 -188.825799) (xy 425.404299 -188.907123) (xy 425.419835 -188.990234) (xy 425.427636 -189.074424)
			(xy 425.427636 -189.158976) (xy 425.427636 -189.158978) (xy 429.897981 -189.158978) (xy 429.897981 -189.074422)
			(xy 429.905783 -188.990228) (xy 429.921321 -188.907113) (xy 429.944461 -188.825786) (xy 429.975007 -188.746941)
			(xy 430.012698 -188.671251) (xy 430.057211 -188.599362) (xy 430.108169 -188.531886) (xy 430.165135 -188.469401)
			(xy 430.227623 -188.412438) (xy 430.295101 -188.361484) (xy 430.366993 -188.316974) (xy 430.442685 -188.279288)
			(xy 430.521531 -188.248746) (xy 430.60286 -188.22561) (xy 430.685976 -188.210077) (xy 430.77017 -188.202279)
			(xy 430.812448 -188.201808) (xy 432.057048 -188.201808) (xy 432.099325 -188.202234) (xy 432.183519 -188.21004)
			(xy 432.266634 -188.225581) (xy 432.34796 -188.248725) (xy 432.426803 -188.279273) (xy 432.502492 -188.316966)
			(xy 432.574381 -188.361481) (xy 432.641855 -188.412439) (xy 432.70434 -188.469406) (xy 432.761302 -188.531894)
			(xy 432.812255 -188.599372) (xy 432.856766 -188.671264) (xy 432.894453 -188.746955) (xy 432.924996 -188.825801)
			(xy 432.948133 -188.907129) (xy 432.963668 -188.990244) (xy 432.971468 -189.074439) (xy 432.971956 -189.116716)
			(xy 432.971445 -189.158978) (xy 437.441781 -189.158978) (xy 437.441781 -189.074422) (xy 437.449583 -188.990228)
			(xy 437.465121 -188.907113) (xy 437.488261 -188.825786) (xy 437.518807 -188.746941) (xy 437.556498 -188.671251)
			(xy 437.601011 -188.599362) (xy 437.651969 -188.531886) (xy 437.708935 -188.469401) (xy 437.771423 -188.412438)
			(xy 437.838901 -188.361484) (xy 437.910793 -188.316974) (xy 437.986485 -188.279288) (xy 438.065331 -188.248746)
			(xy 438.14666 -188.22561) (xy 438.229776 -188.210077) (xy 438.31397 -188.202279) (xy 438.356248 -188.201808)
			(xy 439.600848 -188.201808) (xy 439.643123 -188.202266) (xy 439.727313 -188.210072) (xy 439.810424 -188.225612)
			(xy 439.891746 -188.248754) (xy 439.970587 -188.279301) (xy 440.046272 -188.316991) (xy 440.118157 -188.361504)
			(xy 440.185629 -188.412459) (xy 440.248111 -188.469423) (xy 440.305071 -188.531908) (xy 440.356023 -188.599382)
			(xy 440.400532 -188.67127) (xy 440.438219 -188.746957) (xy 440.468761 -188.825799) (xy 440.491899 -188.907123)
			(xy 440.507435 -188.990234) (xy 440.515236 -189.074424) (xy 440.515236 -189.158976) (xy 440.507435 -189.243166)
			(xy 440.491899 -189.326277) (xy 440.468761 -189.407601) (xy 440.438219 -189.486443) (xy 440.400532 -189.56213)
			(xy 440.356023 -189.634018) (xy 440.305071 -189.701492) (xy 440.248111 -189.763977) (xy 440.185629 -189.820941)
			(xy 440.118157 -189.871896) (xy 440.046272 -189.916409) (xy 439.970587 -189.954099) (xy 439.891746 -189.984646)
			(xy 439.810424 -190.007788) (xy 439.727313 -190.023328) (xy 439.643123 -190.031134) (xy 439.600848 -190.031624)
			(xy 438.356248 -190.031624) (xy 438.31397 -190.031121) (xy 438.229776 -190.023323) (xy 438.14666 -190.00779)
			(xy 438.065331 -189.984654) (xy 437.986485 -189.954112) (xy 437.910793 -189.916426) (xy 437.838901 -189.871916)
			(xy 437.771423 -189.820962) (xy 437.708935 -189.763999) (xy 437.651969 -189.701514) (xy 437.601011 -189.634038)
			(xy 437.556498 -189.562149) (xy 437.518807 -189.486459) (xy 437.488261 -189.407614) (xy 437.465121 -189.326287)
			(xy 437.449583 -189.243172) (xy 437.441781 -189.158978) (xy 432.971445 -189.158978) (xy 432.971429 -189.160318)
			(xy 432.96312 -189.247124) (xy 432.946588 -189.332746) (xy 432.921984 -189.416406) (xy 432.889531 -189.497346)
			(xy 432.849523 -189.57483) (xy 432.802323 -189.648155) (xy 432.74836 -189.716657) (xy 432.688124 -189.779712)
			(xy 432.655472 -189.808612) (xy 432.644945 -189.81839) (xy 432.629354 -189.842508) (xy 432.6211 -189.870015)
			(xy 432.620837 -189.898732) (xy 432.628585 -189.926386) (xy 432.643731 -189.950786) (xy 432.665075 -189.97)
			(xy 432.690928 -189.982506) (xy 432.705002 -189.985396) (xy 432.731293 -189.990361) (xy 432.782255 -190.006657)
			(xy 432.830441 -190.029914) (xy 432.874905 -190.059673) (xy 432.914775 -190.095353) (xy 432.949269 -190.136253)
			(xy 432.977712 -190.181572) (xy 432.999544 -190.230419) (xy 433.014337 -190.281837) (xy 433.021803 -190.334818)
			(xy 433.022248 -190.36157) (xy 433.021762 -190.388821) (xy 433.014006 -190.442769) (xy 432.998651 -190.495064)
			(xy 432.976009 -190.544641) (xy 432.946543 -190.590491) (xy 432.910852 -190.631682) (xy 432.869661 -190.667373)
			(xy 432.823811 -190.696839) (xy 432.774234 -190.719481) (xy 432.721939 -190.734836) (xy 432.667991 -190.742592)
			(xy 432.613489 -190.742592) (xy 432.559541 -190.734836) (xy 432.507246 -190.719481) (xy 432.457669 -190.696839)
			(xy 432.411819 -190.667373) (xy 432.370628 -190.631682) (xy 432.334937 -190.590491) (xy 432.305471 -190.544641)
			(xy 432.282829 -190.495064) (xy 432.267474 -190.442769) (xy 432.259718 -190.388821) (xy 432.259232 -190.36157)
			(xy 432.259603 -190.33652) (xy 432.266154 -190.286851) (xy 432.279141 -190.238464) (xy 432.29834 -190.192189)
			(xy 432.31054 -190.170308) (xy 432.317244 -190.15759) (xy 432.324171 -190.129708) (xy 432.323048 -190.101)
			(xy 432.313965 -190.073744) (xy 432.297642 -190.050102) (xy 432.275373 -190.031949) (xy 432.248927 -190.020726)
			(xy 432.220399 -190.017323) (xy 432.206146 -190.019178) (xy 432.169142 -190.024964) (xy 432.094499 -190.031196)
			(xy 432.057048 -190.031624) (xy 430.812448 -190.031624) (xy 430.77017 -190.031121) (xy 430.685976 -190.023323)
			(xy 430.60286 -190.00779) (xy 430.521531 -189.984654) (xy 430.442685 -189.954112) (xy 430.366993 -189.916426)
			(xy 430.295101 -189.871916) (xy 430.227623 -189.820962) (xy 430.165135 -189.763999) (xy 430.108169 -189.701514)
			(xy 430.057211 -189.634038) (xy 430.012698 -189.562149) (xy 429.975007 -189.486459) (xy 429.944461 -189.407614)
			(xy 429.921321 -189.326287) (xy 429.905783 -189.243172) (xy 429.897981 -189.158978) (xy 425.427636 -189.158978)
			(xy 425.419835 -189.243166) (xy 425.404299 -189.326277) (xy 425.381161 -189.407601) (xy 425.350619 -189.486443)
			(xy 425.312932 -189.56213) (xy 425.268423 -189.634018) (xy 425.217471 -189.701492) (xy 425.160511 -189.763977)
			(xy 425.098029 -189.820941) (xy 425.030557 -189.871896) (xy 424.958672 -189.916409) (xy 424.882987 -189.954099)
			(xy 424.804146 -189.984646) (xy 424.722824 -190.007788) (xy 424.639713 -190.023328) (xy 424.555523 -190.031134)
			(xy 424.513248 -190.031624) (xy 423.268648 -190.031624) (xy 423.22637 -190.031121) (xy 423.142176 -190.023323)
			(xy 423.05906 -190.00779) (xy 422.977731 -189.984654) (xy 422.898885 -189.954112) (xy 422.823193 -189.916426)
			(xy 422.751301 -189.871916) (xy 422.683823 -189.820962) (xy 422.621335 -189.763999) (xy 422.564369 -189.701514)
			(xy 422.513411 -189.634038) (xy 422.468898 -189.562149) (xy 422.431207 -189.486459) (xy 422.400661 -189.407614)
			(xy 422.377521 -189.326287) (xy 422.361983 -189.243172) (xy 422.354181 -189.158978) (xy 417.883836 -189.158978)
			(xy 417.876035 -189.243166) (xy 417.860499 -189.326277) (xy 417.837361 -189.407601) (xy 417.806819 -189.486443)
			(xy 417.769132 -189.56213) (xy 417.724623 -189.634018) (xy 417.673671 -189.701492) (xy 417.616711 -189.763977)
			(xy 417.554229 -189.820941) (xy 417.486757 -189.871896) (xy 417.414872 -189.916409) (xy 417.339187 -189.954099)
			(xy 417.260346 -189.984646) (xy 417.179024 -190.007788) (xy 417.095913 -190.023328) (xy 417.011723 -190.031134)
			(xy 416.969448 -190.031624) (xy 415.724848 -190.031624) (xy 415.68257 -190.031121) (xy 415.598376 -190.023323)
			(xy 415.51526 -190.00779) (xy 415.433931 -189.984654) (xy 415.355085 -189.954112) (xy 415.279393 -189.916426)
			(xy 415.207501 -189.871916) (xy 415.140023 -189.820962) (xy 415.077535 -189.763999) (xy 415.020569 -189.701514)
			(xy 414.969611 -189.634038) (xy 414.925098 -189.562149) (xy 414.887407 -189.486459) (xy 414.856861 -189.407614)
			(xy 414.833721 -189.326287) (xy 414.818183 -189.243172) (xy 414.810381 -189.158978) (xy 410.340036 -189.158978)
			(xy 410.332235 -189.243166) (xy 410.316699 -189.326277) (xy 410.293561 -189.407601) (xy 410.263019 -189.486443)
			(xy 410.225332 -189.56213) (xy 410.180823 -189.634018) (xy 410.129871 -189.701492) (xy 410.072911 -189.763977)
			(xy 410.010429 -189.820941) (xy 409.942957 -189.871896) (xy 409.871072 -189.916409) (xy 409.795387 -189.954099)
			(xy 409.716546 -189.984646) (xy 409.635224 -190.007788) (xy 409.552113 -190.023328) (xy 409.467923 -190.031134)
			(xy 409.425648 -190.031624) (xy 408.181048 -190.031624) (xy 408.13877 -190.031121) (xy 408.054576 -190.023323)
			(xy 407.97146 -190.00779) (xy 407.890131 -189.984654) (xy 407.811285 -189.954112) (xy 407.735593 -189.916426)
			(xy 407.663701 -189.871916) (xy 407.596223 -189.820962) (xy 407.533735 -189.763999) (xy 407.476769 -189.701514)
			(xy 407.425811 -189.634038) (xy 407.381298 -189.562149) (xy 407.343607 -189.486459) (xy 407.313061 -189.407614)
			(xy 407.289921 -189.326287) (xy 407.274383 -189.243172) (xy 407.266581 -189.158978) (xy 406.741884 -189.158978)
			(xy 406.741884 -189.543436) (xy 405.889968 -190.395352) (xy 404.048214 -190.395352) (xy 403.699218 -190.744348)
			(xy 402.0312 -190.744348) (xy 401.60194 -190.315088) (xy 401.60194 -188.674248) (xy 401.17014 -188.242448)
			(xy 397.99768 -188.242448) (xy 397.69796 -188.542168) (xy 397.69796 -189.77483) (xy 398.79854 -189.77483)
			(xy 398.802611 -189.719208) (xy 398.814737 -189.664771) (xy 398.83466 -189.61268) (xy 398.861956 -189.564045)
			(xy 398.896042 -189.519902) (xy 398.936191 -189.481193) (xy 398.981549 -189.448742) (xy 399.031149 -189.423241)
			(xy 399.083933 -189.405234) (xy 399.138776 -189.395104) (xy 399.19451 -189.393067) (xy 399.249947 -189.399167)
			(xy 399.303904 -189.413273) (xy 399.355233 -189.435085) (xy 399.402839 -189.464139) (xy 399.445707 -189.499814)
			(xy 399.482924 -189.541351) (xy 399.513697 -189.587864) (xy 399.537369 -189.638361) (xy 399.553437 -189.691768)
			(xy 399.561557 -189.746944) (xy 399.562066 -189.77483) (xy 399.561557 -189.802716) (xy 399.553437 -189.857892)
			(xy 399.537369 -189.911299) (xy 399.513697 -189.961796) (xy 399.482924 -190.008309) (xy 399.445707 -190.049846)
			(xy 399.402839 -190.085521) (xy 399.355233 -190.114575) (xy 399.303904 -190.136387) (xy 399.249947 -190.150493)
			(xy 399.19451 -190.156593) (xy 399.138776 -190.154556) (xy 399.083933 -190.144426) (xy 399.031149 -190.126419)
			(xy 398.981549 -190.100918) (xy 398.936191 -190.068467) (xy 398.896042 -190.029758) (xy 398.861956 -189.985615)
			(xy 398.83466 -189.93698) (xy 398.814737 -189.884889) (xy 398.802611 -189.830452) (xy 398.79854 -189.77483)
			(xy 397.69796 -189.77483) (xy 397.69796 -191.25057) (xy 426.797722 -191.25057) (xy 426.801793 -191.194948)
			(xy 426.813919 -191.140511) (xy 426.833842 -191.08842) (xy 426.861138 -191.039785) (xy 426.895224 -190.995642)
			(xy 426.935373 -190.956933) (xy 426.980731 -190.924482) (xy 427.030331 -190.898981) (xy 427.083115 -190.880974)
			(xy 427.137958 -190.870844) (xy 427.193692 -190.868807) (xy 427.249129 -190.874907) (xy 427.303086 -190.889013)
			(xy 427.354415 -190.910825) (xy 427.402021 -190.939879) (xy 427.444889 -190.975554) (xy 427.482106 -191.017091)
			(xy 427.512879 -191.063604) (xy 427.536551 -191.114101) (xy 427.552619 -191.167508) (xy 427.560739 -191.222684)
			(xy 427.561248 -191.25057) (xy 427.560951 -191.266826) (xy 432.681124 -191.266826) (xy 432.685195 -191.211204)
			(xy 432.697321 -191.156767) (xy 432.717244 -191.104676) (xy 432.74454 -191.056041) (xy 432.778626 -191.011898)
			(xy 432.818775 -190.973189) (xy 432.864133 -190.940738) (xy 432.913733 -190.915237) (xy 432.966517 -190.89723)
			(xy 433.02136 -190.8871) (xy 433.077094 -190.885063) (xy 433.132531 -190.891163) (xy 433.186488 -190.905269)
			(xy 433.237817 -190.927081) (xy 433.285423 -190.956135) (xy 433.328291 -190.99181) (xy 433.365508 -191.033347)
			(xy 433.396281 -191.07986) (xy 433.419953 -191.130357) (xy 433.436021 -191.183764) (xy 433.444141 -191.23894)
			(xy 433.44465 -191.266826) (xy 433.444141 -191.294712) (xy 433.436021 -191.349888) (xy 433.419953 -191.403295)
			(xy 433.396281 -191.453792) (xy 433.365508 -191.500305) (xy 433.328291 -191.541842) (xy 433.285423 -191.577517)
			(xy 433.237817 -191.606571) (xy 433.186488 -191.628383) (xy 433.132531 -191.642489) (xy 433.077094 -191.648589)
			(xy 433.02136 -191.646552) (xy 432.966517 -191.636422) (xy 432.913733 -191.618415) (xy 432.864133 -191.592914)
			(xy 432.818775 -191.560463) (xy 432.778626 -191.521754) (xy 432.74454 -191.477611) (xy 432.717244 -191.428976)
			(xy 432.697321 -191.376885) (xy 432.685195 -191.322448) (xy 432.681124 -191.266826) (xy 427.560951 -191.266826)
			(xy 427.560739 -191.278456) (xy 427.552619 -191.333632) (xy 427.536551 -191.387039) (xy 427.512879 -191.437536)
			(xy 427.482106 -191.484049) (xy 427.444889 -191.525586) (xy 427.402021 -191.561261) (xy 427.354415 -191.590315)
			(xy 427.303086 -191.612127) (xy 427.249129 -191.626233) (xy 427.193692 -191.632333) (xy 427.137958 -191.630296)
			(xy 427.083115 -191.620166) (xy 427.030331 -191.602159) (xy 426.980731 -191.576658) (xy 426.935373 -191.544207)
			(xy 426.895224 -191.505498) (xy 426.861138 -191.461355) (xy 426.833842 -191.41272) (xy 426.813919 -191.360629)
			(xy 426.801793 -191.306192) (xy 426.797722 -191.25057) (xy 397.69796 -191.25057) (xy 397.69796 -191.971422)
			(xy 403.710392 -191.971422) (xy 403.714463 -191.9158) (xy 403.726589 -191.861363) (xy 403.746512 -191.809272)
			(xy 403.773808 -191.760637) (xy 403.807894 -191.716494) (xy 403.848043 -191.677785) (xy 403.893401 -191.645334)
			(xy 403.943001 -191.619833) (xy 403.995785 -191.601826) (xy 404.050628 -191.591696) (xy 404.106362 -191.589659)
			(xy 404.161799 -191.595759) (xy 404.215756 -191.609865) (xy 404.267085 -191.631677) (xy 404.314691 -191.660731)
			(xy 404.357559 -191.696406) (xy 404.394776 -191.737943) (xy 404.425549 -191.784456) (xy 404.449221 -191.834953)
			(xy 404.465289 -191.88836) (xy 404.473409 -191.943536) (xy 404.473918 -191.971422) (xy 404.473409 -191.999308)
			(xy 404.465289 -192.054484) (xy 404.459253 -192.074546) (xy 406.726134 -192.074546) (xy 406.730205 -192.018924)
			(xy 406.742331 -191.964487) (xy 406.762254 -191.912396) (xy 406.78955 -191.863761) (xy 406.823636 -191.819618)
			(xy 406.863785 -191.780909) (xy 406.909143 -191.748458) (xy 406.958743 -191.722957) (xy 407.011527 -191.70495)
			(xy 407.06637 -191.69482) (xy 407.122104 -191.692783) (xy 407.177541 -191.698883) (xy 407.231498 -191.712989)
			(xy 407.282827 -191.734801) (xy 407.330433 -191.763855) (xy 407.373301 -191.79953) (xy 407.410518 -191.841067)
			(xy 407.441291 -191.88758) (xy 407.464963 -191.938077) (xy 407.481031 -191.991484) (xy 407.489151 -192.04666)
			(xy 407.48966 -192.074546) (xy 407.742134 -192.074546) (xy 407.746205 -192.018924) (xy 407.758331 -191.964487)
			(xy 407.778254 -191.912396) (xy 407.80555 -191.863761) (xy 407.839636 -191.819618) (xy 407.879785 -191.780909)
			(xy 407.925143 -191.748458) (xy 407.974743 -191.722957) (xy 408.027527 -191.70495) (xy 408.08237 -191.69482)
			(xy 408.138104 -191.692783) (xy 408.193541 -191.698883) (xy 408.247498 -191.712989) (xy 408.298827 -191.734801)
			(xy 408.346433 -191.763855) (xy 408.389301 -191.79953) (xy 408.426518 -191.841067) (xy 408.457291 -191.88758)
			(xy 408.480963 -191.938077) (xy 408.497031 -191.991484) (xy 408.505151 -192.04666) (xy 408.50566 -192.074546)
			(xy 408.758134 -192.074546) (xy 408.762205 -192.018924) (xy 408.774331 -191.964487) (xy 408.794254 -191.912396)
			(xy 408.82155 -191.863761) (xy 408.855636 -191.819618) (xy 408.895785 -191.780909) (xy 408.941143 -191.748458)
			(xy 408.990743 -191.722957) (xy 409.043527 -191.70495) (xy 409.09837 -191.69482) (xy 409.154104 -191.692783)
			(xy 409.209541 -191.698883) (xy 409.263498 -191.712989) (xy 409.314827 -191.734801) (xy 409.362433 -191.763855)
			(xy 409.405301 -191.79953) (xy 409.442518 -191.841067) (xy 409.473291 -191.88758) (xy 409.496963 -191.938077)
			(xy 409.513031 -191.991484) (xy 409.521151 -192.04666) (xy 409.52166 -192.074546) (xy 409.774134 -192.074546)
			(xy 409.778205 -192.018924) (xy 409.790331 -191.964487) (xy 409.810254 -191.912396) (xy 409.83755 -191.863761)
			(xy 409.871636 -191.819618) (xy 409.911785 -191.780909) (xy 409.957143 -191.748458) (xy 410.006743 -191.722957)
			(xy 410.059527 -191.70495) (xy 410.11437 -191.69482) (xy 410.170104 -191.692783) (xy 410.225541 -191.698883)
			(xy 410.279498 -191.712989) (xy 410.330827 -191.734801) (xy 410.378433 -191.763855) (xy 410.421301 -191.79953)
			(xy 410.458518 -191.841067) (xy 410.489291 -191.88758) (xy 410.512963 -191.938077) (xy 410.529031 -191.991484)
			(xy 410.537151 -192.04666) (xy 410.53766 -192.074546) (xy 410.790134 -192.074546) (xy 410.794205 -192.018924)
			(xy 410.806331 -191.964487) (xy 410.826254 -191.912396) (xy 410.85355 -191.863761) (xy 410.887636 -191.819618)
			(xy 410.927785 -191.780909) (xy 410.973143 -191.748458) (xy 411.022743 -191.722957) (xy 411.075527 -191.70495)
			(xy 411.13037 -191.69482) (xy 411.186104 -191.692783) (xy 411.241541 -191.698883) (xy 411.295498 -191.712989)
			(xy 411.346827 -191.734801) (xy 411.394433 -191.763855) (xy 411.437301 -191.79953) (xy 411.474518 -191.841067)
			(xy 411.505291 -191.88758) (xy 411.528963 -191.938077) (xy 411.545031 -191.991484) (xy 411.553151 -192.04666)
			(xy 411.55366 -192.074546) (xy 413.873694 -192.074546) (xy 413.877765 -192.018924) (xy 413.889891 -191.964487)
			(xy 413.909814 -191.912396) (xy 413.93711 -191.863761) (xy 413.971196 -191.819618) (xy 414.011345 -191.780909)
			(xy 414.056703 -191.748458) (xy 414.106303 -191.722957) (xy 414.159087 -191.70495) (xy 414.21393 -191.69482)
			(xy 414.269664 -191.692783) (xy 414.325101 -191.698883) (xy 414.379058 -191.712989) (xy 414.430387 -191.734801)
			(xy 414.477993 -191.763855) (xy 414.520861 -191.79953) (xy 414.558078 -191.841067) (xy 414.588851 -191.88758)
			(xy 414.612523 -191.938077) (xy 414.628591 -191.991484) (xy 414.636711 -192.04666) (xy 414.63722 -192.074546)
			(xy 414.889694 -192.074546) (xy 414.893765 -192.018924) (xy 414.905891 -191.964487) (xy 414.925814 -191.912396)
			(xy 414.95311 -191.863761) (xy 414.987196 -191.819618) (xy 415.027345 -191.780909) (xy 415.072703 -191.748458)
			(xy 415.122303 -191.722957) (xy 415.175087 -191.70495) (xy 415.22993 -191.69482) (xy 415.285664 -191.692783)
			(xy 415.341101 -191.698883) (xy 415.395058 -191.712989) (xy 415.446387 -191.734801) (xy 415.493993 -191.763855)
			(xy 415.536861 -191.79953) (xy 415.574078 -191.841067) (xy 415.604851 -191.88758) (xy 415.628523 -191.938077)
			(xy 415.644591 -191.991484) (xy 415.652711 -192.04666) (xy 415.65322 -192.074546) (xy 415.905694 -192.074546)
			(xy 415.909765 -192.018924) (xy 415.921891 -191.964487) (xy 415.941814 -191.912396) (xy 415.96911 -191.863761)
			(xy 416.003196 -191.819618) (xy 416.043345 -191.780909) (xy 416.088703 -191.748458) (xy 416.138303 -191.722957)
			(xy 416.191087 -191.70495) (xy 416.24593 -191.69482) (xy 416.301664 -191.692783) (xy 416.357101 -191.698883)
			(xy 416.411058 -191.712989) (xy 416.462387 -191.734801) (xy 416.509993 -191.763855) (xy 416.552861 -191.79953)
			(xy 416.590078 -191.841067) (xy 416.620851 -191.88758) (xy 416.644523 -191.938077) (xy 416.660591 -191.991484)
			(xy 416.668711 -192.04666) (xy 416.66922 -192.074546) (xy 416.668711 -192.102432) (xy 416.661863 -192.148968)
			(xy 419.101268 -192.148968) (xy 419.105339 -192.093346) (xy 419.117465 -192.038909) (xy 419.137388 -191.986818)
			(xy 419.164684 -191.938183) (xy 419.19877 -191.89404) (xy 419.238919 -191.855331) (xy 419.284277 -191.82288)
			(xy 419.333877 -191.797379) (xy 419.386661 -191.779372) (xy 419.441504 -191.769242) (xy 419.497238 -191.767205)
			(xy 419.552675 -191.773305) (xy 419.606632 -191.787411) (xy 419.657961 -191.809223) (xy 419.705567 -191.838277)
			(xy 419.748435 -191.873952) (xy 419.785652 -191.915489) (xy 419.816425 -191.962002) (xy 419.840097 -192.012499)
			(xy 419.856165 -192.065906) (xy 419.864285 -192.121082) (xy 419.864794 -192.148968) (xy 419.864285 -192.176854)
			(xy 419.856165 -192.23203) (xy 419.840097 -192.285437) (xy 419.824294 -192.319148) (xy 422.956226 -192.319148)
			(xy 422.960297 -192.263526) (xy 422.972423 -192.209089) (xy 422.992346 -192.156998) (xy 423.019642 -192.108363)
			(xy 423.053728 -192.06422) (xy 423.093877 -192.025511) (xy 423.139235 -191.99306) (xy 423.188835 -191.967559)
			(xy 423.241619 -191.949552) (xy 423.296462 -191.939422) (xy 423.352196 -191.937385) (xy 423.407633 -191.943485)
			(xy 423.46159 -191.957591) (xy 423.512919 -191.979403) (xy 423.560525 -192.008457) (xy 423.603393 -192.044132)
			(xy 423.64061 -192.085669) (xy 423.671383 -192.132182) (xy 423.695055 -192.182679) (xy 423.711123 -192.236086)
			(xy 423.719243 -192.291262) (xy 423.719752 -192.319148) (xy 423.719243 -192.347034) (xy 423.711123 -192.40221)
			(xy 423.695055 -192.455617) (xy 423.671383 -192.506114) (xy 423.64061 -192.552627) (xy 423.603393 -192.594164)
			(xy 423.560525 -192.629839) (xy 423.512919 -192.658893) (xy 423.46159 -192.680705) (xy 423.407633 -192.694811)
			(xy 423.352196 -192.700911) (xy 423.296462 -192.698874) (xy 423.241619 -192.688744) (xy 423.188835 -192.670737)
			(xy 423.139235 -192.645236) (xy 423.093877 -192.612785) (xy 423.053728 -192.574076) (xy 423.019642 -192.529933)
			(xy 422.992346 -192.481298) (xy 422.972423 -192.429207) (xy 422.960297 -192.37477) (xy 422.956226 -192.319148)
			(xy 419.824294 -192.319148) (xy 419.816425 -192.335934) (xy 419.785652 -192.382447) (xy 419.748435 -192.423984)
			(xy 419.705567 -192.459659) (xy 419.657961 -192.488713) (xy 419.606632 -192.510525) (xy 419.552675 -192.524631)
			(xy 419.497238 -192.530731) (xy 419.441504 -192.528694) (xy 419.386661 -192.518564) (xy 419.333877 -192.500557)
			(xy 419.284277 -192.475056) (xy 419.238919 -192.442605) (xy 419.19877 -192.403896) (xy 419.164684 -192.359753)
			(xy 419.137388 -192.311118) (xy 419.117465 -192.259027) (xy 419.105339 -192.20459) (xy 419.101268 -192.148968)
			(xy 416.661863 -192.148968) (xy 416.660591 -192.157608) (xy 416.644523 -192.211015) (xy 416.620851 -192.261512)
			(xy 416.590078 -192.308025) (xy 416.552861 -192.349562) (xy 416.509993 -192.385237) (xy 416.462387 -192.414291)
			(xy 416.411058 -192.436103) (xy 416.357101 -192.450209) (xy 416.301664 -192.456309) (xy 416.24593 -192.454272)
			(xy 416.191087 -192.444142) (xy 416.138303 -192.426135) (xy 416.088703 -192.400634) (xy 416.043345 -192.368183)
			(xy 416.003196 -192.329474) (xy 415.96911 -192.285331) (xy 415.941814 -192.236696) (xy 415.921891 -192.184605)
			(xy 415.909765 -192.130168) (xy 415.905694 -192.074546) (xy 415.65322 -192.074546) (xy 415.652711 -192.102432)
			(xy 415.644591 -192.157608) (xy 415.628523 -192.211015) (xy 415.604851 -192.261512) (xy 415.574078 -192.308025)
			(xy 415.536861 -192.349562) (xy 415.493993 -192.385237) (xy 415.446387 -192.414291) (xy 415.395058 -192.436103)
			(xy 415.341101 -192.450209) (xy 415.285664 -192.456309) (xy 415.22993 -192.454272) (xy 415.175087 -192.444142)
			(xy 415.122303 -192.426135) (xy 415.072703 -192.400634) (xy 415.027345 -192.368183) (xy 414.987196 -192.329474)
			(xy 414.95311 -192.285331) (xy 414.925814 -192.236696) (xy 414.905891 -192.184605) (xy 414.893765 -192.130168)
			(xy 414.889694 -192.074546) (xy 414.63722 -192.074546) (xy 414.636711 -192.102432) (xy 414.628591 -192.157608)
			(xy 414.612523 -192.211015) (xy 414.588851 -192.261512) (xy 414.558078 -192.308025) (xy 414.520861 -192.349562)
			(xy 414.477993 -192.385237) (xy 414.430387 -192.414291) (xy 414.379058 -192.436103) (xy 414.325101 -192.450209)
			(xy 414.269664 -192.456309) (xy 414.21393 -192.454272) (xy 414.159087 -192.444142) (xy 414.106303 -192.426135)
			(xy 414.056703 -192.400634) (xy 414.011345 -192.368183) (xy 413.971196 -192.329474) (xy 413.93711 -192.285331)
			(xy 413.909814 -192.236696) (xy 413.889891 -192.184605) (xy 413.877765 -192.130168) (xy 413.873694 -192.074546)
			(xy 411.55366 -192.074546) (xy 411.553151 -192.102432) (xy 411.545031 -192.157608) (xy 411.528963 -192.211015)
			(xy 411.505291 -192.261512) (xy 411.474518 -192.308025) (xy 411.437301 -192.349562) (xy 411.394433 -192.385237)
			(xy 411.346827 -192.414291) (xy 411.295498 -192.436103) (xy 411.241541 -192.450209) (xy 411.186104 -192.456309)
			(xy 411.13037 -192.454272) (xy 411.075527 -192.444142) (xy 411.022743 -192.426135) (xy 410.973143 -192.400634)
			(xy 410.927785 -192.368183) (xy 410.887636 -192.329474) (xy 410.85355 -192.285331) (xy 410.826254 -192.236696)
			(xy 410.806331 -192.184605) (xy 410.794205 -192.130168) (xy 410.790134 -192.074546) (xy 410.53766 -192.074546)
			(xy 410.537151 -192.102432) (xy 410.529031 -192.157608) (xy 410.512963 -192.211015) (xy 410.489291 -192.261512)
			(xy 410.458518 -192.308025) (xy 410.421301 -192.349562) (xy 410.378433 -192.385237) (xy 410.330827 -192.414291)
			(xy 410.279498 -192.436103) (xy 410.225541 -192.450209) (xy 410.170104 -192.456309) (xy 410.11437 -192.454272)
			(xy 410.059527 -192.444142) (xy 410.006743 -192.426135) (xy 409.957143 -192.400634) (xy 409.911785 -192.368183)
			(xy 409.871636 -192.329474) (xy 409.83755 -192.285331) (xy 409.810254 -192.236696) (xy 409.790331 -192.184605)
			(xy 409.778205 -192.130168) (xy 409.774134 -192.074546) (xy 409.52166 -192.074546) (xy 409.521151 -192.102432)
			(xy 409.513031 -192.157608) (xy 409.496963 -192.211015) (xy 409.473291 -192.261512) (xy 409.442518 -192.308025)
			(xy 409.405301 -192.349562) (xy 409.362433 -192.385237) (xy 409.314827 -192.414291) (xy 409.263498 -192.436103)
			(xy 409.209541 -192.450209) (xy 409.154104 -192.456309) (xy 409.09837 -192.454272) (xy 409.043527 -192.444142)
			(xy 408.990743 -192.426135) (xy 408.941143 -192.400634) (xy 408.895785 -192.368183) (xy 408.855636 -192.329474)
			(xy 408.82155 -192.285331) (xy 408.794254 -192.236696) (xy 408.774331 -192.184605) (xy 408.762205 -192.130168)
			(xy 408.758134 -192.074546) (xy 408.50566 -192.074546) (xy 408.505151 -192.102432) (xy 408.497031 -192.157608)
			(xy 408.480963 -192.211015) (xy 408.457291 -192.261512) (xy 408.426518 -192.308025) (xy 408.389301 -192.349562)
			(xy 408.346433 -192.385237) (xy 408.298827 -192.414291) (xy 408.247498 -192.436103) (xy 408.193541 -192.450209)
			(xy 408.138104 -192.456309) (xy 408.08237 -192.454272) (xy 408.027527 -192.444142) (xy 407.974743 -192.426135)
			(xy 407.925143 -192.400634) (xy 407.879785 -192.368183) (xy 407.839636 -192.329474) (xy 407.80555 -192.285331)
			(xy 407.778254 -192.236696) (xy 407.758331 -192.184605) (xy 407.746205 -192.130168) (xy 407.742134 -192.074546)
			(xy 407.48966 -192.074546) (xy 407.489151 -192.102432) (xy 407.481031 -192.157608) (xy 407.464963 -192.211015)
			(xy 407.441291 -192.261512) (xy 407.410518 -192.308025) (xy 407.373301 -192.349562) (xy 407.330433 -192.385237)
			(xy 407.282827 -192.414291) (xy 407.231498 -192.436103) (xy 407.177541 -192.450209) (xy 407.122104 -192.456309)
			(xy 407.06637 -192.454272) (xy 407.011527 -192.444142) (xy 406.958743 -192.426135) (xy 406.909143 -192.400634)
			(xy 406.863785 -192.368183) (xy 406.823636 -192.329474) (xy 406.78955 -192.285331) (xy 406.762254 -192.236696)
			(xy 406.742331 -192.184605) (xy 406.730205 -192.130168) (xy 406.726134 -192.074546) (xy 404.459253 -192.074546)
			(xy 404.449221 -192.107891) (xy 404.425549 -192.158388) (xy 404.394776 -192.204901) (xy 404.357559 -192.246438)
			(xy 404.314691 -192.282113) (xy 404.267085 -192.311167) (xy 404.215756 -192.332979) (xy 404.161799 -192.347085)
			(xy 404.106362 -192.353185) (xy 404.050628 -192.351148) (xy 403.995785 -192.341018) (xy 403.943001 -192.323011)
			(xy 403.893401 -192.29751) (xy 403.848043 -192.265059) (xy 403.807894 -192.22635) (xy 403.773808 -192.182207)
			(xy 403.746512 -192.133572) (xy 403.726589 -192.081481) (xy 403.714463 -192.027044) (xy 403.710392 -191.971422)
			(xy 397.69796 -191.971422) (xy 397.69796 -193.218308) (xy 429.035462 -193.218308) (xy 429.039533 -193.162686)
			(xy 429.051659 -193.108249) (xy 429.071582 -193.056158) (xy 429.098878 -193.007523) (xy 429.132964 -192.96338)
			(xy 429.173113 -192.924671) (xy 429.218471 -192.89222) (xy 429.268071 -192.866719) (xy 429.320855 -192.848712)
			(xy 429.375698 -192.838582) (xy 429.431432 -192.836545) (xy 429.486869 -192.842645) (xy 429.540826 -192.856751)
			(xy 429.592155 -192.878563) (xy 429.639761 -192.907617) (xy 429.682629 -192.943292) (xy 429.719846 -192.984829)
			(xy 429.750619 -193.031342) (xy 429.774291 -193.081839) (xy 429.790359 -193.135246) (xy 429.798479 -193.190422)
			(xy 429.798988 -193.218308) (xy 429.798479 -193.246194) (xy 429.790359 -193.30137) (xy 429.774291 -193.354777)
			(xy 429.750619 -193.405274) (xy 429.719846 -193.451787) (xy 429.682629 -193.493324) (xy 429.639761 -193.528999)
			(xy 429.592155 -193.558053) (xy 429.540826 -193.579865) (xy 429.486869 -193.593971) (xy 429.431432 -193.600071)
			(xy 429.375698 -193.598034) (xy 429.320855 -193.587904) (xy 429.268071 -193.569897) (xy 429.218471 -193.544396)
			(xy 429.173113 -193.511945) (xy 429.132964 -193.473236) (xy 429.098878 -193.429093) (xy 429.071582 -193.380458)
			(xy 429.051659 -193.328367) (xy 429.039533 -193.27393) (xy 429.035462 -193.218308) (xy 397.69796 -193.218308)
			(xy 397.69796 -193.972688) (xy 398.0434 -194.318128) (xy 404.912068 -194.318128)
		)
		(stroke
			(width 0)
			(type solid)
		)
		(fill yes)
		(layer "F.Cu")
		(net "PVNN_MAIN_CPU0")
	)
	(gr_poly
		(pts
			(xy 39.257478 -333.92237) (xy 67.362578 -333.92237) (xy 67.818 -333.466948) (xy 67.818 -321.147948)
			(xy 66.997834 -320.327782) (xy 64.28613 -320.327782) (xy 64.278256 -320.330576) (xy 64.253169 -320.338612)
			(xy 64.201215 -320.347285) (xy 64.174878 -320.347848) (xy 63.816738 -320.347848) (xy 63.790401 -320.34729)
			(xy 63.738445 -320.338617) (xy 63.71336 -320.330576) (xy 63.705486 -320.327782) (xy 62.832996 -320.327782)
			(xy 61.977524 -321.183254) (xy 59.492134 -321.183254) (xy 58.627518 -320.318638) (xy 56.11495 -320.318638)
			(xy 56.10299 -320.342536) (xy 56.072991 -320.38676) (xy 56.03672 -320.426005) (xy 55.994994 -320.459391)
			(xy 55.948748 -320.486169) (xy 55.899021 -320.505737) (xy 55.846929 -320.517656) (xy 55.79364 -320.521659)
			(xy 55.740351 -320.517656) (xy 55.688259 -320.505737) (xy 55.638532 -320.486169) (xy 55.592286 -320.459391)
			(xy 55.55056 -320.426005) (xy 55.514289 -320.38676) (xy 55.48429 -320.342536) (xy 55.47233 -320.318638)
			(xy 55.385462 -320.318638) (xy 54.529736 -321.174364) (xy 51.87315 -321.174364) (xy 51.008534 -320.309748)
			(xy 47.62246 -320.309748) (xy 46.766988 -321.16522) (xy 44.326048 -321.16522) (xy 43.47972 -320.318892)
			(xy 40.174418 -320.318892) (xy 39.327836 -321.165474) (xy 36.977574 -321.165474) (xy 36.148772 -320.336672)
			(xy 32.573468 -320.336672) (xy 31.744666 -321.165474) (xy 29.106622 -321.165474) (xy 28.278074 -320.336926)
			(xy 24.792686 -320.336926) (xy 23.955248 -321.174364) (xy 21.685504 -321.174364) (xy 20.820888 -320.309748)
			(xy 17.59712 -320.309748) (xy 16.741648 -321.16522) (xy 13.94968 -321.16522) (xy 13.121132 -320.336672)
			(xy 10.059416 -320.336672) (xy 9.212834 -321.183254) (xy 5.06984 -321.183254) (xy 4.151376 -322.101718)
			(xy 4.151376 -322.900548) (xy 48.562768 -322.900548) (xy 48.563283 -322.873249) (xy 48.571616 -322.81929)
			(xy 48.588094 -322.767238) (xy 48.61233 -322.718314) (xy 48.643756 -322.673666) (xy 48.662336 -322.65366)
			(xy 48.672736 -322.6421) (xy 48.68654 -322.61425) (xy 48.691357 -322.583543) (xy 48.686745 -322.552804)
			(xy 48.673128 -322.524863) (xy 48.662844 -322.513198) (xy 48.644678 -322.493248) (xy 48.613962 -322.448891)
			(xy 48.590287 -322.400409) (xy 48.574197 -322.34891) (xy 48.566059 -322.295573) (xy 48.565562 -322.268596)
			(xy 48.56606 -322.241947) (xy 48.574003 -322.189243) (xy 48.589713 -322.138313) (xy 48.612839 -322.090292)
			(xy 48.642863 -322.046255) (xy 48.679115 -322.007184) (xy 48.720786 -321.973953) (xy 48.766944 -321.947304)
			(xy 48.816558 -321.927832) (xy 48.86852 -321.915972) (xy 48.92167 -321.911989) (xy 48.97482 -321.915972)
			(xy 49.026782 -321.927832) (xy 49.076396 -321.947304) (xy 49.122554 -321.973953) (xy 49.164225 -322.007184)
			(xy 49.200477 -322.046255) (xy 49.230501 -322.090292) (xy 49.253627 -322.138313) (xy 49.269337 -322.189243)
			(xy 49.27728 -322.241947) (xy 49.277778 -322.268596) (xy 49.277305 -322.295897) (xy 49.268964 -322.349858)
			(xy 49.252477 -322.401911) (xy 49.228231 -322.450835) (xy 49.196795 -322.49548) (xy 49.17821 -322.515484)
			(xy 49.167862 -322.527087) (xy 49.154046 -322.55492) (xy 49.149215 -322.585616) (xy 49.153815 -322.616347)
			(xy 49.167422 -322.644283) (xy 49.177702 -322.655946) (xy 49.195849 -322.675912) (xy 49.226566 -322.720266)
			(xy 49.250243 -322.768744) (xy 49.266338 -322.820239) (xy 49.274483 -322.873572) (xy 49.274984 -322.900548)
			(xy 49.274576 -322.922392) (xy 52.035964 -322.922392) (xy 52.036376 -322.897333) (xy 52.043387 -322.847707)
			(xy 52.057286 -322.799554) (xy 52.077796 -322.753824) (xy 52.104513 -322.71142) (xy 52.136909 -322.67318)
			(xy 52.155344 -322.6562) (xy 52.16539 -322.646655) (xy 52.180316 -322.623317) (xy 52.188429 -322.596829)
			(xy 52.189135 -322.569135) (xy 52.182382 -322.542268) (xy 52.168664 -322.518199) (xy 52.159154 -322.508118)
			(xy 52.139503 -322.487907) (xy 52.106178 -322.442445) (xy 52.080429 -322.392302) (xy 52.062898 -322.338729)
			(xy 52.054024 -322.283064) (xy 52.05349 -322.25488) (xy 52.053988 -322.228231) (xy 52.061931 -322.175527)
			(xy 52.077641 -322.124597) (xy 52.100767 -322.076576) (xy 52.130791 -322.032539) (xy 52.167043 -321.993468)
			(xy 52.208714 -321.960237) (xy 52.254872 -321.933588) (xy 52.304486 -321.914116) (xy 52.356448 -321.902256)
			(xy 52.409598 -321.898273) (xy 52.462748 -321.902256) (xy 52.51471 -321.914116) (xy 52.564324 -321.933588)
			(xy 52.610482 -321.960237) (xy 52.652153 -321.993468) (xy 52.688405 -322.032539) (xy 52.718429 -322.076576)
			(xy 52.741555 -322.124597) (xy 52.757265 -322.175527) (xy 52.765208 -322.228231) (xy 52.765706 -322.25488)
			(xy 52.765285 -322.279939) (xy 52.758277 -322.329565) (xy 52.744381 -322.377718) (xy 52.723873 -322.423448)
			(xy 52.697157 -322.465852) (xy 52.664761 -322.504093) (xy 52.646326 -322.521072) (xy 52.636309 -322.530644)
			(xy 52.621386 -322.553976) (xy 52.613272 -322.580456) (xy 52.612561 -322.608143) (xy 52.619306 -322.635005)
			(xy 52.633012 -322.659072) (xy 52.642516 -322.669154) (xy 52.662148 -322.689382) (xy 52.695477 -322.734839)
			(xy 52.72123 -322.784978) (xy 52.738765 -322.838547) (xy 52.747644 -322.894209) (xy 52.74818 -322.922392)
			(xy 52.747682 -322.949041) (xy 52.739739 -323.001745) (xy 52.724029 -323.052675) (xy 52.700903 -323.100696)
			(xy 52.670879 -323.144733) (xy 52.634627 -323.183804) (xy 52.592956 -323.217035) (xy 52.546798 -323.243684)
			(xy 52.497184 -323.263156) (xy 52.445222 -323.275016) (xy 52.392072 -323.279) (xy 52.338922 -323.275016)
			(xy 52.28696 -323.263156) (xy 52.237346 -323.243684) (xy 52.191188 -323.217035) (xy 52.149517 -323.183804)
			(xy 52.113265 -323.144733) (xy 52.083241 -323.100696) (xy 52.060115 -323.052675) (xy 52.044405 -323.001745)
			(xy 52.036462 -322.949041) (xy 52.035964 -322.922392) (xy 49.274576 -322.922392) (xy 49.274486 -322.927197)
			(xy 49.266543 -322.979901) (xy 49.250833 -323.030831) (xy 49.227707 -323.078852) (xy 49.197683 -323.122889)
			(xy 49.161431 -323.16196) (xy 49.11976 -323.195191) (xy 49.073602 -323.22184) (xy 49.023988 -323.241312)
			(xy 48.972026 -323.253172) (xy 48.918876 -323.257156) (xy 48.865726 -323.253172) (xy 48.813764 -323.241312)
			(xy 48.76415 -323.22184) (xy 48.717992 -323.195191) (xy 48.676321 -323.16196) (xy 48.640069 -323.122889)
			(xy 48.610045 -323.078852) (xy 48.586919 -323.030831) (xy 48.571209 -322.979901) (xy 48.563266 -322.927197)
			(xy 48.562768 -322.900548) (xy 4.151376 -322.900548) (xy 4.151376 -323.43446) (xy 7.452844 -323.43446)
			(xy 7.456827 -323.381306) (xy 7.468689 -323.329339) (xy 7.488163 -323.27972) (xy 7.514814 -323.233559)
			(xy 7.548049 -323.191885) (xy 7.587123 -323.155629) (xy 7.631164 -323.125603) (xy 7.679189 -323.102476)
			(xy 7.730124 -323.086765) (xy 7.782832 -323.078821) (xy 7.809484 -323.078348) (xy 7.835892 -323.078855)
			(xy 7.888128 -323.086653) (xy 7.93864 -323.10208) (xy 7.986319 -323.124798) (xy 8.030121 -323.15431)
			(xy 8.069083 -323.189966) (xy 8.08609 -323.210174) (xy 8.096027 -323.221567) (xy 8.12108 -323.238458)
			(xy 8.149976 -323.247289) (xy 8.180192 -323.247289) (xy 8.209088 -323.238458) (xy 8.234141 -323.221567)
			(xy 8.244078 -323.210174) (xy 8.261082 -323.189962) (xy 8.300044 -323.154302) (xy 8.343845 -323.124786)
			(xy 8.391525 -323.102064) (xy 8.442037 -323.086632) (xy 8.494275 -323.078829) (xy 8.520684 -323.078348)
			(xy 8.547333 -323.078854) (xy 8.600035 -323.086798) (xy 8.650965 -323.102508) (xy 8.698984 -323.125634)
			(xy 8.74302 -323.155658) (xy 8.78209 -323.191909) (xy 8.81532 -323.233579) (xy 8.841969 -323.279737)
			(xy 8.861441 -323.32935) (xy 8.873301 -323.381311) (xy 8.877284 -323.43446) (xy 11.516844 -323.43446)
			(xy 11.520827 -323.381306) (xy 11.532689 -323.329339) (xy 11.552163 -323.27972) (xy 11.578814 -323.233559)
			(xy 11.612049 -323.191885) (xy 11.651123 -323.155629) (xy 11.695164 -323.125603) (xy 11.743189 -323.102476)
			(xy 11.794124 -323.086765) (xy 11.846832 -323.078821) (xy 11.873484 -323.078348) (xy 11.899892 -323.078855)
			(xy 11.952128 -323.086653) (xy 12.00264 -323.10208) (xy 12.050319 -323.124798) (xy 12.094121 -323.15431)
			(xy 12.133083 -323.189966) (xy 12.15009 -323.210174) (xy 12.160027 -323.221567) (xy 12.18508 -323.238458)
			(xy 12.213976 -323.247289) (xy 12.244192 -323.247289) (xy 12.273088 -323.238458) (xy 12.298141 -323.221567)
			(xy 12.308078 -323.210174) (xy 12.325082 -323.189962) (xy 12.364044 -323.154302) (xy 12.407845 -323.124786)
			(xy 12.455525 -323.102064) (xy 12.506037 -323.086632) (xy 12.558275 -323.078829) (xy 12.584684 -323.078348)
			(xy 12.611333 -323.078854) (xy 12.664035 -323.086798) (xy 12.714965 -323.102508) (xy 12.762984 -323.125634)
			(xy 12.80702 -323.155658) (xy 12.84609 -323.191909) (xy 12.87932 -323.233579) (xy 12.905969 -323.279737)
			(xy 12.925441 -323.32935) (xy 12.937301 -323.381311) (xy 12.941284 -323.43446) (xy 14.996644 -323.43446)
			(xy 15.000627 -323.381306) (xy 15.012489 -323.329339) (xy 15.031963 -323.27972) (xy 15.058614 -323.233559)
			(xy 15.091849 -323.191885) (xy 15.130923 -323.155629) (xy 15.174964 -323.125603) (xy 15.222989 -323.102476)
			(xy 15.273924 -323.086765) (xy 15.326632 -323.078821) (xy 15.353284 -323.078348) (xy 15.379692 -323.078855)
			(xy 15.431928 -323.086653) (xy 15.48244 -323.10208) (xy 15.530119 -323.124798) (xy 15.573921 -323.15431)
			(xy 15.612883 -323.189966) (xy 15.62989 -323.210174) (xy 15.639827 -323.221567) (xy 15.66488 -323.238458)
			(xy 15.693776 -323.247289) (xy 15.723992 -323.247289) (xy 15.752888 -323.238458) (xy 15.777941 -323.221567)
			(xy 15.787878 -323.210174) (xy 15.804882 -323.189962) (xy 15.843844 -323.154302) (xy 15.887645 -323.124786)
			(xy 15.935325 -323.102064) (xy 15.985837 -323.086632) (xy 16.038075 -323.078829) (xy 16.064484 -323.078348)
			(xy 16.091133 -323.078854) (xy 16.143835 -323.086798) (xy 16.194765 -323.102508) (xy 16.242784 -323.125634)
			(xy 16.28682 -323.155658) (xy 16.32589 -323.191909) (xy 16.35912 -323.233579) (xy 16.385769 -323.279737)
			(xy 16.405241 -323.32935) (xy 16.417101 -323.381311) (xy 16.421084 -323.43446) (xy 19.060644 -323.43446)
			(xy 19.064627 -323.381306) (xy 19.076489 -323.329339) (xy 19.095963 -323.27972) (xy 19.122614 -323.233559)
			(xy 19.155849 -323.191885) (xy 19.194923 -323.155629) (xy 19.238964 -323.125603) (xy 19.286989 -323.102476)
			(xy 19.337924 -323.086765) (xy 19.390632 -323.078821) (xy 19.417284 -323.078348) (xy 19.443692 -323.078855)
			(xy 19.495928 -323.086653) (xy 19.54644 -323.10208) (xy 19.594119 -323.124798) (xy 19.637921 -323.15431)
			(xy 19.676883 -323.189966) (xy 19.69389 -323.210174) (xy 19.703827 -323.221567) (xy 19.72888 -323.238458)
			(xy 19.757776 -323.247289) (xy 19.787992 -323.247289) (xy 19.816888 -323.238458) (xy 19.841941 -323.221567)
			(xy 19.851878 -323.210174) (xy 19.868882 -323.189962) (xy 19.907844 -323.154302) (xy 19.951645 -323.124786)
			(xy 19.999325 -323.102064) (xy 20.049837 -323.086632) (xy 20.102075 -323.078829) (xy 20.128484 -323.078348)
			(xy 20.155133 -323.078854) (xy 20.207835 -323.086798) (xy 20.258765 -323.102508) (xy 20.306784 -323.125634)
			(xy 20.35082 -323.155658) (xy 20.38989 -323.191909) (xy 20.42312 -323.233579) (xy 20.449769 -323.279737)
			(xy 20.469241 -323.32935) (xy 20.481101 -323.381311) (xy 20.485084 -323.43446) (xy 20.485081 -323.4345)
			(xy 22.540448 -323.4345) (xy 22.544432 -323.381345) (xy 22.556293 -323.329378) (xy 22.575766 -323.279759)
			(xy 22.602417 -323.233596) (xy 22.635651 -323.191921) (xy 22.674724 -323.155664) (xy 22.718765 -323.125636)
			(xy 22.766789 -323.102507) (xy 22.817724 -323.086794) (xy 22.870432 -323.078847) (xy 22.897084 -323.078348)
			(xy 22.923492 -323.078855) (xy 22.975728 -323.086653) (xy 23.02624 -323.10208) (xy 23.073919 -323.124798)
			(xy 23.117721 -323.15431) (xy 23.156683 -323.189966) (xy 23.17369 -323.210174) (xy 23.183627 -323.221567)
			(xy 23.20868 -323.238458) (xy 23.237576 -323.247289) (xy 23.267792 -323.247289) (xy 23.296688 -323.238458)
			(xy 23.321741 -323.221567) (xy 23.331678 -323.210174) (xy 23.348682 -323.189962) (xy 23.387644 -323.154302)
			(xy 23.431445 -323.124786) (xy 23.479125 -323.102064) (xy 23.529637 -323.086632) (xy 23.581875 -323.078829)
			(xy 23.608284 -323.078348) (xy 23.634933 -323.078908) (xy 23.687635 -323.086849) (xy 23.738565 -323.102557)
			(xy 23.786585 -323.12568) (xy 23.830622 -323.155703) (xy 23.869692 -323.191953) (xy 23.902923 -323.233622)
			(xy 23.929573 -323.279778) (xy 23.949045 -323.329391) (xy 23.960905 -323.381352) (xy 23.964888 -323.4345)
			(xy 26.604448 -323.4345) (xy 26.608432 -323.381345) (xy 26.620293 -323.329378) (xy 26.639766 -323.279759)
			(xy 26.666417 -323.233596) (xy 26.699651 -323.191921) (xy 26.738724 -323.155664) (xy 26.782765 -323.125636)
			(xy 26.830789 -323.102507) (xy 26.881724 -323.086794) (xy 26.934432 -323.078847) (xy 26.961084 -323.078348)
			(xy 26.987492 -323.078855) (xy 27.039728 -323.086653) (xy 27.09024 -323.10208) (xy 27.137919 -323.124798)
			(xy 27.181721 -323.15431) (xy 27.220683 -323.189966) (xy 27.23769 -323.210174) (xy 27.247627 -323.221567)
			(xy 27.27268 -323.238458) (xy 27.301576 -323.247289) (xy 27.331792 -323.247289) (xy 27.360688 -323.238458)
			(xy 27.385741 -323.221567) (xy 27.395678 -323.210174) (xy 27.412682 -323.189962) (xy 27.451644 -323.154302)
			(xy 27.495445 -323.124786) (xy 27.543125 -323.102064) (xy 27.593637 -323.086632) (xy 27.645875 -323.078829)
			(xy 27.672284 -323.078348) (xy 27.698933 -323.078908) (xy 27.751635 -323.086849) (xy 27.802565 -323.102557)
			(xy 27.850585 -323.12568) (xy 27.894622 -323.155703) (xy 27.933692 -323.191953) (xy 27.966923 -323.233622)
			(xy 27.993573 -323.279778) (xy 28.013045 -323.329391) (xy 28.024905 -323.381352) (xy 28.028888 -323.4345)
			(xy 30.084248 -323.4345) (xy 30.088232 -323.381345) (xy 30.100093 -323.329378) (xy 30.119566 -323.279759)
			(xy 30.146217 -323.233596) (xy 30.179451 -323.191921) (xy 30.218524 -323.155664) (xy 30.262565 -323.125636)
			(xy 30.310589 -323.102507) (xy 30.361524 -323.086794) (xy 30.414232 -323.078847) (xy 30.440884 -323.078348)
			(xy 30.467292 -323.078855) (xy 30.519528 -323.086653) (xy 30.57004 -323.10208) (xy 30.617719 -323.124798)
			(xy 30.661521 -323.15431) (xy 30.700483 -323.189966) (xy 30.71749 -323.210174) (xy 30.727427 -323.221567)
			(xy 30.75248 -323.238458) (xy 30.781376 -323.247289) (xy 30.811592 -323.247289) (xy 30.840488 -323.238458)
			(xy 30.865541 -323.221567) (xy 30.875478 -323.210174) (xy 30.892482 -323.189962) (xy 30.931444 -323.154302)
			(xy 30.975245 -323.124786) (xy 31.022925 -323.102064) (xy 31.073437 -323.086632) (xy 31.125675 -323.078829)
			(xy 31.152084 -323.078348) (xy 31.178733 -323.078908) (xy 31.231435 -323.086849) (xy 31.282365 -323.102557)
			(xy 31.330385 -323.12568) (xy 31.374422 -323.155703) (xy 31.413492 -323.191953) (xy 31.446723 -323.233622)
			(xy 31.473373 -323.279778) (xy 31.492845 -323.329391) (xy 31.504705 -323.381352) (xy 31.508688 -323.4345)
			(xy 34.148248 -323.4345) (xy 34.152232 -323.381345) (xy 34.164093 -323.329378) (xy 34.183566 -323.279759)
			(xy 34.210217 -323.233596) (xy 34.243451 -323.191921) (xy 34.282524 -323.155664) (xy 34.326565 -323.125636)
			(xy 34.374589 -323.102507) (xy 34.425524 -323.086794) (xy 34.478232 -323.078847) (xy 34.504884 -323.078348)
			(xy 34.531292 -323.078855) (xy 34.583528 -323.086653) (xy 34.63404 -323.10208) (xy 34.681719 -323.124798)
			(xy 34.725521 -323.15431) (xy 34.764483 -323.189966) (xy 34.78149 -323.210174) (xy 34.791427 -323.221567)
			(xy 34.81648 -323.238458) (xy 34.845376 -323.247289) (xy 34.875592 -323.247289) (xy 34.904488 -323.238458)
			(xy 34.929541 -323.221567) (xy 34.939478 -323.210174) (xy 34.956482 -323.189962) (xy 34.995444 -323.154302)
			(xy 35.039245 -323.124786) (xy 35.086925 -323.102064) (xy 35.137437 -323.086632) (xy 35.189675 -323.078829)
			(xy 35.216084 -323.078348) (xy 35.242733 -323.078908) (xy 35.295435 -323.086849) (xy 35.346365 -323.102557)
			(xy 35.394385 -323.12568) (xy 35.438422 -323.155703) (xy 35.477492 -323.191953) (xy 35.510723 -323.233622)
			(xy 35.537373 -323.279778) (xy 35.556845 -323.329391) (xy 35.568705 -323.381352) (xy 35.572688 -323.4345)
			(xy 37.628048 -323.4345) (xy 37.632032 -323.381345) (xy 37.643893 -323.329378) (xy 37.663366 -323.279759)
			(xy 37.690017 -323.233596) (xy 37.723251 -323.191921) (xy 37.762324 -323.155664) (xy 37.806365 -323.125636)
			(xy 37.854389 -323.102507) (xy 37.905324 -323.086794) (xy 37.958032 -323.078847) (xy 37.984684 -323.078348)
			(xy 38.011092 -323.078855) (xy 38.063328 -323.086653) (xy 38.11384 -323.10208) (xy 38.161519 -323.124798)
			(xy 38.205321 -323.15431) (xy 38.244283 -323.189966) (xy 38.26129 -323.210174) (xy 38.271227 -323.221567)
			(xy 38.29628 -323.238458) (xy 38.325176 -323.247289) (xy 38.355392 -323.247289) (xy 38.384288 -323.238458)
			(xy 38.409341 -323.221567) (xy 38.419278 -323.210174) (xy 38.436282 -323.189962) (xy 38.475244 -323.154302)
			(xy 38.519045 -323.124786) (xy 38.566725 -323.102064) (xy 38.617237 -323.086632) (xy 38.669475 -323.078829)
			(xy 38.695884 -323.078348) (xy 38.722533 -323.078908) (xy 38.775235 -323.086849) (xy 38.826165 -323.102557)
			(xy 38.874185 -323.12568) (xy 38.918222 -323.155703) (xy 38.957292 -323.191953) (xy 38.990523 -323.233622)
			(xy 39.017173 -323.279778) (xy 39.036645 -323.329391) (xy 39.048505 -323.381352) (xy 39.052488 -323.4345)
			(xy 41.692048 -323.4345) (xy 41.696032 -323.381345) (xy 41.707893 -323.329378) (xy 41.727366 -323.279759)
			(xy 41.754017 -323.233596) (xy 41.787251 -323.191921) (xy 41.826324 -323.155664) (xy 41.870365 -323.125636)
			(xy 41.918389 -323.102507) (xy 41.969324 -323.086794) (xy 42.022032 -323.078847) (xy 42.048684 -323.078348)
			(xy 42.075092 -323.078855) (xy 42.127328 -323.086653) (xy 42.17784 -323.10208) (xy 42.225519 -323.124798)
			(xy 42.269321 -323.15431) (xy 42.308283 -323.189966) (xy 42.32529 -323.210174) (xy 42.335227 -323.221567)
			(xy 42.36028 -323.238458) (xy 42.389176 -323.247289) (xy 42.419392 -323.247289) (xy 42.448288 -323.238458)
			(xy 42.473341 -323.221567) (xy 42.483278 -323.210174) (xy 42.500282 -323.189962) (xy 42.539244 -323.154302)
			(xy 42.583045 -323.124786) (xy 42.630725 -323.102064) (xy 42.681237 -323.086632) (xy 42.733475 -323.078829)
			(xy 42.759884 -323.078348) (xy 42.786533 -323.078908) (xy 42.839235 -323.086849) (xy 42.890165 -323.102557)
			(xy 42.938185 -323.12568) (xy 42.982222 -323.155703) (xy 43.021292 -323.191953) (xy 43.054523 -323.233622)
			(xy 43.081173 -323.279778) (xy 43.100645 -323.329391) (xy 43.112505 -323.381352) (xy 43.116488 -323.4345)
			(xy 45.171848 -323.4345) (xy 45.175832 -323.381345) (xy 45.187693 -323.329378) (xy 45.207166 -323.279759)
			(xy 45.233817 -323.233596) (xy 45.267051 -323.191921) (xy 45.306124 -323.155664) (xy 45.350165 -323.125636)
			(xy 45.398189 -323.102507) (xy 45.449124 -323.086794) (xy 45.501832 -323.078847) (xy 45.528484 -323.078348)
			(xy 45.554892 -323.078855) (xy 45.607128 -323.086653) (xy 45.65764 -323.10208) (xy 45.705319 -323.124798)
			(xy 45.749121 -323.15431) (xy 45.788083 -323.189966) (xy 45.80509 -323.210174) (xy 45.815027 -323.221567)
			(xy 45.84008 -323.238458) (xy 45.868976 -323.247289) (xy 45.899192 -323.247289) (xy 45.928088 -323.238458)
			(xy 45.953141 -323.221567) (xy 45.963078 -323.210174) (xy 45.980082 -323.189962) (xy 46.019044 -323.154302)
			(xy 46.062845 -323.124786) (xy 46.110525 -323.102064) (xy 46.161037 -323.086632) (xy 46.213275 -323.078829)
			(xy 46.239684 -323.078348) (xy 46.266333 -323.078908) (xy 46.319035 -323.086849) (xy 46.369965 -323.102557)
			(xy 46.417985 -323.12568) (xy 46.462022 -323.155703) (xy 46.501092 -323.191953) (xy 46.534323 -323.233622)
			(xy 46.560973 -323.279778) (xy 46.580445 -323.329391) (xy 46.592305 -323.381352) (xy 46.596288 -323.4345)
			(xy 46.593036 -323.4779) (xy 56.790082 -323.4779) (xy 56.794066 -323.424749) (xy 56.805926 -323.372786)
			(xy 56.825398 -323.32317) (xy 56.852048 -323.277011) (xy 56.88528 -323.235339) (xy 56.924352 -323.199086)
			(xy 56.96839 -323.169061) (xy 57.016412 -323.145935) (xy 57.067343 -323.130224) (xy 57.120048 -323.12228)
			(xy 57.146698 -323.121782) (xy 57.175654 -323.122352) (xy 57.232804 -323.131723) (xy 57.287684 -323.150217)
			(xy 57.338848 -323.177347) (xy 57.384948 -323.212399) (xy 57.40527 -323.233034) (xy 57.415877 -323.243399)
			(xy 57.441581 -323.258153) (xy 57.47044 -323.264901) (xy 57.500022 -323.263072) (xy 57.52783 -323.252821)
			(xy 57.551521 -323.235013) (xy 57.560718 -323.223382) (xy 57.577591 -323.201282) (xy 57.617105 -323.162164)
			(xy 57.66222 -323.129665) (xy 57.711839 -323.104577) (xy 57.764756 -323.087509) (xy 57.819683 -323.078877)
			(xy 57.847484 -323.078348) (xy 57.874133 -323.078908) (xy 57.926835 -323.086849) (xy 57.977765 -323.102557)
			(xy 58.025785 -323.12568) (xy 58.069822 -323.155703) (xy 58.108892 -323.191953) (xy 58.142123 -323.233622)
			(xy 58.168773 -323.279778) (xy 58.188245 -323.329391) (xy 58.200105 -323.381352) (xy 58.204088 -323.4345)
			(xy 58.200105 -323.487648) (xy 58.188245 -323.539609) (xy 58.168773 -323.589222) (xy 58.142123 -323.635378)
			(xy 58.108892 -323.677047) (xy 58.099566 -323.6857) (xy 60.34193 -323.6857) (xy 60.345914 -323.632538)
			(xy 60.357778 -323.580563) (xy 60.377256 -323.530938) (xy 60.403913 -323.48477) (xy 60.437153 -323.443091)
			(xy 60.476235 -323.406832) (xy 60.520285 -323.376803) (xy 60.568318 -323.353676) (xy 60.619262 -323.337966)
			(xy 60.671978 -323.330025) (xy 60.698634 -323.329554) (xy 60.712794 -323.329712) (xy 60.741022 -323.331999)
			(xy 60.755022 -323.334126) (xy 60.769269 -323.335892) (xy 60.797749 -323.332394) (xy 60.824128 -323.321104)
			(xy 60.84632 -323.302915) (xy 60.862568 -323.279265) (xy 60.867544 -323.2658) (xy 60.87682 -323.239567)
			(xy 60.902388 -323.19015) (xy 60.935334 -323.145313) (xy 60.974854 -323.106147) (xy 61.019986 -323.073607)
			(xy 61.069631 -323.048485) (xy 61.12258 -323.031392) (xy 61.177544 -323.022746) (xy 61.205364 -323.022214)
			(xy 61.232019 -323.022641) (xy 61.284733 -323.030581) (xy 61.335675 -323.04629) (xy 61.383706 -323.069417)
			(xy 61.427754 -323.099444) (xy 61.466834 -323.135701) (xy 61.500074 -323.177378) (xy 61.52673 -323.223544)
			(xy 61.546207 -323.273168) (xy 61.55807 -323.32514) (xy 61.562054 -323.3783) (xy 61.55807 -323.43146)
			(xy 61.546207 -323.483432) (xy 61.52673 -323.533056) (xy 61.500074 -323.579222) (xy 61.478557 -323.6062)
			(xy 64.387128 -323.6062) (xy 64.391112 -323.553037) (xy 64.402976 -323.501062) (xy 64.422454 -323.451436)
			(xy 64.449112 -323.405268) (xy 64.482353 -323.363588) (xy 64.521436 -323.327329) (xy 64.565486 -323.2973)
			(xy 64.61352 -323.274173) (xy 64.664465 -323.258463) (xy 64.717182 -323.250523) (xy 64.743838 -323.250052)
			(xy 64.767559 -323.250402) (xy 64.814582 -323.256679) (xy 64.860353 -323.269157) (xy 64.904056 -323.287614)
			(xy 64.924686 -323.299328) (xy 64.937301 -323.306122) (xy 64.965061 -323.313163) (xy 64.993685 -323.312238)
			(xy 65.020932 -323.303419) (xy 65.04467 -323.287398) (xy 65.054226 -323.276722) (xy 65.071218 -323.256992)
			(xy 65.110021 -323.222269) (xy 65.153462 -323.193561) (xy 65.200619 -323.17148) (xy 65.250486 -323.156494)
			(xy 65.302003 -323.148924) (xy 65.328038 -323.148452) (xy 65.354682 -323.149033) (xy 65.407375 -323.15698)
			(xy 65.458296 -323.172692) (xy 65.506305 -323.195817) (xy 65.550333 -323.225838) (xy 65.589394 -323.262086)
			(xy 65.622618 -323.303751) (xy 65.64926 -323.349901) (xy 65.668728 -323.399507) (xy 65.680585 -323.45146)
			(xy 65.684567 -323.5046) (xy 65.680585 -323.55774) (xy 65.668728 -323.609693) (xy 65.64926 -323.659299)
			(xy 65.622618 -323.705449) (xy 65.589394 -323.747114) (xy 65.550333 -323.783362) (xy 65.506305 -323.813383)
			(xy 65.458296 -323.836508) (xy 65.407375 -323.85222) (xy 65.354682 -323.860167) (xy 65.328038 -323.860668)
			(xy 65.304319 -323.860282) (xy 65.257296 -323.854015) (xy 65.211526 -323.841548) (xy 65.167821 -323.823101)
			(xy 65.14719 -323.811392) (xy 65.134589 -323.804568) (xy 65.106823 -323.79753) (xy 65.078193 -323.79846)
			(xy 65.050943 -323.807286) (xy 65.027204 -323.823318) (xy 65.01765 -323.833998) (xy 65.000599 -323.853675)
			(xy 64.961811 -323.888405) (xy 64.918382 -323.917122) (xy 64.871237 -323.939213) (xy 64.821379 -323.954209)
			(xy 64.76987 -323.961791) (xy 64.743838 -323.962268) (xy 64.717182 -323.961877) (xy 64.664465 -323.953937)
			(xy 64.61352 -323.938227) (xy 64.565486 -323.9151) (xy 64.521436 -323.885071) (xy 64.482353 -323.848812)
			(xy 64.449112 -323.807132) (xy 64.422454 -323.760964) (xy 64.402976 -323.711338) (xy 64.391112 -323.659363)
			(xy 64.387128 -323.6062) (xy 61.478557 -323.6062) (xy 61.466834 -323.620899) (xy 61.427754 -323.657156)
			(xy 61.383706 -323.687183) (xy 61.335675 -323.71031) (xy 61.284733 -323.726019) (xy 61.232019 -323.733959)
			(xy 61.205364 -323.73443) (xy 61.191204 -323.734272) (xy 61.162976 -323.731985) (xy 61.148976 -323.729858)
			(xy 61.134728 -323.728101) (xy 61.10625 -323.731599) (xy 61.079873 -323.742887) (xy 61.057681 -323.761074)
			(xy 61.041432 -323.784721) (xy 61.036454 -323.798184) (xy 61.027171 -323.824414) (xy 61.001604 -323.873832)
			(xy 60.96866 -323.91867) (xy 60.929142 -323.957836) (xy 60.88401 -323.990377) (xy 60.834366 -324.015499)
			(xy 60.781417 -324.032592) (xy 60.726454 -324.041239) (xy 60.698634 -324.04177) (xy 60.671978 -324.041375)
			(xy 60.619262 -324.033434) (xy 60.568318 -324.017724) (xy 60.520285 -323.994597) (xy 60.476235 -323.964568)
			(xy 60.437153 -323.928309) (xy 60.403913 -323.88663) (xy 60.377256 -323.840462) (xy 60.357778 -323.790837)
			(xy 60.345914 -323.738862) (xy 60.34193 -323.6857) (xy 58.099566 -323.6857) (xy 58.069822 -323.713297)
			(xy 58.025785 -323.74332) (xy 57.977765 -323.766443) (xy 57.926835 -323.782151) (xy 57.874133 -323.790092)
			(xy 57.847484 -323.790564) (xy 57.818526 -323.790022) (xy 57.761375 -323.780647) (xy 57.706494 -323.762147)
			(xy 57.65533 -323.73501) (xy 57.609232 -323.699951) (xy 57.588912 -323.679312) (xy 57.578327 -323.668921)
			(xy 57.552618 -323.65416) (xy 57.523751 -323.647411) (xy 57.494162 -323.649244) (xy 57.466349 -323.659505)
			(xy 57.442658 -323.677326) (xy 57.433464 -323.688964) (xy 57.416527 -323.711014) (xy 57.377029 -323.750137)
			(xy 57.331928 -323.782643) (xy 57.28232 -323.80774) (xy 57.229414 -323.824819) (xy 57.174495 -323.833463)
			(xy 57.146698 -323.833998) (xy 57.120048 -323.83352) (xy 57.067343 -323.825576) (xy 57.016412 -323.809865)
			(xy 56.96839 -323.786739) (xy 56.924352 -323.756714) (xy 56.88528 -323.720461) (xy 56.852048 -323.678789)
			(xy 56.825398 -323.63263) (xy 56.805926 -323.583014) (xy 56.794066 -323.531051) (xy 56.790082 -323.4779)
			(xy 46.593036 -323.4779) (xy 46.592305 -323.487648) (xy 46.580445 -323.539609) (xy 46.560973 -323.589222)
			(xy 46.534323 -323.635378) (xy 46.501092 -323.677047) (xy 46.462022 -323.713297) (xy 46.417985 -323.74332)
			(xy 46.369965 -323.766443) (xy 46.319035 -323.782151) (xy 46.266333 -323.790092) (xy 46.239684 -323.790564)
			(xy 46.213274 -323.790112) (xy 46.161034 -323.782307) (xy 46.110519 -323.766871) (xy 46.062839 -323.744143)
			(xy 46.01904 -323.71462) (xy 45.980082 -323.678952) (xy 45.963078 -323.658738) (xy 45.953141 -323.647345)
			(xy 45.928088 -323.630454) (xy 45.899192 -323.621623) (xy 45.868976 -323.621623) (xy 45.84008 -323.630454)
			(xy 45.815027 -323.647345) (xy 45.80509 -323.658738) (xy 45.788106 -323.678968) (xy 45.74914 -323.714626)
			(xy 45.705335 -323.744139) (xy 45.657651 -323.766859) (xy 45.607135 -323.782287) (xy 45.554894 -323.790086)
			(xy 45.528484 -323.790564) (xy 45.501832 -323.790153) (xy 45.449124 -323.782206) (xy 45.398189 -323.766493)
			(xy 45.350165 -323.743364) (xy 45.306124 -323.713336) (xy 45.267051 -323.677079) (xy 45.233817 -323.635404)
			(xy 45.207166 -323.589241) (xy 45.187693 -323.539622) (xy 45.175832 -323.487655) (xy 45.171848 -323.4345)
			(xy 43.116488 -323.4345) (xy 43.112505 -323.487648) (xy 43.100645 -323.539609) (xy 43.081173 -323.589222)
			(xy 43.054523 -323.635378) (xy 43.021292 -323.677047) (xy 42.982222 -323.713297) (xy 42.938185 -323.74332)
			(xy 42.890165 -323.766443) (xy 42.839235 -323.782151) (xy 42.786533 -323.790092) (xy 42.759884 -323.790564)
			(xy 42.733474 -323.790112) (xy 42.681234 -323.782307) (xy 42.630719 -323.766871) (xy 42.583039 -323.744143)
			(xy 42.53924 -323.71462) (xy 42.500282 -323.678952) (xy 42.483278 -323.658738) (xy 42.473341 -323.647345)
			(xy 42.448288 -323.630454) (xy 42.419392 -323.621623) (xy 42.389176 -323.621623) (xy 42.36028 -323.630454)
			(xy 42.335227 -323.647345) (xy 42.32529 -323.658738) (xy 42.308306 -323.678968) (xy 42.26934 -323.714626)
			(xy 42.225535 -323.744139) (xy 42.177851 -323.766859) (xy 42.127335 -323.782287) (xy 42.075094 -323.790086)
			(xy 42.048684 -323.790564) (xy 42.022032 -323.790153) (xy 41.969324 -323.782206) (xy 41.918389 -323.766493)
			(xy 41.870365 -323.743364) (xy 41.826324 -323.713336) (xy 41.787251 -323.677079) (xy 41.754017 -323.635404)
			(xy 41.727366 -323.589241) (xy 41.707893 -323.539622) (xy 41.696032 -323.487655) (xy 41.692048 -323.4345)
			(xy 39.052488 -323.4345) (xy 39.048505 -323.487648) (xy 39.036645 -323.539609) (xy 39.017173 -323.589222)
			(xy 38.990523 -323.635378) (xy 38.957292 -323.677047) (xy 38.918222 -323.713297) (xy 38.874185 -323.74332)
			(xy 38.826165 -323.766443) (xy 38.775235 -323.782151) (xy 38.722533 -323.790092) (xy 38.695884 -323.790564)
			(xy 38.669474 -323.790112) (xy 38.617234 -323.782307) (xy 38.566719 -323.766871) (xy 38.519039 -323.744143)
			(xy 38.47524 -323.71462) (xy 38.436282 -323.678952) (xy 38.419278 -323.658738) (xy 38.409341 -323.647345)
			(xy 38.384288 -323.630454) (xy 38.355392 -323.621623) (xy 38.325176 -323.621623) (xy 38.29628 -323.630454)
			(xy 38.271227 -323.647345) (xy 38.26129 -323.658738) (xy 38.244306 -323.678968) (xy 38.20534 -323.714626)
			(xy 38.161535 -323.744139) (xy 38.113851 -323.766859) (xy 38.063335 -323.782287) (xy 38.011094 -323.790086)
			(xy 37.984684 -323.790564) (xy 37.958032 -323.790153) (xy 37.905324 -323.782206) (xy 37.854389 -323.766493)
			(xy 37.806365 -323.743364) (xy 37.762324 -323.713336) (xy 37.723251 -323.677079) (xy 37.690017 -323.635404)
			(xy 37.663366 -323.589241) (xy 37.643893 -323.539622) (xy 37.632032 -323.487655) (xy 37.628048 -323.4345)
			(xy 35.572688 -323.4345) (xy 35.568705 -323.487648) (xy 35.556845 -323.539609) (xy 35.537373 -323.589222)
			(xy 35.510723 -323.635378) (xy 35.477492 -323.677047) (xy 35.438422 -323.713297) (xy 35.394385 -323.74332)
			(xy 35.346365 -323.766443) (xy 35.295435 -323.782151) (xy 35.242733 -323.790092) (xy 35.216084 -323.790564)
			(xy 35.189674 -323.790112) (xy 35.137434 -323.782307) (xy 35.086919 -323.766871) (xy 35.039239 -323.744143)
			(xy 34.99544 -323.71462) (xy 34.956482 -323.678952) (xy 34.939478 -323.658738) (xy 34.929541 -323.647345)
			(xy 34.904488 -323.630454) (xy 34.875592 -323.621623) (xy 34.845376 -323.621623) (xy 34.81648 -323.630454)
			(xy 34.791427 -323.647345) (xy 34.78149 -323.658738) (xy 34.764506 -323.678968) (xy 34.72554 -323.714626)
			(xy 34.681735 -323.744139) (xy 34.634051 -323.766859) (xy 34.583535 -323.782287) (xy 34.531294 -323.790086)
			(xy 34.504884 -323.790564) (xy 34.478232 -323.790153) (xy 34.425524 -323.782206) (xy 34.374589 -323.766493)
			(xy 34.326565 -323.743364) (xy 34.282524 -323.713336) (xy 34.243451 -323.677079) (xy 34.210217 -323.635404)
			(xy 34.183566 -323.589241) (xy 34.164093 -323.539622) (xy 34.152232 -323.487655) (xy 34.148248 -323.4345)
			(xy 31.508688 -323.4345) (xy 31.504705 -323.487648) (xy 31.492845 -323.539609) (xy 31.473373 -323.589222)
			(xy 31.446723 -323.635378) (xy 31.413492 -323.677047) (xy 31.374422 -323.713297) (xy 31.330385 -323.74332)
			(xy 31.282365 -323.766443) (xy 31.231435 -323.782151) (xy 31.178733 -323.790092) (xy 31.152084 -323.790564)
			(xy 31.125674 -323.790112) (xy 31.073434 -323.782307) (xy 31.022919 -323.766871) (xy 30.975239 -323.744143)
			(xy 30.93144 -323.71462) (xy 30.892482 -323.678952) (xy 30.875478 -323.658738) (xy 30.865541 -323.647345)
			(xy 30.840488 -323.630454) (xy 30.811592 -323.621623) (xy 30.781376 -323.621623) (xy 30.75248 -323.630454)
			(xy 30.727427 -323.647345) (xy 30.71749 -323.658738) (xy 30.700506 -323.678968) (xy 30.66154 -323.714626)
			(xy 30.617735 -323.744139) (xy 30.570051 -323.766859) (xy 30.519535 -323.782287) (xy 30.467294 -323.790086)
			(xy 30.440884 -323.790564) (xy 30.414232 -323.790153) (xy 30.361524 -323.782206) (xy 30.310589 -323.766493)
			(xy 30.262565 -323.743364) (xy 30.218524 -323.713336) (xy 30.179451 -323.677079) (xy 30.146217 -323.635404)
			(xy 30.119566 -323.589241) (xy 30.100093 -323.539622) (xy 30.088232 -323.487655) (xy 30.084248 -323.4345)
			(xy 28.028888 -323.4345) (xy 28.024905 -323.487648) (xy 28.013045 -323.539609) (xy 27.993573 -323.589222)
			(xy 27.966923 -323.635378) (xy 27.933692 -323.677047) (xy 27.894622 -323.713297) (xy 27.850585 -323.74332)
			(xy 27.802565 -323.766443) (xy 27.751635 -323.782151) (xy 27.698933 -323.790092) (xy 27.672284 -323.790564)
			(xy 27.645874 -323.790112) (xy 27.593634 -323.782307) (xy 27.543119 -323.766871) (xy 27.495439 -323.744143)
			(xy 27.45164 -323.71462) (xy 27.412682 -323.678952) (xy 27.395678 -323.658738) (xy 27.385741 -323.647345)
			(xy 27.360688 -323.630454) (xy 27.331792 -323.621623) (xy 27.301576 -323.621623) (xy 27.27268 -323.630454)
			(xy 27.247627 -323.647345) (xy 27.23769 -323.658738) (xy 27.220706 -323.678968) (xy 27.18174 -323.714626)
			(xy 27.137935 -323.744139) (xy 27.090251 -323.766859) (xy 27.039735 -323.782287) (xy 26.987494 -323.790086)
			(xy 26.961084 -323.790564) (xy 26.934432 -323.790153) (xy 26.881724 -323.782206) (xy 26.830789 -323.766493)
			(xy 26.782765 -323.743364) (xy 26.738724 -323.713336) (xy 26.699651 -323.677079) (xy 26.666417 -323.635404)
			(xy 26.639766 -323.589241) (xy 26.620293 -323.539622) (xy 26.608432 -323.487655) (xy 26.604448 -323.4345)
			(xy 23.964888 -323.4345) (xy 23.960905 -323.487648) (xy 23.949045 -323.539609) (xy 23.929573 -323.589222)
			(xy 23.902923 -323.635378) (xy 23.869692 -323.677047) (xy 23.830622 -323.713297) (xy 23.786585 -323.74332)
			(xy 23.738565 -323.766443) (xy 23.687635 -323.782151) (xy 23.634933 -323.790092) (xy 23.608284 -323.790564)
			(xy 23.581874 -323.790112) (xy 23.529634 -323.782307) (xy 23.479119 -323.766871) (xy 23.431439 -323.744143)
			(xy 23.38764 -323.71462) (xy 23.348682 -323.678952) (xy 23.331678 -323.658738) (xy 23.321741 -323.647345)
			(xy 23.296688 -323.630454) (xy 23.267792 -323.621623) (xy 23.237576 -323.621623) (xy 23.20868 -323.630454)
			(xy 23.183627 -323.647345) (xy 23.17369 -323.658738) (xy 23.156706 -323.678968) (xy 23.11774 -323.714626)
			(xy 23.073935 -323.744139) (xy 23.026251 -323.766859) (xy 22.975735 -323.782287) (xy 22.923494 -323.790086)
			(xy 22.897084 -323.790564) (xy 22.870432 -323.790153) (xy 22.817724 -323.782206) (xy 22.766789 -323.766493)
			(xy 22.718765 -323.743364) (xy 22.674724 -323.713336) (xy 22.635651 -323.677079) (xy 22.602417 -323.635404)
			(xy 22.575766 -323.589241) (xy 22.556293 -323.539622) (xy 22.544432 -323.487655) (xy 22.540448 -323.4345)
			(xy 20.485081 -323.4345) (xy 20.481101 -323.487609) (xy 20.469241 -323.53957) (xy 20.449769 -323.589183)
			(xy 20.42312 -323.635341) (xy 20.38989 -323.677011) (xy 20.35082 -323.713262) (xy 20.306784 -323.743286)
			(xy 20.258765 -323.766412) (xy 20.207835 -323.782122) (xy 20.155133 -323.790066) (xy 20.128484 -323.790564)
			(xy 20.102074 -323.790112) (xy 20.049834 -323.782307) (xy 19.999319 -323.766871) (xy 19.951639 -323.744143)
			(xy 19.90784 -323.71462) (xy 19.868882 -323.678952) (xy 19.851878 -323.658738) (xy 19.841941 -323.647345)
			(xy 19.816888 -323.630454) (xy 19.787992 -323.621623) (xy 19.757776 -323.621623) (xy 19.72888 -323.630454)
			(xy 19.703827 -323.647345) (xy 19.69389 -323.658738) (xy 19.676906 -323.678968) (xy 19.63794 -323.714626)
			(xy 19.594135 -323.744139) (xy 19.546451 -323.766859) (xy 19.495935 -323.782287) (xy 19.443694 -323.790086)
			(xy 19.417284 -323.790564) (xy 19.390632 -323.790099) (xy 19.337924 -323.782155) (xy 19.286989 -323.766444)
			(xy 19.238964 -323.743317) (xy 19.194923 -323.713291) (xy 19.155849 -323.677035) (xy 19.122614 -323.635361)
			(xy 19.095963 -323.5892) (xy 19.076489 -323.539581) (xy 19.064627 -323.487614) (xy 19.060644 -323.43446)
			(xy 16.421084 -323.43446) (xy 16.417101 -323.487609) (xy 16.405241 -323.53957) (xy 16.385769 -323.589183)
			(xy 16.35912 -323.635341) (xy 16.32589 -323.677011) (xy 16.28682 -323.713262) (xy 16.242784 -323.743286)
			(xy 16.194765 -323.766412) (xy 16.143835 -323.782122) (xy 16.091133 -323.790066) (xy 16.064484 -323.790564)
			(xy 16.038074 -323.790112) (xy 15.985834 -323.782307) (xy 15.935319 -323.766871) (xy 15.887639 -323.744143)
			(xy 15.84384 -323.71462) (xy 15.804882 -323.678952) (xy 15.787878 -323.658738) (xy 15.777941 -323.647345)
			(xy 15.752888 -323.630454) (xy 15.723992 -323.621623) (xy 15.693776 -323.621623) (xy 15.66488 -323.630454)
			(xy 15.639827 -323.647345) (xy 15.62989 -323.658738) (xy 15.612906 -323.678968) (xy 15.57394 -323.714626)
			(xy 15.530135 -323.744139) (xy 15.482451 -323.766859) (xy 15.431935 -323.782287) (xy 15.379694 -323.790086)
			(xy 15.353284 -323.790564) (xy 15.326632 -323.790099) (xy 15.273924 -323.782155) (xy 15.222989 -323.766444)
			(xy 15.174964 -323.743317) (xy 15.130923 -323.713291) (xy 15.091849 -323.677035) (xy 15.058614 -323.635361)
			(xy 15.031963 -323.5892) (xy 15.012489 -323.539581) (xy 15.000627 -323.487614) (xy 14.996644 -323.43446)
			(xy 12.941284 -323.43446) (xy 12.937301 -323.487609) (xy 12.925441 -323.53957) (xy 12.905969 -323.589183)
			(xy 12.87932 -323.635341) (xy 12.84609 -323.677011) (xy 12.80702 -323.713262) (xy 12.762984 -323.743286)
			(xy 12.714965 -323.766412) (xy 12.664035 -323.782122) (xy 12.611333 -323.790066) (xy 12.584684 -323.790564)
			(xy 12.558274 -323.790112) (xy 12.506034 -323.782307) (xy 12.455519 -323.766871) (xy 12.407839 -323.744143)
			(xy 12.36404 -323.71462) (xy 12.325082 -323.678952) (xy 12.308078 -323.658738) (xy 12.298141 -323.647345)
			(xy 12.273088 -323.630454) (xy 12.244192 -323.621623) (xy 12.213976 -323.621623) (xy 12.18508 -323.630454)
			(xy 12.160027 -323.647345) (xy 12.15009 -323.658738) (xy 12.133106 -323.678968) (xy 12.09414 -323.714626)
			(xy 12.050335 -323.744139) (xy 12.002651 -323.766859) (xy 11.952135 -323.782287) (xy 11.899894 -323.790086)
			(xy 11.873484 -323.790564) (xy 11.846832 -323.790099) (xy 11.794124 -323.782155) (xy 11.743189 -323.766444)
			(xy 11.695164 -323.743317) (xy 11.651123 -323.713291) (xy 11.612049 -323.677035) (xy 11.578814 -323.635361)
			(xy 11.552163 -323.5892) (xy 11.532689 -323.539581) (xy 11.520827 -323.487614) (xy 11.516844 -323.43446)
			(xy 8.877284 -323.43446) (xy 8.873301 -323.487609) (xy 8.861441 -323.53957) (xy 8.841969 -323.589183)
			(xy 8.81532 -323.635341) (xy 8.78209 -323.677011) (xy 8.74302 -323.713262) (xy 8.698984 -323.743286)
			(xy 8.650965 -323.766412) (xy 8.600035 -323.782122) (xy 8.547333 -323.790066) (xy 8.520684 -323.790564)
			(xy 8.494274 -323.790112) (xy 8.442034 -323.782307) (xy 8.391519 -323.766871) (xy 8.343839 -323.744143)
			(xy 8.30004 -323.71462) (xy 8.261082 -323.678952) (xy 8.244078 -323.658738) (xy 8.234141 -323.647345)
			(xy 8.209088 -323.630454) (xy 8.180192 -323.621623) (xy 8.149976 -323.621623) (xy 8.12108 -323.630454)
			(xy 8.096027 -323.647345) (xy 8.08609 -323.658738) (xy 8.069106 -323.678968) (xy 8.03014 -323.714626)
			(xy 7.986335 -323.744139) (xy 7.938651 -323.766859) (xy 7.888135 -323.782287) (xy 7.835894 -323.790086)
			(xy 7.809484 -323.790564) (xy 7.782832 -323.790099) (xy 7.730124 -323.782155) (xy 7.679189 -323.766444)
			(xy 7.631164 -323.743317) (xy 7.587123 -323.713291) (xy 7.548049 -323.677035) (xy 7.514814 -323.635361)
			(xy 7.488163 -323.5892) (xy 7.468689 -323.539581) (xy 7.456827 -323.487614) (xy 7.452844 -323.43446)
			(xy 4.151376 -323.43446) (xy 4.151376 -327.108936) (xy 8.653756 -327.108936) (xy 8.653756 -327.024384)
			(xy 8.661558 -326.940192) (xy 8.677094 -326.857079) (xy 8.700233 -326.775754) (xy 8.730777 -326.696911)
			(xy 8.768466 -326.621222) (xy 8.812977 -326.549334) (xy 8.863931 -326.481859) (xy 8.920894 -326.419374)
			(xy 8.983379 -326.362411) (xy 9.050854 -326.311457) (xy 9.122742 -326.266946) (xy 9.198431 -326.229257)
			(xy 9.277274 -326.198713) (xy 9.358599 -326.175574) (xy 9.441712 -326.160038) (xy 9.525904 -326.152236)
			(xy 9.56818 -326.151748) (xy 10.81278 -326.151748) (xy 10.855056 -326.152244) (xy 10.939247 -326.160046)
			(xy 11.02236 -326.175582) (xy 11.103684 -326.198721) (xy 11.182526 -326.229265) (xy 11.258214 -326.266953)
			(xy 11.330102 -326.311463) (xy 11.397576 -326.362417) (xy 11.46006 -326.41938) (xy 11.517023 -326.481864)
			(xy 11.567977 -326.549338) (xy 11.612487 -326.621226) (xy 11.650175 -326.696914) (xy 11.680719 -326.775756)
			(xy 11.703858 -326.85708) (xy 11.719394 -326.940193) (xy 11.727196 -327.024384) (xy 11.727196 -327.108936)
			(xy 16.197556 -327.108936) (xy 16.197556 -327.024384) (xy 16.205358 -326.940192) (xy 16.220894 -326.857079)
			(xy 16.244033 -326.775754) (xy 16.274577 -326.696911) (xy 16.312266 -326.621222) (xy 16.356777 -326.549334)
			(xy 16.407731 -326.481859) (xy 16.464694 -326.419374) (xy 16.527179 -326.362411) (xy 16.594654 -326.311457)
			(xy 16.666542 -326.266946) (xy 16.742231 -326.229257) (xy 16.821074 -326.198713) (xy 16.902399 -326.175574)
			(xy 16.985512 -326.160038) (xy 17.069704 -326.152236) (xy 17.11198 -326.151748) (xy 18.35658 -326.151748)
			(xy 18.398856 -326.152244) (xy 18.483047 -326.160046) (xy 18.56616 -326.175582) (xy 18.647484 -326.198721)
			(xy 18.726326 -326.229265) (xy 18.802014 -326.266953) (xy 18.873902 -326.311463) (xy 18.941376 -326.362417)
			(xy 19.00386 -326.41938) (xy 19.060823 -326.481864) (xy 19.111777 -326.549338) (xy 19.156287 -326.621226)
			(xy 19.193975 -326.696914) (xy 19.224519 -326.775756) (xy 19.247658 -326.85708) (xy 19.263194 -326.940193)
			(xy 19.270996 -327.024384) (xy 19.270996 -327.108936) (xy 23.741356 -327.108936) (xy 23.741356 -327.024384)
			(xy 23.749158 -326.940192) (xy 23.764694 -326.857079) (xy 23.787833 -326.775754) (xy 23.818377 -326.696911)
			(xy 23.856066 -326.621222) (xy 23.900577 -326.549334) (xy 23.951531 -326.481859) (xy 24.008494 -326.419374)
			(xy 24.070979 -326.362411) (xy 24.138454 -326.311457) (xy 24.210342 -326.266946) (xy 24.286031 -326.229257)
			(xy 24.364874 -326.198713) (xy 24.446199 -326.175574) (xy 24.529312 -326.160038) (xy 24.613504 -326.152236)
			(xy 24.65578 -326.151748) (xy 25.90038 -326.151748) (xy 25.942656 -326.152244) (xy 26.026847 -326.160046)
			(xy 26.10996 -326.175582) (xy 26.191284 -326.198721) (xy 26.270126 -326.229265) (xy 26.345814 -326.266953)
			(xy 26.417702 -326.311463) (xy 26.485176 -326.362417) (xy 26.54766 -326.41938) (xy 26.604623 -326.481864)
			(xy 26.655577 -326.549338) (xy 26.700087 -326.621226) (xy 26.737775 -326.696914) (xy 26.768319 -326.775756)
			(xy 26.791458 -326.85708) (xy 26.806994 -326.940193) (xy 26.814796 -327.024384) (xy 26.814796 -327.108936)
			(xy 31.285156 -327.108936) (xy 31.285156 -327.024384) (xy 31.292958 -326.940192) (xy 31.308494 -326.857079)
			(xy 31.331633 -326.775754) (xy 31.362177 -326.696911) (xy 31.399866 -326.621222) (xy 31.444377 -326.549334)
			(xy 31.495331 -326.481859) (xy 31.552294 -326.419374) (xy 31.614779 -326.362411) (xy 31.682254 -326.311457)
			(xy 31.754142 -326.266946) (xy 31.829831 -326.229257) (xy 31.908674 -326.198713) (xy 31.989999 -326.175574)
			(xy 32.073112 -326.160038) (xy 32.157304 -326.152236) (xy 32.19958 -326.151748) (xy 33.44418 -326.151748)
			(xy 33.486456 -326.152244) (xy 33.570647 -326.160046) (xy 33.65376 -326.175582) (xy 33.735084 -326.198721)
			(xy 33.813926 -326.229265) (xy 33.889614 -326.266953) (xy 33.961502 -326.311463) (xy 34.028976 -326.362417)
			(xy 34.09146 -326.41938) (xy 34.148423 -326.481864) (xy 34.199377 -326.549338) (xy 34.243887 -326.621226)
			(xy 34.281575 -326.696914) (xy 34.312119 -326.775756) (xy 34.335258 -326.85708) (xy 34.350794 -326.940193)
			(xy 34.358596 -327.024384) (xy 34.358596 -327.108936) (xy 38.828956 -327.108936) (xy 38.828956 -327.024384)
			(xy 38.836758 -326.940192) (xy 38.852294 -326.857079) (xy 38.875433 -326.775754) (xy 38.905977 -326.696911)
			(xy 38.943666 -326.621222) (xy 38.988177 -326.549334) (xy 39.039131 -326.481859) (xy 39.096094 -326.419374)
			(xy 39.158579 -326.362411) (xy 39.226054 -326.311457) (xy 39.297942 -326.266946) (xy 39.373631 -326.229257)
			(xy 39.452474 -326.198713) (xy 39.533799 -326.175574) (xy 39.616912 -326.160038) (xy 39.701104 -326.152236)
			(xy 39.74338 -326.151748) (xy 40.98798 -326.151748) (xy 41.030256 -326.152244) (xy 41.114447 -326.160046)
			(xy 41.19756 -326.175582) (xy 41.278884 -326.198721) (xy 41.357726 -326.229265) (xy 41.433414 -326.266953)
			(xy 41.505302 -326.311463) (xy 41.572776 -326.362417) (xy 41.63526 -326.41938) (xy 41.692223 -326.481864)
			(xy 41.743177 -326.549338) (xy 41.787687 -326.621226) (xy 41.825375 -326.696914) (xy 41.855919 -326.775756)
			(xy 41.879058 -326.85708) (xy 41.894594 -326.940193) (xy 41.902396 -327.024384) (xy 41.902396 -327.108936)
			(xy 46.372756 -327.108936) (xy 46.372756 -327.024384) (xy 46.380558 -326.940192) (xy 46.396094 -326.857079)
			(xy 46.419233 -326.775754) (xy 46.449777 -326.696911) (xy 46.487466 -326.621222) (xy 46.531977 -326.549334)
			(xy 46.582931 -326.481859) (xy 46.639894 -326.419374) (xy 46.702379 -326.362411) (xy 46.769854 -326.311457)
			(xy 46.841742 -326.266946) (xy 46.917431 -326.229257) (xy 46.996274 -326.198713) (xy 47.077599 -326.175574)
			(xy 47.160712 -326.160038) (xy 47.244904 -326.152236) (xy 47.28718 -326.151748) (xy 48.53178 -326.151748)
			(xy 48.574056 -326.152244) (xy 48.658247 -326.160046) (xy 48.74136 -326.175582) (xy 48.822684 -326.198721)
			(xy 48.901526 -326.229265) (xy 48.977214 -326.266953) (xy 49.049102 -326.311463) (xy 49.116576 -326.362417)
			(xy 49.17906 -326.41938) (xy 49.236023 -326.481864) (xy 49.286977 -326.549338) (xy 49.331487 -326.621226)
			(xy 49.369175 -326.696914) (xy 49.399719 -326.775756) (xy 49.422858 -326.85708) (xy 49.438394 -326.940193)
			(xy 49.446196 -327.024384) (xy 49.446196 -327.108936) (xy 53.916556 -327.108936) (xy 53.916556 -327.024384)
			(xy 53.924358 -326.940192) (xy 53.939894 -326.857079) (xy 53.963033 -326.775754) (xy 53.993577 -326.696911)
			(xy 54.031266 -326.621222) (xy 54.075777 -326.549334) (xy 54.126731 -326.481859) (xy 54.183694 -326.419374)
			(xy 54.246179 -326.362411) (xy 54.313654 -326.311457) (xy 54.385542 -326.266946) (xy 54.461231 -326.229257)
			(xy 54.540074 -326.198713) (xy 54.621399 -326.175574) (xy 54.704512 -326.160038) (xy 54.788704 -326.152236)
			(xy 54.83098 -326.151748) (xy 56.07558 -326.151748) (xy 56.117856 -326.152244) (xy 56.202047 -326.160046)
			(xy 56.28516 -326.175582) (xy 56.366484 -326.198721) (xy 56.445326 -326.229265) (xy 56.521014 -326.266953)
			(xy 56.592902 -326.311463) (xy 56.660376 -326.362417) (xy 56.72286 -326.41938) (xy 56.779823 -326.481864)
			(xy 56.830777 -326.549338) (xy 56.875287 -326.621226) (xy 56.912975 -326.696914) (xy 56.943519 -326.775756)
			(xy 56.966658 -326.85708) (xy 56.982194 -326.940193) (xy 56.989996 -327.024384) (xy 56.989996 -327.108936)
			(xy 56.989992 -327.108978) (xy 61.460336 -327.108978) (xy 61.460336 -327.024422) (xy 61.468138 -326.940228)
			(xy 61.483675 -326.857112) (xy 61.506814 -326.775785) (xy 61.537359 -326.696939) (xy 61.575048 -326.621248)
			(xy 61.61956 -326.549358) (xy 61.670515 -326.481881) (xy 61.727479 -326.419393) (xy 61.789965 -326.362428)
			(xy 61.857441 -326.311471) (xy 61.929331 -326.266957) (xy 62.005021 -326.229267) (xy 62.083866 -326.19872)
			(xy 62.165193 -326.175579) (xy 62.248308 -326.160041) (xy 62.332502 -326.152237) (xy 62.37478 -326.151748)
			(xy 63.61938 -326.151748) (xy 63.661655 -326.152308) (xy 63.745846 -326.160108) (xy 63.828957 -326.175643)
			(xy 63.910281 -326.19878) (xy 63.989123 -326.229321) (xy 64.06481 -326.267008) (xy 64.136697 -326.311517)
			(xy 64.204171 -326.36247) (xy 64.266655 -326.41943) (xy 64.323618 -326.481914) (xy 64.374572 -326.549386)
			(xy 64.419082 -326.621272) (xy 64.45677 -326.696959) (xy 64.487314 -326.7758) (xy 64.510453 -326.857123)
			(xy 64.525989 -326.940234) (xy 64.533791 -327.024425) (xy 64.533791 -327.108975) (xy 64.525989 -327.193166)
			(xy 64.510453 -327.276277) (xy 64.487314 -327.3576) (xy 64.45677 -327.436441) (xy 64.419082 -327.512128)
			(xy 64.374572 -327.584014) (xy 64.323618 -327.651486) (xy 64.266655 -327.71397) (xy 64.204171 -327.77093)
			(xy 64.136697 -327.821883) (xy 64.06481 -327.866392) (xy 63.989123 -327.904079) (xy 63.910281 -327.93462)
			(xy 63.828957 -327.957757) (xy 63.745846 -327.973292) (xy 63.661655 -327.981092) (xy 63.61938 -327.981564)
			(xy 62.37478 -327.981564) (xy 62.332502 -327.981163) (xy 62.248308 -327.973359) (xy 62.165193 -327.957821)
			(xy 62.083866 -327.93468) (xy 62.005021 -327.904133) (xy 61.929331 -327.866443) (xy 61.857441 -327.821929)
			(xy 61.789965 -327.770972) (xy 61.727479 -327.714007) (xy 61.670515 -327.651519) (xy 61.61956 -327.584042)
			(xy 61.575048 -327.512152) (xy 61.537359 -327.436461) (xy 61.506814 -327.357615) (xy 61.483675 -327.276288)
			(xy 61.468138 -327.193172) (xy 61.460336 -327.108978) (xy 56.989992 -327.108978) (xy 56.982194 -327.193127)
			(xy 56.966658 -327.27624) (xy 56.943519 -327.357564) (xy 56.912975 -327.436406) (xy 56.875287 -327.512094)
			(xy 56.830777 -327.583982) (xy 56.779823 -327.651456) (xy 56.72286 -327.71394) (xy 56.660376 -327.770903)
			(xy 56.592902 -327.821857) (xy 56.521014 -327.866367) (xy 56.445326 -327.904055) (xy 56.366484 -327.934599)
			(xy 56.28516 -327.957738) (xy 56.202047 -327.973274) (xy 56.117856 -327.981076) (xy 56.07558 -327.981564)
			(xy 54.83098 -327.981564) (xy 54.788704 -327.981084) (xy 54.704512 -327.973282) (xy 54.621399 -327.957746)
			(xy 54.540074 -327.934607) (xy 54.461231 -327.904063) (xy 54.385542 -327.866374) (xy 54.313654 -327.821863)
			(xy 54.246179 -327.770909) (xy 54.183694 -327.713946) (xy 54.126731 -327.651461) (xy 54.075777 -327.583986)
			(xy 54.031266 -327.512098) (xy 53.993577 -327.436409) (xy 53.963033 -327.357566) (xy 53.939894 -327.276241)
			(xy 53.924358 -327.193128) (xy 53.916556 -327.108936) (xy 49.446196 -327.108936) (xy 49.438394 -327.193127)
			(xy 49.422858 -327.27624) (xy 49.399719 -327.357564) (xy 49.369175 -327.436406) (xy 49.331487 -327.512094)
			(xy 49.286977 -327.583982) (xy 49.236023 -327.651456) (xy 49.17906 -327.71394) (xy 49.116576 -327.770903)
			(xy 49.049102 -327.821857) (xy 48.977214 -327.866367) (xy 48.901526 -327.904055) (xy 48.822684 -327.934599)
			(xy 48.74136 -327.957738) (xy 48.658247 -327.973274) (xy 48.574056 -327.981076) (xy 48.53178 -327.981564)
			(xy 47.28718 -327.981564) (xy 47.244904 -327.981084) (xy 47.160712 -327.973282) (xy 47.077599 -327.957746)
			(xy 46.996274 -327.934607) (xy 46.917431 -327.904063) (xy 46.841742 -327.866374) (xy 46.769854 -327.821863)
			(xy 46.702379 -327.770909) (xy 46.639894 -327.713946) (xy 46.582931 -327.651461) (xy 46.531977 -327.583986)
			(xy 46.487466 -327.512098) (xy 46.449777 -327.436409) (xy 46.419233 -327.357566) (xy 46.396094 -327.276241)
			(xy 46.380558 -327.193128) (xy 46.372756 -327.108936) (xy 41.902396 -327.108936) (xy 41.894594 -327.193127)
			(xy 41.879058 -327.27624) (xy 41.855919 -327.357564) (xy 41.825375 -327.436406) (xy 41.787687 -327.512094)
			(xy 41.743177 -327.583982) (xy 41.692223 -327.651456) (xy 41.63526 -327.71394) (xy 41.572776 -327.770903)
			(xy 41.505302 -327.821857) (xy 41.433414 -327.866367) (xy 41.357726 -327.904055) (xy 41.278884 -327.934599)
			(xy 41.19756 -327.957738) (xy 41.114447 -327.973274) (xy 41.030256 -327.981076) (xy 40.98798 -327.981564)
			(xy 39.74338 -327.981564) (xy 39.701104 -327.981084) (xy 39.616912 -327.973282) (xy 39.533799 -327.957746)
			(xy 39.452474 -327.934607) (xy 39.373631 -327.904063) (xy 39.297942 -327.866374) (xy 39.226054 -327.821863)
			(xy 39.158579 -327.770909) (xy 39.096094 -327.713946) (xy 39.039131 -327.651461) (xy 38.988177 -327.583986)
			(xy 38.943666 -327.512098) (xy 38.905977 -327.436409) (xy 38.875433 -327.357566) (xy 38.852294 -327.276241)
			(xy 38.836758 -327.193128) (xy 38.828956 -327.108936) (xy 34.358596 -327.108936) (xy 34.350794 -327.193127)
			(xy 34.335258 -327.27624) (xy 34.312119 -327.357564) (xy 34.281575 -327.436406) (xy 34.243887 -327.512094)
			(xy 34.199377 -327.583982) (xy 34.148423 -327.651456) (xy 34.09146 -327.71394) (xy 34.028976 -327.770903)
			(xy 33.961502 -327.821857) (xy 33.889614 -327.866367) (xy 33.813926 -327.904055) (xy 33.735084 -327.934599)
			(xy 33.65376 -327.957738) (xy 33.570647 -327.973274) (xy 33.486456 -327.981076) (xy 33.44418 -327.981564)
			(xy 32.19958 -327.981564) (xy 32.157304 -327.981084) (xy 32.073112 -327.973282) (xy 31.989999 -327.957746)
			(xy 31.908674 -327.934607) (xy 31.829831 -327.904063) (xy 31.754142 -327.866374) (xy 31.682254 -327.821863)
			(xy 31.614779 -327.770909) (xy 31.552294 -327.713946) (xy 31.495331 -327.651461) (xy 31.444377 -327.583986)
			(xy 31.399866 -327.512098) (xy 31.362177 -327.436409) (xy 31.331633 -327.357566) (xy 31.308494 -327.276241)
			(xy 31.292958 -327.193128) (xy 31.285156 -327.108936) (xy 26.814796 -327.108936) (xy 26.806994 -327.193127)
			(xy 26.791458 -327.27624) (xy 26.768319 -327.357564) (xy 26.737775 -327.436406) (xy 26.700087 -327.512094)
			(xy 26.655577 -327.583982) (xy 26.604623 -327.651456) (xy 26.54766 -327.71394) (xy 26.485176 -327.770903)
			(xy 26.417702 -327.821857) (xy 26.345814 -327.866367) (xy 26.270126 -327.904055) (xy 26.191284 -327.934599)
			(xy 26.10996 -327.957738) (xy 26.026847 -327.973274) (xy 25.942656 -327.981076) (xy 25.90038 -327.981564)
			(xy 24.65578 -327.981564) (xy 24.613504 -327.981084) (xy 24.529312 -327.973282) (xy 24.446199 -327.957746)
			(xy 24.364874 -327.934607) (xy 24.286031 -327.904063) (xy 24.210342 -327.866374) (xy 24.138454 -327.821863)
			(xy 24.070979 -327.770909) (xy 24.008494 -327.713946) (xy 23.951531 -327.651461) (xy 23.900577 -327.583986)
			(xy 23.856066 -327.512098) (xy 23.818377 -327.436409) (xy 23.787833 -327.357566) (xy 23.764694 -327.276241)
			(xy 23.749158 -327.193128) (xy 23.741356 -327.108936) (xy 19.270996 -327.108936) (xy 19.263194 -327.193127)
			(xy 19.247658 -327.27624) (xy 19.224519 -327.357564) (xy 19.193975 -327.436406) (xy 19.156287 -327.512094)
			(xy 19.111777 -327.583982) (xy 19.060823 -327.651456) (xy 19.00386 -327.71394) (xy 18.941376 -327.770903)
			(xy 18.873902 -327.821857) (xy 18.802014 -327.866367) (xy 18.726326 -327.904055) (xy 18.647484 -327.934599)
			(xy 18.56616 -327.957738) (xy 18.483047 -327.973274) (xy 18.398856 -327.981076) (xy 18.35658 -327.981564)
			(xy 17.11198 -327.981564) (xy 17.069704 -327.981084) (xy 16.985512 -327.973282) (xy 16.902399 -327.957746)
			(xy 16.821074 -327.934607) (xy 16.742231 -327.904063) (xy 16.666542 -327.866374) (xy 16.594654 -327.821863)
			(xy 16.527179 -327.770909) (xy 16.464694 -327.713946) (xy 16.407731 -327.651461) (xy 16.356777 -327.583986)
			(xy 16.312266 -327.512098) (xy 16.274577 -327.436409) (xy 16.244033 -327.357566) (xy 16.220894 -327.276241)
			(xy 16.205358 -327.193128) (xy 16.197556 -327.108936) (xy 11.727196 -327.108936) (xy 11.719394 -327.193127)
			(xy 11.703858 -327.27624) (xy 11.680719 -327.357564) (xy 11.650175 -327.436406) (xy 11.612487 -327.512094)
			(xy 11.567977 -327.583982) (xy 11.517023 -327.651456) (xy 11.46006 -327.71394) (xy 11.397576 -327.770903)
			(xy 11.330102 -327.821857) (xy 11.258214 -327.866367) (xy 11.182526 -327.904055) (xy 11.103684 -327.934599)
			(xy 11.02236 -327.957738) (xy 10.939247 -327.973274) (xy 10.855056 -327.981076) (xy 10.81278 -327.981564)
			(xy 9.56818 -327.981564) (xy 9.525904 -327.981084) (xy 9.441712 -327.973282) (xy 9.358599 -327.957746)
			(xy 9.277274 -327.934607) (xy 9.198431 -327.904063) (xy 9.122742 -327.866374) (xy 9.050854 -327.821863)
			(xy 8.983379 -327.770909) (xy 8.920894 -327.713946) (xy 8.863931 -327.651461) (xy 8.812977 -327.583986)
			(xy 8.768466 -327.512098) (xy 8.730777 -327.436409) (xy 8.700233 -327.357566) (xy 8.677094 -327.276241)
			(xy 8.661558 -327.193128) (xy 8.653756 -327.108936) (xy 4.151376 -327.108936) (xy 4.151376 -332.707488)
			(xy 4.676648 -333.23276) (xy 13.909548 -333.23276) (xy 13.939603 -333.206222) (xy 14.004346 -333.158921)
			(xy 14.073697 -333.118676) (xy 14.146889 -333.085934) (xy 14.223113 -333.061055) (xy 14.301528 -333.044315)
			(xy 14.381267 -333.035898) (xy 14.461449 -333.035898) (xy 14.541188 -333.044315) (xy 14.619603 -333.061055)
			(xy 14.695827 -333.085934) (xy 14.769019 -333.118676) (xy 14.83837 -333.158921) (xy 14.903113 -333.206222)
			(xy 14.933168 -333.23276) (xy 17.214088 -333.23276) (xy 19.297904 -335.316576) (xy 21.063712 -335.316576)
			(xy 21.063712 -333.205074) (xy 21.064111 -333.180169) (xy 21.070584 -333.13078) (xy 21.08343 -333.082655)
			(xy 21.102431 -333.03661) (xy 21.114512 -333.014828) (xy 21.114512 -332.646274) (xy 21.115013 -332.629565)
			(xy 21.123677 -332.597291) (xy 21.140406 -332.568362) (xy 21.164059 -332.544756) (xy 21.193019 -332.528082)
			(xy 21.225311 -332.519481) (xy 21.24202 -332.51902) (xy 21.64842 -332.51902) (xy 21.665111 -332.519565)
			(xy 21.697356 -332.5282) (xy 21.726274 -332.544877) (xy 21.749898 -332.568462) (xy 21.766621 -332.597353)
			(xy 21.775308 -332.629584) (xy 21.775928 -332.646274) (xy 21.775928 -333.014828) (xy 21.78799 -333.03662)
			(xy 21.806987 -333.082664) (xy 21.819839 -333.130786) (xy 21.826329 -333.18017) (xy 21.826728 -333.205074)
			(xy 21.826728 -335.49971) (xy 37.680138 -335.49971)
		)
		(stroke
			(width 0)
			(type solid)
		)
		(fill yes)
		(layer "F.Cu")
		(net "P12V_S3_AUX_CPU1_NVDIMM")
	)
	(gr_poly
		(pts
			(xy 315.62548 -339.354668) (xy 315.62548 -320.688208) (xy 315.2648 -320.327782) (xy 312.226198 -320.327782)
			(xy 312.218324 -320.330576) (xy 312.193238 -320.338617) (xy 312.141283 -320.347301) (xy 312.114946 -320.347848)
			(xy 311.756806 -320.347848) (xy 311.73047 -320.347287) (xy 311.678515 -320.338609) (xy 311.653428 -320.330576)
			(xy 311.645554 -320.327782) (xy 310.773064 -320.327782) (xy 309.917592 -321.183254) (xy 307.527452 -321.183254)
			(xy 307.341524 -321.368928) (xy 307.341524 -321.544442) (xy 307.34635 -321.554348) (xy 307.356559 -321.577728)
			(xy 307.370937 -321.626677) (xy 307.378187 -321.677176) (xy 307.378608 -321.702684) (xy 307.37811 -321.729333)
			(xy 307.370167 -321.782037) (xy 307.354457 -321.832967) (xy 307.331331 -321.880988) (xy 307.301307 -321.925025)
			(xy 307.265055 -321.964096) (xy 307.223384 -321.997327) (xy 307.177226 -322.023976) (xy 307.127612 -322.043448)
			(xy 307.07565 -322.055308) (xy 307.0225 -322.059292) (xy 306.96935 -322.055308) (xy 306.917388 -322.043448)
			(xy 306.867774 -322.023976) (xy 306.821616 -321.997327) (xy 306.779945 -321.964096) (xy 306.743693 -321.925025)
			(xy 306.713669 -321.880988) (xy 306.690543 -321.832967) (xy 306.674833 -321.782037) (xy 306.66689 -321.729333)
			(xy 306.666392 -321.702684) (xy 306.66681 -321.677175) (xy 306.674054 -321.626675) (xy 306.688435 -321.577726)
			(xy 306.69865 -321.554348) (xy 306.703476 -321.544442) (xy 306.703476 -321.236848) (xy 306.703946 -321.211779)
			(xy 306.711799 -321.162261) (xy 306.727304 -321.114581) (xy 306.750078 -321.069914) (xy 306.77956 -321.029361)
			(xy 306.796948 -321.011296) (xy 307.028596 -320.779648) (xy 306.567586 -320.318638) (xy 304.041048 -320.318638)
			(xy 303.968404 -320.391028) (xy 303.968404 -320.593466) (xy 303.97323 -320.603372) (xy 303.983438 -320.626752)
			(xy 303.997814 -320.675701) (xy 304.005061 -320.7262) (xy 304.005488 -320.751708) (xy 304.004967 -320.779692)
			(xy 303.99621 -320.834972) (xy 303.978913 -320.888201) (xy 303.953502 -320.938068) (xy 303.920603 -320.983347)
			(xy 303.881026 -321.022921) (xy 303.835745 -321.055817) (xy 303.785875 -321.081224) (xy 303.732645 -321.098517)
			(xy 303.677364 -321.107269) (xy 303.64938 -321.107816) (xy 303.624666 -321.10738) (xy 303.575718 -321.100503)
			(xy 303.551844 -321.0941) (xy 303.5388 -321.090796) (xy 303.511902 -321.09041) (xy 303.485839 -321.097069)
			(xy 303.462423 -321.11031) (xy 303.443284 -321.129212) (xy 303.429751 -321.152461) (xy 303.422767 -321.178439)
			(xy 303.422304 -321.19189) (xy 303.422304 -321.796664) (xy 303.441956 -321.816842) (xy 303.475275 -321.862252)
			(xy 303.501023 -321.912345) (xy 303.518558 -321.965869) (xy 303.52744 -322.021487) (xy 303.527968 -322.049648)
			(xy 303.527415 -322.077627) (xy 303.518654 -322.132897) (xy 303.501355 -322.186115) (xy 303.475944 -322.235971)
			(xy 303.443046 -322.281239) (xy 303.403472 -322.320803) (xy 303.358196 -322.35369) (xy 303.308333 -322.379089)
			(xy 303.255111 -322.396375) (xy 303.19984 -322.405122) (xy 303.17186 -322.405756) (xy 303.158087 -322.405602)
			(xy 303.130625 -322.403437) (xy 303.116996 -322.401438) (xy 303.10329 -322.399801) (xy 303.075893 -322.403076)
			(xy 303.050374 -322.413566) (xy 303.028594 -322.430505) (xy 303.012145 -322.452658) (xy 303.002227 -322.478405)
			(xy 302.999564 -322.505868) (xy 303.001426 -322.519548) (xy 303.002548 -322.526385) (xy 309.677044 -322.526385)
			(xy 309.677044 -322.473087) (xy 309.684987 -322.420383) (xy 309.700697 -322.369453) (xy 309.723823 -322.321432)
			(xy 309.753847 -322.277395) (xy 309.790099 -322.238324) (xy 309.83177 -322.205093) (xy 309.877928 -322.178444)
			(xy 309.927542 -322.158972) (xy 309.979504 -322.147112) (xy 310.032654 -322.143129) (xy 310.085804 -322.147112)
			(xy 310.137766 -322.158972) (xy 310.18738 -322.178444) (xy 310.233538 -322.205093) (xy 310.275209 -322.238324)
			(xy 310.311461 -322.277395) (xy 310.341485 -322.321432) (xy 310.364611 -322.369453) (xy 310.380321 -322.420383)
			(xy 310.388264 -322.473087) (xy 310.388762 -322.499736) (xy 310.388264 -322.526385) (xy 310.380321 -322.579089)
			(xy 310.364611 -322.630019) (xy 310.341485 -322.67804) (xy 310.311461 -322.722077) (xy 310.275209 -322.761148)
			(xy 310.233538 -322.794379) (xy 310.18738 -322.821028) (xy 310.137766 -322.8405) (xy 310.085804 -322.85236)
			(xy 310.032654 -322.856344) (xy 309.979504 -322.85236) (xy 309.927542 -322.8405) (xy 309.877928 -322.821028)
			(xy 309.83177 -322.794379) (xy 309.790099 -322.761148) (xy 309.753847 -322.722077) (xy 309.723823 -322.67804)
			(xy 309.700697 -322.630019) (xy 309.684987 -322.579089) (xy 309.677044 -322.526385) (xy 303.002548 -322.526385)
			(xy 303.003928 -322.534791) (xy 303.006596 -322.565569) (xy 303.00676 -322.581016) (xy 303.006253 -322.608091)
			(xy 302.998051 -322.661618) (xy 302.981839 -322.713285) (xy 302.95799 -322.761901) (xy 302.927054 -322.806346)
			(xy 302.889745 -322.845593) (xy 302.846923 -322.878739) (xy 302.799577 -322.905018) (xy 302.748796 -322.923825)
			(xy 302.695754 -322.934726) (xy 302.641672 -322.93747) (xy 302.587799 -322.931992) (xy 302.535376 -322.918421)
			(xy 302.485613 -322.897067) (xy 302.439657 -322.868425) (xy 302.398568 -322.833154) (xy 302.363294 -322.792068)
			(xy 302.334648 -322.746115) (xy 302.31329 -322.696354) (xy 302.299713 -322.643932) (xy 302.294231 -322.59006)
			(xy 302.29697 -322.535978) (xy 302.307866 -322.482934) (xy 302.326668 -322.432153) (xy 302.352943 -322.384803)
			(xy 302.386085 -322.341979) (xy 302.42533 -322.304666) (xy 302.469771 -322.273727) (xy 302.518385 -322.249873)
			(xy 302.570051 -322.233656) (xy 302.623577 -322.225449) (xy 302.650652 -322.224908) (xy 302.682673 -322.225602)
			(xy 302.745676 -322.237095) (xy 302.775874 -322.247768) (xy 302.785226 -322.250768) (xy 302.804839 -322.25021)
			(xy 302.822812 -322.242338) (xy 302.83652 -322.228299) (xy 302.843963 -322.210145) (xy 302.844054 -322.190523)
			(xy 302.840898 -322.18122) (xy 302.837242 -322.171797) (xy 302.830887 -322.152609) (xy 302.828198 -322.142866)
			(xy 302.814395 -322.118158) (xy 302.794786 -322.065073) (xy 302.784837 -322.009364) (xy 302.784256 -321.981068)
			(xy 302.784256 -321.105276) (xy 302.783721 -321.090281) (xy 302.775011 -321.061583) (xy 302.758348 -321.036647)
			(xy 302.735166 -321.01762) (xy 302.707461 -321.006139) (xy 302.677615 -321.003192) (xy 302.648199 -321.009032)
			(xy 302.621743 -321.023157) (xy 302.610774 -321.033394) (xy 302.469804 -321.174364) (xy 299.835062 -321.174364)
			(xy 299.830744 -321.178428) (xy 299.830744 -321.373246) (xy 299.83557 -321.383152) (xy 299.845778 -321.406532)
			(xy 299.860155 -321.455481) (xy 299.867404 -321.50598) (xy 299.867828 -321.531488) (xy 299.86733 -321.558137)
			(xy 299.859387 -321.610841) (xy 299.843677 -321.661771) (xy 299.820551 -321.709792) (xy 299.790527 -321.753829)
			(xy 299.754275 -321.7929) (xy 299.712604 -321.826131) (xy 299.666446 -321.85278) (xy 299.616832 -321.872252)
			(xy 299.56487 -321.884112) (xy 299.51172 -321.888096) (xy 299.45857 -321.884112) (xy 299.406608 -321.872252)
			(xy 299.356994 -321.85278) (xy 299.310836 -321.826131) (xy 299.269165 -321.7929) (xy 299.232913 -321.753829)
			(xy 299.202889 -321.709792) (xy 299.179763 -321.661771) (xy 299.164053 -321.610841) (xy 299.15611 -321.558137)
			(xy 299.155612 -321.531488) (xy 299.156029 -321.505979) (xy 299.163274 -321.455478) (xy 299.177655 -321.40653)
			(xy 299.18787 -321.383152) (xy 299.192696 -321.373246) (xy 299.192696 -321.046348) (xy 299.193192 -321.021281)
			(xy 299.201043 -320.971765) (xy 299.216543 -320.924086) (xy 299.239311 -320.87942) (xy 299.268786 -320.838864)
			(xy 299.286168 -320.820796) (xy 299.372782 -320.733928) (xy 298.948602 -320.309748) (xy 295.562528 -320.309748)
			(xy 294.707056 -321.16522) (xy 292.266116 -321.16522) (xy 291.419788 -320.318892) (xy 288.114486 -320.318892)
			(xy 287.26003 -321.173348) (xy 285.50616 -321.173348) (xy 285.29407 -320.961258) (xy 284.59811 -320.961258)
			(xy 284.520386 -320.883534) (xy 284.514036 -320.880232) (xy 284.491483 -320.867533) (xy 284.449975 -320.836618)
			(xy 284.413378 -320.800021) (xy 284.382464 -320.758512) (xy 284.369764 -320.73596) (xy 284.366462 -320.72961)
			(xy 283.973524 -320.336672) (xy 281.927554 -320.336672) (xy 281.430984 -320.832988) (xy 281.430984 -321.888866)
			(xy 281.43581 -321.898772) (xy 281.446019 -321.922152) (xy 281.460395 -321.971101) (xy 281.467643 -322.0216)
			(xy 281.468068 -322.047108) (xy 281.46757 -322.073757) (xy 281.459627 -322.126461) (xy 281.443917 -322.177391)
			(xy 281.420791 -322.225412) (xy 281.390767 -322.269449) (xy 281.354515 -322.30852) (xy 281.312844 -322.341751)
			(xy 281.266686 -322.3684) (xy 281.217072 -322.387872) (xy 281.16511 -322.399732) (xy 281.11196 -322.403716)
			(xy 281.05881 -322.399732) (xy 281.006848 -322.387872) (xy 280.957234 -322.3684) (xy 280.911076 -322.341751)
			(xy 280.869405 -322.30852) (xy 280.833153 -322.269449) (xy 280.803129 -322.225412) (xy 280.780003 -322.177391)
			(xy 280.764293 -322.126461) (xy 280.75635 -322.073757) (xy 280.755852 -322.047108) (xy 280.756268 -322.021599)
			(xy 280.763508 -321.971097) (xy 280.777885 -321.922146) (xy 280.78811 -321.898772) (xy 280.792936 -321.888866)
			(xy 280.792936 -320.870072) (xy 280.792509 -320.860035) (xy 280.78481 -320.841496) (xy 280.770598 -320.827319)
			(xy 280.752039 -320.819666) (xy 280.731965 -320.819705) (xy 280.713436 -320.82743) (xy 280.706068 -320.834258)
			(xy 280.647902 -320.89217) (xy 280.650696 -320.916554) (xy 280.651661 -320.926113) (xy 280.652675 -320.945301)
			(xy 280.652728 -320.954908) (xy 280.652178 -320.982891) (xy 280.643423 -321.038169) (xy 280.626128 -321.091396)
			(xy 280.600719 -321.141262) (xy 280.567823 -321.186541) (xy 280.52825 -321.226116) (xy 280.482973 -321.259013)
			(xy 280.433107 -321.284423) (xy 280.37988 -321.30172) (xy 280.324603 -321.310478) (xy 280.29662 -321.311016)
			(xy 280.270017 -321.310523) (xy 280.217403 -321.30261) (xy 280.166553 -321.286958) (xy 280.118596 -321.263913)
			(xy 280.074602 -321.233991) (xy 280.03555 -321.197856) (xy 280.002309 -321.156313) (xy 279.975618 -321.110287)
			(xy 279.965404 -321.085718) (xy 279.959648 -321.072517) (xy 279.942013 -321.049767) (xy 279.918732 -321.032839)
			(xy 279.891652 -321.023079) (xy 279.862924 -321.021261) (xy 279.83483 -321.027529) (xy 279.8096 -321.041386)
			(xy 279.799034 -321.051174) (xy 279.684734 -321.165474) (xy 277.04669 -321.165474) (xy 276.218142 -320.336926)
			(xy 273.236944 -320.336926) (xy 273.236944 -320.832226) (xy 273.24177 -320.842132) (xy 273.25198 -320.865512)
			(xy 273.266359 -320.914461) (xy 273.273611 -320.964959) (xy 273.274028 -320.990468) (xy 273.27353 -321.017117)
			(xy 273.265587 -321.069821) (xy 273.249877 -321.120751) (xy 273.226751 -321.168772) (xy 273.196727 -321.212809)
			(xy 273.160475 -321.25188) (xy 273.118804 -321.285111) (xy 273.072646 -321.31176) (xy 273.023032 -321.331232)
			(xy 272.97107 -321.343092) (xy 272.91792 -321.347076) (xy 272.86477 -321.343092) (xy 272.812808 -321.331232)
			(xy 272.763194 -321.31176) (xy 272.717036 -321.285111) (xy 272.675365 -321.25188) (xy 272.639113 -321.212809)
			(xy 272.609089 -321.168772) (xy 272.585963 -321.120751) (xy 272.570253 -321.069821) (xy 272.56231 -321.017117)
			(xy 272.561812 -320.990468) (xy 272.562231 -320.964959) (xy 272.569478 -320.91446) (xy 272.583861 -320.865513)
			(xy 272.59407 -320.842132) (xy 272.598896 -320.832226) (xy 272.598896 -320.716148) (xy 272.598357 -320.701162)
			(xy 272.589645 -320.672484) (xy 272.572986 -320.647568) (xy 272.549813 -320.628558) (xy 272.522122 -320.617091)
			(xy 272.492294 -320.614153) (xy 272.462897 -320.619996) (xy 272.43646 -320.634119) (xy 272.425414 -320.644266)
			(xy 271.895316 -321.174364) (xy 269.625572 -321.174364) (xy 268.760956 -320.309748) (xy 265.731244 -320.309748)
			(xy 265.731244 -320.768726) (xy 265.73607 -320.778632) (xy 265.74628 -320.802012) (xy 265.760659 -320.850961)
			(xy 265.767911 -320.901459) (xy 265.768328 -320.926968) (xy 265.76781 -320.954956) (xy 265.759059 -321.010242)
			(xy 265.741766 -321.063479) (xy 265.716358 -321.113355) (xy 265.68346 -321.158643) (xy 265.643882 -321.198226)
			(xy 265.5986 -321.23113) (xy 265.548727 -321.256546) (xy 265.495493 -321.273847) (xy 265.440208 -321.282606)
			(xy 265.41222 -321.283076) (xy 265.385413 -321.282592) (xy 265.332405 -321.274555) (xy 265.281202 -321.25866)
			(xy 265.232962 -321.235266) (xy 265.188775 -321.204902) (xy 265.149642 -321.168255) (xy 265.116447 -321.126154)
			(xy 265.089941 -321.079551) (xy 265.070723 -321.0295) (xy 265.064494 -321.003422) (xy 265.061155 -320.990206)
			(xy 265.048487 -320.966083) (xy 265.029881 -320.946177) (xy 265.006665 -320.931913) (xy 264.980499 -320.92431)
			(xy 264.953255 -320.923912) (xy 264.926878 -320.930746) (xy 264.903255 -320.944325) (xy 264.893298 -320.953638)
			(xy 264.681716 -321.16522) (xy 262.323326 -321.16522) (xy 262.137144 -321.351148) (xy 262.137144 -321.540886)
			(xy 262.14197 -321.550792) (xy 262.152176 -321.574173) (xy 262.166547 -321.623122) (xy 262.173791 -321.67362)
			(xy 262.174228 -321.699128) (xy 262.17373 -321.725777) (xy 262.165787 -321.778481) (xy 262.150077 -321.829411)
			(xy 262.126951 -321.877432) (xy 262.096927 -321.921469) (xy 262.060675 -321.96054) (xy 262.019004 -321.993771)
			(xy 261.972846 -322.02042) (xy 261.923232 -322.039892) (xy 261.87127 -322.051752) (xy 261.81812 -322.055736)
			(xy 261.76497 -322.051752) (xy 261.713008 -322.039892) (xy 261.663394 -322.02042) (xy 261.617236 -321.993771)
			(xy 261.575565 -321.96054) (xy 261.539313 -321.921469) (xy 261.509289 -321.877432) (xy 261.486163 -321.829411)
			(xy 261.470453 -321.778481) (xy 261.46251 -321.725777) (xy 261.462012 -321.699128) (xy 261.462434 -321.67362)
			(xy 261.469686 -321.623122) (xy 261.484074 -321.574178) (xy 261.49427 -321.550792) (xy 261.499096 -321.540886)
			(xy 261.499096 -321.219068) (xy 261.499565 -321.193998) (xy 261.507413 -321.144476) (xy 261.522912 -321.096792)
			(xy 261.54568 -321.05212) (xy 261.575156 -321.011559) (xy 261.592568 -320.993516) (xy 261.655306 -320.930778)
			(xy 261.0612 -320.336672) (xy 257.999484 -320.336672) (xy 257.152902 -321.183254) (xy 254.867156 -321.183254)
			(xy 254.663956 -321.386454) (xy 254.663956 -322.677007) (xy 288.747444 -322.677007) (xy 288.747444 -322.623709)
			(xy 288.755387 -322.571005) (xy 288.771097 -322.520075) (xy 288.794223 -322.472054) (xy 288.824247 -322.428017)
			(xy 288.860499 -322.388946) (xy 288.90217 -322.355715) (xy 288.948328 -322.329066) (xy 288.997942 -322.309594)
			(xy 289.049904 -322.297734) (xy 289.103054 -322.293751) (xy 289.156204 -322.297734) (xy 289.208166 -322.309594)
			(xy 289.25778 -322.329066) (xy 289.303938 -322.355715) (xy 289.345609 -322.388946) (xy 289.381861 -322.428017)
			(xy 289.411885 -322.472054) (xy 289.435011 -322.520075) (xy 289.436957 -322.526385) (xy 291.155364 -322.526385)
			(xy 291.155364 -322.473087) (xy 291.163307 -322.420383) (xy 291.179017 -322.369453) (xy 291.202143 -322.321432)
			(xy 291.232167 -322.277395) (xy 291.268419 -322.238324) (xy 291.31009 -322.205093) (xy 291.356248 -322.178444)
			(xy 291.405862 -322.158972) (xy 291.457824 -322.147112) (xy 291.510974 -322.143129) (xy 291.564124 -322.147112)
			(xy 291.616086 -322.158972) (xy 291.6657 -322.178444) (xy 291.711858 -322.205093) (xy 291.753529 -322.238324)
			(xy 291.789781 -322.277395) (xy 291.819805 -322.321432) (xy 291.842931 -322.369453) (xy 291.858641 -322.420383)
			(xy 291.866584 -322.473087) (xy 291.867082 -322.499736) (xy 291.866584 -322.526385) (xy 292.349164 -322.526385)
			(xy 292.349164 -322.473087) (xy 292.357107 -322.420383) (xy 292.372817 -322.369453) (xy 292.395943 -322.321432)
			(xy 292.425967 -322.277395) (xy 292.462219 -322.238324) (xy 292.50389 -322.205093) (xy 292.550048 -322.178444)
			(xy 292.599662 -322.158972) (xy 292.651624 -322.147112) (xy 292.704774 -322.143129) (xy 292.757924 -322.147112)
			(xy 292.809886 -322.158972) (xy 292.8595 -322.178444) (xy 292.905658 -322.205093) (xy 292.947329 -322.238324)
			(xy 292.983581 -322.277395) (xy 293.013605 -322.321432) (xy 293.036731 -322.369453) (xy 293.052441 -322.420383)
			(xy 293.060384 -322.473087) (xy 293.060882 -322.499736) (xy 293.060384 -322.526385) (xy 294.736764 -322.526385)
			(xy 294.736764 -322.473087) (xy 294.744707 -322.420383) (xy 294.760417 -322.369453) (xy 294.783543 -322.321432)
			(xy 294.813567 -322.277395) (xy 294.849819 -322.238324) (xy 294.89149 -322.205093) (xy 294.937648 -322.178444)
			(xy 294.987262 -322.158972) (xy 295.039224 -322.147112) (xy 295.092374 -322.143129) (xy 295.145524 -322.147112)
			(xy 295.197486 -322.158972) (xy 295.2471 -322.178444) (xy 295.293258 -322.205093) (xy 295.334929 -322.238324)
			(xy 295.371181 -322.277395) (xy 295.401205 -322.321432) (xy 295.424331 -322.369453) (xy 295.440041 -322.420383)
			(xy 295.447984 -322.473087) (xy 295.448482 -322.499736) (xy 295.447984 -322.526385) (xy 295.440041 -322.579089)
			(xy 295.429268 -322.614015) (xy 298.568608 -322.614015) (xy 298.568608 -322.560717) (xy 298.576551 -322.508013)
			(xy 298.592261 -322.457083) (xy 298.615387 -322.409062) (xy 298.645411 -322.365025) (xy 298.681663 -322.325954)
			(xy 298.723334 -322.292723) (xy 298.769492 -322.266074) (xy 298.819106 -322.246602) (xy 298.871068 -322.234742)
			(xy 298.924218 -322.230759) (xy 298.977368 -322.234742) (xy 299.02933 -322.246602) (xy 299.078944 -322.266074)
			(xy 299.125102 -322.292723) (xy 299.166773 -322.325954) (xy 299.203025 -322.365025) (xy 299.233049 -322.409062)
			(xy 299.256175 -322.457083) (xy 299.271885 -322.508013) (xy 299.279828 -322.560717) (xy 299.280326 -322.587366)
			(xy 299.279828 -322.614015) (xy 299.271885 -322.666719) (xy 299.256175 -322.717649) (xy 299.233049 -322.76567)
			(xy 299.203025 -322.809707) (xy 299.166773 -322.848778) (xy 299.125102 -322.882009) (xy 299.078944 -322.908658)
			(xy 299.02933 -322.92813) (xy 298.977368 -322.93999) (xy 298.924218 -322.943974) (xy 298.871068 -322.93999)
			(xy 298.819106 -322.92813) (xy 298.769492 -322.908658) (xy 298.723334 -322.882009) (xy 298.681663 -322.848778)
			(xy 298.645411 -322.809707) (xy 298.615387 -322.76567) (xy 298.592261 -322.717649) (xy 298.576551 -322.666719)
			(xy 298.568608 -322.614015) (xy 295.429268 -322.614015) (xy 295.424331 -322.630019) (xy 295.401205 -322.67804)
			(xy 295.371181 -322.722077) (xy 295.334929 -322.761148) (xy 295.293258 -322.794379) (xy 295.2471 -322.821028)
			(xy 295.197486 -322.8405) (xy 295.145524 -322.85236) (xy 295.092374 -322.856344) (xy 295.039224 -322.85236)
			(xy 294.987262 -322.8405) (xy 294.937648 -322.821028) (xy 294.89149 -322.794379) (xy 294.849819 -322.761148)
			(xy 294.813567 -322.722077) (xy 294.783543 -322.67804) (xy 294.760417 -322.630019) (xy 294.744707 -322.579089)
			(xy 294.736764 -322.526385) (xy 293.060384 -322.526385) (xy 293.052441 -322.579089) (xy 293.036731 -322.630019)
			(xy 293.013605 -322.67804) (xy 292.983581 -322.722077) (xy 292.947329 -322.761148) (xy 292.905658 -322.794379)
			(xy 292.8595 -322.821028) (xy 292.809886 -322.8405) (xy 292.757924 -322.85236) (xy 292.704774 -322.856344)
			(xy 292.651624 -322.85236) (xy 292.599662 -322.8405) (xy 292.550048 -322.821028) (xy 292.50389 -322.794379)
			(xy 292.462219 -322.761148) (xy 292.425967 -322.722077) (xy 292.395943 -322.67804) (xy 292.372817 -322.630019)
			(xy 292.357107 -322.579089) (xy 292.349164 -322.526385) (xy 291.866584 -322.526385) (xy 291.858641 -322.579089)
			(xy 291.842931 -322.630019) (xy 291.819805 -322.67804) (xy 291.789781 -322.722077) (xy 291.753529 -322.761148)
			(xy 291.711858 -322.794379) (xy 291.6657 -322.821028) (xy 291.616086 -322.8405) (xy 291.564124 -322.85236)
			(xy 291.510974 -322.856344) (xy 291.457824 -322.85236) (xy 291.405862 -322.8405) (xy 291.356248 -322.821028)
			(xy 291.31009 -322.794379) (xy 291.268419 -322.761148) (xy 291.232167 -322.722077) (xy 291.202143 -322.67804)
			(xy 291.179017 -322.630019) (xy 291.163307 -322.579089) (xy 291.155364 -322.526385) (xy 289.436957 -322.526385)
			(xy 289.450721 -322.571005) (xy 289.458664 -322.623709) (xy 289.459162 -322.650358) (xy 289.458664 -322.677007)
			(xy 289.450721 -322.729711) (xy 289.435011 -322.780641) (xy 289.411885 -322.828662) (xy 289.381861 -322.872699)
			(xy 289.345609 -322.91177) (xy 289.303938 -322.945001) (xy 289.25778 -322.97165) (xy 289.208166 -322.991122)
			(xy 289.156204 -323.002982) (xy 289.103054 -323.006966) (xy 289.049904 -323.002982) (xy 288.997942 -322.991122)
			(xy 288.948328 -322.97165) (xy 288.90217 -322.945001) (xy 288.860499 -322.91177) (xy 288.824247 -322.872699)
			(xy 288.794223 -322.828662) (xy 288.771097 -322.780641) (xy 288.755387 -322.729711) (xy 288.747444 -322.677007)
			(xy 254.663956 -322.677007) (xy 254.663956 -323.4179) (xy 257.227639 -323.4179) (xy 257.231621 -323.364758)
			(xy 257.24348 -323.312803) (xy 257.262949 -323.263196) (xy 257.289594 -323.217044) (xy 257.32282 -323.175379)
			(xy 257.361885 -323.139132) (xy 257.405916 -323.109111) (xy 257.453929 -323.085988) (xy 257.504853 -323.07028)
			(xy 257.557548 -323.062336) (xy 257.584194 -323.061838) (xy 257.60922 -323.062245) (xy 257.658779 -323.069254)
			(xy 257.706868 -323.083133) (xy 257.752539 -323.10361) (xy 257.794893 -323.130281) (xy 257.833095 -323.16262)
			(xy 257.866391 -323.199991) (xy 257.880612 -323.220588) (xy 257.888945 -323.232217) (xy 257.910781 -323.250684)
			(xy 257.936878 -323.262376) (xy 257.965194 -323.266377) (xy 257.99351 -323.262376) (xy 258.019607 -323.250684)
			(xy 258.041443 -323.232217) (xy 258.049776 -323.220588) (xy 258.064018 -323.200007) (xy 258.097311 -323.162638)
			(xy 258.13551 -323.1303) (xy 258.17786 -323.103629) (xy 258.223528 -323.083152) (xy 258.271614 -323.069272)
			(xy 258.32117 -323.062263) (xy 258.346194 -323.061838) (xy 258.372849 -323.062219) (xy 258.425563 -323.070164)
			(xy 258.476505 -323.085876) (xy 258.524536 -323.109006) (xy 258.568582 -323.139036) (xy 258.607662 -323.175295)
			(xy 258.6409 -323.216974) (xy 258.667555 -323.263142) (xy 258.687031 -323.312766) (xy 258.698894 -323.364739)
			(xy 258.702878 -323.4179) (xy 258.702016 -323.4294) (xy 259.456968 -323.4294) (xy 259.460951 -323.376251)
			(xy 259.47281 -323.32429) (xy 259.49228 -323.274676) (xy 259.518927 -323.228517) (xy 259.552155 -323.186846)
			(xy 259.591222 -323.150591) (xy 259.635256 -323.120564) (xy 259.683274 -323.097434) (xy 259.734202 -323.081719)
			(xy 259.786903 -323.073769) (xy 259.813552 -323.073268) (xy 259.839959 -323.07379) (xy 259.892195 -323.081584)
			(xy 259.942707 -323.097008) (xy 259.990387 -323.119723) (xy 260.034188 -323.149232) (xy 260.073151 -323.184887)
			(xy 260.090158 -323.205094) (xy 260.100095 -323.216487) (xy 260.125148 -323.233378) (xy 260.154044 -323.242209)
			(xy 260.18426 -323.242209) (xy 260.213156 -323.233378) (xy 260.238209 -323.216487) (xy 260.248146 -323.205094)
			(xy 260.265172 -323.184902) (xy 260.304129 -323.149239) (xy 260.347925 -323.119721) (xy 260.3956 -323.096994)
			(xy 260.44611 -323.081558) (xy 260.498344 -323.073751) (xy 260.524752 -323.073268) (xy 260.551404 -323.073786)
			(xy 260.604113 -323.081724) (xy 260.655049 -323.09743) (xy 260.703076 -323.120552) (xy 260.74712 -323.150576)
			(xy 260.786197 -323.186828) (xy 260.819433 -323.2285) (xy 260.846087 -323.274661) (xy 260.865562 -323.324279)
			(xy 260.877424 -323.376246) (xy 260.881408 -323.4294) (xy 262.936768 -323.4294) (xy 262.940751 -323.376251)
			(xy 262.95261 -323.32429) (xy 262.97208 -323.274676) (xy 262.998727 -323.228517) (xy 263.031955 -323.186846)
			(xy 263.071022 -323.150591) (xy 263.115056 -323.120564) (xy 263.163074 -323.097434) (xy 263.214002 -323.081719)
			(xy 263.266703 -323.073769) (xy 263.293352 -323.073268) (xy 263.319759 -323.07379) (xy 263.371995 -323.081584)
			(xy 263.422507 -323.097008) (xy 263.470187 -323.119723) (xy 263.513988 -323.149232) (xy 263.552951 -323.184887)
			(xy 263.569958 -323.205094) (xy 263.579895 -323.216487) (xy 263.604948 -323.233378) (xy 263.633844 -323.242209)
			(xy 263.66406 -323.242209) (xy 263.692956 -323.233378) (xy 263.718009 -323.216487) (xy 263.727946 -323.205094)
			(xy 263.744972 -323.184902) (xy 263.783929 -323.149239) (xy 263.827725 -323.119721) (xy 263.8754 -323.096994)
			(xy 263.92591 -323.081558) (xy 263.978144 -323.073751) (xy 264.004552 -323.073268) (xy 264.031204 -323.073786)
			(xy 264.083913 -323.081724) (xy 264.134849 -323.09743) (xy 264.182876 -323.120552) (xy 264.22692 -323.150576)
			(xy 264.265997 -323.186828) (xy 264.299233 -323.2285) (xy 264.325887 -323.274661) (xy 264.345362 -323.324279)
			(xy 264.357224 -323.376246) (xy 264.361208 -323.4294) (xy 267.000768 -323.4294) (xy 267.004751 -323.376251)
			(xy 267.01661 -323.32429) (xy 267.03608 -323.274676) (xy 267.062727 -323.228517) (xy 267.095955 -323.186846)
			(xy 267.135022 -323.150591) (xy 267.179056 -323.120564) (xy 267.227074 -323.097434) (xy 267.278002 -323.081719)
			(xy 267.330703 -323.073769) (xy 267.357352 -323.073268) (xy 267.383759 -323.07379) (xy 267.435995 -323.081584)
			(xy 267.486507 -323.097008) (xy 267.534187 -323.119723) (xy 267.577988 -323.149232) (xy 267.616951 -323.184887)
			(xy 267.633958 -323.205094) (xy 267.643895 -323.216487) (xy 267.668948 -323.233378) (xy 267.697844 -323.242209)
			(xy 267.72806 -323.242209) (xy 267.756956 -323.233378) (xy 267.782009 -323.216487) (xy 267.791946 -323.205094)
			(xy 267.808972 -323.184902) (xy 267.847929 -323.149239) (xy 267.891725 -323.119721) (xy 267.9394 -323.096994)
			(xy 267.98991 -323.081558) (xy 268.042144 -323.073751) (xy 268.068552 -323.073268) (xy 268.095204 -323.073786)
			(xy 268.147913 -323.081724) (xy 268.198849 -323.09743) (xy 268.246876 -323.120552) (xy 268.29092 -323.150576)
			(xy 268.329997 -323.186828) (xy 268.363233 -323.2285) (xy 268.389887 -323.274661) (xy 268.409362 -323.324279)
			(xy 268.421224 -323.376246) (xy 268.425208 -323.4294) (xy 270.480568 -323.4294) (xy 270.484551 -323.376251)
			(xy 270.49641 -323.32429) (xy 270.51588 -323.274676) (xy 270.542527 -323.228517) (xy 270.575755 -323.186846)
			(xy 270.614822 -323.150591) (xy 270.658856 -323.120564) (xy 270.706874 -323.097434) (xy 270.757802 -323.081719)
			(xy 270.810503 -323.073769) (xy 270.837152 -323.073268) (xy 270.863559 -323.07379) (xy 270.915795 -323.081584)
			(xy 270.966307 -323.097008) (xy 271.013987 -323.119723) (xy 271.057788 -323.149232) (xy 271.096751 -323.184887)
			(xy 271.113758 -323.205094) (xy 271.123695 -323.216487) (xy 271.148748 -323.233378) (xy 271.177644 -323.242209)
			(xy 271.20786 -323.242209) (xy 271.236756 -323.233378) (xy 271.261809 -323.216487) (xy 271.271746 -323.205094)
			(xy 271.288772 -323.184902) (xy 271.327729 -323.149239) (xy 271.371525 -323.119721) (xy 271.4192 -323.096994)
			(xy 271.46971 -323.081558) (xy 271.521944 -323.073751) (xy 271.548352 -323.073268) (xy 271.575004 -323.073786)
			(xy 271.627713 -323.081724) (xy 271.678649 -323.09743) (xy 271.726676 -323.120552) (xy 271.77072 -323.150576)
			(xy 271.809797 -323.186828) (xy 271.843033 -323.2285) (xy 271.869687 -323.274661) (xy 271.889162 -323.324279)
			(xy 271.901024 -323.376246) (xy 271.905008 -323.4294) (xy 274.544568 -323.4294) (xy 274.548551 -323.376251)
			(xy 274.56041 -323.32429) (xy 274.57988 -323.274676) (xy 274.606527 -323.228517) (xy 274.639755 -323.186846)
			(xy 274.678822 -323.150591) (xy 274.722856 -323.120564) (xy 274.770874 -323.097434) (xy 274.821802 -323.081719)
			(xy 274.874503 -323.073769) (xy 274.901152 -323.073268) (xy 274.927559 -323.07379) (xy 274.979795 -323.081584)
			(xy 275.030307 -323.097008) (xy 275.077987 -323.119723) (xy 275.121788 -323.149232) (xy 275.160751 -323.184887)
			(xy 275.177758 -323.205094) (xy 275.187695 -323.216487) (xy 275.212748 -323.233378) (xy 275.241644 -323.242209)
			(xy 275.27186 -323.242209) (xy 275.300756 -323.233378) (xy 275.325809 -323.216487) (xy 275.335746 -323.205094)
			(xy 275.352772 -323.184902) (xy 275.391729 -323.149239) (xy 275.435525 -323.119721) (xy 275.4832 -323.096994)
			(xy 275.53371 -323.081558) (xy 275.585944 -323.073751) (xy 275.612352 -323.073268) (xy 275.639004 -323.073786)
			(xy 275.691713 -323.081724) (xy 275.742649 -323.09743) (xy 275.790676 -323.120552) (xy 275.83472 -323.150576)
			(xy 275.873797 -323.186828) (xy 275.907033 -323.2285) (xy 275.933687 -323.274661) (xy 275.953162 -323.324279)
			(xy 275.965024 -323.376246) (xy 275.969008 -323.4294) (xy 278.024368 -323.4294) (xy 278.028351 -323.376251)
			(xy 278.04021 -323.32429) (xy 278.05968 -323.274676) (xy 278.086327 -323.228517) (xy 278.119555 -323.186846)
			(xy 278.158622 -323.150591) (xy 278.202656 -323.120564) (xy 278.250674 -323.097434) (xy 278.301602 -323.081719)
			(xy 278.354303 -323.073769) (xy 278.380952 -323.073268) (xy 278.407359 -323.07379) (xy 278.459595 -323.081584)
			(xy 278.510107 -323.097008) (xy 278.557787 -323.119723) (xy 278.601588 -323.149232) (xy 278.640551 -323.184887)
			(xy 278.657558 -323.205094) (xy 278.667495 -323.216487) (xy 278.692548 -323.233378) (xy 278.721444 -323.242209)
			(xy 278.75166 -323.242209) (xy 278.780556 -323.233378) (xy 278.805609 -323.216487) (xy 278.815546 -323.205094)
			(xy 278.832572 -323.184902) (xy 278.871529 -323.149239) (xy 278.915325 -323.119721) (xy 278.963 -323.096994)
			(xy 279.01351 -323.081558) (xy 279.065744 -323.073751) (xy 279.092152 -323.073268) (xy 279.118804 -323.073786)
			(xy 279.171513 -323.081724) (xy 279.222449 -323.09743) (xy 279.270476 -323.120552) (xy 279.31452 -323.150576)
			(xy 279.353597 -323.186828) (xy 279.386833 -323.2285) (xy 279.413487 -323.274661) (xy 279.432962 -323.324279)
			(xy 279.444824 -323.376246) (xy 279.448808 -323.4294) (xy 282.088368 -323.4294) (xy 282.092351 -323.376251)
			(xy 282.10421 -323.32429) (xy 282.12368 -323.274676) (xy 282.150327 -323.228517) (xy 282.183555 -323.186846)
			(xy 282.222622 -323.150591) (xy 282.266656 -323.120564) (xy 282.314674 -323.097434) (xy 282.365602 -323.081719)
			(xy 282.418303 -323.073769) (xy 282.444952 -323.073268) (xy 282.471359 -323.07379) (xy 282.523595 -323.081584)
			(xy 282.574107 -323.097008) (xy 282.621787 -323.119723) (xy 282.665588 -323.149232) (xy 282.704551 -323.184887)
			(xy 282.721558 -323.205094) (xy 282.731495 -323.216487) (xy 282.756548 -323.233378) (xy 282.785444 -323.242209)
			(xy 282.81566 -323.242209) (xy 282.844556 -323.233378) (xy 282.869609 -323.216487) (xy 282.879546 -323.205094)
			(xy 282.896572 -323.184902) (xy 282.935529 -323.149239) (xy 282.979325 -323.119721) (xy 283.027 -323.096994)
			(xy 283.07751 -323.081558) (xy 283.129744 -323.073751) (xy 283.156152 -323.073268) (xy 283.182804 -323.073786)
			(xy 283.235513 -323.081724) (xy 283.286449 -323.09743) (xy 283.334476 -323.120552) (xy 283.37852 -323.150576)
			(xy 283.417597 -323.186828) (xy 283.450833 -323.2285) (xy 283.477487 -323.274661) (xy 283.496962 -323.324279)
			(xy 283.508824 -323.376246) (xy 283.512808 -323.4294) (xy 285.695168 -323.4294) (xy 285.699151 -323.376251)
			(xy 285.71101 -323.32429) (xy 285.73048 -323.274676) (xy 285.757127 -323.228517) (xy 285.790355 -323.186846)
			(xy 285.829422 -323.150591) (xy 285.873456 -323.120564) (xy 285.921474 -323.097434) (xy 285.972402 -323.081719)
			(xy 286.025103 -323.073769) (xy 286.051752 -323.073268) (xy 286.078159 -323.07379) (xy 286.130395 -323.081584)
			(xy 286.180907 -323.097008) (xy 286.228587 -323.119723) (xy 286.272388 -323.149232) (xy 286.311351 -323.184887)
			(xy 286.328358 -323.205094) (xy 286.338295 -323.216487) (xy 286.363348 -323.233378) (xy 286.392244 -323.242209)
			(xy 286.42246 -323.242209) (xy 286.451356 -323.233378) (xy 286.476409 -323.216487) (xy 286.486346 -323.205094)
			(xy 286.503372 -323.184902) (xy 286.542329 -323.149239) (xy 286.586125 -323.119721) (xy 286.6338 -323.096994)
			(xy 286.68431 -323.081558) (xy 286.736544 -323.073751) (xy 286.762952 -323.073268) (xy 286.789604 -323.073786)
			(xy 286.842313 -323.081724) (xy 286.893249 -323.09743) (xy 286.941276 -323.120552) (xy 286.98532 -323.150576)
			(xy 287.024397 -323.186828) (xy 287.057633 -323.2285) (xy 287.084287 -323.274661) (xy 287.103762 -323.324279)
			(xy 287.114929 -323.3732) (xy 304.96231 -323.3732) (xy 304.966293 -323.320051) (xy 304.978154 -323.268089)
			(xy 304.997626 -323.218476) (xy 305.024276 -323.172319) (xy 305.057508 -323.13065) (xy 305.09658 -323.094399)
			(xy 305.140618 -323.064377) (xy 305.188639 -323.041254) (xy 305.23957 -323.025546) (xy 305.292273 -323.017606)
			(xy 305.318922 -323.017134) (xy 305.347083 -323.017681) (xy 305.4027 -323.026558) (xy 305.456223 -323.044088)
			(xy 305.506316 -323.069832) (xy 305.551728 -323.103148) (xy 305.571906 -323.122798) (xy 305.5817 -323.132009)
			(xy 305.604958 -323.145478) (xy 305.630919 -323.152431) (xy 305.657795 -323.15239) (xy 305.683735 -323.145356)
			(xy 305.70695 -323.131816) (xy 305.716686 -323.122544) (xy 305.736918 -323.102799) (xy 305.782429 -323.069269)
			(xy 305.832662 -323.043341) (xy 305.886357 -323.025667) (xy 305.942168 -323.016688) (xy 305.970432 -323.016118)
			(xy 305.997082 -323.016566) (xy 306.049785 -323.024514) (xy 306.100716 -323.040228) (xy 306.148735 -323.063357)
			(xy 306.192772 -323.093384) (xy 306.231841 -323.129639) (xy 306.265071 -323.171311) (xy 306.29172 -323.217471)
			(xy 306.311191 -323.267086) (xy 306.323051 -323.31905) (xy 306.327034 -323.3722) (xy 306.323051 -323.42535)
			(xy 306.311191 -323.477314) (xy 306.29172 -323.526929) (xy 306.265071 -323.573089) (xy 306.231841 -323.614761)
			(xy 306.192772 -323.651016) (xy 306.148735 -323.681043) (xy 306.100716 -323.704172) (xy 306.049785 -323.719886)
			(xy 305.997082 -323.727834) (xy 305.970432 -323.728334) (xy 305.942271 -323.727797) (xy 305.886655 -323.718914)
			(xy 305.833132 -323.701381) (xy 305.783039 -323.675635) (xy 305.737627 -323.64232) (xy 305.717448 -323.62267)
			(xy 305.707693 -323.613415) (xy 305.684423 -323.599954) (xy 305.658452 -323.593009) (xy 305.631569 -323.593059)
			(xy 305.605625 -323.600101) (xy 305.582405 -323.613649) (xy 305.572668 -323.622924) (xy 305.552468 -323.642703)
			(xy 305.506947 -323.676226) (xy 305.456706 -323.702146) (xy 305.403004 -323.719813) (xy 305.347188 -323.728784)
			(xy 305.318922 -323.72935) (xy 305.292273 -323.728794) (xy 305.23957 -323.720854) (xy 305.188639 -323.705146)
			(xy 305.140618 -323.682023) (xy 305.09658 -323.652001) (xy 305.057508 -323.61575) (xy 305.024276 -323.574081)
			(xy 304.997626 -323.527924) (xy 304.978154 -323.478311) (xy 304.966293 -323.426349) (xy 304.96231 -323.3732)
			(xy 287.114929 -323.3732) (xy 287.115624 -323.376246) (xy 287.119608 -323.4294) (xy 287.115624 -323.482554)
			(xy 287.103762 -323.534521) (xy 287.084287 -323.584139) (xy 287.057633 -323.6303) (xy 287.024397 -323.671972)
			(xy 286.98532 -323.708224) (xy 286.941276 -323.738248) (xy 286.893249 -323.76137) (xy 286.842313 -323.777076)
			(xy 286.789604 -323.785014) (xy 286.762952 -323.785484) (xy 286.736544 -323.784977) (xy 286.684307 -323.777182)
			(xy 286.633794 -323.761757) (xy 286.586114 -323.739038) (xy 286.542313 -323.709526) (xy 286.503352 -323.673867)
			(xy 286.486346 -323.653658) (xy 286.476409 -323.642265) (xy 286.451356 -323.625374) (xy 286.42246 -323.616543)
			(xy 286.392244 -323.616543) (xy 286.363348 -323.625374) (xy 286.338295 -323.642265) (xy 286.328358 -323.653658)
			(xy 286.311318 -323.673838) (xy 286.272366 -323.709504) (xy 286.228573 -323.739025) (xy 286.1809 -323.761754)
			(xy 286.130392 -323.777192) (xy 286.078159 -323.785) (xy 286.051752 -323.785484) (xy 286.025103 -323.785031)
			(xy 285.972402 -323.777081) (xy 285.921474 -323.761366) (xy 285.873456 -323.738236) (xy 285.829422 -323.708209)
			(xy 285.790355 -323.671954) (xy 285.757127 -323.630283) (xy 285.73048 -323.584124) (xy 285.71101 -323.53451)
			(xy 285.699151 -323.482549) (xy 285.695168 -323.4294) (xy 283.512808 -323.4294) (xy 283.508824 -323.482554)
			(xy 283.496962 -323.534521) (xy 283.477487 -323.584139) (xy 283.450833 -323.6303) (xy 283.417597 -323.671972)
			(xy 283.37852 -323.708224) (xy 283.334476 -323.738248) (xy 283.286449 -323.76137) (xy 283.235513 -323.777076)
			(xy 283.182804 -323.785014) (xy 283.156152 -323.785484) (xy 283.129744 -323.784977) (xy 283.077507 -323.777182)
			(xy 283.026994 -323.761757) (xy 282.979314 -323.739038) (xy 282.935513 -323.709526) (xy 282.896552 -323.673867)
			(xy 282.879546 -323.653658) (xy 282.869609 -323.642265) (xy 282.844556 -323.625374) (xy 282.81566 -323.616543)
			(xy 282.785444 -323.616543) (xy 282.756548 -323.625374) (xy 282.731495 -323.642265) (xy 282.721558 -323.653658)
			(xy 282.704518 -323.673838) (xy 282.665566 -323.709504) (xy 282.621773 -323.739025) (xy 282.5741 -323.761754)
			(xy 282.523592 -323.777192) (xy 282.471359 -323.785) (xy 282.444952 -323.785484) (xy 282.418303 -323.785031)
			(xy 282.365602 -323.777081) (xy 282.314674 -323.761366) (xy 282.266656 -323.738236) (xy 282.222622 -323.708209)
			(xy 282.183555 -323.671954) (xy 282.150327 -323.630283) (xy 282.12368 -323.584124) (xy 282.10421 -323.53451)
			(xy 282.092351 -323.482549) (xy 282.088368 -323.4294) (xy 279.448808 -323.4294) (xy 279.444824 -323.482554)
			(xy 279.432962 -323.534521) (xy 279.413487 -323.584139) (xy 279.386833 -323.6303) (xy 279.353597 -323.671972)
			(xy 279.31452 -323.708224) (xy 279.270476 -323.738248) (xy 279.222449 -323.76137) (xy 279.171513 -323.777076)
			(xy 279.118804 -323.785014) (xy 279.092152 -323.785484) (xy 279.065744 -323.784977) (xy 279.013507 -323.777182)
			(xy 278.962994 -323.761757) (xy 278.915314 -323.739038) (xy 278.871513 -323.709526) (xy 278.832552 -323.673867)
			(xy 278.815546 -323.653658) (xy 278.805609 -323.642265) (xy 278.780556 -323.625374) (xy 278.75166 -323.616543)
			(xy 278.721444 -323.616543) (xy 278.692548 -323.625374) (xy 278.667495 -323.642265) (xy 278.657558 -323.653658)
			(xy 278.640518 -323.673838) (xy 278.601566 -323.709504) (xy 278.557773 -323.739025) (xy 278.5101 -323.761754)
			(xy 278.459592 -323.777192) (xy 278.407359 -323.785) (xy 278.380952 -323.785484) (xy 278.354303 -323.785031)
			(xy 278.301602 -323.777081) (xy 278.250674 -323.761366) (xy 278.202656 -323.738236) (xy 278.158622 -323.708209)
			(xy 278.119555 -323.671954) (xy 278.086327 -323.630283) (xy 278.05968 -323.584124) (xy 278.04021 -323.53451)
			(xy 278.028351 -323.482549) (xy 278.024368 -323.4294) (xy 275.969008 -323.4294) (xy 275.965024 -323.482554)
			(xy 275.953162 -323.534521) (xy 275.933687 -323.584139) (xy 275.907033 -323.6303) (xy 275.873797 -323.671972)
			(xy 275.83472 -323.708224) (xy 275.790676 -323.738248) (xy 275.742649 -323.76137) (xy 275.691713 -323.777076)
			(xy 275.639004 -323.785014) (xy 275.612352 -323.785484) (xy 275.585944 -323.784977) (xy 275.533707 -323.777182)
			(xy 275.483194 -323.761757) (xy 275.435514 -323.739038) (xy 275.391713 -323.709526) (xy 275.352752 -323.673867)
			(xy 275.335746 -323.653658) (xy 275.325809 -323.642265) (xy 275.300756 -323.625374) (xy 275.27186 -323.616543)
			(xy 275.241644 -323.616543) (xy 275.212748 -323.625374) (xy 275.187695 -323.642265) (xy 275.177758 -323.653658)
			(xy 275.160718 -323.673838) (xy 275.121766 -323.709504) (xy 275.077973 -323.739025) (xy 275.0303 -323.761754)
			(xy 274.979792 -323.777192) (xy 274.927559 -323.785) (xy 274.901152 -323.785484) (xy 274.874503 -323.785031)
			(xy 274.821802 -323.777081) (xy 274.770874 -323.761366) (xy 274.722856 -323.738236) (xy 274.678822 -323.708209)
			(xy 274.639755 -323.671954) (xy 274.606527 -323.630283) (xy 274.57988 -323.584124) (xy 274.56041 -323.53451)
			(xy 274.548551 -323.482549) (xy 274.544568 -323.4294) (xy 271.905008 -323.4294) (xy 271.901024 -323.482554)
			(xy 271.889162 -323.534521) (xy 271.869687 -323.584139) (xy 271.843033 -323.6303) (xy 271.809797 -323.671972)
			(xy 271.77072 -323.708224) (xy 271.726676 -323.738248) (xy 271.678649 -323.76137) (xy 271.627713 -323.777076)
			(xy 271.575004 -323.785014) (xy 271.548352 -323.785484) (xy 271.521944 -323.784977) (xy 271.469707 -323.777182)
			(xy 271.419194 -323.761757) (xy 271.371514 -323.739038) (xy 271.327713 -323.709526) (xy 271.288752 -323.673867)
			(xy 271.271746 -323.653658) (xy 271.261809 -323.642265) (xy 271.236756 -323.625374) (xy 271.20786 -323.616543)
			(xy 271.177644 -323.616543) (xy 271.148748 -323.625374) (xy 271.123695 -323.642265) (xy 271.113758 -323.653658)
			(xy 271.096718 -323.673838) (xy 271.057766 -323.709504) (xy 271.013973 -323.739025) (xy 270.9663 -323.761754)
			(xy 270.915792 -323.777192) (xy 270.863559 -323.785) (xy 270.837152 -323.785484) (xy 270.810503 -323.785031)
			(xy 270.757802 -323.777081) (xy 270.706874 -323.761366) (xy 270.658856 -323.738236) (xy 270.614822 -323.708209)
			(xy 270.575755 -323.671954) (xy 270.542527 -323.630283) (xy 270.51588 -323.584124) (xy 270.49641 -323.53451)
			(xy 270.484551 -323.482549) (xy 270.480568 -323.4294) (xy 268.425208 -323.4294) (xy 268.421224 -323.482554)
			(xy 268.409362 -323.534521) (xy 268.389887 -323.584139) (xy 268.363233 -323.6303) (xy 268.329997 -323.671972)
			(xy 268.29092 -323.708224) (xy 268.246876 -323.738248) (xy 268.198849 -323.76137) (xy 268.147913 -323.777076)
			(xy 268.095204 -323.785014) (xy 268.068552 -323.785484) (xy 268.042144 -323.784977) (xy 267.989907 -323.777182)
			(xy 267.939394 -323.761757) (xy 267.891714 -323.739038) (xy 267.847913 -323.709526) (xy 267.808952 -323.673867)
			(xy 267.791946 -323.653658) (xy 267.782009 -323.642265) (xy 267.756956 -323.625374) (xy 267.72806 -323.616543)
			(xy 267.697844 -323.616543) (xy 267.668948 -323.625374) (xy 267.643895 -323.642265) (xy 267.633958 -323.653658)
			(xy 267.616918 -323.673838) (xy 267.577966 -323.709504) (xy 267.534173 -323.739025) (xy 267.4865 -323.761754)
			(xy 267.435992 -323.777192) (xy 267.383759 -323.785) (xy 267.357352 -323.785484) (xy 267.330703 -323.785031)
			(xy 267.278002 -323.777081) (xy 267.227074 -323.761366) (xy 267.179056 -323.738236) (xy 267.135022 -323.708209)
			(xy 267.095955 -323.671954) (xy 267.062727 -323.630283) (xy 267.03608 -323.584124) (xy 267.01661 -323.53451)
			(xy 267.004751 -323.482549) (xy 267.000768 -323.4294) (xy 264.361208 -323.4294) (xy 264.357224 -323.482554)
			(xy 264.345362 -323.534521) (xy 264.325887 -323.584139) (xy 264.299233 -323.6303) (xy 264.265997 -323.671972)
			(xy 264.22692 -323.708224) (xy 264.182876 -323.738248) (xy 264.134849 -323.76137) (xy 264.083913 -323.777076)
			(xy 264.031204 -323.785014) (xy 264.004552 -323.785484) (xy 263.978144 -323.784977) (xy 263.925907 -323.777182)
			(xy 263.875394 -323.761757) (xy 263.827714 -323.739038) (xy 263.783913 -323.709526) (xy 263.744952 -323.673867)
			(xy 263.727946 -323.653658) (xy 263.718009 -323.642265) (xy 263.692956 -323.625374) (xy 263.66406 -323.616543)
			(xy 263.633844 -323.616543) (xy 263.604948 -323.625374) (xy 263.579895 -323.642265) (xy 263.569958 -323.653658)
			(xy 263.552918 -323.673838) (xy 263.513966 -323.709504) (xy 263.470173 -323.739025) (xy 263.4225 -323.761754)
			(xy 263.371992 -323.777192) (xy 263.319759 -323.785) (xy 263.293352 -323.785484) (xy 263.266703 -323.785031)
			(xy 263.214002 -323.777081) (xy 263.163074 -323.761366) (xy 263.115056 -323.738236) (xy 263.071022 -323.708209)
			(xy 263.031955 -323.671954) (xy 262.998727 -323.630283) (xy 262.97208 -323.584124) (xy 262.95261 -323.53451)
			(xy 262.940751 -323.482549) (xy 262.936768 -323.4294) (xy 260.881408 -323.4294) (xy 260.877424 -323.482554)
			(xy 260.865562 -323.534521) (xy 260.846087 -323.584139) (xy 260.819433 -323.6303) (xy 260.786197 -323.671972)
			(xy 260.74712 -323.708224) (xy 260.703076 -323.738248) (xy 260.655049 -323.76137) (xy 260.604113 -323.777076)
			(xy 260.551404 -323.785014) (xy 260.524752 -323.785484) (xy 260.498344 -323.784977) (xy 260.446107 -323.777182)
			(xy 260.395594 -323.761757) (xy 260.347914 -323.739038) (xy 260.304113 -323.709526) (xy 260.265152 -323.673867)
			(xy 260.248146 -323.653658) (xy 260.238209 -323.642265) (xy 260.213156 -323.625374) (xy 260.18426 -323.616543)
			(xy 260.154044 -323.616543) (xy 260.125148 -323.625374) (xy 260.100095 -323.642265) (xy 260.090158 -323.653658)
			(xy 260.073118 -323.673838) (xy 260.034166 -323.709504) (xy 259.990373 -323.739025) (xy 259.9427 -323.761754)
			(xy 259.892192 -323.777192) (xy 259.839959 -323.785) (xy 259.813552 -323.785484) (xy 259.786903 -323.785031)
			(xy 259.734202 -323.777081) (xy 259.683274 -323.761366) (xy 259.635256 -323.738236) (xy 259.591222 -323.708209)
			(xy 259.552155 -323.671954) (xy 259.518927 -323.630283) (xy 259.49228 -323.584124) (xy 259.47281 -323.53451)
			(xy 259.460951 -323.482549) (xy 259.456968 -323.4294) (xy 258.702016 -323.4294) (xy 258.698894 -323.471061)
			(xy 258.687031 -323.523034) (xy 258.667555 -323.572658) (xy 258.6409 -323.618826) (xy 258.607662 -323.660505)
			(xy 258.568582 -323.696764) (xy 258.524536 -323.726794) (xy 258.476505 -323.749924) (xy 258.425563 -323.765636)
			(xy 258.372849 -323.773581) (xy 258.346194 -323.774054) (xy 258.321168 -323.773659) (xy 258.271608 -323.766649)
			(xy 258.223519 -323.752768) (xy 258.177847 -323.732289) (xy 258.135493 -323.705616) (xy 258.097292 -323.673275)
			(xy 258.063996 -323.635902) (xy 258.049776 -323.615304) (xy 258.041443 -323.603675) (xy 258.019607 -323.585208)
			(xy 257.99351 -323.573516) (xy 257.965194 -323.569515) (xy 257.936878 -323.573516) (xy 257.910781 -323.585208)
			(xy 257.888945 -323.603675) (xy 257.880612 -323.615304) (xy 257.866407 -323.635912) (xy 257.833104 -323.673276)
			(xy 257.794898 -323.705609) (xy 257.752541 -323.732274) (xy 257.706868 -323.752747) (xy 257.658778 -323.766623)
			(xy 257.60922 -323.77363) (xy 257.584194 -323.774054) (xy 257.557548 -323.773464) (xy 257.504853 -323.76552)
			(xy 257.453929 -323.749812) (xy 257.405916 -323.726689) (xy 257.361885 -323.696668) (xy 257.32282 -323.660421)
			(xy 257.289594 -323.618756) (xy 257.262949 -323.572604) (xy 257.24348 -323.522997) (xy 257.231621 -323.471042)
			(xy 257.227639 -323.4179) (xy 254.663956 -323.4179) (xy 254.663956 -324.0672) (xy 312.413162 -324.0672)
			(xy 312.417145 -324.01405) (xy 312.429005 -323.962087) (xy 312.448476 -323.912472) (xy 312.475123 -323.866312)
			(xy 312.508353 -323.82464) (xy 312.547421 -323.788385) (xy 312.591457 -323.758357) (xy 312.639476 -323.735227)
			(xy 312.690406 -323.719512) (xy 312.743109 -323.711563) (xy 312.769758 -323.711062) (xy 312.779941 -323.711118)
			(xy 312.800273 -323.712262) (xy 312.810398 -323.713348) (xy 312.824914 -323.714563) (xy 312.853602 -323.709556)
			(xy 312.879705 -323.696648) (xy 312.901098 -323.67689) (xy 312.916036 -323.651892) (xy 312.920126 -323.63791)
			(xy 312.927129 -323.612761) (xy 312.947399 -323.564654) (xy 312.974475 -323.520022) (xy 313.007778 -323.479821)
			(xy 313.046593 -323.444913) (xy 313.090088 -323.416047) (xy 313.137332 -323.39384) (xy 313.187312 -323.378768)
			(xy 313.238956 -323.371155) (xy 313.265058 -323.370702) (xy 313.291712 -323.371152) (xy 313.344425 -323.379092)
			(xy 313.395366 -323.3948) (xy 313.443397 -323.417925) (xy 313.487444 -323.447951) (xy 313.526523 -323.484207)
			(xy 313.559762 -323.525883) (xy 313.586418 -323.572048) (xy 313.605895 -323.62167) (xy 313.617758 -323.673641)
			(xy 313.621742 -323.7268) (xy 313.617758 -323.779959) (xy 313.605895 -323.83193) (xy 313.586418 -323.881552)
			(xy 313.559762 -323.927717) (xy 313.526523 -323.969393) (xy 313.487444 -324.005649) (xy 313.443397 -324.035675)
			(xy 313.395366 -324.0588) (xy 313.344425 -324.074508) (xy 313.291712 -324.082448) (xy 313.265058 -324.082918)
			(xy 313.254875 -324.082861) (xy 313.234543 -324.081718) (xy 313.224418 -324.080632) (xy 313.209901 -324.079447)
			(xy 313.181217 -324.084449) (xy 313.155116 -324.09735) (xy 313.133723 -324.117101) (xy 313.118782 -324.142091)
			(xy 313.11469 -324.15607) (xy 313.107725 -324.18123) (xy 313.087446 -324.229335) (xy 313.060362 -324.273964)
			(xy 313.027053 -324.314162) (xy 312.988234 -324.349067) (xy 312.944735 -324.377932) (xy 312.897488 -324.400138)
			(xy 312.847507 -324.41521) (xy 312.79586 -324.422824) (xy 312.769758 -324.423278) (xy 312.743108 -324.422837)
			(xy 312.690406 -324.414888) (xy 312.639476 -324.399173) (xy 312.591457 -324.376043) (xy 312.547421 -324.346015)
			(xy 312.508353 -324.30976) (xy 312.475123 -324.268088) (xy 312.448475 -324.221928) (xy 312.429005 -324.172313)
			(xy 312.417145 -324.12035) (xy 312.413162 -324.0672) (xy 254.663956 -324.0672) (xy 254.663956 -327.10898)
			(xy 256.593721 -327.10898) (xy 256.593721 -327.02442) (xy 256.601524 -326.94022) (xy 256.617062 -326.857099)
			(xy 256.640204 -326.775767) (xy 256.670752 -326.696917) (xy 256.708445 -326.621222) (xy 256.752962 -326.549328)
			(xy 256.803923 -326.481848) (xy 256.860892 -326.419358) (xy 256.923385 -326.362392) (xy 256.990867 -326.311435)
			(xy 257.062764 -326.266922) (xy 257.138461 -326.229233) (xy 257.217312 -326.198689) (xy 257.298646 -326.175551)
			(xy 257.381767 -326.160017) (xy 257.465968 -326.152219) (xy 257.508248 -326.151748) (xy 258.752848 -326.151748)
			(xy 258.795121 -326.152326) (xy 258.879305 -326.160131) (xy 258.96241 -326.17567) (xy 259.043727 -326.198811)
			(xy 259.122562 -326.229355) (xy 259.198243 -326.267043) (xy 259.270123 -326.311553) (xy 259.337591 -326.362505)
			(xy 259.400069 -326.419465) (xy 259.457025 -326.481946) (xy 259.507974 -326.549416) (xy 259.55248 -326.621299)
			(xy 259.590164 -326.696982) (xy 259.620704 -326.775818) (xy 259.643841 -326.857136) (xy 259.659375 -326.940242)
			(xy 259.667176 -327.024427) (xy 259.667176 -327.108973) (xy 259.667175 -327.10898) (xy 264.137521 -327.10898)
			(xy 264.137521 -327.02442) (xy 264.145324 -326.94022) (xy 264.160862 -326.857099) (xy 264.184004 -326.775767)
			(xy 264.214552 -326.696917) (xy 264.252245 -326.621222) (xy 264.296762 -326.549328) (xy 264.347723 -326.481848)
			(xy 264.404692 -326.419358) (xy 264.467185 -326.362392) (xy 264.534667 -326.311435) (xy 264.606564 -326.266922)
			(xy 264.682261 -326.229233) (xy 264.761112 -326.198689) (xy 264.842446 -326.175551) (xy 264.925567 -326.160017)
			(xy 265.009768 -326.152219) (xy 265.052048 -326.151748) (xy 266.296648 -326.151748) (xy 266.338921 -326.152326)
			(xy 266.423105 -326.160131) (xy 266.50621 -326.17567) (xy 266.587527 -326.198811) (xy 266.666362 -326.229355)
			(xy 266.742043 -326.267043) (xy 266.813923 -326.311553) (xy 266.881391 -326.362505) (xy 266.943869 -326.419465)
			(xy 267.000825 -326.481946) (xy 267.051774 -326.549416) (xy 267.09628 -326.621299) (xy 267.133964 -326.696982)
			(xy 267.164504 -326.775818) (xy 267.187641 -326.857136) (xy 267.203175 -326.940242) (xy 267.210976 -327.024427)
			(xy 267.210976 -327.108973) (xy 267.210975 -327.10898) (xy 271.681321 -327.10898) (xy 271.681321 -327.02442)
			(xy 271.689124 -326.94022) (xy 271.704662 -326.857099) (xy 271.727804 -326.775767) (xy 271.758352 -326.696917)
			(xy 271.796045 -326.621222) (xy 271.840562 -326.549328) (xy 271.891523 -326.481848) (xy 271.948492 -326.419358)
			(xy 272.010985 -326.362392) (xy 272.078467 -326.311435) (xy 272.150364 -326.266922) (xy 272.226061 -326.229233)
			(xy 272.304912 -326.198689) (xy 272.386246 -326.175551) (xy 272.469367 -326.160017) (xy 272.553568 -326.152219)
			(xy 272.595848 -326.151748) (xy 273.840448 -326.151748) (xy 273.882721 -326.152326) (xy 273.966905 -326.160131)
			(xy 274.05001 -326.17567) (xy 274.131327 -326.198811) (xy 274.210162 -326.229355) (xy 274.285843 -326.267043)
			(xy 274.357723 -326.311553) (xy 274.425191 -326.362505) (xy 274.487669 -326.419465) (xy 274.544625 -326.481946)
			(xy 274.595574 -326.549416) (xy 274.64008 -326.621299) (xy 274.677764 -326.696982) (xy 274.708304 -326.775818)
			(xy 274.731441 -326.857136) (xy 274.746975 -326.940242) (xy 274.754776 -327.024427) (xy 274.754776 -327.108973)
			(xy 274.754775 -327.10898) (xy 279.225121 -327.10898) (xy 279.225121 -327.02442) (xy 279.232924 -326.94022)
			(xy 279.248462 -326.857099) (xy 279.271604 -326.775767) (xy 279.302152 -326.696917) (xy 279.339845 -326.621222)
			(xy 279.384362 -326.549328) (xy 279.435323 -326.481848) (xy 279.492292 -326.419358) (xy 279.554785 -326.362392)
			(xy 279.622267 -326.311435) (xy 279.694164 -326.266922) (xy 279.769861 -326.229233) (xy 279.848712 -326.198689)
			(xy 279.930046 -326.175551) (xy 280.013167 -326.160017) (xy 280.097368 -326.152219) (xy 280.139648 -326.151748)
			(xy 281.384248 -326.151748) (xy 281.426521 -326.152326) (xy 281.510705 -326.160131) (xy 281.59381 -326.17567)
			(xy 281.675127 -326.198811) (xy 281.753962 -326.229355) (xy 281.829643 -326.267043) (xy 281.901523 -326.311553)
			(xy 281.968991 -326.362505) (xy 282.031469 -326.419465) (xy 282.088425 -326.481946) (xy 282.139374 -326.549416)
			(xy 282.18388 -326.621299) (xy 282.221564 -326.696982) (xy 282.252104 -326.775818) (xy 282.275241 -326.857136)
			(xy 282.290775 -326.940242) (xy 282.298576 -327.024427) (xy 282.298576 -327.108973) (xy 282.298575 -327.10898)
			(xy 286.768921 -327.10898) (xy 286.768921 -327.02442) (xy 286.776724 -326.94022) (xy 286.792262 -326.857099)
			(xy 286.815404 -326.775767) (xy 286.845952 -326.696917) (xy 286.883645 -326.621222) (xy 286.928162 -326.549328)
			(xy 286.979123 -326.481848) (xy 287.036092 -326.419358) (xy 287.098585 -326.362392) (xy 287.166067 -326.311435)
			(xy 287.237964 -326.266922) (xy 287.313661 -326.229233) (xy 287.392512 -326.198689) (xy 287.473846 -326.175551)
			(xy 287.556967 -326.160017) (xy 287.641168 -326.152219) (xy 287.683448 -326.151748) (xy 288.928048 -326.151748)
			(xy 288.970321 -326.152326) (xy 289.054505 -326.160131) (xy 289.13761 -326.17567) (xy 289.218927 -326.198811)
			(xy 289.297762 -326.229355) (xy 289.373443 -326.267043) (xy 289.445323 -326.311553) (xy 289.512791 -326.362505)
			(xy 289.575269 -326.419465) (xy 289.632225 -326.481946) (xy 289.683174 -326.549416) (xy 289.72768 -326.621299)
			(xy 289.765364 -326.696982) (xy 289.795904 -326.775818) (xy 289.807903 -326.81799) (xy 293.396668 -326.81799)
			(xy 293.400739 -326.762368) (xy 293.412865 -326.707931) (xy 293.432788 -326.65584) (xy 293.460084 -326.607205)
			(xy 293.49417 -326.563062) (xy 293.534319 -326.524353) (xy 293.579677 -326.491902) (xy 293.629277 -326.466401)
			(xy 293.682061 -326.448394) (xy 293.736904 -326.438264) (xy 293.792638 -326.436227) (xy 293.848075 -326.442327)
			(xy 293.902032 -326.456433) (xy 293.953361 -326.478245) (xy 294.000967 -326.507299) (xy 294.043835 -326.542974)
			(xy 294.081052 -326.584511) (xy 294.111825 -326.631024) (xy 294.135497 -326.681521) (xy 294.151565 -326.734928)
			(xy 294.159685 -326.790104) (xy 294.160194 -326.81799) (xy 294.159685 -326.845876) (xy 294.151565 -326.901052)
			(xy 294.135497 -326.954459) (xy 294.111825 -327.004956) (xy 294.081052 -327.051469) (xy 294.043835 -327.093006)
			(xy 294.02464 -327.10898) (xy 294.312721 -327.10898) (xy 294.312721 -327.02442) (xy 294.320524 -326.94022)
			(xy 294.336062 -326.857099) (xy 294.359204 -326.775767) (xy 294.389752 -326.696917) (xy 294.427445 -326.621222)
			(xy 294.471962 -326.549328) (xy 294.522923 -326.481848) (xy 294.579892 -326.419358) (xy 294.642385 -326.362392)
			(xy 294.709867 -326.311435) (xy 294.781764 -326.266922) (xy 294.857461 -326.229233) (xy 294.936312 -326.198689)
			(xy 295.017646 -326.175551) (xy 295.100767 -326.160017) (xy 295.184968 -326.152219) (xy 295.227248 -326.151748)
			(xy 296.471848 -326.151748) (xy 296.514121 -326.152326) (xy 296.598305 -326.160131) (xy 296.68141 -326.17567)
			(xy 296.762727 -326.198811) (xy 296.841562 -326.229355) (xy 296.917243 -326.267043) (xy 296.989123 -326.311553)
			(xy 297.056591 -326.362505) (xy 297.119069 -326.419465) (xy 297.176025 -326.481946) (xy 297.226974 -326.549416)
			(xy 297.27148 -326.621299) (xy 297.309164 -326.696982) (xy 297.339704 -326.775818) (xy 297.362841 -326.857136)
			(xy 297.378375 -326.940242) (xy 297.386176 -327.024427) (xy 297.386176 -327.108973) (xy 297.386175 -327.10898)
			(xy 301.856521 -327.10898) (xy 301.856521 -327.02442) (xy 301.864324 -326.94022) (xy 301.879862 -326.857099)
			(xy 301.903004 -326.775767) (xy 301.933552 -326.696917) (xy 301.971245 -326.621222) (xy 302.015762 -326.549328)
			(xy 302.066723 -326.481848) (xy 302.123692 -326.419358) (xy 302.186185 -326.362392) (xy 302.253667 -326.311435)
			(xy 302.325564 -326.266922) (xy 302.401261 -326.229233) (xy 302.480112 -326.198689) (xy 302.561446 -326.175551)
			(xy 302.644567 -326.160017) (xy 302.728768 -326.152219) (xy 302.771048 -326.151748) (xy 304.015648 -326.151748)
			(xy 304.057921 -326.152326) (xy 304.142105 -326.160131) (xy 304.22521 -326.17567) (xy 304.306527 -326.198811)
			(xy 304.385362 -326.229355) (xy 304.461043 -326.267043) (xy 304.532923 -326.311553) (xy 304.600391 -326.362505)
			(xy 304.662869 -326.419465) (xy 304.719825 -326.481946) (xy 304.770774 -326.549416) (xy 304.81528 -326.621299)
			(xy 304.852964 -326.696982) (xy 304.883504 -326.775818) (xy 304.906641 -326.857136) (xy 304.922175 -326.940242)
			(xy 304.929976 -327.024427) (xy 304.929976 -327.108973) (xy 304.929975 -327.10898) (xy 309.400321 -327.10898)
			(xy 309.400321 -327.02442) (xy 309.408124 -326.94022) (xy 309.423662 -326.857099) (xy 309.446804 -326.775767)
			(xy 309.477352 -326.696917) (xy 309.515045 -326.621222) (xy 309.559562 -326.549328) (xy 309.610523 -326.481848)
			(xy 309.667492 -326.419358) (xy 309.729985 -326.362392) (xy 309.797467 -326.311435) (xy 309.869364 -326.266922)
			(xy 309.945061 -326.229233) (xy 310.023912 -326.198689) (xy 310.105246 -326.175551) (xy 310.188367 -326.160017)
			(xy 310.272568 -326.152219) (xy 310.314848 -326.151748) (xy 311.559448 -326.151748) (xy 311.601721 -326.152326)
			(xy 311.685905 -326.160131) (xy 311.76901 -326.17567) (xy 311.850327 -326.198811) (xy 311.929162 -326.229355)
			(xy 312.004843 -326.267043) (xy 312.076723 -326.311553) (xy 312.144191 -326.362505) (xy 312.206669 -326.419465)
			(xy 312.263625 -326.481946) (xy 312.314574 -326.549416) (xy 312.35908 -326.621299) (xy 312.396764 -326.696982)
			(xy 312.427304 -326.775818) (xy 312.450441 -326.857136) (xy 312.465975 -326.940242) (xy 312.473776 -327.024427)
			(xy 312.473776 -327.108973) (xy 312.465975 -327.193158) (xy 312.450441 -327.276264) (xy 312.427304 -327.357582)
			(xy 312.396764 -327.436418) (xy 312.35908 -327.512101) (xy 312.314574 -327.583984) (xy 312.263625 -327.651454)
			(xy 312.206669 -327.713935) (xy 312.144191 -327.770895) (xy 312.076724 -327.821847) (xy 312.004843 -327.866357)
			(xy 311.929162 -327.904045) (xy 311.850327 -327.934589) (xy 311.76901 -327.95773) (xy 311.685905 -327.973269)
			(xy 311.601721 -327.981074) (xy 311.559448 -327.981564) (xy 310.314848 -327.981564) (xy 310.272568 -327.981181)
			(xy 310.188367 -327.973383) (xy 310.105246 -327.957849) (xy 310.023912 -327.934711) (xy 309.945061 -327.904167)
			(xy 309.869364 -327.866478) (xy 309.797467 -327.821965) (xy 309.729985 -327.771008) (xy 309.667492 -327.714042)
			(xy 309.610523 -327.651552) (xy 309.559562 -327.584072) (xy 309.515045 -327.512178) (xy 309.477352 -327.436483)
			(xy 309.446804 -327.357633) (xy 309.423662 -327.276301) (xy 309.408124 -327.19318) (xy 309.400321 -327.10898)
			(xy 304.929975 -327.10898) (xy 304.922175 -327.193158) (xy 304.906641 -327.276264) (xy 304.883504 -327.357582)
			(xy 304.852964 -327.436418) (xy 304.81528 -327.512101) (xy 304.770774 -327.583984) (xy 304.719825 -327.651454)
			(xy 304.662869 -327.713935) (xy 304.600391 -327.770895) (xy 304.532924 -327.821847) (xy 304.461043 -327.866357)
			(xy 304.385362 -327.904045) (xy 304.306527 -327.934589) (xy 304.22521 -327.95773) (xy 304.142105 -327.973269)
			(xy 304.057921 -327.981074) (xy 304.015648 -327.981564) (xy 302.771048 -327.981564) (xy 302.728768 -327.981181)
			(xy 302.644567 -327.973383) (xy 302.561446 -327.957849) (xy 302.480112 -327.934711) (xy 302.401261 -327.904167)
			(xy 302.325564 -327.866478) (xy 302.253667 -327.821965) (xy 302.186185 -327.771008) (xy 302.123692 -327.714042)
			(xy 302.066723 -327.651552) (xy 302.015762 -327.584072) (xy 301.971245 -327.512178) (xy 301.933552 -327.436483)
			(xy 301.903004 -327.357633) (xy 301.879862 -327.276301) (xy 301.864324 -327.19318) (xy 301.856521 -327.10898)
			(xy 297.386175 -327.10898) (xy 297.378375 -327.193158) (xy 297.362841 -327.276264) (xy 297.339704 -327.357582)
			(xy 297.309164 -327.436418) (xy 297.27148 -327.512101) (xy 297.226974 -327.583984) (xy 297.176025 -327.651454)
			(xy 297.119069 -327.713935) (xy 297.056591 -327.770895) (xy 296.989124 -327.821847) (xy 296.917243 -327.866357)
			(xy 296.841562 -327.904045) (xy 296.762727 -327.934589) (xy 296.68141 -327.95773) (xy 296.598305 -327.973269)
			(xy 296.514121 -327.981074) (xy 296.471848 -327.981564) (xy 295.227248 -327.981564) (xy 295.184968 -327.981181)
			(xy 295.100767 -327.973383) (xy 295.017646 -327.957849) (xy 294.936312 -327.934711) (xy 294.857461 -327.904167)
			(xy 294.781764 -327.866478) (xy 294.709867 -327.821965) (xy 294.642385 -327.771008) (xy 294.579892 -327.714042)
			(xy 294.522923 -327.651552) (xy 294.471962 -327.584072) (xy 294.427445 -327.512178) (xy 294.389752 -327.436483)
			(xy 294.359204 -327.357633) (xy 294.336062 -327.276301) (xy 294.320524 -327.19318) (xy 294.312721 -327.10898)
			(xy 294.02464 -327.10898) (xy 294.000967 -327.128681) (xy 293.953361 -327.157735) (xy 293.902032 -327.179547)
			(xy 293.848075 -327.193653) (xy 293.792638 -327.199753) (xy 293.736904 -327.197716) (xy 293.682061 -327.187586)
			(xy 293.629277 -327.169579) (xy 293.579677 -327.144078) (xy 293.534319 -327.111627) (xy 293.49417 -327.072918)
			(xy 293.460084 -327.028775) (xy 293.432788 -326.98014) (xy 293.412865 -326.928049) (xy 293.400739 -326.873612)
			(xy 293.396668 -326.81799) (xy 289.807903 -326.81799) (xy 289.819041 -326.857136) (xy 289.834575 -326.940242)
			(xy 289.842376 -327.024427) (xy 289.842376 -327.108973) (xy 289.834575 -327.193158) (xy 289.819041 -327.276264)
			(xy 289.795904 -327.357582) (xy 289.765364 -327.436418) (xy 289.72768 -327.512101) (xy 289.683174 -327.583984)
			(xy 289.632225 -327.651454) (xy 289.575269 -327.713935) (xy 289.512791 -327.770895) (xy 289.445324 -327.821847)
			(xy 289.373443 -327.866357) (xy 289.297762 -327.904045) (xy 289.218927 -327.934589) (xy 289.13761 -327.95773)
			(xy 289.054505 -327.973269) (xy 288.970321 -327.981074) (xy 288.928048 -327.981564) (xy 287.683448 -327.981564)
			(xy 287.641168 -327.981181) (xy 287.556967 -327.973383) (xy 287.473846 -327.957849) (xy 287.392512 -327.934711)
			(xy 287.313661 -327.904167) (xy 287.237964 -327.866478) (xy 287.166067 -327.821965) (xy 287.098585 -327.771008)
			(xy 287.036092 -327.714042) (xy 286.979123 -327.651552) (xy 286.928162 -327.584072) (xy 286.883645 -327.512178)
			(xy 286.845952 -327.436483) (xy 286.815404 -327.357633) (xy 286.792262 -327.276301) (xy 286.776724 -327.19318)
			(xy 286.768921 -327.10898) (xy 282.298575 -327.10898) (xy 282.290775 -327.193158) (xy 282.275241 -327.276264)
			(xy 282.252104 -327.357582) (xy 282.221564 -327.436418) (xy 282.18388 -327.512101) (xy 282.139374 -327.583984)
			(xy 282.088425 -327.651454) (xy 282.031469 -327.713935) (xy 281.968991 -327.770895) (xy 281.901524 -327.821847)
			(xy 281.829643 -327.866357) (xy 281.753962 -327.904045) (xy 281.675127 -327.934589) (xy 281.59381 -327.95773)
			(xy 281.510705 -327.973269) (xy 281.426521 -327.981074) (xy 281.384248 -327.981564) (xy 280.139648 -327.981564)
			(xy 280.097368 -327.981181) (xy 280.013167 -327.973383) (xy 279.930046 -327.957849) (xy 279.848712 -327.934711)
			(xy 279.769861 -327.904167) (xy 279.694164 -327.866478) (xy 279.622267 -327.821965) (xy 279.554785 -327.771008)
			(xy 279.492292 -327.714042) (xy 279.435323 -327.651552) (xy 279.384362 -327.584072) (xy 279.339845 -327.512178)
			(xy 279.302152 -327.436483) (xy 279.271604 -327.357633) (xy 279.248462 -327.276301) (xy 279.232924 -327.19318)
			(xy 279.225121 -327.10898) (xy 274.754775 -327.10898) (xy 274.746975 -327.193158) (xy 274.731441 -327.276264)
			(xy 274.708304 -327.357582) (xy 274.677764 -327.436418) (xy 274.64008 -327.512101) (xy 274.595574 -327.583984)
			(xy 274.544625 -327.651454) (xy 274.487669 -327.713935) (xy 274.425191 -327.770895) (xy 274.357724 -327.821847)
			(xy 274.285843 -327.866357) (xy 274.210162 -327.904045) (xy 274.131327 -327.934589) (xy 274.05001 -327.95773)
			(xy 273.966905 -327.973269) (xy 273.882721 -327.981074) (xy 273.840448 -327.981564) (xy 272.595848 -327.981564)
			(xy 272.553568 -327.981181) (xy 272.469367 -327.973383) (xy 272.386246 -327.957849) (xy 272.304912 -327.934711)
			(xy 272.226061 -327.904167) (xy 272.150364 -327.866478) (xy 272.078467 -327.821965) (xy 272.010985 -327.771008)
			(xy 271.948492 -327.714042) (xy 271.891523 -327.651552) (xy 271.840562 -327.584072) (xy 271.796045 -327.512178)
			(xy 271.758352 -327.436483) (xy 271.727804 -327.357633) (xy 271.704662 -327.276301) (xy 271.689124 -327.19318)
			(xy 271.681321 -327.10898) (xy 267.210975 -327.10898) (xy 267.203175 -327.193158) (xy 267.187641 -327.276264)
			(xy 267.164504 -327.357582) (xy 267.133964 -327.436418) (xy 267.09628 -327.512101) (xy 267.051774 -327.583984)
			(xy 267.000825 -327.651454) (xy 266.943869 -327.713935) (xy 266.881391 -327.770895) (xy 266.813924 -327.821847)
			(xy 266.742043 -327.866357) (xy 266.666362 -327.904045) (xy 266.587527 -327.934589) (xy 266.50621 -327.95773)
			(xy 266.423105 -327.973269) (xy 266.338921 -327.981074) (xy 266.296648 -327.981564) (xy 265.052048 -327.981564)
			(xy 265.009768 -327.981181) (xy 264.925567 -327.973383) (xy 264.842446 -327.957849) (xy 264.761112 -327.934711)
			(xy 264.682261 -327.904167) (xy 264.606564 -327.866478) (xy 264.534667 -327.821965) (xy 264.467185 -327.771008)
			(xy 264.404692 -327.714042) (xy 264.347723 -327.651552) (xy 264.296762 -327.584072) (xy 264.252245 -327.512178)
			(xy 264.214552 -327.436483) (xy 264.184004 -327.357633) (xy 264.160862 -327.276301) (xy 264.145324 -327.19318)
			(xy 264.137521 -327.10898) (xy 259.667175 -327.10898) (xy 259.659375 -327.193158) (xy 259.643841 -327.276264)
			(xy 259.620704 -327.357582) (xy 259.590164 -327.436418) (xy 259.55248 -327.512101) (xy 259.507974 -327.583984)
			(xy 259.457025 -327.651454) (xy 259.400069 -327.713935) (xy 259.337591 -327.770895) (xy 259.270124 -327.821847)
			(xy 259.198243 -327.866357) (xy 259.122562 -327.904045) (xy 259.043727 -327.934589) (xy 258.96241 -327.95773)
			(xy 258.879305 -327.973269) (xy 258.795121 -327.981074) (xy 258.752848 -327.981564) (xy 257.508248 -327.981564)
			(xy 257.465968 -327.981181) (xy 257.381767 -327.973383) (xy 257.298646 -327.957849) (xy 257.217312 -327.934711)
			(xy 257.138461 -327.904167) (xy 257.062764 -327.866478) (xy 256.990867 -327.821965) (xy 256.923385 -327.771008)
			(xy 256.860892 -327.714042) (xy 256.803923 -327.651552) (xy 256.752962 -327.584072) (xy 256.708445 -327.512178)
			(xy 256.670752 -327.436483) (xy 256.640204 -327.357633) (xy 256.617062 -327.276301) (xy 256.601524 -327.19318)
			(xy 256.593721 -327.10898) (xy 254.663956 -327.10898) (xy 254.663956 -329.7555) (xy 255.548892 -329.7555)
			(xy 255.549362 -329.72803) (xy 255.557243 -329.673659) (xy 255.572841 -329.620981) (xy 255.595833 -329.571084)
			(xy 255.625745 -329.525002) (xy 255.661957 -329.483686) (xy 255.703722 -329.447992) (xy 255.726692 -329.43292)
			(xy 255.738753 -329.42467) (xy 255.758019 -329.402719) (xy 255.770287 -329.376214) (xy 255.774553 -329.347321)
			(xy 255.770468 -329.318401) (xy 255.758367 -329.29182) (xy 255.739239 -329.269749) (xy 255.7272 -329.26147)
			(xy 255.704491 -329.246315) (xy 255.663182 -329.210622) (xy 255.627381 -329.169405) (xy 255.59782 -329.123508)
			(xy 255.575102 -329.073865) (xy 255.559691 -329.021492) (xy 255.551902 -328.967457) (xy 255.551432 -328.94016)
			(xy 255.551918 -328.912909) (xy 255.559674 -328.858961) (xy 255.575029 -328.806666) (xy 255.597671 -328.757089)
			(xy 255.627137 -328.711239) (xy 255.662828 -328.670048) (xy 255.704019 -328.634357) (xy 255.749869 -328.604891)
			(xy 255.799446 -328.582249) (xy 255.851741 -328.566894) (xy 255.905689 -328.559138) (xy 255.960191 -328.559138)
			(xy 256.014139 -328.566894) (xy 256.066434 -328.582249) (xy 256.116011 -328.604891) (xy 256.161861 -328.634357)
			(xy 256.203052 -328.670048) (xy 256.238743 -328.711239) (xy 256.268209 -328.757089) (xy 256.290851 -328.806666)
			(xy 256.306206 -328.858961) (xy 256.313962 -328.912909) (xy 256.314448 -328.94016) (xy 256.313974 -328.96763)
			(xy 256.306098 -329.022002) (xy 256.290503 -329.074682) (xy 256.267512 -329.124579) (xy 256.2376 -329.170662)
			(xy 256.201386 -329.211977) (xy 256.15962 -329.247669) (xy 256.136648 -329.26274) (xy 256.124526 -329.27091)
			(xy 256.105249 -329.292876) (xy 256.092979 -329.319399) (xy 256.088718 -329.348312) (xy 256.092815 -329.377247)
			(xy 256.104936 -329.40384) (xy 256.124088 -329.425914) (xy 256.13614 -329.43419) (xy 256.158886 -329.449292)
			(xy 256.200193 -329.484996) (xy 256.235989 -329.526222) (xy 256.265545 -329.572129) (xy 256.288257 -329.621779)
			(xy 256.303661 -329.67416) (xy 256.311442 -329.728201) (xy 256.311908 -329.7555) (xy 256.311422 -329.782751)
			(xy 256.303666 -329.836699) (xy 256.288311 -329.888994) (xy 256.265669 -329.938571) (xy 256.236203 -329.984421)
			(xy 256.200512 -330.025612) (xy 256.159321 -330.061303) (xy 256.113471 -330.090769) (xy 256.063894 -330.113411)
			(xy 256.011599 -330.128766) (xy 255.957651 -330.136522) (xy 255.903149 -330.136522) (xy 255.849201 -330.128766)
			(xy 255.796906 -330.113411) (xy 255.747329 -330.090769) (xy 255.701479 -330.061303) (xy 255.660288 -330.025612)
			(xy 255.624597 -329.984421) (xy 255.595131 -329.938571) (xy 255.572489 -329.888994) (xy 255.557134 -329.836699)
			(xy 255.549378 -329.782751) (xy 255.548892 -329.7555) (xy 254.663956 -329.7555) (xy 254.663956 -339.160104)
			(xy 255.0668 -339.562948) (xy 315.4172 -339.562948)
		)
		(stroke
			(width 0)
			(type solid)
		)
		(fill yes)
		(layer "F.Cu")
		(net "P12V_S3_AUX_CPU0_NVDIMM")
	)
	(gr_poly
		(pts
			(xy 437.260238 -338.01685) (xy 438.644538 -338.01685) (xy 439.475118 -337.18627) (xy 439.475118 -334.10271)
			(xy 441.575698 -332.00213) (xy 444.387478 -332.00213) (xy 445.865758 -333.48041) (xy 446.896998 -333.48041)
			(xy 447.191638 -333.77505) (xy 447.191638 -334.25257) (xy 447.460878 -334.52181) (xy 448.969384 -334.52181)
			(xy 448.969384 -332.760574) (xy 448.969794 -332.735671) (xy 448.976283 -332.686288) (xy 448.989136 -332.638167)
			(xy 449.008133 -332.592126) (xy 449.020184 -332.570328) (xy 449.020184 -332.201774) (xy 449.020683 -332.18509)
			(xy 449.029326 -332.152861) (xy 449.046017 -332.123967) (xy 449.069618 -332.100378) (xy 449.09852 -332.083702)
			(xy 449.130754 -332.075075) (xy 449.147438 -332.07452) (xy 449.553838 -332.07452) (xy 449.570518 -332.075069)
			(xy 449.602738 -332.08371) (xy 449.631626 -332.100393) (xy 449.655214 -332.123983) (xy 449.671895 -332.152873)
			(xy 449.680533 -332.185094) (xy 449.681092 -332.201774) (xy 449.681092 -332.570328) (xy 449.693172 -332.592112)
			(xy 449.712192 -332.63815) (xy 449.725043 -332.686276) (xy 449.731506 -332.735668) (xy 449.731892 -332.760574)
			(xy 449.731892 -334.52181) (xy 460.782416 -334.52181) (xy 466.086952 -329.217274) (xy 466.086952 -320.716656)
			(xy 465.680552 -320.310256) (xy 465.123784 -320.310256) (xy 465.123784 -320.811906) (xy 465.12861 -320.821812)
			(xy 465.138823 -320.845191) (xy 465.153207 -320.89414) (xy 465.160463 -320.944639) (xy 465.160868 -320.970148)
			(xy 465.16037 -320.996797) (xy 465.152427 -321.049501) (xy 465.136717 -321.100431) (xy 465.113591 -321.148452)
			(xy 465.083567 -321.192489) (xy 465.047315 -321.23156) (xy 465.005644 -321.264791) (xy 464.959486 -321.29144)
			(xy 464.909872 -321.310912) (xy 464.85791 -321.322772) (xy 464.80476 -321.326756) (xy 464.75161 -321.322772)
			(xy 464.699648 -321.310912) (xy 464.650034 -321.29144) (xy 464.603876 -321.264791) (xy 464.562205 -321.23156)
			(xy 464.525953 -321.192489) (xy 464.495929 -321.148452) (xy 464.472803 -321.100431) (xy 464.457093 -321.049501)
			(xy 464.44915 -320.996797) (xy 464.448652 -320.970148) (xy 464.449072 -320.944639) (xy 464.45632 -320.894141)
			(xy 464.470704 -320.845194) (xy 464.48091 -320.821812) (xy 464.485736 -320.811906) (xy 464.485736 -320.485008)
			(xy 464.31073 -320.310256) (xy 460.981552 -320.310256) (xy 460.432912 -320.858896) (xy 460.429102 -320.869564)
			(xy 460.424008 -320.882743) (xy 460.408917 -320.906623) (xy 460.388945 -320.9266) (xy 460.365068 -320.941696)
			(xy 460.351886 -320.94678) (xy 460.341218 -320.95059) (xy 460.143352 -321.148456) (xy 458.187552 -321.148456)
			(xy 457.961492 -320.922396) (xy 457.94422 -320.920364) (xy 457.918184 -320.91671) (xy 457.867501 -320.902735)
			(xy 457.819423 -320.881461) (xy 457.774994 -320.853352) (xy 457.73518 -320.819017) (xy 457.700846 -320.779202)
			(xy 457.672736 -320.734773) (xy 457.651464 -320.686695) (xy 457.637489 -320.636012) (xy 457.633832 -320.609976)
			(xy 457.6318 -320.592704) (xy 457.349352 -320.310256) (xy 454.96607 -320.310256) (xy 454.562464 -320.713608)
			(xy 454.562464 -321.030346) (xy 454.56729 -321.040252) (xy 454.577501 -321.063632) (xy 454.591881 -321.11258)
			(xy 454.599131 -321.163079) (xy 454.599548 -321.188588) (xy 454.59905 -321.215237) (xy 454.591107 -321.267941)
			(xy 454.575397 -321.318871) (xy 454.552271 -321.366892) (xy 454.522247 -321.410929) (xy 454.485995 -321.45)
			(xy 454.444324 -321.483231) (xy 454.398166 -321.50988) (xy 454.348552 -321.529352) (xy 454.29659 -321.541212)
			(xy 454.24344 -321.545196) (xy 454.19029 -321.541212) (xy 454.138328 -321.529352) (xy 454.088714 -321.50988)
			(xy 454.042556 -321.483231) (xy 454.000885 -321.45) (xy 453.964633 -321.410929) (xy 453.934609 -321.366892)
			(xy 453.911483 -321.318871) (xy 453.895773 -321.267941) (xy 453.88783 -321.215237) (xy 453.887332 -321.188588)
			(xy 453.887749 -321.163079) (xy 453.894992 -321.112578) (xy 453.90937 -321.063628) (xy 453.91959 -321.040252)
			(xy 453.924416 -321.030346) (xy 453.924416 -320.581528) (xy 453.924755 -320.559432) (xy 453.930782 -320.515655)
			(xy 453.942795 -320.473129) (xy 453.95134 -320.45275) (xy 453.95668 -320.439342) (xy 453.960429 -320.410738)
			(xy 453.95603 -320.382228) (xy 453.943835 -320.356084) (xy 453.924816 -320.334394) (xy 453.900491 -320.318886)
			(xy 453.8728 -320.310799) (xy 453.858376 -320.310256) (xy 453.767952 -320.310256) (xy 452.929752 -321.148456)
			(xy 450.465952 -321.148456) (xy 449.627752 -320.310256) (xy 446.325752 -320.310256) (xy 445.487552 -321.148456)
			(xy 442.896752 -321.148456) (xy 442.058552 -320.310256) (xy 438.654952 -320.310256) (xy 437.816752 -321.148456)
			(xy 436.140352 -321.148456) (xy 435.987952 -320.996056) (xy 435.479952 -320.996056) (xy 435.401974 -320.918078)
			(xy 435.37759 -320.920618) (xy 435.367781 -320.92167) (xy 435.348085 -320.922812) (xy 435.33822 -320.922904)
			(xy 435.310234 -320.922385) (xy 435.25495 -320.913632) (xy 435.201716 -320.896337) (xy 435.151844 -320.870928)
			(xy 435.10656 -320.83803) (xy 435.066981 -320.798452) (xy 435.03408 -320.75317) (xy 435.008669 -320.703299)
			(xy 434.991372 -320.650066) (xy 434.982616 -320.594782) (xy 434.982112 -320.566796) (xy 434.982209 -320.556932)
			(xy 434.983351 -320.537235) (xy 434.984398 -320.527426) (xy 434.986938 -320.503042) (xy 434.794152 -320.310256)
			(xy 432.237642 -320.310256) (xy 431.872644 -320.675) (xy 431.872644 -320.875406) (xy 431.87747 -320.885312)
			(xy 431.887681 -320.908692) (xy 431.902063 -320.95764) (xy 431.909318 -321.008139) (xy 431.909728 -321.033648)
			(xy 431.90923 -321.060297) (xy 431.901287 -321.113001) (xy 431.885577 -321.163931) (xy 431.862451 -321.211952)
			(xy 431.832427 -321.255989) (xy 431.796175 -321.29506) (xy 431.754504 -321.328291) (xy 431.708346 -321.35494)
			(xy 431.658732 -321.374412) (xy 431.60677 -321.386272) (xy 431.55362 -321.390256) (xy 431.50047 -321.386272)
			(xy 431.448508 -321.374412) (xy 431.398894 -321.35494) (xy 431.352736 -321.328291) (xy 431.311065 -321.29506)
			(xy 431.274813 -321.255989) (xy 431.244789 -321.211952) (xy 431.221663 -321.163931) (xy 431.205953 -321.113001)
			(xy 431.19801 -321.060297) (xy 431.197512 -321.033648) (xy 431.197932 -321.00814) (xy 431.205182 -320.957641)
			(xy 431.219568 -320.908695) (xy 431.22977 -320.885312) (xy 431.234596 -320.875406) (xy 431.234596 -320.54292)
			(xy 431.235141 -320.515555) (xy 431.244441 -320.461623) (xy 431.262806 -320.410067) (xy 431.275744 -320.385948)
			(xy 431.282348 -320.374518) (xy 431.282348 -320.310256) (xy 431.161952 -320.310256) (xy 430.323752 -321.148456)
			(xy 428.647352 -321.148456) (xy 428.444152 -320.945256) (xy 428.25035 -320.945256) (xy 427.946566 -321.24904)
			(xy 427.942756 -321.259454) (xy 427.932854 -321.284629) (xy 427.906542 -321.331894) (xy 427.873384 -321.374636)
			(xy 427.834143 -321.411871) (xy 427.789721 -321.442742) (xy 427.741141 -321.466539) (xy 427.689521 -321.482715)
			(xy 427.636048 -321.490897) (xy 427.609 -321.491356) (xy 427.581016 -321.490807) (xy 427.525736 -321.482052)
			(xy 427.472505 -321.464758) (xy 427.422636 -321.439351) (xy 427.377354 -321.406456) (xy 427.337775 -321.366882)
			(xy 427.304874 -321.321605) (xy 427.27946 -321.271739) (xy 427.262159 -321.218511) (xy 427.253397 -321.163232)
			(xy 427.252892 -321.135248) (xy 427.253399 -321.108205) (xy 427.261586 -321.054742) (xy 427.277763 -321.003132)
			(xy 427.301559 -320.954561) (xy 427.332426 -320.910148) (xy 427.369655 -320.870913) (xy 427.412389 -320.837759)
			(xy 427.459644 -320.811449) (xy 427.484794 -320.801492) (xy 427.495208 -320.797682) (xy 427.60392 -320.689224)
			(xy 427.224952 -320.310256) (xy 425.218352 -320.310256) (xy 425.040552 -320.132456) (xy 423.821352 -320.132456)
			(xy 422.805352 -321.148456) (xy 420.493952 -321.148456) (xy 420.410132 -321.064636) (xy 420.380414 -321.074542)
			(xy 420.353182 -321.082974) (xy 420.296902 -321.092031) (xy 420.2684 -321.092576) (xy 420.240416 -321.092055)
			(xy 420.185136 -321.083299) (xy 420.131907 -321.066003) (xy 420.082039 -321.040593) (xy 420.03676 -321.007693)
			(xy 419.997186 -320.968115) (xy 419.964291 -320.922834) (xy 419.938885 -320.872964) (xy 419.921593 -320.819733)
			(xy 419.912842 -320.764452) (xy 419.912292 -320.736468) (xy 419.912856 -320.707968) (xy 419.921916 -320.651691)
			(xy 419.930326 -320.624454) (xy 419.940232 -320.594736) (xy 419.655752 -320.310256) (xy 417.217352 -320.310256)
			(xy 416.353752 -321.173856) (xy 413.178752 -321.173856) (xy 412.890716 -320.88582) (xy 412.806642 -320.88582)
			(xy 412.796736 -320.890646) (xy 412.773356 -320.900854) (xy 412.724407 -320.91523) (xy 412.673908 -320.922478)
			(xy 412.6484 -320.922904) (xy 412.620415 -320.922383) (xy 412.565133 -320.913628) (xy 412.511902 -320.896332)
			(xy 412.462032 -320.870922) (xy 412.416752 -320.838023) (xy 412.377175 -320.798445) (xy 412.344276 -320.753164)
			(xy 412.318867 -320.703294) (xy 412.301571 -320.650063) (xy 412.292816 -320.594781) (xy 412.292292 -320.566796)
			(xy 412.292832 -320.538623) (xy 412.301704 -320.482979) (xy 412.319212 -320.429422) (xy 412.344919 -320.379281)
			(xy 412.361126 -320.35623) (xy 412.264352 -320.259456) (xy 409.172918 -320.259456) (xy 409.131516 -320.300604)
			(xy 409.11176 -320.319785) (xy 409.068325 -320.353629) (xy 409.021046 -320.381858) (xy 408.970647 -320.404039)
			(xy 408.917896 -320.419834) (xy 408.8636 -320.429003) (xy 408.836114 -320.430652) (xy 408.826686 -320.431455)
			(xy 408.809382 -320.439077) (xy 408.796006 -320.452441) (xy 408.788366 -320.469737) (xy 408.7876 -320.479166)
			(xy 408.785841 -320.505796) (xy 408.775352 -320.558122) (xy 408.757178 -320.608299) (xy 408.731727 -320.655206)
			(xy 408.699566 -320.697794) (xy 408.661415 -320.735111) (xy 408.618127 -320.766323) (xy 408.570669 -320.790732)
			(xy 408.545538 -320.799714) (xy 408.527691 -320.815813) (xy 408.488065 -320.843014) (xy 408.444811 -320.863969)
			(xy 408.398905 -320.878206) (xy 408.351384 -320.885401) (xy 408.327352 -320.88582) (xy 408.17292 -320.88582)
			(xy 408.159446 -320.910187) (xy 408.126101 -320.954777) (xy 408.086221 -320.993632) (xy 408.040778 -321.025805)
			(xy 407.990881 -321.050511) (xy 407.937746 -321.067148) (xy 407.910284 -321.071748) (xy 407.89352 -321.074288)
			(xy 407.819352 -321.148456) (xy 402.462492 -321.148456) (xy 402.159978 -321.45097) (xy 402.159978 -321.785213)
			(xy 412.579556 -321.785213) (xy 412.579556 -321.731915) (xy 412.587499 -321.679211) (xy 412.603209 -321.628281)
			(xy 412.626335 -321.58026) (xy 412.656359 -321.536223) (xy 412.692611 -321.497152) (xy 412.734282 -321.463921)
			(xy 412.78044 -321.437272) (xy 412.830054 -321.4178) (xy 412.882016 -321.40594) (xy 412.935166 -321.401957)
			(xy 412.988316 -321.40594) (xy 413.040278 -321.4178) (xy 413.089892 -321.437272) (xy 413.13605 -321.463921)
			(xy 413.177721 -321.497152) (xy 413.213973 -321.536223) (xy 413.243997 -321.58026) (xy 413.267123 -321.628281)
			(xy 413.282833 -321.679211) (xy 413.290776 -321.731915) (xy 413.291274 -321.758564) (xy 413.290776 -321.785213)
			(xy 413.282833 -321.837917) (xy 413.267123 -321.888847) (xy 413.243997 -321.936868) (xy 413.213973 -321.980905)
			(xy 413.177721 -322.019976) (xy 413.13605 -322.053207) (xy 413.089892 -322.079856) (xy 413.040278 -322.099328)
			(xy 412.988316 -322.111188) (xy 412.935166 -322.115172) (xy 412.882016 -322.111188) (xy 412.830054 -322.099328)
			(xy 412.78044 -322.079856) (xy 412.734282 -322.053207) (xy 412.692611 -322.019976) (xy 412.656359 -321.980905)
			(xy 412.626335 -321.936868) (xy 412.603209 -321.888847) (xy 412.587499 -321.837917) (xy 412.579556 -321.785213)
			(xy 402.159978 -321.785213) (xy 402.159978 -322.369749) (xy 415.741388 -322.369749) (xy 415.741388 -322.315251)
			(xy 415.749143 -322.261309) (xy 415.764496 -322.209019) (xy 415.787133 -322.159446) (xy 415.816595 -322.113599)
			(xy 415.852281 -322.072411) (xy 415.893465 -322.03672) (xy 415.939309 -322.007254) (xy 415.988879 -321.984611)
			(xy 416.041168 -321.969252) (xy 416.095109 -321.961491) (xy 416.122358 -321.961002) (xy 416.149857 -321.961476)
			(xy 416.204285 -321.969388) (xy 416.257014 -321.985025) (xy 416.306955 -322.008064) (xy 416.353075 -322.038029)
			(xy 416.394419 -322.0743) (xy 416.430133 -322.116126) (xy 416.459478 -322.162642) (xy 416.4711 -322.18757)
			(xy 416.476995 -322.199647) (xy 416.493947 -322.220485) (xy 416.515741 -322.236189) (xy 416.540873 -322.245674)
			(xy 416.567608 -322.248287) (xy 416.594101 -322.243847) (xy 416.606482 -322.238624) (xy 416.63165 -322.227563)
			(xy 416.684358 -322.211948) (xy 416.738762 -322.204055) (xy 416.766248 -322.203572) (xy 416.793496 -322.204102)
			(xy 416.847435 -322.211863) (xy 416.899721 -322.227222) (xy 416.94929 -322.249864) (xy 416.995132 -322.27933)
			(xy 417.036314 -322.31502) (xy 417.071999 -322.356207) (xy 417.101459 -322.402052) (xy 417.124095 -322.451624)
			(xy 417.139447 -322.503912) (xy 417.147202 -322.557852) (xy 417.147202 -322.612348) (xy 417.139447 -322.666288)
			(xy 417.124095 -322.718576) (xy 417.101459 -322.768148) (xy 417.071999 -322.813993) (xy 417.036314 -322.85518)
			(xy 416.995132 -322.89087) (xy 416.94929 -322.920336) (xy 416.899721 -322.942978) (xy 416.847435 -322.958337)
			(xy 416.793496 -322.966098) (xy 416.766248 -322.966588) (xy 416.738748 -322.966115) (xy 416.684321 -322.958204)
			(xy 416.631591 -322.942567) (xy 416.58165 -322.919527) (xy 416.53553 -322.889562) (xy 416.494186 -322.853292)
			(xy 416.458472 -322.811465) (xy 416.429128 -322.764948) (xy 416.417506 -322.74002) (xy 416.411719 -322.727884)
			(xy 416.394745 -322.707041) (xy 416.372927 -322.691339) (xy 416.347772 -322.681863) (xy 416.321017 -322.679267)
			(xy 416.294509 -322.68373) (xy 416.282124 -322.688966) (xy 416.256955 -322.700024) (xy 416.204247 -322.715641)
			(xy 416.149844 -322.723535) (xy 416.122358 -322.724018) (xy 416.095109 -322.723509) (xy 416.041168 -322.715748)
			(xy 415.988879 -322.700389) (xy 415.939309 -322.677746) (xy 415.893465 -322.64828) (xy 415.852281 -322.612589)
			(xy 415.816595 -322.571401) (xy 415.787133 -322.525554) (xy 415.764496 -322.475981) (xy 415.749143 -322.423691)
			(xy 415.741388 -322.369749) (xy 402.159978 -322.369749) (xy 402.159978 -323.3786) (xy 406.395968 -323.3786)
			(xy 406.399951 -323.325451) (xy 406.41181 -323.27349) (xy 406.43128 -323.223876) (xy 406.457927 -323.177717)
			(xy 406.491155 -323.136046) (xy 406.530222 -323.099791) (xy 406.574256 -323.069764) (xy 406.622274 -323.046634)
			(xy 406.673202 -323.030919) (xy 406.725903 -323.022969) (xy 406.752552 -323.022468) (xy 406.778523 -323.02292)
			(xy 406.829916 -323.030456) (xy 406.87967 -323.045376) (xy 406.926729 -323.067363) (xy 406.970097 -323.095951)
			(xy 406.989788 -323.112892) (xy 407.001182 -323.12238) (xy 407.02803 -323.134929) (xy 407.057352 -323.139233)
			(xy 407.086674 -323.134929) (xy 407.113522 -323.12238) (xy 407.124916 -323.112892) (xy 407.144627 -323.095977)
			(xy 407.187993 -323.067395) (xy 407.235048 -323.045409) (xy 407.284796 -323.030486) (xy 407.336183 -323.022941)
			(xy 407.362152 -323.022468) (xy 407.388804 -323.022986) (xy 407.441513 -323.030924) (xy 407.492449 -323.04663)
			(xy 407.540476 -323.069752) (xy 407.58452 -323.099776) (xy 407.623597 -323.136028) (xy 407.656833 -323.1777)
			(xy 407.683487 -323.223861) (xy 407.702962 -323.273479) (xy 407.714824 -323.325446) (xy 407.718808 -323.3786)
			(xy 407.715 -323.4294) (xy 410.129768 -323.4294) (xy 410.133751 -323.376251) (xy 410.14561 -323.32429)
			(xy 410.16508 -323.274676) (xy 410.191727 -323.228517) (xy 410.224955 -323.186846) (xy 410.264022 -323.150591)
			(xy 410.308056 -323.120564) (xy 410.356074 -323.097434) (xy 410.407002 -323.081719) (xy 410.459703 -323.073769)
			(xy 410.486352 -323.073268) (xy 410.512759 -323.07379) (xy 410.564995 -323.081584) (xy 410.615507 -323.097008)
			(xy 410.663187 -323.119723) (xy 410.706988 -323.149232) (xy 410.745951 -323.184887) (xy 410.762958 -323.205094)
			(xy 410.772895 -323.216487) (xy 410.797948 -323.233378) (xy 410.826844 -323.242209) (xy 410.85706 -323.242209)
			(xy 410.885956 -323.233378) (xy 410.911009 -323.216487) (xy 410.920946 -323.205094) (xy 410.937972 -323.184902)
			(xy 410.976929 -323.149239) (xy 411.020725 -323.119721) (xy 411.0684 -323.096994) (xy 411.11891 -323.081558)
			(xy 411.171144 -323.073751) (xy 411.197552 -323.073268) (xy 411.224204 -323.073786) (xy 411.276913 -323.081724)
			(xy 411.327849 -323.09743) (xy 411.375876 -323.120552) (xy 411.41992 -323.150576) (xy 411.458997 -323.186828)
			(xy 411.492233 -323.2285) (xy 411.518887 -323.274661) (xy 411.538362 -323.324279) (xy 411.550224 -323.376246)
			(xy 411.554208 -323.4294) (xy 413.609568 -323.4294) (xy 413.613551 -323.376251) (xy 413.62541 -323.32429)
			(xy 413.64488 -323.274676) (xy 413.671527 -323.228517) (xy 413.704755 -323.186846) (xy 413.743822 -323.150591)
			(xy 413.787856 -323.120564) (xy 413.835874 -323.097434) (xy 413.886802 -323.081719) (xy 413.939503 -323.073769)
			(xy 413.966152 -323.073268) (xy 413.992559 -323.07379) (xy 414.044795 -323.081584) (xy 414.095307 -323.097008)
			(xy 414.142987 -323.119723) (xy 414.186788 -323.149232) (xy 414.225751 -323.184887) (xy 414.242758 -323.205094)
			(xy 414.252695 -323.216487) (xy 414.277748 -323.233378) (xy 414.306644 -323.242209) (xy 414.33686 -323.242209)
			(xy 414.365756 -323.233378) (xy 414.390809 -323.216487) (xy 414.400746 -323.205094) (xy 414.417772 -323.184902)
			(xy 414.456729 -323.149239) (xy 414.500525 -323.119721) (xy 414.5482 -323.096994) (xy 414.59871 -323.081558)
			(xy 414.650944 -323.073751) (xy 414.677352 -323.073268) (xy 414.704004 -323.073786) (xy 414.756713 -323.081724)
			(xy 414.807649 -323.09743) (xy 414.855676 -323.120552) (xy 414.89972 -323.150576) (xy 414.938797 -323.186828)
			(xy 414.972033 -323.2285) (xy 414.998687 -323.274661) (xy 415.018162 -323.324279) (xy 415.030024 -323.376246)
			(xy 415.034008 -323.4294) (xy 417.673568 -323.4294) (xy 417.677551 -323.376251) (xy 417.68941 -323.32429)
			(xy 417.70888 -323.274676) (xy 417.735527 -323.228517) (xy 417.768755 -323.186846) (xy 417.807822 -323.150591)
			(xy 417.851856 -323.120564) (xy 417.899874 -323.097434) (xy 417.950802 -323.081719) (xy 418.003503 -323.073769)
			(xy 418.030152 -323.073268) (xy 418.056559 -323.07379) (xy 418.108795 -323.081584) (xy 418.159307 -323.097008)
			(xy 418.206987 -323.119723) (xy 418.250788 -323.149232) (xy 418.289751 -323.184887) (xy 418.306758 -323.205094)
			(xy 418.316695 -323.216487) (xy 418.341748 -323.233378) (xy 418.370644 -323.242209) (xy 418.40086 -323.242209)
			(xy 418.429756 -323.233378) (xy 418.454809 -323.216487) (xy 418.464746 -323.205094) (xy 418.481772 -323.184902)
			(xy 418.520729 -323.149239) (xy 418.564525 -323.119721) (xy 418.6122 -323.096994) (xy 418.66271 -323.081558)
			(xy 418.714944 -323.073751) (xy 418.741352 -323.073268) (xy 418.768004 -323.073786) (xy 418.820713 -323.081724)
			(xy 418.871649 -323.09743) (xy 418.919676 -323.120552) (xy 418.96372 -323.150576) (xy 419.002797 -323.186828)
			(xy 419.036033 -323.2285) (xy 419.062687 -323.274661) (xy 419.082162 -323.324279) (xy 419.094024 -323.376246)
			(xy 419.098008 -323.4294) (xy 421.153368 -323.4294) (xy 421.157351 -323.376251) (xy 421.16921 -323.32429)
			(xy 421.18868 -323.274676) (xy 421.215327 -323.228517) (xy 421.248555 -323.186846) (xy 421.287622 -323.150591)
			(xy 421.331656 -323.120564) (xy 421.379674 -323.097434) (xy 421.430602 -323.081719) (xy 421.483303 -323.073769)
			(xy 421.509952 -323.073268) (xy 421.536359 -323.07379) (xy 421.588595 -323.081584) (xy 421.639107 -323.097008)
			(xy 421.686787 -323.119723) (xy 421.730588 -323.149232) (xy 421.769551 -323.184887) (xy 421.786558 -323.205094)
			(xy 421.796495 -323.216487) (xy 421.821548 -323.233378) (xy 421.850444 -323.242209) (xy 421.88066 -323.242209)
			(xy 421.909556 -323.233378) (xy 421.934609 -323.216487) (xy 421.944546 -323.205094) (xy 421.961572 -323.184902)
			(xy 422.000529 -323.149239) (xy 422.044325 -323.119721) (xy 422.092 -323.096994) (xy 422.14251 -323.081558)
			(xy 422.194744 -323.073751) (xy 422.221152 -323.073268) (xy 422.247804 -323.073786) (xy 422.300513 -323.081724)
			(xy 422.351449 -323.09743) (xy 422.399476 -323.120552) (xy 422.44352 -323.150576) (xy 422.482597 -323.186828)
			(xy 422.515833 -323.2285) (xy 422.542487 -323.274661) (xy 422.561962 -323.324279) (xy 422.573824 -323.376246)
			(xy 422.577808 -323.4294) (xy 425.217368 -323.4294) (xy 425.221351 -323.376251) (xy 425.23321 -323.32429)
			(xy 425.25268 -323.274676) (xy 425.279327 -323.228517) (xy 425.312555 -323.186846) (xy 425.351622 -323.150591)
			(xy 425.395656 -323.120564) (xy 425.443674 -323.097434) (xy 425.494602 -323.081719) (xy 425.547303 -323.073769)
			(xy 425.573952 -323.073268) (xy 425.600359 -323.07379) (xy 425.652595 -323.081584) (xy 425.703107 -323.097008)
			(xy 425.750787 -323.119723) (xy 425.794588 -323.149232) (xy 425.833551 -323.184887) (xy 425.850558 -323.205094)
			(xy 425.860495 -323.216487) (xy 425.885548 -323.233378) (xy 425.914444 -323.242209) (xy 425.94466 -323.242209)
			(xy 425.973556 -323.233378) (xy 425.998609 -323.216487) (xy 426.008546 -323.205094) (xy 426.025572 -323.184902)
			(xy 426.064529 -323.149239) (xy 426.108325 -323.119721) (xy 426.156 -323.096994) (xy 426.20651 -323.081558)
			(xy 426.258744 -323.073751) (xy 426.285152 -323.073268) (xy 426.311804 -323.073786) (xy 426.364513 -323.081724)
			(xy 426.415449 -323.09743) (xy 426.463476 -323.120552) (xy 426.50752 -323.150576) (xy 426.546597 -323.186828)
			(xy 426.579833 -323.2285) (xy 426.606487 -323.274661) (xy 426.625962 -323.324279) (xy 426.637824 -323.376246)
			(xy 426.641808 -323.4294) (xy 428.697168 -323.4294) (xy 428.701151 -323.376251) (xy 428.71301 -323.32429)
			(xy 428.73248 -323.274676) (xy 428.759127 -323.228517) (xy 428.792355 -323.186846) (xy 428.831422 -323.150591)
			(xy 428.875456 -323.120564) (xy 428.923474 -323.097434) (xy 428.974402 -323.081719) (xy 429.027103 -323.073769)
			(xy 429.053752 -323.073268) (xy 429.080159 -323.07379) (xy 429.132395 -323.081584) (xy 429.182907 -323.097008)
			(xy 429.230587 -323.119723) (xy 429.274388 -323.149232) (xy 429.313351 -323.184887) (xy 429.330358 -323.205094)
			(xy 429.340295 -323.216487) (xy 429.365348 -323.233378) (xy 429.394244 -323.242209) (xy 429.42446 -323.242209)
			(xy 429.453356 -323.233378) (xy 429.478409 -323.216487) (xy 429.488346 -323.205094) (xy 429.505372 -323.184902)
			(xy 429.544329 -323.149239) (xy 429.588125 -323.119721) (xy 429.6358 -323.096994) (xy 429.68631 -323.081558)
			(xy 429.738544 -323.073751) (xy 429.764952 -323.073268) (xy 429.791604 -323.073786) (xy 429.844313 -323.081724)
			(xy 429.895249 -323.09743) (xy 429.943276 -323.120552) (xy 429.98732 -323.150576) (xy 430.026397 -323.186828)
			(xy 430.059633 -323.2285) (xy 430.086287 -323.274661) (xy 430.105762 -323.324279) (xy 430.117624 -323.376246)
			(xy 430.121608 -323.4294) (xy 432.761168 -323.4294) (xy 432.765151 -323.376251) (xy 432.77701 -323.32429)
			(xy 432.79648 -323.274676) (xy 432.823127 -323.228517) (xy 432.856355 -323.186846) (xy 432.895422 -323.150591)
			(xy 432.939456 -323.120564) (xy 432.987474 -323.097434) (xy 433.038402 -323.081719) (xy 433.091103 -323.073769)
			(xy 433.117752 -323.073268) (xy 433.144314 -323.073727) (xy 433.196845 -323.081638) (xy 433.24762 -323.097261)
			(xy 433.295512 -323.12025) (xy 433.339459 -323.150096) (xy 433.359306 -323.167756) (xy 433.370108 -323.177123)
			(xy 433.395674 -323.189907) (xy 433.423782 -323.195102) (xy 433.452228 -323.192301) (xy 433.478783 -323.181724)
			(xy 433.49037 -323.173344) (xy 433.513938 -323.155803) (xy 433.565646 -323.127918) (xy 433.62123 -323.1089)
			(xy 433.679182 -323.099265) (xy 433.708556 -323.098668) (xy 433.735208 -323.099186) (xy 433.787916 -323.107125)
			(xy 433.838852 -323.122831) (xy 433.886879 -323.145954) (xy 433.930922 -323.175977) (xy 433.969998 -323.21223)
			(xy 434.003234 -323.253902) (xy 434.029887 -323.300062) (xy 434.049362 -323.34968) (xy 434.061224 -323.401646)
			(xy 434.063304 -323.4294) (xy 436.240968 -323.4294) (xy 436.244951 -323.376251) (xy 436.25681 -323.32429)
			(xy 436.27628 -323.274676) (xy 436.302927 -323.228517) (xy 436.336155 -323.186846) (xy 436.375222 -323.150591)
			(xy 436.419256 -323.120564) (xy 436.467274 -323.097434) (xy 436.518202 -323.081719) (xy 436.570903 -323.073769)
			(xy 436.597552 -323.073268) (xy 436.623959 -323.07379) (xy 436.676195 -323.081584) (xy 436.726707 -323.097008)
			(xy 436.774387 -323.119723) (xy 436.818188 -323.149232) (xy 436.857151 -323.184887) (xy 436.874158 -323.205094)
			(xy 436.884095 -323.216487) (xy 436.909148 -323.233378) (xy 436.938044 -323.242209) (xy 436.96826 -323.242209)
			(xy 436.997156 -323.233378) (xy 437.022209 -323.216487) (xy 437.032146 -323.205094) (xy 437.049172 -323.184902)
			(xy 437.088129 -323.149239) (xy 437.131925 -323.119721) (xy 437.1796 -323.096994) (xy 437.23011 -323.081558)
			(xy 437.282344 -323.073751) (xy 437.308752 -323.073268) (xy 437.335404 -323.073786) (xy 437.388113 -323.081724)
			(xy 437.439049 -323.09743) (xy 437.487076 -323.120552) (xy 437.53112 -323.150576) (xy 437.570197 -323.186828)
			(xy 437.603433 -323.2285) (xy 437.630087 -323.274661) (xy 437.649562 -323.324279) (xy 437.661424 -323.376246)
			(xy 437.665408 -323.4294) (xy 440.304968 -323.4294) (xy 440.308951 -323.376251) (xy 440.32081 -323.32429)
			(xy 440.34028 -323.274676) (xy 440.366927 -323.228517) (xy 440.400155 -323.186846) (xy 440.439222 -323.150591)
			(xy 440.483256 -323.120564) (xy 440.531274 -323.097434) (xy 440.582202 -323.081719) (xy 440.634903 -323.073769)
			(xy 440.661552 -323.073268) (xy 440.687959 -323.07379) (xy 440.740195 -323.081584) (xy 440.790707 -323.097008)
			(xy 440.838387 -323.119723) (xy 440.882188 -323.149232) (xy 440.921151 -323.184887) (xy 440.938158 -323.205094)
			(xy 440.948095 -323.216487) (xy 440.973148 -323.233378) (xy 441.002044 -323.242209) (xy 441.03226 -323.242209)
			(xy 441.061156 -323.233378) (xy 441.086209 -323.216487) (xy 441.096146 -323.205094) (xy 441.113172 -323.184902)
			(xy 441.152129 -323.149239) (xy 441.195925 -323.119721) (xy 441.2436 -323.096994) (xy 441.29411 -323.081558)
			(xy 441.346344 -323.073751) (xy 441.372752 -323.073268) (xy 441.399404 -323.073786) (xy 441.452113 -323.081724)
			(xy 441.503049 -323.09743) (xy 441.551076 -323.120552) (xy 441.59512 -323.150576) (xy 441.634197 -323.186828)
			(xy 441.667433 -323.2285) (xy 441.694087 -323.274661) (xy 441.713562 -323.324279) (xy 441.725424 -323.376246)
			(xy 441.729408 -323.4294) (xy 443.784768 -323.4294) (xy 443.788751 -323.376251) (xy 443.80061 -323.32429)
			(xy 443.82008 -323.274676) (xy 443.846727 -323.228517) (xy 443.879955 -323.186846) (xy 443.919022 -323.150591)
			(xy 443.963056 -323.120564) (xy 444.011074 -323.097434) (xy 444.062002 -323.081719) (xy 444.114703 -323.073769)
			(xy 444.141352 -323.073268) (xy 444.167759 -323.07379) (xy 444.219995 -323.081584) (xy 444.270507 -323.097008)
			(xy 444.318187 -323.119723) (xy 444.361988 -323.149232) (xy 444.400951 -323.184887) (xy 444.417958 -323.205094)
			(xy 444.427895 -323.216487) (xy 444.452948 -323.233378) (xy 444.481844 -323.242209) (xy 444.51206 -323.242209)
			(xy 444.540956 -323.233378) (xy 444.566009 -323.216487) (xy 444.575946 -323.205094) (xy 444.592972 -323.184902)
			(xy 444.631929 -323.149239) (xy 444.675725 -323.119721) (xy 444.7234 -323.096994) (xy 444.77391 -323.081558)
			(xy 444.826144 -323.073751) (xy 444.852552 -323.073268) (xy 444.879204 -323.073786) (xy 444.931913 -323.081724)
			(xy 444.982849 -323.09743) (xy 445.030876 -323.120552) (xy 445.07492 -323.150576) (xy 445.113997 -323.186828)
			(xy 445.147233 -323.2285) (xy 445.173887 -323.274661) (xy 445.193362 -323.324279) (xy 445.205224 -323.376246)
			(xy 445.209208 -323.4294) (xy 447.848768 -323.4294) (xy 447.852751 -323.376251) (xy 447.86461 -323.32429)
			(xy 447.88408 -323.274676) (xy 447.910727 -323.228517) (xy 447.943955 -323.186846) (xy 447.983022 -323.150591)
			(xy 448.027056 -323.120564) (xy 448.075074 -323.097434) (xy 448.126002 -323.081719) (xy 448.178703 -323.073769)
			(xy 448.205352 -323.073268) (xy 448.231759 -323.07379) (xy 448.283995 -323.081584) (xy 448.334507 -323.097008)
			(xy 448.382187 -323.119723) (xy 448.425988 -323.149232) (xy 448.464951 -323.184887) (xy 448.481958 -323.205094)
			(xy 448.491895 -323.216487) (xy 448.516948 -323.233378) (xy 448.545844 -323.242209) (xy 448.57606 -323.242209)
			(xy 448.604956 -323.233378) (xy 448.630009 -323.216487) (xy 448.639946 -323.205094) (xy 448.656972 -323.184902)
			(xy 448.695929 -323.149239) (xy 448.739725 -323.119721) (xy 448.7874 -323.096994) (xy 448.83791 -323.081558)
			(xy 448.890144 -323.073751) (xy 448.916552 -323.073268) (xy 448.943204 -323.073786) (xy 448.995913 -323.081724)
			(xy 449.046849 -323.09743) (xy 449.094876 -323.120552) (xy 449.13892 -323.150576) (xy 449.177997 -323.186828)
			(xy 449.211233 -323.2285) (xy 449.237887 -323.274661) (xy 449.257362 -323.324279) (xy 449.269224 -323.376246)
			(xy 449.273208 -323.4294) (xy 451.328568 -323.4294) (xy 451.332551 -323.376251) (xy 451.34441 -323.32429)
			(xy 451.36388 -323.274676) (xy 451.390527 -323.228517) (xy 451.423755 -323.186846) (xy 451.462822 -323.150591)
			(xy 451.506856 -323.120564) (xy 451.554874 -323.097434) (xy 451.605802 -323.081719) (xy 451.658503 -323.073769)
			(xy 451.685152 -323.073268) (xy 451.711559 -323.07379) (xy 451.763795 -323.081584) (xy 451.814307 -323.097008)
			(xy 451.861987 -323.119723) (xy 451.905788 -323.149232) (xy 451.944751 -323.184887) (xy 451.961758 -323.205094)
			(xy 451.971695 -323.216487) (xy 451.996748 -323.233378) (xy 452.025644 -323.242209) (xy 452.05586 -323.242209)
			(xy 452.084756 -323.233378) (xy 452.109809 -323.216487) (xy 452.119746 -323.205094) (xy 452.136772 -323.184902)
			(xy 452.175729 -323.149239) (xy 452.219525 -323.119721) (xy 452.2672 -323.096994) (xy 452.31771 -323.081558)
			(xy 452.369944 -323.073751) (xy 452.396352 -323.073268) (xy 452.423004 -323.073786) (xy 452.475713 -323.081724)
			(xy 452.526649 -323.09743) (xy 452.574676 -323.120552) (xy 452.61872 -323.150576) (xy 452.657797 -323.186828)
			(xy 452.691033 -323.2285) (xy 452.717687 -323.274661) (xy 452.737162 -323.324279) (xy 452.749024 -323.376246)
			(xy 452.753008 -323.4294) (xy 455.392568 -323.4294) (xy 455.396551 -323.376251) (xy 455.40841 -323.32429)
			(xy 455.42788 -323.274676) (xy 455.454527 -323.228517) (xy 455.487755 -323.186846) (xy 455.526822 -323.150591)
			(xy 455.570856 -323.120564) (xy 455.618874 -323.097434) (xy 455.669802 -323.081719) (xy 455.722503 -323.073769)
			(xy 455.749152 -323.073268) (xy 455.775559 -323.07379) (xy 455.827795 -323.081584) (xy 455.878307 -323.097008)
			(xy 455.925987 -323.119723) (xy 455.969788 -323.149232) (xy 456.008751 -323.184887) (xy 456.025758 -323.205094)
			(xy 456.035695 -323.216487) (xy 456.060748 -323.233378) (xy 456.089644 -323.242209) (xy 456.11986 -323.242209)
			(xy 456.148756 -323.233378) (xy 456.173809 -323.216487) (xy 456.183746 -323.205094) (xy 456.200772 -323.184902)
			(xy 456.239729 -323.149239) (xy 456.283525 -323.119721) (xy 456.3312 -323.096994) (xy 456.38171 -323.081558)
			(xy 456.433944 -323.073751) (xy 456.460352 -323.073268) (xy 456.487004 -323.073786) (xy 456.539713 -323.081724)
			(xy 456.590649 -323.09743) (xy 456.638676 -323.120552) (xy 456.68272 -323.150576) (xy 456.721797 -323.186828)
			(xy 456.755033 -323.2285) (xy 456.781687 -323.274661) (xy 456.801162 -323.324279) (xy 456.813024 -323.376246)
			(xy 456.817008 -323.4294) (xy 458.872368 -323.4294) (xy 458.876351 -323.376251) (xy 458.88821 -323.32429)
			(xy 458.90768 -323.274676) (xy 458.934327 -323.228517) (xy 458.967555 -323.186846) (xy 459.006622 -323.150591)
			(xy 459.050656 -323.120564) (xy 459.098674 -323.097434) (xy 459.149602 -323.081719) (xy 459.202303 -323.073769)
			(xy 459.228952 -323.073268) (xy 459.255359 -323.07379) (xy 459.307595 -323.081584) (xy 459.358107 -323.097008)
			(xy 459.405787 -323.119723) (xy 459.449588 -323.149232) (xy 459.488551 -323.184887) (xy 459.505558 -323.205094)
			(xy 459.515495 -323.216487) (xy 459.540548 -323.233378) (xy 459.569444 -323.242209) (xy 459.59966 -323.242209)
			(xy 459.628556 -323.233378) (xy 459.653609 -323.216487) (xy 459.663546 -323.205094) (xy 459.680572 -323.184902)
			(xy 459.719529 -323.149239) (xy 459.763325 -323.119721) (xy 459.811 -323.096994) (xy 459.86151 -323.081558)
			(xy 459.913744 -323.073751) (xy 459.940152 -323.073268) (xy 459.966804 -323.073786) (xy 460.019513 -323.081724)
			(xy 460.070449 -323.09743) (xy 460.118476 -323.120552) (xy 460.16252 -323.150576) (xy 460.201597 -323.186828)
			(xy 460.234833 -323.2285) (xy 460.261487 -323.274661) (xy 460.280962 -323.324279) (xy 460.287564 -323.3532)
			(xy 460.751968 -323.3532) (xy 460.755951 -323.300051) (xy 460.76781 -323.24809) (xy 460.78728 -323.198476)
			(xy 460.813927 -323.152317) (xy 460.847155 -323.110646) (xy 460.886222 -323.074391) (xy 460.930256 -323.044364)
			(xy 460.978274 -323.021234) (xy 461.029202 -323.005519) (xy 461.081903 -322.997569) (xy 461.108552 -322.997068)
			(xy 461.134959 -322.99759) (xy 461.187195 -323.005384) (xy 461.237707 -323.020808) (xy 461.285387 -323.043523)
			(xy 461.329188 -323.073032) (xy 461.368151 -323.108687) (xy 461.385158 -323.128894) (xy 461.395095 -323.140287)
			(xy 461.420148 -323.157178) (xy 461.449044 -323.166009) (xy 461.47926 -323.166009) (xy 461.508156 -323.157178)
			(xy 461.533209 -323.140287) (xy 461.543146 -323.128894) (xy 461.560172 -323.108702) (xy 461.599129 -323.073039)
			(xy 461.642925 -323.043521) (xy 461.6906 -323.020794) (xy 461.74111 -323.005358) (xy 461.793344 -322.997551)
			(xy 461.819752 -322.997068) (xy 461.846404 -322.997586) (xy 461.899113 -323.005524) (xy 461.950049 -323.02123)
			(xy 461.998076 -323.044352) (xy 462.04212 -323.074376) (xy 462.081197 -323.110628) (xy 462.114433 -323.1523)
			(xy 462.141087 -323.198461) (xy 462.160562 -323.248079) (xy 462.172424 -323.300046) (xy 462.176408 -323.3532)
			(xy 462.172424 -323.406354) (xy 462.160562 -323.458321) (xy 462.141087 -323.507939) (xy 462.114433 -323.5541)
			(xy 462.081197 -323.595772) (xy 462.04212 -323.632024) (xy 461.998076 -323.662048) (xy 461.950049 -323.68517)
			(xy 461.899113 -323.700876) (xy 461.846404 -323.708814) (xy 461.819752 -323.709284) (xy 461.793344 -323.708777)
			(xy 461.741107 -323.700982) (xy 461.690594 -323.685557) (xy 461.642914 -323.662838) (xy 461.599113 -323.633326)
			(xy 461.560152 -323.597667) (xy 461.543146 -323.577458) (xy 461.533209 -323.566065) (xy 461.508156 -323.549174)
			(xy 461.47926 -323.540343) (xy 461.449044 -323.540343) (xy 461.420148 -323.549174) (xy 461.395095 -323.566065)
			(xy 461.385158 -323.577458) (xy 461.368118 -323.597638) (xy 461.329166 -323.633304) (xy 461.285373 -323.662825)
			(xy 461.2377 -323.685554) (xy 461.187192 -323.700992) (xy 461.134959 -323.7088) (xy 461.108552 -323.709284)
			(xy 461.081903 -323.708831) (xy 461.029202 -323.700881) (xy 460.978274 -323.685166) (xy 460.930256 -323.662036)
			(xy 460.886222 -323.632009) (xy 460.847155 -323.595754) (xy 460.813927 -323.554083) (xy 460.78728 -323.507924)
			(xy 460.76781 -323.45831) (xy 460.755951 -323.406349) (xy 460.751968 -323.3532) (xy 460.287564 -323.3532)
			(xy 460.292824 -323.376246) (xy 460.296808 -323.4294) (xy 460.292824 -323.482554) (xy 460.280962 -323.534521)
			(xy 460.261487 -323.584139) (xy 460.234833 -323.6303) (xy 460.201597 -323.671972) (xy 460.16252 -323.708224)
			(xy 460.118476 -323.738248) (xy 460.070449 -323.76137) (xy 460.019513 -323.777076) (xy 459.966804 -323.785014)
			(xy 459.940152 -323.785484) (xy 459.913744 -323.784977) (xy 459.861507 -323.777182) (xy 459.810994 -323.761757)
			(xy 459.763314 -323.739038) (xy 459.719513 -323.709526) (xy 459.680552 -323.673867) (xy 459.663546 -323.653658)
			(xy 459.653609 -323.642265) (xy 459.628556 -323.625374) (xy 459.59966 -323.616543) (xy 459.569444 -323.616543)
			(xy 459.540548 -323.625374) (xy 459.515495 -323.642265) (xy 459.505558 -323.653658) (xy 459.488518 -323.673838)
			(xy 459.449566 -323.709504) (xy 459.405773 -323.739025) (xy 459.3581 -323.761754) (xy 459.307592 -323.777192)
			(xy 459.255359 -323.785) (xy 459.228952 -323.785484) (xy 459.202303 -323.785031) (xy 459.149602 -323.777081)
			(xy 459.098674 -323.761366) (xy 459.050656 -323.738236) (xy 459.006622 -323.708209) (xy 458.967555 -323.671954)
			(xy 458.934327 -323.630283) (xy 458.90768 -323.584124) (xy 458.88821 -323.53451) (xy 458.876351 -323.482549)
			(xy 458.872368 -323.4294) (xy 456.817008 -323.4294) (xy 456.813024 -323.482554) (xy 456.801162 -323.534521)
			(xy 456.781687 -323.584139) (xy 456.755033 -323.6303) (xy 456.721797 -323.671972) (xy 456.68272 -323.708224)
			(xy 456.638676 -323.738248) (xy 456.590649 -323.76137) (xy 456.539713 -323.777076) (xy 456.487004 -323.785014)
			(xy 456.460352 -323.785484) (xy 456.433944 -323.784977) (xy 456.381707 -323.777182) (xy 456.331194 -323.761757)
			(xy 456.283514 -323.739038) (xy 456.239713 -323.709526) (xy 456.200752 -323.673867) (xy 456.183746 -323.653658)
			(xy 456.173809 -323.642265) (xy 456.148756 -323.625374) (xy 456.11986 -323.616543) (xy 456.089644 -323.616543)
			(xy 456.060748 -323.625374) (xy 456.035695 -323.642265) (xy 456.025758 -323.653658) (xy 456.008718 -323.673838)
			(xy 455.969766 -323.709504) (xy 455.925973 -323.739025) (xy 455.8783 -323.761754) (xy 455.827792 -323.777192)
			(xy 455.775559 -323.785) (xy 455.749152 -323.785484) (xy 455.722503 -323.785031) (xy 455.669802 -323.777081)
			(xy 455.618874 -323.761366) (xy 455.570856 -323.738236) (xy 455.526822 -323.708209) (xy 455.487755 -323.671954)
			(xy 455.454527 -323.630283) (xy 455.42788 -323.584124) (xy 455.40841 -323.53451) (xy 455.396551 -323.482549)
			(xy 455.392568 -323.4294) (xy 452.753008 -323.4294) (xy 452.749024 -323.482554) (xy 452.737162 -323.534521)
			(xy 452.717687 -323.584139) (xy 452.691033 -323.6303) (xy 452.657797 -323.671972) (xy 452.61872 -323.708224)
			(xy 452.574676 -323.738248) (xy 452.526649 -323.76137) (xy 452.475713 -323.777076) (xy 452.423004 -323.785014)
			(xy 452.396352 -323.785484) (xy 452.369944 -323.784977) (xy 452.317707 -323.777182) (xy 452.267194 -323.761757)
			(xy 452.219514 -323.739038) (xy 452.175713 -323.709526) (xy 452.136752 -323.673867) (xy 452.119746 -323.653658)
			(xy 452.109809 -323.642265) (xy 452.084756 -323.625374) (xy 452.05586 -323.616543) (xy 452.025644 -323.616543)
			(xy 451.996748 -323.625374) (xy 451.971695 -323.642265) (xy 451.961758 -323.653658) (xy 451.944718 -323.673838)
			(xy 451.905766 -323.709504) (xy 451.861973 -323.739025) (xy 451.8143 -323.761754) (xy 451.763792 -323.777192)
			(xy 451.711559 -323.785) (xy 451.685152 -323.785484) (xy 451.658503 -323.785031) (xy 451.605802 -323.777081)
			(xy 451.554874 -323.761366) (xy 451.506856 -323.738236) (xy 451.462822 -323.708209) (xy 451.423755 -323.671954)
			(xy 451.390527 -323.630283) (xy 451.36388 -323.584124) (xy 451.34441 -323.53451) (xy 451.332551 -323.482549)
			(xy 451.328568 -323.4294) (xy 449.273208 -323.4294) (xy 449.269224 -323.482554) (xy 449.257362 -323.534521)
			(xy 449.237887 -323.584139) (xy 449.211233 -323.6303) (xy 449.177997 -323.671972) (xy 449.13892 -323.708224)
			(xy 449.094876 -323.738248) (xy 449.046849 -323.76137) (xy 448.995913 -323.777076) (xy 448.943204 -323.785014)
			(xy 448.916552 -323.785484) (xy 448.890144 -323.784977) (xy 448.837907 -323.777182) (xy 448.787394 -323.761757)
			(xy 448.739714 -323.739038) (xy 448.695913 -323.709526) (xy 448.656952 -323.673867) (xy 448.639946 -323.653658)
			(xy 448.630009 -323.642265) (xy 448.604956 -323.625374) (xy 448.57606 -323.616543) (xy 448.545844 -323.616543)
			(xy 448.516948 -323.625374) (xy 448.491895 -323.642265) (xy 448.481958 -323.653658) (xy 448.464918 -323.673838)
			(xy 448.425966 -323.709504) (xy 448.382173 -323.739025) (xy 448.3345 -323.761754) (xy 448.283992 -323.777192)
			(xy 448.231759 -323.785) (xy 448.205352 -323.785484) (xy 448.178703 -323.785031) (xy 448.126002 -323.777081)
			(xy 448.075074 -323.761366) (xy 448.027056 -323.738236) (xy 447.983022 -323.708209) (xy 447.943955 -323.671954)
			(xy 447.910727 -323.630283) (xy 447.88408 -323.584124) (xy 447.86461 -323.53451) (xy 447.852751 -323.482549)
			(xy 447.848768 -323.4294) (xy 445.209208 -323.4294) (xy 445.205224 -323.482554) (xy 445.193362 -323.534521)
			(xy 445.173887 -323.584139) (xy 445.147233 -323.6303) (xy 445.113997 -323.671972) (xy 445.07492 -323.708224)
			(xy 445.030876 -323.738248) (xy 444.982849 -323.76137) (xy 444.931913 -323.777076) (xy 444.879204 -323.785014)
			(xy 444.852552 -323.785484) (xy 444.826144 -323.784977) (xy 444.773907 -323.777182) (xy 444.723394 -323.761757)
			(xy 444.675714 -323.739038) (xy 444.631913 -323.709526) (xy 444.592952 -323.673867) (xy 444.575946 -323.653658)
			(xy 444.566009 -323.642265) (xy 444.540956 -323.625374) (xy 444.51206 -323.616543) (xy 444.481844 -323.616543)
			(xy 444.452948 -323.625374) (xy 444.427895 -323.642265) (xy 444.417958 -323.653658) (xy 444.400918 -323.673838)
			(xy 444.361966 -323.709504) (xy 444.318173 -323.739025) (xy 444.2705 -323.761754) (xy 444.219992 -323.777192)
			(xy 444.167759 -323.785) (xy 444.141352 -323.785484) (xy 444.114703 -323.785031) (xy 444.062002 -323.777081)
			(xy 444.011074 -323.761366) (xy 443.963056 -323.738236) (xy 443.919022 -323.708209) (xy 443.879955 -323.671954)
			(xy 443.846727 -323.630283) (xy 443.82008 -323.584124) (xy 443.80061 -323.53451) (xy 443.788751 -323.482549)
			(xy 443.784768 -323.4294) (xy 441.729408 -323.4294) (xy 441.725424 -323.482554) (xy 441.713562 -323.534521)
			(xy 441.694087 -323.584139) (xy 441.667433 -323.6303) (xy 441.634197 -323.671972) (xy 441.59512 -323.708224)
			(xy 441.551076 -323.738248) (xy 441.503049 -323.76137) (xy 441.452113 -323.777076) (xy 441.399404 -323.785014)
			(xy 441.372752 -323.785484) (xy 441.346344 -323.784977) (xy 441.294107 -323.777182) (xy 441.243594 -323.761757)
			(xy 441.195914 -323.739038) (xy 441.152113 -323.709526) (xy 441.113152 -323.673867) (xy 441.096146 -323.653658)
			(xy 441.086209 -323.642265) (xy 441.061156 -323.625374) (xy 441.03226 -323.616543) (xy 441.002044 -323.616543)
			(xy 440.973148 -323.625374) (xy 440.948095 -323.642265) (xy 440.938158 -323.653658) (xy 440.921118 -323.673838)
			(xy 440.882166 -323.709504) (xy 440.838373 -323.739025) (xy 440.7907 -323.761754) (xy 440.740192 -323.777192)
			(xy 440.687959 -323.785) (xy 440.661552 -323.785484) (xy 440.634903 -323.785031) (xy 440.582202 -323.777081)
			(xy 440.531274 -323.761366) (xy 440.483256 -323.738236) (xy 440.439222 -323.708209) (xy 440.400155 -323.671954)
			(xy 440.366927 -323.630283) (xy 440.34028 -323.584124) (xy 440.32081 -323.53451) (xy 440.308951 -323.482549)
			(xy 440.304968 -323.4294) (xy 437.665408 -323.4294) (xy 437.661424 -323.482554) (xy 437.649562 -323.534521)
			(xy 437.630087 -323.584139) (xy 437.603433 -323.6303) (xy 437.570197 -323.671972) (xy 437.53112 -323.708224)
			(xy 437.487076 -323.738248) (xy 437.439049 -323.76137) (xy 437.388113 -323.777076) (xy 437.335404 -323.785014)
			(xy 437.308752 -323.785484) (xy 437.282344 -323.784977) (xy 437.230107 -323.777182) (xy 437.179594 -323.761757)
			(xy 437.131914 -323.739038) (xy 437.088113 -323.709526) (xy 437.049152 -323.673867) (xy 437.032146 -323.653658)
			(xy 437.022209 -323.642265) (xy 436.997156 -323.625374) (xy 436.96826 -323.616543) (xy 436.938044 -323.616543)
			(xy 436.909148 -323.625374) (xy 436.884095 -323.642265) (xy 436.874158 -323.653658) (xy 436.857118 -323.673838)
			(xy 436.818166 -323.709504) (xy 436.774373 -323.739025) (xy 436.7267 -323.761754) (xy 436.676192 -323.777192)
			(xy 436.623959 -323.785) (xy 436.597552 -323.785484) (xy 436.570903 -323.785031) (xy 436.518202 -323.777081)
			(xy 436.467274 -323.761366) (xy 436.419256 -323.738236) (xy 436.375222 -323.708209) (xy 436.336155 -323.671954)
			(xy 436.302927 -323.630283) (xy 436.27628 -323.584124) (xy 436.25681 -323.53451) (xy 436.244951 -323.482549)
			(xy 436.240968 -323.4294) (xy 434.063304 -323.4294) (xy 434.065208 -323.4548) (xy 434.061224 -323.507954)
			(xy 434.049362 -323.55992) (xy 434.029887 -323.609538) (xy 434.003234 -323.655698) (xy 433.969998 -323.69737)
			(xy 433.930922 -323.733623) (xy 433.886879 -323.763646) (xy 433.838852 -323.786769) (xy 433.787916 -323.802475)
			(xy 433.735208 -323.810414) (xy 433.708556 -323.810884) (xy 433.681995 -323.810406) (xy 433.629465 -323.802498)
			(xy 433.578691 -323.786878) (xy 433.530799 -323.763894) (xy 433.48685 -323.734053) (xy 433.467002 -323.716396)
			(xy 433.456194 -323.707037) (xy 433.430629 -323.694259) (xy 433.402524 -323.689065) (xy 433.374081 -323.691863)
			(xy 433.347526 -323.702432) (xy 433.335938 -323.710808) (xy 433.312372 -323.728352) (xy 433.260663 -323.756235)
			(xy 433.205078 -323.775251) (xy 433.147126 -323.784886) (xy 433.117752 -323.785484) (xy 433.091103 -323.785031)
			(xy 433.038402 -323.777081) (xy 432.987474 -323.761366) (xy 432.939456 -323.738236) (xy 432.895422 -323.708209)
			(xy 432.856355 -323.671954) (xy 432.823127 -323.630283) (xy 432.79648 -323.584124) (xy 432.77701 -323.53451)
			(xy 432.765151 -323.482549) (xy 432.761168 -323.4294) (xy 430.121608 -323.4294) (xy 430.117624 -323.482554)
			(xy 430.105762 -323.534521) (xy 430.086287 -323.584139) (xy 430.059633 -323.6303) (xy 430.026397 -323.671972)
			(xy 429.98732 -323.708224) (xy 429.943276 -323.738248) (xy 429.895249 -323.76137) (xy 429.844313 -323.777076)
			(xy 429.791604 -323.785014) (xy 429.764952 -323.785484) (xy 429.738544 -323.784977) (xy 429.686307 -323.777182)
			(xy 429.635794 -323.761757) (xy 429.588114 -323.739038) (xy 429.544313 -323.709526) (xy 429.505352 -323.673867)
			(xy 429.488346 -323.653658) (xy 429.478409 -323.642265) (xy 429.453356 -323.625374) (xy 429.42446 -323.616543)
			(xy 429.394244 -323.616543) (xy 429.365348 -323.625374) (xy 429.340295 -323.642265) (xy 429.330358 -323.653658)
			(xy 429.313318 -323.673838) (xy 429.274366 -323.709504) (xy 429.230573 -323.739025) (xy 429.1829 -323.761754)
			(xy 429.132392 -323.777192) (xy 429.080159 -323.785) (xy 429.053752 -323.785484) (xy 429.027103 -323.785031)
			(xy 428.974402 -323.777081) (xy 428.923474 -323.761366) (xy 428.875456 -323.738236) (xy 428.831422 -323.708209)
			(xy 428.792355 -323.671954) (xy 428.759127 -323.630283) (xy 428.73248 -323.584124) (xy 428.71301 -323.53451)
			(xy 428.701151 -323.482549) (xy 428.697168 -323.4294) (xy 426.641808 -323.4294) (xy 426.637824 -323.482554)
			(xy 426.625962 -323.534521) (xy 426.606487 -323.584139) (xy 426.579833 -323.6303) (xy 426.546597 -323.671972)
			(xy 426.50752 -323.708224) (xy 426.463476 -323.738248) (xy 426.415449 -323.76137) (xy 426.364513 -323.777076)
			(xy 426.311804 -323.785014) (xy 426.285152 -323.785484) (xy 426.258744 -323.784977) (xy 426.206507 -323.777182)
			(xy 426.155994 -323.761757) (xy 426.108314 -323.739038) (xy 426.064513 -323.709526) (xy 426.025552 -323.673867)
			(xy 426.008546 -323.653658) (xy 425.998609 -323.642265) (xy 425.973556 -323.625374) (xy 425.94466 -323.616543)
			(xy 425.914444 -323.616543) (xy 425.885548 -323.625374) (xy 425.860495 -323.642265) (xy 425.850558 -323.653658)
			(xy 425.833518 -323.673838) (xy 425.794566 -323.709504) (xy 425.750773 -323.739025) (xy 425.7031 -323.761754)
			(xy 425.652592 -323.777192) (xy 425.600359 -323.785) (xy 425.573952 -323.785484) (xy 425.547303 -323.785031)
			(xy 425.494602 -323.777081) (xy 425.443674 -323.761366) (xy 425.395656 -323.738236) (xy 425.351622 -323.708209)
			(xy 425.312555 -323.671954) (xy 425.279327 -323.630283) (xy 425.25268 -323.584124) (xy 425.23321 -323.53451)
			(xy 425.221351 -323.482549) (xy 425.217368 -323.4294) (xy 422.577808 -323.4294) (xy 422.573824 -323.482554)
			(xy 422.561962 -323.534521) (xy 422.542487 -323.584139) (xy 422.515833 -323.6303) (xy 422.482597 -323.671972)
			(xy 422.44352 -323.708224) (xy 422.399476 -323.738248) (xy 422.351449 -323.76137) (xy 422.300513 -323.777076)
			(xy 422.247804 -323.785014) (xy 422.221152 -323.785484) (xy 422.194744 -323.784977) (xy 422.142507 -323.777182)
			(xy 422.091994 -323.761757) (xy 422.044314 -323.739038) (xy 422.000513 -323.709526) (xy 421.961552 -323.673867)
			(xy 421.944546 -323.653658) (xy 421.934609 -323.642265) (xy 421.909556 -323.625374) (xy 421.88066 -323.616543)
			(xy 421.850444 -323.616543) (xy 421.821548 -323.625374) (xy 421.796495 -323.642265) (xy 421.786558 -323.653658)
			(xy 421.769518 -323.673838) (xy 421.730566 -323.709504) (xy 421.686773 -323.739025) (xy 421.6391 -323.761754)
			(xy 421.588592 -323.777192) (xy 421.536359 -323.785) (xy 421.509952 -323.785484) (xy 421.483303 -323.785031)
			(xy 421.430602 -323.777081) (xy 421.379674 -323.761366) (xy 421.331656 -323.738236) (xy 421.287622 -323.708209)
			(xy 421.248555 -323.671954) (xy 421.215327 -323.630283) (xy 421.18868 -323.584124) (xy 421.16921 -323.53451)
			(xy 421.157351 -323.482549) (xy 421.153368 -323.4294) (xy 419.098008 -323.4294) (xy 419.094024 -323.482554)
			(xy 419.082162 -323.534521) (xy 419.062687 -323.584139) (xy 419.036033 -323.6303) (xy 419.002797 -323.671972)
			(xy 418.96372 -323.708224) (xy 418.919676 -323.738248) (xy 418.871649 -323.76137) (xy 418.820713 -323.777076)
			(xy 418.768004 -323.785014) (xy 418.741352 -323.785484) (xy 418.714944 -323.784977) (xy 418.662707 -323.777182)
			(xy 418.612194 -323.761757) (xy 418.564514 -323.739038) (xy 418.520713 -323.709526) (xy 418.481752 -323.673867)
			(xy 418.464746 -323.653658) (xy 418.454809 -323.642265) (xy 418.429756 -323.625374) (xy 418.40086 -323.616543)
			(xy 418.370644 -323.616543) (xy 418.341748 -323.625374) (xy 418.316695 -323.642265) (xy 418.306758 -323.653658)
			(xy 418.289718 -323.673838) (xy 418.250766 -323.709504) (xy 418.206973 -323.739025) (xy 418.1593 -323.761754)
			(xy 418.108792 -323.777192) (xy 418.056559 -323.785) (xy 418.030152 -323.785484) (xy 418.003503 -323.785031)
			(xy 417.950802 -323.777081) (xy 417.899874 -323.761366) (xy 417.851856 -323.738236) (xy 417.807822 -323.708209)
			(xy 417.768755 -323.671954) (xy 417.735527 -323.630283) (xy 417.70888 -323.584124) (xy 417.68941 -323.53451)
			(xy 417.677551 -323.482549) (xy 417.673568 -323.4294) (xy 415.034008 -323.4294) (xy 415.030024 -323.482554)
			(xy 415.018162 -323.534521) (xy 414.998687 -323.584139) (xy 414.972033 -323.6303) (xy 414.938797 -323.671972)
			(xy 414.89972 -323.708224) (xy 414.855676 -323.738248) (xy 414.807649 -323.76137) (xy 414.756713 -323.777076)
			(xy 414.704004 -323.785014) (xy 414.677352 -323.785484) (xy 414.650944 -323.784977) (xy 414.598707 -323.777182)
			(xy 414.548194 -323.761757) (xy 414.500514 -323.739038) (xy 414.456713 -323.709526) (xy 414.417752 -323.673867)
			(xy 414.400746 -323.653658) (xy 414.390809 -323.642265) (xy 414.365756 -323.625374) (xy 414.33686 -323.616543)
			(xy 414.306644 -323.616543) (xy 414.277748 -323.625374) (xy 414.252695 -323.642265) (xy 414.242758 -323.653658)
			(xy 414.225718 -323.673838) (xy 414.186766 -323.709504) (xy 414.142973 -323.739025) (xy 414.0953 -323.761754)
			(xy 414.044792 -323.777192) (xy 413.992559 -323.785) (xy 413.966152 -323.785484) (xy 413.939503 -323.785031)
			(xy 413.886802 -323.777081) (xy 413.835874 -323.761366) (xy 413.787856 -323.738236) (xy 413.743822 -323.708209)
			(xy 413.704755 -323.671954) (xy 413.671527 -323.630283) (xy 413.64488 -323.584124) (xy 413.62541 -323.53451)
			(xy 413.613551 -323.482549) (xy 413.609568 -323.4294) (xy 411.554208 -323.4294) (xy 411.550224 -323.482554)
			(xy 411.538362 -323.534521) (xy 411.518887 -323.584139) (xy 411.492233 -323.6303) (xy 411.458997 -323.671972)
			(xy 411.41992 -323.708224) (xy 411.375876 -323.738248) (xy 411.327849 -323.76137) (xy 411.276913 -323.777076)
			(xy 411.224204 -323.785014) (xy 411.197552 -323.785484) (xy 411.171144 -323.784977) (xy 411.118907 -323.777182)
			(xy 411.068394 -323.761757) (xy 411.020714 -323.739038) (xy 410.976913 -323.709526) (xy 410.937952 -323.673867)
			(xy 410.920946 -323.653658) (xy 410.911009 -323.642265) (xy 410.885956 -323.625374) (xy 410.85706 -323.616543)
			(xy 410.826844 -323.616543) (xy 410.797948 -323.625374) (xy 410.772895 -323.642265) (xy 410.762958 -323.653658)
			(xy 410.745918 -323.673838) (xy 410.706966 -323.709504) (xy 410.663173 -323.739025) (xy 410.6155 -323.761754)
			(xy 410.564992 -323.777192) (xy 410.512759 -323.785) (xy 410.486352 -323.785484) (xy 410.459703 -323.785031)
			(xy 410.407002 -323.777081) (xy 410.356074 -323.761366) (xy 410.308056 -323.738236) (xy 410.264022 -323.708209)
			(xy 410.224955 -323.671954) (xy 410.191727 -323.630283) (xy 410.16508 -323.584124) (xy 410.14561 -323.53451)
			(xy 410.133751 -323.482549) (xy 410.129768 -323.4294) (xy 407.715 -323.4294) (xy 407.714824 -323.431754)
			(xy 407.702962 -323.483721) (xy 407.683487 -323.533339) (xy 407.656833 -323.5795) (xy 407.623597 -323.621172)
			(xy 407.58452 -323.657424) (xy 407.540476 -323.687448) (xy 407.492449 -323.71057) (xy 407.441513 -323.726276)
			(xy 407.388804 -323.734214) (xy 407.362152 -323.734684) (xy 407.336181 -323.734217) (xy 407.28479 -323.726682)
			(xy 407.235037 -323.711765) (xy 407.187977 -323.689782) (xy 407.144608 -323.661198) (xy 407.124916 -323.64426)
			(xy 407.113522 -323.634772) (xy 407.086674 -323.622223) (xy 407.057352 -323.617919) (xy 407.02803 -323.622223)
			(xy 407.001182 -323.634772) (xy 406.989788 -323.64426) (xy 406.970083 -323.661182) (xy 406.926714 -323.689761)
			(xy 406.879658 -323.711745) (xy 406.829909 -323.726667) (xy 406.778521 -323.734211) (xy 406.752552 -323.734684)
			(xy 406.725903 -323.734231) (xy 406.673202 -323.726281) (xy 406.622274 -323.710566) (xy 406.574256 -323.687436)
			(xy 406.530222 -323.657409) (xy 406.491155 -323.621154) (xy 406.457927 -323.579483) (xy 406.43128 -323.533324)
			(xy 406.41181 -323.48371) (xy 406.399951 -323.431749) (xy 406.395968 -323.3786) (xy 402.159978 -323.3786)
			(xy 402.159978 -327.10898) (xy 407.266521 -327.10898) (xy 407.266521 -327.02442) (xy 407.274324 -326.94022)
			(xy 407.289862 -326.857099) (xy 407.313004 -326.775767) (xy 407.343552 -326.696917) (xy 407.381245 -326.621222)
			(xy 407.425762 -326.549328) (xy 407.476723 -326.481848) (xy 407.533692 -326.419358) (xy 407.596185 -326.362392)
			(xy 407.663667 -326.311435) (xy 407.735564 -326.266922) (xy 407.811261 -326.229233) (xy 407.890112 -326.198689)
			(xy 407.971446 -326.175551) (xy 408.054567 -326.160017) (xy 408.138768 -326.152219) (xy 408.181048 -326.151748)
			(xy 409.425648 -326.151748) (xy 409.467921 -326.152326) (xy 409.552105 -326.160131) (xy 409.63521 -326.17567)
			(xy 409.716527 -326.198811) (xy 409.795362 -326.229355) (xy 409.871043 -326.267043) (xy 409.942923 -326.311553)
			(xy 410.010391 -326.362505) (xy 410.072869 -326.419465) (xy 410.129825 -326.481946) (xy 410.180774 -326.549416)
			(xy 410.22528 -326.621299) (xy 410.262964 -326.696982) (xy 410.293504 -326.775818) (xy 410.316641 -326.857136)
			(xy 410.332175 -326.940242) (xy 410.339976 -327.024427) (xy 410.339976 -327.108973) (xy 410.339975 -327.10898)
			(xy 414.810321 -327.10898) (xy 414.810321 -327.02442) (xy 414.818124 -326.94022) (xy 414.833662 -326.857099)
			(xy 414.856804 -326.775767) (xy 414.887352 -326.696917) (xy 414.925045 -326.621222) (xy 414.969562 -326.549328)
			(xy 415.020523 -326.481848) (xy 415.077492 -326.419358) (xy 415.139985 -326.362392) (xy 415.207467 -326.311435)
			(xy 415.279364 -326.266922) (xy 415.355061 -326.229233) (xy 415.433912 -326.198689) (xy 415.515246 -326.175551)
			(xy 415.598367 -326.160017) (xy 415.682568 -326.152219) (xy 415.724848 -326.151748) (xy 416.969448 -326.151748)
			(xy 417.011721 -326.152326) (xy 417.095905 -326.160131) (xy 417.17901 -326.17567) (xy 417.260327 -326.198811)
			(xy 417.339162 -326.229355) (xy 417.414843 -326.267043) (xy 417.486723 -326.311553) (xy 417.554191 -326.362505)
			(xy 417.616669 -326.419465) (xy 417.673625 -326.481946) (xy 417.724574 -326.549416) (xy 417.76908 -326.621299)
			(xy 417.806764 -326.696982) (xy 417.837304 -326.775818) (xy 417.860441 -326.857136) (xy 417.875975 -326.940242)
			(xy 417.883776 -327.024427) (xy 417.883776 -327.108973) (xy 417.883775 -327.10898) (xy 422.354121 -327.10898)
			(xy 422.354121 -327.02442) (xy 422.361924 -326.94022) (xy 422.377462 -326.857099) (xy 422.400604 -326.775767)
			(xy 422.431152 -326.696917) (xy 422.468845 -326.621222) (xy 422.513362 -326.549328) (xy 422.564323 -326.481848)
			(xy 422.621292 -326.419358) (xy 422.683785 -326.362392) (xy 422.751267 -326.311435) (xy 422.823164 -326.266922)
			(xy 422.898861 -326.229233) (xy 422.977712 -326.198689) (xy 423.059046 -326.175551) (xy 423.142167 -326.160017)
			(xy 423.226368 -326.152219) (xy 423.268648 -326.151748) (xy 424.513248 -326.151748) (xy 424.555521 -326.152326)
			(xy 424.639705 -326.160131) (xy 424.72281 -326.17567) (xy 424.804127 -326.198811) (xy 424.882962 -326.229355)
			(xy 424.958643 -326.267043) (xy 425.030523 -326.311553) (xy 425.097991 -326.362505) (xy 425.160469 -326.419465)
			(xy 425.217425 -326.481946) (xy 425.268374 -326.549416) (xy 425.31288 -326.621299) (xy 425.350564 -326.696982)
			(xy 425.381104 -326.775818) (xy 425.404241 -326.857136) (xy 425.419775 -326.940242) (xy 425.427576 -327.024427)
			(xy 425.427576 -327.108973) (xy 425.427575 -327.10898) (xy 429.897921 -327.10898) (xy 429.897921 -327.02442)
			(xy 429.905724 -326.94022) (xy 429.921262 -326.857099) (xy 429.944404 -326.775767) (xy 429.974952 -326.696917)
			(xy 430.012645 -326.621222) (xy 430.057162 -326.549328) (xy 430.108123 -326.481848) (xy 430.165092 -326.419358)
			(xy 430.227585 -326.362392) (xy 430.295067 -326.311435) (xy 430.366964 -326.266922) (xy 430.442661 -326.229233)
			(xy 430.521512 -326.198689) (xy 430.602846 -326.175551) (xy 430.685967 -326.160017) (xy 430.770168 -326.152219)
			(xy 430.812448 -326.151748) (xy 432.057048 -326.151748) (xy 432.099321 -326.152326) (xy 432.183505 -326.160131)
			(xy 432.26661 -326.17567) (xy 432.347927 -326.198811) (xy 432.426762 -326.229355) (xy 432.502443 -326.267043)
			(xy 432.574323 -326.311553) (xy 432.641791 -326.362505) (xy 432.704269 -326.419465) (xy 432.761225 -326.481946)
			(xy 432.812174 -326.549416) (xy 432.85668 -326.621299) (xy 432.894364 -326.696982) (xy 432.924904 -326.775818)
			(xy 432.948041 -326.857136) (xy 432.963575 -326.940242) (xy 432.971376 -327.024427) (xy 432.971376 -327.108973)
			(xy 432.971375 -327.10898) (xy 437.441721 -327.10898) (xy 437.441721 -327.02442) (xy 437.449524 -326.94022)
			(xy 437.465062 -326.857099) (xy 437.488204 -326.775767) (xy 437.518752 -326.696917) (xy 437.556445 -326.621222)
			(xy 437.600962 -326.549328) (xy 437.651923 -326.481848) (xy 437.708892 -326.419358) (xy 437.771385 -326.362392)
			(xy 437.838867 -326.311435) (xy 437.910764 -326.266922) (xy 437.986461 -326.229233) (xy 438.065312 -326.198689)
			(xy 438.146646 -326.175551) (xy 438.229767 -326.160017) (xy 438.313968 -326.152219) (xy 438.356248 -326.151748)
			(xy 439.600848 -326.151748) (xy 439.643121 -326.152326) (xy 439.727305 -326.160131) (xy 439.81041 -326.17567)
			(xy 439.891727 -326.198811) (xy 439.970562 -326.229355) (xy 440.046243 -326.267043) (xy 440.118123 -326.311553)
			(xy 440.185591 -326.362505) (xy 440.248069 -326.419465) (xy 440.305025 -326.481946) (xy 440.355974 -326.549416)
			(xy 440.40048 -326.621299) (xy 440.438164 -326.696982) (xy 440.468704 -326.775818) (xy 440.491841 -326.857136)
			(xy 440.507375 -326.940242) (xy 440.515176 -327.024427) (xy 440.515176 -327.108973) (xy 440.515175 -327.10898)
			(xy 444.985521 -327.10898) (xy 444.985521 -327.02442) (xy 444.993324 -326.94022) (xy 445.008862 -326.857099)
			(xy 445.032004 -326.775767) (xy 445.062552 -326.696917) (xy 445.100245 -326.621222) (xy 445.144762 -326.549328)
			(xy 445.195723 -326.481848) (xy 445.252692 -326.419358) (xy 445.315185 -326.362392) (xy 445.382667 -326.311435)
			(xy 445.454564 -326.266922) (xy 445.530261 -326.229233) (xy 445.609112 -326.198689) (xy 445.690446 -326.175551)
			(xy 445.773567 -326.160017) (xy 445.857768 -326.152219) (xy 445.900048 -326.151748) (xy 447.144648 -326.151748)
			(xy 447.186921 -326.152326) (xy 447.271105 -326.160131) (xy 447.35421 -326.17567) (xy 447.435527 -326.198811)
			(xy 447.514362 -326.229355) (xy 447.590043 -326.267043) (xy 447.661923 -326.311553) (xy 447.729391 -326.362505)
			(xy 447.791869 -326.419465) (xy 447.848825 -326.481946) (xy 447.899774 -326.549416) (xy 447.94428 -326.621299)
			(xy 447.981964 -326.696982) (xy 448.012504 -326.775818) (xy 448.035641 -326.857136) (xy 448.051175 -326.940242)
			(xy 448.058976 -327.024427) (xy 448.058976 -327.108973) (xy 448.058975 -327.10898) (xy 452.529321 -327.10898)
			(xy 452.529321 -327.02442) (xy 452.537124 -326.94022) (xy 452.552662 -326.857099) (xy 452.575804 -326.775767)
			(xy 452.606352 -326.696917) (xy 452.644045 -326.621222) (xy 452.688562 -326.549328) (xy 452.739523 -326.481848)
			(xy 452.796492 -326.419358) (xy 452.858985 -326.362392) (xy 452.926467 -326.311435) (xy 452.998364 -326.266922)
			(xy 453.074061 -326.229233) (xy 453.152912 -326.198689) (xy 453.234246 -326.175551) (xy 453.317367 -326.160017)
			(xy 453.401568 -326.152219) (xy 453.443848 -326.151748) (xy 454.688448 -326.151748) (xy 454.730721 -326.152326)
			(xy 454.814905 -326.160131) (xy 454.89801 -326.17567) (xy 454.979327 -326.198811) (xy 455.058162 -326.229355)
			(xy 455.133843 -326.267043) (xy 455.205723 -326.311553) (xy 455.273191 -326.362505) (xy 455.335669 -326.419465)
			(xy 455.392625 -326.481946) (xy 455.443574 -326.549416) (xy 455.48808 -326.621299) (xy 455.525764 -326.696982)
			(xy 455.556304 -326.775818) (xy 455.579441 -326.857136) (xy 455.594975 -326.940242) (xy 455.602776 -327.024427)
			(xy 455.602776 -327.108973) (xy 455.602775 -327.10898) (xy 460.073121 -327.10898) (xy 460.073121 -327.02442)
			(xy 460.080924 -326.94022) (xy 460.096462 -326.857099) (xy 460.119604 -326.775767) (xy 460.150152 -326.696917)
			(xy 460.187845 -326.621222) (xy 460.232362 -326.549328) (xy 460.283323 -326.481848) (xy 460.340292 -326.419358)
			(xy 460.402785 -326.362392) (xy 460.470267 -326.311435) (xy 460.542164 -326.266922) (xy 460.617861 -326.229233)
			(xy 460.696712 -326.198689) (xy 460.778046 -326.175551) (xy 460.861167 -326.160017) (xy 460.945368 -326.152219)
			(xy 460.987648 -326.151748) (xy 462.232248 -326.151748) (xy 462.274521 -326.152326) (xy 462.358705 -326.160131)
			(xy 462.44181 -326.17567) (xy 462.523127 -326.198811) (xy 462.601962 -326.229355) (xy 462.677643 -326.267043)
			(xy 462.749523 -326.311553) (xy 462.816991 -326.362505) (xy 462.879469 -326.419465) (xy 462.936425 -326.481946)
			(xy 462.987374 -326.549416) (xy 463.03188 -326.621299) (xy 463.069564 -326.696982) (xy 463.100104 -326.775818)
			(xy 463.123241 -326.857136) (xy 463.138775 -326.940242) (xy 463.146576 -327.024427) (xy 463.146576 -327.108973)
			(xy 463.138775 -327.193158) (xy 463.123241 -327.276264) (xy 463.100104 -327.357582) (xy 463.069564 -327.436418)
			(xy 463.03188 -327.512101) (xy 462.987374 -327.583984) (xy 462.936425 -327.651454) (xy 462.879469 -327.713935)
			(xy 462.816991 -327.770895) (xy 462.749524 -327.821847) (xy 462.677643 -327.866357) (xy 462.601962 -327.904045)
			(xy 462.523127 -327.934589) (xy 462.44181 -327.95773) (xy 462.358705 -327.973269) (xy 462.274521 -327.981074)
			(xy 462.232248 -327.981564) (xy 460.987648 -327.981564) (xy 460.945368 -327.981181) (xy 460.861167 -327.973383)
			(xy 460.778046 -327.957849) (xy 460.696712 -327.934711) (xy 460.617861 -327.904167) (xy 460.542164 -327.866478)
			(xy 460.470267 -327.821965) (xy 460.402785 -327.771008) (xy 460.340292 -327.714042) (xy 460.283323 -327.651552)
			(xy 460.232362 -327.584072) (xy 460.187845 -327.512178) (xy 460.150152 -327.436483) (xy 460.119604 -327.357633)
			(xy 460.096462 -327.276301) (xy 460.080924 -327.19318) (xy 460.073121 -327.10898) (xy 455.602775 -327.10898)
			(xy 455.594975 -327.193158) (xy 455.579441 -327.276264) (xy 455.556304 -327.357582) (xy 455.525764 -327.436418)
			(xy 455.48808 -327.512101) (xy 455.443574 -327.583984) (xy 455.392625 -327.651454) (xy 455.335669 -327.713935)
			(xy 455.273191 -327.770895) (xy 455.205724 -327.821847) (xy 455.133843 -327.866357) (xy 455.058162 -327.904045)
			(xy 454.979327 -327.934589) (xy 454.89801 -327.95773) (xy 454.814905 -327.973269) (xy 454.730721 -327.981074)
			(xy 454.688448 -327.981564) (xy 453.443848 -327.981564) (xy 453.401568 -327.981181) (xy 453.317367 -327.973383)
			(xy 453.234246 -327.957849) (xy 453.152912 -327.934711) (xy 453.074061 -327.904167) (xy 452.998364 -327.866478)
			(xy 452.926467 -327.821965) (xy 452.858985 -327.771008) (xy 452.796492 -327.714042) (xy 452.739523 -327.651552)
			(xy 452.688562 -327.584072) (xy 452.644045 -327.512178) (xy 452.606352 -327.436483) (xy 452.575804 -327.357633)
			(xy 452.552662 -327.276301) (xy 452.537124 -327.19318) (xy 452.529321 -327.10898) (xy 448.058975 -327.10898)
			(xy 448.051175 -327.193158) (xy 448.035641 -327.276264) (xy 448.012504 -327.357582) (xy 447.981964 -327.436418)
			(xy 447.94428 -327.512101) (xy 447.899774 -327.583984) (xy 447.848825 -327.651454) (xy 447.791869 -327.713935)
			(xy 447.729391 -327.770895) (xy 447.661924 -327.821847) (xy 447.590043 -327.866357) (xy 447.514362 -327.904045)
			(xy 447.435527 -327.934589) (xy 447.35421 -327.95773) (xy 447.271105 -327.973269) (xy 447.186921 -327.981074)
			(xy 447.144648 -327.981564) (xy 445.900048 -327.981564) (xy 445.857768 -327.981181) (xy 445.773567 -327.973383)
			(xy 445.690446 -327.957849) (xy 445.609112 -327.934711) (xy 445.530261 -327.904167) (xy 445.454564 -327.866478)
			(xy 445.382667 -327.821965) (xy 445.315185 -327.771008) (xy 445.252692 -327.714042) (xy 445.195723 -327.651552)
			(xy 445.144762 -327.584072) (xy 445.100245 -327.512178) (xy 445.062552 -327.436483) (xy 445.032004 -327.357633)
			(xy 445.008862 -327.276301) (xy 444.993324 -327.19318) (xy 444.985521 -327.10898) (xy 440.515175 -327.10898)
			(xy 440.507375 -327.193158) (xy 440.491841 -327.276264) (xy 440.468704 -327.357582) (xy 440.438164 -327.436418)
			(xy 440.40048 -327.512101) (xy 440.355974 -327.583984) (xy 440.305025 -327.651454) (xy 440.248069 -327.713935)
			(xy 440.185591 -327.770895) (xy 440.118124 -327.821847) (xy 440.046243 -327.866357) (xy 439.970562 -327.904045)
			(xy 439.891727 -327.934589) (xy 439.81041 -327.95773) (xy 439.727305 -327.973269) (xy 439.643121 -327.981074)
			(xy 439.600848 -327.981564) (xy 438.356248 -327.981564) (xy 438.313968 -327.981181) (xy 438.229767 -327.973383)
			(xy 438.146646 -327.957849) (xy 438.065312 -327.934711) (xy 437.986461 -327.904167) (xy 437.910764 -327.866478)
			(xy 437.838867 -327.821965) (xy 437.771385 -327.771008) (xy 437.708892 -327.714042) (xy 437.651923 -327.651552)
			(xy 437.600962 -327.584072) (xy 437.556445 -327.512178) (xy 437.518752 -327.436483) (xy 437.488204 -327.357633)
			(xy 437.465062 -327.276301) (xy 437.449524 -327.19318) (xy 437.441721 -327.10898) (xy 432.971375 -327.10898)
			(xy 432.963575 -327.193158) (xy 432.948041 -327.276264) (xy 432.924904 -327.357582) (xy 432.894364 -327.436418)
			(xy 432.85668 -327.512101) (xy 432.812174 -327.583984) (xy 432.761225 -327.651454) (xy 432.704269 -327.713935)
			(xy 432.641791 -327.770895) (xy 432.574324 -327.821847) (xy 432.502443 -327.866357) (xy 432.426762 -327.904045)
			(xy 432.347927 -327.934589) (xy 432.26661 -327.95773) (xy 432.183505 -327.973269) (xy 432.099321 -327.981074)
			(xy 432.057048 -327.981564) (xy 430.812448 -327.981564) (xy 430.770168 -327.981181) (xy 430.685967 -327.973383)
			(xy 430.602846 -327.957849) (xy 430.521512 -327.934711) (xy 430.442661 -327.904167) (xy 430.366964 -327.866478)
			(xy 430.295067 -327.821965) (xy 430.227585 -327.771008) (xy 430.165092 -327.714042) (xy 430.108123 -327.651552)
			(xy 430.057162 -327.584072) (xy 430.012645 -327.512178) (xy 429.974952 -327.436483) (xy 429.944404 -327.357633)
			(xy 429.921262 -327.276301) (xy 429.905724 -327.19318) (xy 429.897921 -327.10898) (xy 425.427575 -327.10898)
			(xy 425.419775 -327.193158) (xy 425.404241 -327.276264) (xy 425.381104 -327.357582) (xy 425.350564 -327.436418)
			(xy 425.31288 -327.512101) (xy 425.268374 -327.583984) (xy 425.217425 -327.651454) (xy 425.160469 -327.713935)
			(xy 425.097991 -327.770895) (xy 425.030524 -327.821847) (xy 424.958643 -327.866357) (xy 424.882962 -327.904045)
			(xy 424.804127 -327.934589) (xy 424.72281 -327.95773) (xy 424.639705 -327.973269) (xy 424.555521 -327.981074)
			(xy 424.513248 -327.981564) (xy 423.268648 -327.981564) (xy 423.226368 -327.981181) (xy 423.142167 -327.973383)
			(xy 423.059046 -327.957849) (xy 422.977712 -327.934711) (xy 422.898861 -327.904167) (xy 422.823164 -327.866478)
			(xy 422.751267 -327.821965) (xy 422.683785 -327.771008) (xy 422.621292 -327.714042) (xy 422.564323 -327.651552)
			(xy 422.513362 -327.584072) (xy 422.468845 -327.512178) (xy 422.431152 -327.436483) (xy 422.400604 -327.357633)
			(xy 422.377462 -327.276301) (xy 422.361924 -327.19318) (xy 422.354121 -327.10898) (xy 417.883775 -327.10898)
			(xy 417.875975 -327.193158) (xy 417.860441 -327.276264) (xy 417.837304 -327.357582) (xy 417.806764 -327.436418)
			(xy 417.76908 -327.512101) (xy 417.724574 -327.583984) (xy 417.673625 -327.651454) (xy 417.616669 -327.713935)
			(xy 417.554191 -327.770895) (xy 417.486724 -327.821847) (xy 417.414843 -327.866357) (xy 417.339162 -327.904045)
			(xy 417.260327 -327.934589) (xy 417.17901 -327.95773) (xy 417.095905 -327.973269) (xy 417.011721 -327.981074)
			(xy 416.969448 -327.981564) (xy 415.724848 -327.981564) (xy 415.682568 -327.981181) (xy 415.598367 -327.973383)
			(xy 415.515246 -327.957849) (xy 415.433912 -327.934711) (xy 415.355061 -327.904167) (xy 415.279364 -327.866478)
			(xy 415.207467 -327.821965) (xy 415.139985 -327.771008) (xy 415.077492 -327.714042) (xy 415.020523 -327.651552)
			(xy 414.969562 -327.584072) (xy 414.925045 -327.512178) (xy 414.887352 -327.436483) (xy 414.856804 -327.357633)
			(xy 414.833662 -327.276301) (xy 414.818124 -327.19318) (xy 414.810321 -327.10898) (xy 410.339975 -327.10898)
			(xy 410.332175 -327.193158) (xy 410.316641 -327.276264) (xy 410.293504 -327.357582) (xy 410.262964 -327.436418)
			(xy 410.22528 -327.512101) (xy 410.180774 -327.583984) (xy 410.129825 -327.651454) (xy 410.072869 -327.713935)
			(xy 410.010391 -327.770895) (xy 409.942924 -327.821847) (xy 409.871043 -327.866357) (xy 409.795362 -327.904045)
			(xy 409.716527 -327.934589) (xy 409.63521 -327.95773) (xy 409.552105 -327.973269) (xy 409.467921 -327.981074)
			(xy 409.425648 -327.981564) (xy 408.181048 -327.981564) (xy 408.138768 -327.981181) (xy 408.054567 -327.973383)
			(xy 407.971446 -327.957849) (xy 407.890112 -327.934711) (xy 407.811261 -327.904167) (xy 407.735564 -327.866478)
			(xy 407.663667 -327.821965) (xy 407.596185 -327.771008) (xy 407.533692 -327.714042) (xy 407.476723 -327.651552)
			(xy 407.425762 -327.584072) (xy 407.381245 -327.512178) (xy 407.343552 -327.436483) (xy 407.313004 -327.357633)
			(xy 407.289862 -327.276301) (xy 407.274324 -327.19318) (xy 407.266521 -327.10898) (xy 402.159978 -327.10898)
			(xy 402.159978 -339.836506) (xy 402.54936 -340.225888) (xy 435.0512 -340.225888)
		)
		(stroke
			(width 0)
			(type solid)
		)
		(fill yes)
		(layer "F.Cu")
		(net "P12V_S3_AUX_CPU0_NVDIMM")
	)
	(gr_poly
		(pts
			(xy 211.64042 -329.082908) (xy 211.64042 -326.49795) (xy 212.551264 -325.586852) (xy 216.114376 -325.586852)
			(xy 216.700862 -325.000366) (xy 216.700862 -320.456306) (xy 216.554558 -320.310256) (xy 213.041484 -320.310256)
			(xy 212.492844 -320.858896) (xy 212.489034 -320.869564) (xy 212.483941 -320.882744) (xy 212.468852 -320.906628)
			(xy 212.448882 -320.926609) (xy 212.425007 -320.941711) (xy 212.411818 -320.94678) (xy 212.40115 -320.95059)
			(xy 212.203284 -321.148456) (xy 210.247484 -321.148456) (xy 210.021678 -320.92265) (xy 210.000088 -320.922904)
			(xy 209.9945 -320.922904) (xy 209.966515 -320.922383) (xy 209.911233 -320.913628) (xy 209.858002 -320.896332)
			(xy 209.808132 -320.870922) (xy 209.762852 -320.838023) (xy 209.723275 -320.798445) (xy 209.690376 -320.753164)
			(xy 209.664967 -320.703294) (xy 209.647671 -320.650063) (xy 209.638916 -320.594781) (xy 209.638392 -320.566796)
			(xy 209.638392 -320.561208) (xy 209.638646 -320.539618) (xy 209.409284 -320.310256) (xy 205.827884 -320.310256)
			(xy 204.989684 -321.148456) (xy 202.525884 -321.148456) (xy 202.274932 -320.897504) (xy 202.266042 -320.89344)
			(xy 202.241615 -320.88233) (xy 202.196132 -320.853856) (xy 202.155439 -320.818876) (xy 202.120457 -320.778185)
			(xy 202.091979 -320.732704) (xy 202.080876 -320.708274) (xy 202.076812 -320.699384) (xy 201.687684 -320.310256)
			(xy 198.385684 -320.310256) (xy 197.547484 -321.148456) (xy 194.956684 -321.148456) (xy 194.705732 -320.897504)
			(xy 194.696842 -320.89344) (xy 194.672415 -320.88233) (xy 194.626932 -320.853856) (xy 194.586239 -320.818876)
			(xy 194.551257 -320.778185) (xy 194.522779 -320.732704) (xy 194.511676 -320.708274) (xy 194.507612 -320.699384)
			(xy 194.118484 -320.310256) (xy 191.78651 -320.310256) (xy 191.599566 -320.4972) (xy 191.595756 -320.507614)
			(xy 191.585851 -320.532786) (xy 191.559535 -320.580044) (xy 191.526374 -320.622779) (xy 191.487131 -320.660007)
			(xy 191.44271 -320.690873) (xy 191.394133 -320.714665) (xy 191.342515 -320.730838) (xy 191.289046 -320.739018)
			(xy 191.262 -320.739516) (xy 191.235121 -320.739033) (xy 191.181971 -320.730965) (xy 191.130639 -320.714999)
			(xy 191.08229 -320.691495) (xy 191.038025 -320.66099) (xy 190.99885 -320.624177) (xy 190.965654 -320.581892)
			(xy 190.939194 -320.535096) (xy 190.92007 -320.484855) (xy 190.908717 -320.432309) (xy 190.906654 -320.405506)
			(xy 190.905164 -320.390215) (xy 190.894222 -320.361521) (xy 190.875257 -320.337368) (xy 190.849977 -320.319933)
			(xy 190.820662 -320.310787) (xy 190.805308 -320.310256) (xy 190.714884 -320.310256) (xy 189.876684 -321.148456)
			(xy 188.200284 -321.148456) (xy 188.047884 -320.996056) (xy 187.539884 -320.996056) (xy 187.451746 -320.907918)
			(xy 187.424314 -320.914014) (xy 187.404829 -320.91816) (xy 187.365239 -320.922612) (xy 187.34532 -320.922904)
			(xy 187.317334 -320.922385) (xy 187.26205 -320.913632) (xy 187.208816 -320.896337) (xy 187.158944 -320.870928)
			(xy 187.11366 -320.83803) (xy 187.074081 -320.798452) (xy 187.04118 -320.75317) (xy 187.015769 -320.703299)
			(xy 186.998472 -320.650066) (xy 186.989716 -320.594782) (xy 186.989212 -320.566796) (xy 186.989477 -320.546875)
			(xy 186.99393 -320.507283) (xy 186.998102 -320.487802) (xy 187.004198 -320.46037) (xy 186.854084 -320.310256)
			(xy 183.221884 -320.310256) (xy 182.383684 -321.148456) (xy 180.707284 -321.148456) (xy 180.504084 -320.945256)
			(xy 179.919884 -320.945256) (xy 179.896008 -320.92138) (xy 179.873402 -320.922396) (xy 179.85486 -320.922904)
			(xy 179.826879 -320.922352) (xy 179.771607 -320.913592) (xy 179.718386 -320.896294) (xy 179.668525 -320.870884)
			(xy 179.623253 -320.837987) (xy 179.583685 -320.798413) (xy 179.550793 -320.753137) (xy 179.525389 -320.703274)
			(xy 179.508098 -320.65005) (xy 179.499344 -320.594777) (xy 179.498752 -320.566796) (xy 179.49926 -320.548254)
			(xy 179.500276 -320.525648) (xy 179.284884 -320.310256) (xy 177.278284 -320.310256) (xy 177.100484 -320.132456)
			(xy 177.05705 -320.132456) (xy 176.638966 -320.55054) (xy 176.635156 -320.560954) (xy 176.625254 -320.586129)
			(xy 176.598942 -320.633394) (xy 176.565784 -320.676136) (xy 176.526543 -320.713371) (xy 176.482121 -320.744242)
			(xy 176.433541 -320.768039) (xy 176.381921 -320.784215) (xy 176.328448 -320.792397) (xy 176.3014 -320.792856)
			(xy 176.273416 -320.792307) (xy 176.218136 -320.783552) (xy 176.164905 -320.766258) (xy 176.115036 -320.740851)
			(xy 176.069754 -320.707956) (xy 176.030175 -320.668382) (xy 175.997274 -320.623105) (xy 175.97186 -320.573239)
			(xy 175.954559 -320.520011) (xy 175.945797 -320.464732) (xy 175.945292 -320.436748) (xy 175.945903 -320.406807)
			(xy 175.955914 -320.347769) (xy 175.975661 -320.291238) (xy 176.004587 -320.238807) (xy 176.022762 -320.215006)
			(xy 176.028406 -320.207311) (xy 176.034046 -320.189096) (xy 176.032641 -320.170079) (xy 176.024384 -320.15289)
			(xy 176.010417 -320.139908) (xy 175.992672 -320.132926) (xy 175.983138 -320.132456) (xy 175.881284 -320.132456)
			(xy 174.865284 -321.148456) (xy 172.553884 -321.148456) (xy 172.313346 -320.907918) (xy 172.285914 -320.914014)
			(xy 172.266429 -320.91816) (xy 172.226839 -320.922612) (xy 172.20692 -320.922904) (xy 172.178934 -320.922385)
			(xy 172.12365 -320.913632) (xy 172.070416 -320.896337) (xy 172.020544 -320.870928) (xy 171.97526 -320.83803)
			(xy 171.935681 -320.798452) (xy 171.90278 -320.75317) (xy 171.877369 -320.703299) (xy 171.860072 -320.650066)
			(xy 171.851316 -320.594782) (xy 171.850812 -320.566796) (xy 171.851077 -320.546875) (xy 171.85553 -320.507283)
			(xy 171.859702 -320.487802) (xy 171.865798 -320.46037) (xy 171.715684 -320.310256) (xy 169.277284 -320.310256)
			(xy 168.413684 -321.173856) (xy 168.259252 -321.173856) (xy 168.240742 -321.193528) (xy 168.198833 -321.227604)
			(xy 168.152255 -321.254954) (xy 168.10208 -321.274952) (xy 168.049459 -321.287137) (xy 167.9956 -321.29123)
			(xy 167.941741 -321.287137) (xy 167.88912 -321.274952) (xy 167.838945 -321.254954) (xy 167.792367 -321.227604)
			(xy 167.750458 -321.193528) (xy 167.731948 -321.173856) (xy 165.238684 -321.173856) (xy 164.643816 -320.578988)
			(xy 164.61486 -320.587624) (xy 164.590029 -320.594522) (xy 164.539028 -320.601923) (xy 164.51326 -320.602356)
			(xy 164.486216 -320.60185) (xy 164.432749 -320.593665) (xy 164.381136 -320.57749) (xy 164.332561 -320.553697)
			(xy 164.288143 -320.522832) (xy 164.248903 -320.485605) (xy 164.215743 -320.442873) (xy 164.189425 -320.395618)
			(xy 164.179504 -320.370454) (xy 164.175694 -320.36004) (xy 164.07511 -320.259456) (xy 160.95726 -320.259456)
			(xy 160.942425 -320.259928) (xy 160.913988 -320.268383) (xy 160.889181 -320.284655) (xy 160.870098 -320.307371)
			(xy 160.85835 -320.334613) (xy 160.854929 -320.364083) (xy 160.860122 -320.393292) (xy 160.866328 -320.406776)
			(xy 160.878316 -320.431731) (xy 160.895278 -320.484428) (xy 160.903878 -320.539116) (xy 160.904428 -320.566796)
			(xy 160.903879 -320.59478) (xy 160.895125 -320.650059) (xy 160.877831 -320.703288) (xy 160.852423 -320.753156)
			(xy 160.819528 -320.798436) (xy 160.779954 -320.838012) (xy 160.734676 -320.870911) (xy 160.68481 -320.896322)
			(xy 160.631582 -320.913619) (xy 160.576304 -320.922377) (xy 160.54832 -320.922904) (xy 160.52281 -320.922489)
			(xy 160.472308 -320.915249) (xy 160.423357 -320.900873) (xy 160.399984 -320.890646) (xy 160.390078 -320.88582)
			(xy 160.14192 -320.88582) (xy 159.879284 -321.148456) (xy 155.292552 -321.148456) (xy 155.000198 -321.44081)
			(xy 155.000198 -323.3837) (xy 158.455848 -323.3837) (xy 158.459832 -323.330545) (xy 158.471693 -323.278578)
			(xy 158.491166 -323.228959) (xy 158.517817 -323.182796) (xy 158.551051 -323.141121) (xy 158.590124 -323.104864)
			(xy 158.634165 -323.074836) (xy 158.682189 -323.051707) (xy 158.733124 -323.035994) (xy 158.785832 -323.028047)
			(xy 158.812484 -323.027548) (xy 158.838456 -323.027986) (xy 158.889849 -323.035526) (xy 158.939603 -323.05045)
			(xy 158.986662 -323.07244) (xy 159.030029 -323.10103) (xy 159.04972 -323.117972) (xy 159.061114 -323.12746)
			(xy 159.087962 -323.140009) (xy 159.117284 -323.144313) (xy 159.146606 -323.140009) (xy 159.173454 -323.12746)
			(xy 159.184848 -323.117972) (xy 159.204544 -323.101039) (xy 159.247914 -323.07246) (xy 159.294973 -323.050478)
			(xy 159.344724 -323.035559) (xy 159.396114 -323.028019) (xy 159.422084 -323.027548) (xy 159.448733 -323.028108)
			(xy 159.501435 -323.036049) (xy 159.552365 -323.051757) (xy 159.600385 -323.07488) (xy 159.644422 -323.104903)
			(xy 159.683492 -323.141153) (xy 159.716723 -323.182822) (xy 159.743373 -323.228978) (xy 159.762845 -323.278591)
			(xy 159.774705 -323.330552) (xy 159.778688 -323.3837) (xy 159.774881 -323.4345) (xy 162.189648 -323.4345)
			(xy 162.193632 -323.381345) (xy 162.205493 -323.329378) (xy 162.224966 -323.279759) (xy 162.251617 -323.233596)
			(xy 162.284851 -323.191921) (xy 162.323924 -323.155664) (xy 162.367965 -323.125636) (xy 162.415989 -323.102507)
			(xy 162.466924 -323.086794) (xy 162.519632 -323.078847) (xy 162.546284 -323.078348) (xy 162.572692 -323.078855)
			(xy 162.624928 -323.086653) (xy 162.67544 -323.10208) (xy 162.723119 -323.124798) (xy 162.766921 -323.15431)
			(xy 162.805883 -323.189966) (xy 162.82289 -323.210174) (xy 162.832827 -323.221567) (xy 162.85788 -323.238458)
			(xy 162.886776 -323.247289) (xy 162.916992 -323.247289) (xy 162.945888 -323.238458) (xy 162.970941 -323.221567)
			(xy 162.980878 -323.210174) (xy 162.997882 -323.189962) (xy 163.036844 -323.154302) (xy 163.080645 -323.124786)
			(xy 163.128325 -323.102064) (xy 163.178837 -323.086632) (xy 163.231075 -323.078829) (xy 163.257484 -323.078348)
			(xy 163.284133 -323.078908) (xy 163.336835 -323.086849) (xy 163.387765 -323.102557) (xy 163.435785 -323.12568)
			(xy 163.479822 -323.155703) (xy 163.518892 -323.191953) (xy 163.552123 -323.233622) (xy 163.578773 -323.279778)
			(xy 163.598245 -323.329391) (xy 163.610105 -323.381352) (xy 163.614088 -323.4345) (xy 165.669448 -323.4345)
			(xy 165.673432 -323.381345) (xy 165.685293 -323.329378) (xy 165.704766 -323.279759) (xy 165.731417 -323.233596)
			(xy 165.764651 -323.191921) (xy 165.803724 -323.155664) (xy 165.847765 -323.125636) (xy 165.895789 -323.102507)
			(xy 165.946724 -323.086794) (xy 165.999432 -323.078847) (xy 166.026084 -323.078348) (xy 166.052492 -323.078855)
			(xy 166.104728 -323.086653) (xy 166.15524 -323.10208) (xy 166.202919 -323.124798) (xy 166.246721 -323.15431)
			(xy 166.285683 -323.189966) (xy 166.30269 -323.210174) (xy 166.312627 -323.221567) (xy 166.33768 -323.238458)
			(xy 166.366576 -323.247289) (xy 166.396792 -323.247289) (xy 166.425688 -323.238458) (xy 166.450741 -323.221567)
			(xy 166.460678 -323.210174) (xy 166.477682 -323.189962) (xy 166.516644 -323.154302) (xy 166.560445 -323.124786)
			(xy 166.608125 -323.102064) (xy 166.658637 -323.086632) (xy 166.710875 -323.078829) (xy 166.737284 -323.078348)
			(xy 166.763933 -323.078908) (xy 166.816635 -323.086849) (xy 166.867565 -323.102557) (xy 166.915585 -323.12568)
			(xy 166.959622 -323.155703) (xy 166.998692 -323.191953) (xy 167.031923 -323.233622) (xy 167.058573 -323.279778)
			(xy 167.078045 -323.329391) (xy 167.089905 -323.381352) (xy 167.093888 -323.4345) (xy 169.733448 -323.4345)
			(xy 169.737432 -323.381345) (xy 169.749293 -323.329378) (xy 169.768766 -323.279759) (xy 169.795417 -323.233596)
			(xy 169.828651 -323.191921) (xy 169.867724 -323.155664) (xy 169.911765 -323.125636) (xy 169.959789 -323.102507)
			(xy 170.010724 -323.086794) (xy 170.063432 -323.078847) (xy 170.090084 -323.078348) (xy 170.116492 -323.078855)
			(xy 170.168728 -323.086653) (xy 170.21924 -323.10208) (xy 170.266919 -323.124798) (xy 170.310721 -323.15431)
			(xy 170.349683 -323.189966) (xy 170.36669 -323.210174) (xy 170.376627 -323.221567) (xy 170.40168 -323.238458)
			(xy 170.430576 -323.247289) (xy 170.460792 -323.247289) (xy 170.489688 -323.238458) (xy 170.514741 -323.221567)
			(xy 170.524678 -323.210174) (xy 170.541682 -323.189962) (xy 170.580644 -323.154302) (xy 170.624445 -323.124786)
			(xy 170.672125 -323.102064) (xy 170.722637 -323.086632) (xy 170.774875 -323.078829) (xy 170.801284 -323.078348)
			(xy 170.827933 -323.078908) (xy 170.880635 -323.086849) (xy 170.931565 -323.102557) (xy 170.979585 -323.12568)
			(xy 171.023622 -323.155703) (xy 171.062692 -323.191953) (xy 171.095923 -323.233622) (xy 171.122573 -323.279778)
			(xy 171.142045 -323.329391) (xy 171.153905 -323.381352) (xy 171.157888 -323.4345) (xy 173.213248 -323.4345)
			(xy 173.217232 -323.381345) (xy 173.229093 -323.329378) (xy 173.248566 -323.279759) (xy 173.275217 -323.233596)
			(xy 173.308451 -323.191921) (xy 173.347524 -323.155664) (xy 173.391565 -323.125636) (xy 173.439589 -323.102507)
			(xy 173.490524 -323.086794) (xy 173.543232 -323.078847) (xy 173.569884 -323.078348) (xy 173.596292 -323.078855)
			(xy 173.648528 -323.086653) (xy 173.69904 -323.10208) (xy 173.746719 -323.124798) (xy 173.790521 -323.15431)
			(xy 173.829483 -323.189966) (xy 173.84649 -323.210174) (xy 173.856427 -323.221567) (xy 173.88148 -323.238458)
			(xy 173.910376 -323.247289) (xy 173.940592 -323.247289) (xy 173.969488 -323.238458) (xy 173.994541 -323.221567)
			(xy 174.004478 -323.210174) (xy 174.021482 -323.189962) (xy 174.060444 -323.154302) (xy 174.104245 -323.124786)
			(xy 174.151925 -323.102064) (xy 174.202437 -323.086632) (xy 174.254675 -323.078829) (xy 174.281084 -323.078348)
			(xy 174.307733 -323.078908) (xy 174.360435 -323.086849) (xy 174.411365 -323.102557) (xy 174.459385 -323.12568)
			(xy 174.503422 -323.155703) (xy 174.542492 -323.191953) (xy 174.575723 -323.233622) (xy 174.602373 -323.279778)
			(xy 174.621845 -323.329391) (xy 174.633705 -323.381352) (xy 174.637688 -323.4345) (xy 177.277248 -323.4345)
			(xy 177.281232 -323.381345) (xy 177.293093 -323.329378) (xy 177.312566 -323.279759) (xy 177.339217 -323.233596)
			(xy 177.372451 -323.191921) (xy 177.411524 -323.155664) (xy 177.455565 -323.125636) (xy 177.503589 -323.102507)
			(xy 177.554524 -323.086794) (xy 177.607232 -323.078847) (xy 177.633884 -323.078348) (xy 177.660292 -323.078855)
			(xy 177.712528 -323.086653) (xy 177.76304 -323.10208) (xy 177.810719 -323.124798) (xy 177.854521 -323.15431)
			(xy 177.893483 -323.189966) (xy 177.91049 -323.210174) (xy 177.920427 -323.221567) (xy 177.94548 -323.238458)
			(xy 177.974376 -323.247289) (xy 178.004592 -323.247289) (xy 178.033488 -323.238458) (xy 178.058541 -323.221567)
			(xy 178.068478 -323.210174) (xy 178.085482 -323.189962) (xy 178.124444 -323.154302) (xy 178.168245 -323.124786)
			(xy 178.215925 -323.102064) (xy 178.266437 -323.086632) (xy 178.318675 -323.078829) (xy 178.345084 -323.078348)
			(xy 178.371733 -323.078908) (xy 178.424435 -323.086849) (xy 178.475365 -323.102557) (xy 178.523385 -323.12568)
			(xy 178.567422 -323.155703) (xy 178.606492 -323.191953) (xy 178.639723 -323.233622) (xy 178.666373 -323.279778)
			(xy 178.685845 -323.329391) (xy 178.697705 -323.381352) (xy 178.701688 -323.4345) (xy 180.757048 -323.4345)
			(xy 180.761032 -323.381345) (xy 180.772893 -323.329378) (xy 180.792366 -323.279759) (xy 180.819017 -323.233596)
			(xy 180.852251 -323.191921) (xy 180.891324 -323.155664) (xy 180.935365 -323.125636) (xy 180.983389 -323.102507)
			(xy 181.034324 -323.086794) (xy 181.087032 -323.078847) (xy 181.113684 -323.078348) (xy 181.140092 -323.078855)
			(xy 181.192328 -323.086653) (xy 181.24284 -323.10208) (xy 181.290519 -323.124798) (xy 181.334321 -323.15431)
			(xy 181.373283 -323.189966) (xy 181.39029 -323.210174) (xy 181.400227 -323.221567) (xy 181.42528 -323.238458)
			(xy 181.454176 -323.247289) (xy 181.484392 -323.247289) (xy 181.513288 -323.238458) (xy 181.538341 -323.221567)
			(xy 181.548278 -323.210174) (xy 181.565282 -323.189962) (xy 181.604244 -323.154302) (xy 181.648045 -323.124786)
			(xy 181.695725 -323.102064) (xy 181.746237 -323.086632) (xy 181.798475 -323.078829) (xy 181.824884 -323.078348)
			(xy 181.851533 -323.078908) (xy 181.904235 -323.086849) (xy 181.955165 -323.102557) (xy 182.003185 -323.12568)
			(xy 182.047222 -323.155703) (xy 182.086292 -323.191953) (xy 182.119523 -323.233622) (xy 182.146173 -323.279778)
			(xy 182.165645 -323.329391) (xy 182.177505 -323.381352) (xy 182.181488 -323.4345) (xy 184.821048 -323.4345)
			(xy 184.825032 -323.381345) (xy 184.836893 -323.329378) (xy 184.856366 -323.279759) (xy 184.883017 -323.233596)
			(xy 184.916251 -323.191921) (xy 184.955324 -323.155664) (xy 184.999365 -323.125636) (xy 185.047389 -323.102507)
			(xy 185.098324 -323.086794) (xy 185.151032 -323.078847) (xy 185.177684 -323.078348) (xy 185.204244 -323.078854)
			(xy 185.256773 -323.086754) (xy 185.307547 -323.102366) (xy 185.35544 -323.125345) (xy 185.399389 -323.155181)
			(xy 185.419238 -323.172836) (xy 185.43009 -323.182141) (xy 185.455638 -323.194934) (xy 185.483732 -323.200142)
			(xy 185.512167 -323.197356) (xy 185.538716 -323.186796) (xy 185.550302 -323.178424) (xy 185.57389 -323.160911)
			(xy 185.625591 -323.133021) (xy 185.681169 -323.113995) (xy 185.739116 -323.10435) (xy 185.768488 -323.103748)
			(xy 185.795136 -323.104308) (xy 185.847838 -323.11225) (xy 185.898768 -323.127958) (xy 185.946787 -323.151082)
			(xy 185.990824 -323.181104) (xy 186.029894 -323.217354) (xy 186.063124 -323.259023) (xy 186.089773 -323.305179)
			(xy 186.109245 -323.354792) (xy 186.121105 -323.406752) (xy 186.123184 -323.4345) (xy 188.300848 -323.4345)
			(xy 188.304832 -323.381345) (xy 188.316693 -323.329378) (xy 188.336166 -323.279759) (xy 188.362817 -323.233596)
			(xy 188.396051 -323.191921) (xy 188.435124 -323.155664) (xy 188.479165 -323.125636) (xy 188.527189 -323.102507)
			(xy 188.578124 -323.086794) (xy 188.630832 -323.078847) (xy 188.657484 -323.078348) (xy 188.683892 -323.078855)
			(xy 188.736128 -323.086653) (xy 188.78664 -323.10208) (xy 188.834319 -323.124798) (xy 188.878121 -323.15431)
			(xy 188.917083 -323.189966) (xy 188.93409 -323.210174) (xy 188.944027 -323.221567) (xy 188.96908 -323.238458)
			(xy 188.997976 -323.247289) (xy 189.028192 -323.247289) (xy 189.057088 -323.238458) (xy 189.082141 -323.221567)
			(xy 189.092078 -323.210174) (xy 189.109082 -323.189962) (xy 189.148044 -323.154302) (xy 189.191845 -323.124786)
			(xy 189.239525 -323.102064) (xy 189.290037 -323.086632) (xy 189.342275 -323.078829) (xy 189.368684 -323.078348)
			(xy 189.395333 -323.078908) (xy 189.448035 -323.086849) (xy 189.498965 -323.102557) (xy 189.546985 -323.12568)
			(xy 189.591022 -323.155703) (xy 189.630092 -323.191953) (xy 189.663323 -323.233622) (xy 189.689973 -323.279778)
			(xy 189.709445 -323.329391) (xy 189.721305 -323.381352) (xy 189.725288 -323.4345) (xy 192.364848 -323.4345)
			(xy 192.368832 -323.381345) (xy 192.380693 -323.329378) (xy 192.400166 -323.279759) (xy 192.426817 -323.233596)
			(xy 192.460051 -323.191921) (xy 192.499124 -323.155664) (xy 192.543165 -323.125636) (xy 192.591189 -323.102507)
			(xy 192.642124 -323.086794) (xy 192.694832 -323.078847) (xy 192.721484 -323.078348) (xy 192.747892 -323.078855)
			(xy 192.800128 -323.086653) (xy 192.85064 -323.10208) (xy 192.898319 -323.124798) (xy 192.942121 -323.15431)
			(xy 192.981083 -323.189966) (xy 192.99809 -323.210174) (xy 193.008027 -323.221567) (xy 193.03308 -323.238458)
			(xy 193.061976 -323.247289) (xy 193.092192 -323.247289) (xy 193.121088 -323.238458) (xy 193.146141 -323.221567)
			(xy 193.156078 -323.210174) (xy 193.173082 -323.189962) (xy 193.212044 -323.154302) (xy 193.255845 -323.124786)
			(xy 193.303525 -323.102064) (xy 193.354037 -323.086632) (xy 193.406275 -323.078829) (xy 193.432684 -323.078348)
			(xy 193.459333 -323.078908) (xy 193.512035 -323.086849) (xy 193.562965 -323.102557) (xy 193.610985 -323.12568)
			(xy 193.655022 -323.155703) (xy 193.694092 -323.191953) (xy 193.727323 -323.233622) (xy 193.753973 -323.279778)
			(xy 193.773445 -323.329391) (xy 193.785305 -323.381352) (xy 193.789288 -323.4345) (xy 195.844648 -323.4345)
			(xy 195.848632 -323.381345) (xy 195.860493 -323.329378) (xy 195.879966 -323.279759) (xy 195.906617 -323.233596)
			(xy 195.939851 -323.191921) (xy 195.978924 -323.155664) (xy 196.022965 -323.125636) (xy 196.070989 -323.102507)
			(xy 196.121924 -323.086794) (xy 196.174632 -323.078847) (xy 196.201284 -323.078348) (xy 196.227692 -323.078855)
			(xy 196.279928 -323.086653) (xy 196.33044 -323.10208) (xy 196.378119 -323.124798) (xy 196.421921 -323.15431)
			(xy 196.460883 -323.189966) (xy 196.47789 -323.210174) (xy 196.487827 -323.221567) (xy 196.51288 -323.238458)
			(xy 196.541776 -323.247289) (xy 196.571992 -323.247289) (xy 196.600888 -323.238458) (xy 196.625941 -323.221567)
			(xy 196.635878 -323.210174) (xy 196.652882 -323.189962) (xy 196.691844 -323.154302) (xy 196.735645 -323.124786)
			(xy 196.783325 -323.102064) (xy 196.833837 -323.086632) (xy 196.886075 -323.078829) (xy 196.912484 -323.078348)
			(xy 196.939133 -323.078908) (xy 196.991835 -323.086849) (xy 197.042765 -323.102557) (xy 197.090785 -323.12568)
			(xy 197.134822 -323.155703) (xy 197.173892 -323.191953) (xy 197.207123 -323.233622) (xy 197.233773 -323.279778)
			(xy 197.253245 -323.329391) (xy 197.265105 -323.381352) (xy 197.269088 -323.4345) (xy 199.908648 -323.4345)
			(xy 199.912632 -323.381345) (xy 199.924493 -323.329378) (xy 199.943966 -323.279759) (xy 199.970617 -323.233596)
			(xy 200.003851 -323.191921) (xy 200.042924 -323.155664) (xy 200.086965 -323.125636) (xy 200.134989 -323.102507)
			(xy 200.185924 -323.086794) (xy 200.238632 -323.078847) (xy 200.265284 -323.078348) (xy 200.291692 -323.078855)
			(xy 200.343928 -323.086653) (xy 200.39444 -323.10208) (xy 200.442119 -323.124798) (xy 200.485921 -323.15431)
			(xy 200.524883 -323.189966) (xy 200.54189 -323.210174) (xy 200.551827 -323.221567) (xy 200.57688 -323.238458)
			(xy 200.605776 -323.247289) (xy 200.635992 -323.247289) (xy 200.664888 -323.238458) (xy 200.689941 -323.221567)
			(xy 200.699878 -323.210174) (xy 200.716882 -323.189962) (xy 200.755844 -323.154302) (xy 200.799645 -323.124786)
			(xy 200.847325 -323.102064) (xy 200.897837 -323.086632) (xy 200.950075 -323.078829) (xy 200.976484 -323.078348)
			(xy 201.003133 -323.078908) (xy 201.055835 -323.086849) (xy 201.106765 -323.102557) (xy 201.154785 -323.12568)
			(xy 201.198822 -323.155703) (xy 201.237892 -323.191953) (xy 201.271123 -323.233622) (xy 201.297773 -323.279778)
			(xy 201.317245 -323.329391) (xy 201.329105 -323.381352) (xy 201.333088 -323.4345) (xy 203.388448 -323.4345)
			(xy 203.392432 -323.381345) (xy 203.404293 -323.329378) (xy 203.423766 -323.279759) (xy 203.450417 -323.233596)
			(xy 203.483651 -323.191921) (xy 203.522724 -323.155664) (xy 203.566765 -323.125636) (xy 203.614789 -323.102507)
			(xy 203.665724 -323.086794) (xy 203.718432 -323.078847) (xy 203.745084 -323.078348) (xy 203.771492 -323.078855)
			(xy 203.823728 -323.086653) (xy 203.87424 -323.10208) (xy 203.921919 -323.124798) (xy 203.965721 -323.15431)
			(xy 204.004683 -323.189966) (xy 204.02169 -323.210174) (xy 204.031627 -323.221567) (xy 204.05668 -323.238458)
			(xy 204.085576 -323.247289) (xy 204.115792 -323.247289) (xy 204.144688 -323.238458) (xy 204.169741 -323.221567)
			(xy 204.179678 -323.210174) (xy 204.196682 -323.189962) (xy 204.235644 -323.154302) (xy 204.279445 -323.124786)
			(xy 204.327125 -323.102064) (xy 204.377637 -323.086632) (xy 204.429875 -323.078829) (xy 204.456284 -323.078348)
			(xy 204.482933 -323.078908) (xy 204.535635 -323.086849) (xy 204.586565 -323.102557) (xy 204.634585 -323.12568)
			(xy 204.678622 -323.155703) (xy 204.717692 -323.191953) (xy 204.750923 -323.233622) (xy 204.777573 -323.279778)
			(xy 204.797045 -323.329391) (xy 204.808905 -323.381352) (xy 204.812888 -323.4345) (xy 207.452448 -323.4345)
			(xy 207.456432 -323.381345) (xy 207.468293 -323.329378) (xy 207.487766 -323.279759) (xy 207.514417 -323.233596)
			(xy 207.547651 -323.191921) (xy 207.586724 -323.155664) (xy 207.630765 -323.125636) (xy 207.678789 -323.102507)
			(xy 207.729724 -323.086794) (xy 207.782432 -323.078847) (xy 207.809084 -323.078348) (xy 207.835492 -323.078855)
			(xy 207.887728 -323.086653) (xy 207.93824 -323.10208) (xy 207.985919 -323.124798) (xy 208.029721 -323.15431)
			(xy 208.068683 -323.189966) (xy 208.08569 -323.210174) (xy 208.095627 -323.221567) (xy 208.12068 -323.238458)
			(xy 208.149576 -323.247289) (xy 208.179792 -323.247289) (xy 208.208688 -323.238458) (xy 208.233741 -323.221567)
			(xy 208.243678 -323.210174) (xy 208.260682 -323.189962) (xy 208.299644 -323.154302) (xy 208.343445 -323.124786)
			(xy 208.391125 -323.102064) (xy 208.441637 -323.086632) (xy 208.493875 -323.078829) (xy 208.520284 -323.078348)
			(xy 208.546933 -323.078908) (xy 208.599635 -323.086849) (xy 208.650565 -323.102557) (xy 208.698585 -323.12568)
			(xy 208.742622 -323.155703) (xy 208.781692 -323.191953) (xy 208.814923 -323.233622) (xy 208.841573 -323.279778)
			(xy 208.861045 -323.329391) (xy 208.872905 -323.381352) (xy 208.876888 -323.4345) (xy 210.932248 -323.4345)
			(xy 210.936232 -323.381345) (xy 210.948093 -323.329378) (xy 210.967566 -323.279759) (xy 210.994217 -323.233596)
			(xy 211.027451 -323.191921) (xy 211.066524 -323.155664) (xy 211.110565 -323.125636) (xy 211.158589 -323.102507)
			(xy 211.209524 -323.086794) (xy 211.262232 -323.078847) (xy 211.288884 -323.078348) (xy 211.315292 -323.078855)
			(xy 211.367528 -323.086653) (xy 211.41804 -323.10208) (xy 211.465719 -323.124798) (xy 211.509521 -323.15431)
			(xy 211.548483 -323.189966) (xy 211.56549 -323.210174) (xy 211.575427 -323.221567) (xy 211.60048 -323.238458)
			(xy 211.629376 -323.247289) (xy 211.659592 -323.247289) (xy 211.688488 -323.238458) (xy 211.713541 -323.221567)
			(xy 211.723478 -323.210174) (xy 211.740482 -323.189962) (xy 211.779444 -323.154302) (xy 211.823245 -323.124786)
			(xy 211.870925 -323.102064) (xy 211.921437 -323.086632) (xy 211.973675 -323.078829) (xy 212.000084 -323.078348)
			(xy 212.026733 -323.078908) (xy 212.079435 -323.086849) (xy 212.130365 -323.102557) (xy 212.178385 -323.12568)
			(xy 212.222422 -323.155703) (xy 212.261492 -323.191953) (xy 212.294723 -323.233622) (xy 212.321373 -323.279778)
			(xy 212.340845 -323.329391) (xy 212.347443 -323.3583) (xy 212.811848 -323.3583) (xy 212.815832 -323.305145)
			(xy 212.827693 -323.253178) (xy 212.847166 -323.203559) (xy 212.873817 -323.157396) (xy 212.907051 -323.115721)
			(xy 212.946124 -323.079464) (xy 212.990165 -323.049436) (xy 213.038189 -323.026307) (xy 213.089124 -323.010594)
			(xy 213.141832 -323.002647) (xy 213.168484 -323.002148) (xy 213.194892 -323.002655) (xy 213.247128 -323.010453)
			(xy 213.29764 -323.02588) (xy 213.345319 -323.048598) (xy 213.389121 -323.07811) (xy 213.428083 -323.113766)
			(xy 213.44509 -323.133974) (xy 213.455027 -323.145367) (xy 213.48008 -323.162258) (xy 213.508976 -323.171089)
			(xy 213.539192 -323.171089) (xy 213.568088 -323.162258) (xy 213.593141 -323.145367) (xy 213.603078 -323.133974)
			(xy 213.620082 -323.113762) (xy 213.659044 -323.078102) (xy 213.702845 -323.048586) (xy 213.750525 -323.025864)
			(xy 213.801037 -323.010432) (xy 213.853275 -323.002629) (xy 213.879684 -323.002148) (xy 213.906333 -323.002708)
			(xy 213.959035 -323.010649) (xy 214.009965 -323.026357) (xy 214.057985 -323.04948) (xy 214.102022 -323.079503)
			(xy 214.141092 -323.115753) (xy 214.174323 -323.157422) (xy 214.200973 -323.203578) (xy 214.220445 -323.253191)
			(xy 214.232305 -323.305152) (xy 214.236288 -323.3583) (xy 214.232305 -323.411448) (xy 214.220445 -323.463409)
			(xy 214.200973 -323.513022) (xy 214.174323 -323.559178) (xy 214.141092 -323.600847) (xy 214.102022 -323.637097)
			(xy 214.057985 -323.66712) (xy 214.009965 -323.690243) (xy 213.959035 -323.705951) (xy 213.906333 -323.713892)
			(xy 213.879684 -323.714364) (xy 213.853274 -323.713912) (xy 213.801034 -323.706107) (xy 213.750519 -323.690671)
			(xy 213.702839 -323.667943) (xy 213.65904 -323.63842) (xy 213.620082 -323.602752) (xy 213.603078 -323.582538)
			(xy 213.593141 -323.571145) (xy 213.568088 -323.554254) (xy 213.539192 -323.545423) (xy 213.508976 -323.545423)
			(xy 213.48008 -323.554254) (xy 213.455027 -323.571145) (xy 213.44509 -323.582538) (xy 213.428106 -323.602768)
			(xy 213.38914 -323.638426) (xy 213.345335 -323.667939) (xy 213.297651 -323.690659) (xy 213.247135 -323.706087)
			(xy 213.194894 -323.713886) (xy 213.168484 -323.714364) (xy 213.141832 -323.713953) (xy 213.089124 -323.706006)
			(xy 213.038189 -323.690293) (xy 212.990165 -323.667164) (xy 212.946124 -323.637136) (xy 212.907051 -323.600879)
			(xy 212.873817 -323.559204) (xy 212.847166 -323.513041) (xy 212.827693 -323.463422) (xy 212.815832 -323.411455)
			(xy 212.811848 -323.3583) (xy 212.347443 -323.3583) (xy 212.352705 -323.381352) (xy 212.356688 -323.4345)
			(xy 212.352705 -323.487648) (xy 212.340845 -323.539609) (xy 212.321373 -323.589222) (xy 212.294723 -323.635378)
			(xy 212.261492 -323.677047) (xy 212.222422 -323.713297) (xy 212.178385 -323.74332) (xy 212.130365 -323.766443)
			(xy 212.079435 -323.782151) (xy 212.026733 -323.790092) (xy 212.000084 -323.790564) (xy 211.973674 -323.790112)
			(xy 211.921434 -323.782307) (xy 211.870919 -323.766871) (xy 211.823239 -323.744143) (xy 211.77944 -323.71462)
			(xy 211.740482 -323.678952) (xy 211.723478 -323.658738) (xy 211.713541 -323.647345) (xy 211.688488 -323.630454)
			(xy 211.659592 -323.621623) (xy 211.629376 -323.621623) (xy 211.60048 -323.630454) (xy 211.575427 -323.647345)
			(xy 211.56549 -323.658738) (xy 211.548506 -323.678968) (xy 211.50954 -323.714626) (xy 211.465735 -323.744139)
			(xy 211.418051 -323.766859) (xy 211.367535 -323.782287) (xy 211.315294 -323.790086) (xy 211.288884 -323.790564)
			(xy 211.262232 -323.790153) (xy 211.209524 -323.782206) (xy 211.158589 -323.766493) (xy 211.110565 -323.743364)
			(xy 211.066524 -323.713336) (xy 211.027451 -323.677079) (xy 210.994217 -323.635404) (xy 210.967566 -323.589241)
			(xy 210.948093 -323.539622) (xy 210.936232 -323.487655) (xy 210.932248 -323.4345) (xy 208.876888 -323.4345)
			(xy 208.872905 -323.487648) (xy 208.861045 -323.539609) (xy 208.841573 -323.589222) (xy 208.814923 -323.635378)
			(xy 208.781692 -323.677047) (xy 208.742622 -323.713297) (xy 208.698585 -323.74332) (xy 208.650565 -323.766443)
			(xy 208.599635 -323.782151) (xy 208.546933 -323.790092) (xy 208.520284 -323.790564) (xy 208.493874 -323.790112)
			(xy 208.441634 -323.782307) (xy 208.391119 -323.766871) (xy 208.343439 -323.744143) (xy 208.29964 -323.71462)
			(xy 208.260682 -323.678952) (xy 208.243678 -323.658738) (xy 208.233741 -323.647345) (xy 208.208688 -323.630454)
			(xy 208.179792 -323.621623) (xy 208.149576 -323.621623) (xy 208.12068 -323.630454) (xy 208.095627 -323.647345)
			(xy 208.08569 -323.658738) (xy 208.068706 -323.678968) (xy 208.02974 -323.714626) (xy 207.985935 -323.744139)
			(xy 207.938251 -323.766859) (xy 207.887735 -323.782287) (xy 207.835494 -323.790086) (xy 207.809084 -323.790564)
			(xy 207.782432 -323.790153) (xy 207.729724 -323.782206) (xy 207.678789 -323.766493) (xy 207.630765 -323.743364)
			(xy 207.586724 -323.713336) (xy 207.547651 -323.677079) (xy 207.514417 -323.635404) (xy 207.487766 -323.589241)
			(xy 207.468293 -323.539622) (xy 207.456432 -323.487655) (xy 207.452448 -323.4345) (xy 204.812888 -323.4345)
			(xy 204.808905 -323.487648) (xy 204.797045 -323.539609) (xy 204.777573 -323.589222) (xy 204.750923 -323.635378)
			(xy 204.717692 -323.677047) (xy 204.678622 -323.713297) (xy 204.634585 -323.74332) (xy 204.586565 -323.766443)
			(xy 204.535635 -323.782151) (xy 204.482933 -323.790092) (xy 204.456284 -323.790564) (xy 204.429874 -323.790112)
			(xy 204.377634 -323.782307) (xy 204.327119 -323.766871) (xy 204.279439 -323.744143) (xy 204.23564 -323.71462)
			(xy 204.196682 -323.678952) (xy 204.179678 -323.658738) (xy 204.169741 -323.647345) (xy 204.144688 -323.630454)
			(xy 204.115792 -323.621623) (xy 204.085576 -323.621623) (xy 204.05668 -323.630454) (xy 204.031627 -323.647345)
			(xy 204.02169 -323.658738) (xy 204.004706 -323.678968) (xy 203.96574 -323.714626) (xy 203.921935 -323.744139)
			(xy 203.874251 -323.766859) (xy 203.823735 -323.782287) (xy 203.771494 -323.790086) (xy 203.745084 -323.790564)
			(xy 203.718432 -323.790153) (xy 203.665724 -323.782206) (xy 203.614789 -323.766493) (xy 203.566765 -323.743364)
			(xy 203.522724 -323.713336) (xy 203.483651 -323.677079) (xy 203.450417 -323.635404) (xy 203.423766 -323.589241)
			(xy 203.404293 -323.539622) (xy 203.392432 -323.487655) (xy 203.388448 -323.4345) (xy 201.333088 -323.4345)
			(xy 201.329105 -323.487648) (xy 201.317245 -323.539609) (xy 201.297773 -323.589222) (xy 201.271123 -323.635378)
			(xy 201.237892 -323.677047) (xy 201.198822 -323.713297) (xy 201.154785 -323.74332) (xy 201.106765 -323.766443)
			(xy 201.055835 -323.782151) (xy 201.003133 -323.790092) (xy 200.976484 -323.790564) (xy 200.950074 -323.790112)
			(xy 200.897834 -323.782307) (xy 200.847319 -323.766871) (xy 200.799639 -323.744143) (xy 200.75584 -323.71462)
			(xy 200.716882 -323.678952) (xy 200.699878 -323.658738) (xy 200.689941 -323.647345) (xy 200.664888 -323.630454)
			(xy 200.635992 -323.621623) (xy 200.605776 -323.621623) (xy 200.57688 -323.630454) (xy 200.551827 -323.647345)
			(xy 200.54189 -323.658738) (xy 200.524906 -323.678968) (xy 200.48594 -323.714626) (xy 200.442135 -323.744139)
			(xy 200.394451 -323.766859) (xy 200.343935 -323.782287) (xy 200.291694 -323.790086) (xy 200.265284 -323.790564)
			(xy 200.238632 -323.790153) (xy 200.185924 -323.782206) (xy 200.134989 -323.766493) (xy 200.086965 -323.743364)
			(xy 200.042924 -323.713336) (xy 200.003851 -323.677079) (xy 199.970617 -323.635404) (xy 199.943966 -323.589241)
			(xy 199.924493 -323.539622) (xy 199.912632 -323.487655) (xy 199.908648 -323.4345) (xy 197.269088 -323.4345)
			(xy 197.265105 -323.487648) (xy 197.253245 -323.539609) (xy 197.233773 -323.589222) (xy 197.207123 -323.635378)
			(xy 197.173892 -323.677047) (xy 197.134822 -323.713297) (xy 197.090785 -323.74332) (xy 197.042765 -323.766443)
			(xy 196.991835 -323.782151) (xy 196.939133 -323.790092) (xy 196.912484 -323.790564) (xy 196.886074 -323.790112)
			(xy 196.833834 -323.782307) (xy 196.783319 -323.766871) (xy 196.735639 -323.744143) (xy 196.69184 -323.71462)
			(xy 196.652882 -323.678952) (xy 196.635878 -323.658738) (xy 196.625941 -323.647345) (xy 196.600888 -323.630454)
			(xy 196.571992 -323.621623) (xy 196.541776 -323.621623) (xy 196.51288 -323.630454) (xy 196.487827 -323.647345)
			(xy 196.47789 -323.658738) (xy 196.460906 -323.678968) (xy 196.42194 -323.714626) (xy 196.378135 -323.744139)
			(xy 196.330451 -323.766859) (xy 196.279935 -323.782287) (xy 196.227694 -323.790086) (xy 196.201284 -323.790564)
			(xy 196.174632 -323.790153) (xy 196.121924 -323.782206) (xy 196.070989 -323.766493) (xy 196.022965 -323.743364)
			(xy 195.978924 -323.713336) (xy 195.939851 -323.677079) (xy 195.906617 -323.635404) (xy 195.879966 -323.589241)
			(xy 195.860493 -323.539622) (xy 195.848632 -323.487655) (xy 195.844648 -323.4345) (xy 193.789288 -323.4345)
			(xy 193.785305 -323.487648) (xy 193.773445 -323.539609) (xy 193.753973 -323.589222) (xy 193.727323 -323.635378)
			(xy 193.694092 -323.677047) (xy 193.655022 -323.713297) (xy 193.610985 -323.74332) (xy 193.562965 -323.766443)
			(xy 193.512035 -323.782151) (xy 193.459333 -323.790092) (xy 193.432684 -323.790564) (xy 193.406274 -323.790112)
			(xy 193.354034 -323.782307) (xy 193.303519 -323.766871) (xy 193.255839 -323.744143) (xy 193.21204 -323.71462)
			(xy 193.173082 -323.678952) (xy 193.156078 -323.658738) (xy 193.146141 -323.647345) (xy 193.121088 -323.630454)
			(xy 193.092192 -323.621623) (xy 193.061976 -323.621623) (xy 193.03308 -323.630454) (xy 193.008027 -323.647345)
			(xy 192.99809 -323.658738) (xy 192.981106 -323.678968) (xy 192.94214 -323.714626) (xy 192.898335 -323.744139)
			(xy 192.850651 -323.766859) (xy 192.800135 -323.782287) (xy 192.747894 -323.790086) (xy 192.721484 -323.790564)
			(xy 192.694832 -323.790153) (xy 192.642124 -323.782206) (xy 192.591189 -323.766493) (xy 192.543165 -323.743364)
			(xy 192.499124 -323.713336) (xy 192.460051 -323.677079) (xy 192.426817 -323.635404) (xy 192.400166 -323.589241)
			(xy 192.380693 -323.539622) (xy 192.368832 -323.487655) (xy 192.364848 -323.4345) (xy 189.725288 -323.4345)
			(xy 189.721305 -323.487648) (xy 189.709445 -323.539609) (xy 189.689973 -323.589222) (xy 189.663323 -323.635378)
			(xy 189.630092 -323.677047) (xy 189.591022 -323.713297) (xy 189.546985 -323.74332) (xy 189.498965 -323.766443)
			(xy 189.448035 -323.782151) (xy 189.395333 -323.790092) (xy 189.368684 -323.790564) (xy 189.342274 -323.790112)
			(xy 189.290034 -323.782307) (xy 189.239519 -323.766871) (xy 189.191839 -323.744143) (xy 189.14804 -323.71462)
			(xy 189.109082 -323.678952) (xy 189.092078 -323.658738) (xy 189.082141 -323.647345) (xy 189.057088 -323.630454)
			(xy 189.028192 -323.621623) (xy 188.997976 -323.621623) (xy 188.96908 -323.630454) (xy 188.944027 -323.647345)
			(xy 188.93409 -323.658738) (xy 188.917106 -323.678968) (xy 188.87814 -323.714626) (xy 188.834335 -323.744139)
			(xy 188.786651 -323.766859) (xy 188.736135 -323.782287) (xy 188.683894 -323.790086) (xy 188.657484 -323.790564)
			(xy 188.630832 -323.790153) (xy 188.578124 -323.782206) (xy 188.527189 -323.766493) (xy 188.479165 -323.743364)
			(xy 188.435124 -323.713336) (xy 188.396051 -323.677079) (xy 188.362817 -323.635404) (xy 188.336166 -323.589241)
			(xy 188.316693 -323.539622) (xy 188.304832 -323.487655) (xy 188.300848 -323.4345) (xy 186.123184 -323.4345)
			(xy 186.125088 -323.4599) (xy 186.121105 -323.513048) (xy 186.109245 -323.565008) (xy 186.089773 -323.614621)
			(xy 186.063124 -323.660777) (xy 186.029894 -323.702446) (xy 185.990824 -323.738696) (xy 185.946787 -323.768718)
			(xy 185.898768 -323.791842) (xy 185.847838 -323.80755) (xy 185.795136 -323.815492) (xy 185.768488 -323.815964)
			(xy 185.741928 -323.815472) (xy 185.689398 -323.807568) (xy 185.638624 -323.791952) (xy 185.590732 -323.76897)
			(xy 185.546783 -323.739132) (xy 185.526934 -323.721476) (xy 185.516102 -323.712144) (xy 185.490547 -323.699353)
			(xy 185.462448 -323.69415) (xy 185.434007 -323.696942) (xy 185.407456 -323.707511) (xy 185.39587 -323.715888)
			(xy 185.372292 -323.733415) (xy 185.320587 -323.761302) (xy 185.265006 -323.780324) (xy 185.207057 -323.789964)
			(xy 185.177684 -323.790564) (xy 185.151032 -323.790153) (xy 185.098324 -323.782206) (xy 185.047389 -323.766493)
			(xy 184.999365 -323.743364) (xy 184.955324 -323.713336) (xy 184.916251 -323.677079) (xy 184.883017 -323.635404)
			(xy 184.856366 -323.589241) (xy 184.836893 -323.539622) (xy 184.825032 -323.487655) (xy 184.821048 -323.4345)
			(xy 182.181488 -323.4345) (xy 182.177505 -323.487648) (xy 182.165645 -323.539609) (xy 182.146173 -323.589222)
			(xy 182.119523 -323.635378) (xy 182.086292 -323.677047) (xy 182.047222 -323.713297) (xy 182.003185 -323.74332)
			(xy 181.955165 -323.766443) (xy 181.904235 -323.782151) (xy 181.851533 -323.790092) (xy 181.824884 -323.790564)
			(xy 181.798474 -323.790112) (xy 181.746234 -323.782307) (xy 181.695719 -323.766871) (xy 181.648039 -323.744143)
			(xy 181.60424 -323.71462) (xy 181.565282 -323.678952) (xy 181.548278 -323.658738) (xy 181.538341 -323.647345)
			(xy 181.513288 -323.630454) (xy 181.484392 -323.621623) (xy 181.454176 -323.621623) (xy 181.42528 -323.630454)
			(xy 181.400227 -323.647345) (xy 181.39029 -323.658738) (xy 181.373306 -323.678968) (xy 181.33434 -323.714626)
			(xy 181.290535 -323.744139) (xy 181.242851 -323.766859) (xy 181.192335 -323.782287) (xy 181.140094 -323.790086)
			(xy 181.113684 -323.790564) (xy 181.087032 -323.790153) (xy 181.034324 -323.782206) (xy 180.983389 -323.766493)
			(xy 180.935365 -323.743364) (xy 180.891324 -323.713336) (xy 180.852251 -323.677079) (xy 180.819017 -323.635404)
			(xy 180.792366 -323.589241) (xy 180.772893 -323.539622) (xy 180.761032 -323.487655) (xy 180.757048 -323.4345)
			(xy 178.701688 -323.4345) (xy 178.697705 -323.487648) (xy 178.685845 -323.539609) (xy 178.666373 -323.589222)
			(xy 178.639723 -323.635378) (xy 178.606492 -323.677047) (xy 178.567422 -323.713297) (xy 178.523385 -323.74332)
			(xy 178.475365 -323.766443) (xy 178.424435 -323.782151) (xy 178.371733 -323.790092) (xy 178.345084 -323.790564)
			(xy 178.318674 -323.790112) (xy 178.266434 -323.782307) (xy 178.215919 -323.766871) (xy 178.168239 -323.744143)
			(xy 178.12444 -323.71462) (xy 178.085482 -323.678952) (xy 178.068478 -323.658738) (xy 178.058541 -323.647345)
			(xy 178.033488 -323.630454) (xy 178.004592 -323.621623) (xy 177.974376 -323.621623) (xy 177.94548 -323.630454)
			(xy 177.920427 -323.647345) (xy 177.91049 -323.658738) (xy 177.893506 -323.678968) (xy 177.85454 -323.714626)
			(xy 177.810735 -323.744139) (xy 177.763051 -323.766859) (xy 177.712535 -323.782287) (xy 177.660294 -323.790086)
			(xy 177.633884 -323.790564) (xy 177.607232 -323.790153) (xy 177.554524 -323.782206) (xy 177.503589 -323.766493)
			(xy 177.455565 -323.743364) (xy 177.411524 -323.713336) (xy 177.372451 -323.677079) (xy 177.339217 -323.635404)
			(xy 177.312566 -323.589241) (xy 177.293093 -323.539622) (xy 177.281232 -323.487655) (xy 177.277248 -323.4345)
			(xy 174.637688 -323.4345) (xy 174.633705 -323.487648) (xy 174.621845 -323.539609) (xy 174.602373 -323.589222)
			(xy 174.575723 -323.635378) (xy 174.542492 -323.677047) (xy 174.503422 -323.713297) (xy 174.459385 -323.74332)
			(xy 174.411365 -323.766443) (xy 174.360435 -323.782151) (xy 174.307733 -323.790092) (xy 174.281084 -323.790564)
			(xy 174.254674 -323.790112) (xy 174.202434 -323.782307) (xy 174.151919 -323.766871) (xy 174.104239 -323.744143)
			(xy 174.06044 -323.71462) (xy 174.021482 -323.678952) (xy 174.004478 -323.658738) (xy 173.994541 -323.647345)
			(xy 173.969488 -323.630454) (xy 173.940592 -323.621623) (xy 173.910376 -323.621623) (xy 173.88148 -323.630454)
			(xy 173.856427 -323.647345) (xy 173.84649 -323.658738) (xy 173.829506 -323.678968) (xy 173.79054 -323.714626)
			(xy 173.746735 -323.744139) (xy 173.699051 -323.766859) (xy 173.648535 -323.782287) (xy 173.596294 -323.790086)
			(xy 173.569884 -323.790564) (xy 173.543232 -323.790153) (xy 173.490524 -323.782206) (xy 173.439589 -323.766493)
			(xy 173.391565 -323.743364) (xy 173.347524 -323.713336) (xy 173.308451 -323.677079) (xy 173.275217 -323.635404)
			(xy 173.248566 -323.589241) (xy 173.229093 -323.539622) (xy 173.217232 -323.487655) (xy 173.213248 -323.4345)
			(xy 171.157888 -323.4345) (xy 171.153905 -323.487648) (xy 171.142045 -323.539609) (xy 171.122573 -323.589222)
			(xy 171.095923 -323.635378) (xy 171.062692 -323.677047) (xy 171.023622 -323.713297) (xy 170.979585 -323.74332)
			(xy 170.931565 -323.766443) (xy 170.880635 -323.782151) (xy 170.827933 -323.790092) (xy 170.801284 -323.790564)
			(xy 170.774874 -323.790112) (xy 170.722634 -323.782307) (xy 170.672119 -323.766871) (xy 170.624439 -323.744143)
			(xy 170.58064 -323.71462) (xy 170.541682 -323.678952) (xy 170.524678 -323.658738) (xy 170.514741 -323.647345)
			(xy 170.489688 -323.630454) (xy 170.460792 -323.621623) (xy 170.430576 -323.621623) (xy 170.40168 -323.630454)
			(xy 170.376627 -323.647345) (xy 170.36669 -323.658738) (xy 170.349706 -323.678968) (xy 170.31074 -323.714626)
			(xy 170.266935 -323.744139) (xy 170.219251 -323.766859) (xy 170.168735 -323.782287) (xy 170.116494 -323.790086)
			(xy 170.090084 -323.790564) (xy 170.063432 -323.790153) (xy 170.010724 -323.782206) (xy 169.959789 -323.766493)
			(xy 169.911765 -323.743364) (xy 169.867724 -323.713336) (xy 169.828651 -323.677079) (xy 169.795417 -323.635404)
			(xy 169.768766 -323.589241) (xy 169.749293 -323.539622) (xy 169.737432 -323.487655) (xy 169.733448 -323.4345)
			(xy 167.093888 -323.4345) (xy 167.089905 -323.487648) (xy 167.078045 -323.539609) (xy 167.058573 -323.589222)
			(xy 167.031923 -323.635378) (xy 166.998692 -323.677047) (xy 166.959622 -323.713297) (xy 166.915585 -323.74332)
			(xy 166.867565 -323.766443) (xy 166.816635 -323.782151) (xy 166.763933 -323.790092) (xy 166.737284 -323.790564)
			(xy 166.710874 -323.790112) (xy 166.658634 -323.782307) (xy 166.608119 -323.766871) (xy 166.560439 -323.744143)
			(xy 166.51664 -323.71462) (xy 166.477682 -323.678952) (xy 166.460678 -323.658738) (xy 166.450741 -323.647345)
			(xy 166.425688 -323.630454) (xy 166.396792 -323.621623) (xy 166.366576 -323.621623) (xy 166.33768 -323.630454)
			(xy 166.312627 -323.647345) (xy 166.30269 -323.658738) (xy 166.285706 -323.678968) (xy 166.24674 -323.714626)
			(xy 166.202935 -323.744139) (xy 166.155251 -323.766859) (xy 166.104735 -323.782287) (xy 166.052494 -323.790086)
			(xy 166.026084 -323.790564) (xy 165.999432 -323.790153) (xy 165.946724 -323.782206) (xy 165.895789 -323.766493)
			(xy 165.847765 -323.743364) (xy 165.803724 -323.713336) (xy 165.764651 -323.677079) (xy 165.731417 -323.635404)
			(xy 165.704766 -323.589241) (xy 165.685293 -323.539622) (xy 165.673432 -323.487655) (xy 165.669448 -323.4345)
			(xy 163.614088 -323.4345) (xy 163.610105 -323.487648) (xy 163.598245 -323.539609) (xy 163.578773 -323.589222)
			(xy 163.552123 -323.635378) (xy 163.518892 -323.677047) (xy 163.479822 -323.713297) (xy 163.435785 -323.74332)
			(xy 163.387765 -323.766443) (xy 163.336835 -323.782151) (xy 163.284133 -323.790092) (xy 163.257484 -323.790564)
			(xy 163.231074 -323.790112) (xy 163.178834 -323.782307) (xy 163.128319 -323.766871) (xy 163.080639 -323.744143)
			(xy 163.03684 -323.71462) (xy 162.997882 -323.678952) (xy 162.980878 -323.658738) (xy 162.970941 -323.647345)
			(xy 162.945888 -323.630454) (xy 162.916992 -323.621623) (xy 162.886776 -323.621623) (xy 162.85788 -323.630454)
			(xy 162.832827 -323.647345) (xy 162.82289 -323.658738) (xy 162.805906 -323.678968) (xy 162.76694 -323.714626)
			(xy 162.723135 -323.744139) (xy 162.675451 -323.766859) (xy 162.624935 -323.782287) (xy 162.572694 -323.790086)
			(xy 162.546284 -323.790564) (xy 162.519632 -323.790153) (xy 162.466924 -323.782206) (xy 162.415989 -323.766493)
			(xy 162.367965 -323.743364) (xy 162.323924 -323.713336) (xy 162.284851 -323.677079) (xy 162.251617 -323.635404)
			(xy 162.224966 -323.589241) (xy 162.205493 -323.539622) (xy 162.193632 -323.487655) (xy 162.189648 -323.4345)
			(xy 159.774881 -323.4345) (xy 159.774705 -323.436848) (xy 159.762845 -323.488809) (xy 159.743373 -323.538422)
			(xy 159.716723 -323.584578) (xy 159.683492 -323.626247) (xy 159.644422 -323.662497) (xy 159.600385 -323.69252)
			(xy 159.552365 -323.715643) (xy 159.501435 -323.731351) (xy 159.448733 -323.739292) (xy 159.422084 -323.739764)
			(xy 159.396114 -323.739283) (xy 159.344723 -323.731753) (xy 159.294969 -323.716839) (xy 159.24791 -323.694859)
			(xy 159.20454 -323.666277) (xy 159.184848 -323.64934) (xy 159.173454 -323.639852) (xy 159.146606 -323.627303)
			(xy 159.117284 -323.622999) (xy 159.087962 -323.627303) (xy 159.061114 -323.639852) (xy 159.04972 -323.64934)
			(xy 159.030038 -323.66629) (xy 158.986664 -323.694866) (xy 158.939601 -323.716844) (xy 158.889847 -323.731759)
			(xy 158.838455 -323.739296) (xy 158.812484 -323.739764) (xy 158.785832 -323.739353) (xy 158.733124 -323.731406)
			(xy 158.682189 -323.715693) (xy 158.634165 -323.692564) (xy 158.590124 -323.662536) (xy 158.551051 -323.626279)
			(xy 158.517817 -323.584604) (xy 158.491166 -323.538441) (xy 158.471693 -323.488822) (xy 158.459832 -323.436855)
			(xy 158.455848 -323.3837) (xy 155.000198 -323.3837) (xy 155.000198 -327.108978) (xy 159.326536 -327.108978)
			(xy 159.326536 -327.024422) (xy 159.334338 -326.940228) (xy 159.349875 -326.857112) (xy 159.373014 -326.775785)
			(xy 159.403559 -326.696939) (xy 159.441248 -326.621248) (xy 159.48576 -326.549358) (xy 159.536715 -326.481881)
			(xy 159.593679 -326.419393) (xy 159.656165 -326.362428) (xy 159.723641 -326.311471) (xy 159.795531 -326.266957)
			(xy 159.871221 -326.229267) (xy 159.950066 -326.19872) (xy 160.031393 -326.175579) (xy 160.114508 -326.160041)
			(xy 160.198702 -326.152237) (xy 160.24098 -326.151748) (xy 161.48558 -326.151748) (xy 161.527855 -326.152308)
			(xy 161.612046 -326.160108) (xy 161.695157 -326.175643) (xy 161.776481 -326.19878) (xy 161.855323 -326.229321)
			(xy 161.93101 -326.267008) (xy 162.002897 -326.311517) (xy 162.070371 -326.36247) (xy 162.132855 -326.41943)
			(xy 162.189818 -326.481914) (xy 162.240772 -326.549386) (xy 162.285282 -326.621272) (xy 162.32297 -326.696959)
			(xy 162.353514 -326.7758) (xy 162.376653 -326.857123) (xy 162.392189 -326.940234) (xy 162.399991 -327.024425)
			(xy 162.399991 -327.108975) (xy 162.399991 -327.108978) (xy 166.870336 -327.108978) (xy 166.870336 -327.024422)
			(xy 166.878138 -326.940228) (xy 166.893675 -326.857112) (xy 166.916814 -326.775785) (xy 166.947359 -326.696939)
			(xy 166.985048 -326.621248) (xy 167.02956 -326.549358) (xy 167.080515 -326.481881) (xy 167.137479 -326.419393)
			(xy 167.199965 -326.362428) (xy 167.267441 -326.311471) (xy 167.339331 -326.266957) (xy 167.415021 -326.229267)
			(xy 167.493866 -326.19872) (xy 167.575193 -326.175579) (xy 167.658308 -326.160041) (xy 167.742502 -326.152237)
			(xy 167.78478 -326.151748) (xy 169.02938 -326.151748) (xy 169.071655 -326.152308) (xy 169.155846 -326.160108)
			(xy 169.238957 -326.175643) (xy 169.320281 -326.19878) (xy 169.399123 -326.229321) (xy 169.47481 -326.267008)
			(xy 169.546697 -326.311517) (xy 169.614171 -326.36247) (xy 169.676655 -326.41943) (xy 169.733618 -326.481914)
			(xy 169.784572 -326.549386) (xy 169.829082 -326.621272) (xy 169.86677 -326.696959) (xy 169.897314 -326.7758)
			(xy 169.920453 -326.857123) (xy 169.935989 -326.940234) (xy 169.943791 -327.024425) (xy 169.943791 -327.108975)
			(xy 169.943791 -327.108978) (xy 174.414136 -327.108978) (xy 174.414136 -327.024422) (xy 174.421938 -326.940228)
			(xy 174.437475 -326.857112) (xy 174.460614 -326.775785) (xy 174.491159 -326.696939) (xy 174.528848 -326.621248)
			(xy 174.57336 -326.549358) (xy 174.624315 -326.481881) (xy 174.681279 -326.419393) (xy 174.743765 -326.362428)
			(xy 174.811241 -326.311471) (xy 174.883131 -326.266957) (xy 174.958821 -326.229267) (xy 175.037666 -326.19872)
			(xy 175.118993 -326.175579) (xy 175.202108 -326.160041) (xy 175.286302 -326.152237) (xy 175.32858 -326.151748)
			(xy 176.57318 -326.151748) (xy 176.615455 -326.152308) (xy 176.699646 -326.160108) (xy 176.782757 -326.175643)
			(xy 176.864081 -326.19878) (xy 176.942923 -326.229321) (xy 177.01861 -326.267008) (xy 177.090497 -326.311517)
			(xy 177.157971 -326.36247) (xy 177.220455 -326.41943) (xy 177.277418 -326.481914) (xy 177.328372 -326.549386)
			(xy 177.372882 -326.621272) (xy 177.41057 -326.696959) (xy 177.441114 -326.7758) (xy 177.451456 -326.812148)
			(xy 178.870862 -326.812148) (xy 178.874933 -326.756526) (xy 178.887059 -326.702089) (xy 178.906982 -326.649998)
			(xy 178.934278 -326.601363) (xy 178.968364 -326.55722) (xy 179.008513 -326.518511) (xy 179.053871 -326.48606)
			(xy 179.103471 -326.460559) (xy 179.156255 -326.442552) (xy 179.211098 -326.432422) (xy 179.266832 -326.430385)
			(xy 179.322269 -326.436485) (xy 179.376226 -326.450591) (xy 179.427555 -326.472403) (xy 179.475161 -326.501457)
			(xy 179.518029 -326.537132) (xy 179.555246 -326.578669) (xy 179.586019 -326.625182) (xy 179.609691 -326.675679)
			(xy 179.620723 -326.712347) (xy 180.395926 -326.712347) (xy 180.395926 -326.657853) (xy 180.403681 -326.603914)
			(xy 180.419033 -326.551627) (xy 180.44167 -326.502058) (xy 180.471131 -326.456214) (xy 180.506816 -326.41503)
			(xy 180.547998 -326.379343) (xy 180.59384 -326.34988) (xy 180.643409 -326.32724) (xy 180.695694 -326.311885)
			(xy 180.749633 -326.304128) (xy 180.77688 -326.30364) (xy 180.792509 -326.303797) (xy 180.823663 -326.306341)
			(xy 180.83911 -326.30872) (xy 180.853915 -326.310687) (xy 180.883515 -326.306789) (xy 180.910729 -326.29451)
			(xy 180.933239 -326.274897) (xy 180.949128 -326.249619) (xy 180.957041 -326.220831) (xy 180.956306 -326.190984)
			(xy 180.95214 -326.17664) (xy 180.943146 -326.147552) (xy 180.93345 -326.087447) (xy 180.932836 -326.057006)
			(xy 180.933322 -326.029755) (xy 180.941078 -325.975807) (xy 180.956433 -325.923512) (xy 180.979075 -325.873935)
			(xy 181.008541 -325.828085) (xy 181.044232 -325.786894) (xy 181.085423 -325.751203) (xy 181.131273 -325.721737)
			(xy 181.18085 -325.699095) (xy 181.233145 -325.68374) (xy 181.287093 -325.675984) (xy 181.341595 -325.675984)
			(xy 181.395543 -325.68374) (xy 181.447838 -325.699095) (xy 181.497415 -325.721737) (xy 181.543265 -325.751203)
			(xy 181.584456 -325.786894) (xy 181.620147 -325.828085) (xy 181.649613 -325.873935) (xy 181.672255 -325.923512)
			(xy 181.68761 -325.975807) (xy 181.695366 -326.029755) (xy 181.695852 -326.057006) (xy 181.695398 -326.083657)
			(xy 181.687974 -326.13644) (xy 181.673273 -326.187675) (xy 181.662832 -326.2122) (xy 181.657016 -326.226601)
			(xy 181.653488 -326.257443) (xy 181.659384 -326.287921) (xy 181.674158 -326.315223) (xy 181.696449 -326.336828)
			(xy 181.710076 -326.34428) (xy 181.732863 -326.356168) (xy 181.775287 -326.385182) (xy 181.813428 -326.419634)
			(xy 181.846594 -326.458898) (xy 181.874184 -326.502261) (xy 181.895698 -326.548939) (xy 181.903624 -326.573388)
			(xy 181.9083 -326.587317) (xy 181.924494 -326.611825) (xy 181.946989 -326.630716) (xy 181.973927 -326.64243)
			(xy 182.003084 -326.646) (xy 182.032053 -326.64113) (xy 182.058441 -326.628225) (xy 182.080069 -326.608348)
			(xy 182.088028 -326.595994) (xy 182.110525 -326.559521) (xy 182.161296 -326.490479) (xy 182.2183 -326.426486)
			(xy 182.281037 -326.368104) (xy 182.348958 -326.315843) (xy 182.421469 -326.270162) (xy 182.497933 -326.231461)
			(xy 182.57768 -326.200079) (xy 182.660012 -326.176291) (xy 182.744208 -326.160306) (xy 182.82953 -326.152263)
			(xy 182.87238 -326.151748) (xy 184.11698 -326.151748) (xy 184.159255 -326.152308) (xy 184.243446 -326.160108)
			(xy 184.326557 -326.175643) (xy 184.407881 -326.19878) (xy 184.486723 -326.229321) (xy 184.56241 -326.267008)
			(xy 184.634297 -326.311517) (xy 184.701771 -326.36247) (xy 184.764255 -326.41943) (xy 184.821218 -326.481914)
			(xy 184.872172 -326.549386) (xy 184.916682 -326.621272) (xy 184.95437 -326.696959) (xy 184.984914 -326.7758)
			(xy 185.008053 -326.857123) (xy 185.023589 -326.940234) (xy 185.031391 -327.024425) (xy 185.031391 -327.108975)
			(xy 185.031391 -327.108978) (xy 189.501736 -327.108978) (xy 189.501736 -327.024422) (xy 189.509538 -326.940228)
			(xy 189.525075 -326.857112) (xy 189.548214 -326.775785) (xy 189.578759 -326.696939) (xy 189.616448 -326.621248)
			(xy 189.66096 -326.549358) (xy 189.711915 -326.481881) (xy 189.768879 -326.419393) (xy 189.831365 -326.362428)
			(xy 189.898841 -326.311471) (xy 189.970731 -326.266957) (xy 190.046421 -326.229267) (xy 190.125266 -326.19872)
			(xy 190.206593 -326.175579) (xy 190.289708 -326.160041) (xy 190.373902 -326.152237) (xy 190.41618 -326.151748)
			(xy 191.66078 -326.151748) (xy 191.703055 -326.152308) (xy 191.787246 -326.160108) (xy 191.870357 -326.175643)
			(xy 191.951681 -326.19878) (xy 192.030523 -326.229321) (xy 192.10621 -326.267008) (xy 192.178097 -326.311517)
			(xy 192.245571 -326.36247) (xy 192.308055 -326.41943) (xy 192.365018 -326.481914) (xy 192.415972 -326.549386)
			(xy 192.460482 -326.621272) (xy 192.49817 -326.696959) (xy 192.528714 -326.7758) (xy 192.551853 -326.857123)
			(xy 192.567389 -326.940234) (xy 192.575191 -327.024425) (xy 192.575191 -327.108975) (xy 192.575191 -327.108978)
			(xy 197.045536 -327.108978) (xy 197.045536 -327.024422) (xy 197.053338 -326.940228) (xy 197.068875 -326.857112)
			(xy 197.092014 -326.775785) (xy 197.122559 -326.696939) (xy 197.160248 -326.621248) (xy 197.20476 -326.549358)
			(xy 197.255715 -326.481881) (xy 197.312679 -326.419393) (xy 197.375165 -326.362428) (xy 197.442641 -326.311471)
			(xy 197.514531 -326.266957) (xy 197.590221 -326.229267) (xy 197.669066 -326.19872) (xy 197.750393 -326.175579)
			(xy 197.833508 -326.160041) (xy 197.917702 -326.152237) (xy 197.95998 -326.151748) (xy 199.20458 -326.151748)
			(xy 199.246855 -326.152308) (xy 199.331046 -326.160108) (xy 199.414157 -326.175643) (xy 199.495481 -326.19878)
			(xy 199.574323 -326.229321) (xy 199.65001 -326.267008) (xy 199.721897 -326.311517) (xy 199.789371 -326.36247)
			(xy 199.851855 -326.41943) (xy 199.908818 -326.481914) (xy 199.959772 -326.549386) (xy 200.004282 -326.621272)
			(xy 200.04197 -326.696959) (xy 200.072514 -326.7758) (xy 200.095653 -326.857123) (xy 200.111189 -326.940234)
			(xy 200.118991 -327.024425) (xy 200.118991 -327.108975) (xy 200.118991 -327.108978) (xy 204.589336 -327.108978)
			(xy 204.589336 -327.024422) (xy 204.597138 -326.940228) (xy 204.612675 -326.857112) (xy 204.635814 -326.775785)
			(xy 204.666359 -326.696939) (xy 204.704048 -326.621248) (xy 204.74856 -326.549358) (xy 204.799515 -326.481881)
			(xy 204.856479 -326.419393) (xy 204.918965 -326.362428) (xy 204.986441 -326.311471) (xy 205.058331 -326.266957)
			(xy 205.134021 -326.229267) (xy 205.212866 -326.19872) (xy 205.294193 -326.175579) (xy 205.377308 -326.160041)
			(xy 205.461502 -326.152237) (xy 205.50378 -326.151748) (xy 206.74838 -326.151748) (xy 206.790655 -326.152308)
			(xy 206.874846 -326.160108) (xy 206.957957 -326.175643) (xy 207.039281 -326.19878) (xy 207.118123 -326.229321)
			(xy 207.19381 -326.267008) (xy 207.265697 -326.311517) (xy 207.333171 -326.36247) (xy 207.395655 -326.41943)
			(xy 207.452618 -326.481914) (xy 207.503572 -326.549386) (xy 207.548082 -326.621272) (xy 207.58577 -326.696959)
			(xy 207.616314 -326.7758) (xy 207.639453 -326.857123) (xy 207.654989 -326.940234) (xy 207.662791 -327.024425)
			(xy 207.662791 -327.108975) (xy 207.654989 -327.193166) (xy 207.639453 -327.276277) (xy 207.616314 -327.3576)
			(xy 207.58577 -327.436441) (xy 207.548082 -327.512128) (xy 207.503572 -327.584014) (xy 207.452618 -327.651486)
			(xy 207.395655 -327.71397) (xy 207.333171 -327.77093) (xy 207.265697 -327.821883) (xy 207.19381 -327.866392)
			(xy 207.118123 -327.904079) (xy 207.039281 -327.93462) (xy 206.957957 -327.957757) (xy 206.874846 -327.973292)
			(xy 206.790655 -327.981092) (xy 206.74838 -327.981564) (xy 205.50378 -327.981564) (xy 205.461502 -327.981163)
			(xy 205.377308 -327.973359) (xy 205.294193 -327.957821) (xy 205.212866 -327.93468) (xy 205.134021 -327.904133)
			(xy 205.058331 -327.866443) (xy 204.986441 -327.821929) (xy 204.918965 -327.770972) (xy 204.856479 -327.714007)
			(xy 204.799515 -327.651519) (xy 204.74856 -327.584042) (xy 204.704048 -327.512152) (xy 204.666359 -327.436461)
			(xy 204.635814 -327.357615) (xy 204.612675 -327.276288) (xy 204.597138 -327.193172) (xy 204.589336 -327.108978)
			(xy 200.118991 -327.108978) (xy 200.111189 -327.193166) (xy 200.095653 -327.276277) (xy 200.072514 -327.3576)
			(xy 200.04197 -327.436441) (xy 200.004282 -327.512128) (xy 199.959772 -327.584014) (xy 199.908818 -327.651486)
			(xy 199.851855 -327.71397) (xy 199.789371 -327.77093) (xy 199.721897 -327.821883) (xy 199.65001 -327.866392)
			(xy 199.574323 -327.904079) (xy 199.495481 -327.93462) (xy 199.414157 -327.957757) (xy 199.331046 -327.973292)
			(xy 199.246855 -327.981092) (xy 199.20458 -327.981564) (xy 197.95998 -327.981564) (xy 197.917702 -327.981163)
			(xy 197.833508 -327.973359) (xy 197.750393 -327.957821) (xy 197.669066 -327.93468) (xy 197.590221 -327.904133)
			(xy 197.514531 -327.866443) (xy 197.442641 -327.821929) (xy 197.375165 -327.770972) (xy 197.312679 -327.714007)
			(xy 197.255715 -327.651519) (xy 197.20476 -327.584042) (xy 197.160248 -327.512152) (xy 197.122559 -327.436461)
			(xy 197.092014 -327.357615) (xy 197.068875 -327.276288) (xy 197.053338 -327.193172) (xy 197.045536 -327.108978)
			(xy 192.575191 -327.108978) (xy 192.567389 -327.193166) (xy 192.551853 -327.276277) (xy 192.528714 -327.3576)
			(xy 192.49817 -327.436441) (xy 192.460482 -327.512128) (xy 192.415972 -327.584014) (xy 192.365018 -327.651486)
			(xy 192.308055 -327.71397) (xy 192.245571 -327.77093) (xy 192.178097 -327.821883) (xy 192.10621 -327.866392)
			(xy 192.030523 -327.904079) (xy 191.951681 -327.93462) (xy 191.870357 -327.957757) (xy 191.787246 -327.973292)
			(xy 191.703055 -327.981092) (xy 191.66078 -327.981564) (xy 190.41618 -327.981564) (xy 190.373902 -327.981163)
			(xy 190.289708 -327.973359) (xy 190.206593 -327.957821) (xy 190.125266 -327.93468) (xy 190.046421 -327.904133)
			(xy 189.970731 -327.866443) (xy 189.898841 -327.821929) (xy 189.831365 -327.770972) (xy 189.768879 -327.714007)
			(xy 189.711915 -327.651519) (xy 189.66096 -327.584042) (xy 189.616448 -327.512152) (xy 189.578759 -327.436461)
			(xy 189.548214 -327.357615) (xy 189.525075 -327.276288) (xy 189.509538 -327.193172) (xy 189.501736 -327.108978)
			(xy 185.031391 -327.108978) (xy 185.023589 -327.193166) (xy 185.008053 -327.276277) (xy 184.984914 -327.3576)
			(xy 184.95437 -327.436441) (xy 184.916682 -327.512128) (xy 184.872172 -327.584014) (xy 184.821218 -327.651486)
			(xy 184.764255 -327.71397) (xy 184.701771 -327.77093) (xy 184.634297 -327.821883) (xy 184.56241 -327.866392)
			(xy 184.486723 -327.904079) (xy 184.407881 -327.93462) (xy 184.326557 -327.957757) (xy 184.243446 -327.973292)
			(xy 184.159255 -327.981092) (xy 184.11698 -327.981564) (xy 182.87238 -327.981564) (xy 182.830102 -327.981154)
			(xy 182.745905 -327.97335) (xy 182.662789 -327.95781) (xy 182.58146 -327.934668) (xy 182.502614 -327.90412)
			(xy 182.426923 -327.866428) (xy 182.355032 -327.821912) (xy 182.287556 -327.770953) (xy 182.22507 -327.713985)
			(xy 182.168106 -327.651495) (xy 182.117152 -327.584015) (xy 182.072641 -327.512121) (xy 182.034954 -327.436428)
			(xy 182.004411 -327.357579) (xy 181.981275 -327.276249) (xy 181.965741 -327.193131) (xy 181.957943 -327.108935)
			(xy 181.957472 -327.066656) (xy 181.957726 -327.051162) (xy 181.95744 -327.036491) (xy 181.949569 -327.008239)
			(xy 181.933997 -326.983387) (xy 181.912007 -326.963982) (xy 181.88541 -326.951623) (xy 181.856399 -326.947329)
			(xy 181.827362 -326.951454) (xy 181.800694 -326.963657) (xy 181.789324 -326.97293) (xy 181.768404 -326.990529)
			(xy 181.722465 -327.020166) (xy 181.672766 -327.04294) (xy 181.620324 -327.058386) (xy 181.566215 -327.066188)
			(xy 181.53888 -327.066656) (xy 181.509964 -327.066097) (xy 181.452794 -327.057378) (xy 181.397596 -327.04013)
			(xy 181.345633 -327.014746) (xy 181.298099 -326.981809) (xy 181.256081 -326.942073) (xy 181.23789 -326.91959)
			(xy 181.227993 -326.907785) (xy 181.202669 -326.890266) (xy 181.173276 -326.88109) (xy 181.142484 -326.88109)
			(xy 181.113091 -326.890266) (xy 181.087767 -326.907785) (xy 181.07787 -326.91959) (xy 181.059693 -326.942086)
			(xy 181.017671 -326.981821) (xy 180.970133 -327.014759) (xy 180.918169 -327.040145) (xy 180.862969 -327.057398)
			(xy 180.805797 -327.066123) (xy 180.77688 -327.066656) (xy 180.749633 -327.066072) (xy 180.695694 -327.058315)
			(xy 180.643409 -327.04296) (xy 180.59384 -327.02032) (xy 180.547998 -326.990857) (xy 180.506816 -326.95517)
			(xy 180.471131 -326.913986) (xy 180.44167 -326.868142) (xy 180.419033 -326.818573) (xy 180.403681 -326.766286)
			(xy 180.395926 -326.712347) (xy 179.620723 -326.712347) (xy 179.625759 -326.729086) (xy 179.633879 -326.784262)
			(xy 179.634388 -326.812148) (xy 179.633879 -326.840034) (xy 179.625759 -326.89521) (xy 179.609691 -326.948617)
			(xy 179.586019 -326.999114) (xy 179.555246 -327.045627) (xy 179.518029 -327.087164) (xy 179.475161 -327.122839)
			(xy 179.427555 -327.151893) (xy 179.376226 -327.173705) (xy 179.322269 -327.187811) (xy 179.266832 -327.193911)
			(xy 179.211098 -327.191874) (xy 179.156255 -327.181744) (xy 179.103471 -327.163737) (xy 179.053871 -327.138236)
			(xy 179.008513 -327.105785) (xy 178.968364 -327.067076) (xy 178.934278 -327.022933) (xy 178.906982 -326.974298)
			(xy 178.887059 -326.922207) (xy 178.874933 -326.86777) (xy 178.870862 -326.812148) (xy 177.451456 -326.812148)
			(xy 177.464253 -326.857123) (xy 177.479789 -326.940234) (xy 177.487591 -327.024425) (xy 177.487591 -327.108975)
			(xy 177.479789 -327.193166) (xy 177.464253 -327.276277) (xy 177.441114 -327.3576) (xy 177.41057 -327.436441)
			(xy 177.372882 -327.512128) (xy 177.328372 -327.584014) (xy 177.277418 -327.651486) (xy 177.220455 -327.71397)
			(xy 177.157971 -327.77093) (xy 177.121554 -327.79843) (xy 178.371752 -327.79843) (xy 178.375823 -327.742808)
			(xy 178.387949 -327.688371) (xy 178.407872 -327.63628) (xy 178.435168 -327.587645) (xy 178.469254 -327.543502)
			(xy 178.509403 -327.504793) (xy 178.554761 -327.472342) (xy 178.604361 -327.446841) (xy 178.657145 -327.428834)
			(xy 178.711988 -327.418704) (xy 178.767722 -327.416667) (xy 178.823159 -327.422767) (xy 178.877116 -327.436873)
			(xy 178.928445 -327.458685) (xy 178.976051 -327.487739) (xy 179.018919 -327.523414) (xy 179.056136 -327.564951)
			(xy 179.086909 -327.611464) (xy 179.110581 -327.661961) (xy 179.122371 -327.701148) (xy 179.378862 -327.701148)
			(xy 179.382933 -327.645526) (xy 179.395059 -327.591089) (xy 179.414982 -327.538998) (xy 179.442278 -327.490363)
			(xy 179.476364 -327.44622) (xy 179.516513 -327.407511) (xy 179.561871 -327.37506) (xy 179.611471 -327.349559)
			(xy 179.664255 -327.331552) (xy 179.719098 -327.321422) (xy 179.774832 -327.319385) (xy 179.830269 -327.325485)
			(xy 179.884226 -327.339591) (xy 179.935555 -327.361403) (xy 179.983161 -327.390457) (xy 180.026029 -327.426132)
			(xy 180.063246 -327.467669) (xy 180.094019 -327.514182) (xy 180.117691 -327.564679) (xy 180.133759 -327.618086)
			(xy 180.141879 -327.673262) (xy 180.142388 -327.701148) (xy 180.141879 -327.729034) (xy 180.133759 -327.78421)
			(xy 180.117691 -327.837617) (xy 180.094019 -327.888114) (xy 180.063246 -327.934627) (xy 180.026029 -327.976164)
			(xy 179.983161 -328.011839) (xy 179.935555 -328.040893) (xy 179.884226 -328.062705) (xy 179.830269 -328.076811)
			(xy 179.774832 -328.082911) (xy 179.719098 -328.080874) (xy 179.664255 -328.070744) (xy 179.611471 -328.052737)
			(xy 179.561871 -328.027236) (xy 179.516513 -327.994785) (xy 179.476364 -327.956076) (xy 179.442278 -327.911933)
			(xy 179.414982 -327.863298) (xy 179.395059 -327.811207) (xy 179.382933 -327.75677) (xy 179.378862 -327.701148)
			(xy 179.122371 -327.701148) (xy 179.126649 -327.715368) (xy 179.134769 -327.770544) (xy 179.135278 -327.79843)
			(xy 179.134769 -327.826316) (xy 179.126649 -327.881492) (xy 179.110581 -327.934899) (xy 179.086909 -327.985396)
			(xy 179.056136 -328.031909) (xy 179.018919 -328.073446) (xy 178.976051 -328.109121) (xy 178.928445 -328.138175)
			(xy 178.877116 -328.159987) (xy 178.823159 -328.174093) (xy 178.767722 -328.180193) (xy 178.711988 -328.178156)
			(xy 178.657145 -328.168026) (xy 178.604361 -328.150019) (xy 178.554761 -328.124518) (xy 178.509403 -328.092067)
			(xy 178.469254 -328.053358) (xy 178.435168 -328.009215) (xy 178.407872 -327.96058) (xy 178.387949 -327.908489)
			(xy 178.375823 -327.854052) (xy 178.371752 -327.79843) (xy 177.121554 -327.79843) (xy 177.090497 -327.821883)
			(xy 177.01861 -327.866392) (xy 176.942923 -327.904079) (xy 176.864081 -327.93462) (xy 176.782757 -327.957757)
			(xy 176.699646 -327.973292) (xy 176.615455 -327.981092) (xy 176.57318 -327.981564) (xy 175.32858 -327.981564)
			(xy 175.286302 -327.981163) (xy 175.202108 -327.973359) (xy 175.118993 -327.957821) (xy 175.037666 -327.93468)
			(xy 174.958821 -327.904133) (xy 174.883131 -327.866443) (xy 174.811241 -327.821929) (xy 174.743765 -327.770972)
			(xy 174.681279 -327.714007) (xy 174.624315 -327.651519) (xy 174.57336 -327.584042) (xy 174.528848 -327.512152)
			(xy 174.491159 -327.436461) (xy 174.460614 -327.357615) (xy 174.437475 -327.276288) (xy 174.421938 -327.193172)
			(xy 174.414136 -327.108978) (xy 169.943791 -327.108978) (xy 169.935989 -327.193166) (xy 169.920453 -327.276277)
			(xy 169.897314 -327.3576) (xy 169.86677 -327.436441) (xy 169.829082 -327.512128) (xy 169.784572 -327.584014)
			(xy 169.733618 -327.651486) (xy 169.676655 -327.71397) (xy 169.614171 -327.77093) (xy 169.546697 -327.821883)
			(xy 169.47481 -327.866392) (xy 169.399123 -327.904079) (xy 169.320281 -327.93462) (xy 169.238957 -327.957757)
			(xy 169.155846 -327.973292) (xy 169.071655 -327.981092) (xy 169.02938 -327.981564) (xy 167.78478 -327.981564)
			(xy 167.742502 -327.981163) (xy 167.658308 -327.973359) (xy 167.575193 -327.957821) (xy 167.493866 -327.93468)
			(xy 167.415021 -327.904133) (xy 167.339331 -327.866443) (xy 167.267441 -327.821929) (xy 167.199965 -327.770972)
			(xy 167.137479 -327.714007) (xy 167.080515 -327.651519) (xy 167.02956 -327.584042) (xy 166.985048 -327.512152)
			(xy 166.947359 -327.436461) (xy 166.916814 -327.357615) (xy 166.893675 -327.276288) (xy 166.878138 -327.193172)
			(xy 166.870336 -327.108978) (xy 162.399991 -327.108978) (xy 162.392189 -327.193166) (xy 162.376653 -327.276277)
			(xy 162.353514 -327.3576) (xy 162.32297 -327.436441) (xy 162.285282 -327.512128) (xy 162.240772 -327.584014)
			(xy 162.189818 -327.651486) (xy 162.132855 -327.71397) (xy 162.070371 -327.77093) (xy 162.002897 -327.821883)
			(xy 161.93101 -327.866392) (xy 161.855323 -327.904079) (xy 161.776481 -327.93462) (xy 161.695157 -327.957757)
			(xy 161.612046 -327.973292) (xy 161.527855 -327.981092) (xy 161.48558 -327.981564) (xy 160.24098 -327.981564)
			(xy 160.198702 -327.981163) (xy 160.114508 -327.973359) (xy 160.031393 -327.957821) (xy 159.950066 -327.93468)
			(xy 159.871221 -327.904133) (xy 159.795531 -327.866443) (xy 159.723641 -327.821929) (xy 159.656165 -327.770972)
			(xy 159.593679 -327.714007) (xy 159.536715 -327.651519) (xy 159.48576 -327.584042) (xy 159.441248 -327.512152)
			(xy 159.403559 -327.436461) (xy 159.373014 -327.357615) (xy 159.349875 -327.276288) (xy 159.334338 -327.193172)
			(xy 159.326536 -327.108978) (xy 155.000198 -327.108978) (xy 155.000198 -328.817986) (xy 178.635912 -328.817986)
			(xy 178.639983 -328.762364) (xy 178.652109 -328.707927) (xy 178.672032 -328.655836) (xy 178.699328 -328.607201)
			(xy 178.733414 -328.563058) (xy 178.773563 -328.524349) (xy 178.818921 -328.491898) (xy 178.868521 -328.466397)
			(xy 178.921305 -328.44839) (xy 178.976148 -328.43826) (xy 179.031882 -328.436223) (xy 179.087319 -328.442323)
			(xy 179.141276 -328.456429) (xy 179.192605 -328.478241) (xy 179.240211 -328.507295) (xy 179.283079 -328.54297)
			(xy 179.320296 -328.584507) (xy 179.351069 -328.63102) (xy 179.374741 -328.681517) (xy 179.390809 -328.734924)
			(xy 179.398929 -328.7901) (xy 179.399438 -328.817986) (xy 179.398929 -328.845872) (xy 179.390809 -328.901048)
			(xy 179.374741 -328.954455) (xy 179.351069 -329.004952) (xy 179.320296 -329.051465) (xy 179.283079 -329.093002)
			(xy 179.240211 -329.128677) (xy 179.192605 -329.157731) (xy 179.141276 -329.179543) (xy 179.087319 -329.193649)
			(xy 179.031882 -329.199749) (xy 178.976148 -329.197712) (xy 178.921305 -329.187582) (xy 178.868521 -329.169575)
			(xy 178.818921 -329.144074) (xy 178.773563 -329.111623) (xy 178.733414 -329.072914) (xy 178.699328 -329.028771)
			(xy 178.672032 -328.980136) (xy 178.652109 -328.928045) (xy 178.639983 -328.873608) (xy 178.635912 -328.817986)
			(xy 155.000198 -328.817986) (xy 155.000198 -329.90663) (xy 175.585118 -329.90663) (xy 175.589189 -329.851008)
			(xy 175.601315 -329.796571) (xy 175.621238 -329.74448) (xy 175.648534 -329.695845) (xy 175.68262 -329.651702)
			(xy 175.722769 -329.612993) (xy 175.768127 -329.580542) (xy 175.817727 -329.555041) (xy 175.870511 -329.537034)
			(xy 175.925354 -329.526904) (xy 175.981088 -329.524867) (xy 176.036525 -329.530967) (xy 176.090482 -329.545073)
			(xy 176.141811 -329.566885) (xy 176.189417 -329.595939) (xy 176.232285 -329.631614) (xy 176.269502 -329.673151)
			(xy 176.300275 -329.719664) (xy 176.323947 -329.770161) (xy 176.340015 -329.823568) (xy 176.348135 -329.878744)
			(xy 176.348644 -329.90663) (xy 176.348135 -329.934516) (xy 176.340015 -329.989692) (xy 176.323947 -330.043099)
			(xy 176.300275 -330.093596) (xy 176.269502 -330.140109) (xy 176.232285 -330.181646) (xy 176.189417 -330.217321)
			(xy 176.150376 -330.241148) (xy 176.607722 -330.241148) (xy 176.611793 -330.185526) (xy 176.623919 -330.131089)
			(xy 176.643842 -330.078998) (xy 176.671138 -330.030363) (xy 176.705224 -329.98622) (xy 176.745373 -329.947511)
			(xy 176.790731 -329.91506) (xy 176.840331 -329.889559) (xy 176.893115 -329.871552) (xy 176.947958 -329.861422)
			(xy 177.003692 -329.859385) (xy 177.059129 -329.865485) (xy 177.113086 -329.879591) (xy 177.164415 -329.901403)
			(xy 177.212021 -329.930457) (xy 177.254889 -329.966132) (xy 177.292106 -330.007669) (xy 177.322879 -330.054182)
			(xy 177.346551 -330.104679) (xy 177.362619 -330.158086) (xy 177.370739 -330.213262) (xy 177.371248 -330.241148)
			(xy 177.370739 -330.269034) (xy 177.362619 -330.32421) (xy 177.346551 -330.377617) (xy 177.322879 -330.428114)
			(xy 177.292106 -330.474627) (xy 177.273719 -330.495148) (xy 179.277772 -330.495148) (xy 179.278258 -330.467897)
			(xy 179.286014 -330.413949) (xy 179.301369 -330.361654) (xy 179.324011 -330.312077) (xy 179.353477 -330.266227)
			(xy 179.389168 -330.225036) (xy 179.430359 -330.189345) (xy 179.476209 -330.159879) (xy 179.525786 -330.137237)
			(xy 179.578081 -330.121882) (xy 179.632029 -330.114126) (xy 179.686531 -330.114126) (xy 179.740479 -330.121882)
			(xy 179.792774 -330.137237) (xy 179.842351 -330.159879) (xy 179.888201 -330.189345) (xy 179.929392 -330.225036)
			(xy 179.965083 -330.266227) (xy 179.994549 -330.312077) (xy 180.017191 -330.361654) (xy 180.032546 -330.413949)
			(xy 180.040302 -330.467897) (xy 180.040788 -330.495148) (xy 180.040062 -330.529094) (xy 180.028043 -330.595913)
			(xy 180.016912 -330.62799) (xy 180.012185 -330.642196) (xy 180.010328 -330.672064) (xy 180.017207 -330.701189)
			(xy 180.032232 -330.727069) (xy 180.054113 -330.747484) (xy 180.080972 -330.760681) (xy 180.095652 -330.763626)
			(xy 180.122108 -330.768377) (xy 180.173409 -330.784427) (xy 180.221947 -330.807521) (xy 180.266763 -330.8372)
			(xy 180.306969 -330.872877) (xy 180.341767 -330.913845) (xy 180.37047 -330.959293) (xy 180.392507 -331.008321)
			(xy 180.407443 -331.059956) (xy 180.414982 -331.113178) (xy 180.415438 -331.140054) (xy 180.414952 -331.167305)
			(xy 180.407196 -331.221253) (xy 180.391841 -331.273548) (xy 180.369199 -331.323125) (xy 180.339733 -331.368975)
			(xy 180.304042 -331.410166) (xy 180.262851 -331.445857) (xy 180.217001 -331.475323) (xy 180.167424 -331.497965)
			(xy 180.115129 -331.51332) (xy 180.061181 -331.521076) (xy 180.006679 -331.521076) (xy 179.952731 -331.51332)
			(xy 179.900436 -331.497965) (xy 179.850859 -331.475323) (xy 179.805009 -331.445857) (xy 179.763818 -331.410166)
			(xy 179.728127 -331.368975) (xy 179.698661 -331.323125) (xy 179.676019 -331.273548) (xy 179.660664 -331.221253)
			(xy 179.652908 -331.167305) (xy 179.652422 -331.140054) (xy 179.653154 -331.106109) (xy 179.665169 -331.03929)
			(xy 179.676298 -331.007212) (xy 179.681015 -330.993003) (xy 179.682872 -330.963137) (xy 179.675994 -330.934014)
			(xy 179.660971 -330.908135) (xy 179.639092 -330.88772) (xy 179.612237 -330.874522) (xy 179.597558 -330.871576)
			(xy 179.571104 -330.866816) (xy 179.519803 -330.850767) (xy 179.471265 -330.827675) (xy 179.426448 -330.797997)
			(xy 179.386243 -330.762321) (xy 179.351444 -330.721353) (xy 179.322742 -330.675906) (xy 179.300704 -330.62688)
			(xy 179.285767 -330.575245) (xy 179.278228 -330.522024) (xy 179.277772 -330.495148) (xy 177.273719 -330.495148)
			(xy 177.254889 -330.516164) (xy 177.212021 -330.551839) (xy 177.164415 -330.580893) (xy 177.113086 -330.602705)
			(xy 177.059129 -330.616811) (xy 177.003692 -330.622911) (xy 176.947958 -330.620874) (xy 176.893115 -330.610744)
			(xy 176.840331 -330.592737) (xy 176.790731 -330.567236) (xy 176.745373 -330.534785) (xy 176.705224 -330.496076)
			(xy 176.671138 -330.451933) (xy 176.643842 -330.403298) (xy 176.623919 -330.351207) (xy 176.611793 -330.29677)
			(xy 176.607722 -330.241148) (xy 176.150376 -330.241148) (xy 176.141811 -330.246375) (xy 176.090482 -330.268187)
			(xy 176.036525 -330.282293) (xy 175.981088 -330.288393) (xy 175.925354 -330.286356) (xy 175.870511 -330.276226)
			(xy 175.817727 -330.258219) (xy 175.768127 -330.232718) (xy 175.722769 -330.200267) (xy 175.68262 -330.161558)
			(xy 175.648534 -330.117415) (xy 175.621238 -330.06878) (xy 175.601315 -330.016689) (xy 175.589189 -329.962252)
			(xy 175.585118 -329.90663) (xy 155.000198 -329.90663) (xy 155.000198 -330.843128) (xy 175.457102 -330.843128)
			(xy 175.461173 -330.787506) (xy 175.473299 -330.733069) (xy 175.493222 -330.680978) (xy 175.520518 -330.632343)
			(xy 175.554604 -330.5882) (xy 175.594753 -330.549491) (xy 175.640111 -330.51704) (xy 175.689711 -330.491539)
			(xy 175.742495 -330.473532) (xy 175.797338 -330.463402) (xy 175.853072 -330.461365) (xy 175.908509 -330.467465)
			(xy 175.962466 -330.481571) (xy 176.013795 -330.503383) (xy 176.061401 -330.532437) (xy 176.104269 -330.568112)
			(xy 176.141486 -330.609649) (xy 176.172259 -330.656162) (xy 176.195931 -330.706659) (xy 176.211999 -330.760066)
			(xy 176.220119 -330.815242) (xy 176.220628 -330.843128) (xy 176.220119 -330.871014) (xy 176.211999 -330.92619)
			(xy 176.195931 -330.979597) (xy 176.172259 -331.030094) (xy 176.141486 -331.076607) (xy 176.104269 -331.118144)
			(xy 176.061401 -331.153819) (xy 176.013795 -331.182873) (xy 175.962466 -331.204685) (xy 175.908509 -331.218791)
			(xy 175.853072 -331.224891) (xy 175.797338 -331.222854) (xy 175.742495 -331.212724) (xy 175.689711 -331.194717)
			(xy 175.640111 -331.169216) (xy 175.594753 -331.136765) (xy 175.554604 -331.098056) (xy 175.520518 -331.053913)
			(xy 175.493222 -331.005278) (xy 175.473299 -330.953187) (xy 175.461173 -330.89875) (xy 175.457102 -330.843128)
			(xy 155.000198 -330.843128) (xy 155.000198 -332.559406) (xy 155.43784 -332.997048) (xy 207.72628 -332.997048)
		)
		(stroke
			(width 0)
			(type solid)
		)
		(fill yes)
		(layer "F.Cu")
		(net "P12V_S3_AUX_CPU1_NVDIMM")
	)
	(gr_poly
		(pts
			(xy 18.475706 -194.099942) (xy 18.450814 -194.06489) (xy 18.434149 -194.040525) (xy 18.407745 -193.987733)
			(xy 18.389801 -193.931499) (xy 18.380748 -193.87317) (xy 18.380202 -193.843656) (xy 18.380691 -193.816407)
			(xy 18.388453 -193.762465) (xy 18.403812 -193.710176) (xy 18.426456 -193.660605) (xy 18.455923 -193.614761)
			(xy 18.491615 -193.573577) (xy 18.532804 -193.537891) (xy 18.578652 -193.50843) (xy 18.628227 -193.485793)
			(xy 18.680518 -193.470441) (xy 18.734461 -193.462687) (xy 18.76171 -193.462148) (xy 18.791221 -193.462705)
			(xy 18.84954 -193.471794) (xy 18.905768 -193.489739) (xy 18.95857 -193.516114) (xy 18.982944 -193.53276)
			(xy 19.017996 -193.557652) (xy 19.125692 -193.449956) (xy 23.327868 -193.449956) (xy 23.340314 -193.41719)
			(xy 23.350396 -193.392021) (xy 23.37665 -193.344584) (xy 23.409355 -193.301341) (xy 23.447852 -193.263163)
			(xy 23.491367 -193.23082) (xy 23.539021 -193.204962) (xy 23.589857 -193.186111) (xy 23.642849 -193.174647)
			(xy 23.69693 -193.170799) (xy 23.751011 -193.174647) (xy 23.804003 -193.186111) (xy 23.854839 -193.204962)
			(xy 23.902493 -193.23082) (xy 23.946008 -193.263163) (xy 23.984505 -193.301341) (xy 24.01721 -193.344584)
			(xy 24.043464 -193.392021) (xy 24.053546 -193.41719) (xy 24.065992 -193.449956) (xy 33.323276 -193.449956)
			(xy 33.33739 -193.449488) (xy 33.364535 -193.441745) (xy 33.388525 -193.426869) (xy 33.40753 -193.405997)
			(xy 33.420098 -193.380722) (xy 33.425272 -193.352972) (xy 33.422655 -193.324866) (xy 33.418018 -193.311526)
			(xy 33.409808 -193.289426) (xy 33.398276 -193.243711) (xy 33.392464 -193.196923) (xy 33.39211 -193.17335)
			(xy 33.392596 -193.146099) (xy 33.400352 -193.092151) (xy 33.415707 -193.039856) (xy 33.438349 -192.990279)
			(xy 33.467815 -192.944429) (xy 33.503506 -192.903238) (xy 33.544697 -192.867547) (xy 33.590547 -192.838081)
			(xy 33.640124 -192.815439) (xy 33.692419 -192.800084) (xy 33.746367 -192.792328) (xy 33.800869 -192.792328)
			(xy 33.854817 -192.800084) (xy 33.907112 -192.815439) (xy 33.956689 -192.838081) (xy 34.002539 -192.867547)
			(xy 34.04373 -192.903238) (xy 34.079421 -192.944429) (xy 34.108887 -192.990279) (xy 34.131529 -193.039856)
			(xy 34.146884 -193.092151) (xy 34.15464 -193.146099) (xy 34.155126 -193.17335) (xy 34.154777 -193.196924)
			(xy 34.148971 -193.243713) (xy 34.13744 -193.28943) (xy 34.129218 -193.311526) (xy 34.124519 -193.324857)
			(xy 34.121872 -193.352987) (xy 34.127033 -193.380766) (xy 34.139608 -193.406068) (xy 34.158634 -193.426956)
			(xy 34.182655 -193.441833) (xy 34.209833 -193.449558) (xy 34.22396 -193.449956) (xy 59.344052 -193.449956)
			(xy 59.74715 -193.046858) (xy 59.74715 -188.939678) (xy 60.65774 -188.029088) (xy 66.72072 -188.029088)
			(xy 67.422522 -188.73089) (xy 90.77909 -188.73089) (xy 90.783161 -188.675268) (xy 90.795287 -188.620831)
			(xy 90.81521 -188.56874) (xy 90.842506 -188.520105) (xy 90.876592 -188.475962) (xy 90.916741 -188.437253)
			(xy 90.962099 -188.404802) (xy 91.011699 -188.379301) (xy 91.064483 -188.361294) (xy 91.119326 -188.351164)
			(xy 91.17506 -188.349127) (xy 91.230497 -188.355227) (xy 91.284454 -188.369333) (xy 91.335783 -188.391145)
			(xy 91.383389 -188.420199) (xy 91.426257 -188.455874) (xy 91.463474 -188.497411) (xy 91.494247 -188.543924)
			(xy 91.517919 -188.594421) (xy 91.533987 -188.647828) (xy 91.542107 -188.703004) (xy 91.542616 -188.73089)
			(xy 91.542107 -188.758776) (xy 91.533987 -188.813952) (xy 91.517919 -188.867359) (xy 91.494247 -188.917856)
			(xy 91.463474 -188.964369) (xy 91.426257 -189.005906) (xy 91.383389 -189.041581) (xy 91.335783 -189.070635)
			(xy 91.284454 -189.092447) (xy 91.230497 -189.106553) (xy 91.17506 -189.112653) (xy 91.119326 -189.110616)
			(xy 91.064483 -189.100486) (xy 91.011699 -189.082479) (xy 90.962099 -189.056978) (xy 90.916741 -189.024527)
			(xy 90.876592 -188.985818) (xy 90.842506 -188.941675) (xy 90.81521 -188.89304) (xy 90.795287 -188.840949)
			(xy 90.783161 -188.786512) (xy 90.77909 -188.73089) (xy 67.422522 -188.73089) (xy 68.58762 -189.895988)
			(xy 69.260974 -189.895988) (xy 69.290692 -189.925706) (xy 69.354192 -189.862206) (xy 69.334634 -189.828424)
			(xy 69.322386 -189.806524) (xy 69.303108 -189.760197) (xy 69.290067 -189.711743) (xy 69.28349 -189.661997)
			(xy 69.283072 -189.636908) (xy 69.283557 -189.609656) (xy 69.291313 -189.555706) (xy 69.306667 -189.503409)
			(xy 69.329307 -189.45383) (xy 69.358773 -189.407977) (xy 69.394464 -189.366784) (xy 69.435655 -189.33109)
			(xy 69.481505 -189.301621) (xy 69.531083 -189.278977) (xy 69.583379 -189.263619) (xy 69.637328 -189.255859)
			(xy 69.66458 -189.2554) (xy 69.691764 -189.25588) (xy 69.745581 -189.263595) (xy 69.797758 -189.278873)
			(xy 69.847238 -189.301404) (xy 69.893018 -189.33073) (xy 69.93417 -189.366259) (xy 69.952362 -189.386464)
			(xy 69.961833 -189.396633) (xy 69.98504 -189.411899) (xy 70.011503 -189.420341) (xy 70.039262 -189.421335)
			(xy 70.066261 -189.414807) (xy 70.0905 -189.40124) (xy 70.100698 -189.391798) (xy 70.12229 -189.37115)
			(xy 70.170701 -189.336148) (xy 70.223974 -189.309115) (xy 70.280807 -189.290712) (xy 70.339815 -189.281387)
			(xy 70.369684 -189.2808) (xy 70.396937 -189.281262) (xy 70.450889 -189.289017) (xy 70.503187 -189.304372)
			(xy 70.552768 -189.327013) (xy 70.598622 -189.35648) (xy 70.639816 -189.392172) (xy 70.675511 -189.433365)
			(xy 70.70498 -189.479218) (xy 70.727623 -189.528798) (xy 70.742979 -189.581096) (xy 70.750737 -189.635047)
			(xy 70.750737 -189.662308) (xy 71.003666 -189.662308) (xy 71.007737 -189.606686) (xy 71.019863 -189.552249)
			(xy 71.039786 -189.500158) (xy 71.067082 -189.451523) (xy 71.101168 -189.40738) (xy 71.141317 -189.368671)
			(xy 71.186675 -189.33622) (xy 71.236275 -189.310719) (xy 71.289059 -189.292712) (xy 71.343902 -189.282582)
			(xy 71.399636 -189.280545) (xy 71.455073 -189.286645) (xy 71.50903 -189.300751) (xy 71.560359 -189.322563)
			(xy 71.607965 -189.351617) (xy 71.650833 -189.387292) (xy 71.68805 -189.428829) (xy 71.718823 -189.475342)
			(xy 71.742495 -189.525839) (xy 71.758563 -189.579246) (xy 71.766683 -189.634422) (xy 71.767192 -189.662308)
			(xy 72.019666 -189.662308) (xy 72.023737 -189.606686) (xy 72.035863 -189.552249) (xy 72.055786 -189.500158)
			(xy 72.083082 -189.451523) (xy 72.117168 -189.40738) (xy 72.157317 -189.368671) (xy 72.202675 -189.33622)
			(xy 72.252275 -189.310719) (xy 72.305059 -189.292712) (xy 72.359902 -189.282582) (xy 72.415636 -189.280545)
			(xy 72.471073 -189.286645) (xy 72.52503 -189.300751) (xy 72.545026 -189.309248) (xy 73.450702 -189.309248)
			(xy 73.454773 -189.253626) (xy 73.466899 -189.199189) (xy 73.486822 -189.147098) (xy 73.514118 -189.098463)
			(xy 73.548204 -189.05432) (xy 73.588353 -189.015611) (xy 73.633711 -188.98316) (xy 73.683311 -188.957659)
			(xy 73.736095 -188.939652) (xy 73.790938 -188.929522) (xy 73.846672 -188.927485) (xy 73.902109 -188.933585)
			(xy 73.956066 -188.947691) (xy 74.007395 -188.969503) (xy 74.055001 -188.998557) (xy 74.097869 -189.034232)
			(xy 74.135086 -189.075769) (xy 74.165859 -189.122282) (xy 74.189531 -189.172779) (xy 74.205599 -189.226186)
			(xy 74.213719 -189.281362) (xy 74.214228 -189.309248) (xy 74.213719 -189.337134) (xy 74.205599 -189.39231)
			(xy 74.189531 -189.445717) (xy 74.165859 -189.496214) (xy 74.135086 -189.542727) (xy 74.097869 -189.584264)
			(xy 74.055001 -189.619939) (xy 74.007395 -189.648993) (xy 73.956066 -189.670805) (xy 73.902109 -189.684911)
			(xy 73.846672 -189.691011) (xy 73.790938 -189.688974) (xy 73.736095 -189.678844) (xy 73.683311 -189.660837)
			(xy 73.633711 -189.635336) (xy 73.588353 -189.602885) (xy 73.548204 -189.564176) (xy 73.514118 -189.520033)
			(xy 73.486822 -189.471398) (xy 73.466899 -189.419307) (xy 73.454773 -189.36487) (xy 73.450702 -189.309248)
			(xy 72.545026 -189.309248) (xy 72.576359 -189.322563) (xy 72.623965 -189.351617) (xy 72.666833 -189.387292)
			(xy 72.70405 -189.428829) (xy 72.734823 -189.475342) (xy 72.758495 -189.525839) (xy 72.774563 -189.579246)
			(xy 72.782683 -189.634422) (xy 72.783192 -189.662308) (xy 72.782683 -189.690194) (xy 72.776208 -189.73419)
			(xy 80.3816 -189.73419) (xy 80.385671 -189.678568) (xy 80.397797 -189.624131) (xy 80.41772 -189.57204)
			(xy 80.445016 -189.523405) (xy 80.479102 -189.479262) (xy 80.519251 -189.440553) (xy 80.564609 -189.408102)
			(xy 80.614209 -189.382601) (xy 80.666993 -189.364594) (xy 80.721836 -189.354464) (xy 80.77757 -189.352427)
			(xy 80.833007 -189.358527) (xy 80.886964 -189.372633) (xy 80.938293 -189.394445) (xy 80.985899 -189.423499)
			(xy 81.028767 -189.459174) (xy 81.065984 -189.500711) (xy 81.096757 -189.547224) (xy 81.120429 -189.597721)
			(xy 81.136497 -189.651128) (xy 81.144617 -189.706304) (xy 81.145126 -189.73419) (xy 81.144617 -189.762076)
			(xy 81.136497 -189.817252) (xy 81.120429 -189.870659) (xy 81.096757 -189.921156) (xy 81.065984 -189.967669)
			(xy 81.028767 -190.009206) (xy 80.985899 -190.044881) (xy 80.938293 -190.073935) (xy 80.886964 -190.095747)
			(xy 80.833007 -190.109853) (xy 80.77757 -190.115953) (xy 80.721836 -190.113916) (xy 80.666993 -190.103786)
			(xy 80.614209 -190.085779) (xy 80.564609 -190.060278) (xy 80.519251 -190.027827) (xy 80.479102 -189.989118)
			(xy 80.445016 -189.944975) (xy 80.41772 -189.89634) (xy 80.397797 -189.844249) (xy 80.385671 -189.789812)
			(xy 80.3816 -189.73419) (xy 72.776208 -189.73419) (xy 72.774563 -189.74537) (xy 72.758495 -189.798777)
			(xy 72.734823 -189.849274) (xy 72.70405 -189.895787) (xy 72.666833 -189.937324) (xy 72.623965 -189.972999)
			(xy 72.576359 -190.002053) (xy 72.52503 -190.023865) (xy 72.471073 -190.037971) (xy 72.415636 -190.044071)
			(xy 72.359902 -190.042034) (xy 72.305059 -190.031904) (xy 72.252275 -190.013897) (xy 72.202675 -189.988396)
			(xy 72.157317 -189.955945) (xy 72.117168 -189.917236) (xy 72.083082 -189.873093) (xy 72.055786 -189.824458)
			(xy 72.035863 -189.772367) (xy 72.023737 -189.71793) (xy 72.019666 -189.662308) (xy 71.767192 -189.662308)
			(xy 71.766683 -189.690194) (xy 71.758563 -189.74537) (xy 71.742495 -189.798777) (xy 71.718823 -189.849274)
			(xy 71.68805 -189.895787) (xy 71.650833 -189.937324) (xy 71.607965 -189.972999) (xy 71.560359 -190.002053)
			(xy 71.50903 -190.023865) (xy 71.455073 -190.037971) (xy 71.399636 -190.044071) (xy 71.343902 -190.042034)
			(xy 71.289059 -190.031904) (xy 71.236275 -190.013897) (xy 71.186675 -189.988396) (xy 71.141317 -189.955945)
			(xy 71.101168 -189.917236) (xy 71.067082 -189.873093) (xy 71.039786 -189.824458) (xy 71.019863 -189.772367)
			(xy 71.007737 -189.71793) (xy 71.003666 -189.662308) (xy 70.750737 -189.662308) (xy 70.750737 -189.689553)
			(xy 70.742979 -189.743504) (xy 70.727623 -189.795802) (xy 70.70498 -189.845382) (xy 70.675511 -189.891235)
			(xy 70.639816 -189.932428) (xy 70.598622 -189.96812) (xy 70.552768 -189.997587) (xy 70.503187 -190.020228)
			(xy 70.450889 -190.035583) (xy 70.396937 -190.043338) (xy 70.369684 -190.043816) (xy 70.342502 -190.043333)
			(xy 70.288689 -190.035612) (xy 70.236517 -190.020328) (xy 70.187045 -189.997791) (xy 70.141273 -189.968457)
			(xy 70.100131 -189.932922) (xy 70.081902 -189.912752) (xy 70.072427 -189.902581) (xy 70.049214 -189.887312)
			(xy 70.022746 -189.878862) (xy 69.99498 -189.877856) (xy 69.967969 -189.88437) (xy 69.943713 -189.89792)
			(xy 69.933566 -189.907418) (xy 69.911976 -189.928068) (xy 69.863566 -189.963073) (xy 69.810293 -189.990107)
			(xy 69.753458 -190.008509) (xy 69.69445 -190.017831) (xy 69.66458 -190.018416) (xy 69.635116 -190.0174)
			(xy 69.621375 -190.01678) (xy 69.594387 -190.022037) (xy 69.569783 -190.034312) (xy 69.549353 -190.052713)
			(xy 69.534582 -190.075903) (xy 69.526542 -190.102197) (xy 69.525818 -190.129683) (xy 69.532463 -190.156363)
			(xy 69.545994 -190.180299) (xy 69.55536 -190.190374) (xy 71.336662 -191.971676) (xy 73.218548 -191.971676)
			(xy 74.274172 -190.916052) (xy 90.359484 -190.916052) (xy 91.919552 -189.355984) (xy 91.919552 -185.338466)
			(xy 91.563698 -184.982612) (xy 91.553792 -184.978802) (xy 91.52849 -184.968515) (xy 91.480878 -184.941749)
			(xy 91.437571 -184.908466) (xy 91.399453 -184.869348) (xy 91.367303 -184.825192) (xy 91.354148 -184.801256)
			(xy 91.339924 -184.774078) (xy 89.950544 -184.774078) (xy 89.950544 -184.869328) (xy 89.957656 -184.88152)
			(xy 89.970722 -184.903937) (xy 89.991332 -184.951555) (xy 90.005289 -185.001529) (xy 90.012334 -185.052935)
			(xy 90.012774 -185.078878) (xy 90.012312 -185.106131) (xy 90.004558 -185.160082) (xy 89.989203 -185.212381)
			(xy 89.966561 -185.261962) (xy 89.937093 -185.307815) (xy 89.901399 -185.349008) (xy 89.860206 -185.384701)
			(xy 89.814351 -185.414167) (xy 89.76477 -185.436807) (xy 89.712471 -185.45216) (xy 89.658519 -185.459913)
			(xy 89.631266 -185.460386) (xy 89.603255 -185.459892) (xy 89.547836 -185.4517) (xy 89.494209 -185.435497)
			(xy 89.443525 -185.411632) (xy 89.396873 -185.380616) (xy 89.355254 -185.343115) (xy 89.319562 -185.299935)
			(xy 89.304622 -185.276236) (xy 89.296198 -185.263374) (xy 89.27317 -185.243025) (xy 89.245138 -185.230431)
			(xy 89.214631 -185.226729) (xy 89.184401 -185.232254) (xy 89.157174 -185.246506) (xy 89.145872 -185.256932)
			(xy 88.835992 -185.566812) (xy 88.866726 -185.602626) (xy 88.88403 -185.623486) (xy 88.913188 -185.669171)
			(xy 88.93559 -185.718521) (xy 88.950784 -185.770544) (xy 88.958467 -185.824194) (xy 88.958928 -185.851292)
			(xy 88.958483 -185.877671) (xy 88.951221 -185.929928) (xy 88.936833 -185.980687) (xy 88.915594 -186.028982)
			(xy 88.887908 -186.073892) (xy 88.854302 -186.114563) (xy 88.815417 -186.150221) (xy 88.771993 -186.180185)
			(xy 88.748616 -186.192414) (xy 88.736258 -186.199117) (xy 88.715531 -186.218095) (xy 88.70077 -186.242009)
			(xy 88.693099 -186.269045) (xy 88.693098 -186.297148) (xy 88.700768 -186.324184) (xy 88.715526 -186.3481)
			(xy 88.736252 -186.367079) (xy 88.748616 -186.37377) (xy 88.771984 -186.386014) (xy 88.815409 -186.415973)
			(xy 88.854294 -186.451627) (xy 88.887897 -186.492296) (xy 88.91558 -186.537206) (xy 88.936814 -186.5855)
			(xy 88.951195 -186.636259) (xy 88.958448 -186.688514) (xy 88.958928 -186.714892) (xy 88.958442 -186.742143)
			(xy 88.950686 -186.796091) (xy 88.935331 -186.848386) (xy 88.912689 -186.897963) (xy 88.883223 -186.943813)
			(xy 88.847532 -186.985004) (xy 88.828898 -187.00115) (xy 90.7796 -187.00115) (xy 90.780142 -186.974203)
			(xy 90.787733 -186.920846) (xy 90.802758 -186.869088) (xy 90.824918 -186.819959) (xy 90.85377 -186.774438)
			(xy 90.888741 -186.733431) (xy 90.929136 -186.697753) (xy 90.974149 -186.668114) (xy 91.022885 -186.645106)
			(xy 91.074375 -186.629185) (xy 91.10091 -186.624468) (xy 91.114738 -186.621771) (xy 91.140288 -186.609933)
			(xy 91.161632 -186.591565) (xy 91.177147 -186.568065) (xy 91.185652 -186.541221) (xy 91.186501 -186.513075)
			(xy 91.179628 -186.485767) (xy 91.165558 -186.461375) (xy 91.155774 -186.45124) (xy 91.137909 -186.433224)
			(xy 91.106612 -186.393289) (xy 91.080886 -186.349558) (xy 91.061183 -186.302803) (xy 91.047852 -186.253848)
			(xy 91.041128 -186.203559) (xy 91.040712 -186.17819) (xy 91.041198 -186.150939) (xy 91.048954 -186.096991)
			(xy 91.064309 -186.044696) (xy 91.086951 -185.995119) (xy 91.116417 -185.949269) (xy 91.152108 -185.908078)
			(xy 91.193299 -185.872387) (xy 91.239149 -185.842921) (xy 91.288726 -185.820279) (xy 91.341021 -185.804924)
			(xy 91.394969 -185.797168) (xy 91.449471 -185.797168) (xy 91.503419 -185.804924) (xy 91.555714 -185.820279)
			(xy 91.605291 -185.842921) (xy 91.651141 -185.872387) (xy 91.692332 -185.908078) (xy 91.728023 -185.949269)
			(xy 91.757489 -185.995119) (xy 91.780131 -186.044696) (xy 91.795486 -186.096991) (xy 91.803242 -186.150939)
			(xy 91.803728 -186.17819) (xy 91.803283 -186.205141) (xy 91.795684 -186.258505) (xy 91.780651 -186.310268)
			(xy 91.758482 -186.359401) (xy 91.729619 -186.404924) (xy 91.694636 -186.445932) (xy 91.65423 -186.481609)
			(xy 91.609205 -186.511244) (xy 91.560458 -186.534247) (xy 91.508958 -186.55016) (xy 91.482418 -186.554872)
			(xy 91.468576 -186.557515) (xy 91.443014 -186.569355) (xy 91.421661 -186.587729) (xy 91.406141 -186.611239)
			(xy 91.397636 -186.638095) (xy 91.396793 -186.666253) (xy 91.403676 -186.693569) (xy 91.417762 -186.717965)
			(xy 91.427554 -186.7281) (xy 91.445396 -186.746138) (xy 91.476693 -186.786069) (xy 91.502422 -186.829795)
			(xy 91.522129 -186.876546) (xy 91.535465 -186.925497) (xy 91.542196 -186.975783) (xy 91.542616 -187.00115)
			(xy 91.54213 -187.028401) (xy 91.534374 -187.082349) (xy 91.519019 -187.134644) (xy 91.496377 -187.184221)
			(xy 91.466911 -187.230071) (xy 91.43122 -187.271262) (xy 91.390029 -187.306953) (xy 91.344179 -187.336419)
			(xy 91.294602 -187.359061) (xy 91.242307 -187.374416) (xy 91.188359 -187.382172) (xy 91.133857 -187.382172)
			(xy 91.079909 -187.374416) (xy 91.027614 -187.359061) (xy 90.978037 -187.336419) (xy 90.932187 -187.306953)
			(xy 90.890996 -187.271262) (xy 90.855305 -187.230071) (xy 90.825839 -187.184221) (xy 90.803197 -187.134644)
			(xy 90.787842 -187.082349) (xy 90.780086 -187.028401) (xy 90.7796 -187.00115) (xy 88.828898 -187.00115)
			(xy 88.806341 -187.020695) (xy 88.760491 -187.050161) (xy 88.710914 -187.072803) (xy 88.658619 -187.088158)
			(xy 88.604671 -187.095914) (xy 88.550169 -187.095914) (xy 88.496221 -187.088158) (xy 88.443926 -187.072803)
			(xy 88.394349 -187.050161) (xy 88.348499 -187.020695) (xy 88.307308 -186.985004) (xy 88.271617 -186.943813)
			(xy 88.242151 -186.897963) (xy 88.219509 -186.848386) (xy 88.204154 -186.796091) (xy 88.196398 -186.742143)
			(xy 88.195912 -186.714892) (xy 88.196358 -186.688514) (xy 88.203623 -186.63626) (xy 88.218013 -186.585504)
			(xy 88.239255 -186.537212) (xy 88.266943 -186.492306) (xy 88.300551 -186.451639) (xy 88.339437 -186.415987)
			(xy 88.382863 -186.386028) (xy 88.406224 -186.37377) (xy 88.418586 -186.367072) (xy 88.439321 -186.348099)
			(xy 88.454087 -186.324186) (xy 88.461761 -186.297149) (xy 88.46176 -186.269044) (xy 88.454084 -186.242008)
			(xy 88.439316 -186.218095) (xy 88.41858 -186.199124) (xy 88.406224 -186.192414) (xy 88.382854 -186.180171)
			(xy 88.339427 -186.150214) (xy 88.30054 -186.114561) (xy 88.266934 -186.073892) (xy 88.23925 -186.028982)
			(xy 88.218015 -185.980687) (xy 88.203635 -185.929927) (xy 88.196383 -185.877671) (xy 88.195912 -185.851292)
			(xy 88.196419 -185.822397) (xy 88.205097 -185.765264) (xy 88.222312 -185.7101) (xy 88.23452 -185.683906)
			(xy 88.24056 -185.670458) (xy 88.245436 -185.641398) (xy 88.241814 -185.612154) (xy 88.229997 -185.585161)
			(xy 88.210966 -185.562663) (xy 88.186306 -185.546534) (xy 88.158067 -185.538113) (xy 88.143334 -185.537602)
			(xy 87.221822 -185.537602) (xy 86.308946 -184.624726) (xy 84.615528 -184.624726) (xy 84.383118 -184.857136)
			(xy 84.383118 -185.85307) (xy 83.689952 -186.546236) (xy 83.060032 -186.546236) (xy 82.97672 -186.462924)
			(xy 82.96529 -186.459114) (xy 82.940246 -186.450346) (xy 82.892667 -186.426858) (xy 82.848804 -186.397001)
			(xy 82.809502 -186.361352) (xy 82.775521 -186.3206) (xy 82.747516 -186.275532) (xy 82.726029 -186.227016)
			(xy 82.711474 -186.175991) (xy 82.704131 -186.12344) (xy 82.70367 -186.09691) (xy 82.703973 -186.0748)
			(xy 82.70907 -186.030874) (xy 82.71383 -186.00928) (xy 82.7151 -186.003438) (xy 82.7151 -182.73141)
			(xy 82.715616 -182.704087) (xy 82.723696 -182.650041) (xy 82.739622 -182.597767) (xy 82.76305 -182.548397)
			(xy 82.777838 -182.525416) (xy 82.777838 -161.513266) (xy 82.745834 -161.481262) (xy 82.745834 -158.837376)
			(xy 81.157826 -157.249368) (xy 75.60564 -157.249368) (xy 75.34402 -157.510988) (xy 75.34402 -159.57169)
			(xy 75.386946 -159.578548) (xy 75.420968 -159.584436) (xy 75.487574 -159.602643) (xy 75.551812 -159.627968)
			(xy 75.612923 -159.660111) (xy 75.670188 -159.698692) (xy 75.722931 -159.743258) (xy 75.770528 -159.793281)
			(xy 75.812419 -159.848172) (xy 75.848109 -159.907282) (xy 75.877177 -159.969915) (xy 75.89928 -160.035332)
			(xy 75.914157 -160.10276) (xy 75.921632 -160.171403) (xy 75.922124 -160.205928) (xy 75.921762 -160.237205)
			(xy 75.91564 -160.299457) (xy 75.903426 -160.360806) (xy 75.894692 -160.39084) (xy 75.885802 -160.42005)
			(xy 77.987398 -162.521646) (xy 77.987398 -173.56709) (xy 71.38924 -180.165248) (xy 44.31284 -180.165248)
			(xy 44.05884 -180.419248) (xy 44.05884 -181.176422) (xy 56.742582 -181.176422) (xy 56.746653 -181.1208)
			(xy 56.758779 -181.066363) (xy 56.778702 -181.014272) (xy 56.805998 -180.965637) (xy 56.840084 -180.921494)
			(xy 56.880233 -180.882785) (xy 56.925591 -180.850334) (xy 56.975191 -180.824833) (xy 57.027975 -180.806826)
			(xy 57.082818 -180.796696) (xy 57.138552 -180.794659) (xy 57.193989 -180.800759) (xy 57.247946 -180.814865)
			(xy 57.299275 -180.836677) (xy 57.346881 -180.865731) (xy 57.389749 -180.901406) (xy 57.426966 -180.942943)
			(xy 57.457739 -180.989456) (xy 57.481411 -181.039953) (xy 57.497479 -181.09336) (xy 57.505599 -181.148536)
			(xy 57.506108 -181.176422) (xy 57.505599 -181.204308) (xy 57.497479 -181.259484) (xy 57.481411 -181.312891)
			(xy 57.457739 -181.363388) (xy 57.426966 -181.409901) (xy 57.389749 -181.451438) (xy 57.346881 -181.487113)
			(xy 57.299275 -181.516167) (xy 57.247946 -181.537979) (xy 57.193989 -181.552085) (xy 57.138552 -181.558185)
			(xy 57.082818 -181.556148) (xy 57.027975 -181.546018) (xy 56.975191 -181.528011) (xy 56.925591 -181.50251)
			(xy 56.880233 -181.470059) (xy 56.840084 -181.43135) (xy 56.805998 -181.387207) (xy 56.778702 -181.338572)
			(xy 56.758779 -181.286481) (xy 56.746653 -181.232044) (xy 56.742582 -181.176422) (xy 44.05884 -181.176422)
			(xy 44.05884 -182.029608) (xy 60.308742 -182.029608) (xy 60.312813 -181.973986) (xy 60.324939 -181.919549)
			(xy 60.344862 -181.867458) (xy 60.372158 -181.818823) (xy 60.406244 -181.77468) (xy 60.446393 -181.735971)
			(xy 60.491751 -181.70352) (xy 60.541351 -181.678019) (xy 60.594135 -181.660012) (xy 60.648978 -181.649882)
			(xy 60.704712 -181.647845) (xy 60.760149 -181.653945) (xy 60.814106 -181.668051) (xy 60.865435 -181.689863)
			(xy 60.913041 -181.718917) (xy 60.955909 -181.754592) (xy 60.993126 -181.796129) (xy 61.023899 -181.842642)
			(xy 61.047571 -181.893139) (xy 61.063639 -181.946546) (xy 61.071759 -182.001722) (xy 61.072268 -182.029608)
			(xy 61.202822 -182.029608) (xy 61.206893 -181.973986) (xy 61.219019 -181.919549) (xy 61.238942 -181.867458)
			(xy 61.266238 -181.818823) (xy 61.300324 -181.77468) (xy 61.340473 -181.735971) (xy 61.385831 -181.70352)
			(xy 61.435431 -181.678019) (xy 61.488215 -181.660012) (xy 61.543058 -181.649882) (xy 61.598792 -181.647845)
			(xy 61.654229 -181.653945) (xy 61.708186 -181.668051) (xy 61.759515 -181.689863) (xy 61.807121 -181.718917)
			(xy 61.849989 -181.754592) (xy 61.887206 -181.796129) (xy 61.897156 -181.811168) (xy 68.096382 -181.811168)
			(xy 68.100453 -181.755546) (xy 68.112579 -181.701109) (xy 68.132502 -181.649018) (xy 68.159798 -181.600383)
			(xy 68.193884 -181.55624) (xy 68.234033 -181.517531) (xy 68.279391 -181.48508) (xy 68.328991 -181.459579)
			(xy 68.381775 -181.441572) (xy 68.436618 -181.431442) (xy 68.492352 -181.429405) (xy 68.547789 -181.435505)
			(xy 68.601746 -181.449611) (xy 68.653075 -181.471423) (xy 68.700681 -181.500477) (xy 68.743549 -181.536152)
			(xy 68.780766 -181.577689) (xy 68.811539 -181.624202) (xy 68.835211 -181.674699) (xy 68.846313 -181.7116)
			(xy 75.379324 -181.7116) (xy 75.383395 -181.655978) (xy 75.395521 -181.601541) (xy 75.415444 -181.54945)
			(xy 75.44274 -181.500815) (xy 75.476826 -181.456672) (xy 75.516975 -181.417963) (xy 75.562333 -181.385512)
			(xy 75.611933 -181.360011) (xy 75.664717 -181.342004) (xy 75.71956 -181.331874) (xy 75.775294 -181.329837)
			(xy 75.830731 -181.335937) (xy 75.884688 -181.350043) (xy 75.936017 -181.371855) (xy 75.983623 -181.400909)
			(xy 76.026491 -181.436584) (xy 76.063708 -181.478121) (xy 76.094481 -181.524634) (xy 76.118153 -181.575131)
			(xy 76.134221 -181.628538) (xy 76.142341 -181.683714) (xy 76.14285 -181.7116) (xy 76.142341 -181.739486)
			(xy 76.134221 -181.794662) (xy 76.118153 -181.848069) (xy 76.094481 -181.898566) (xy 76.063708 -181.945079)
			(xy 76.026491 -181.986616) (xy 75.983623 -182.022291) (xy 75.936017 -182.051345) (xy 75.884688 -182.073157)
			(xy 75.830731 -182.087263) (xy 75.775294 -182.093363) (xy 75.71956 -182.091326) (xy 75.664717 -182.081196)
			(xy 75.611933 -182.063189) (xy 75.562333 -182.037688) (xy 75.516975 -182.005237) (xy 75.476826 -181.966528)
			(xy 75.44274 -181.922385) (xy 75.415444 -181.87375) (xy 75.395521 -181.821659) (xy 75.383395 -181.767222)
			(xy 75.379324 -181.7116) (xy 68.846313 -181.7116) (xy 68.851279 -181.728106) (xy 68.859399 -181.783282)
			(xy 68.859908 -181.811168) (xy 68.859399 -181.839054) (xy 68.851279 -181.89423) (xy 68.835211 -181.947637)
			(xy 68.811539 -181.998134) (xy 68.780766 -182.044647) (xy 68.743549 -182.086184) (xy 68.700681 -182.121859)
			(xy 68.653075 -182.150913) (xy 68.601746 -182.172725) (xy 68.547789 -182.186831) (xy 68.492352 -182.192931)
			(xy 68.436618 -182.190894) (xy 68.381775 -182.180764) (xy 68.328991 -182.162757) (xy 68.279391 -182.137256)
			(xy 68.234033 -182.104805) (xy 68.193884 -182.066096) (xy 68.159798 -182.021953) (xy 68.132502 -181.973318)
			(xy 68.112579 -181.921227) (xy 68.100453 -181.86679) (xy 68.096382 -181.811168) (xy 61.897156 -181.811168)
			(xy 61.917979 -181.842642) (xy 61.941651 -181.893139) (xy 61.957719 -181.946546) (xy 61.965839 -182.001722)
			(xy 61.966348 -182.029608) (xy 61.965839 -182.057494) (xy 61.957719 -182.11267) (xy 61.941651 -182.166077)
			(xy 61.917979 -182.216574) (xy 61.887206 -182.263087) (xy 61.849989 -182.304624) (xy 61.807121 -182.340299)
			(xy 61.759515 -182.369353) (xy 61.708186 -182.391165) (xy 61.654229 -182.405271) (xy 61.598792 -182.411371)
			(xy 61.543058 -182.409334) (xy 61.488215 -182.399204) (xy 61.435431 -182.381197) (xy 61.385831 -182.355696)
			(xy 61.340473 -182.323245) (xy 61.300324 -182.284536) (xy 61.266238 -182.240393) (xy 61.238942 -182.191758)
			(xy 61.219019 -182.139667) (xy 61.206893 -182.08523) (xy 61.202822 -182.029608) (xy 61.072268 -182.029608)
			(xy 61.071759 -182.057494) (xy 61.063639 -182.11267) (xy 61.047571 -182.166077) (xy 61.023899 -182.216574)
			(xy 60.993126 -182.263087) (xy 60.955909 -182.304624) (xy 60.913041 -182.340299) (xy 60.865435 -182.369353)
			(xy 60.814106 -182.391165) (xy 60.760149 -182.405271) (xy 60.704712 -182.411371) (xy 60.648978 -182.409334)
			(xy 60.594135 -182.399204) (xy 60.541351 -182.381197) (xy 60.491751 -182.355696) (xy 60.446393 -182.323245)
			(xy 60.406244 -182.284536) (xy 60.372158 -182.240393) (xy 60.344862 -182.191758) (xy 60.324939 -182.139667)
			(xy 60.312813 -182.08523) (xy 60.308742 -182.029608) (xy 44.05884 -182.029608) (xy 44.05884 -182.822088)
			(xy 57.385202 -182.822088) (xy 57.389273 -182.766466) (xy 57.401399 -182.712029) (xy 57.421322 -182.659938)
			(xy 57.448618 -182.611303) (xy 57.482704 -182.56716) (xy 57.522853 -182.528451) (xy 57.568211 -182.496)
			(xy 57.617811 -182.470499) (xy 57.670595 -182.452492) (xy 57.725438 -182.442362) (xy 57.781172 -182.440325)
			(xy 57.836609 -182.446425) (xy 57.890566 -182.460531) (xy 57.941895 -182.482343) (xy 57.989501 -182.511397)
			(xy 58.032369 -182.547072) (xy 58.069586 -182.588609) (xy 58.100359 -182.635122) (xy 58.124031 -182.685619)
			(xy 58.140099 -182.739026) (xy 58.148219 -182.794202) (xy 58.148728 -182.822088) (xy 58.148219 -182.849974)
			(xy 58.140099 -182.90515) (xy 58.124031 -182.958557) (xy 58.100359 -183.009054) (xy 58.069586 -183.055567)
			(xy 58.032369 -183.097104) (xy 57.989501 -183.132779) (xy 57.941895 -183.161833) (xy 57.890566 -183.183645)
			(xy 57.836609 -183.197751) (xy 57.781172 -183.203851) (xy 57.725438 -183.201814) (xy 57.670595 -183.191684)
			(xy 57.617811 -183.173677) (xy 57.568211 -183.148176) (xy 57.522853 -183.115725) (xy 57.482704 -183.077016)
			(xy 57.448618 -183.032873) (xy 57.421322 -182.984238) (xy 57.401399 -182.932147) (xy 57.389273 -182.87771)
			(xy 57.385202 -182.822088) (xy 44.05884 -182.822088) (xy 44.05884 -184.724548) (xy 68.223382 -184.724548)
			(xy 68.227453 -184.668926) (xy 68.239579 -184.614489) (xy 68.259502 -184.562398) (xy 68.286798 -184.513763)
			(xy 68.320884 -184.46962) (xy 68.361033 -184.430911) (xy 68.406391 -184.39846) (xy 68.455991 -184.372959)
			(xy 68.508775 -184.354952) (xy 68.563618 -184.344822) (xy 68.619352 -184.342785) (xy 68.674789 -184.348885)
			(xy 68.728746 -184.362991) (xy 68.780075 -184.384803) (xy 68.827681 -184.413857) (xy 68.870549 -184.449532)
			(xy 68.907766 -184.491069) (xy 68.938539 -184.537582) (xy 68.962211 -184.588079) (xy 68.978279 -184.641486)
			(xy 68.986399 -184.696662) (xy 68.986908 -184.724548) (xy 68.98686 -184.727154) (xy 69.277665 -184.727154)
			(xy 69.277665 -184.672646) (xy 69.285423 -184.618693) (xy 69.300781 -184.566394) (xy 69.323425 -184.516812)
			(xy 69.352896 -184.470959) (xy 69.388593 -184.429766) (xy 69.429789 -184.394073) (xy 69.475646 -184.364607)
			(xy 69.525229 -184.341967) (xy 69.57753 -184.326615) (xy 69.631484 -184.318863) (xy 69.658738 -184.318402)
			(xy 69.690451 -184.319061) (xy 69.752999 -184.329582) (xy 69.812953 -184.350279) (xy 69.84111 -184.364884)
			(xy 69.853841 -184.371276) (xy 69.881619 -184.377528) (xy 69.910043 -184.375855) (xy 69.936896 -184.366388)
			(xy 69.960084 -184.349865) (xy 69.9778 -184.327575) (xy 69.988661 -184.301255) (xy 69.990716 -184.28716)
			(xy 69.994415 -184.259584) (xy 70.008628 -184.205795) (xy 70.030505 -184.154641) (xy 70.05958 -184.107209)
			(xy 70.095239 -184.064504) (xy 70.136723 -184.027432) (xy 70.183153 -183.996781) (xy 70.233543 -183.9732)
			(xy 70.286825 -183.95719) (xy 70.341867 -183.949091) (xy 70.369684 -183.948578) (xy 70.396937 -183.949068)
			(xy 70.450887 -183.956823) (xy 70.503185 -183.972177) (xy 70.552765 -183.994818) (xy 70.598619 -184.024284)
			(xy 70.639812 -184.059977) (xy 70.675506 -184.101168) (xy 70.704974 -184.14702) (xy 70.727617 -184.1966)
			(xy 70.742974 -184.248897) (xy 70.750731 -184.302847) (xy 70.750731 -184.357353) (xy 70.742974 -184.411303)
			(xy 70.727617 -184.4636) (xy 70.704974 -184.51318) (xy 70.675506 -184.559032) (xy 70.639812 -184.600223)
			(xy 70.598619 -184.635916) (xy 70.552765 -184.665382) (xy 70.503185 -184.688023) (xy 70.450887 -184.703377)
			(xy 70.396937 -184.711132) (xy 70.369684 -184.711594) (xy 70.337972 -184.710926) (xy 70.275424 -184.700409)
			(xy 70.215469 -184.679715) (xy 70.187312 -184.665112) (xy 70.174567 -184.65875) (xy 70.146794 -184.652495)
			(xy 70.118374 -184.654163) (xy 70.091525 -184.663625) (xy 70.068338 -184.680143) (xy 70.050623 -184.702428)
			(xy 70.039761 -184.728743) (xy 70.037706 -184.742836) (xy 70.03416 -184.770435) (xy 70.01993 -184.824232)
			(xy 69.998036 -184.87539) (xy 69.968943 -184.922825) (xy 69.933266 -184.96553) (xy 69.891765 -185.002599)
			(xy 69.845318 -185.033246) (xy 69.794912 -185.05682) (xy 69.762196 -185.066643) (xy 71.462894 -185.066643)
			(xy 71.462894 -185.002721) (xy 71.470905 -184.939303) (xy 71.486802 -184.877389) (xy 71.510334 -184.817956)
			(xy 71.541128 -184.761941) (xy 71.578701 -184.710226) (xy 71.622458 -184.663629) (xy 71.671711 -184.622884)
			(xy 71.725682 -184.588633) (xy 71.783521 -184.561416) (xy 71.844314 -184.541663) (xy 71.907104 -184.529685)
			(xy 71.9709 -184.525672) (xy 72.034696 -184.529685) (xy 72.097486 -184.541663) (xy 72.158279 -184.561416)
			(xy 72.216118 -184.588633) (xy 72.270089 -184.622884) (xy 72.319342 -184.663629) (xy 72.363099 -184.710226)
			(xy 72.400672 -184.761941) (xy 72.431466 -184.817956) (xy 72.454998 -184.877389) (xy 72.461406 -184.902348)
			(xy 72.724262 -184.902348) (xy 72.728333 -184.846726) (xy 72.740459 -184.792289) (xy 72.760382 -184.740198)
			(xy 72.787678 -184.691563) (xy 72.821764 -184.64742) (xy 72.861913 -184.608711) (xy 72.907271 -184.57626)
			(xy 72.956871 -184.550759) (xy 73.009655 -184.532752) (xy 73.064498 -184.522622) (xy 73.120232 -184.520585)
			(xy 73.175669 -184.526685) (xy 73.229626 -184.540791) (xy 73.280955 -184.562603) (xy 73.328561 -184.591657)
			(xy 73.371429 -184.627332) (xy 73.408646 -184.668869) (xy 73.439419 -184.715382) (xy 73.463091 -184.765879)
			(xy 73.479159 -184.819286) (xy 73.487279 -184.874462) (xy 73.487788 -184.902348) (xy 73.487279 -184.930234)
			(xy 73.479159 -184.98541) (xy 73.463091 -185.038817) (xy 73.439419 -185.089314) (xy 73.408646 -185.135827)
			(xy 73.371429 -185.177364) (xy 73.328561 -185.213039) (xy 73.280955 -185.242093) (xy 73.229626 -185.263905)
			(xy 73.175669 -185.278011) (xy 73.120232 -185.284111) (xy 73.064498 -185.282074) (xy 73.009655 -185.271944)
			(xy 72.956871 -185.253937) (xy 72.907271 -185.228436) (xy 72.861913 -185.195985) (xy 72.821764 -185.157276)
			(xy 72.787678 -185.113133) (xy 72.760382 -185.064498) (xy 72.740459 -185.012407) (xy 72.728333 -184.95797)
			(xy 72.724262 -184.902348) (xy 72.461406 -184.902348) (xy 72.470895 -184.939303) (xy 72.478906 -185.002721)
			(xy 72.479408 -185.034682) (xy 72.478906 -185.066643) (xy 72.470895 -185.130061) (xy 72.454998 -185.191975)
			(xy 72.431466 -185.251408) (xy 72.400672 -185.307423) (xy 72.363099 -185.359138) (xy 72.319342 -185.405735)
			(xy 72.270089 -185.44648) (xy 72.216118 -185.480731) (xy 72.158279 -185.507948) (xy 72.097486 -185.527701)
			(xy 72.034696 -185.539679) (xy 71.9709 -185.543693) (xy 71.907104 -185.539679) (xy 71.844314 -185.527701)
			(xy 71.783521 -185.507948) (xy 71.725682 -185.480731) (xy 71.671711 -185.44648) (xy 71.622458 -185.405735)
			(xy 71.578701 -185.359138) (xy 71.541128 -185.307423) (xy 71.510334 -185.251408) (xy 71.486802 -185.191975)
			(xy 71.470905 -185.130061) (xy 71.462894 -185.066643) (xy 69.762196 -185.066643) (xy 69.741616 -185.072822)
			(xy 69.686561 -185.080911) (xy 69.658738 -185.081418) (xy 69.631484 -185.080937) (xy 69.57753 -185.073185)
			(xy 69.525229 -185.057833) (xy 69.475646 -185.035193) (xy 69.429789 -185.005727) (xy 69.388593 -184.970034)
			(xy 69.352896 -184.928841) (xy 69.323425 -184.882988) (xy 69.300781 -184.833406) (xy 69.285423 -184.781107)
			(xy 69.277665 -184.727154) (xy 68.98686 -184.727154) (xy 68.986399 -184.752434) (xy 68.978279 -184.80761)
			(xy 68.962211 -184.861017) (xy 68.938539 -184.911514) (xy 68.907766 -184.958027) (xy 68.870549 -184.999564)
			(xy 68.827681 -185.035239) (xy 68.780075 -185.064293) (xy 68.728746 -185.086105) (xy 68.674789 -185.100211)
			(xy 68.619352 -185.106311) (xy 68.563618 -185.104274) (xy 68.508775 -185.094144) (xy 68.455991 -185.076137)
			(xy 68.406391 -185.050636) (xy 68.361033 -185.018185) (xy 68.320884 -184.979476) (xy 68.286798 -184.935333)
			(xy 68.259502 -184.886698) (xy 68.239579 -184.834607) (xy 68.227453 -184.78017) (xy 68.223382 -184.724548)
			(xy 44.05884 -184.724548) (xy 44.05884 -185.37047) (xy 43.282362 -186.146948) (xy 50.346862 -186.146948)
			(xy 50.350933 -186.091326) (xy 50.363059 -186.036889) (xy 50.382982 -185.984798) (xy 50.410278 -185.936163)
			(xy 50.444364 -185.89202) (xy 50.484513 -185.853311) (xy 50.529871 -185.82086) (xy 50.579471 -185.795359)
			(xy 50.632255 -185.777352) (xy 50.687098 -185.767222) (xy 50.742832 -185.765185) (xy 50.798269 -185.771285)
			(xy 50.852226 -185.785391) (xy 50.903555 -185.807203) (xy 50.951161 -185.836257) (xy 50.994029 -185.871932)
			(xy 51.023617 -185.904954) (xy 51.348563 -185.904954) (xy 51.348563 -185.850446) (xy 51.356321 -185.796493)
			(xy 51.371679 -185.744193) (xy 51.394324 -185.694611) (xy 51.423795 -185.648757) (xy 51.459492 -185.607564)
			(xy 51.500689 -185.571871) (xy 51.546546 -185.542405) (xy 51.59613 -185.519765) (xy 51.648432 -185.504413)
			(xy 51.702386 -185.496661) (xy 51.72964 -185.4962) (xy 51.755668 -185.496675) (xy 51.807243 -185.503734)
			(xy 51.857378 -185.517743) (xy 51.905142 -185.538442) (xy 51.949646 -185.565445) (xy 51.990063 -185.598251)
			(xy 52.025643 -185.636249) (xy 52.041044 -185.657236) (xy 52.049209 -185.668104) (xy 52.070195 -185.685369)
			(xy 52.094997 -185.696477) (xy 52.121852 -185.700639) (xy 52.148853 -185.697559) (xy 52.17408 -185.687456)
			(xy 52.195743 -185.671048) (xy 52.204366 -185.660538) (xy 52.222578 -185.637801) (xy 52.264663 -185.597529)
			(xy 52.312383 -185.564125) (xy 52.364629 -185.538367) (xy 52.420183 -185.520854) (xy 52.477755 -185.511993)
			(xy 52.50688 -185.51144) (xy 52.535797 -185.511958) (xy 52.592969 -185.520685) (xy 52.648169 -185.537942)
			(xy 52.700131 -185.563333) (xy 52.747664 -185.596278) (xy 52.78968 -185.63602) (xy 52.80787 -185.658506)
			(xy 52.817767 -185.670311) (xy 52.843091 -185.68783) (xy 52.872484 -185.697006) (xy 52.903276 -185.697006)
			(xy 52.932669 -185.68783) (xy 52.957993 -185.670311) (xy 52.96789 -185.658506) (xy 52.986088 -185.636029)
			(xy 53.028106 -185.596293) (xy 53.07564 -185.563353) (xy 53.1276 -185.537963) (xy 53.182796 -185.520706)
			(xy 53.239964 -185.511976) (xy 53.26888 -185.51144) (xy 53.296137 -185.511806) (xy 53.350097 -185.519561)
			(xy 53.402404 -185.534917) (xy 53.451993 -185.557562) (xy 53.497854 -185.587033) (xy 53.539055 -185.622731)
			(xy 53.574755 -185.66393) (xy 53.604229 -185.709789) (xy 53.626876 -185.759377) (xy 53.642235 -185.811683)
			(xy 53.649993 -185.865643) (xy 53.649993 -185.920157) (xy 53.642235 -185.974117) (xy 53.626876 -186.026423)
			(xy 53.606633 -186.070748) (xy 71.844914 -186.070748) (xy 71.848985 -186.015126) (xy 71.861111 -185.960689)
			(xy 71.881034 -185.908598) (xy 71.90833 -185.859963) (xy 71.942416 -185.81582) (xy 71.982565 -185.777111)
			(xy 72.027923 -185.74466) (xy 72.077523 -185.719159) (xy 72.130307 -185.701152) (xy 72.18515 -185.691022)
			(xy 72.240884 -185.688985) (xy 72.296321 -185.695085) (xy 72.350278 -185.709191) (xy 72.401607 -185.731003)
			(xy 72.449213 -185.760057) (xy 72.492081 -185.795732) (xy 72.529298 -185.837269) (xy 72.560071 -185.883782)
			(xy 72.583743 -185.934279) (xy 72.599811 -185.987686) (xy 72.607931 -186.042862) (xy 72.60844 -186.070748)
			(xy 72.607931 -186.098634) (xy 72.599811 -186.15381) (xy 72.583743 -186.207217) (xy 72.560071 -186.257714)
			(xy 72.529298 -186.304227) (xy 72.492081 -186.345764) (xy 72.449213 -186.381439) (xy 72.401607 -186.410493)
			(xy 72.350278 -186.432305) (xy 72.296321 -186.446411) (xy 72.240884 -186.452511) (xy 72.18515 -186.450474)
			(xy 72.130307 -186.440344) (xy 72.077523 -186.422337) (xy 72.027923 -186.396836) (xy 71.982565 -186.364385)
			(xy 71.942416 -186.325676) (xy 71.90833 -186.281533) (xy 71.881034 -186.232898) (xy 71.861111 -186.180807)
			(xy 71.848985 -186.12637) (xy 71.844914 -186.070748) (xy 53.606633 -186.070748) (xy 53.604229 -186.076011)
			(xy 53.574755 -186.12187) (xy 53.539055 -186.163069) (xy 53.497854 -186.198767) (xy 53.451993 -186.228238)
			(xy 53.402404 -186.250883) (xy 53.350097 -186.266239) (xy 53.296137 -186.273994) (xy 53.26888 -186.274456)
			(xy 53.239964 -186.273897) (xy 53.182794 -186.265178) (xy 53.127596 -186.24793) (xy 53.075633 -186.222546)
			(xy 53.028099 -186.189609) (xy 52.986081 -186.149873) (xy 52.96789 -186.12739) (xy 52.957993 -186.115585)
			(xy 52.932669 -186.098066) (xy 52.903276 -186.08889) (xy 52.872484 -186.08889) (xy 52.843091 -186.098066)
			(xy 52.817767 -186.115585) (xy 52.80787 -186.12739) (xy 52.789693 -186.149886) (xy 52.747671 -186.189621)
			(xy 52.700133 -186.222559) (xy 52.648169 -186.247945) (xy 52.592969 -186.265198) (xy 52.535797 -186.273923)
			(xy 52.50688 -186.274456) (xy 52.480849 -186.274059) (xy 52.42927 -186.266989) (xy 52.379132 -186.252967)
			(xy 52.331368 -186.232257) (xy 52.286865 -186.205241) (xy 52.24645 -186.172423) (xy 52.210875 -186.134412)
			(xy 52.195476 -186.11342) (xy 52.187289 -186.102567) (xy 52.166311 -186.085293) (xy 52.141513 -186.074178)
			(xy 52.11466 -186.070011) (xy 52.087659 -186.073089) (xy 52.062433 -186.083194) (xy 52.040773 -186.099605)
			(xy 52.032154 -186.110118) (xy 52.014003 -186.132905) (xy 51.971903 -186.173171) (xy 51.92417 -186.206567)
			(xy 51.871913 -186.232317) (xy 51.816348 -186.24982) (xy 51.758768 -186.258669) (xy 51.72964 -186.259216)
			(xy 51.702386 -186.258739) (xy 51.648432 -186.250987) (xy 51.59613 -186.235635) (xy 51.546546 -186.212995)
			(xy 51.500689 -186.183529) (xy 51.459492 -186.147836) (xy 51.423795 -186.106643) (xy 51.394324 -186.060789)
			(xy 51.371679 -186.011207) (xy 51.356321 -185.958907) (xy 51.348563 -185.904954) (xy 51.023617 -185.904954)
			(xy 51.031246 -185.913469) (xy 51.062019 -185.959982) (xy 51.085691 -186.010479) (xy 51.101759 -186.063886)
			(xy 51.109879 -186.119062) (xy 51.110388 -186.146948) (xy 51.109879 -186.174834) (xy 51.101759 -186.23001)
			(xy 51.085691 -186.283417) (xy 51.062019 -186.333914) (xy 51.031246 -186.380427) (xy 50.994029 -186.421964)
			(xy 50.951161 -186.457639) (xy 50.903555 -186.486693) (xy 50.852226 -186.508505) (xy 50.798269 -186.522611)
			(xy 50.742832 -186.528711) (xy 50.687098 -186.526674) (xy 50.632255 -186.516544) (xy 50.579471 -186.498537)
			(xy 50.529871 -186.473036) (xy 50.484513 -186.440585) (xy 50.444364 -186.401876) (xy 50.410278 -186.357733)
			(xy 50.382982 -186.309098) (xy 50.363059 -186.257007) (xy 50.350933 -186.20257) (xy 50.346862 -186.146948)
			(xy 43.282362 -186.146948) (xy 43.19016 -186.23915) (xy 14.731238 -186.23915) (xy 14.731238 -186.991498)
			(xy 24.160986 -186.991498) (xy 24.165057 -186.935876) (xy 24.177183 -186.881439) (xy 24.197106 -186.829348)
			(xy 24.224402 -186.780713) (xy 24.258488 -186.73657) (xy 24.298637 -186.697861) (xy 24.343995 -186.66541)
			(xy 24.393595 -186.639909) (xy 24.446379 -186.621902) (xy 24.501222 -186.611772) (xy 24.556956 -186.609735)
			(xy 24.612393 -186.615835) (xy 24.66635 -186.629941) (xy 24.717679 -186.651753) (xy 24.765285 -186.680807)
			(xy 24.808153 -186.716482) (xy 24.84537 -186.758019) (xy 24.876143 -186.804532) (xy 24.899815 -186.855029)
			(xy 24.915883 -186.908436) (xy 24.924003 -186.963612) (xy 24.924512 -186.991498) (xy 24.924003 -187.019384)
			(xy 24.915883 -187.07456) (xy 24.899815 -187.127967) (xy 24.876143 -187.178464) (xy 24.84537 -187.224977)
			(xy 24.808153 -187.266514) (xy 24.765285 -187.302189) (xy 24.717679 -187.331243) (xy 24.66635 -187.353055)
			(xy 24.612393 -187.367161) (xy 24.556956 -187.373261) (xy 24.501222 -187.371224) (xy 24.446379 -187.361094)
			(xy 24.393595 -187.343087) (xy 24.343995 -187.317586) (xy 24.298637 -187.285135) (xy 24.258488 -187.246426)
			(xy 24.224402 -187.202283) (xy 24.197106 -187.153648) (xy 24.177183 -187.101557) (xy 24.165057 -187.04712)
			(xy 24.160986 -186.991498) (xy 14.731238 -186.991498) (xy 14.731238 -187.236354) (xy 14.731703 -187.250272)
			(xy 14.739283 -187.27706) (xy 14.753813 -187.300806) (xy 14.774212 -187.319751) (xy 14.798967 -187.332486)
			(xy 14.826241 -187.338068) (xy 14.854009 -187.336081) (xy 14.88021 -187.326673) (xy 14.891766 -187.318904)
			(xy 14.91613 -187.302237) (xy 14.968922 -187.275827) (xy 15.025156 -187.257877) (xy 15.083485 -187.248817)
			(xy 15.113 -187.248292) (xy 15.140251 -187.248778) (xy 15.194199 -187.256534) (xy 15.246494 -187.271889)
			(xy 15.296071 -187.294531) (xy 15.341921 -187.323997) (xy 15.383112 -187.359688) (xy 15.418803 -187.400879)
			(xy 15.448269 -187.446729) (xy 15.470911 -187.496306) (xy 15.486266 -187.548601) (xy 15.494022 -187.602549)
			(xy 15.494022 -187.657051) (xy 15.486266 -187.710999) (xy 15.470911 -187.763294) (xy 15.462277 -187.7822)
			(xy 15.856202 -187.7822) (xy 15.860273 -187.726578) (xy 15.872399 -187.672141) (xy 15.892322 -187.62005)
			(xy 15.919618 -187.571415) (xy 15.953704 -187.527272) (xy 15.993853 -187.488563) (xy 16.039211 -187.456112)
			(xy 16.088811 -187.430611) (xy 16.141595 -187.412604) (xy 16.196438 -187.402474) (xy 16.252172 -187.400437)
			(xy 16.266031 -187.401962) (xy 20.53666 -187.401962) (xy 20.540731 -187.34634) (xy 20.552857 -187.291903)
			(xy 20.57278 -187.239812) (xy 20.600076 -187.191177) (xy 20.634162 -187.147034) (xy 20.674311 -187.108325)
			(xy 20.719669 -187.075874) (xy 20.769269 -187.050373) (xy 20.822053 -187.032366) (xy 20.876896 -187.022236)
			(xy 20.93263 -187.020199) (xy 20.988067 -187.026299) (xy 21.042024 -187.040405) (xy 21.093353 -187.062217)
			(xy 21.140959 -187.091271) (xy 21.183827 -187.126946) (xy 21.221044 -187.168483) (xy 21.251817 -187.214996)
			(xy 21.275489 -187.265493) (xy 21.291557 -187.3189) (xy 21.299677 -187.374076) (xy 21.300186 -187.401962)
			(xy 21.299677 -187.429848) (xy 21.291557 -187.485024) (xy 21.275489 -187.538431) (xy 21.251817 -187.588928)
			(xy 21.221044 -187.635441) (xy 21.220181 -187.636404) (xy 29.77769 -187.636404) (xy 29.778177 -187.607486)
			(xy 29.786908 -187.550311) (xy 29.80417 -187.49511) (xy 29.829567 -187.443148) (xy 29.862518 -187.395615)
			(xy 29.902267 -187.353602) (xy 29.924756 -187.335414) (xy 29.93656 -187.325514) (xy 29.954083 -187.300192)
			(xy 29.963262 -187.270799) (xy 29.963263 -187.240006) (xy 29.954085 -187.210612) (xy 29.936563 -187.18529)
			(xy 29.924756 -187.175394) (xy 29.90226 -187.157218) (xy 29.862528 -187.115193) (xy 29.829592 -187.067655)
			(xy 29.804206 -187.015691) (xy 29.786952 -186.960492) (xy 29.778224 -186.903321) (xy 29.77769 -186.874404)
			(xy 29.778159 -186.847151) (xy 29.785915 -186.793201) (xy 29.801271 -186.740903) (xy 29.823913 -186.691323)
			(xy 29.85338 -186.64547) (xy 29.889073 -186.604277) (xy 29.930265 -186.568584) (xy 29.976118 -186.539116)
			(xy 30.025697 -186.516473) (xy 30.077995 -186.501117) (xy 30.131945 -186.493359) (xy 30.159198 -186.492896)
			(xy 30.188117 -186.493379) (xy 30.245291 -186.50211) (xy 30.300492 -186.519373) (xy 30.352455 -186.544771)
			(xy 30.399987 -186.577722) (xy 30.442001 -186.617472) (xy 30.460188 -186.639962) (xy 30.470085 -186.651767)
			(xy 30.495409 -186.669286) (xy 30.524802 -186.678462) (xy 30.555594 -186.678462) (xy 30.584987 -186.669286)
			(xy 30.610311 -186.651767) (xy 30.620208 -186.639962) (xy 30.636961 -186.619179) (xy 30.675315 -186.582049)
			(xy 30.718469 -186.550627) (xy 30.765583 -186.525528) (xy 30.815735 -186.507242) (xy 30.867946 -186.496125)
			(xy 30.921198 -186.492395) (xy 30.97445 -186.496125) (xy 31.026661 -186.507242) (xy 31.076813 -186.525528)
			(xy 31.123927 -186.550627) (xy 31.167081 -186.582049) (xy 31.205435 -186.619179) (xy 31.222188 -186.639962)
			(xy 31.232085 -186.651767) (xy 31.257409 -186.669286) (xy 31.286802 -186.678462) (xy 31.317594 -186.678462)
			(xy 31.346987 -186.669286) (xy 31.372311 -186.651767) (xy 31.382208 -186.639962) (xy 31.400385 -186.617467)
			(xy 31.442409 -186.577734) (xy 31.489947 -186.544798) (xy 31.541911 -186.519412) (xy 31.59711 -186.502157)
			(xy 31.654281 -186.49343) (xy 31.683198 -186.492896) (xy 31.710451 -186.493357) (xy 31.764402 -186.501114)
			(xy 31.8167 -186.51647) (xy 31.866281 -186.539113) (xy 31.912134 -186.568581) (xy 31.953327 -186.604275)
			(xy 31.98902 -186.645468) (xy 32.018488 -186.691321) (xy 32.041131 -186.740902) (xy 32.056486 -186.7932)
			(xy 32.064243 -186.847151) (xy 32.064706 -186.874404) (xy 32.064226 -186.903323) (xy 32.055494 -186.960497)
			(xy 32.038231 -187.015699) (xy 32.012832 -187.067661) (xy 31.97988 -187.115193) (xy 31.94013 -187.157207)
			(xy 31.91764 -187.175394) (xy 31.905828 -187.185286) (xy 31.888306 -187.21061) (xy 31.879128 -187.240005)
			(xy 31.879129 -187.2708) (xy 31.888308 -187.300195) (xy 31.905832 -187.325518) (xy 31.91764 -187.335414)
			(xy 31.940139 -187.353587) (xy 31.979871 -187.395612) (xy 31.994653 -187.416948) (xy 45.521372 -187.416948)
			(xy 45.521898 -187.388031) (xy 45.530621 -187.330859) (xy 45.547876 -187.275659) (xy 45.573266 -187.223697)
			(xy 45.60621 -187.176163) (xy 45.645952 -187.134147) (xy 45.668438 -187.115958) (xy 45.6802 -187.106011)
			(xy 45.697727 -187.080703) (xy 45.706913 -187.051321) (xy 45.706921 -187.020537) (xy 45.697753 -186.99115)
			(xy 45.680241 -186.965832) (xy 45.668438 -186.955938) (xy 45.645981 -186.937716) (xy 45.606242 -186.895704)
			(xy 45.573299 -186.848176) (xy 45.547906 -186.79622) (xy 45.530644 -186.741028) (xy 45.52191 -186.683862)
			(xy 45.521372 -186.654948) (xy 45.5219 -186.627697) (xy 45.52965 -186.57375) (xy 45.544999 -186.521454)
			(xy 45.567634 -186.471876) (xy 45.597095 -186.426023) (xy 45.632782 -186.38483) (xy 45.673969 -186.349136)
			(xy 45.719816 -186.319667) (xy 45.76939 -186.297023) (xy 45.821683 -186.281664) (xy 45.875629 -186.273905)
			(xy 45.90288 -186.27344) (xy 45.931797 -186.273958) (xy 45.988969 -186.282685) (xy 46.044169 -186.299942)
			(xy 46.096131 -186.325333) (xy 46.143664 -186.358278) (xy 46.18568 -186.39802) (xy 46.20387 -186.420506)
			(xy 46.213767 -186.432311) (xy 46.239091 -186.44983) (xy 46.268484 -186.459006) (xy 46.299276 -186.459006)
			(xy 46.328669 -186.44983) (xy 46.353993 -186.432311) (xy 46.36389 -186.420506) (xy 46.380643 -186.399723)
			(xy 46.418997 -186.362593) (xy 46.462151 -186.331171) (xy 46.509265 -186.306072) (xy 46.559417 -186.287786)
			(xy 46.611628 -186.276669) (xy 46.66488 -186.272939) (xy 46.718132 -186.276669) (xy 46.770343 -186.287786)
			(xy 46.820495 -186.306072) (xy 46.867609 -186.331171) (xy 46.910763 -186.362593) (xy 46.949117 -186.399723)
			(xy 46.96587 -186.420506) (xy 46.975767 -186.432311) (xy 47.001091 -186.44983) (xy 47.030484 -186.459006)
			(xy 47.061276 -186.459006) (xy 47.090669 -186.44983) (xy 47.115993 -186.432311) (xy 47.12589 -186.420506)
			(xy 47.144088 -186.398029) (xy 47.186106 -186.358293) (xy 47.23364 -186.325353) (xy 47.2856 -186.299963)
			(xy 47.340796 -186.282706) (xy 47.397964 -186.273976) (xy 47.42688 -186.27344) (xy 47.454135 -186.273874)
			(xy 47.508089 -186.28163) (xy 47.56039 -186.296985) (xy 47.609974 -186.319629) (xy 47.655829 -186.3491)
			(xy 47.697023 -186.384797) (xy 47.732717 -186.425993) (xy 47.762184 -186.471851) (xy 47.784824 -186.521436)
			(xy 47.800176 -186.573738) (xy 47.807928 -186.627693) (xy 47.808388 -186.654948) (xy 47.807837 -186.683864)
			(xy 47.799115 -186.741034) (xy 47.781864 -186.796232) (xy 47.756479 -186.848194) (xy 47.723541 -186.895729)
			(xy 47.683805 -186.937747) (xy 47.661322 -186.955938) (xy 47.649468 -186.965782) (xy 47.631949 -186.99112)
			(xy 47.622778 -187.020527) (xy 47.622787 -187.051331) (xy 47.631976 -187.080733) (xy 47.649509 -187.106061)
			(xy 47.661322 -187.115958) (xy 47.68379 -187.134167) (xy 47.723525 -187.176184) (xy 47.756465 -187.223715)
			(xy 47.781856 -187.275673) (xy 47.799116 -187.330867) (xy 47.80785 -187.388033) (xy 47.808388 -187.416948)
			(xy 47.807967 -187.444201) (xy 47.800203 -187.498152) (xy 47.784841 -187.55045) (xy 47.762193 -187.600028)
			(xy 47.73272 -187.645879) (xy 47.697021 -187.68707) (xy 47.655825 -187.72276) (xy 47.609969 -187.752225)
			(xy 47.560386 -187.774865) (xy 47.508086 -187.790218) (xy 47.454133 -187.797972) (xy 47.42688 -187.798456)
			(xy 47.397964 -187.797897) (xy 47.340794 -187.789178) (xy 47.285596 -187.77193) (xy 47.233633 -187.746546)
			(xy 47.186099 -187.713609) (xy 47.144081 -187.673873) (xy 47.12589 -187.65139) (xy 47.115993 -187.639585)
			(xy 47.090669 -187.622066) (xy 47.061276 -187.61289) (xy 47.030484 -187.61289) (xy 47.001091 -187.622066)
			(xy 46.975767 -187.639585) (xy 46.96587 -187.65139) (xy 46.949117 -187.672173) (xy 46.910763 -187.709303)
			(xy 46.867609 -187.740725) (xy 46.820495 -187.765824) (xy 46.770343 -187.78411) (xy 46.718132 -187.795227)
			(xy 46.66488 -187.798957) (xy 46.611628 -187.795227) (xy 46.559417 -187.78411) (xy 46.509265 -187.765824)
			(xy 46.462151 -187.740725) (xy 46.418997 -187.709303) (xy 46.380643 -187.672173) (xy 46.36389 -187.65139)
			(xy 46.353993 -187.639585) (xy 46.328669 -187.622066) (xy 46.299276 -187.61289) (xy 46.268484 -187.61289)
			(xy 46.239091 -187.622066) (xy 46.213767 -187.639585) (xy 46.20387 -187.65139) (xy 46.185693 -187.673886)
			(xy 46.143671 -187.713621) (xy 46.096133 -187.746559) (xy 46.044169 -187.771945) (xy 45.988969 -187.789198)
			(xy 45.931797 -187.797923) (xy 45.90288 -187.798456) (xy 45.87563 -187.797941) (xy 45.821686 -187.790183)
			(xy 45.769395 -187.774828) (xy 45.719821 -187.752188) (xy 45.673973 -187.722724) (xy 45.632784 -187.687036)
			(xy 45.597093 -187.64585) (xy 45.567626 -187.600004) (xy 45.544982 -187.550431) (xy 45.529623 -187.498141)
			(xy 45.521861 -187.444198) (xy 45.521372 -187.416948) (xy 31.994653 -187.416948) (xy 32.012807 -187.443151)
			(xy 32.038192 -187.495115) (xy 32.055446 -187.550316) (xy 32.064172 -187.607487) (xy 32.064706 -187.636404)
			(xy 32.064226 -187.663655) (xy 32.056469 -187.717603) (xy 32.041113 -187.769898) (xy 32.018471 -187.819476)
			(xy 32.014828 -187.825144) (xy 50.220926 -187.825144) (xy 50.220926 -187.770651) (xy 50.228682 -187.716712)
			(xy 50.244034 -187.664426) (xy 50.266671 -187.614856) (xy 50.296132 -187.569013) (xy 50.331817 -187.527829)
			(xy 50.372999 -187.492142) (xy 50.418841 -187.462679) (xy 50.468409 -187.44004) (xy 50.520695 -187.424685)
			(xy 50.574633 -187.416928) (xy 50.60188 -187.41644) (xy 50.61616 -187.416594) (xy 50.644637 -187.418753)
			(xy 50.658776 -187.420758) (xy 50.672463 -187.422461) (xy 50.699839 -187.419145) (xy 50.725325 -187.408615)
			(xy 50.747058 -187.391641) (xy 50.763448 -187.369464) (xy 50.773297 -187.343707) (xy 50.775884 -187.316253)
			(xy 50.771021 -187.289109) (xy 50.765456 -187.276486) (xy 50.753743 -187.250691) (xy 50.737209 -187.196507)
			(xy 50.72887 -187.140474) (xy 50.728372 -187.112148) (xy 50.728804 -187.084891) (xy 50.736555 -187.03093)
			(xy 50.751908 -186.978622) (xy 50.774549 -186.929031) (xy 50.804017 -186.883167) (xy 50.839712 -186.841964)
			(xy 50.880908 -186.806261) (xy 50.926766 -186.776784) (xy 50.976353 -186.754134) (xy 51.028658 -186.738771)
			(xy 51.082617 -186.731009) (xy 51.137132 -186.731005) (xy 51.191092 -186.73876) (xy 51.2434 -186.754116)
			(xy 51.292989 -186.77676) (xy 51.338851 -186.80623) (xy 51.380052 -186.841928) (xy 51.415753 -186.883127)
			(xy 51.445227 -186.928986) (xy 51.467874 -186.978574) (xy 51.483234 -187.03088) (xy 51.490993 -187.08484)
			(xy 51.490993 -187.113947) (xy 51.744926 -187.113947) (xy 51.744926 -187.059453) (xy 51.752681 -187.005514)
			(xy 51.768033 -186.953227) (xy 51.79067 -186.903658) (xy 51.820131 -186.857814) (xy 51.855816 -186.81663)
			(xy 51.896998 -186.780943) (xy 51.94284 -186.75148) (xy 51.992409 -186.72884) (xy 52.044694 -186.713485)
			(xy 52.098633 -186.705728) (xy 52.12588 -186.70524) (xy 52.153121 -186.705696) (xy 52.20705 -186.713445)
			(xy 52.259328 -186.728787) (xy 52.308892 -186.751411) (xy 52.354732 -186.780856) (xy 52.395917 -186.816523)
			(xy 52.431609 -186.857687) (xy 52.449386 -186.885326) (xy 68.972669 -186.885326) (xy 68.972673 -186.830821)
			(xy 68.980434 -186.776872) (xy 68.995794 -186.724577) (xy 69.018439 -186.675) (xy 69.04791 -186.62915)
			(xy 69.083606 -186.587961) (xy 69.124801 -186.552272) (xy 69.170656 -186.522809) (xy 69.220237 -186.500171)
			(xy 69.272535 -186.48482) (xy 69.326485 -186.477069) (xy 69.380989 -186.477074) (xy 69.434938 -186.484836)
			(xy 69.487233 -186.500197) (xy 69.53681 -186.522844) (xy 69.582659 -186.552317) (xy 69.623846 -186.588014)
			(xy 69.659535 -186.62921) (xy 69.688997 -186.675065) (xy 69.711633 -186.724647) (xy 69.726982 -186.776945)
			(xy 69.734732 -186.830896) (xy 69.735192 -186.858148) (xy 69.734755 -186.884607) (xy 69.72744 -186.937018)
			(xy 69.712958 -186.987916) (xy 69.691585 -187.036327) (xy 69.678042 -187.059062) (xy 69.672784 -187.068604)
			(xy 69.670014 -187.090189) (xy 69.676412 -187.11099) (xy 69.690833 -187.127288) (xy 69.7107 -187.13617)
			(xy 69.732461 -187.136049) (xy 69.742558 -187.13196) (xy 69.760727 -187.123786) (xy 69.798394 -187.110803)
			(xy 69.817742 -187.106052) (xy 69.831575 -187.102386) (xy 69.856565 -187.088462) (xy 69.876718 -187.068159)
			(xy 69.890456 -187.043067) (xy 69.896705 -187.015151) (xy 69.894973 -186.986596) (xy 69.89064 -186.972956)
			(xy 69.881294 -186.945481) (xy 69.868189 -186.888945) (xy 69.861589 -186.831286) (xy 69.861176 -186.802268)
			(xy 69.861678 -186.770307) (xy 69.869689 -186.706889) (xy 69.885586 -186.644975) (xy 69.909118 -186.585542)
			(xy 69.939912 -186.529527) (xy 69.977485 -186.477812) (xy 70.021242 -186.431215) (xy 70.070495 -186.39047)
			(xy 70.124466 -186.356219) (xy 70.182305 -186.329002) (xy 70.243098 -186.309249) (xy 70.305888 -186.297271)
			(xy 70.369684 -186.293258) (xy 70.43348 -186.297271) (xy 70.49627 -186.309249) (xy 70.557063 -186.329002)
			(xy 70.614902 -186.356219) (xy 70.668873 -186.39047) (xy 70.718126 -186.431215) (xy 70.761883 -186.477812)
			(xy 70.799456 -186.529527) (xy 70.83025 -186.585542) (xy 70.853782 -186.644975) (xy 70.869679 -186.706889)
			(xy 70.876369 -186.75985) (xy 73.05878 -186.75985) (xy 73.062851 -186.704228) (xy 73.074977 -186.649791)
			(xy 73.0949 -186.5977) (xy 73.122196 -186.549065) (xy 73.156282 -186.504922) (xy 73.196431 -186.466213)
			(xy 73.241789 -186.433762) (xy 73.291389 -186.408261) (xy 73.344173 -186.390254) (xy 73.399016 -186.380124)
			(xy 73.45475 -186.378087) (xy 73.510187 -186.384187) (xy 73.564144 -186.398293) (xy 73.615473 -186.420105)
			(xy 73.663079 -186.449159) (xy 73.705947 -186.484834) (xy 73.743164 -186.526371) (xy 73.773937 -186.572884)
			(xy 73.797609 -186.623381) (xy 73.813677 -186.676788) (xy 73.821797 -186.731964) (xy 73.822306 -186.75985)
			(xy 73.821797 -186.787736) (xy 73.813677 -186.842912) (xy 73.797609 -186.896319) (xy 73.773937 -186.946816)
			(xy 73.743164 -186.993329) (xy 73.705947 -187.034866) (xy 73.663079 -187.070541) (xy 73.615473 -187.099595)
			(xy 73.564144 -187.121407) (xy 73.510187 -187.135513) (xy 73.45475 -187.141613) (xy 73.399016 -187.139576)
			(xy 73.344173 -187.129446) (xy 73.291389 -187.111439) (xy 73.241789 -187.085938) (xy 73.196431 -187.053487)
			(xy 73.156282 -187.014778) (xy 73.122196 -186.970635) (xy 73.0949 -186.922) (xy 73.074977 -186.869909)
			(xy 73.062851 -186.815472) (xy 73.05878 -186.75985) (xy 70.876369 -186.75985) (xy 70.87769 -186.770307)
			(xy 70.878192 -186.802268) (xy 70.877721 -186.834277) (xy 70.869679 -186.897788) (xy 70.85373 -186.959788)
			(xy 70.842378 -186.98972) (xy 70.837121 -187.004501) (xy 70.834901 -187.035778) (xy 70.842255 -187.06626)
			(xy 70.858491 -187.093084) (xy 70.882086 -187.113735) (xy 70.896226 -187.12053) (xy 70.91918 -187.130952)
			(xy 70.962376 -187.156942) (xy 70.982332 -187.172346) (xy 70.99423 -187.18117) (xy 71.021681 -187.192256)
			(xy 71.051158 -187.195003) (xy 71.080185 -187.189182) (xy 71.106324 -187.175282) (xy 71.117206 -187.165234)
			(xy 71.138796 -187.144688) (xy 71.187133 -187.109828) (xy 71.240305 -187.082911) (xy 71.297016 -187.064593)
			(xy 71.355886 -187.05532) (xy 71.385684 -187.054744) (xy 71.412934 -187.055302) (xy 71.46688 -187.063056)
			(xy 71.519173 -187.078409) (xy 71.568749 -187.101048) (xy 71.614599 -187.130512) (xy 71.655788 -187.166201)
			(xy 71.691479 -187.207389) (xy 71.720945 -187.253237) (xy 71.743585 -187.302812) (xy 71.75894 -187.355104)
			(xy 71.766697 -187.40905) (xy 71.766697 -187.46355) (xy 71.765077 -187.474817) (xy 71.893678 -187.474817)
			(xy 71.893678 -187.410895) (xy 71.901689 -187.347477) (xy 71.917586 -187.285563) (xy 71.941118 -187.22613)
			(xy 71.971912 -187.170115) (xy 72.009485 -187.1184) (xy 72.053242 -187.071803) (xy 72.102495 -187.031058)
			(xy 72.156466 -186.996807) (xy 72.214305 -186.96959) (xy 72.275098 -186.949837) (xy 72.337888 -186.937859)
			(xy 72.401684 -186.933846) (xy 72.46548 -186.937859) (xy 72.52827 -186.949837) (xy 72.589063 -186.96959)
			(xy 72.646902 -186.996807) (xy 72.700873 -187.031058) (xy 72.750126 -187.071803) (xy 72.793883 -187.1184)
			(xy 72.831456 -187.170115) (xy 72.86225 -187.22613) (xy 72.885782 -187.285563) (xy 72.901679 -187.347477)
			(xy 72.90969 -187.410895) (xy 72.910192 -187.442856) (xy 72.90969 -187.474817) (xy 72.901679 -187.538235)
			(xy 72.885782 -187.600149) (xy 72.86225 -187.659582) (xy 72.831456 -187.715597) (xy 72.793883 -187.767312)
			(xy 72.750126 -187.813909) (xy 72.700873 -187.854654) (xy 72.646902 -187.888905) (xy 72.638858 -187.89269)
			(xy 73.29754 -187.89269) (xy 73.301611 -187.837068) (xy 73.313737 -187.782631) (xy 73.33366 -187.73054)
			(xy 73.360956 -187.681905) (xy 73.395042 -187.637762) (xy 73.435191 -187.599053) (xy 73.480549 -187.566602)
			(xy 73.530149 -187.541101) (xy 73.582933 -187.523094) (xy 73.637776 -187.512964) (xy 73.69351 -187.510927)
			(xy 73.748947 -187.517027) (xy 73.802904 -187.531133) (xy 73.854233 -187.552945) (xy 73.901839 -187.581999)
			(xy 73.944707 -187.617674) (xy 73.981924 -187.659211) (xy 74.012697 -187.705724) (xy 74.036369 -187.756221)
			(xy 74.052437 -187.809628) (xy 74.053409 -187.816236) (xy 87.107266 -187.816236) (xy 87.111337 -187.760614)
			(xy 87.123463 -187.706177) (xy 87.143386 -187.654086) (xy 87.170682 -187.605451) (xy 87.204768 -187.561308)
			(xy 87.244917 -187.522599) (xy 87.290275 -187.490148) (xy 87.339875 -187.464647) (xy 87.392659 -187.44664)
			(xy 87.447502 -187.43651) (xy 87.503236 -187.434473) (xy 87.558673 -187.440573) (xy 87.61263 -187.454679)
			(xy 87.663959 -187.476491) (xy 87.711565 -187.505545) (xy 87.754433 -187.54122) (xy 87.79165 -187.582757)
			(xy 87.822423 -187.62927) (xy 87.846095 -187.679767) (xy 87.862163 -187.733174) (xy 87.870283 -187.78835)
			(xy 87.870792 -187.816236) (xy 87.870283 -187.844122) (xy 87.862163 -187.899298) (xy 87.846095 -187.952705)
			(xy 87.822423 -188.003202) (xy 87.79165 -188.049715) (xy 87.754433 -188.091252) (xy 87.711565 -188.126927)
			(xy 87.663959 -188.155981) (xy 87.61263 -188.177793) (xy 87.558673 -188.191899) (xy 87.503236 -188.197999)
			(xy 87.447502 -188.195962) (xy 87.392659 -188.185832) (xy 87.339875 -188.167825) (xy 87.290275 -188.142324)
			(xy 87.244917 -188.109873) (xy 87.204768 -188.071164) (xy 87.170682 -188.027021) (xy 87.143386 -187.978386)
			(xy 87.123463 -187.926295) (xy 87.111337 -187.871858) (xy 87.107266 -187.816236) (xy 74.053409 -187.816236)
			(xy 74.060557 -187.864804) (xy 74.061066 -187.89269) (xy 74.060557 -187.920576) (xy 74.052437 -187.975752)
			(xy 74.036369 -188.029159) (xy 74.012697 -188.079656) (xy 73.981924 -188.126169) (xy 73.944707 -188.167706)
			(xy 73.901839 -188.203381) (xy 73.854233 -188.232435) (xy 73.802904 -188.254247) (xy 73.748947 -188.268353)
			(xy 73.69351 -188.274453) (xy 73.637776 -188.272416) (xy 73.582933 -188.262286) (xy 73.530149 -188.244279)
			(xy 73.480549 -188.218778) (xy 73.435191 -188.186327) (xy 73.395042 -188.147618) (xy 73.360956 -188.103475)
			(xy 73.33366 -188.05484) (xy 73.313737 -188.002749) (xy 73.301611 -187.948312) (xy 73.29754 -187.89269)
			(xy 72.638858 -187.89269) (xy 72.589063 -187.916122) (xy 72.52827 -187.935875) (xy 72.46548 -187.947853)
			(xy 72.401684 -187.951867) (xy 72.337888 -187.947853) (xy 72.275098 -187.935875) (xy 72.214305 -187.916122)
			(xy 72.156466 -187.888905) (xy 72.102495 -187.854654) (xy 72.053242 -187.813909) (xy 72.009485 -187.767312)
			(xy 71.971912 -187.715597) (xy 71.941118 -187.659582) (xy 71.917586 -187.600149) (xy 71.901689 -187.538235)
			(xy 71.893678 -187.474817) (xy 71.765077 -187.474817) (xy 71.75894 -187.517496) (xy 71.743585 -187.569788)
			(xy 71.720945 -187.619363) (xy 71.691479 -187.665211) (xy 71.655788 -187.706399) (xy 71.614599 -187.742088)
			(xy 71.568749 -187.771552) (xy 71.519173 -187.794191) (xy 71.46688 -187.809544) (xy 71.412934 -187.817298)
			(xy 71.385684 -187.81776) (xy 71.35994 -187.81735) (xy 71.308921 -187.810412) (xy 71.259299 -187.796679)
			(xy 71.211972 -187.7764) (xy 71.167802 -187.749942) (xy 71.147432 -187.734194) (xy 71.135555 -187.725342)
			(xy 71.108095 -187.714268) (xy 71.078614 -187.71153) (xy 71.049584 -187.717356) (xy 71.023442 -187.731258)
			(xy 71.012558 -187.741306) (xy 70.99099 -187.761876) (xy 70.942646 -187.796732) (xy 70.889469 -187.823643)
			(xy 70.832753 -187.841956) (xy 70.773879 -187.851223) (xy 70.74408 -187.851796) (xy 70.715555 -187.851274)
			(xy 70.659142 -187.842762) (xy 70.604625 -187.825948) (xy 70.553218 -187.801204) (xy 70.506069 -187.769083)
			(xy 70.464226 -187.730301) (xy 70.428624 -187.685721) (xy 70.41388 -187.661296) (xy 70.40679 -187.649881)
			(xy 70.387768 -187.630918) (xy 70.364454 -187.617578) (xy 70.338467 -187.610788) (xy 70.311608 -187.611017)
			(xy 70.28574 -187.61825) (xy 70.262658 -187.631985) (xy 70.243962 -187.651271) (xy 70.237096 -187.66282)
			(xy 70.22256 -187.687959) (xy 70.187031 -187.733889) (xy 70.144955 -187.773908) (xy 70.097302 -187.807092)
			(xy 70.045174 -187.832676) (xy 69.989772 -187.850069) (xy 69.932374 -187.85887) (xy 69.90334 -187.859416)
			(xy 69.876088 -187.858908) (xy 69.82214 -187.851156) (xy 69.769843 -187.835806) (xy 69.720264 -187.813168)
			(xy 69.674411 -187.783705) (xy 69.633218 -187.748016) (xy 69.597524 -187.706828) (xy 69.568055 -187.660979)
			(xy 69.545411 -187.611402) (xy 69.530054 -187.559107) (xy 69.522296 -187.505159) (xy 69.521832 -187.477908)
			(xy 69.522381 -187.448873) (xy 69.531179 -187.391473) (xy 69.539358 -187.363608) (xy 69.543364 -187.349136)
			(xy 69.54376 -187.319127) (xy 69.535412 -187.290301) (xy 69.519042 -187.265147) (xy 69.496065 -187.245841)
			(xy 69.468467 -187.234052) (xy 69.438633 -187.230797) (xy 69.423788 -187.233052) (xy 69.406424 -187.236122)
			(xy 69.371316 -187.239434) (xy 69.353684 -187.239656) (xy 69.326432 -187.239128) (xy 69.272483 -187.231368)
			(xy 69.220187 -187.21601) (xy 69.170609 -187.193366) (xy 69.124758 -187.163896) (xy 69.083569 -187.128201)
			(xy 69.047878 -187.087007) (xy 69.018414 -187.041154) (xy 68.995775 -186.991573) (xy 68.980423 -186.939276)
			(xy 68.972669 -186.885326) (xy 52.449386 -186.885326) (xy 52.461081 -186.90351) (xy 52.483734 -186.95306)
			(xy 52.499107 -187.005329) (xy 52.506888 -187.059253) (xy 52.507388 -187.086494) (xy 52.507798 -187.099882)
			(xy 52.514833 -187.125718) (xy 52.528343 -187.148838) (xy 52.547397 -187.167651) (xy 52.570688 -187.180864)
			(xy 52.596612 -187.187569) (xy 52.610004 -187.18784) (xy 52.61356 -187.18784) (xy 52.640818 -187.188204)
			(xy 52.69478 -187.195958) (xy 52.74709 -187.211312) (xy 52.796681 -187.233955) (xy 52.842545 -187.263426)
			(xy 52.883748 -187.299124) (xy 52.91945 -187.340323) (xy 52.948926 -187.386184) (xy 52.971574 -187.435773)
			(xy 52.986511 -187.486642) (xy 67.775104 -187.486642) (xy 67.775105 -187.432146) (xy 67.782861 -187.378203)
			(xy 67.798215 -187.325914) (xy 67.820854 -187.276342) (xy 67.850317 -187.230496) (xy 67.886004 -187.18931)
			(xy 67.92719 -187.153622) (xy 67.973035 -187.124157) (xy 68.022607 -187.101518) (xy 68.074896 -187.086163)
			(xy 68.128838 -187.078405) (xy 68.183334 -187.078403) (xy 68.237277 -187.086157) (xy 68.289567 -187.101508)
			(xy 68.33914 -187.124144) (xy 68.384988 -187.153605) (xy 68.426176 -187.18929) (xy 68.461866 -187.230474)
			(xy 68.491333 -187.276317) (xy 68.513975 -187.325888) (xy 68.529333 -187.378176) (xy 68.537093 -187.432118)
			(xy 68.537582 -187.459366) (xy 68.537474 -187.473388) (xy 68.53544 -187.501356) (xy 68.533518 -187.515246)
			(xy 68.531778 -187.530214) (xy 68.536199 -187.560008) (xy 68.549127 -187.587212) (xy 68.569435 -187.609456)
			(xy 68.595354 -187.624801) (xy 68.624624 -187.631909) (xy 68.63969 -187.631578) (xy 68.661788 -187.63107)
			(xy 68.689042 -187.631542) (xy 68.742996 -187.639298) (xy 68.795297 -187.654653) (xy 68.84488 -187.677296)
			(xy 68.890736 -187.706764) (xy 68.931932 -187.742459) (xy 68.967628 -187.783653) (xy 68.997098 -187.829509)
			(xy 69.019742 -187.879091) (xy 69.035099 -187.931391) (xy 69.042857 -187.985345) (xy 69.042857 -188.039854)
			(xy 69.0351 -188.093807) (xy 69.019743 -188.146108) (xy 68.997099 -188.19569) (xy 68.967629 -188.241546)
			(xy 68.931933 -188.28274) (xy 68.890738 -188.318435) (xy 68.844882 -188.347904) (xy 68.795298 -188.370546)
			(xy 68.742997 -188.385902) (xy 68.689044 -188.393658) (xy 68.634535 -188.393656) (xy 68.580582 -188.385897)
			(xy 68.528282 -188.370539) (xy 68.4787 -188.347893) (xy 68.432845 -188.318422) (xy 68.391652 -188.282725)
			(xy 68.355958 -188.241528) (xy 68.326491 -188.195672) (xy 68.30385 -188.146088) (xy 68.288496 -188.093786)
			(xy 68.280741 -188.039832) (xy 68.28028 -188.012578) (xy 68.280383 -187.998556) (xy 68.28242 -187.970587)
			(xy 68.284344 -187.956698) (xy 68.28608 -187.941728) (xy 68.281669 -187.91193) (xy 68.268745 -187.884721)
			(xy 68.248435 -187.862474) (xy 68.222513 -187.847131) (xy 68.193239 -187.84003) (xy 68.178172 -187.840366)
			(xy 68.156074 -187.840874) (xy 68.128826 -187.840394) (xy 68.074884 -187.832635) (xy 68.022595 -187.817278)
			(xy 67.973024 -187.794637) (xy 67.92718 -187.765171) (xy 67.885996 -187.729482) (xy 67.85031 -187.688294)
			(xy 67.820848 -187.642447) (xy 67.798211 -187.592875) (xy 67.782858 -187.540585) (xy 67.775104 -187.486642)
			(xy 52.986511 -187.486642) (xy 52.986934 -187.488081) (xy 52.994693 -187.542042) (xy 52.994693 -187.596558)
			(xy 52.986934 -187.650519) (xy 52.971574 -187.702827) (xy 52.948926 -187.752416) (xy 52.91945 -187.798277)
			(xy 52.883748 -187.839476) (xy 52.842545 -187.875174) (xy 52.796681 -187.904645) (xy 52.74709 -187.927288)
			(xy 52.69478 -187.942642) (xy 52.640818 -187.950396) (xy 52.61356 -187.950856) (xy 52.586321 -187.95036)
			(xy 52.532399 -187.942606) (xy 52.480128 -187.927261) (xy 52.43057 -187.904638) (xy 52.384735 -187.875195)
			(xy 52.343553 -187.839533) (xy 52.307862 -187.798375) (xy 52.278388 -187.75256) (xy 52.25573 -187.703018)
			(xy 52.24035 -187.650757) (xy 52.232558 -187.59684) (xy 52.232052 -187.569602) (xy 52.231618 -187.556214)
			(xy 52.224601 -187.530372) (xy 52.2111 -187.507245) (xy 52.192048 -187.488428) (xy 52.168756 -187.475217)
			(xy 52.142829 -187.468521) (xy 52.129436 -187.468256) (xy 52.12588 -187.468256) (xy 52.098633 -187.467672)
			(xy 52.044694 -187.459915) (xy 51.992409 -187.44456) (xy 51.94284 -187.42192) (xy 51.896998 -187.392457)
			(xy 51.855816 -187.35677) (xy 51.820131 -187.315586) (xy 51.79067 -187.269742) (xy 51.768033 -187.220173)
			(xy 51.752681 -187.167886) (xy 51.744926 -187.113947) (xy 51.490993 -187.113947) (xy 51.490993 -187.139355)
			(xy 51.483235 -187.193314) (xy 51.467876 -187.245621) (xy 51.44523 -187.295209) (xy 51.415756 -187.341069)
			(xy 51.380056 -187.382268) (xy 51.338855 -187.417966) (xy 51.292994 -187.447438) (xy 51.243405 -187.470082)
			(xy 51.191098 -187.485439) (xy 51.137137 -187.493194) (xy 51.10988 -187.493656) (xy 51.0956 -187.493507)
			(xy 51.067123 -187.491345) (xy 51.052984 -187.489338) (xy 51.03929 -187.487695) (xy 51.011917 -187.490998)
			(xy 50.986432 -187.501517) (xy 50.964698 -187.518481) (xy 50.948307 -187.540651) (xy 50.938458 -187.566403)
			(xy 50.935872 -187.593852) (xy 50.940737 -187.62099) (xy 50.946304 -187.63361) (xy 50.958019 -187.659404)
			(xy 50.974551 -187.713589) (xy 50.98289 -187.769622) (xy 50.983388 -187.797948) (xy 50.98287 -187.825195)
			(xy 50.975109 -187.879133) (xy 50.95975 -187.931417) (xy 50.937107 -187.980984) (xy 50.907641 -188.026823)
			(xy 50.885866 -188.051948) (xy 53.267862 -188.051948) (xy 53.271933 -187.996326) (xy 53.284059 -187.941889)
			(xy 53.303982 -187.889798) (xy 53.331278 -187.841163) (xy 53.365364 -187.79702) (xy 53.405513 -187.758311)
			(xy 53.450871 -187.72586) (xy 53.500471 -187.700359) (xy 53.553255 -187.682352) (xy 53.608098 -187.672222)
			(xy 53.663832 -187.670185) (xy 53.719269 -187.676285) (xy 53.773226 -187.690391) (xy 53.824555 -187.712203)
			(xy 53.872161 -187.741257) (xy 53.915029 -187.776932) (xy 53.952246 -187.818469) (xy 53.983019 -187.864982)
			(xy 54.006691 -187.915479) (xy 54.022759 -187.968886) (xy 54.030879 -188.024062) (xy 54.031388 -188.051948)
			(xy 54.030879 -188.079834) (xy 54.022759 -188.13501) (xy 54.006691 -188.188417) (xy 53.983019 -188.238914)
			(xy 53.952246 -188.285427) (xy 53.915029 -188.326964) (xy 53.872161 -188.362639) (xy 53.824555 -188.391693)
			(xy 53.773226 -188.413505) (xy 53.719269 -188.427611) (xy 53.663832 -188.433711) (xy 53.608098 -188.431674)
			(xy 53.553255 -188.421544) (xy 53.500471 -188.403537) (xy 53.450871 -188.378036) (xy 53.405513 -188.345585)
			(xy 53.365364 -188.306876) (xy 53.331278 -188.262733) (xy 53.303982 -188.214098) (xy 53.284059 -188.162007)
			(xy 53.271933 -188.10757) (xy 53.267862 -188.051948) (xy 50.885866 -188.051948) (xy 50.871951 -188.068003)
			(xy 50.830765 -188.103685) (xy 50.784919 -188.133142) (xy 50.735348 -188.155776) (xy 50.683061 -188.171124)
			(xy 50.629121 -188.178876) (xy 50.574628 -188.178872) (xy 50.52069 -188.171114) (xy 50.468404 -188.155758)
			(xy 50.418836 -188.133118) (xy 50.372995 -188.103655) (xy 50.331813 -188.067967) (xy 50.296129 -188.026783)
			(xy 50.266668 -187.980939) (xy 50.244032 -187.931369) (xy 50.22868 -187.879083) (xy 50.220926 -187.825144)
			(xy 32.014828 -187.825144) (xy 31.989004 -187.865326) (xy 31.953312 -187.906517) (xy 31.912122 -187.942208)
			(xy 31.866271 -187.971674) (xy 31.816693 -187.994315) (xy 31.764398 -188.00967) (xy 31.710449 -188.017426)
			(xy 31.683198 -188.017912) (xy 31.654279 -188.017429) (xy 31.597105 -188.008697) (xy 31.541904 -187.991434)
			(xy 31.489942 -187.966036) (xy 31.442409 -187.933085) (xy 31.400396 -187.893336) (xy 31.382208 -187.870846)
			(xy 31.372311 -187.859041) (xy 31.346987 -187.841522) (xy 31.317594 -187.832346) (xy 31.286802 -187.832346)
			(xy 31.257409 -187.841522) (xy 31.232085 -187.859041) (xy 31.222188 -187.870846) (xy 31.205435 -187.891629)
			(xy 31.167081 -187.928759) (xy 31.123927 -187.960181) (xy 31.076813 -187.98528) (xy 31.026661 -188.003566)
			(xy 30.97445 -188.014683) (xy 30.921198 -188.018413) (xy 30.867946 -188.014683) (xy 30.815735 -188.003566)
			(xy 30.765583 -187.98528) (xy 30.718469 -187.960181) (xy 30.675315 -187.928759) (xy 30.636961 -187.891629)
			(xy 30.620208 -187.870846) (xy 30.610311 -187.859041) (xy 30.584987 -187.841522) (xy 30.555594 -187.832346)
			(xy 30.524802 -187.832346) (xy 30.495409 -187.841522) (xy 30.470085 -187.859041) (xy 30.460188 -187.870846)
			(xy 30.442015 -187.893345) (xy 30.39999 -187.933077) (xy 30.352451 -187.966013) (xy 30.300487 -187.991398)
			(xy 30.245286 -188.008652) (xy 30.188115 -188.017378) (xy 30.159198 -188.017912) (xy 30.131947 -188.017424)
			(xy 30.077999 -188.009667) (xy 30.025705 -187.994312) (xy 29.976128 -187.971671) (xy 29.930278 -187.942205)
			(xy 29.889088 -187.906514) (xy 29.853396 -187.865324) (xy 29.82393 -187.819474) (xy 29.801288 -187.769897)
			(xy 29.785933 -187.717603) (xy 29.778176 -187.663655) (xy 29.77769 -187.636404) (xy 21.220181 -187.636404)
			(xy 21.183827 -187.676978) (xy 21.140959 -187.712653) (xy 21.093353 -187.741707) (xy 21.042024 -187.763519)
			(xy 20.988067 -187.777625) (xy 20.93263 -187.783725) (xy 20.876896 -187.781688) (xy 20.822053 -187.771558)
			(xy 20.769269 -187.753551) (xy 20.719669 -187.72805) (xy 20.674311 -187.695599) (xy 20.634162 -187.65689)
			(xy 20.600076 -187.612747) (xy 20.57278 -187.564112) (xy 20.552857 -187.512021) (xy 20.540731 -187.457584)
			(xy 20.53666 -187.401962) (xy 16.266031 -187.401962) (xy 16.307609 -187.406537) (xy 16.361566 -187.420643)
			(xy 16.412895 -187.442455) (xy 16.460501 -187.471509) (xy 16.503369 -187.507184) (xy 16.540586 -187.548721)
			(xy 16.571359 -187.595234) (xy 16.595031 -187.645731) (xy 16.611099 -187.699138) (xy 16.619219 -187.754314)
			(xy 16.619728 -187.7822) (xy 16.619219 -187.810086) (xy 16.611099 -187.865262) (xy 16.595031 -187.918669)
			(xy 16.571359 -187.969166) (xy 16.540586 -188.015679) (xy 16.503369 -188.057216) (xy 16.460501 -188.092891)
			(xy 16.412895 -188.121945) (xy 16.361566 -188.143757) (xy 16.307609 -188.157863) (xy 16.252172 -188.163963)
			(xy 16.196438 -188.161926) (xy 16.141595 -188.151796) (xy 16.088811 -188.133789) (xy 16.039211 -188.108288)
			(xy 15.993853 -188.075837) (xy 15.953704 -188.037128) (xy 15.919618 -187.992985) (xy 15.892322 -187.94435)
			(xy 15.872399 -187.892259) (xy 15.860273 -187.837822) (xy 15.856202 -187.7822) (xy 15.462277 -187.7822)
			(xy 15.448269 -187.812871) (xy 15.418803 -187.858721) (xy 15.383112 -187.899912) (xy 15.341921 -187.935603)
			(xy 15.296071 -187.965069) (xy 15.246494 -187.987711) (xy 15.194199 -188.003066) (xy 15.140251 -188.010822)
			(xy 15.113 -188.011308) (xy 15.083489 -188.010752) (xy 15.02517 -188.001663) (xy 14.968942 -187.983718)
			(xy 14.916141 -187.957341) (xy 14.891766 -187.940696) (xy 14.880175 -187.93297) (xy 14.853973 -187.923541)
			(xy 14.826198 -187.921537) (xy 14.798914 -187.927107) (xy 14.774146 -187.939836) (xy 14.753736 -187.958779)
			(xy 14.739198 -187.98253) (xy 14.731612 -188.009323) (xy 14.731238 -188.023246) (xy 14.731238 -189.158996)
			(xy 16.197556 -189.158996) (xy 16.197556 -189.074444) (xy 16.205358 -188.990252) (xy 16.220894 -188.907139)
			(xy 16.244033 -188.825814) (xy 16.274577 -188.746971) (xy 16.312266 -188.671282) (xy 16.356777 -188.599394)
			(xy 16.407731 -188.531919) (xy 16.464694 -188.469434) (xy 16.527179 -188.412471) (xy 16.594654 -188.361517)
			(xy 16.666542 -188.317006) (xy 16.742231 -188.279317) (xy 16.821074 -188.248773) (xy 16.902399 -188.225634)
			(xy 16.985512 -188.210098) (xy 17.069704 -188.202296) (xy 17.11198 -188.201808) (xy 18.35658 -188.201808)
			(xy 18.398856 -188.202304) (xy 18.483047 -188.210106) (xy 18.56616 -188.225642) (xy 18.647484 -188.248781)
			(xy 18.72096 -188.277246) (xy 21.112224 -188.277246) (xy 21.116295 -188.221624) (xy 21.128421 -188.167187)
			(xy 21.148344 -188.115096) (xy 21.17564 -188.066461) (xy 21.209726 -188.022318) (xy 21.249875 -187.983609)
			(xy 21.295233 -187.951158) (xy 21.344833 -187.925657) (xy 21.397617 -187.90765) (xy 21.45246 -187.89752)
			(xy 21.508194 -187.895483) (xy 21.563631 -187.901583) (xy 21.617588 -187.915689) (xy 21.668917 -187.937501)
			(xy 21.716523 -187.966555) (xy 21.759391 -188.00223) (xy 21.796608 -188.043767) (xy 21.827381 -188.09028)
			(xy 21.851053 -188.140777) (xy 21.867121 -188.194184) (xy 21.875241 -188.24936) (xy 21.87575 -188.277246)
			(xy 21.875241 -188.305132) (xy 21.867121 -188.360308) (xy 21.851053 -188.413715) (xy 21.827381 -188.464212)
			(xy 21.796608 -188.510725) (xy 21.759391 -188.552262) (xy 21.716523 -188.587937) (xy 21.668917 -188.616991)
			(xy 21.617588 -188.638803) (xy 21.563631 -188.652909) (xy 21.508194 -188.659009) (xy 21.45246 -188.656972)
			(xy 21.397617 -188.646842) (xy 21.344833 -188.628835) (xy 21.295233 -188.603334) (xy 21.249875 -188.570883)
			(xy 21.209726 -188.532174) (xy 21.17564 -188.488031) (xy 21.148344 -188.439396) (xy 21.128421 -188.387305)
			(xy 21.116295 -188.332868) (xy 21.112224 -188.277246) (xy 18.72096 -188.277246) (xy 18.726326 -188.279325)
			(xy 18.802014 -188.317013) (xy 18.873902 -188.361523) (xy 18.941376 -188.412477) (xy 19.00386 -188.46944)
			(xy 19.060823 -188.531924) (xy 19.111777 -188.599398) (xy 19.156287 -188.671286) (xy 19.193975 -188.746974)
			(xy 19.224519 -188.825816) (xy 19.247658 -188.90714) (xy 19.263194 -188.990253) (xy 19.270996 -189.074444)
			(xy 19.270996 -189.158996) (xy 23.741356 -189.158996) (xy 23.741356 -189.074444) (xy 23.749158 -188.990252)
			(xy 23.764694 -188.907139) (xy 23.787833 -188.825814) (xy 23.818377 -188.746971) (xy 23.856066 -188.671282)
			(xy 23.900577 -188.599394) (xy 23.951531 -188.531919) (xy 24.008494 -188.469434) (xy 24.070979 -188.412471)
			(xy 24.138454 -188.361517) (xy 24.210342 -188.317006) (xy 24.286031 -188.279317) (xy 24.364874 -188.248773)
			(xy 24.446199 -188.225634) (xy 24.529312 -188.210098) (xy 24.613504 -188.202296) (xy 24.65578 -188.201808)
			(xy 25.90038 -188.201808) (xy 25.942658 -188.202248) (xy 26.026854 -188.210049) (xy 26.109971 -188.225584)
			(xy 26.1913 -188.248723) (xy 26.270147 -188.279267) (xy 26.345839 -188.316955) (xy 26.417731 -188.361468)
			(xy 26.485209 -188.412423) (xy 26.547698 -188.469388) (xy 26.604664 -188.531875) (xy 26.655621 -188.599352)
			(xy 26.700135 -188.671243) (xy 26.737825 -188.746935) (xy 26.768371 -188.825781) (xy 26.791511 -188.90711)
			(xy 26.807049 -188.990226) (xy 26.814851 -189.074422) (xy 26.814851 -189.158975) (xy 31.285196 -189.158975)
			(xy 31.285196 -189.074425) (xy 31.292997 -188.990236) (xy 31.308533 -188.907126) (xy 31.331671 -188.825804)
			(xy 31.362213 -188.746963) (xy 31.3999 -188.671277) (xy 31.444409 -188.599391) (xy 31.495361 -188.531919)
			(xy 31.552321 -188.469435) (xy 31.614803 -188.412474) (xy 31.682275 -188.36152) (xy 31.75416 -188.31701)
			(xy 31.829845 -188.279321) (xy 31.908685 -188.248777) (xy 31.990007 -188.225638) (xy 32.073116 -188.2101)
			(xy 32.157305 -188.202297) (xy 32.19958 -188.201808) (xy 33.44418 -188.201808) (xy 33.486458 -188.202248)
			(xy 33.570654 -188.210049) (xy 33.653771 -188.225584) (xy 33.7351 -188.248723) (xy 33.813947 -188.279267)
			(xy 33.889639 -188.316955) (xy 33.961531 -188.361468) (xy 34.029009 -188.412423) (xy 34.091498 -188.469388)
			(xy 34.148464 -188.531875) (xy 34.199421 -188.599352) (xy 34.243935 -188.671243) (xy 34.281625 -188.746935)
			(xy 34.312171 -188.825781) (xy 34.335311 -188.90711) (xy 34.350849 -188.990226) (xy 34.358651 -189.074422)
			(xy 34.358651 -189.158975) (xy 38.828996 -189.158975) (xy 38.828996 -189.074425) (xy 38.836797 -188.990236)
			(xy 38.852333 -188.907126) (xy 38.875471 -188.825804) (xy 38.906013 -188.746963) (xy 38.9437 -188.671277)
			(xy 38.988209 -188.599391) (xy 39.039161 -188.531919) (xy 39.096121 -188.469435) (xy 39.158603 -188.412474)
			(xy 39.226075 -188.36152) (xy 39.29796 -188.31701) (xy 39.373645 -188.279321) (xy 39.452485 -188.248777)
			(xy 39.533807 -188.225638) (xy 39.616916 -188.2101) (xy 39.701105 -188.202297) (xy 39.74338 -188.201808)
			(xy 40.98798 -188.201808) (xy 41.030258 -188.202248) (xy 41.114454 -188.210049) (xy 41.197571 -188.225584)
			(xy 41.2789 -188.248723) (xy 41.357747 -188.279267) (xy 41.433439 -188.316955) (xy 41.505331 -188.361468)
			(xy 41.572809 -188.412423) (xy 41.635298 -188.469388) (xy 41.692264 -188.531875) (xy 41.743221 -188.599352)
			(xy 41.787735 -188.671243) (xy 41.825425 -188.746935) (xy 41.855971 -188.825781) (xy 41.879111 -188.90711)
			(xy 41.894649 -188.990226) (xy 41.902451 -189.074422) (xy 41.902451 -189.158975) (xy 46.372796 -189.158975)
			(xy 46.372796 -189.074425) (xy 46.380597 -188.990236) (xy 46.396133 -188.907126) (xy 46.419271 -188.825804)
			(xy 46.449813 -188.746963) (xy 46.4875 -188.671277) (xy 46.532009 -188.599391) (xy 46.582961 -188.531919)
			(xy 46.639921 -188.469435) (xy 46.702403 -188.412474) (xy 46.769875 -188.36152) (xy 46.84176 -188.31701)
			(xy 46.917445 -188.279321) (xy 46.996285 -188.248777) (xy 47.077607 -188.225638) (xy 47.160716 -188.2101)
			(xy 47.244905 -188.202297) (xy 47.28718 -188.201808) (xy 48.53178 -188.201808) (xy 48.574058 -188.202248)
			(xy 48.658254 -188.210049) (xy 48.741371 -188.225584) (xy 48.8227 -188.248723) (xy 48.901547 -188.279267)
			(xy 48.977239 -188.316955) (xy 49.049131 -188.361468) (xy 49.116609 -188.412423) (xy 49.179098 -188.469388)
			(xy 49.236064 -188.531875) (xy 49.287021 -188.599352) (xy 49.331535 -188.671243) (xy 49.369225 -188.746935)
			(xy 49.399771 -188.825781) (xy 49.422911 -188.90711) (xy 49.438449 -188.990226) (xy 49.446251 -189.074422)
			(xy 49.446251 -189.158975) (xy 53.916596 -189.158975) (xy 53.916596 -189.074425) (xy 53.924397 -188.990236)
			(xy 53.939933 -188.907126) (xy 53.963071 -188.825804) (xy 53.993613 -188.746963) (xy 54.0313 -188.671277)
			(xy 54.075809 -188.599391) (xy 54.126761 -188.531919) (xy 54.183721 -188.469435) (xy 54.246203 -188.412474)
			(xy 54.313675 -188.36152) (xy 54.38556 -188.31701) (xy 54.461245 -188.279321) (xy 54.540085 -188.248777)
			(xy 54.621407 -188.225638) (xy 54.704516 -188.2101) (xy 54.788705 -188.202297) (xy 54.83098 -188.201808)
			(xy 56.07558 -188.201808) (xy 56.117858 -188.202248) (xy 56.202054 -188.210049) (xy 56.285171 -188.225584)
			(xy 56.3665 -188.248723) (xy 56.445347 -188.279267) (xy 56.521039 -188.316955) (xy 56.592931 -188.361468)
			(xy 56.660409 -188.412423) (xy 56.722898 -188.469388) (xy 56.779864 -188.531875) (xy 56.830821 -188.599352)
			(xy 56.875335 -188.671243) (xy 56.913025 -188.746935) (xy 56.943571 -188.825781) (xy 56.966711 -188.90711)
			(xy 56.982249 -188.990226) (xy 56.990051 -189.074422) (xy 56.990051 -189.158978) (xy 56.982249 -189.243174)
			(xy 56.966711 -189.32629) (xy 56.943571 -189.407619) (xy 56.913025 -189.486465) (xy 56.875335 -189.562157)
			(xy 56.830821 -189.634048) (xy 56.779864 -189.701525) (xy 56.722898 -189.764012) (xy 56.660409 -189.820977)
			(xy 56.592931 -189.871932) (xy 56.521039 -189.916445) (xy 56.445347 -189.954133) (xy 56.3665 -189.984677)
			(xy 56.285171 -190.007816) (xy 56.202054 -190.023351) (xy 56.117858 -190.031152) (xy 56.07558 -190.031624)
			(xy 54.83098 -190.031624) (xy 54.788705 -190.031103) (xy 54.704516 -190.0233) (xy 54.621407 -190.007762)
			(xy 54.540085 -189.984623) (xy 54.461245 -189.954079) (xy 54.38556 -189.91639) (xy 54.313675 -189.87188)
			(xy 54.246203 -189.820926) (xy 54.183721 -189.763965) (xy 54.126761 -189.701481) (xy 54.075809 -189.634009)
			(xy 54.0313 -189.562123) (xy 53.993613 -189.486437) (xy 53.963071 -189.407596) (xy 53.939933 -189.326274)
			(xy 53.924397 -189.243164) (xy 53.916596 -189.158975) (xy 49.446251 -189.158975) (xy 49.446251 -189.158978)
			(xy 49.438449 -189.243174) (xy 49.422911 -189.32629) (xy 49.399771 -189.407619) (xy 49.369225 -189.486465)
			(xy 49.331535 -189.562157) (xy 49.287021 -189.634048) (xy 49.236064 -189.701525) (xy 49.179098 -189.764012)
			(xy 49.116609 -189.820977) (xy 49.049131 -189.871932) (xy 48.977239 -189.916445) (xy 48.901547 -189.954133)
			(xy 48.8227 -189.984677) (xy 48.741371 -190.007816) (xy 48.658254 -190.023351) (xy 48.574058 -190.031152)
			(xy 48.53178 -190.031624) (xy 47.28718 -190.031624) (xy 47.244905 -190.031103) (xy 47.160716 -190.0233)
			(xy 47.077607 -190.007762) (xy 46.996285 -189.984623) (xy 46.917445 -189.954079) (xy 46.84176 -189.91639)
			(xy 46.769875 -189.87188) (xy 46.702403 -189.820926) (xy 46.639921 -189.763965) (xy 46.582961 -189.701481)
			(xy 46.532009 -189.634009) (xy 46.4875 -189.562123) (xy 46.449813 -189.486437) (xy 46.419271 -189.407596)
			(xy 46.396133 -189.326274) (xy 46.380597 -189.243164) (xy 46.372796 -189.158975) (xy 41.902451 -189.158975)
			(xy 41.902451 -189.158978) (xy 41.894649 -189.243174) (xy 41.879111 -189.32629) (xy 41.855971 -189.407619)
			(xy 41.825425 -189.486465) (xy 41.787735 -189.562157) (xy 41.743221 -189.634048) (xy 41.692264 -189.701525)
			(xy 41.635298 -189.764012) (xy 41.572809 -189.820977) (xy 41.505331 -189.871932) (xy 41.433439 -189.916445)
			(xy 41.357747 -189.954133) (xy 41.2789 -189.984677) (xy 41.197571 -190.007816) (xy 41.114454 -190.023351)
			(xy 41.030258 -190.031152) (xy 40.98798 -190.031624) (xy 39.74338 -190.031624) (xy 39.701105 -190.031103)
			(xy 39.616916 -190.0233) (xy 39.533807 -190.007762) (xy 39.452485 -189.984623) (xy 39.373645 -189.954079)
			(xy 39.29796 -189.91639) (xy 39.226075 -189.87188) (xy 39.158603 -189.820926) (xy 39.096121 -189.763965)
			(xy 39.039161 -189.701481) (xy 38.988209 -189.634009) (xy 38.9437 -189.562123) (xy 38.906013 -189.486437)
			(xy 38.875471 -189.407596) (xy 38.852333 -189.326274) (xy 38.836797 -189.243164) (xy 38.828996 -189.158975)
			(xy 34.358651 -189.158975) (xy 34.358651 -189.158978) (xy 34.350849 -189.243174) (xy 34.335311 -189.32629)
			(xy 34.312171 -189.407619) (xy 34.281625 -189.486465) (xy 34.243935 -189.562157) (xy 34.199421 -189.634048)
			(xy 34.148464 -189.701525) (xy 34.091498 -189.764012) (xy 34.029009 -189.820977) (xy 33.961531 -189.871932)
			(xy 33.889639 -189.916445) (xy 33.813947 -189.954133) (xy 33.7351 -189.984677) (xy 33.653771 -190.007816)
			(xy 33.570654 -190.023351) (xy 33.486458 -190.031152) (xy 33.44418 -190.031624) (xy 32.19958 -190.031624)
			(xy 32.157305 -190.031103) (xy 32.073116 -190.0233) (xy 31.990007 -190.007762) (xy 31.908685 -189.984623)
			(xy 31.829845 -189.954079) (xy 31.75416 -189.91639) (xy 31.682275 -189.87188) (xy 31.614803 -189.820926)
			(xy 31.552321 -189.763965) (xy 31.495361 -189.701481) (xy 31.444409 -189.634009) (xy 31.3999 -189.562123)
			(xy 31.362213 -189.486437) (xy 31.331671 -189.407596) (xy 31.308533 -189.326274) (xy 31.292997 -189.243164)
			(xy 31.285196 -189.158975) (xy 26.814851 -189.158975) (xy 26.814851 -189.158978) (xy 26.807049 -189.243174)
			(xy 26.791511 -189.32629) (xy 26.768371 -189.407619) (xy 26.737825 -189.486465) (xy 26.700135 -189.562157)
			(xy 26.655621 -189.634048) (xy 26.604664 -189.701525) (xy 26.547698 -189.764012) (xy 26.485209 -189.820977)
			(xy 26.417731 -189.871932) (xy 26.345839 -189.916445) (xy 26.270147 -189.954133) (xy 26.1913 -189.984677)
			(xy 26.109971 -190.007816) (xy 26.026854 -190.023351) (xy 25.942658 -190.031152) (xy 25.90038 -190.031624)
			(xy 24.65578 -190.031624) (xy 24.613504 -190.031144) (xy 24.529312 -190.023342) (xy 24.446199 -190.007806)
			(xy 24.364874 -189.984667) (xy 24.286031 -189.954123) (xy 24.210342 -189.916434) (xy 24.138454 -189.871923)
			(xy 24.070979 -189.820969) (xy 24.008494 -189.764006) (xy 23.951531 -189.701521) (xy 23.900577 -189.634046)
			(xy 23.856066 -189.562158) (xy 23.818377 -189.486469) (xy 23.787833 -189.407626) (xy 23.764694 -189.326301)
			(xy 23.749158 -189.243188) (xy 23.741356 -189.158996) (xy 19.270996 -189.158996) (xy 19.263194 -189.243187)
			(xy 19.247658 -189.3263) (xy 19.224519 -189.407624) (xy 19.193975 -189.486466) (xy 19.156287 -189.562154)
			(xy 19.111777 -189.634042) (xy 19.060823 -189.701516) (xy 19.00386 -189.764) (xy 18.941376 -189.820963)
			(xy 18.873902 -189.871917) (xy 18.802014 -189.916427) (xy 18.726326 -189.954115) (xy 18.647484 -189.984659)
			(xy 18.56616 -190.007798) (xy 18.483047 -190.023334) (xy 18.398856 -190.031136) (xy 18.35658 -190.031624)
			(xy 17.11198 -190.031624) (xy 17.069704 -190.031144) (xy 16.985512 -190.023342) (xy 16.902399 -190.007806)
			(xy 16.821074 -189.984667) (xy 16.742231 -189.954123) (xy 16.666542 -189.916434) (xy 16.594654 -189.871923)
			(xy 16.527179 -189.820969) (xy 16.464694 -189.764006) (xy 16.407731 -189.701521) (xy 16.356777 -189.634046)
			(xy 16.312266 -189.562158) (xy 16.274577 -189.486469) (xy 16.244033 -189.407626) (xy 16.220894 -189.326301)
			(xy 16.205358 -189.243188) (xy 16.197556 -189.158996) (xy 14.731238 -189.158996) (xy 14.731238 -191.074294)
			(xy 14.731749 -191.088785) (xy 14.739893 -191.116601) (xy 14.755525 -191.141006) (xy 14.777386 -191.160035)
			(xy 14.803714 -191.172153) (xy 14.832386 -191.176383) (xy 14.846808 -191.174878) (xy 14.859823 -191.173194)
			(xy 14.886009 -191.171413) (xy 14.899132 -191.171322) (xy 14.926383 -191.171808) (xy 14.980331 -191.179565)
			(xy 15.032625 -191.19492) (xy 15.082202 -191.217561) (xy 15.128052 -191.247028) (xy 15.169242 -191.282719)
			(xy 15.204934 -191.323909) (xy 15.2344 -191.36976) (xy 15.257041 -191.419337) (xy 15.272396 -191.471631)
			(xy 15.280152 -191.525579) (xy 15.280152 -191.580081) (xy 15.272396 -191.634029) (xy 15.257041 -191.686323)
			(xy 15.2344 -191.7359) (xy 15.204934 -191.781751) (xy 15.169242 -191.822941) (xy 15.128052 -191.858632)
			(xy 15.082202 -191.888099) (xy 15.032625 -191.91074) (xy 14.980331 -191.926095) (xy 14.926383 -191.933852)
			(xy 14.899132 -191.934338) (xy 14.886009 -191.934231) (xy 14.859825 -191.93245) (xy 14.846808 -191.930782)
			(xy 14.832393 -191.929304) (xy 14.803744 -191.933554) (xy 14.777442 -191.945678) (xy 14.755602 -191.964701)
			(xy 14.739982 -191.98909) (xy 14.73184 -192.016885) (xy 14.731238 -192.031366) (xy 14.731238 -192.20815)
			(xy 15.371572 -192.848484) (xy 20.437346 -192.848484) (xy 20.441417 -192.792862) (xy 20.453543 -192.738425)
			(xy 20.473466 -192.686334) (xy 20.500762 -192.637699) (xy 20.534848 -192.593556) (xy 20.574997 -192.554847)
			(xy 20.620355 -192.522396) (xy 20.669955 -192.496895) (xy 20.722739 -192.478888) (xy 20.777582 -192.468758)
			(xy 20.833316 -192.466721) (xy 20.888753 -192.472821) (xy 20.94271 -192.486927) (xy 20.994039 -192.508739)
			(xy 21.041645 -192.537793) (xy 21.084513 -192.573468) (xy 21.12173 -192.615005) (xy 21.152503 -192.661518)
			(xy 21.176175 -192.712015) (xy 21.192243 -192.765422) (xy 21.200363 -192.820598) (xy 21.200872 -192.848484)
			(xy 21.200738 -192.85585) (xy 21.43074 -192.85585) (xy 21.434811 -192.800228) (xy 21.446937 -192.745791)
			(xy 21.46686 -192.6937) (xy 21.494156 -192.645065) (xy 21.528242 -192.600922) (xy 21.568391 -192.562213)
			(xy 21.613749 -192.529762) (xy 21.663349 -192.504261) (xy 21.716133 -192.486254) (xy 21.770976 -192.476124)
			(xy 21.82671 -192.474087) (xy 21.882147 -192.480187) (xy 21.936104 -192.494293) (xy 21.987433 -192.516105)
			(xy 22.035039 -192.545159) (xy 22.077907 -192.580834) (xy 22.115124 -192.622371) (xy 22.145897 -192.668884)
			(xy 22.169569 -192.719381) (xy 22.179601 -192.752726) (xy 27.69184 -192.752726) (xy 27.695911 -192.697104)
			(xy 27.708037 -192.642667) (xy 27.72796 -192.590576) (xy 27.755256 -192.541941) (xy 27.789342 -192.497798)
			(xy 27.829491 -192.459089) (xy 27.874849 -192.426638) (xy 27.924449 -192.401137) (xy 27.977233 -192.38313)
			(xy 28.032076 -192.373) (xy 28.08781 -192.370963) (xy 28.143247 -192.377063) (xy 28.197204 -192.391169)
			(xy 28.248533 -192.412981) (xy 28.296139 -192.442035) (xy 28.339007 -192.47771) (xy 28.376224 -192.519247)
			(xy 28.379452 -192.524126) (xy 37.94074 -192.524126) (xy 37.944811 -192.468504) (xy 37.956937 -192.414067)
			(xy 37.97686 -192.361976) (xy 38.004156 -192.313341) (xy 38.038242 -192.269198) (xy 38.078391 -192.230489)
			(xy 38.123749 -192.198038) (xy 38.173349 -192.172537) (xy 38.226133 -192.15453) (xy 38.280976 -192.1444)
			(xy 38.33671 -192.142363) (xy 38.392147 -192.148463) (xy 38.446104 -192.162569) (xy 38.497433 -192.184381)
			(xy 38.545039 -192.213435) (xy 38.578366 -192.24117) (xy 50.31689 -192.24117) (xy 50.320961 -192.185548)
			(xy 50.333087 -192.131111) (xy 50.35301 -192.07902) (xy 50.380306 -192.030385) (xy 50.414392 -191.986242)
			(xy 50.454541 -191.947533) (xy 50.499899 -191.915082) (xy 50.549499 -191.889581) (xy 50.602283 -191.871574)
			(xy 50.657126 -191.861444) (xy 50.71286 -191.859407) (xy 50.768297 -191.865507) (xy 50.822254 -191.879613)
			(xy 50.873583 -191.901425) (xy 50.921189 -191.930479) (xy 50.964057 -191.966154) (xy 51.001274 -192.007691)
			(xy 51.032047 -192.054204) (xy 51.055719 -192.104701) (xy 51.071787 -192.158108) (xy 51.079907 -192.213284)
			(xy 51.080416 -192.24117) (xy 52.34889 -192.24117) (xy 52.352961 -192.185548) (xy 52.365087 -192.131111)
			(xy 52.38501 -192.07902) (xy 52.412306 -192.030385) (xy 52.446392 -191.986242) (xy 52.486541 -191.947533)
			(xy 52.531899 -191.915082) (xy 52.581499 -191.889581) (xy 52.634283 -191.871574) (xy 52.689126 -191.861444)
			(xy 52.74486 -191.859407) (xy 52.800297 -191.865507) (xy 52.854254 -191.879613) (xy 52.905583 -191.901425)
			(xy 52.953189 -191.930479) (xy 52.996057 -191.966154) (xy 53.033274 -192.007691) (xy 53.064047 -192.054204)
			(xy 53.087719 -192.104701) (xy 53.103787 -192.158108) (xy 53.111907 -192.213284) (xy 53.112416 -192.24117)
			(xy 53.11237 -192.24371) (xy 54.69585 -192.24371) (xy 54.699921 -192.188088) (xy 54.712047 -192.133651)
			(xy 54.73197 -192.08156) (xy 54.759266 -192.032925) (xy 54.793352 -191.988782) (xy 54.833501 -191.950073)
			(xy 54.878859 -191.917622) (xy 54.928459 -191.892121) (xy 54.981243 -191.874114) (xy 55.036086 -191.863984)
			(xy 55.09182 -191.861947) (xy 55.147257 -191.868047) (xy 55.201214 -191.882153) (xy 55.252543 -191.903965)
			(xy 55.300149 -191.933019) (xy 55.343017 -191.968694) (xy 55.380234 -192.010231) (xy 55.411007 -192.056744)
			(xy 55.434679 -192.107241) (xy 55.450747 -192.160648) (xy 55.458867 -192.215824) (xy 55.459376 -192.24371)
			(xy 55.458867 -192.271596) (xy 55.450747 -192.326772) (xy 55.434679 -192.380179) (xy 55.411007 -192.430676)
			(xy 55.380234 -192.477189) (xy 55.343017 -192.518726) (xy 55.300149 -192.554401) (xy 55.252543 -192.583455)
			(xy 55.201214 -192.605267) (xy 55.147257 -192.619373) (xy 55.09182 -192.625473) (xy 55.036086 -192.623436)
			(xy 54.981243 -192.613306) (xy 54.928459 -192.595299) (xy 54.878859 -192.569798) (xy 54.833501 -192.537347)
			(xy 54.793352 -192.498638) (xy 54.759266 -192.454495) (xy 54.73197 -192.40586) (xy 54.712047 -192.353769)
			(xy 54.699921 -192.299332) (xy 54.69585 -192.24371) (xy 53.11237 -192.24371) (xy 53.111907 -192.269056)
			(xy 53.103787 -192.324232) (xy 53.087719 -192.377639) (xy 53.064047 -192.428136) (xy 53.033274 -192.474649)
			(xy 52.996057 -192.516186) (xy 52.953189 -192.551861) (xy 52.905583 -192.580915) (xy 52.854254 -192.602727)
			(xy 52.800297 -192.616833) (xy 52.74486 -192.622933) (xy 52.689126 -192.620896) (xy 52.634283 -192.610766)
			(xy 52.581499 -192.592759) (xy 52.531899 -192.567258) (xy 52.486541 -192.534807) (xy 52.446392 -192.496098)
			(xy 52.412306 -192.451955) (xy 52.38501 -192.40332) (xy 52.365087 -192.351229) (xy 52.352961 -192.296792)
			(xy 52.34889 -192.24117) (xy 51.080416 -192.24117) (xy 51.079907 -192.269056) (xy 51.071787 -192.324232)
			(xy 51.055719 -192.377639) (xy 51.032047 -192.428136) (xy 51.001274 -192.474649) (xy 50.964057 -192.516186)
			(xy 50.921189 -192.551861) (xy 50.873583 -192.580915) (xy 50.822254 -192.602727) (xy 50.768297 -192.616833)
			(xy 50.71286 -192.622933) (xy 50.657126 -192.620896) (xy 50.602283 -192.610766) (xy 50.549499 -192.592759)
			(xy 50.499899 -192.567258) (xy 50.454541 -192.534807) (xy 50.414392 -192.496098) (xy 50.380306 -192.451955)
			(xy 50.35301 -192.40332) (xy 50.333087 -192.351229) (xy 50.320961 -192.296792) (xy 50.31689 -192.24117)
			(xy 38.578366 -192.24117) (xy 38.587907 -192.24911) (xy 38.625124 -192.290647) (xy 38.655897 -192.33716)
			(xy 38.679569 -192.387657) (xy 38.695637 -192.441064) (xy 38.703757 -192.49624) (xy 38.704266 -192.524126)
			(xy 38.703757 -192.552012) (xy 38.695637 -192.607188) (xy 38.679569 -192.660595) (xy 38.655897 -192.711092)
			(xy 38.625124 -192.757605) (xy 38.587907 -192.799142) (xy 38.545039 -192.834817) (xy 38.497433 -192.863871)
			(xy 38.446104 -192.885683) (xy 38.392147 -192.899789) (xy 38.33671 -192.905889) (xy 38.280976 -192.903852)
			(xy 38.226133 -192.893722) (xy 38.173349 -192.875715) (xy 38.123749 -192.850214) (xy 38.078391 -192.817763)
			(xy 38.038242 -192.779054) (xy 38.004156 -192.734911) (xy 37.97686 -192.686276) (xy 37.956937 -192.634185)
			(xy 37.944811 -192.579748) (xy 37.94074 -192.524126) (xy 28.379452 -192.524126) (xy 28.406997 -192.56576)
			(xy 28.430669 -192.616257) (xy 28.446737 -192.669664) (xy 28.454857 -192.72484) (xy 28.455366 -192.752726)
			(xy 28.454857 -192.780612) (xy 28.446737 -192.835788) (xy 28.430669 -192.889195) (xy 28.406997 -192.939692)
			(xy 28.376224 -192.986205) (xy 28.339007 -193.027742) (xy 28.296139 -193.063417) (xy 28.248533 -193.092471)
			(xy 28.197204 -193.114283) (xy 28.143247 -193.128389) (xy 28.08781 -193.134489) (xy 28.032076 -193.132452)
			(xy 27.977233 -193.122322) (xy 27.924449 -193.104315) (xy 27.874849 -193.078814) (xy 27.829491 -193.046363)
			(xy 27.789342 -193.007654) (xy 27.755256 -192.963511) (xy 27.72796 -192.914876) (xy 27.708037 -192.862785)
			(xy 27.695911 -192.808348) (xy 27.69184 -192.752726) (xy 22.179601 -192.752726) (xy 22.185637 -192.772788)
			(xy 22.193757 -192.827964) (xy 22.194266 -192.85585) (xy 22.193757 -192.883736) (xy 22.185637 -192.938912)
			(xy 22.169569 -192.992319) (xy 22.145897 -193.042816) (xy 22.115124 -193.089329) (xy 22.077907 -193.130866)
			(xy 22.035039 -193.166541) (xy 21.987433 -193.195595) (xy 21.936104 -193.217407) (xy 21.882147 -193.231513)
			(xy 21.82671 -193.237613) (xy 21.770976 -193.235576) (xy 21.716133 -193.225446) (xy 21.663349 -193.207439)
			(xy 21.613749 -193.181938) (xy 21.568391 -193.149487) (xy 21.528242 -193.110778) (xy 21.494156 -193.066635)
			(xy 21.46686 -193.018) (xy 21.446937 -192.965909) (xy 21.434811 -192.911472) (xy 21.43074 -192.85585)
			(xy 21.200738 -192.85585) (xy 21.200363 -192.87637) (xy 21.192243 -192.931546) (xy 21.176175 -192.984953)
			(xy 21.152503 -193.03545) (xy 21.12173 -193.081963) (xy 21.084513 -193.1235) (xy 21.041645 -193.159175)
			(xy 20.994039 -193.188229) (xy 20.94271 -193.210041) (xy 20.888753 -193.224147) (xy 20.833316 -193.230247)
			(xy 20.777582 -193.22821) (xy 20.722739 -193.21808) (xy 20.669955 -193.200073) (xy 20.620355 -193.174572)
			(xy 20.574997 -193.142121) (xy 20.534848 -193.103412) (xy 20.500762 -193.059269) (xy 20.473466 -193.010634)
			(xy 20.453543 -192.958543) (xy 20.441417 -192.904106) (xy 20.437346 -192.848484) (xy 15.371572 -192.848484)
			(xy 17.276318 -194.75323) (xy 17.822418 -194.75323)
		)
		(stroke
			(width 0)
			(type solid)
		)
		(fill yes)
		(layer "F.Cu")
		(net "PVNN_TERM_CPU1")
	)
	(gr_poly
		(pts
			(xy 331.422756 -330.735686) (xy 331.422756 -330.010262) (xy 331.423264 -330.010008) (xy 331.423264 -329.846432)
			(xy 333.963264 -327.306432) (xy 333.963264 -326.036432) (xy 333.991204 -326.008238) (xy 333.991204 -325.978774)
			(xy 334.391254 -325.578724) (xy 334.420718 -325.578724) (xy 334.471264 -325.528432) (xy 339.157056 -325.528432)
			(xy 340.35111 -324.334124) (xy 340.364318 -324.334124) (xy 340.440264 -324.258432) (xy 341.837264 -324.258432)
			(xy 341.963756 -324.131686) (xy 341.963756 -322.83019) (xy 341.964264 -322.829936) (xy 341.964264 -322.734432)
			(xy 342.472264 -322.226432) (xy 372.190264 -322.226432) (xy 375.568464 -325.604632) (xy 381.232664 -325.604632)
			(xy 382.477264 -326.849232) (xy 382.477264 -329.659996) (xy 384.133344 -331.316076) (xy 399.084292 -331.316076)
			(xy 399.82902 -330.571348) (xy 399.82902 -317.250572) (xy 385.167378 -302.58893) (xy 385.161282 -302.58893)
			(xy 384.798824 -302.226472) (xy 384.798824 -290.8808) (xy 384.176524 -290.2585) (xy 367.89233 -290.2585)
			(xy 367.762028 -290.128198) (xy 367.762028 -289.348672) (xy 367.761426 -289.333135) (xy 367.752005 -289.303521)
			(xy 367.734131 -289.278098) (xy 367.709453 -289.259211) (xy 367.680244 -289.248599) (xy 367.664746 -289.247326)
			(xy 367.646021 -289.246259) (xy 367.608973 -289.240404) (xy 367.590832 -289.235642) (xy 367.584228 -289.233864)
			(xy 367.526316 -289.233864) (xy 367.526316 -289.296602) (xy 367.525726 -289.324792) (xy 367.515818 -289.380294)
			(xy 367.496279 -289.433179) (xy 367.467719 -289.48179) (xy 367.449862 -289.503612) (xy 367.437416 -289.517836)
			(xy 367.437416 -289.568128) (xy 367.451132 -289.582606) (xy 367.467562 -289.601046) (xy 367.495329 -289.641888)
			(xy 367.516712 -289.686406) (xy 367.531235 -289.73361) (xy 367.538575 -289.782448) (xy 367.539016 -289.807142)
			(xy 367.538507 -289.833109) (xy 367.530382 -289.884404) (xy 367.514334 -289.933797) (xy 367.490756 -289.980071)
			(xy 367.46023 -290.022087) (xy 367.423507 -290.05881) (xy 367.381491 -290.089336) (xy 367.335217 -290.112914)
			(xy 367.285824 -290.128962) (xy 367.234529 -290.137087) (xy 367.182595 -290.137087) (xy 367.1313 -290.128962)
			(xy 367.081907 -290.112914) (xy 367.035633 -290.089336) (xy 366.993617 -290.05881) (xy 366.956894 -290.022087)
			(xy 366.926368 -289.980071) (xy 366.90279 -289.933797) (xy 366.886742 -289.884404) (xy 366.878617 -289.833109)
			(xy 366.878108 -289.807142) (xy 366.87857 -289.782451) (xy 366.88592 -289.733619) (xy 366.900447 -289.686422)
			(xy 366.921829 -289.641909) (xy 366.949591 -289.60107) (xy 366.965992 -289.582606) (xy 366.979708 -289.568128)
			(xy 366.979708 -289.517836) (xy 366.967262 -289.503612) (xy 366.949381 -289.481809) (xy 366.920823 -289.433193)
			(xy 366.90129 -289.380302) (xy 366.891395 -289.324794) (xy 366.890808 -289.296602) (xy 366.890808 -289.195002)
			(xy 366.891297 -289.170032) (xy 366.899109 -289.120705) (xy 366.91454 -289.073208) (xy 366.937211 -289.02871)
			(xy 366.966563 -288.988305) (xy 367.001875 -288.95299) (xy 367.042276 -288.923632) (xy 367.086771 -288.900956)
			(xy 367.134266 -288.885518) (xy 367.183592 -288.877701) (xy 367.208562 -288.877248) (xy 367.220033 -288.877353)
			(xy 367.242915 -288.879007) (xy 367.254282 -288.88055) (xy 367.268383 -288.882158) (xy 367.296502 -288.878405)
			(xy 367.322496 -288.867043) (xy 367.344348 -288.848953) (xy 367.360364 -288.825537) (xy 367.36528 -288.812224)
			(xy 367.373061 -288.790297) (xy 367.393913 -288.748705) (xy 367.420392 -288.71045) (xy 367.435892 -288.693098)
			(xy 367.442191 -288.685645) (xy 367.449134 -288.667425) (xy 367.448777 -288.64793) (xy 367.441171 -288.629977)
			(xy 367.434622 -288.62274) (xy 367.416133 -288.603324) (xy 367.384803 -288.55982) (xy 367.360614 -288.511975)
			(xy 367.344155 -288.460952) (xy 367.335826 -288.407992) (xy 367.335308 -288.381186) (xy 367.335808 -288.354912)
			(xy 367.343814 -288.302976) (xy 367.359638 -288.252866) (xy 367.382908 -288.205751) (xy 367.413084 -288.162729)
			(xy 367.44946 -288.124806) (xy 367.491189 -288.092866) (xy 367.537295 -288.067655) (xy 367.586703 -288.04976)
			(xy 367.63826 -288.0396) (xy 367.664492 -288.038032) (xy 367.680031 -288.036858) (xy 367.709337 -288.026311)
			(xy 367.734103 -288.007423) (xy 367.752024 -287.981949) (xy 367.761436 -287.952259) (xy 367.762028 -287.936686)
			(xy 367.762028 -287.720786) (xy 367.761428 -287.705248) (xy 367.752009 -287.67563) (xy 367.734136 -287.650204)
			(xy 367.709457 -287.631313) (xy 367.680246 -287.6207) (xy 367.664746 -287.61944) (xy 367.639519 -287.617893)
			(xy 367.589938 -287.608094) (xy 367.542428 -287.59086) (xy 367.498096 -287.566592) (xy 367.457976 -287.535855)
			(xy 367.423005 -287.499369) (xy 367.393998 -287.457982) (xy 367.371632 -287.41266) (xy 367.356428 -287.364462)
			(xy 367.348741 -287.31451) (xy 367.348262 -287.28924) (xy 367.348715 -287.264605) (xy 367.356031 -287.215882)
			(xy 367.370507 -287.168787) (xy 367.391822 -287.124367) (xy 367.419501 -287.083607) (xy 367.435892 -287.065212)
			(xy 367.442194 -287.057758) (xy 367.449142 -287.039536) (xy 367.448789 -287.020038) (xy 367.441185 -287.00208)
			(xy 367.434622 -286.994854) (xy 367.418533 -286.978068) (xy 367.390562 -286.940925) (xy 367.367861 -286.900346)
			(xy 367.350844 -286.857075) (xy 367.34496 -286.83458) (xy 367.342126 -286.825076) (xy 367.330438 -286.809078)
			(xy 367.313562 -286.798696) (xy 367.294013 -286.795476) (xy 367.284254 -286.797242) (xy 367.265661 -286.80131)
			(xy 367.227847 -286.805635) (xy 367.208816 -286.805878) (xy 367.182847 -286.80537) (xy 367.131549 -286.797248)
			(xy 367.082153 -286.781201) (xy 367.035875 -286.757624) (xy 366.993855 -286.727099) (xy 366.957127 -286.690376)
			(xy 366.926597 -286.648359) (xy 366.903014 -286.602084) (xy 366.886962 -286.55269) (xy 366.878833 -286.501393)
			(xy 366.878362 -286.475424) (xy 366.878816 -286.45079) (xy 366.886135 -286.402068) (xy 366.900613 -286.354974)
			(xy 366.921928 -286.310556) (xy 366.949608 -286.269798) (xy 366.965992 -286.251396) (xy 366.97223 -286.24395)
			(xy 366.979095 -286.225797) (xy 366.978747 -286.206392) (xy 366.971236 -286.188496) (xy 366.964722 -286.181292)
			(xy 366.948578 -286.164457) (xy 366.920515 -286.1272) (xy 366.897743 -286.086493) (xy 366.880681 -286.043082)
			(xy 366.874806 -286.02051) (xy 366.871964 -286.011011) (xy 366.86027 -285.995023) (xy 366.8434 -285.984644)
			(xy 366.823857 -285.981413) (xy 366.8141 -285.983172) (xy 366.795566 -285.987203) (xy 366.757882 -285.991532)
			(xy 366.738916 -285.991808) (xy 366.712947 -285.991326) (xy 366.661649 -285.983203) (xy 366.612253 -285.967154)
			(xy 366.565977 -285.943574) (xy 366.523959 -285.913045) (xy 366.487235 -285.876318) (xy 366.45671 -285.834298)
			(xy 366.433135 -285.788019) (xy 366.41709 -285.738622) (xy 366.408971 -285.687323) (xy 366.408462 -285.661354)
			(xy 366.408914 -285.636719) (xy 366.416229 -285.587995) (xy 366.430703 -285.540899) (xy 366.452016 -285.496477)
			(xy 366.479694 -285.455716) (xy 366.496092 -285.437326) (xy 366.502397 -285.429872) (xy 366.50935 -285.411648)
			(xy 366.509 -285.392146) (xy 366.501399 -285.374182) (xy 366.494822 -285.366968) (xy 366.478732 -285.350182)
			(xy 366.45076 -285.313039) (xy 366.428057 -285.272461) (xy 366.411038 -285.22919) (xy 366.40516 -285.206694)
			(xy 366.402315 -285.197202) (xy 366.390619 -285.181231) (xy 366.373752 -285.170869) (xy 366.354218 -285.167655)
			(xy 366.344454 -285.169356) (xy 366.325861 -285.173424) (xy 366.288047 -285.177748) (xy 366.269016 -285.177992)
			(xy 366.243047 -285.177484) (xy 366.191748 -285.169362) (xy 366.142351 -285.153315) (xy 366.096072 -285.129739)
			(xy 366.05405 -285.099214) (xy 366.017322 -285.062491) (xy 365.986789 -285.020474) (xy 365.963206 -284.974199)
			(xy 365.947151 -284.924805) (xy 365.93902 -284.873507) (xy 365.938562 -284.847538) (xy 365.939015 -284.822903)
			(xy 365.946332 -284.77418) (xy 365.960808 -284.727086) (xy 365.982123 -284.682666) (xy 366.009802 -284.641906)
			(xy 366.026192 -284.62351) (xy 366.032432 -284.616064) (xy 366.039302 -284.597909) (xy 366.038958 -284.5785)
			(xy 366.031449 -284.5606) (xy 366.024922 -284.553406) (xy 366.006329 -284.533908) (xy 365.974836 -284.490197)
			(xy 365.950555 -284.442105) (xy 365.93408 -284.390811) (xy 365.925818 -284.337574) (xy 365.925969 -284.2837)
			(xy 365.93453 -284.230511) (xy 365.951292 -284.17931) (xy 365.975843 -284.131356) (xy 366.007581 -284.087822)
			(xy 366.045728 -284.049779) (xy 366.089346 -284.018158) (xy 366.137367 -283.993737) (xy 366.188612 -283.977113)
			(xy 366.241825 -283.968695) (xy 366.268762 -283.96819) (xy 366.291387 -283.968567) (xy 366.336239 -283.974557)
			(xy 366.35817 -283.980128) (xy 366.367894 -283.982235) (xy 366.387607 -283.979695) (xy 366.404887 -283.969872)
			(xy 366.417153 -283.954232) (xy 366.4204 -283.944822) (xy 366.427876 -283.919823) (xy 366.449604 -283.872387)
			(xy 366.478517 -283.828954) (xy 366.495838 -283.80944) (xy 366.502127 -283.802027) (xy 366.509093 -283.783896)
			(xy 366.508817 -283.764474) (xy 366.501339 -283.746548) (xy 366.494822 -283.739336) (xy 366.478733 -283.72255)
			(xy 366.450765 -283.685405) (xy 366.428066 -283.644826) (xy 366.411051 -283.601555) (xy 366.40516 -283.579062)
			(xy 366.402324 -283.569561) (xy 366.390634 -283.553568) (xy 366.37376 -283.543191) (xy 366.354214 -283.539972)
			(xy 366.344454 -283.541724) (xy 366.325862 -283.545793) (xy 366.288047 -283.550117) (xy 366.269016 -283.55036)
			(xy 366.243046 -283.549878) (xy 366.191744 -283.541755) (xy 366.142345 -283.525707) (xy 366.096065 -283.502128)
			(xy 366.054043 -283.4716) (xy 366.017314 -283.434874) (xy 365.986783 -283.392854) (xy 365.963201 -283.346575)
			(xy 365.94715 -283.297177) (xy 365.939023 -283.245876) (xy 365.938562 -283.219906) (xy 365.939018 -283.195272)
			(xy 365.946338 -283.146552) (xy 365.960818 -283.09946) (xy 365.982136 -283.055043) (xy 366.009817 -283.014287)
			(xy 366.026192 -282.995878) (xy 366.032426 -282.988432) (xy 366.039285 -282.970282) (xy 366.038932 -282.950882)
			(xy 366.031418 -282.932992) (xy 366.024922 -282.925774) (xy 366.008779 -282.908939) (xy 365.980717 -282.871681)
			(xy 365.957948 -282.830974) (xy 365.940888 -282.787562) (xy 365.935006 -282.764992) (xy 365.932162 -282.755495)
			(xy 365.920467 -282.739513) (xy 365.903598 -282.729138) (xy 365.884058 -282.725908) (xy 365.8743 -282.727654)
			(xy 365.855766 -282.731685) (xy 365.818082 -282.736012) (xy 365.799116 -282.73629) (xy 365.773147 -282.735782)
			(xy 365.721848 -282.72766) (xy 365.672451 -282.711613) (xy 365.626172 -282.688037) (xy 365.584151 -282.657511)
			(xy 365.547422 -282.620789) (xy 365.51689 -282.578772) (xy 365.493307 -282.532497) (xy 365.477252 -282.483103)
			(xy 365.469122 -282.431805) (xy 365.468662 -282.405836) (xy 365.469115 -282.381201) (xy 365.476432 -282.332479)
			(xy 365.490909 -282.285384) (xy 365.512223 -282.240964) (xy 365.539903 -282.200205) (xy 365.556292 -282.181808)
			(xy 365.562593 -282.174354) (xy 365.56954 -282.156133) (xy 365.569185 -282.136636) (xy 365.561581 -282.118679)
			(xy 365.555022 -282.11145) (xy 365.538933 -282.094664) (xy 365.510963 -282.05752) (xy 365.488262 -282.016942)
			(xy 365.471245 -281.97367) (xy 365.46536 -281.951176) (xy 365.462526 -281.941672) (xy 365.450837 -281.925676)
			(xy 365.433962 -281.915295) (xy 365.414413 -281.912075) (xy 365.404654 -281.913838) (xy 365.386061 -281.917906)
			(xy 365.348247 -281.922231) (xy 365.329216 -281.922474) (xy 365.303247 -281.921966) (xy 365.251949 -281.913844)
			(xy 365.202553 -281.897797) (xy 365.156276 -281.87422) (xy 365.114256 -281.843695) (xy 365.077529 -281.806971)
			(xy 365.046999 -281.764955) (xy 365.023417 -281.71868) (xy 365.007365 -281.669286) (xy 364.999237 -281.617989)
			(xy 364.998762 -281.59202) (xy 364.999217 -281.567386) (xy 365.006535 -281.518664) (xy 365.021014 -281.471571)
			(xy 365.04233 -281.427153) (xy 365.07001 -281.386396) (xy 365.086392 -281.367992) (xy 365.092629 -281.360546)
			(xy 365.099493 -281.342394) (xy 365.099144 -281.32299) (xy 365.091632 -281.305096) (xy 365.085122 -281.297888)
			(xy 365.068989 -281.281083) (xy 365.040942 -281.243888) (xy 365.018181 -281.203242) (xy 365.001125 -281.159892)
			(xy 364.995206 -281.13736) (xy 364.992371 -281.127854) (xy 364.980682 -281.11185) (xy 364.963806 -281.101459)
			(xy 364.944254 -281.098225) (xy 364.9345 -281.100022) (xy 364.915966 -281.104053) (xy 364.878282 -281.108381)
			(xy 364.859316 -281.108658) (xy 364.833346 -281.108176) (xy 364.782044 -281.100053) (xy 364.732646 -281.084005)
			(xy 364.686365 -281.060426) (xy 364.644344 -281.029898) (xy 364.607615 -280.993172) (xy 364.577084 -280.951152)
			(xy 364.553503 -280.904873) (xy 364.537451 -280.855475) (xy 364.529325 -280.804174) (xy 364.528862 -280.778204)
			(xy 364.529318 -280.75357) (xy 364.536639 -280.70485) (xy 364.551119 -280.657758) (xy 364.572436 -280.613342)
			(xy 364.600118 -280.572586) (xy 364.616492 -280.554176) (xy 364.622787 -280.546723) (xy 364.629722 -280.528506)
			(xy 364.629359 -280.509017) (xy 364.62175 -280.491072) (xy 364.615222 -280.483818) (xy 364.599128 -280.466998)
			(xy 364.571153 -280.429789) (xy 364.548452 -280.389147) (xy 364.531439 -280.345815) (xy 364.52556 -280.32329)
			(xy 364.522705 -280.313759) (xy 364.510954 -280.297729) (xy 364.494005 -280.287346) (xy 364.474386 -280.28416)
			(xy 364.4646 -280.285952) (xy 364.446066 -280.289983) (xy 364.408382 -280.29431) (xy 364.389416 -280.294588)
			(xy 364.363447 -280.29408) (xy 364.312148 -280.285958) (xy 364.262751 -280.269911) (xy 364.216473 -280.246335)
			(xy 364.174452 -280.215809) (xy 364.137723 -280.179086) (xy 364.107191 -280.13707) (xy 364.083608 -280.090795)
			(xy 364.067554 -280.041401) (xy 364.059424 -279.990103) (xy 364.058962 -279.964134) (xy 364.059416 -279.939499)
			(xy 364.066733 -279.890777) (xy 364.081209 -279.843683) (xy 364.102524 -279.799263) (xy 364.130204 -279.758504)
			(xy 364.146592 -279.740106) (xy 364.152831 -279.73266) (xy 364.1597 -279.714505) (xy 364.159355 -279.695098)
			(xy 364.151845 -279.677199) (xy 364.145322 -279.670002) (xy 364.129188 -279.653197) (xy 364.101139 -279.616003)
			(xy 364.078377 -279.575357) (xy 364.06132 -279.532007) (xy 364.055406 -279.509474) (xy 364.052573 -279.499966)
			(xy 364.040885 -279.483958) (xy 364.024008 -279.473563) (xy 364.004453 -279.470329) (xy 363.9947 -279.472136)
			(xy 363.976108 -279.476207) (xy 363.938293 -279.480537) (xy 363.919262 -279.480772) (xy 363.893296 -279.48026)
			(xy 363.842005 -279.472131) (xy 363.792616 -279.456079) (xy 363.746346 -279.4325) (xy 363.704334 -279.401973)
			(xy 363.667614 -279.365251) (xy 363.63709 -279.323237) (xy 363.613513 -279.276965) (xy 363.597464 -279.227576)
			(xy 363.589339 -279.176284) (xy 363.588808 -279.150318) (xy 363.589243 -279.125659) (xy 363.596538 -279.076883)
			(xy 363.611013 -279.029737) (xy 363.632346 -278.985272) (xy 363.66006 -278.944477) (xy 363.676438 -278.926036)
			(xy 363.682726 -278.918623) (xy 363.689691 -278.900492) (xy 363.689414 -278.881072) (xy 363.681935 -278.863147)
			(xy 363.675422 -278.855932) (xy 363.659327 -278.839113) (xy 363.631351 -278.801904) (xy 363.608648 -278.761262)
			(xy 363.591633 -278.71793) (xy 363.58576 -278.695404) (xy 363.58295 -278.685846) (xy 363.571232 -278.669761)
			(xy 363.554257 -278.659375) (xy 363.534601 -278.656265) (xy 363.5248 -278.658066) (xy 363.506208 -278.662137)
			(xy 363.468393 -278.666466) (xy 363.449362 -278.666702) (xy 363.430394 -278.666454) (xy 363.392708 -278.662124)
			(xy 363.374178 -278.658066) (xy 363.364411 -278.656283) (xy 363.344834 -278.659469) (xy 363.327934 -278.669851)
			(xy 363.316241 -278.685872) (xy 363.313472 -278.695404) (xy 363.307593 -278.717977) (xy 363.290554 -278.761399)
			(xy 363.267786 -278.802109) (xy 363.239707 -278.839356) (xy 363.223556 -278.856186) (xy 363.217006 -278.863379)
			(xy 363.209422 -278.881274) (xy 363.20907 -278.900707) (xy 363.216 -278.918866) (xy 363.222286 -278.92629)
			(xy 363.238663 -278.944697) (xy 363.266337 -278.985455) (xy 363.287648 -279.029874) (xy 363.302123 -279.076965)
			(xy 363.30944 -279.125685) (xy 363.309916 -279.150318) (xy 363.309407 -279.176285) (xy 363.301282 -279.22758)
			(xy 363.285234 -279.276973) (xy 363.261656 -279.323247) (xy 363.23113 -279.365263) (xy 363.194407 -279.401986)
			(xy 363.152391 -279.432512) (xy 363.106117 -279.45609) (xy 363.056724 -279.472138) (xy 363.005429 -279.480263)
			(xy 362.953495 -279.480263) (xy 362.9022 -279.472138) (xy 362.852807 -279.45609) (xy 362.806533 -279.432512)
			(xy 362.764517 -279.401986) (xy 362.727794 -279.365263) (xy 362.697268 -279.323247) (xy 362.67369 -279.276973)
			(xy 362.657642 -279.22758) (xy 362.649517 -279.176285) (xy 362.649008 -279.150318) (xy 362.649443 -279.125659)
			(xy 362.656738 -279.076883) (xy 362.671213 -279.029737) (xy 362.692546 -278.985272) (xy 362.72026 -278.944477)
			(xy 362.736638 -278.926036) (xy 362.742926 -278.918623) (xy 362.749891 -278.900492) (xy 362.749614 -278.881072)
			(xy 362.742135 -278.863147) (xy 362.735622 -278.855932) (xy 362.719527 -278.839113) (xy 362.691551 -278.801904)
			(xy 362.668848 -278.761262) (xy 362.651833 -278.71793) (xy 362.64596 -278.695404) (xy 362.64315 -278.685846)
			(xy 362.631432 -278.669761) (xy 362.614457 -278.659375) (xy 362.594801 -278.656265) (xy 362.585 -278.658066)
			(xy 362.566408 -278.662137) (xy 362.528593 -278.666466) (xy 362.509562 -278.666702) (xy 362.483595 -278.66619)
			(xy 362.432302 -278.658061) (xy 362.382912 -278.64201) (xy 362.336639 -278.618431) (xy 362.294625 -278.587905)
			(xy 362.257902 -278.551183) (xy 362.227374 -278.509169) (xy 362.203794 -278.462898) (xy 362.187741 -278.413508)
			(xy 362.179611 -278.362215) (xy 362.179108 -278.336248) (xy 362.17956 -278.311613) (xy 362.186875 -278.262888)
			(xy 362.201348 -278.215791) (xy 362.222659 -278.171368) (xy 362.250334 -278.130605) (xy 362.266738 -278.11222)
			(xy 362.272986 -278.104776) (xy 362.279867 -278.086619) (xy 362.279525 -278.067204) (xy 362.27201 -278.0493)
			(xy 362.265468 -278.042116) (xy 362.246983 -278.022698) (xy 362.215661 -277.979192) (xy 362.191479 -277.931347)
			(xy 362.175027 -277.880325) (xy 362.166702 -277.827366) (xy 362.166154 -277.800562) (xy 362.166686 -277.773578)
			(xy 362.175133 -277.720274) (xy 362.191814 -277.668948) (xy 362.216317 -277.620863) (xy 362.24804 -277.577202)
			(xy 362.286202 -277.53904) (xy 362.329863 -277.507317) (xy 362.377948 -277.482814) (xy 362.429274 -277.466133)
			(xy 362.482578 -277.457686) (xy 362.509562 -277.457154) (xy 362.532187 -277.457531) (xy 362.577039 -277.46352)
			(xy 362.59897 -277.469092) (xy 362.608733 -277.471222) (xy 362.628532 -277.468678) (xy 362.645871 -277.458787)
			(xy 362.65814 -277.443041) (xy 362.6612 -277.433532) (xy 362.668675 -277.408533) (xy 362.690402 -277.361095)
			(xy 362.719314 -277.317662) (xy 362.736638 -277.29815) (xy 362.742929 -277.290737) (xy 362.749898 -277.272604)
			(xy 362.749625 -277.25318) (xy 362.742149 -277.23525) (xy 362.735622 -277.228046) (xy 362.719533 -277.21126)
			(xy 362.691563 -277.174116) (xy 362.668863 -277.133537) (xy 362.651847 -277.090266) (xy 362.64596 -277.067772)
			(xy 362.643125 -277.058269) (xy 362.631436 -277.042274) (xy 362.614561 -277.031894) (xy 362.595013 -277.028674)
			(xy 362.585254 -277.030434) (xy 362.566661 -277.034502) (xy 362.528847 -277.038827) (xy 362.509816 -277.03907)
			(xy 362.483848 -277.038562) (xy 362.43255 -277.03044) (xy 362.383154 -277.014393) (xy 362.336877 -276.990816)
			(xy 362.294857 -276.96029) (xy 362.25813 -276.923567) (xy 362.227601 -276.881551) (xy 362.20402 -276.835276)
			(xy 362.187968 -276.785882) (xy 362.179841 -276.734584) (xy 362.179362 -276.708616) (xy 362.179817 -276.683982)
			(xy 362.187136 -276.635261) (xy 362.201615 -276.588168) (xy 362.222932 -276.54375) (xy 362.250612 -276.502993)
			(xy 362.266992 -276.484588) (xy 362.273228 -276.477142) (xy 362.28009 -276.45899) (xy 362.27974 -276.439587)
			(xy 362.272228 -276.421695) (xy 362.265722 -276.414484) (xy 362.249589 -276.397679) (xy 362.221542 -276.360483)
			(xy 362.198782 -276.319837) (xy 362.181727 -276.276487) (xy 362.175806 -276.253956) (xy 362.172971 -276.24445)
			(xy 362.161281 -276.228448) (xy 362.144406 -276.218058) (xy 362.124854 -276.214824) (xy 362.1151 -276.216618)
			(xy 362.096566 -276.220649) (xy 362.058882 -276.224977) (xy 362.039916 -276.225254) (xy 362.013946 -276.224772)
			(xy 361.962645 -276.216649) (xy 361.913246 -276.200601) (xy 361.866966 -276.177022) (xy 361.824945 -276.146494)
			(xy 361.788217 -276.109767) (xy 361.757686 -276.067747) (xy 361.734105 -276.021469) (xy 361.718054 -275.972071)
			(xy 361.709929 -275.92077) (xy 361.709462 -275.8948) (xy 361.709918 -275.870166) (xy 361.71724 -275.821446)
			(xy 361.73172 -275.774355) (xy 361.753038 -275.729939) (xy 361.78072 -275.689184) (xy 361.797092 -275.670772)
			(xy 361.803386 -275.663319) (xy 361.81032 -275.645103) (xy 361.809956 -275.625615) (xy 361.802346 -275.607671)
			(xy 361.795822 -275.600414) (xy 361.779728 -275.583594) (xy 361.751753 -275.546385) (xy 361.729053 -275.505743)
			(xy 361.71204 -275.46241) (xy 361.70616 -275.439886) (xy 361.703348 -275.430331) (xy 361.691628 -275.414251)
			(xy 361.674655 -275.403869) (xy 361.655002 -275.400761) (xy 361.6452 -275.402548) (xy 361.626608 -275.406619)
			(xy 361.588793 -275.410948) (xy 361.569762 -275.411184) (xy 361.543796 -275.410672) (xy 361.492504 -275.402543)
			(xy 361.443114 -275.386491) (xy 361.396843 -275.362912) (xy 361.35483 -275.332386) (xy 361.318109 -275.295664)
			(xy 361.287584 -275.25365) (xy 361.264005 -275.207378) (xy 361.247955 -275.157989) (xy 361.239827 -275.106696)
			(xy 361.239308 -275.08073) (xy 361.239762 -275.056095) (xy 361.247078 -275.007372) (xy 361.261554 -274.960277)
			(xy 361.282866 -274.915855) (xy 361.310543 -274.875094) (xy 361.326938 -274.856702) (xy 361.333244 -274.849251)
			(xy 361.340196 -274.83103) (xy 361.33984 -274.81153) (xy 361.332226 -274.793575) (xy 361.325668 -274.786344)
			(xy 361.307181 -274.766927) (xy 361.275855 -274.723421) (xy 361.25167 -274.675576) (xy 361.235213 -274.624554)
			(xy 361.226885 -274.571595) (xy 361.226354 -274.54479) (xy 361.226878 -274.517879) (xy 361.235278 -274.464716)
			(xy 361.25187 -274.413515) (xy 361.276248 -274.365531) (xy 361.307815 -274.321937) (xy 361.345798 -274.283804)
			(xy 361.389265 -274.252064) (xy 361.437152 -274.227495) (xy 361.462574 -274.218654) (xy 361.497372 -274.20697)
			(xy 361.497372 -273.777456) (xy 361.463082 -273.765772) (xy 361.438955 -273.757022) (xy 361.393532 -273.733135)
			(xy 361.352347 -273.702515) (xy 361.316387 -273.665899) (xy 361.286518 -273.624166) (xy 361.263457 -273.578318)
			(xy 361.247757 -273.529458) (xy 361.239796 -273.478758) (xy 361.239308 -273.453098) (xy 361.239764 -273.428464)
			(xy 361.247085 -273.379743) (xy 361.261564 -273.332651) (xy 361.282879 -273.288233) (xy 361.310558 -273.247475)
			(xy 361.326938 -273.22907) (xy 361.333237 -273.221619) (xy 361.340178 -273.203403) (xy 361.339813 -273.183912)
			(xy 361.332195 -273.165969) (xy 361.325668 -273.158712) (xy 361.307183 -273.139294) (xy 361.275861 -273.095788)
			(xy 361.251681 -273.047942) (xy 361.235229 -272.996921) (xy 361.226905 -272.943962) (xy 361.226354 -272.917158)
			(xy 361.226881 -272.890248) (xy 361.235285 -272.837089) (xy 361.25188 -272.785892) (xy 361.27626 -272.737911)
			(xy 361.307828 -272.694322) (xy 361.34581 -272.656193) (xy 361.389277 -272.624456) (xy 361.437163 -272.599891)
			(xy 361.462574 -272.591022) (xy 361.497372 -272.579338) (xy 361.497372 -272.14957) (xy 361.463082 -272.137886)
			(xy 361.438954 -272.129137) (xy 361.39353 -272.105249) (xy 361.352344 -272.07463) (xy 361.316383 -272.038014)
			(xy 361.286512 -271.996281) (xy 361.263449 -271.950433) (xy 361.247747 -271.901573) (xy 361.239784 -271.850873)
			(xy 361.239308 -271.825212) (xy 361.239763 -271.800578) (xy 361.247082 -271.751856) (xy 361.261559 -271.704762)
			(xy 361.282874 -271.660343) (xy 361.310551 -271.619583) (xy 361.326938 -271.601184) (xy 361.33324 -271.593733)
			(xy 361.340186 -271.575515) (xy 361.339824 -271.55602) (xy 361.332208 -271.538072) (xy 361.325668 -271.530826)
			(xy 361.307182 -271.511409) (xy 361.275859 -271.467902) (xy 361.251676 -271.420057) (xy 361.235222 -271.369035)
			(xy 361.226896 -271.316077) (xy 361.226354 -271.289272) (xy 361.22688 -271.262362) (xy 361.235282 -271.209201)
			(xy 361.251876 -271.158002) (xy 361.276255 -271.11002) (xy 361.307822 -271.066429) (xy 361.345805 -271.028297)
			(xy 361.389272 -270.99656) (xy 361.437158 -270.971992) (xy 361.462574 -270.963136) (xy 361.497372 -270.951452)
			(xy 361.497372 -270.521938) (xy 361.463082 -270.510254) (xy 361.438955 -270.501504) (xy 361.393534 -270.477616)
			(xy 361.35235 -270.446996) (xy 361.316393 -270.410379) (xy 361.286526 -270.368646) (xy 361.263467 -270.322798)
			(xy 361.24777 -270.273938) (xy 361.239812 -270.22324) (xy 361.239308 -270.19758) (xy 361.239765 -270.172947)
			(xy 361.247089 -270.124227) (xy 361.261569 -270.077136) (xy 361.282887 -270.03272) (xy 361.310567 -269.991964)
			(xy 361.326938 -269.973552) (xy 361.333253 -269.9661) (xy 361.340223 -269.947872) (xy 361.33988 -269.928359)
			(xy 361.332274 -269.910386) (xy 361.325668 -269.903194) (xy 361.307178 -269.883778) (xy 361.275846 -269.840274)
			(xy 361.251654 -269.792429) (xy 361.23519 -269.741407) (xy 361.226853 -269.688446) (xy 361.226354 -269.66164)
			(xy 361.226882 -269.634731) (xy 361.235288 -269.581574) (xy 361.251885 -269.530379) (xy 361.276267 -269.482401)
			(xy 361.307835 -269.438814) (xy 361.345818 -269.400686) (xy 361.389284 -269.368952) (xy 361.437169 -269.344388)
			(xy 361.462574 -269.335504) (xy 361.497372 -269.32382) (xy 361.497372 -268.894052) (xy 361.463082 -268.882368)
			(xy 361.438955 -268.873618) (xy 361.393533 -268.849731) (xy 361.352347 -268.819111) (xy 361.316389 -268.782494)
			(xy 361.28652 -268.740761) (xy 361.263459 -268.694914) (xy 361.24776 -268.646053) (xy 361.2398 -268.595354)
			(xy 361.239308 -268.569694) (xy 361.239764 -268.54506) (xy 361.247086 -268.49634) (xy 361.261565 -268.449248)
			(xy 361.282881 -268.40483) (xy 361.31056 -268.364072) (xy 361.326938 -268.345666) (xy 361.333256 -268.338214)
			(xy 361.340231 -268.319983) (xy 361.339892 -268.300467) (xy 361.332288 -268.282489) (xy 361.325668 -268.275308)
			(xy 361.307183 -268.25589) (xy 361.275862 -268.212383) (xy 361.251682 -268.164538) (xy 361.23523 -268.113517)
			(xy 361.226907 -268.060558) (xy 361.226354 -268.033754) (xy 361.226881 -268.006845) (xy 361.235285 -267.953686)
			(xy 361.251881 -267.902489) (xy 361.276262 -267.854509) (xy 361.30783 -267.81092) (xy 361.345812 -267.772791)
			(xy 361.389278 -267.741055) (xy 361.437164 -267.71649) (xy 361.462574 -267.707618) (xy 361.497372 -267.695934)
			(xy 361.497372 -267.266166) (xy 361.463082 -267.254482) (xy 361.438954 -267.245732) (xy 361.393531 -267.221845)
			(xy 361.352344 -267.191226) (xy 361.316384 -267.154609) (xy 361.286514 -267.112876) (xy 361.263451 -267.067029)
			(xy 361.24775 -267.018168) (xy 361.239788 -266.967468) (xy 361.239308 -266.941808) (xy 361.239763 -266.917174)
			(xy 361.247083 -266.868452) (xy 361.261561 -266.821359) (xy 361.282875 -266.77694) (xy 361.310553 -266.736181)
			(xy 361.326938 -266.71778) (xy 361.333239 -266.710329) (xy 361.340184 -266.692111) (xy 361.339821 -266.672618)
			(xy 361.332204 -266.654671) (xy 361.325668 -266.647422) (xy 361.307183 -266.628004) (xy 361.27586 -266.584498)
			(xy 361.251677 -266.536653) (xy 361.235224 -266.485631) (xy 361.226898 -266.432673) (xy 361.226354 -266.405868)
			(xy 361.226869 -266.378652) (xy 361.235449 -266.324902) (xy 361.252404 -266.273179) (xy 361.27731 -266.22478)
			(xy 361.309542 -266.180919) (xy 361.348293 -266.142694) (xy 361.39259 -266.111064) (xy 361.441325 -266.086822)
			(xy 361.467146 -266.078208) (xy 361.479084 -266.074398) (xy 361.7595 -265.793982) (xy 361.74045 -265.760454)
			(xy 361.726626 -265.734608) (xy 361.707029 -265.679371) (xy 361.697086 -265.621611) (xy 361.696508 -265.592306)
			(xy 361.697009 -265.565319) (xy 361.705452 -265.512009) (xy 361.722131 -265.460676) (xy 361.746635 -265.412585)
			(xy 361.778361 -265.368919) (xy 361.816527 -265.330754) (xy 361.860193 -265.29903) (xy 361.908286 -265.274527)
			(xy 361.959619 -265.25785) (xy 362.012929 -265.249409) (xy 362.039916 -265.248898) (xy 362.062468 -265.249254)
			(xy 362.107188 -265.255115) (xy 362.12907 -265.260582) (xy 362.138805 -265.262851) (xy 362.158628 -265.260412)
			(xy 362.176002 -265.250561) (xy 362.188272 -265.234801) (xy 362.1913 -265.225276) (xy 362.198773 -265.200313)
			(xy 362.220494 -265.152952) (xy 362.249403 -265.109602) (xy 362.266738 -265.090148) (xy 362.273052 -265.082696)
			(xy 362.280021 -265.064468) (xy 362.279677 -265.044957) (xy 362.27207 -265.026985) (xy 362.265468 -265.01979)
			(xy 362.246979 -265.000374) (xy 362.215647 -264.956869) (xy 362.191455 -264.909025) (xy 362.174992 -264.858003)
			(xy 362.166656 -264.805042) (xy 362.166154 -264.778236) (xy 362.166681 -264.751248) (xy 362.175119 -264.697936)
			(xy 362.191793 -264.646599) (xy 362.216292 -264.598504) (xy 362.248014 -264.554833) (xy 362.286177 -264.516662)
			(xy 362.329841 -264.484931) (xy 362.377931 -264.460421) (xy 362.429263 -264.443736) (xy 362.482574 -264.435286)
			(xy 362.509562 -264.434828) (xy 362.532187 -264.435205) (xy 362.577039 -264.441194) (xy 362.59897 -264.446766)
			(xy 362.608695 -264.448872) (xy 362.628412 -264.446333) (xy 362.645697 -264.436513) (xy 362.657972 -264.420876)
			(xy 362.6612 -264.41146) (xy 362.668673 -264.38646) (xy 362.690397 -264.33902) (xy 362.719307 -264.295584)
			(xy 362.736638 -264.276078) (xy 362.742915 -264.268666) (xy 362.749859 -264.250543) (xy 362.749566 -264.231139)
			(xy 362.742079 -264.213234) (xy 362.735622 -264.205974) (xy 362.717131 -264.186559) (xy 362.685796 -264.143055)
			(xy 362.661603 -264.095211) (xy 362.645139 -264.044188) (xy 362.636804 -263.991227) (xy 362.636308 -263.96442)
			(xy 362.636808 -263.937432) (xy 362.645249 -263.884121) (xy 362.661927 -263.832786) (xy 362.68643 -263.784693)
			(xy 362.718156 -263.741025) (xy 362.756322 -263.702858) (xy 362.799989 -263.671132) (xy 362.848082 -263.646628)
			(xy 362.899417 -263.62995) (xy 362.952728 -263.621509) (xy 362.979716 -263.621012) (xy 363.002341 -263.621386)
			(xy 363.047195 -263.627369) (xy 363.069124 -263.63295) (xy 363.078853 -263.635066) (xy 363.098583 -263.632539)
			(xy 363.115882 -263.622721) (xy 363.128168 -263.607078) (xy 363.131354 -263.597644) (xy 363.138261 -263.57448)
			(xy 363.157908 -263.530318) (xy 363.183782 -263.489491) (xy 363.21533 -263.452871) (xy 363.251878 -263.421238)
			(xy 363.292645 -263.39527) (xy 363.336761 -263.37552) (xy 363.383285 -263.362411) (xy 363.407198 -263.358884)
			(xy 363.451394 -263.353042) (xy 363.451394 -260.577076) (xy 363.003084 -260.128766) (xy 363.003084 -258.919726)
			(xy 363.239304 -258.683506) (xy 367.730278 -258.683506) (xy 367.860834 -258.55295) (xy 367.860834 -256.833116)
			(xy 367.722404 -256.694686) (xy 363.495844 -256.694686) (xy 363.486954 -256.697988) (xy 363.458381 -256.708263)
			(xy 363.398693 -256.719373) (xy 363.368336 -256.720086) (xy 363.337981 -256.71937) (xy 363.278298 -256.708242)
			(xy 363.249718 -256.697988) (xy 363.240828 -256.694686) (xy 363.189266 -256.694686) (xy 363.010704 -256.516124)
			(xy 363.010704 -255.218946) (xy 363.211364 -255.018286) (xy 367.768124 -255.018286) (xy 367.888266 -254.898144)
			(xy 367.888266 -253.085092) (xy 367.81994 -253.016766) (xy 363.793024 -253.016766) (xy 363.671104 -253.138686)
			(xy 363.193584 -253.138686) (xy 363.013244 -252.958346) (xy 363.013244 -251.777246) (xy 363.439964 -251.350526)
			(xy 367.722404 -251.350526) (xy 367.887504 -251.185426) (xy 367.887504 -249.575066) (xy 367.694464 -249.382026)
			(xy 364.265464 -249.382026) (xy 364.100364 -249.547126) (xy 363.40415 -249.547126) (xy 363.398308 -249.548396)
			(xy 363.379659 -249.552537) (xy 363.341717 -249.556995) (xy 363.322616 -249.557286) (xy 363.303516 -249.556983)
			(xy 363.265575 -249.552526) (xy 363.246924 -249.548396) (xy 363.241082 -249.547126) (xy 363.142784 -249.547126)
			(xy 362.970064 -249.374406) (xy 362.970064 -248.444766) (xy 363.709204 -247.705626) (xy 366.721644 -247.705626)
			(xy 366.773968 -247.653302) (xy 366.773968 -247.196102) (xy 366.602264 -247.024398) (xy 366.602264 -246.94515)
			(xy 366.538764 -246.94515) (xy 366.527588 -246.950992) (xy 366.503623 -246.963116) (xy 366.452742 -246.980296)
			(xy 366.399753 -246.989033) (xy 366.372902 -246.9896) (xy 366.34758 -246.989117) (xy 366.297527 -246.981398)
			(xy 366.249235 -246.96614) (xy 366.203833 -246.943699) (xy 366.162383 -246.914599) (xy 366.143794 -246.897398)
			(xy 366.13393 -246.888515) (xy 366.110707 -246.875681) (xy 366.084962 -246.869258) (xy 366.058431 -246.869678)
			(xy 366.032903 -246.876913) (xy 366.010096 -246.890475) (xy 366.000538 -246.899684) (xy 365.981759 -246.918268)
			(xy 365.939383 -246.949817) (xy 365.892524 -246.974215) (xy 365.842378 -246.990841) (xy 365.790225 -246.99927)
			(xy 365.76381 -246.99976) (xy 365.73784 -246.999278) (xy 365.686538 -246.991154) (xy 365.63714 -246.975105)
			(xy 365.59086 -246.951525) (xy 365.548839 -246.920996) (xy 365.51211 -246.884269) (xy 365.48158 -246.842249)
			(xy 365.457999 -246.79597) (xy 365.441948 -246.746571) (xy 365.433823 -246.69527) (xy 365.433823 -246.64333)
			(xy 365.441948 -246.592029) (xy 365.457999 -246.54263) (xy 365.48158 -246.496351) (xy 365.51211 -246.454331)
			(xy 365.548839 -246.417604) (xy 365.59086 -246.387075) (xy 365.63714 -246.363495) (xy 365.686538 -246.347446)
			(xy 365.73784 -246.339322) (xy 365.76381 -246.338852) (xy 365.789132 -246.339336) (xy 365.839183 -246.347057)
			(xy 365.887472 -246.362319) (xy 365.93287 -246.384764) (xy 365.974316 -246.413867) (xy 365.992918 -246.431054)
			(xy 366.002784 -246.439931) (xy 366.026007 -246.452755) (xy 366.051749 -246.459173) (xy 366.078275 -246.458751)
			(xy 366.103799 -246.451518) (xy 366.126604 -246.437962) (xy 366.136174 -246.428768) (xy 366.154954 -246.410187)
			(xy 366.197332 -246.378645) (xy 366.244191 -246.354252) (xy 366.294336 -246.33763) (xy 366.346488 -246.329204)
			(xy 366.372902 -246.328692) (xy 366.401148 -246.329266) (xy 366.456818 -246.33886) (xy 366.510051 -246.357768)
			(xy 366.534954 -246.37111) (xy 366.568482 -246.389906) (xy 366.765332 -246.193056) (xy 366.765332 -245.877334)
			(xy 366.764824 -245.876826) (xy 366.764824 -245.749826) (xy 366.701324 -245.686326) (xy 363.514894 -245.686326)
			(xy 363.503972 -245.69166) (xy 363.480836 -245.702763) (xy 363.431985 -245.718478) (xy 363.381293 -245.726457)
			(xy 363.355636 -245.726966) (xy 363.329979 -245.726459) (xy 363.279288 -245.718479) (xy 363.230441 -245.702753)
			(xy 363.2073 -245.69166) (xy 363.196378 -245.686326) (xy 363.135164 -245.686326) (xy 362.998512 -245.549674)
			(xy 362.998512 -244.452394) (xy 363.433614 -244.017546) (xy 367.752884 -244.017546) (xy 367.888774 -243.881656)
			(xy 367.888774 -242.256056) (xy 367.663984 -242.031266) (xy 363.127544 -242.031266) (xy 362.987844 -241.891566)
			(xy 362.987844 -240.491772) (xy 363.211364 -240.268506) (xy 365.708184 -240.268506) (xy 365.758984 -240.217706)
			(xy 365.758984 -239.691926) (xy 365.735362 -239.668304) (xy 364.771432 -239.668304) (xy 363.369352 -238.266224)
			(xy 362.52785 -238.266224) (xy 362.519214 -238.269272) (xy 362.490391 -238.2793) (xy 362.430343 -238.290151)
			(xy 362.399834 -238.290862) (xy 362.377145 -238.290501) (xy 362.332164 -238.284517) (xy 362.310172 -238.278924)
			(xy 362.300442 -238.27681) (xy 362.280712 -238.279338) (xy 362.263411 -238.289154) (xy 362.25112 -238.304794)
			(xy 362.247942 -238.31423) (xy 362.24047 -238.339231) (xy 362.21875 -238.386674) (xy 362.189844 -238.430113)
			(xy 362.172504 -238.449612) (xy 362.166268 -238.457058) (xy 362.159407 -238.47521) (xy 362.159756 -238.494612)
			(xy 362.167268 -238.512505) (xy 362.173774 -238.519716) (xy 362.192365 -238.539214) (xy 362.223854 -238.582923)
			(xy 362.248133 -238.631013) (xy 362.264604 -238.682303) (xy 362.272865 -238.735537) (xy 362.272712 -238.789408)
			(xy 362.26415 -238.842594) (xy 362.247387 -238.89379) (xy 362.222837 -238.941742) (xy 362.1911 -238.985271)
			(xy 362.152956 -239.023311) (xy 362.109339 -239.054929) (xy 362.061321 -239.079348) (xy 362.010079 -239.09597)
			(xy 361.956869 -239.104387) (xy 361.929934 -239.104932) (xy 361.907245 -239.104571) (xy 361.862264 -239.098586)
			(xy 361.840272 -239.092994) (xy 361.830541 -239.09088) (xy 361.810808 -239.093408) (xy 361.793503 -239.103221)
			(xy 361.781205 -239.118859) (xy 361.778042 -239.1283) (xy 361.770565 -239.15326) (xy 361.748838 -239.200617)
			(xy 361.719925 -239.243962) (xy 361.702604 -239.263428) (xy 361.69631 -239.270881) (xy 361.689377 -239.289097)
			(xy 361.689741 -239.308585) (xy 361.69735 -239.326529) (xy 361.703874 -239.333786) (xy 361.722362 -239.353202)
			(xy 361.753689 -239.396707) (xy 361.777874 -239.444552) (xy 361.794329 -239.495575) (xy 361.802655 -239.548535)
			(xy 361.803188 -239.57534) (xy 361.802708 -239.601039) (xy 361.795047 -239.651863) (xy 361.779898 -239.700977)
			(xy 361.757597 -239.747285) (xy 361.728644 -239.789752) (xy 361.693684 -239.827429) (xy 361.6535 -239.859475)
			(xy 361.608988 -239.885174) (xy 361.561143 -239.903951) (xy 361.511034 -239.915389) (xy 361.45978 -239.91923)
			(xy 361.408526 -239.915389) (xy 361.358417 -239.903951) (xy 361.310572 -239.885174) (xy 361.26606 -239.859475)
			(xy 361.225876 -239.827429) (xy 361.190916 -239.789752) (xy 361.161963 -239.747285) (xy 361.139662 -239.700977)
			(xy 361.124513 -239.651863) (xy 361.116852 -239.601039) (xy 361.116372 -239.57534) (xy 361.116884 -239.548533)
			(xy 361.12521 -239.495569) (xy 361.141664 -239.444542) (xy 361.165849 -239.396693) (xy 361.197176 -239.353182)
			(xy 361.215686 -239.333786) (xy 361.222256 -239.326561) (xy 361.229865 -239.308596) (xy 361.23023 -239.289089)
			(xy 361.223296 -239.270851) (xy 361.216956 -239.263428) (xy 361.199654 -239.243998) (xy 361.170766 -239.20073)
			(xy 361.149029 -239.153464) (xy 361.141518 -239.128554) (xy 361.138431 -239.119088) (xy 361.126259 -239.103358)
			(xy 361.109004 -239.093466) (xy 361.08928 -239.09091) (xy 361.079542 -239.092994) (xy 361.057608 -239.098551)
			(xy 361.012758 -239.104539) (xy 360.990134 -239.104932) (xy 360.963144 -239.104433) (xy 360.909829 -239.095994)
			(xy 360.85849 -239.079318) (xy 360.810392 -239.054816) (xy 360.766719 -239.023092) (xy 360.728546 -238.984926)
			(xy 360.696814 -238.941258) (xy 360.672304 -238.893164) (xy 360.65562 -238.841828) (xy 360.647172 -238.788514)
			(xy 360.646726 -238.761524) (xy 360.647239 -238.734718) (xy 360.655568 -238.681756) (xy 360.672027 -238.630733)
			(xy 360.696216 -238.582887) (xy 360.727547 -238.539382) (xy 360.74604 -238.51997) (xy 360.752522 -238.512737)
			(xy 360.75998 -238.494821) (xy 360.760257 -238.475417) (xy 360.753313 -238.457296) (xy 360.747056 -238.449866)
			(xy 360.729728 -238.430357) (xy 360.700816 -238.386923) (xy 360.679092 -238.339484) (xy 360.671618 -238.314484)
			(xy 360.668512 -238.304989) (xy 360.656279 -238.289221) (xy 360.638949 -238.279324) (xy 360.619152 -238.276802)
			(xy 360.609388 -238.278924) (xy 360.587454 -238.284484) (xy 360.542604 -238.290477) (xy 360.51998 -238.290862)
			(xy 360.497355 -238.290488) (xy 360.452501 -238.284504) (xy 360.430572 -238.278924) (xy 360.420816 -238.276806)
			(xy 360.401036 -238.279366) (xy 360.383719 -238.289262) (xy 360.371472 -238.305004) (xy 360.368342 -238.314484)
			(xy 360.360866 -238.339445) (xy 360.33914 -238.386803) (xy 360.310229 -238.43015) (xy 360.292904 -238.449612)
			(xy 360.286668 -238.457058) (xy 360.279807 -238.47521) (xy 360.280156 -238.494612) (xy 360.287668 -238.512505)
			(xy 360.294174 -238.519716) (xy 360.312087 -238.538455) (xy 360.342636 -238.580335) (xy 360.366545 -238.62633)
			(xy 360.383268 -238.675397) (xy 360.392427 -238.726419) (xy 360.393813 -238.778239) (xy 360.387395 -238.829678)
			(xy 360.373319 -238.879568) (xy 360.351904 -238.926776) (xy 360.323638 -238.97023) (xy 360.289161 -239.008941)
			(xy 360.249258 -239.04203) (xy 360.204835 -239.068747) (xy 360.156901 -239.088483) (xy 360.106545 -239.10079)
			(xy 360.054911 -239.10539) (xy 360.003173 -239.102177) (xy 359.952505 -239.091224) (xy 359.904059 -239.07278)
			(xy 359.858935 -239.047264) (xy 359.818159 -239.015256) (xy 359.782657 -238.977483) (xy 359.753235 -238.934804)
			(xy 359.730563 -238.888187) (xy 359.715154 -238.838692) (xy 359.707359 -238.787443) (xy 359.706926 -238.761524)
			(xy 359.707439 -238.734718) (xy 359.715768 -238.681756) (xy 359.732227 -238.630733) (xy 359.756416 -238.582887)
			(xy 359.787747 -238.539382) (xy 359.80624 -238.51997) (xy 359.812722 -238.512737) (xy 359.82018 -238.494821)
			(xy 359.820457 -238.475417) (xy 359.813513 -238.457296) (xy 359.807256 -238.449866) (xy 359.789928 -238.430357)
			(xy 359.761016 -238.386923) (xy 359.739292 -238.339484) (xy 359.731818 -238.314484) (xy 359.728712 -238.304989)
			(xy 359.716479 -238.289221) (xy 359.699149 -238.279324) (xy 359.679352 -238.276802) (xy 359.669588 -238.278924)
			(xy 359.647654 -238.284484) (xy 359.602804 -238.290477) (xy 359.58018 -238.290862) (xy 359.557555 -238.290488)
			(xy 359.512701 -238.284504) (xy 359.490772 -238.278924) (xy 359.481016 -238.276806) (xy 359.461236 -238.279366)
			(xy 359.443919 -238.289262) (xy 359.431672 -238.305004) (xy 359.428542 -238.314484) (xy 359.421066 -238.339445)
			(xy 359.39934 -238.386803) (xy 359.370429 -238.43015) (xy 359.353104 -238.449612) (xy 359.346868 -238.457058)
			(xy 359.340007 -238.47521) (xy 359.340356 -238.494612) (xy 359.347868 -238.512505) (xy 359.354374 -238.519716)
			(xy 359.372287 -238.538455) (xy 359.402836 -238.580335) (xy 359.426745 -238.62633) (xy 359.443468 -238.675397)
			(xy 359.452627 -238.726419) (xy 359.454013 -238.778239) (xy 359.447595 -238.829678) (xy 359.433519 -238.879568)
			(xy 359.412104 -238.926776) (xy 359.383838 -238.97023) (xy 359.349361 -239.008941) (xy 359.309458 -239.04203)
			(xy 359.265035 -239.068747) (xy 359.217101 -239.088483) (xy 359.166745 -239.10079) (xy 359.115111 -239.10539)
			(xy 359.063373 -239.102177) (xy 359.012705 -239.091224) (xy 358.964259 -239.07278) (xy 358.919135 -239.047264)
			(xy 358.878359 -239.015256) (xy 358.842857 -238.977483) (xy 358.813435 -238.934804) (xy 358.790763 -238.888187)
			(xy 358.775354 -238.838692) (xy 358.767559 -238.787443) (xy 358.767126 -238.761524) (xy 358.767639 -238.734718)
			(xy 358.775968 -238.681756) (xy 358.792427 -238.630733) (xy 358.816616 -238.582887) (xy 358.847947 -238.539382)
			(xy 358.86644 -238.51997) (xy 358.872922 -238.512737) (xy 358.88038 -238.494821) (xy 358.880657 -238.475417)
			(xy 358.873713 -238.457296) (xy 358.867456 -238.449866) (xy 358.850128 -238.430357) (xy 358.821216 -238.386923)
			(xy 358.799492 -238.339484) (xy 358.792018 -238.314484) (xy 358.788848 -238.305044) (xy 358.77656 -238.289397)
			(xy 358.759255 -238.279581) (xy 358.73952 -238.277064) (xy 358.729788 -238.279178) (xy 358.707912 -238.284676)
			(xy 358.663188 -238.290542) (xy 358.640634 -238.290862) (xy 358.617945 -238.290501) (xy 358.572964 -238.284517)
			(xy 358.550972 -238.278924) (xy 358.541242 -238.27681) (xy 358.521512 -238.279338) (xy 358.504211 -238.289154)
			(xy 358.49192 -238.304794) (xy 358.488742 -238.31423) (xy 358.48127 -238.339231) (xy 358.45955 -238.386674)
			(xy 358.430644 -238.430113) (xy 358.413304 -238.449612) (xy 358.407068 -238.457058) (xy 358.400207 -238.47521)
			(xy 358.400556 -238.494612) (xy 358.408068 -238.512505) (xy 358.414574 -238.519716) (xy 358.432487 -238.538455)
			(xy 358.463036 -238.580335) (xy 358.486945 -238.62633) (xy 358.503668 -238.675397) (xy 358.512827 -238.726419)
			(xy 358.514213 -238.778239) (xy 358.507795 -238.829678) (xy 358.493719 -238.879568) (xy 358.472304 -238.926776)
			(xy 358.444038 -238.97023) (xy 358.409561 -239.008941) (xy 358.369658 -239.04203) (xy 358.325235 -239.068747)
			(xy 358.277301 -239.088483) (xy 358.226945 -239.10079) (xy 358.175311 -239.10539) (xy 358.123573 -239.102177)
			(xy 358.072905 -239.091224) (xy 358.024459 -239.07278) (xy 357.979335 -239.047264) (xy 357.938559 -239.015256)
			(xy 357.903057 -238.977483) (xy 357.873635 -238.934804) (xy 357.850963 -238.888187) (xy 357.835554 -238.838692)
			(xy 357.827759 -238.787443) (xy 357.827326 -238.761524) (xy 357.827839 -238.734718) (xy 357.836168 -238.681756)
			(xy 357.852627 -238.630733) (xy 357.876816 -238.582887) (xy 357.908147 -238.539382) (xy 357.92664 -238.51997)
			(xy 357.933122 -238.512737) (xy 357.94058 -238.494821) (xy 357.940857 -238.475417) (xy 357.933913 -238.457296)
			(xy 357.927656 -238.449866) (xy 357.910328 -238.430357) (xy 357.881416 -238.386923) (xy 357.859692 -238.339484)
			(xy 357.852218 -238.314484) (xy 357.849112 -238.304989) (xy 357.836879 -238.289221) (xy 357.819549 -238.279324)
			(xy 357.799752 -238.276802) (xy 357.789988 -238.278924) (xy 357.768054 -238.284484) (xy 357.723204 -238.290477)
			(xy 357.70058 -238.290862) (xy 357.677955 -238.290488) (xy 357.633101 -238.284504) (xy 357.611172 -238.278924)
			(xy 357.601416 -238.276806) (xy 357.581636 -238.279366) (xy 357.564319 -238.289262) (xy 357.552072 -238.305004)
			(xy 357.548942 -238.314484) (xy 357.541466 -238.339445) (xy 357.51974 -238.386803) (xy 357.490829 -238.43015)
			(xy 357.473504 -238.449612) (xy 357.467268 -238.457058) (xy 357.460407 -238.47521) (xy 357.460756 -238.494612)
			(xy 357.468268 -238.512505) (xy 357.474774 -238.519716) (xy 357.492687 -238.538455) (xy 357.523236 -238.580335)
			(xy 357.547145 -238.62633) (xy 357.563868 -238.675397) (xy 357.573027 -238.726419) (xy 357.574413 -238.778239)
			(xy 357.567995 -238.829678) (xy 357.553919 -238.879568) (xy 357.532504 -238.926776) (xy 357.504238 -238.97023)
			(xy 357.469761 -239.008941) (xy 357.429858 -239.04203) (xy 357.385435 -239.068747) (xy 357.337501 -239.088483)
			(xy 357.287145 -239.10079) (xy 357.235511 -239.10539) (xy 357.183773 -239.102177) (xy 357.133105 -239.091224)
			(xy 357.084659 -239.07278) (xy 357.039535 -239.047264) (xy 356.998759 -239.015256) (xy 356.963257 -238.977483)
			(xy 356.933835 -238.934804) (xy 356.911163 -238.888187) (xy 356.895754 -238.838692) (xy 356.887959 -238.787443)
			(xy 356.887526 -238.761524) (xy 356.888039 -238.734718) (xy 356.896368 -238.681756) (xy 356.912827 -238.630733)
			(xy 356.937016 -238.582887) (xy 356.968347 -238.539382) (xy 356.98684 -238.51997) (xy 356.993322 -238.512737)
			(xy 357.00078 -238.494821) (xy 357.001057 -238.475417) (xy 356.994113 -238.457296) (xy 356.987856 -238.449866)
			(xy 356.971471 -238.431437) (xy 356.943793 -238.390628) (xy 356.932738 -238.368586) (xy 356.918768 -238.33963)
			(xy 353.619816 -238.33963) (xy 353.619816 -238.69015) (xy 353.619368 -238.710644) (xy 353.611978 -238.750962)
			(xy 353.597449 -238.789289) (xy 353.576257 -238.824374) (xy 353.549093 -238.85507) (xy 353.516846 -238.880372)
			(xy 353.498912 -238.890302) (xy 353.47148 -238.904526) (xy 353.47148 -239.169448) (xy 353.470878 -239.195084)
			(xy 353.459586 -239.245094) (xy 353.449128 -239.268508) (xy 353.44989 -239.292638) (xy 353.449378 -239.318604)
			(xy 353.441249 -239.369897) (xy 353.425198 -239.419287) (xy 353.401618 -239.465558) (xy 353.371092 -239.507572)
			(xy 353.33437 -239.544293) (xy 353.292356 -239.574819) (xy 353.246085 -239.598398) (xy 353.196695 -239.61445)
			(xy 353.145402 -239.622578) (xy 353.119436 -239.623092) (xy 353.105655 -239.62295) (xy 353.078187 -239.620662)
			(xy 353.064572 -239.61852) (xy 353.049974 -239.616591) (xy 353.020766 -239.620236) (xy 352.993808 -239.632052)
			(xy 352.971334 -239.65106) (xy 352.955207 -239.675683) (xy 352.946764 -239.70388) (xy 352.946208 -239.718596)
			(xy 352.946208 -240.16081) (xy 353.020884 -240.235486) (xy 356.574344 -240.235486) (xy 356.719124 -240.380266)
			(xy 356.719124 -240.389156) (xy 357.827326 -240.389156) (xy 357.827865 -240.362351) (xy 357.836188 -240.309391)
			(xy 357.852642 -240.258368) (xy 357.876826 -240.210523) (xy 357.908153 -240.167018) (xy 357.92664 -240.147602)
			(xy 357.933244 -240.14041) (xy 357.940839 -240.122437) (xy 357.94118 -240.102927) (xy 357.934219 -240.084699)
			(xy 357.92791 -240.077244) (xy 357.911548 -240.058823) (xy 357.883864 -240.018071) (xy 357.862544 -239.973657)
			(xy 357.848061 -239.926568) (xy 357.840737 -239.877849) (xy 357.84028 -239.853216) (xy 357.840789 -239.827249)
			(xy 357.848914 -239.775954) (xy 357.864962 -239.726561) (xy 357.88854 -239.680287) (xy 357.919066 -239.638271)
			(xy 357.955789 -239.601548) (xy 357.997805 -239.571022) (xy 358.044079 -239.547444) (xy 358.093472 -239.531396)
			(xy 358.144767 -239.523271) (xy 358.196701 -239.523271) (xy 358.247996 -239.531396) (xy 358.297389 -239.547444)
			(xy 358.343663 -239.571022) (xy 358.385679 -239.601548) (xy 358.422402 -239.638271) (xy 358.452928 -239.680287)
			(xy 358.476506 -239.726561) (xy 358.492554 -239.775954) (xy 358.500679 -239.827249) (xy 358.501188 -239.853216)
			(xy 358.500714 -239.877849) (xy 358.493393 -239.926568) (xy 358.478917 -239.973659) (xy 358.457606 -240.018077)
			(xy 358.429933 -240.058837) (xy 358.413558 -240.077244) (xy 358.407312 -240.084735) (xy 358.400377 -240.102941)
			(xy 358.400717 -240.122421) (xy 358.408283 -240.140374) (xy 358.414828 -240.147602) (xy 358.433301 -240.167033)
			(xy 358.464632 -240.210534) (xy 358.488823 -240.258375) (xy 358.505287 -240.309394) (xy 358.513624 -240.362351)
			(xy 358.514142 -240.389156) (xy 358.513662 -240.414855) (xy 358.506001 -240.465679) (xy 358.490852 -240.514793)
			(xy 358.468551 -240.561101) (xy 358.439598 -240.603568) (xy 358.404638 -240.641245) (xy 358.364454 -240.673291)
			(xy 358.319942 -240.69899) (xy 358.272097 -240.717767) (xy 358.221988 -240.729205) (xy 358.170734 -240.733046)
			(xy 358.11948 -240.729205) (xy 358.069371 -240.717767) (xy 358.021526 -240.69899) (xy 357.977014 -240.673291)
			(xy 357.93683 -240.641245) (xy 357.90187 -240.603568) (xy 357.872917 -240.561101) (xy 357.850616 -240.514793)
			(xy 357.835467 -240.465679) (xy 357.827806 -240.414855) (xy 357.827326 -240.389156) (xy 356.719124 -240.389156)
			(xy 356.719124 -241.749326) (xy 356.490524 -241.977926) (xy 355.545644 -241.977926) (xy 355.545644 -241.979196)
			(xy 354.910644 -241.979196) (xy 354.910644 -241.977926) (xy 354.580444 -241.977926) (xy 354.580444 -241.979196)
			(xy 353.945444 -241.979196) (xy 353.945444 -241.977926) (xy 353.564444 -241.977926) (xy 353.564444 -241.979196)
			(xy 352.929444 -241.979196) (xy 352.929444 -241.977926) (xy 352.599244 -241.977926) (xy 352.599244 -241.979196)
			(xy 351.964244 -241.979196) (xy 351.964244 -241.977926) (xy 351.791524 -241.977926) (xy 351.752408 -242.017042)
			(xy 357.827326 -242.017042) (xy 357.827856 -241.990237) (xy 357.836182 -241.937276) (xy 357.852638 -241.886254)
			(xy 357.876824 -241.838409) (xy 357.908152 -241.794904) (xy 357.92664 -241.775488) (xy 357.93316 -241.768229)
			(xy 357.940768 -241.750285) (xy 357.941133 -241.730799) (xy 357.934202 -241.712584) (xy 357.92791 -241.70513)
			(xy 357.911542 -241.686715) (xy 357.883859 -241.645961) (xy 357.86254 -241.601546) (xy 357.848058 -241.554455)
			(xy 357.840736 -241.505735) (xy 357.84028 -241.481102) (xy 357.840789 -241.455135) (xy 357.848914 -241.40384)
			(xy 357.864962 -241.354447) (xy 357.88854 -241.308173) (xy 357.919066 -241.266157) (xy 357.955789 -241.229434)
			(xy 357.997805 -241.198908) (xy 358.044079 -241.17533) (xy 358.093472 -241.159282) (xy 358.144767 -241.151157)
			(xy 358.196701 -241.151157) (xy 358.247996 -241.159282) (xy 358.297389 -241.17533) (xy 358.343663 -241.198908)
			(xy 358.372599 -241.219931) (xy 361.116298 -241.219931) (xy 361.117685 -241.168113) (xy 361.126845 -241.117092)
			(xy 361.143569 -241.068028) (xy 361.167477 -241.022034) (xy 361.198027 -240.980156) (xy 361.21594 -240.961418)
			(xy 361.222442 -240.954205) (xy 361.229953 -240.936313) (xy 361.230303 -240.916912) (xy 361.223444 -240.898761)
			(xy 361.21721 -240.891314) (xy 361.200834 -240.872905) (xy 361.173152 -240.83215) (xy 361.151835 -240.787733)
			(xy 361.137355 -240.740641) (xy 361.130035 -240.69192) (xy 361.12958 -240.667286) (xy 361.130089 -240.641319)
			(xy 361.138214 -240.590024) (xy 361.154262 -240.540631) (xy 361.17784 -240.494357) (xy 361.208366 -240.452341)
			(xy 361.245089 -240.415618) (xy 361.287105 -240.385092) (xy 361.333379 -240.361514) (xy 361.382772 -240.345466)
			(xy 361.434067 -240.337341) (xy 361.486001 -240.337341) (xy 361.537296 -240.345466) (xy 361.586689 -240.361514)
			(xy 361.632963 -240.385092) (xy 361.674979 -240.415618) (xy 361.711702 -240.452341) (xy 361.742228 -240.494357)
			(xy 361.765806 -240.540631) (xy 361.781854 -240.590024) (xy 361.789979 -240.641319) (xy 361.790488 -240.667286)
			(xy 361.79001 -240.691942) (xy 361.782693 -240.740708) (xy 361.76822 -240.787848) (xy 361.74691 -240.832318)
			(xy 361.719236 -240.873132) (xy 361.702858 -240.891568) (xy 361.696609 -240.899001) (xy 361.689678 -240.917121)
			(xy 361.689955 -240.93652) (xy 361.697401 -240.954435) (xy 361.703874 -240.961672) (xy 361.722371 -240.981081)
			(xy 361.753701 -241.024587) (xy 361.777889 -241.072433) (xy 361.794347 -241.123458) (xy 361.802675 -241.17642)
			(xy 361.803188 -241.203226) (xy 361.802729 -241.229144) (xy 361.794935 -241.280391) (xy 361.779526 -241.329885)
			(xy 361.756853 -241.3765) (xy 361.727432 -241.419179) (xy 361.691931 -241.45695) (xy 361.651155 -241.488957)
			(xy 361.606033 -241.514471) (xy 361.557588 -241.532914) (xy 361.506922 -241.543866) (xy 361.455185 -241.547078)
			(xy 361.403552 -241.542478) (xy 361.353198 -241.530171) (xy 361.305266 -241.510434) (xy 361.260844 -241.483718)
			(xy 361.220943 -241.450629) (xy 361.186468 -241.411918) (xy 361.158203 -241.368465) (xy 361.136789 -241.321258)
			(xy 361.122714 -241.271369) (xy 361.116298 -241.219931) (xy 358.372599 -241.219931) (xy 358.385679 -241.229434)
			(xy 358.422402 -241.266157) (xy 358.452928 -241.308173) (xy 358.476506 -241.354447) (xy 358.492554 -241.40384)
			(xy 358.500679 -241.455135) (xy 358.501188 -241.481102) (xy 358.500705 -241.505735) (xy 358.493387 -241.554453)
			(xy 358.478912 -241.601544) (xy 358.457603 -241.645962) (xy 358.429933 -241.686722) (xy 358.413558 -241.70513)
			(xy 358.407226 -241.712557) (xy 358.400306 -241.730793) (xy 358.40067 -241.750295) (xy 358.408267 -241.768259)
			(xy 358.414828 -241.775488) (xy 358.433342 -241.794881) (xy 358.464667 -241.838393) (xy 358.488851 -241.886243)
			(xy 358.505305 -241.93727) (xy 358.51363 -241.990235) (xy 358.514142 -242.017042) (xy 358.513662 -242.042741)
			(xy 358.506001 -242.093565) (xy 358.490852 -242.142679) (xy 358.468551 -242.188987) (xy 358.439598 -242.231454)
			(xy 358.404638 -242.269131) (xy 358.364454 -242.301177) (xy 358.319942 -242.326876) (xy 358.272097 -242.345653)
			(xy 358.221988 -242.357091) (xy 358.170734 -242.360932) (xy 358.11948 -242.357091) (xy 358.069371 -242.345653)
			(xy 358.021526 -242.326876) (xy 357.977014 -242.301177) (xy 357.93683 -242.269131) (xy 357.90187 -242.231454)
			(xy 357.872917 -242.188987) (xy 357.850616 -242.142679) (xy 357.835467 -242.093565) (xy 357.827806 -242.042741)
			(xy 357.827326 -242.017042) (xy 351.752408 -242.017042) (xy 351.697544 -242.071906) (xy 351.697544 -243.644928)
			(xy 357.827326 -243.644928) (xy 357.827847 -243.618122) (xy 357.836175 -243.565162) (xy 357.852633 -243.514139)
			(xy 357.876821 -243.466294) (xy 357.908151 -243.42279) (xy 357.92664 -243.403374) (xy 357.933174 -243.396126)
			(xy 357.940779 -243.378178) (xy 357.94114 -243.358688) (xy 357.934205 -243.34047) (xy 357.92791 -243.333016)
			(xy 357.911535 -243.314607) (xy 357.883853 -243.273851) (xy 357.862535 -243.229434) (xy 357.848055 -243.182343)
			(xy 357.840735 -243.133622) (xy 357.84028 -243.108988) (xy 357.840789 -243.083021) (xy 357.848914 -243.031726)
			(xy 357.864962 -242.982333) (xy 357.88854 -242.936059) (xy 357.919066 -242.894043) (xy 357.955789 -242.85732)
			(xy 357.997805 -242.826794) (xy 358.044079 -242.803216) (xy 358.093472 -242.787168) (xy 358.144767 -242.779043)
			(xy 358.196701 -242.779043) (xy 358.247996 -242.787168) (xy 358.297389 -242.803216) (xy 358.343663 -242.826794)
			(xy 358.372314 -242.84761) (xy 361.116249 -242.84761) (xy 361.11764 -242.79578) (xy 361.126807 -242.744749)
			(xy 361.14354 -242.695675) (xy 361.167459 -242.649673) (xy 361.198021 -242.60779) (xy 361.21594 -242.58905)
			(xy 361.222412 -242.581812) (xy 361.229927 -242.563932) (xy 361.230286 -242.544539) (xy 361.223438 -242.526392)
			(xy 361.21721 -242.518946) (xy 361.200849 -242.500525) (xy 361.173165 -242.459772) (xy 361.151845 -242.415359)
			(xy 361.137362 -242.36827) (xy 361.130037 -242.319551) (xy 361.12958 -242.294918) (xy 361.130089 -242.268951)
			(xy 361.138214 -242.217656) (xy 361.154262 -242.168263) (xy 361.17784 -242.121989) (xy 361.208366 -242.079973)
			(xy 361.245089 -242.04325) (xy 361.287105 -242.012724) (xy 361.333379 -241.989146) (xy 361.382772 -241.973098)
			(xy 361.434067 -241.964973) (xy 361.486001 -241.964973) (xy 361.537296 -241.973098) (xy 361.586689 -241.989146)
			(xy 361.632963 -242.012724) (xy 361.674979 -242.04325) (xy 361.711702 -242.079973) (xy 361.742228 -242.121989)
			(xy 361.765806 -242.168263) (xy 361.781854 -242.217656) (xy 361.789979 -242.268951) (xy 361.790488 -242.294918)
			(xy 361.790029 -242.319575) (xy 361.782708 -242.368342) (xy 361.76823 -242.415482) (xy 361.746916 -242.459951)
			(xy 361.719238 -242.500765) (xy 361.702858 -242.5192) (xy 361.696577 -242.526609) (xy 361.689651 -242.54474)
			(xy 361.689937 -242.564148) (xy 361.697394 -242.582067) (xy 361.703874 -242.589304) (xy 361.722338 -242.608742)
			(xy 361.753673 -242.65224) (xy 361.777866 -242.700079) (xy 361.794332 -242.751097) (xy 361.80267 -242.804054)
			(xy 361.803188 -242.830858) (xy 361.802782 -242.856782) (xy 361.794995 -242.908042) (xy 361.779591 -242.95755)
			(xy 361.765337 -242.986869) (xy 365.433835 -242.986869) (xy 365.433835 -242.934931) (xy 365.44196 -242.883632)
			(xy 365.45801 -242.834235) (xy 365.48159 -242.787958) (xy 365.51212 -242.745939) (xy 365.548846 -242.709213)
			(xy 365.590866 -242.678685) (xy 365.637144 -242.655106) (xy 365.686541 -242.639058) (xy 365.737841 -242.630934)
			(xy 365.76381 -242.630452) (xy 365.789671 -242.630958) (xy 365.840762 -242.639005) (xy 365.889975 -242.654916)
			(xy 365.936106 -242.678303) (xy 365.978029 -242.708593) (xy 365.996728 -242.726464) (xy 366.006443 -242.735509)
			(xy 366.029452 -242.748721) (xy 366.055089 -242.755558) (xy 366.081623 -242.755558) (xy 366.10726 -242.748721)
			(xy 366.130269 -242.735509) (xy 366.139984 -242.726464) (xy 366.158664 -242.708574) (xy 366.200598 -242.678296)
			(xy 366.246735 -242.654916) (xy 366.295949 -242.639006) (xy 366.347041 -242.630952) (xy 366.372902 -242.630452)
			(xy 366.39887 -242.630949) (xy 366.450165 -242.639074) (xy 366.499559 -242.655123) (xy 366.545833 -242.678702)
			(xy 366.587849 -242.709228) (xy 366.624573 -242.745952) (xy 366.6551 -242.787969) (xy 366.678678 -242.834243)
			(xy 366.694726 -242.883637) (xy 366.702851 -242.934932) (xy 366.702851 -242.986868) (xy 366.694726 -243.038163)
			(xy 366.678678 -243.087557) (xy 366.6551 -243.133831) (xy 366.624573 -243.175848) (xy 366.587849 -243.212572)
			(xy 366.545833 -243.243098) (xy 366.499559 -243.266677) (xy 366.450165 -243.282726) (xy 366.39887 -243.290851)
			(xy 366.372902 -243.29136) (xy 366.347042 -243.290843) (xy 366.295951 -243.282798) (xy 366.246739 -243.26689)
			(xy 366.200607 -243.243506) (xy 366.158683 -243.213218) (xy 366.139984 -243.195348) (xy 366.130269 -243.186303)
			(xy 366.10726 -243.173091) (xy 366.081623 -243.166254) (xy 366.055089 -243.166254) (xy 366.029452 -243.173091)
			(xy 366.006443 -243.186303) (xy 365.996728 -243.195348) (xy 365.978028 -243.213217) (xy 365.936101 -243.243502)
			(xy 365.88997 -243.266887) (xy 365.840759 -243.282802) (xy 365.78967 -243.290859) (xy 365.76381 -243.29136)
			(xy 365.737841 -243.290866) (xy 365.686541 -243.282742) (xy 365.637144 -243.266694) (xy 365.590866 -243.243115)
			(xy 365.548846 -243.212587) (xy 365.51212 -243.175861) (xy 365.48159 -243.133842) (xy 365.45801 -243.087565)
			(xy 365.44196 -243.038168) (xy 365.433835 -242.986869) (xy 361.765337 -242.986869) (xy 361.756921 -243.004179)
			(xy 361.727499 -243.046871) (xy 361.691995 -243.084656) (xy 361.651214 -243.116675) (xy 361.606084 -243.1422)
			(xy 361.55763 -243.160651) (xy 361.506953 -243.17161) (xy 361.455205 -243.174827) (xy 361.403561 -243.170228)
			(xy 361.353195 -243.15792) (xy 361.305251 -243.13818) (xy 361.260819 -243.111459) (xy 361.220909 -243.078362)
			(xy 361.186426 -243.039642) (xy 361.158156 -242.996179) (xy 361.136739 -242.948961) (xy 361.122664 -242.89906)
			(xy 361.116249 -242.84761) (xy 358.372314 -242.84761) (xy 358.385679 -242.85732) (xy 358.422402 -242.894043)
			(xy 358.452928 -242.936059) (xy 358.476506 -242.982333) (xy 358.492554 -243.031726) (xy 358.500679 -243.083021)
			(xy 358.501188 -243.108988) (xy 358.500697 -243.13362) (xy 358.49338 -243.182338) (xy 358.478908 -243.229429)
			(xy 358.457601 -243.273848) (xy 358.429932 -243.314608) (xy 358.413558 -243.333016) (xy 358.40724 -243.340453)
			(xy 358.400317 -243.358685) (xy 358.400678 -243.378183) (xy 358.40827 -243.396145) (xy 358.414828 -243.403374)
			(xy 358.433335 -243.422773) (xy 358.464662 -243.466283) (xy 358.488846 -243.514132) (xy 358.505302 -243.565158)
			(xy 358.513629 -243.618121) (xy 358.514142 -243.644928) (xy 358.513662 -243.670627) (xy 358.506001 -243.721451)
			(xy 358.490852 -243.770565) (xy 358.468551 -243.816873) (xy 358.439598 -243.85934) (xy 358.404638 -243.897017)
			(xy 358.364454 -243.929063) (xy 358.319942 -243.954762) (xy 358.272097 -243.973539) (xy 358.221988 -243.984977)
			(xy 358.170734 -243.988818) (xy 358.11948 -243.984977) (xy 358.069371 -243.973539) (xy 358.021526 -243.954762)
			(xy 357.977014 -243.929063) (xy 357.93683 -243.897017) (xy 357.90187 -243.85934) (xy 357.872917 -243.816873)
			(xy 357.850616 -243.770565) (xy 357.835467 -243.721451) (xy 357.827806 -243.670627) (xy 357.827326 -243.644928)
			(xy 351.697544 -243.644928) (xy 351.697544 -243.900706) (xy 351.794064 -243.997226) (xy 356.579424 -243.997226)
			(xy 356.764844 -244.182646) (xy 356.764844 -245.27256) (xy 357.827326 -245.27256) (xy 357.827805 -245.245753)
			(xy 357.836143 -245.19279) (xy 357.852611 -245.141767) (xy 357.876808 -245.093923) (xy 357.908147 -245.05042)
			(xy 357.92664 -245.031006) (xy 357.93324 -245.023811) (xy 357.940835 -245.005839) (xy 357.941178 -244.986331)
			(xy 357.934218 -244.968103) (xy 357.92791 -244.960648) (xy 357.91155 -244.942226) (xy 357.883866 -244.901474)
			(xy 357.862545 -244.85706) (xy 357.848062 -244.809971) (xy 357.840738 -244.761253) (xy 357.84028 -244.73662)
			(xy 357.840789 -244.710653) (xy 357.848914 -244.659358) (xy 357.864962 -244.609965) (xy 357.88854 -244.563691)
			(xy 357.919066 -244.521675) (xy 357.955789 -244.484952) (xy 357.997805 -244.454426) (xy 358.044079 -244.430848)
			(xy 358.093472 -244.4148) (xy 358.144767 -244.406675) (xy 358.196701 -244.406675) (xy 358.247996 -244.4148)
			(xy 358.297389 -244.430848) (xy 358.343663 -244.454426) (xy 358.372583 -244.475437) (xy 361.116311 -244.475437)
			(xy 361.117697 -244.423622) (xy 361.126855 -244.372604) (xy 361.143577 -244.323542) (xy 361.167482 -244.27755)
			(xy 361.198029 -244.235673) (xy 361.21594 -244.216936) (xy 361.222425 -244.209709) (xy 361.229938 -244.191823)
			(xy 361.230293 -244.172427) (xy 361.22344 -244.154278) (xy 361.21721 -244.146832) (xy 361.200843 -244.128416)
			(xy 361.17316 -244.087663) (xy 361.15184 -244.043247) (xy 361.137359 -243.996157) (xy 361.130036 -243.947437)
			(xy 361.12958 -243.922804) (xy 361.130089 -243.896837) (xy 361.138214 -243.845542) (xy 361.154262 -243.796149)
			(xy 361.17784 -243.749875) (xy 361.208366 -243.707859) (xy 361.245089 -243.671136) (xy 361.287105 -243.64061)
			(xy 361.333379 -243.617032) (xy 361.382772 -243.600984) (xy 361.434067 -243.592859) (xy 361.486001 -243.592859)
			(xy 361.537296 -243.600984) (xy 361.586689 -243.617032) (xy 361.632963 -243.64061) (xy 361.674979 -243.671136)
			(xy 361.711702 -243.707859) (xy 361.742228 -243.749875) (xy 361.765806 -243.796149) (xy 361.781854 -243.845542)
			(xy 361.789979 -243.896837) (xy 361.790488 -243.922804) (xy 361.790021 -243.94746) (xy 361.782701 -243.996227)
			(xy 361.768225 -244.043367) (xy 361.746913 -244.087837) (xy 361.719237 -244.128651) (xy 361.702858 -244.147086)
			(xy 361.696591 -244.154505) (xy 361.689663 -244.172632) (xy 361.689945 -244.192036) (xy 361.697397 -244.209953)
			(xy 361.703874 -244.21719) (xy 361.722379 -244.236591) (xy 361.753708 -244.280099) (xy 361.777894 -244.327948)
			(xy 361.79435 -244.378974) (xy 361.802676 -244.431937) (xy 361.803188 -244.458744) (xy 361.802715 -244.484661)
			(xy 361.794919 -244.535904) (xy 361.779508 -244.585394) (xy 361.756835 -244.632006) (xy 361.727414 -244.67468)
			(xy 361.691914 -244.712448) (xy 361.65114 -244.744452) (xy 361.606019 -244.769963) (xy 361.557577 -244.788404)
			(xy 361.506913 -244.799354) (xy 361.455179 -244.802566) (xy 361.40355 -244.797965) (xy 361.353199 -244.785657)
			(xy 361.30527 -244.765922) (xy 361.260851 -244.739207) (xy 361.220952 -244.70612) (xy 361.186479 -244.667411)
			(xy 361.158215 -244.623962) (xy 361.136803 -244.576758) (xy 361.122728 -244.526872) (xy 361.116311 -244.475437)
			(xy 358.372583 -244.475437) (xy 358.385679 -244.484952) (xy 358.422402 -244.521675) (xy 358.452928 -244.563691)
			(xy 358.476506 -244.609965) (xy 358.492554 -244.659358) (xy 358.500679 -244.710653) (xy 358.501188 -244.73662)
			(xy 358.500716 -244.761253) (xy 358.493395 -244.809972) (xy 358.478918 -244.857063) (xy 358.457607 -244.901481)
			(xy 358.429934 -244.942241) (xy 358.413558 -244.960648) (xy 358.407308 -244.968136) (xy 358.400374 -244.986344)
			(xy 358.400715 -245.005824) (xy 358.408283 -245.023778) (xy 358.414828 -245.031006) (xy 358.433303 -245.050435)
			(xy 358.464633 -245.093937) (xy 358.488824 -245.141778) (xy 358.505288 -245.192797) (xy 358.513624 -245.245755)
			(xy 358.514142 -245.27256) (xy 358.513662 -245.298259) (xy 358.506001 -245.349083) (xy 358.490852 -245.398197)
			(xy 358.468551 -245.444505) (xy 358.439598 -245.486972) (xy 358.404638 -245.524649) (xy 358.364454 -245.556695)
			(xy 358.319942 -245.582394) (xy 358.272097 -245.601171) (xy 358.221988 -245.612609) (xy 358.170734 -245.61645)
			(xy 358.11948 -245.612609) (xy 358.069371 -245.601171) (xy 358.021526 -245.582394) (xy 357.977014 -245.556695)
			(xy 357.93683 -245.524649) (xy 357.90187 -245.486972) (xy 357.872917 -245.444505) (xy 357.850616 -245.398197)
			(xy 357.835467 -245.349083) (xy 357.827806 -245.298259) (xy 357.827326 -245.27256) (xy 356.764844 -245.27256)
			(xy 356.764844 -245.523766) (xy 356.587044 -245.701566) (xy 353.095052 -245.701566) (xy 352.965512 -245.831106)
			(xy 352.965512 -246.254778) (xy 352.965963 -246.268239) (xy 352.973074 -246.294206) (xy 352.986728 -246.317411)
			(xy 353.005974 -246.336238) (xy 353.029474 -246.349377) (xy 353.055592 -246.355915) (xy 353.08251 -246.355396)
			(xy 353.09556 -246.35206) (xy 353.1183 -246.345871) (xy 353.16496 -246.339245) (xy 353.188524 -246.338852)
			(xy 353.214277 -246.339346) (xy 353.265159 -246.347336) (xy 353.314187 -246.363119) (xy 353.360174 -246.386314)
			(xy 353.402009 -246.416359) (xy 353.42068 -246.434102) (xy 353.43037 -246.443095) (xy 353.453302 -246.456227)
			(xy 353.478841 -246.463022) (xy 353.505267 -246.463022) (xy 353.530806 -246.456227) (xy 353.553738 -246.443095)
			(xy 353.563428 -246.434102) (xy 353.582103 -246.416361) (xy 353.62393 -246.386304) (xy 353.669916 -246.363104)
			(xy 353.718946 -246.347322) (xy 353.76983 -246.339341) (xy 353.795584 -246.338852) (xy 353.821554 -246.339334)
			(xy 353.872854 -246.347456) (xy 353.922252 -246.363505) (xy 353.968531 -246.387083) (xy 354.010551 -246.417611)
			(xy 354.047279 -246.454337) (xy 354.077809 -246.496356) (xy 354.101389 -246.542634) (xy 354.11744 -246.592031)
			(xy 354.125565 -246.64333) (xy 354.125565 -246.69527) (xy 354.11744 -246.746569) (xy 354.101389 -246.795966)
			(xy 354.077809 -246.842244) (xy 354.047279 -246.884263) (xy 354.031095 -246.900446) (xy 357.827326 -246.900446)
			(xy 357.827859 -246.873641) (xy 357.836184 -246.820681) (xy 357.852639 -246.769658) (xy 357.876824 -246.721813)
			(xy 357.908152 -246.678308) (xy 357.92664 -246.658892) (xy 357.933254 -246.651708) (xy 357.940847 -246.633731)
			(xy 357.941185 -246.614219) (xy 357.93422 -246.595989) (xy 357.92791 -246.588534) (xy 357.911544 -246.570117)
			(xy 357.88386 -246.529364) (xy 357.862541 -246.484949) (xy 357.848059 -246.437859) (xy 357.840737 -246.389139)
			(xy 357.84028 -246.364506) (xy 357.840789 -246.338539) (xy 357.848914 -246.287244) (xy 357.864962 -246.237851)
			(xy 357.88854 -246.191577) (xy 357.919066 -246.149561) (xy 357.955789 -246.112838) (xy 357.997805 -246.082312)
			(xy 358.044079 -246.058734) (xy 358.093472 -246.042686) (xy 358.144767 -246.034561) (xy 358.196701 -246.034561)
			(xy 358.247996 -246.042686) (xy 358.297389 -246.058734) (xy 358.343663 -246.082312) (xy 358.372595 -246.103332)
			(xy 361.116301 -246.103332) (xy 361.117688 -246.051515) (xy 361.126847 -246.000495) (xy 361.143571 -245.951431)
			(xy 361.167479 -245.905437) (xy 361.198028 -245.86356) (xy 361.21594 -245.844822) (xy 361.222439 -245.837606)
			(xy 361.229949 -245.819715) (xy 361.230301 -245.800315) (xy 361.223443 -245.782164) (xy 361.21721 -245.774718)
			(xy 361.200836 -245.756308) (xy 361.173154 -245.715553) (xy 361.151836 -245.671136) (xy 361.137356 -245.624044)
			(xy 361.130035 -245.575324) (xy 361.12958 -245.55069) (xy 361.130089 -245.524723) (xy 361.138214 -245.473428)
			(xy 361.154262 -245.424035) (xy 361.17784 -245.377761) (xy 361.208366 -245.335745) (xy 361.245089 -245.299022)
			(xy 361.287105 -245.268496) (xy 361.333379 -245.244918) (xy 361.382772 -245.22887) (xy 361.434067 -245.220745)
			(xy 361.486001 -245.220745) (xy 361.537296 -245.22887) (xy 361.586689 -245.244918) (xy 361.632963 -245.268496)
			(xy 361.674979 -245.299022) (xy 361.711702 -245.335745) (xy 361.742228 -245.377761) (xy 361.765806 -245.424035)
			(xy 361.781854 -245.473428) (xy 361.789979 -245.524723) (xy 361.790488 -245.55069) (xy 361.790012 -245.575346)
			(xy 361.782695 -245.624112) (xy 361.768221 -245.671252) (xy 361.746911 -245.715722) (xy 361.719236 -245.756536)
			(xy 361.702858 -245.774972) (xy 361.696605 -245.782402) (xy 361.689674 -245.800524) (xy 361.689952 -245.819924)
			(xy 361.697399 -245.837839) (xy 361.703874 -245.845076) (xy 361.722373 -245.864483) (xy 361.753702 -245.90799)
			(xy 361.77789 -245.955837) (xy 361.794347 -246.006861) (xy 361.802675 -246.059823) (xy 361.803188 -246.08663)
			(xy 361.802726 -246.112548) (xy 361.794931 -246.163794) (xy 361.779522 -246.213287) (xy 361.756849 -246.259902)
			(xy 361.727428 -246.302579) (xy 361.691927 -246.34035) (xy 361.651152 -246.372355) (xy 361.60603 -246.397869)
			(xy 361.557585 -246.416312) (xy 361.50692 -246.427263) (xy 361.455183 -246.430476) (xy 361.403552 -246.425876)
			(xy 361.353198 -246.413568) (xy 361.305267 -246.393831) (xy 361.260846 -246.367115) (xy 361.220945 -246.334027)
			(xy 361.18647 -246.295316) (xy 361.158205 -246.251865) (xy 361.136792 -246.204658) (xy 361.122717 -246.15477)
			(xy 361.116301 -246.103332) (xy 358.372595 -246.103332) (xy 358.385679 -246.112838) (xy 358.422402 -246.149561)
			(xy 358.452928 -246.191577) (xy 358.476506 -246.237851) (xy 358.492554 -246.287244) (xy 358.500679 -246.338539)
			(xy 358.501188 -246.364506) (xy 358.500708 -246.389139) (xy 358.493389 -246.437857) (xy 358.478914 -246.484948)
			(xy 358.457604 -246.529366) (xy 358.429933 -246.570126) (xy 358.413558 -246.588534) (xy 358.407222 -246.595958)
			(xy 358.400303 -246.614195) (xy 358.400668 -246.633698) (xy 358.408266 -246.651663) (xy 358.414828 -246.658892)
			(xy 358.433344 -246.678284) (xy 358.464669 -246.721795) (xy 358.488852 -246.769646) (xy 358.505306 -246.820674)
			(xy 358.51363 -246.873639) (xy 358.514142 -246.900446) (xy 358.513662 -246.926145) (xy 358.506001 -246.976969)
			(xy 358.490852 -247.026083) (xy 358.468551 -247.072391) (xy 358.439598 -247.114858) (xy 358.404638 -247.152535)
			(xy 358.364454 -247.184581) (xy 358.319942 -247.21028) (xy 358.272097 -247.229057) (xy 358.221988 -247.240495)
			(xy 358.170734 -247.244336) (xy 358.11948 -247.240495) (xy 358.069371 -247.229057) (xy 358.021526 -247.21028)
			(xy 357.977014 -247.184581) (xy 357.93683 -247.152535) (xy 357.90187 -247.114858) (xy 357.872917 -247.072391)
			(xy 357.850616 -247.026083) (xy 357.835467 -246.976969) (xy 357.827806 -246.926145) (xy 357.827326 -246.900446)
			(xy 354.031095 -246.900446) (xy 354.010551 -246.920989) (xy 353.968531 -246.951517) (xy 353.922252 -246.975095)
			(xy 353.872854 -246.991144) (xy 353.821554 -246.999266) (xy 353.795584 -246.99976) (xy 353.769831 -246.999267)
			(xy 353.718948 -246.991278) (xy 353.669919 -246.975496) (xy 353.62393 -246.952303) (xy 353.582094 -246.922259)
			(xy 353.563428 -246.90451) (xy 353.553738 -246.895517) (xy 353.530806 -246.882385) (xy 353.505267 -246.87559)
			(xy 353.478841 -246.87559) (xy 353.453302 -246.882385) (xy 353.43037 -246.895517) (xy 353.42068 -246.90451)
			(xy 353.402008 -246.922256) (xy 353.360183 -246.952321) (xy 353.314197 -246.975529) (xy 353.265166 -246.991317)
			(xy 353.214279 -246.999301) (xy 353.188524 -246.99976) (xy 353.164959 -246.999378) (xy 353.1183 -246.992746)
			(xy 353.09556 -246.986552) (xy 353.082516 -246.983178) (xy 353.055589 -246.982659) (xy 353.029462 -246.989199)
			(xy 353.005955 -247.002344) (xy 352.986703 -247.021178) (xy 352.973046 -247.044392) (xy 352.965935 -247.070369)
			(xy 352.965512 -247.083834) (xy 352.965512 -247.596914) (xy 353.048824 -247.680226) (xy 356.554024 -247.680226)
			(xy 356.744524 -247.870726) (xy 356.744524 -248.528078) (xy 357.827326 -248.528078) (xy 357.827816 -248.501271)
			(xy 357.836152 -248.448309) (xy 357.852617 -248.397286) (xy 357.876812 -248.349441) (xy 357.908148 -248.305939)
			(xy 357.92664 -248.286524) (xy 357.933223 -248.279315) (xy 357.940821 -248.261349) (xy 357.941168 -248.241846)
			(xy 357.934214 -248.223621) (xy 357.92791 -248.216166) (xy 357.911559 -248.197736) (xy 357.883873 -248.156987)
			(xy 357.862551 -248.112575) (xy 357.848066 -248.065488) (xy 357.840739 -248.01677) (xy 357.84028 -247.992138)
			(xy 357.840789 -247.966171) (xy 357.848914 -247.914876) (xy 357.864962 -247.865483) (xy 357.88854 -247.819209)
			(xy 357.919066 -247.777193) (xy 357.955789 -247.74047) (xy 357.997805 -247.709944) (xy 358.044079 -247.686366)
			(xy 358.093472 -247.670318) (xy 358.144767 -247.662193) (xy 358.196701 -247.662193) (xy 358.247996 -247.670318)
			(xy 358.297389 -247.686366) (xy 358.343663 -247.709944) (xy 358.37266 -247.731011) (xy 361.116252 -247.731011)
			(xy 361.117643 -247.679182) (xy 361.126809 -247.628151) (xy 361.143541 -247.579078) (xy 361.16746 -247.533077)
			(xy 361.198021 -247.491194) (xy 361.21594 -247.472454) (xy 361.222408 -247.465213) (xy 361.229923 -247.447334)
			(xy 361.230284 -247.427942) (xy 361.223437 -247.409796) (xy 361.21721 -247.40235) (xy 361.200851 -247.383927)
			(xy 361.173167 -247.343175) (xy 361.151846 -247.298762) (xy 361.137362 -247.251673) (xy 361.130038 -247.202955)
			(xy 361.12958 -247.178322) (xy 361.130089 -247.152355) (xy 361.138214 -247.10106) (xy 361.154262 -247.051667)
			(xy 361.17784 -247.005393) (xy 361.208366 -246.963377) (xy 361.245089 -246.926654) (xy 361.287105 -246.896128)
			(xy 361.333379 -246.87255) (xy 361.382772 -246.856502) (xy 361.434067 -246.848377) (xy 361.486001 -246.848377)
			(xy 361.537296 -246.856502) (xy 361.586689 -246.87255) (xy 361.632963 -246.896128) (xy 361.674979 -246.926654)
			(xy 361.711702 -246.963377) (xy 361.742228 -247.005393) (xy 361.765806 -247.051667) (xy 361.781854 -247.10106)
			(xy 361.789979 -247.152355) (xy 361.790488 -247.178322) (xy 361.790032 -247.202979) (xy 361.782709 -247.251746)
			(xy 361.768231 -247.298886) (xy 361.746916 -247.343355) (xy 361.719238 -247.384169) (xy 361.702858 -247.402604)
			(xy 361.696573 -247.41001) (xy 361.689648 -247.428143) (xy 361.689935 -247.447551) (xy 361.697394 -247.465471)
			(xy 361.703874 -247.472708) (xy 361.72234 -247.492145) (xy 361.753674 -247.535643) (xy 361.777868 -247.583483)
			(xy 361.794333 -247.634501) (xy 361.80267 -247.687457) (xy 361.803188 -247.714262) (xy 361.802779 -247.740186)
			(xy 361.794991 -247.791445) (xy 361.779587 -247.840952) (xy 361.756917 -247.88758) (xy 361.727495 -247.930272)
			(xy 361.691991 -247.968056) (xy 361.651211 -248.000074) (xy 361.606081 -248.025598) (xy 361.557628 -248.044049)
			(xy 361.506952 -248.055007) (xy 361.455204 -248.058224) (xy 361.40356 -248.053625) (xy 361.353195 -248.041317)
			(xy 361.305252 -248.021578) (xy 361.260821 -247.994856) (xy 361.220911 -247.96176) (xy 361.186429 -247.923041)
			(xy 361.158158 -247.879579) (xy 361.136742 -247.832361) (xy 361.122667 -247.78246) (xy 361.116252 -247.731011)
			(xy 358.37266 -247.731011) (xy 358.385679 -247.74047) (xy 358.422402 -247.777193) (xy 358.452928 -247.819209)
			(xy 358.476506 -247.865483) (xy 358.492554 -247.914876) (xy 358.500679 -247.966171) (xy 358.501188 -247.992138)
			(xy 358.500727 -248.016771) (xy 358.493403 -248.065491) (xy 358.478924 -248.112582) (xy 358.45761 -248.157)
			(xy 358.429935 -248.197759) (xy 358.413558 -248.216166) (xy 358.40729 -248.223641) (xy 358.400359 -248.241855)
			(xy 358.400705 -248.26134) (xy 358.408279 -248.279296) (xy 358.414828 -248.286524) (xy 358.433311 -248.305945)
			(xy 358.464641 -248.349449) (xy 358.48883 -248.397292) (xy 358.505292 -248.448313) (xy 358.513625 -248.501273)
			(xy 358.514142 -248.528078) (xy 358.513662 -248.553777) (xy 358.506001 -248.604601) (xy 358.490852 -248.653715)
			(xy 358.468551 -248.700023) (xy 358.439598 -248.74249) (xy 358.404638 -248.780167) (xy 358.364454 -248.812213)
			(xy 358.319942 -248.837912) (xy 358.272097 -248.856689) (xy 358.221988 -248.868127) (xy 358.170734 -248.871968)
			(xy 358.11948 -248.868127) (xy 358.069371 -248.856689) (xy 358.021526 -248.837912) (xy 357.977014 -248.812213)
			(xy 357.93683 -248.780167) (xy 357.90187 -248.74249) (xy 357.872917 -248.700023) (xy 357.850616 -248.653715)
			(xy 357.835467 -248.604601) (xy 357.827806 -248.553777) (xy 357.827326 -248.528078) (xy 356.744524 -248.528078)
			(xy 356.744524 -249.216926) (xy 356.607364 -249.354086) (xy 351.809304 -249.354086) (xy 351.700084 -249.463306)
			(xy 351.700084 -250.363072) (xy 353.066795 -250.363072) (xy 353.066795 -250.311128) (xy 353.074921 -250.259823)
			(xy 353.090973 -250.210421) (xy 353.114555 -250.164138) (xy 353.145087 -250.122115) (xy 353.181818 -250.085385)
			(xy 353.223842 -250.054853) (xy 353.270125 -250.031271) (xy 353.319527 -250.01522) (xy 353.370832 -250.007095)
			(xy 353.396804 -250.006612) (xy 353.422558 -250.007091) (xy 353.473444 -250.015072) (xy 353.522474 -250.030855)
			(xy 353.56846 -250.054059) (xy 353.610287 -250.084119) (xy 353.62896 -250.101862) (xy 353.63865 -250.110855)
			(xy 353.661582 -250.123987) (xy 353.687121 -250.130782) (xy 353.713547 -250.130782) (xy 353.739086 -250.123987)
			(xy 353.762018 -250.110855) (xy 353.771708 -250.101862) (xy 353.790394 -250.084135) (xy 353.832224 -250.054086)
			(xy 353.878207 -250.030887) (xy 353.927232 -250.0151) (xy 353.978112 -250.007107) (xy 354.003864 -250.006612)
			(xy 354.029832 -250.00716) (xy 354.081131 -250.01528) (xy 354.130527 -250.031325) (xy 354.176805 -250.0549)
			(xy 354.218825 -250.085425) (xy 354.255552 -250.122148) (xy 354.280123 -250.155964) (xy 357.827326 -250.155964)
			(xy 357.827807 -250.129157) (xy 357.836145 -250.076194) (xy 357.852612 -250.025171) (xy 357.876809 -249.977327)
			(xy 357.908147 -249.933824) (xy 357.92664 -249.91441) (xy 357.933236 -249.907212) (xy 357.940832 -249.889241)
			(xy 357.941176 -249.869734) (xy 357.934217 -249.851507) (xy 357.92791 -249.844052) (xy 357.911552 -249.825628)
			(xy 357.883868 -249.784877) (xy 357.862547 -249.740464) (xy 357.848063 -249.693375) (xy 357.840738 -249.644657)
			(xy 357.84028 -249.620024) (xy 357.840789 -249.594057) (xy 357.848914 -249.542762) (xy 357.864962 -249.493369)
			(xy 357.88854 -249.447095) (xy 357.919066 -249.405079) (xy 357.955789 -249.368356) (xy 357.997805 -249.33783)
			(xy 358.044079 -249.314252) (xy 358.093472 -249.298204) (xy 358.144767 -249.290079) (xy 358.196701 -249.290079)
			(xy 358.247996 -249.298204) (xy 358.297389 -249.314252) (xy 358.343663 -249.33783) (xy 358.372578 -249.358838)
			(xy 361.116314 -249.358838) (xy 361.1177 -249.307024) (xy 361.126857 -249.256006) (xy 361.143578 -249.206945)
			(xy 361.167484 -249.160953) (xy 361.198029 -249.119077) (xy 361.21594 -249.10034) (xy 361.222421 -249.09311)
			(xy 361.229935 -249.075226) (xy 361.230291 -249.055831) (xy 361.22344 -249.037682) (xy 361.21721 -249.030236)
			(xy 361.200845 -249.011819) (xy 361.173161 -248.971065) (xy 361.151842 -248.926651) (xy 361.13736 -248.879561)
			(xy 361.130037 -248.830841) (xy 361.12958 -248.806208) (xy 361.130089 -248.780241) (xy 361.138214 -248.728946)
			(xy 361.154262 -248.679553) (xy 361.17784 -248.633279) (xy 361.208366 -248.591263) (xy 361.245089 -248.55454)
			(xy 361.287105 -248.524014) (xy 361.333379 -248.500436) (xy 361.382772 -248.484388) (xy 361.434067 -248.476263)
			(xy 361.486001 -248.476263) (xy 361.537296 -248.484388) (xy 361.586689 -248.500436) (xy 361.632963 -248.524014)
			(xy 361.674979 -248.55454) (xy 361.711702 -248.591263) (xy 361.742228 -248.633279) (xy 361.765806 -248.679553)
			(xy 361.781854 -248.728946) (xy 361.789979 -248.780241) (xy 361.790488 -248.806208) (xy 361.790023 -248.830864)
			(xy 361.782703 -248.879631) (xy 361.768226 -248.926771) (xy 361.746914 -248.971241) (xy 361.719237 -249.012055)
			(xy 361.702858 -249.03049) (xy 361.696587 -249.037907) (xy 361.689659 -249.056034) (xy 361.689942 -249.075439)
			(xy 361.697396 -249.093357) (xy 361.703874 -249.100594) (xy 361.722333 -249.120037) (xy 361.753668 -249.163534)
			(xy 361.777863 -249.211372) (xy 361.79433 -249.262388) (xy 361.802669 -249.315344) (xy 361.803188 -249.342148)
			(xy 361.802712 -249.368064) (xy 361.794915 -249.419307) (xy 361.779505 -249.468796) (xy 361.756831 -249.515407)
			(xy 361.72741 -249.558081) (xy 361.69191 -249.595848) (xy 361.651136 -249.627851) (xy 361.606016 -249.653362)
			(xy 361.557574 -249.671802) (xy 361.506911 -249.682752) (xy 361.455178 -249.685963) (xy 361.40355 -249.681362)
			(xy 361.353199 -249.669055) (xy 361.305271 -249.649319) (xy 361.260852 -249.622605) (xy 361.220954 -249.589518)
			(xy 361.186481 -249.55081) (xy 361.158218 -249.507361) (xy 361.136806 -249.460158) (xy 361.122731 -249.410272)
			(xy 361.116314 -249.358838) (xy 358.372578 -249.358838) (xy 358.385679 -249.368356) (xy 358.422402 -249.405079)
			(xy 358.452928 -249.447095) (xy 358.476506 -249.493369) (xy 358.492554 -249.542762) (xy 358.500679 -249.594057)
			(xy 358.501188 -249.620024) (xy 358.500719 -249.644657) (xy 358.493397 -249.693376) (xy 358.478919 -249.740467)
			(xy 358.457607 -249.784885) (xy 358.429934 -249.825645) (xy 358.413558 -249.844052) (xy 358.407304 -249.851537)
			(xy 358.40037 -249.869746) (xy 358.400713 -249.889228) (xy 358.408282 -249.907182) (xy 358.414828 -249.91441)
			(xy 358.433304 -249.933837) (xy 358.464635 -249.977339) (xy 358.488826 -250.025181) (xy 358.505289 -250.076201)
			(xy 358.513624 -250.129159) (xy 358.514142 -250.155964) (xy 358.513662 -250.181663) (xy 358.506001 -250.232487)
			(xy 358.490852 -250.281601) (xy 358.468551 -250.327909) (xy 358.444578 -250.363072) (xy 365.433795 -250.363072)
			(xy 365.433795 -250.311128) (xy 365.441921 -250.259822) (xy 365.457973 -250.21042) (xy 365.481556 -250.164137)
			(xy 365.512089 -250.122113) (xy 365.54882 -250.085383) (xy 365.590845 -250.054851) (xy 365.637129 -250.031269)
			(xy 365.686532 -250.015219) (xy 365.737838 -250.007094) (xy 365.76381 -250.006612) (xy 365.789672 -250.007101)
			(xy 365.840764 -250.015149) (xy 365.889978 -250.031063) (xy 365.936109 -250.054454) (xy 365.978031 -250.08475)
			(xy 365.996728 -250.102624) (xy 366.006443 -250.111669) (xy 366.029452 -250.124881) (xy 366.055089 -250.131718)
			(xy 366.081623 -250.131718) (xy 366.10726 -250.124881) (xy 366.130269 -250.111669) (xy 366.139984 -250.102624)
			(xy 366.158674 -250.084744) (xy 366.200604 -250.054462) (xy 366.246738 -250.03108) (xy 366.295951 -250.015167)
			(xy 366.347041 -250.007112) (xy 366.372902 -250.006612) (xy 366.398866 -250.007189) (xy 366.450156 -250.015313)
			(xy 366.499543 -250.03136) (xy 366.545812 -250.054936) (xy 366.587823 -250.085459) (xy 366.624542 -250.122178)
			(xy 366.655065 -250.16419) (xy 366.678641 -250.210459) (xy 366.694687 -250.259846) (xy 366.702811 -250.311136)
			(xy 366.702811 -250.363064) (xy 366.694687 -250.414354) (xy 366.678641 -250.463741) (xy 366.655065 -250.51001)
			(xy 366.624542 -250.552022) (xy 366.587823 -250.588741) (xy 366.545812 -250.619264) (xy 366.499543 -250.64284)
			(xy 366.450156 -250.658887) (xy 366.398866 -250.667011) (xy 366.372902 -250.66752) (xy 366.347041 -250.667014)
			(xy 366.29595 -250.658969) (xy 366.246737 -250.643058) (xy 366.200605 -250.619671) (xy 366.158682 -250.58938)
			(xy 366.139984 -250.571508) (xy 366.130269 -250.562463) (xy 366.10726 -250.549251) (xy 366.081623 -250.542414)
			(xy 366.055089 -250.542414) (xy 366.029452 -250.549251) (xy 366.006443 -250.562463) (xy 365.996728 -250.571508)
			(xy 365.978038 -250.589387) (xy 365.936107 -250.619668) (xy 365.889973 -250.64305) (xy 365.840761 -250.658963)
			(xy 365.789671 -250.667019) (xy 365.76381 -250.66752) (xy 365.737838 -250.667106) (xy 365.686532 -250.658981)
			(xy 365.637129 -250.642931) (xy 365.590845 -250.619349) (xy 365.54882 -250.588817) (xy 365.512089 -250.552087)
			(xy 365.481556 -250.510063) (xy 365.457973 -250.46378) (xy 365.441921 -250.414378) (xy 365.433795 -250.363072)
			(xy 358.444578 -250.363072) (xy 358.439598 -250.370376) (xy 358.404638 -250.408053) (xy 358.364454 -250.440099)
			(xy 358.319942 -250.465798) (xy 358.272097 -250.484575) (xy 358.221988 -250.496013) (xy 358.170734 -250.499854)
			(xy 358.11948 -250.496013) (xy 358.069371 -250.484575) (xy 358.021526 -250.465798) (xy 357.977014 -250.440099)
			(xy 357.93683 -250.408053) (xy 357.90187 -250.370376) (xy 357.872917 -250.327909) (xy 357.850616 -250.281601)
			(xy 357.835467 -250.232487) (xy 357.827806 -250.181663) (xy 357.827326 -250.155964) (xy 354.280123 -250.155964)
			(xy 354.286081 -250.164164) (xy 354.309661 -250.21044) (xy 354.325712 -250.259834) (xy 354.333837 -250.311132)
			(xy 354.333837 -250.363068) (xy 354.325712 -250.414366) (xy 354.309661 -250.46376) (xy 354.286081 -250.510036)
			(xy 354.255552 -250.552052) (xy 354.218825 -250.588775) (xy 354.176805 -250.6193) (xy 354.130527 -250.642875)
			(xy 354.081131 -250.65892) (xy 354.029832 -250.66704) (xy 354.003864 -250.66752) (xy 353.97811 -250.667052)
			(xy 353.927223 -250.659067) (xy 353.878193 -250.64328) (xy 353.832208 -250.620075) (xy 353.790381 -250.590014)
			(xy 353.771708 -250.57227) (xy 353.762018 -250.563277) (xy 353.739086 -250.550145) (xy 353.713547 -250.54335)
			(xy 353.687121 -250.54335) (xy 353.661582 -250.550145) (xy 353.63865 -250.563277) (xy 353.62896 -250.57227)
			(xy 353.610293 -250.590018) (xy 353.568458 -250.620063) (xy 353.522469 -250.643258) (xy 353.47344 -250.65904)
			(xy 353.422557 -250.667028) (xy 353.396804 -250.66752) (xy 353.370832 -250.667105) (xy 353.319527 -250.65898)
			(xy 353.270125 -250.642929) (xy 353.223842 -250.619347) (xy 353.181818 -250.588815) (xy 353.145087 -250.552085)
			(xy 353.114555 -250.510062) (xy 353.090973 -250.463779) (xy 353.074921 -250.414377) (xy 353.066795 -250.363072)
			(xy 351.700084 -250.363072) (xy 351.700084 -251.187966) (xy 351.844864 -251.332746) (xy 356.569264 -251.332746)
			(xy 356.772464 -251.535946) (xy 356.772464 -252.849126) (xy 356.617524 -253.004066) (xy 351.842324 -253.004066)
			(xy 351.710244 -253.136146) (xy 351.710244 -253.383796) (xy 361.226354 -253.383796) (xy 361.226834 -253.358097)
			(xy 361.234495 -253.307273) (xy 361.249644 -253.258159) (xy 361.271945 -253.211851) (xy 361.300898 -253.169384)
			(xy 361.335858 -253.131707) (xy 361.376042 -253.099661) (xy 361.420554 -253.073962) (xy 361.468399 -253.055185)
			(xy 361.518508 -253.043747) (xy 361.569762 -253.039907) (xy 361.621016 -253.043747) (xy 361.671125 -253.055185)
			(xy 361.71897 -253.073962) (xy 361.763482 -253.099661) (xy 361.803666 -253.131707) (xy 361.838626 -253.169384)
			(xy 361.867579 -253.211851) (xy 361.88988 -253.258159) (xy 361.905029 -253.307273) (xy 361.91269 -253.358097)
			(xy 361.91317 -253.383796) (xy 361.912665 -253.410602) (xy 361.904333 -253.463564) (xy 361.887872 -253.514587)
			(xy 361.86368 -253.562431) (xy 361.832347 -253.605935) (xy 361.813856 -253.62535) (xy 361.807299 -253.632579)
			(xy 361.799698 -253.650536) (xy 361.799343 -253.670032) (xy 361.806287 -253.688254) (xy 361.812586 -253.695708)
			(xy 361.828988 -253.714094) (xy 361.856663 -253.754857) (xy 361.877974 -253.79928) (xy 361.892447 -253.846377)
			(xy 361.899763 -253.895101) (xy 361.900216 -253.919736) (xy 361.899707 -253.945703) (xy 361.891582 -253.996998)
			(xy 361.877295 -254.040971) (xy 365.433815 -254.040971) (xy 365.433815 -253.989029) (xy 365.441941 -253.937727)
			(xy 365.457992 -253.888327) (xy 365.481573 -253.842047) (xy 365.512104 -253.800026) (xy 365.548833 -253.763298)
			(xy 365.590856 -253.732768) (xy 365.637137 -253.709188) (xy 365.686537 -253.693138) (xy 365.737839 -253.685014)
			(xy 365.76381 -253.684532) (xy 365.78967 -253.685043) (xy 365.840761 -253.69309) (xy 365.889974 -253.709)
			(xy 365.936105 -253.732385) (xy 365.978029 -253.762674) (xy 365.996728 -253.780544) (xy 366.006443 -253.789589)
			(xy 366.029452 -253.802801) (xy 366.055089 -253.809638) (xy 366.081623 -253.809638) (xy 366.10726 -253.802801)
			(xy 366.130269 -253.789589) (xy 366.139984 -253.780544) (xy 366.158678 -253.762668) (xy 366.200606 -253.732384)
			(xy 366.246739 -253.709001) (xy 366.295951 -253.693087) (xy 366.347041 -253.685032) (xy 366.372902 -253.684532)
			(xy 366.398868 -253.685069) (xy 366.450161 -253.693194) (xy 366.499551 -253.709242) (xy 366.545823 -253.732819)
			(xy 366.587836 -253.763344) (xy 366.624558 -253.800065) (xy 366.655082 -253.842079) (xy 366.678659 -253.888351)
			(xy 366.694707 -253.937741) (xy 366.702831 -253.989034) (xy 366.702831 -254.040966) (xy 366.694707 -254.092259)
			(xy 366.678659 -254.141649) (xy 366.655082 -254.187921) (xy 366.624558 -254.229935) (xy 366.587836 -254.266656)
			(xy 366.545823 -254.297181) (xy 366.499551 -254.320758) (xy 366.450161 -254.336806) (xy 366.398868 -254.344931)
			(xy 366.372902 -254.34544) (xy 366.347042 -254.344929) (xy 366.295951 -254.336883) (xy 366.246738 -254.320974)
			(xy 366.200606 -254.297588) (xy 366.158683 -254.267299) (xy 366.139984 -254.249428) (xy 366.130269 -254.240383)
			(xy 366.10726 -254.227171) (xy 366.081623 -254.220334) (xy 366.055089 -254.220334) (xy 366.029452 -254.227171)
			(xy 366.006443 -254.240383) (xy 365.996728 -254.249428) (xy 365.978041 -254.267311) (xy 365.936109 -254.297591)
			(xy 365.889974 -254.320972) (xy 365.840761 -254.336884) (xy 365.789671 -254.344939) (xy 365.76381 -254.34544)
			(xy 365.737839 -254.344986) (xy 365.686537 -254.336862) (xy 365.637137 -254.320812) (xy 365.590856 -254.297232)
			(xy 365.548833 -254.266702) (xy 365.512104 -254.229974) (xy 365.481573 -254.187953) (xy 365.457992 -254.141673)
			(xy 365.441941 -254.092273) (xy 365.433815 -254.040971) (xy 361.877295 -254.040971) (xy 361.875534 -254.046391)
			(xy 361.851956 -254.092665) (xy 361.82143 -254.134681) (xy 361.784707 -254.171404) (xy 361.742691 -254.20193)
			(xy 361.696417 -254.225508) (xy 361.647024 -254.241556) (xy 361.595729 -254.249681) (xy 361.543795 -254.249681)
			(xy 361.4925 -254.241556) (xy 361.443107 -254.225508) (xy 361.396833 -254.20193) (xy 361.354817 -254.171404)
			(xy 361.318094 -254.134681) (xy 361.287568 -254.092665) (xy 361.26399 -254.046391) (xy 361.247942 -253.996998)
			(xy 361.239817 -253.945703) (xy 361.239308 -253.919736) (xy 361.239728 -253.895101) (xy 361.247058 -253.846378)
			(xy 361.261546 -253.799286) (xy 361.282869 -253.754869) (xy 361.310556 -253.714112) (xy 361.326938 -253.695708)
			(xy 361.333233 -253.688253) (xy 361.34016 -253.67003) (xy 361.339806 -253.650538) (xy 361.332222 -253.632578)
			(xy 361.325668 -253.62535) (xy 361.307172 -253.605941) (xy 361.275844 -253.562434) (xy 361.251657 -253.514587)
			(xy 361.235199 -253.463564) (xy 361.226869 -253.410602) (xy 361.226354 -253.383796) (xy 351.710244 -253.383796)
			(xy 351.710244 -254.040971) (xy 353.066815 -254.040971) (xy 353.066815 -253.989029) (xy 353.07494 -253.937728)
			(xy 353.090991 -253.888329) (xy 353.114572 -253.842049) (xy 353.145103 -253.800028) (xy 353.181831 -253.7633)
			(xy 353.223852 -253.73277) (xy 353.270132 -253.70919) (xy 353.319532 -253.693139) (xy 353.370833 -253.685015)
			(xy 353.396804 -253.684532) (xy 353.422558 -253.685005) (xy 353.473445 -253.692987) (xy 353.522475 -253.708771)
			(xy 353.568461 -253.731976) (xy 353.610287 -253.762038) (xy 353.62896 -253.779782) (xy 353.63865 -253.788775)
			(xy 353.661582 -253.801907) (xy 353.687121 -253.808702) (xy 353.713547 -253.808702) (xy 353.739086 -253.801907)
			(xy 353.762018 -253.788775) (xy 353.771708 -253.779782) (xy 353.790381 -253.762041) (xy 353.832216 -253.731997)
			(xy 353.878203 -253.708802) (xy 353.92723 -253.693018) (xy 353.978111 -253.685027) (xy 354.003864 -253.684532)
			(xy 354.029834 -253.68504) (xy 354.081135 -253.69316) (xy 354.130535 -253.709206) (xy 354.176815 -253.732783)
			(xy 354.218838 -253.76331) (xy 354.255567 -253.800035) (xy 354.286098 -253.842054) (xy 354.30968 -253.888332)
			(xy 354.325731 -253.93773) (xy 354.333857 -253.98903) (xy 354.333857 -254.04097) (xy 354.325731 -254.09227)
			(xy 354.30968 -254.141668) (xy 354.286098 -254.187946) (xy 354.279075 -254.197612) (xy 357.937308 -254.197612)
			(xy 357.937744 -254.171691) (xy 357.945535 -254.120436) (xy 357.96094 -254.070936) (xy 357.983611 -254.024313)
			(xy 358.013033 -253.981627) (xy 358.048536 -253.943848) (xy 358.089314 -253.911835) (xy 358.13444 -253.886315)
			(xy 358.18289 -253.867868) (xy 358.233562 -253.856912) (xy 358.285305 -253.853698) (xy 358.336944 -253.858297)
			(xy 358.387304 -253.870605) (xy 358.435242 -253.890343) (xy 358.479669 -253.917063) (xy 358.519576 -253.950156)
			(xy 358.554054 -253.988872) (xy 358.582322 -254.03233) (xy 358.603737 -254.079543) (xy 358.617812 -254.129439)
			(xy 358.624227 -254.180883) (xy 358.622837 -254.232707) (xy 358.613673 -254.283734) (xy 358.596944 -254.332803)
			(xy 358.573029 -254.378801) (xy 358.542473 -254.420681) (xy 358.524556 -254.43942) (xy 358.518017 -254.446603)
			(xy 358.510513 -254.464509) (xy 358.510173 -254.48392) (xy 358.517045 -254.502077) (xy 358.523286 -254.509524)
			(xy 358.539696 -254.527904) (xy 358.567369 -254.568669) (xy 358.588679 -254.613093) (xy 358.603151 -254.660191)
			(xy 358.610464 -254.708916) (xy 358.610916 -254.733552) (xy 358.610407 -254.759519) (xy 358.602282 -254.810814)
			(xy 358.586234 -254.860207) (xy 358.562656 -254.906481) (xy 358.53213 -254.948497) (xy 358.495407 -254.98522)
			(xy 358.458985 -255.011682) (xy 361.226354 -255.011682) (xy 361.226834 -254.985983) (xy 361.234495 -254.935159)
			(xy 361.249644 -254.886045) (xy 361.271945 -254.839737) (xy 361.300898 -254.79727) (xy 361.335858 -254.759593)
			(xy 361.376042 -254.727547) (xy 361.420554 -254.701848) (xy 361.468399 -254.683071) (xy 361.518508 -254.671633)
			(xy 361.569762 -254.667793) (xy 361.621016 -254.671633) (xy 361.671125 -254.683071) (xy 361.71897 -254.701848)
			(xy 361.763482 -254.727547) (xy 361.803666 -254.759593) (xy 361.838626 -254.79727) (xy 361.867579 -254.839737)
			(xy 361.88988 -254.886045) (xy 361.905029 -254.935159) (xy 361.91269 -254.985983) (xy 361.91317 -255.011682)
			(xy 361.912656 -255.038488) (xy 361.904327 -255.091449) (xy 361.887867 -255.142472) (xy 361.863677 -255.190317)
			(xy 361.832346 -255.233821) (xy 361.813856 -255.253236) (xy 361.807312 -255.260476) (xy 361.799709 -255.278428)
			(xy 361.799351 -255.297921) (xy 361.806289 -255.31614) (xy 361.812586 -255.323594) (xy 361.828981 -255.341986)
			(xy 361.856657 -255.382748) (xy 361.877969 -255.427169) (xy 361.892444 -255.474264) (xy 361.899762 -255.522987)
			(xy 361.900216 -255.547622) (xy 361.899707 -255.573589) (xy 361.891582 -255.624884) (xy 361.875534 -255.674277)
			(xy 361.851956 -255.720551) (xy 361.82143 -255.762567) (xy 361.784707 -255.79929) (xy 361.742691 -255.829816)
			(xy 361.696417 -255.853394) (xy 361.647024 -255.869442) (xy 361.595729 -255.877567) (xy 361.543795 -255.877567)
			(xy 361.4925 -255.869442) (xy 361.443107 -255.853394) (xy 361.396833 -255.829816) (xy 361.354817 -255.79929)
			(xy 361.318094 -255.762567) (xy 361.287568 -255.720551) (xy 361.26399 -255.674277) (xy 361.247942 -255.624884)
			(xy 361.239817 -255.573589) (xy 361.239308 -255.547622) (xy 361.23978 -255.522989) (xy 361.247097 -255.474269)
			(xy 361.261573 -255.427177) (xy 361.282885 -255.382758) (xy 361.310561 -255.342) (xy 361.326938 -255.323594)
			(xy 361.333246 -255.31615) (xy 361.340172 -255.297922) (xy 361.339814 -255.278426) (xy 361.332225 -255.260464)
			(xy 361.325668 -255.253236) (xy 361.307165 -255.233833) (xy 361.275838 -255.190324) (xy 361.251653 -255.142476)
			(xy 361.235196 -255.091451) (xy 361.226868 -255.038489) (xy 361.226354 -255.011682) (xy 358.458985 -255.011682)
			(xy 358.453391 -255.015746) (xy 358.407117 -255.039324) (xy 358.357724 -255.055372) (xy 358.306429 -255.063497)
			(xy 358.254495 -255.063497) (xy 358.2032 -255.055372) (xy 358.153807 -255.039324) (xy 358.107533 -255.015746)
			(xy 358.065517 -254.98522) (xy 358.028794 -254.948497) (xy 357.998268 -254.906481) (xy 357.97469 -254.860207)
			(xy 357.958642 -254.810814) (xy 357.950517 -254.759519) (xy 357.950008 -254.733552) (xy 357.95045 -254.708895)
			(xy 357.957776 -254.660127) (xy 357.972258 -254.612987) (xy 357.993575 -254.568518) (xy 358.021256 -254.527705)
			(xy 358.037638 -254.50927) (xy 358.043949 -254.501883) (xy 358.05087 -254.483742) (xy 358.050576 -254.464327)
			(xy 358.043108 -254.446403) (xy 358.036622 -254.439166) (xy 358.018143 -254.419741) (xy 357.986811 -254.376239)
			(xy 357.96262 -254.328397) (xy 357.946157 -254.277376) (xy 357.937824 -254.224417) (xy 357.937308 -254.197612)
			(xy 354.279075 -254.197612) (xy 354.255567 -254.229965) (xy 354.218838 -254.26669) (xy 354.176815 -254.297217)
			(xy 354.130535 -254.320794) (xy 354.081135 -254.33684) (xy 354.029834 -254.34496) (xy 354.003864 -254.34544)
			(xy 353.97811 -254.344966) (xy 353.927224 -254.336982) (xy 353.878194 -254.321197) (xy 353.832209 -254.297993)
			(xy 353.790382 -254.267933) (xy 353.771708 -254.25019) (xy 353.762018 -254.241197) (xy 353.739086 -254.228065)
			(xy 353.713547 -254.22127) (xy 353.687121 -254.22127) (xy 353.661582 -254.228065) (xy 353.63865 -254.241197)
			(xy 353.62896 -254.25019) (xy 353.610296 -254.267941) (xy 353.56846 -254.297985) (xy 353.52247 -254.321179)
			(xy 353.473441 -254.33696) (xy 353.422557 -254.344948) (xy 353.396804 -254.34544) (xy 353.370833 -254.344985)
			(xy 353.319532 -254.336861) (xy 353.270132 -254.32081) (xy 353.223852 -254.29723) (xy 353.181831 -254.2667)
			(xy 353.145103 -254.229972) (xy 353.114572 -254.187951) (xy 353.090991 -254.141671) (xy 353.07494 -254.092272)
			(xy 353.066815 -254.040971) (xy 351.710244 -254.040971) (xy 351.710244 -254.787146) (xy 351.893124 -254.970026)
			(xy 356.493064 -254.970026) (xy 356.780084 -255.257046) (xy 356.780084 -255.825498) (xy 357.937308 -255.825498)
			(xy 357.937755 -255.799578) (xy 357.945547 -255.748326) (xy 357.960954 -255.698828) (xy 357.983625 -255.652208)
			(xy 358.013047 -255.609525) (xy 358.048549 -255.57175) (xy 358.089326 -255.539739) (xy 358.134451 -255.514221)
			(xy 358.182899 -255.495775) (xy 358.233569 -255.484821) (xy 358.285309 -255.481607) (xy 358.336945 -255.486207)
			(xy 358.387303 -255.498515) (xy 358.435239 -255.518253) (xy 358.479664 -255.544971) (xy 358.519569 -255.578063)
			(xy 358.554046 -255.616777) (xy 358.582312 -255.660233) (xy 358.603726 -255.707444) (xy 358.617801 -255.757337)
			(xy 358.624217 -255.808779) (xy 358.622828 -255.860601) (xy 358.613665 -255.911625) (xy 358.596938 -255.960692)
			(xy 358.573025 -256.006688) (xy 358.542471 -256.048568) (xy 358.524556 -256.067306) (xy 358.51803 -256.0745)
			(xy 358.510524 -256.092401) (xy 358.510181 -256.111808) (xy 358.517048 -256.129963) (xy 358.523286 -256.13741)
			(xy 358.539689 -256.155795) (xy 358.567364 -256.196559) (xy 358.588674 -256.240982) (xy 358.603148 -256.288079)
			(xy 358.610463 -256.336803) (xy 358.610916 -256.361438) (xy 358.610407 -256.387405) (xy 358.602282 -256.4387)
			(xy 358.586234 -256.488093) (xy 358.562656 -256.534367) (xy 358.53213 -256.576383) (xy 358.495407 -256.613106)
			(xy 358.459334 -256.639314) (xy 361.226354 -256.639314) (xy 361.226834 -256.613615) (xy 361.234495 -256.562791)
			(xy 361.249644 -256.513677) (xy 361.271945 -256.467369) (xy 361.300898 -256.424902) (xy 361.335858 -256.387225)
			(xy 361.376042 -256.355179) (xy 361.420554 -256.32948) (xy 361.468399 -256.310703) (xy 361.518508 -256.299265)
			(xy 361.569762 -256.295425) (xy 361.621016 -256.299265) (xy 361.671125 -256.310703) (xy 361.71897 -256.32948)
			(xy 361.763482 -256.355179) (xy 361.803666 -256.387225) (xy 361.838626 -256.424902) (xy 361.867579 -256.467369)
			(xy 361.88988 -256.513677) (xy 361.905029 -256.562791) (xy 361.91269 -256.613615) (xy 361.91317 -256.639314)
			(xy 361.912676 -256.666121) (xy 361.904342 -256.719083) (xy 361.887877 -256.770106) (xy 361.863683 -256.81795)
			(xy 361.832348 -256.861453) (xy 361.813856 -256.880868) (xy 361.807281 -256.888083) (xy 361.799683 -256.906046)
			(xy 361.799333 -256.925547) (xy 361.806283 -256.943771) (xy 361.812586 -256.951226) (xy 361.828996 -256.969605)
			(xy 361.85667 -257.01037) (xy 361.877979 -257.054795) (xy 361.892451 -257.101893) (xy 361.899764 -257.150618)
			(xy 361.900216 -257.175254) (xy 361.899707 -257.201221) (xy 361.891582 -257.252516) (xy 361.875534 -257.301909)
			(xy 361.851956 -257.348183) (xy 361.82143 -257.390199) (xy 361.784707 -257.426922) (xy 361.742691 -257.457448)
			(xy 361.696417 -257.481026) (xy 361.647024 -257.497074) (xy 361.595729 -257.505199) (xy 361.543795 -257.505199)
			(xy 361.4925 -257.497074) (xy 361.443107 -257.481026) (xy 361.396833 -257.457448) (xy 361.354817 -257.426922)
			(xy 361.318094 -257.390199) (xy 361.287568 -257.348183) (xy 361.26399 -257.301909) (xy 361.247942 -257.252516)
			(xy 361.239817 -257.201221) (xy 361.239308 -257.175254) (xy 361.239739 -257.150619) (xy 361.247066 -257.101897)
			(xy 361.261551 -257.054805) (xy 361.282873 -257.010387) (xy 361.310557 -256.969631) (xy 361.326938 -256.951226)
			(xy 361.333214 -256.943758) (xy 361.340145 -256.925541) (xy 361.339796 -256.906053) (xy 361.332219 -256.888096)
			(xy 361.325668 -256.880868) (xy 361.30718 -256.861451) (xy 361.275851 -256.817946) (xy 361.251663 -256.770102)
			(xy 361.235203 -256.71908) (xy 361.22687 -256.66612) (xy 361.226354 -256.639314) (xy 358.459334 -256.639314)
			(xy 358.453391 -256.643632) (xy 358.407117 -256.66721) (xy 358.357724 -256.683258) (xy 358.306429 -256.691383)
			(xy 358.254495 -256.691383) (xy 358.2032 -256.683258) (xy 358.153807 -256.66721) (xy 358.107533 -256.643632)
			(xy 358.065517 -256.613106) (xy 358.028794 -256.576383) (xy 357.998268 -256.534367) (xy 357.97469 -256.488093)
			(xy 357.958642 -256.4387) (xy 357.950517 -256.387405) (xy 357.950008 -256.361438) (xy 357.950441 -256.33678)
			(xy 357.957769 -256.288012) (xy 357.972253 -256.240872) (xy 357.993573 -256.196403) (xy 358.021256 -256.15559)
			(xy 358.037638 -256.137156) (xy 358.043864 -256.129705) (xy 358.0508 -256.111593) (xy 358.05053 -256.0922)
			(xy 358.043091 -256.074289) (xy 358.036622 -256.067052) (xy 358.018136 -256.047633) (xy 357.986805 -256.00413)
			(xy 357.962615 -255.956286) (xy 357.946154 -255.905264) (xy 357.937823 -255.852304) (xy 357.937308 -255.825498)
			(xy 356.780084 -255.825498) (xy 356.780084 -256.481326) (xy 356.581964 -256.679446) (xy 353.932744 -256.679446)
			(xy 353.81057 -256.80162) (xy 353.81057 -257.270758) (xy 353.811132 -257.285895) (xy 353.820017 -257.314837)
			(xy 353.836992 -257.339905) (xy 353.860565 -257.358901) (xy 353.888669 -257.370158) (xy 353.918838 -257.372688)
			(xy 353.93376 -257.370072) (xy 353.951069 -257.366521) (xy 353.986197 -257.362703) (xy 354.003864 -257.362452)
			(xy 354.029835 -257.362932) (xy 354.081137 -257.371053) (xy 354.130538 -257.387099) (xy 354.176819 -257.410676)
			(xy 354.218843 -257.441204) (xy 354.23077 -257.45313) (xy 357.937308 -257.45313) (xy 357.93773 -257.427207)
			(xy 357.945519 -257.375949) (xy 357.960923 -257.326445) (xy 357.983594 -257.279818) (xy 358.013015 -257.237129)
			(xy 358.048519 -257.199347) (xy 358.089298 -257.167331) (xy 358.134427 -257.141808) (xy 358.182879 -257.123358)
			(xy 358.233554 -257.112401) (xy 358.2853 -257.109185) (xy 358.336941 -257.113783) (xy 358.387305 -257.126092)
			(xy 358.435246 -257.145831) (xy 358.479676 -257.172552) (xy 358.519585 -257.205647) (xy 358.554065 -257.244365)
			(xy 358.582335 -257.287826) (xy 358.60375 -257.335042) (xy 358.617825 -257.384941) (xy 358.62424 -257.436389)
			(xy 358.622849 -257.488216) (xy 358.613683 -257.539245) (xy 358.596952 -257.588317) (xy 358.573034 -257.634317)
			(xy 358.542474 -257.676199) (xy 358.524556 -257.694938) (xy 358.518096 -257.702185) (xy 358.511082 -257.718869)
			(xy 365.433835 -257.718869) (xy 365.433835 -257.666931) (xy 365.44196 -257.615632) (xy 365.45801 -257.566235)
			(xy 365.48159 -257.519958) (xy 365.51212 -257.477939) (xy 365.548846 -257.441213) (xy 365.590866 -257.410685)
			(xy 365.637144 -257.387106) (xy 365.686541 -257.371058) (xy 365.737841 -257.362934) (xy 365.76381 -257.362452)
			(xy 365.789671 -257.362958) (xy 365.840762 -257.371005) (xy 365.889975 -257.386916) (xy 365.936106 -257.410303)
			(xy 365.978029 -257.440593) (xy 365.996728 -257.458464) (xy 366.006443 -257.467509) (xy 366.029452 -257.480721)
			(xy 366.055089 -257.487558) (xy 366.081623 -257.487558) (xy 366.10726 -257.480721) (xy 366.130269 -257.467509)
			(xy 366.139984 -257.458464) (xy 366.158664 -257.440574) (xy 366.200598 -257.410296) (xy 366.246735 -257.386916)
			(xy 366.295949 -257.371006) (xy 366.347041 -257.362952) (xy 366.372902 -257.362452) (xy 366.39887 -257.362949)
			(xy 366.450165 -257.371074) (xy 366.499559 -257.387123) (xy 366.545833 -257.410702) (xy 366.587849 -257.441228)
			(xy 366.624573 -257.477952) (xy 366.6551 -257.519969) (xy 366.678678 -257.566243) (xy 366.694726 -257.615637)
			(xy 366.702851 -257.666932) (xy 366.702851 -257.718868) (xy 366.694726 -257.770163) (xy 366.678678 -257.819557)
			(xy 366.6551 -257.865831) (xy 366.624573 -257.907848) (xy 366.587849 -257.944572) (xy 366.545833 -257.975098)
			(xy 366.499559 -257.998677) (xy 366.450165 -258.014726) (xy 366.39887 -258.022851) (xy 366.372902 -258.02336)
			(xy 366.347042 -258.022843) (xy 366.295951 -258.014798) (xy 366.246739 -257.99889) (xy 366.200607 -257.975506)
			(xy 366.158683 -257.945218) (xy 366.139984 -257.927348) (xy 366.130269 -257.918303) (xy 366.10726 -257.905091)
			(xy 366.081623 -257.898254) (xy 366.055089 -257.898254) (xy 366.029452 -257.905091) (xy 366.006443 -257.918303)
			(xy 365.996728 -257.927348) (xy 365.978028 -257.945217) (xy 365.936101 -257.975502) (xy 365.88997 -257.998887)
			(xy 365.840759 -258.014802) (xy 365.78967 -258.022859) (xy 365.76381 -258.02336) (xy 365.737841 -258.022866)
			(xy 365.686541 -258.014742) (xy 365.637144 -257.998694) (xy 365.590866 -257.975115) (xy 365.548846 -257.944587)
			(xy 365.51212 -257.907861) (xy 365.48159 -257.865842) (xy 365.45801 -257.819565) (xy 365.44196 -257.770168)
			(xy 365.433835 -257.718869) (xy 358.511082 -257.718869) (xy 358.51058 -257.720062) (xy 358.510218 -257.739451)
			(xy 358.517061 -257.757596) (xy 358.523286 -257.765042) (xy 358.539657 -257.783455) (xy 358.567336 -257.824211)
			(xy 358.588653 -257.868627) (xy 358.603134 -257.915717) (xy 358.610458 -257.964437) (xy 358.610916 -257.98907)
			(xy 358.610407 -258.015037) (xy 358.602282 -258.066332) (xy 358.586234 -258.115725) (xy 358.562656 -258.161999)
			(xy 358.53213 -258.204015) (xy 358.495407 -258.240738) (xy 358.458985 -258.2672) (xy 361.226354 -258.2672)
			(xy 361.226834 -258.241501) (xy 361.234495 -258.190677) (xy 361.249644 -258.141563) (xy 361.271945 -258.095255)
			(xy 361.300898 -258.052788) (xy 361.335858 -258.015111) (xy 361.376042 -257.983065) (xy 361.420554 -257.957366)
			(xy 361.468399 -257.938589) (xy 361.518508 -257.927151) (xy 361.569762 -257.923311) (xy 361.621016 -257.927151)
			(xy 361.671125 -257.938589) (xy 361.71897 -257.957366) (xy 361.763482 -257.983065) (xy 361.803666 -258.015111)
			(xy 361.838626 -258.052788) (xy 361.867579 -258.095255) (xy 361.88988 -258.141563) (xy 361.905029 -258.190677)
			(xy 361.91269 -258.241501) (xy 361.91317 -258.2672) (xy 361.912667 -258.294007) (xy 361.904335 -258.346968)
			(xy 361.887873 -258.397991) (xy 361.863681 -258.445836) (xy 361.832347 -258.489339) (xy 361.813856 -258.508754)
			(xy 361.807295 -258.51598) (xy 361.799694 -258.533938) (xy 361.799341 -258.553436) (xy 361.806286 -258.571658)
			(xy 361.812586 -258.579112) (xy 361.82899 -258.597496) (xy 361.856664 -258.63826) (xy 361.877975 -258.682684)
			(xy 361.892448 -258.72978) (xy 361.899763 -258.778505) (xy 361.900216 -258.80314) (xy 361.899707 -258.829107)
			(xy 361.891582 -258.880402) (xy 361.875534 -258.929795) (xy 361.851956 -258.976069) (xy 361.82143 -259.018085)
			(xy 361.784707 -259.054808) (xy 361.742691 -259.085334) (xy 361.696417 -259.108912) (xy 361.647024 -259.12496)
			(xy 361.595729 -259.133085) (xy 361.543795 -259.133085) (xy 361.4925 -259.12496) (xy 361.443107 -259.108912)
			(xy 361.396833 -259.085334) (xy 361.354817 -259.054808) (xy 361.318094 -259.018085) (xy 361.287568 -258.976069)
			(xy 361.26399 -258.929795) (xy 361.247942 -258.880402) (xy 361.239817 -258.829107) (xy 361.239308 -258.80314)
			(xy 361.239731 -258.778505) (xy 361.24706 -258.729783) (xy 361.261547 -258.68269) (xy 361.28287 -258.638273)
			(xy 361.310556 -258.597517) (xy 361.326938 -258.579112) (xy 361.333229 -258.571654) (xy 361.340157 -258.553432)
			(xy 361.339804 -258.533941) (xy 361.332222 -258.515982) (xy 361.325668 -258.508754) (xy 361.307174 -258.489343)
			(xy 361.275846 -258.445837) (xy 361.251658 -258.39799) (xy 361.2352 -258.346967) (xy 361.226869 -258.294006)
			(xy 361.226354 -258.2672) (xy 358.458985 -258.2672) (xy 358.453391 -258.271264) (xy 358.407117 -258.294842)
			(xy 358.357724 -258.31089) (xy 358.306429 -258.319015) (xy 358.254495 -258.319015) (xy 358.2032 -258.31089)
			(xy 358.153807 -258.294842) (xy 358.107533 -258.271264) (xy 358.065517 -258.240738) (xy 358.028794 -258.204015)
			(xy 357.998268 -258.161999) (xy 357.97469 -258.115725) (xy 357.958642 -258.066332) (xy 357.950517 -258.015037)
			(xy 357.950008 -257.98907) (xy 357.950461 -257.964413) (xy 357.957784 -257.915646) (xy 357.972263 -257.868506)
			(xy 357.993579 -257.824036) (xy 358.021257 -257.783223) (xy 358.037638 -257.764788) (xy 358.043931 -257.757388)
			(xy 358.050856 -257.739252) (xy 358.050566 -257.719842) (xy 358.043104 -257.701921) (xy 358.036622 -257.694684)
			(xy 358.018151 -257.675251) (xy 357.986818 -257.631752) (xy 357.962625 -257.583911) (xy 357.946161 -257.532892)
			(xy 357.937825 -257.479935) (xy 357.937308 -257.45313) (xy 354.23077 -257.45313) (xy 354.255573 -257.47793)
			(xy 354.286105 -257.51995) (xy 354.309687 -257.566229) (xy 354.325739 -257.615628) (xy 354.333865 -257.666929)
			(xy 354.333865 -257.718871) (xy 354.325739 -257.770172) (xy 354.309687 -257.819571) (xy 354.286105 -257.86585)
			(xy 354.255573 -257.90787) (xy 354.218843 -257.944596) (xy 354.176819 -257.975124) (xy 354.130538 -257.998701)
			(xy 354.081137 -258.014747) (xy 354.029835 -258.022868) (xy 354.003864 -258.02336) (xy 353.986197 -258.023104)
			(xy 353.951069 -258.019287) (xy 353.93376 -258.01574) (xy 353.918847 -258.013068) (xy 353.888672 -258.015599)
			(xy 353.860565 -258.026864) (xy 353.836995 -258.045874) (xy 353.820034 -258.070958) (xy 353.811172 -258.099913)
			(xy 353.81057 -258.115054) (xy 353.81057 -258.45897) (xy 353.812348 -258.461002) (xy 353.812348 -258.52755)
			(xy 353.899724 -258.614926) (xy 356.589584 -258.614926) (xy 356.777544 -258.802886) (xy 356.777544 -259.081016)
			(xy 357.937308 -259.081016) (xy 357.937741 -259.055094) (xy 357.945531 -259.003839) (xy 357.960937 -258.954338)
			(xy 357.983608 -258.907714) (xy 358.013029 -258.865027) (xy 358.048532 -258.827248) (xy 358.08931 -258.795234)
			(xy 358.134437 -258.769714) (xy 358.182888 -258.751266) (xy 358.23356 -258.74031) (xy 358.285304 -258.737095)
			(xy 358.336943 -258.741694) (xy 358.387304 -258.754002) (xy 358.435243 -258.77374) (xy 358.479671 -258.80046)
			(xy 358.519578 -258.833554) (xy 358.554057 -258.87227) (xy 358.582325 -258.915729) (xy 358.60374 -258.962943)
			(xy 358.617814 -259.012839) (xy 358.62423 -259.064284) (xy 358.622839 -259.116109) (xy 358.613675 -259.167136)
			(xy 358.596946 -259.216206) (xy 358.57303 -259.262204) (xy 358.542473 -259.304085) (xy 358.524556 -259.322824)
			(xy 358.518013 -259.330004) (xy 358.51051 -259.347911) (xy 358.510171 -259.367323) (xy 358.517044 -259.385481)
			(xy 358.523286 -259.392928) (xy 358.53965 -259.411346) (xy 358.56733 -259.452101) (xy 358.588648 -259.496516)
			(xy 358.603131 -259.543605) (xy 358.610457 -259.592323) (xy 358.610916 -259.616956) (xy 358.610407 -259.642923)
			(xy 358.602282 -259.694218) (xy 358.586234 -259.743611) (xy 358.562656 -259.789885) (xy 358.53213 -259.831901)
			(xy 358.495407 -259.868624) (xy 358.459334 -259.894832) (xy 361.226354 -259.894832) (xy 361.226834 -259.869133)
			(xy 361.234495 -259.818309) (xy 361.249644 -259.769195) (xy 361.271945 -259.722887) (xy 361.300898 -259.68042)
			(xy 361.335858 -259.642743) (xy 361.376042 -259.610697) (xy 361.420554 -259.584998) (xy 361.468399 -259.566221)
			(xy 361.518508 -259.554783) (xy 361.569762 -259.550943) (xy 361.621016 -259.554783) (xy 361.671125 -259.566221)
			(xy 361.71897 -259.584998) (xy 361.763482 -259.610697) (xy 361.803666 -259.642743) (xy 361.838626 -259.68042)
			(xy 361.867579 -259.722887) (xy 361.88988 -259.769195) (xy 361.905029 -259.818309) (xy 361.91269 -259.869133)
			(xy 361.91317 -259.894832) (xy 361.912687 -259.921639) (xy 361.90435 -259.974602) (xy 361.887883 -260.025625)
			(xy 361.863687 -260.073469) (xy 361.832349 -260.116972) (xy 361.813856 -260.136386) (xy 361.807264 -260.143587)
			(xy 361.799668 -260.161557) (xy 361.799324 -260.181063) (xy 361.80628 -260.199289) (xy 361.812586 -260.206744)
			(xy 361.828958 -260.225156) (xy 361.856637 -260.265912) (xy 361.877953 -260.310329) (xy 361.892434 -260.357419)
			(xy 361.899758 -260.406139) (xy 361.900216 -260.430772) (xy 361.899707 -260.456739) (xy 361.891582 -260.508034)
			(xy 361.875534 -260.557427) (xy 361.851956 -260.603701) (xy 361.82143 -260.645717) (xy 361.784707 -260.68244)
			(xy 361.742691 -260.712966) (xy 361.696417 -260.736544) (xy 361.647024 -260.752592) (xy 361.595729 -260.760717)
			(xy 361.543795 -260.760717) (xy 361.4925 -260.752592) (xy 361.443107 -260.736544) (xy 361.396833 -260.712966)
			(xy 361.354817 -260.68244) (xy 361.318094 -260.645717) (xy 361.287568 -260.603701) (xy 361.26399 -260.557427)
			(xy 361.247942 -260.508034) (xy 361.239817 -260.456739) (xy 361.239308 -260.430772) (xy 361.23975 -260.406138)
			(xy 361.247074 -260.357416) (xy 361.261557 -260.310324) (xy 361.282876 -260.265906) (xy 361.310558 -260.225149)
			(xy 361.326938 -260.206744) (xy 361.333197 -260.199262) (xy 361.34013 -260.181052) (xy 361.339787 -260.161569)
			(xy 361.332215 -260.143614) (xy 361.325668 -260.136386) (xy 361.307189 -260.116961) (xy 361.275859 -260.073458)
			(xy 361.251669 -260.025616) (xy 361.235206 -259.974596) (xy 361.226872 -259.921637) (xy 361.226354 -259.894832)
			(xy 358.459334 -259.894832) (xy 358.453391 -259.89915) (xy 358.407117 -259.922728) (xy 358.357724 -259.938776)
			(xy 358.306429 -259.946901) (xy 358.254495 -259.946901) (xy 358.2032 -259.938776) (xy 358.153807 -259.922728)
			(xy 358.107533 -259.89915) (xy 358.065517 -259.868624) (xy 358.028794 -259.831901) (xy 357.998268 -259.789885)
			(xy 357.97469 -259.743611) (xy 357.958642 -259.694218) (xy 357.950517 -259.642923) (xy 357.950008 -259.616956)
			(xy 357.950452 -259.592299) (xy 357.957777 -259.543531) (xy 357.972259 -259.496391) (xy 357.993576 -259.451922)
			(xy 358.021257 -259.411109) (xy 358.037638 -259.392674) (xy 358.043945 -259.385284) (xy 358.050867 -259.367144)
			(xy 358.050574 -259.34773) (xy 358.043107 -259.329807) (xy 358.036622 -259.32257) (xy 358.018145 -259.303143)
			(xy 357.986812 -259.259642) (xy 357.962621 -259.2118) (xy 357.946158 -259.16078) (xy 357.937824 -259.107821)
			(xy 357.937308 -259.081016) (xy 356.777544 -259.081016) (xy 356.777544 -260.118606) (xy 356.523544 -260.372606)
			(xy 356.048564 -260.372606) (xy 355.837236 -260.583934) (xy 355.837236 -260.708902) (xy 357.937308 -260.708902)
			(xy 357.937752 -260.682981) (xy 357.945543 -260.631729) (xy 357.96095 -260.58223) (xy 357.983621 -260.535609)
			(xy 358.013043 -260.492926) (xy 358.048545 -260.455149) (xy 358.089322 -260.423138) (xy 358.134448 -260.397619)
			(xy 358.182896 -260.379173) (xy 358.233567 -260.368219) (xy 358.285308 -260.365005) (xy 358.336945 -260.369604)
			(xy 358.387304 -260.381912) (xy 358.43524 -260.40165) (xy 358.479666 -260.428369) (xy 358.519571 -260.461461)
			(xy 358.554048 -260.500175) (xy 358.582315 -260.543632) (xy 358.603729 -260.590843) (xy 358.617804 -260.640737)
			(xy 358.62422 -260.69218) (xy 358.62283 -260.744002) (xy 358.613667 -260.795027) (xy 358.59694 -260.844096)
			(xy 358.573026 -260.890092) (xy 358.542472 -260.931972) (xy 358.524556 -260.95071) (xy 358.518027 -260.957901)
			(xy 358.510521 -260.975803) (xy 358.510178 -260.995211) (xy 358.517047 -261.013367) (xy 358.523286 -261.020814)
			(xy 358.539691 -261.039198) (xy 358.567365 -261.079962) (xy 358.588675 -261.124385) (xy 358.603149 -261.171482)
			(xy 358.610463 -261.220207) (xy 358.610916 -261.244842) (xy 358.610407 -261.270809) (xy 358.602282 -261.322104)
			(xy 358.586234 -261.371497) (xy 358.562656 -261.417771) (xy 358.53213 -261.459787) (xy 358.495407 -261.49651)
			(xy 358.459334 -261.522718) (xy 361.226354 -261.522718) (xy 361.226834 -261.497019) (xy 361.234495 -261.446195)
			(xy 361.249644 -261.397081) (xy 361.271945 -261.350773) (xy 361.300898 -261.308306) (xy 361.335858 -261.270629)
			(xy 361.376042 -261.238583) (xy 361.420554 -261.212884) (xy 361.468399 -261.194107) (xy 361.518508 -261.182669)
			(xy 361.569762 -261.178829) (xy 361.621016 -261.182669) (xy 361.671125 -261.194107) (xy 361.71897 -261.212884)
			(xy 361.763482 -261.238583) (xy 361.803666 -261.270629) (xy 361.838626 -261.308306) (xy 361.867579 -261.350773)
			(xy 361.88988 -261.397081) (xy 361.905029 -261.446195) (xy 361.91269 -261.497019) (xy 361.91317 -261.522718)
			(xy 361.912679 -261.549525) (xy 361.904344 -261.602487) (xy 361.887879 -261.65351) (xy 361.863684 -261.701355)
			(xy 361.832348 -261.744857) (xy 361.813856 -261.764272) (xy 361.807278 -261.771484) (xy 361.79968 -261.789449)
			(xy 361.799331 -261.808951) (xy 361.806283 -261.827175) (xy 361.812586 -261.83463) (xy 361.828951 -261.853047)
			(xy 361.856631 -261.893802) (xy 361.877949 -261.938217) (xy 361.892431 -261.985307) (xy 361.899757 -262.034025)
			(xy 361.900216 -262.058658) (xy 361.899707 -262.084625) (xy 361.891582 -262.13592) (xy 361.875534 -262.185313)
			(xy 361.851956 -262.231587) (xy 361.82143 -262.273603) (xy 361.784707 -262.310326) (xy 361.742691 -262.340852)
			(xy 361.696417 -262.36443) (xy 361.647024 -262.380478) (xy 361.595729 -262.388603) (xy 361.543795 -262.388603)
			(xy 361.4925 -262.380478) (xy 361.443107 -262.36443) (xy 361.396833 -262.340852) (xy 361.354817 -262.310326)
			(xy 361.318094 -262.273603) (xy 361.287568 -262.231587) (xy 361.26399 -262.185313) (xy 361.247942 -262.13592)
			(xy 361.239817 -262.084625) (xy 361.239308 -262.058658) (xy 361.239741 -262.034023) (xy 361.247068 -261.985301)
			(xy 361.261553 -261.938209) (xy 361.282873 -261.893792) (xy 361.310557 -261.853035) (xy 361.326938 -261.83463)
			(xy 361.333211 -261.827159) (xy 361.340142 -261.808943) (xy 361.339794 -261.789457) (xy 361.332218 -261.7715)
			(xy 361.325668 -261.764272) (xy 361.307182 -261.744853) (xy 361.275853 -261.701349) (xy 361.251664 -261.653505)
			(xy 361.235203 -261.602483) (xy 361.22687 -261.549524) (xy 361.226354 -261.522718) (xy 358.459334 -261.522718)
			(xy 358.453391 -261.527036) (xy 358.407117 -261.550614) (xy 358.357724 -261.566662) (xy 358.306429 -261.574787)
			(xy 358.254495 -261.574787) (xy 358.2032 -261.566662) (xy 358.153807 -261.550614) (xy 358.107533 -261.527036)
			(xy 358.065517 -261.49651) (xy 358.028794 -261.459787) (xy 357.998268 -261.417771) (xy 357.97469 -261.371497)
			(xy 357.958642 -261.322104) (xy 357.950517 -261.270809) (xy 357.950008 -261.244842) (xy 357.950444 -261.220184)
			(xy 357.957771 -261.171417) (xy 357.972255 -261.124276) (xy 357.993574 -261.079807) (xy 358.021256 -261.038994)
			(xy 358.037638 -261.02056) (xy 358.04386 -261.013106) (xy 358.050796 -260.994996) (xy 358.050527 -260.975604)
			(xy 358.043091 -260.957692) (xy 358.036622 -260.950456) (xy 358.018138 -260.931036) (xy 357.986806 -260.887533)
			(xy 357.962616 -260.839689) (xy 357.946155 -260.788667) (xy 357.937823 -260.735708) (xy 357.937308 -260.708902)
			(xy 355.837236 -260.708902) (xy 355.837236 -261.497064) (xy 355.338888 -261.995412) (xy 355.124512 -262.210042)
			(xy 355.124512 -262.336534) (xy 357.937308 -262.336534) (xy 357.937727 -262.310611) (xy 357.945515 -262.259352)
			(xy 357.960919 -262.209847) (xy 357.98359 -262.163219) (xy 358.013011 -262.120529) (xy 358.048515 -262.082746)
			(xy 358.089295 -262.050729) (xy 358.134424 -262.025206) (xy 358.182876 -262.006756) (xy 358.233552 -261.995798)
			(xy 358.285299 -261.992582) (xy 358.336941 -261.99718) (xy 358.387305 -262.009489) (xy 358.435247 -262.029228)
			(xy 358.479678 -262.055949) (xy 358.519587 -262.089045) (xy 358.554068 -262.127764) (xy 358.582337 -262.171225)
			(xy 358.603753 -262.218442) (xy 358.617828 -262.268342) (xy 358.624243 -262.31979) (xy 358.622851 -262.371618)
			(xy 358.613685 -262.422648) (xy 358.596953 -262.47172) (xy 358.573035 -262.51772) (xy 358.542475 -262.559603)
			(xy 358.524556 -262.578342) (xy 358.518092 -262.585586) (xy 358.510577 -262.603464) (xy 358.510216 -262.622854)
			(xy 358.51706 -262.641) (xy 358.523286 -262.648446) (xy 358.539659 -262.666857) (xy 358.567338 -262.707614)
			(xy 358.588654 -262.75203) (xy 358.603135 -262.799121) (xy 358.610458 -262.847841) (xy 358.610916 -262.872474)
			(xy 358.610407 -262.898441) (xy 358.602282 -262.949736) (xy 358.586234 -262.999129) (xy 358.562656 -263.045403)
			(xy 358.53213 -263.087419) (xy 358.495407 -263.124142) (xy 358.458985 -263.150604) (xy 361.226354 -263.150604)
			(xy 361.226834 -263.124905) (xy 361.234495 -263.074081) (xy 361.249644 -263.024967) (xy 361.271945 -262.978659)
			(xy 361.300898 -262.936192) (xy 361.335858 -262.898515) (xy 361.376042 -262.866469) (xy 361.420554 -262.84077)
			(xy 361.468399 -262.821993) (xy 361.518508 -262.810555) (xy 361.569762 -262.806715) (xy 361.621016 -262.810555)
			(xy 361.671125 -262.821993) (xy 361.71897 -262.84077) (xy 361.763482 -262.866469) (xy 361.803666 -262.898515)
			(xy 361.838626 -262.936192) (xy 361.867579 -262.978659) (xy 361.88988 -263.024967) (xy 361.905029 -263.074081)
			(xy 361.91269 -263.124905) (xy 361.91317 -263.150604) (xy 361.91267 -263.177411) (xy 361.904337 -263.230372)
			(xy 361.887874 -263.281395) (xy 361.863682 -263.32924) (xy 361.832347 -263.372743) (xy 361.813856 -263.392158)
			(xy 361.807291 -263.399381) (xy 361.799691 -263.417341) (xy 361.799339 -263.436839) (xy 361.806285 -263.455061)
			(xy 361.812586 -263.462516) (xy 361.828992 -263.480899) (xy 361.856666 -263.521663) (xy 361.877976 -263.566087)
			(xy 361.892449 -263.613184) (xy 361.899763 -263.661909) (xy 361.900216 -263.686544) (xy 361.899707 -263.712511)
			(xy 361.891582 -263.763806) (xy 361.875534 -263.813199) (xy 361.851956 -263.859473) (xy 361.82143 -263.901489)
			(xy 361.784707 -263.938212) (xy 361.742691 -263.968738) (xy 361.696417 -263.992316) (xy 361.647024 -264.008364)
			(xy 361.595729 -264.016489) (xy 361.543795 -264.016489) (xy 361.4925 -264.008364) (xy 361.443107 -263.992316)
			(xy 361.396833 -263.968738) (xy 361.354817 -263.938212) (xy 361.318094 -263.901489) (xy 361.287568 -263.859473)
			(xy 361.26399 -263.813199) (xy 361.247942 -263.763806) (xy 361.239817 -263.712511) (xy 361.239308 -263.686544)
			(xy 361.239733 -263.661909) (xy 361.247062 -263.613187) (xy 361.261548 -263.566094) (xy 361.282871 -263.521677)
			(xy 361.310556 -263.480921) (xy 361.326938 -263.462516) (xy 361.333225 -263.455055) (xy 361.340154 -263.436835)
			(xy 361.339802 -263.417345) (xy 361.332221 -263.399386) (xy 361.325668 -263.392158) (xy 361.307176 -263.372745)
			(xy 361.275847 -263.329239) (xy 361.25166 -263.281394) (xy 361.235201 -263.230371) (xy 361.226869 -263.17741)
			(xy 361.226354 -263.150604) (xy 358.458985 -263.150604) (xy 358.453391 -263.154668) (xy 358.407117 -263.178246)
			(xy 358.357724 -263.194294) (xy 358.306429 -263.202419) (xy 358.254495 -263.202419) (xy 358.2032 -263.194294)
			(xy 358.153807 -263.178246) (xy 358.107533 -263.154668) (xy 358.065517 -263.124142) (xy 358.028794 -263.087419)
			(xy 357.998268 -263.045403) (xy 357.97469 -262.999129) (xy 357.958642 -262.949736) (xy 357.950517 -262.898441)
			(xy 357.950008 -262.872474) (xy 357.950463 -262.847817) (xy 357.957786 -262.79905) (xy 357.972265 -262.75191)
			(xy 357.993579 -262.707441) (xy 358.021258 -262.666627) (xy 358.037638 -262.648192) (xy 358.043927 -262.640789)
			(xy 358.050852 -262.622655) (xy 358.050564 -262.603245) (xy 358.043104 -262.585325) (xy 358.036622 -262.578088)
			(xy 358.018153 -262.558654) (xy 357.98682 -262.515154) (xy 357.962627 -262.467314) (xy 357.946162 -262.416296)
			(xy 357.937826 -262.363339) (xy 357.937308 -262.336534) (xy 355.124512 -262.336534) (xy 355.124512 -263.303258)
			(xy 355.392482 -263.571228) (xy 356.165658 -263.571228) (xy 356.249224 -263.654794) (xy 356.279704 -263.64311)
			(xy 356.308987 -263.632779) (xy 356.370071 -263.621656) (xy 356.401116 -263.621012) (xy 356.428102 -263.621515)
			(xy 356.481409 -263.629961) (xy 356.532738 -263.646641) (xy 356.580826 -263.671147) (xy 356.624489 -263.702873)
			(xy 356.662651 -263.741038) (xy 356.694372 -263.784704) (xy 356.718872 -263.832795) (xy 356.735548 -263.884126)
			(xy 356.743988 -263.937434) (xy 356.744524 -263.96442) (xy 356.743879 -263.995465) (xy 356.732757 -264.056549)
			(xy 356.722426 -264.085832) (xy 356.710742 -264.116312) (xy 356.912164 -264.317734) (xy 356.969822 -264.317734)
			(xy 357.275892 -264.623804) (xy 357.275892 -265.073892) (xy 357.480616 -265.278616) (xy 357.48849 -265.282426)
			(xy 357.514618 -265.29554) (xy 357.562359 -265.329276) (xy 357.603697 -265.370609) (xy 357.637439 -265.418345)
			(xy 357.650542 -265.444478) (xy 357.654352 -265.452352) (xy 358.0511 -265.8491) (xy 358.0511 -266.160758)
			(xy 358.070221 -266.180264) (xy 358.102654 -266.224212) (xy 358.12772 -266.272741) (xy 358.144786 -266.324626)
			(xy 358.153423 -266.378558) (xy 358.15397 -266.405868) (xy 358.153795 -266.420098) (xy 358.15138 -266.448456)
			(xy 358.149144 -266.46251) (xy 358.14508 -266.488418) (xy 358.500934 -266.844272) (xy 358.500934 -266.95654)
			(xy 358.519858 -266.972935) (xy 358.553215 -267.010272) (xy 358.580791 -267.052061) (xy 358.602001 -267.097414)
			(xy 358.616395 -267.145368) (xy 358.623666 -267.194904) (xy 358.624124 -267.219938) (xy 358.623603 -267.246779)
			(xy 358.615245 -267.299805) (xy 358.598737 -267.350886) (xy 358.574483 -267.398775) (xy 358.543073 -267.442308)
			(xy 358.524556 -267.461746) (xy 358.517999 -267.468939) (xy 358.5104 -267.48684) (xy 358.510037 -267.506283)
			(xy 358.51696 -267.524456) (xy 358.523286 -267.53185) (xy 358.539665 -267.550256) (xy 358.567344 -267.591014)
			(xy 358.588661 -267.635431) (xy 358.603141 -267.682523) (xy 358.610464 -267.731244) (xy 358.610916 -267.755878)
			(xy 358.610346 -267.783664) (xy 358.601051 -267.838452) (xy 358.582718 -267.890912) (xy 358.555865 -267.939565)
			(xy 358.521248 -267.983038) (xy 358.500934 -268.002004) (xy 358.500934 -268.584172) (xy 358.519856 -268.600568)
			(xy 358.553209 -268.637906) (xy 358.580782 -268.679695) (xy 358.601988 -268.725048) (xy 358.616377 -268.773001)
			(xy 358.623644 -268.822537) (xy 358.624124 -268.84757) (xy 358.623608 -268.874413) (xy 358.615259 -268.927445)
			(xy 358.59876 -268.978532) (xy 358.574512 -269.026429) (xy 358.543106 -269.06997) (xy 358.524556 -269.089378)
			(xy 358.518005 -269.096571) (xy 358.510418 -269.114467) (xy 358.510063 -269.133902) (xy 358.516992 -269.152064)
			(xy 358.523286 -269.159482) (xy 358.539663 -269.177888) (xy 358.567338 -269.218647) (xy 358.58865 -269.263065)
			(xy 358.603126 -269.310157) (xy 358.610445 -269.358877) (xy 358.610916 -269.38351) (xy 358.610344 -269.411295)
			(xy 358.601043 -269.46608) (xy 358.582707 -269.518537) (xy 358.555851 -269.567186) (xy 358.521233 -269.610654)
			(xy 358.500934 -269.629636) (xy 358.500934 -270.212058) (xy 358.519857 -270.228453) (xy 358.553212 -270.265791)
			(xy 358.580786 -270.30758) (xy 358.601994 -270.352933) (xy 358.616385 -270.400887) (xy 358.623653 -270.450423)
			(xy 358.624124 -270.475456) (xy 358.623609 -270.502299) (xy 358.615262 -270.555332) (xy 358.598764 -270.606421)
			(xy 358.574517 -270.65432) (xy 358.543112 -270.697862) (xy 358.524556 -270.717264) (xy 358.518002 -270.724457)
			(xy 358.51041 -270.742355) (xy 358.510051 -270.761794) (xy 358.516978 -270.77996) (xy 358.523286 -270.787368)
			(xy 358.539664 -270.805774) (xy 358.567341 -270.846532) (xy 358.588655 -270.89095) (xy 358.603133 -270.938042)
			(xy 358.610453 -270.986762) (xy 358.610916 -271.011396) (xy 358.610345 -271.039181) (xy 358.601047 -271.093968)
			(xy 358.582712 -271.146426) (xy 358.555857 -271.195077) (xy 358.52124 -271.238547) (xy 358.500934 -271.257522)
			(xy 358.500934 -271.839944) (xy 358.519857 -271.856339) (xy 358.553214 -271.893676) (xy 358.58079 -271.935465)
			(xy 358.601999 -271.980818) (xy 358.616392 -272.028772) (xy 358.623663 -272.078308) (xy 358.624124 -272.103342)
			(xy 358.623603 -272.130183) (xy 358.615244 -272.183209) (xy 358.598736 -272.234289) (xy 358.574482 -272.282178)
			(xy 358.543071 -272.32571) (xy 358.524556 -272.34515) (xy 358.517999 -272.352343) (xy 358.510402 -272.370243)
			(xy 358.51004 -272.389686) (xy 358.516964 -272.407857) (xy 358.523286 -272.415254) (xy 358.539665 -272.43366)
			(xy 358.567343 -272.474418) (xy 358.588659 -272.518836) (xy 358.603139 -272.565928) (xy 358.610462 -272.614648)
			(xy 358.610916 -272.639282) (xy 358.610346 -272.667068) (xy 358.60105 -272.721856) (xy 358.582716 -272.774315)
			(xy 358.555863 -272.822968) (xy 358.521247 -272.86644) (xy 358.500934 -272.885408) (xy 358.500934 -273.467576)
			(xy 358.519856 -273.483972) (xy 358.553209 -273.52131) (xy 358.580781 -273.563099) (xy 358.601986 -273.608452)
			(xy 358.616375 -273.656406) (xy 358.623641 -273.705941) (xy 358.624124 -273.730974) (xy 358.623608 -273.757817)
			(xy 358.615258 -273.810848) (xy 358.598758 -273.861935) (xy 358.57451 -273.909832) (xy 358.543104 -273.953372)
			(xy 358.524556 -273.972782) (xy 358.518006 -273.979975) (xy 358.51042 -273.997871) (xy 358.510067 -274.017305)
			(xy 358.516996 -274.035465) (xy 358.523286 -274.042886) (xy 358.539663 -274.061292) (xy 358.567338 -274.102051)
			(xy 358.588649 -274.146469) (xy 358.603125 -274.193561) (xy 358.610442 -274.242281) (xy 358.610916 -274.266914)
			(xy 358.610343 -274.294698) (xy 358.601042 -274.349484) (xy 358.582705 -274.40194) (xy 358.555849 -274.450588)
			(xy 358.521231 -274.494057) (xy 358.500934 -274.51304) (xy 358.500934 -275.095462) (xy 358.519856 -275.111857)
			(xy 358.553211 -275.149195) (xy 358.580785 -275.190984) (xy 358.601992 -275.236337) (xy 358.616382 -275.284291)
			(xy 358.623651 -275.333827) (xy 358.624124 -275.35886) (xy 358.623609 -275.385703) (xy 358.615261 -275.438736)
			(xy 358.598763 -275.489824) (xy 358.574516 -275.537722) (xy 358.54311 -275.581264) (xy 358.524556 -275.600668)
			(xy 358.518003 -275.607861) (xy 358.510412 -275.625759) (xy 358.510055 -275.645196) (xy 358.516982 -275.663361)
			(xy 358.523286 -275.670772) (xy 358.539664 -275.689178) (xy 358.56734 -275.729937) (xy 358.588654 -275.774355)
			(xy 358.603131 -275.821446) (xy 358.610451 -275.870167) (xy 358.610916 -275.8948) (xy 358.610344 -275.922585)
			(xy 358.601046 -275.977371) (xy 358.58271 -276.029829) (xy 358.555855 -276.078479) (xy 358.521238 -276.121949)
			(xy 358.500934 -276.140926) (xy 358.500934 -276.243288) (xy 358.270302 -276.47392) (xy 358.260635 -276.484224)
			(xy 358.246885 -276.508892) (xy 358.240417 -276.536383) (xy 358.241726 -276.564594) (xy 358.250712 -276.591368)
			(xy 358.266688 -276.614657) (xy 358.288432 -276.632679) (xy 358.314281 -276.644056) (xy 358.328214 -276.646386)
			(xy 358.355214 -276.650692) (xy 358.407477 -276.66674) (xy 358.456538 -276.690865) (xy 358.501156 -276.722458)
			(xy 358.540206 -276.760722) (xy 358.5727 -276.804689) (xy 358.597817 -276.853249) (xy 358.614924 -276.905176)
			(xy 358.623587 -276.959156) (xy 358.624124 -276.986492) (xy 358.623607 -277.013334) (xy 358.615255 -277.066364)
			(xy 358.598752 -277.117449) (xy 358.574502 -277.165344) (xy 358.543095 -277.208882) (xy 358.524556 -277.2283)
			(xy 358.518009 -277.235493) (xy 358.51043 -277.253386) (xy 358.510082 -277.272815) (xy 358.517014 -277.290969)
			(xy 358.523286 -277.298404) (xy 358.539668 -277.316809) (xy 358.567352 -277.357566) (xy 358.588675 -277.401983)
			(xy 358.603162 -277.449075) (xy 358.610492 -277.497797) (xy 358.610916 -277.522432) (xy 358.610431 -277.548399)
			(xy 358.602302 -277.599692) (xy 358.586248 -277.649081) (xy 358.562666 -277.695352) (xy 358.532136 -277.737364)
			(xy 358.49541 -277.774082) (xy 358.453392 -277.804603) (xy 358.407117 -277.828175) (xy 358.357723 -277.844218)
			(xy 358.306429 -277.852336) (xy 358.280462 -277.852886) (xy 358.261495 -277.852638) (xy 358.223808 -277.848308)
			(xy 358.205278 -277.84425) (xy 358.195491 -277.842423) (xy 358.175853 -277.845568) (xy 358.158902 -277.855971)
			(xy 358.147205 -277.872055) (xy 358.144318 -277.881588) (xy 358.139028 -277.902017) (xy 358.124128 -277.941499)
			(xy 358.1146 -277.960328) (xy 358.108758 -277.97125) (xy 358.108758 -278.193754) (xy 358.113076 -278.203406)
			(xy 358.121926 -278.224465) (xy 358.134388 -278.268413) (xy 358.140658 -278.313661) (xy 358.141016 -278.336502)
			(xy 358.140627 -278.35934) (xy 358.134343 -278.404582) (xy 358.121906 -278.448533) (xy 358.113076 -278.469598)
			(xy 358.108758 -278.47925) (xy 358.108758 -278.501602) (xy 358.072944 -278.537416) (xy 358.05941 -278.554514)
			(xy 358.028572 -278.585347) (xy 358.011476 -278.598884) (xy 357.936292 -278.674068) (xy 357.754428 -278.674068)
			(xy 357.73995 -278.65959) (xy 357.726742 -278.656034) (xy 357.701276 -278.648851) (xy 357.652866 -278.627498)
			(xy 357.608484 -278.598693) (xy 357.569269 -278.563174) (xy 357.536225 -278.521851) (xy 357.52278 -278.499062)
			(xy 357.508302 -278.473154) (xy 357.189786 -278.473154) (xy 357.15067 -278.51227) (xy 357.147622 -278.516842)
			(xy 357.13478 -278.535836) (xy 357.104683 -278.570422) (xy 357.070092 -278.600514) (xy 357.051102 -278.613362)
			(xy 357.04653 -278.61641) (xy 356.685088 -278.977852) (xy 356.700074 -279.01011) (xy 356.709948 -279.032149)
			(xy 356.723867 -279.078393) (xy 356.730901 -279.126171) (xy 356.731316 -279.150318) (xy 356.730865 -279.174881)
			(xy 356.723589 -279.223466) (xy 356.709199 -279.270438) (xy 356.688012 -279.314762) (xy 356.660497 -279.35546)
			(xy 356.644194 -279.373838) (xy 356.644194 -279.428194) (xy 361.226354 -279.428194) (xy 361.226834 -279.402495)
			(xy 361.234495 -279.351671) (xy 361.249644 -279.302557) (xy 361.271945 -279.256249) (xy 361.300898 -279.213782)
			(xy 361.335858 -279.176105) (xy 361.376042 -279.144059) (xy 361.420554 -279.11836) (xy 361.468399 -279.099583)
			(xy 361.518508 -279.088145) (xy 361.569762 -279.084305) (xy 361.621016 -279.088145) (xy 361.671125 -279.099583)
			(xy 361.71897 -279.11836) (xy 361.763482 -279.144059) (xy 361.803666 -279.176105) (xy 361.838626 -279.213782)
			(xy 361.867579 -279.256249) (xy 361.88988 -279.302557) (xy 361.905029 -279.351671) (xy 361.91269 -279.402495)
			(xy 361.91317 -279.428194) (xy 361.912664 -279.455) (xy 361.904332 -279.507962) (xy 361.887871 -279.558985)
			(xy 361.86368 -279.606829) (xy 361.832347 -279.650333) (xy 361.813856 -279.669748) (xy 361.807301 -279.676979)
			(xy 361.799699 -279.694935) (xy 361.799344 -279.714431) (xy 361.806287 -279.732652) (xy 361.812586 -279.740106)
			(xy 361.828987 -279.758493) (xy 361.856662 -279.799256) (xy 361.877973 -279.843679) (xy 361.892447 -279.890775)
			(xy 361.899763 -279.939499) (xy 361.900216 -279.964134) (xy 361.899707 -279.990101) (xy 361.891582 -280.041396)
			(xy 361.875534 -280.090789) (xy 361.851956 -280.137063) (xy 361.82143 -280.179079) (xy 361.784707 -280.215802)
			(xy 361.742691 -280.246328) (xy 361.696417 -280.269906) (xy 361.647024 -280.285954) (xy 361.595729 -280.294079)
			(xy 361.543795 -280.294079) (xy 361.4925 -280.285954) (xy 361.443107 -280.269906) (xy 361.396833 -280.246328)
			(xy 361.354817 -280.215802) (xy 361.318094 -280.179079) (xy 361.287568 -280.137063) (xy 361.26399 -280.090789)
			(xy 361.247942 -280.041396) (xy 361.239817 -279.990101) (xy 361.239308 -279.964134) (xy 361.239727 -279.939499)
			(xy 361.247057 -279.890776) (xy 361.261545 -279.843684) (xy 361.282869 -279.799266) (xy 361.310556 -279.75851)
			(xy 361.326938 -279.740106) (xy 361.333235 -279.732653) (xy 361.340162 -279.714429) (xy 361.339808 -279.694936)
			(xy 361.332223 -279.676976) (xy 361.325668 -279.669748) (xy 361.307171 -279.65034) (xy 361.275843 -279.606832)
			(xy 361.251657 -279.558986) (xy 361.235198 -279.507962) (xy 361.226869 -279.455) (xy 361.226354 -279.428194)
			(xy 356.644194 -279.428194) (xy 356.644194 -279.727152) (xy 356.129082 -280.242264) (xy 357.937308 -280.242264)
			(xy 357.937781 -280.216347) (xy 357.945577 -280.165102) (xy 357.960987 -280.115611) (xy 357.983659 -280.068998)
			(xy 358.01308 -280.026322) (xy 358.048581 -279.988553) (xy 358.089355 -279.956548) (xy 358.134477 -279.931035)
			(xy 358.18292 -279.912594) (xy 358.233585 -279.901643) (xy 358.28532 -279.898432) (xy 358.33695 -279.903032)
			(xy 358.387302 -279.91534) (xy 358.435232 -279.935076) (xy 358.479652 -279.961791) (xy 358.519551 -279.99488)
			(xy 358.554025 -280.033589) (xy 358.582289 -280.07704) (xy 358.603701 -280.124245) (xy 358.617776 -280.174132)
			(xy 358.624192 -280.225568) (xy 358.622805 -280.277384) (xy 358.613646 -280.328403) (xy 358.596923 -280.377466)
			(xy 358.573016 -280.423458) (xy 358.542468 -280.465335) (xy 358.524556 -280.484072) (xy 358.518064 -280.491293)
			(xy 358.510553 -280.509181) (xy 358.510199 -280.528579) (xy 358.517054 -280.546729) (xy 358.523286 -280.554176)
			(xy 358.539673 -280.572575) (xy 358.56735 -280.613335) (xy 358.588663 -280.657755) (xy 358.603141 -280.704848)
			(xy 358.61046 -280.75357) (xy 358.610916 -280.778204) (xy 358.610407 -280.804171) (xy 358.602282 -280.855466)
			(xy 358.586234 -280.904859) (xy 358.562656 -280.951133) (xy 358.53213 -280.993149) (xy 358.495407 -281.029872)
			(xy 358.459334 -281.05608) (xy 361.226354 -281.05608) (xy 361.226834 -281.030381) (xy 361.234495 -280.979557)
			(xy 361.249644 -280.930443) (xy 361.271945 -280.884135) (xy 361.300898 -280.841668) (xy 361.335858 -280.803991)
			(xy 361.376042 -280.771945) (xy 361.420554 -280.746246) (xy 361.468399 -280.727469) (xy 361.518508 -280.716031)
			(xy 361.569762 -280.712191) (xy 361.621016 -280.716031) (xy 361.671125 -280.727469) (xy 361.71897 -280.746246)
			(xy 361.763482 -280.771945) (xy 361.803666 -280.803991) (xy 361.838626 -280.841668) (xy 361.867579 -280.884135)
			(xy 361.88988 -280.930443) (xy 361.905029 -280.979557) (xy 361.91269 -281.030381) (xy 361.91317 -281.05608)
			(xy 361.912655 -281.082886) (xy 361.904326 -281.135847) (xy 361.887866 -281.18687) (xy 361.863677 -281.234715)
			(xy 361.832346 -281.278219) (xy 361.813856 -281.297634) (xy 361.807315 -281.304876) (xy 361.799711 -281.322827)
			(xy 361.799352 -281.342319) (xy 361.80629 -281.360538) (xy 361.812586 -281.367992) (xy 361.82898 -281.386384)
			(xy 361.856656 -281.427146) (xy 361.877969 -281.471567) (xy 361.892444 -281.518662) (xy 361.899762 -281.567385)
			(xy 361.900216 -281.59202) (xy 361.899707 -281.617987) (xy 361.891582 -281.669282) (xy 361.875534 -281.718675)
			(xy 361.851956 -281.764949) (xy 361.82143 -281.806965) (xy 361.784707 -281.843688) (xy 361.742691 -281.874214)
			(xy 361.696417 -281.897792) (xy 361.647024 -281.91384) (xy 361.595729 -281.921965) (xy 361.543795 -281.921965)
			(xy 361.4925 -281.91384) (xy 361.443107 -281.897792) (xy 361.396833 -281.874214) (xy 361.354817 -281.843688)
			(xy 361.318094 -281.806965) (xy 361.287568 -281.764949) (xy 361.26399 -281.718675) (xy 361.247942 -281.669282)
			(xy 361.239817 -281.617987) (xy 361.239308 -281.59202) (xy 361.239779 -281.567387) (xy 361.247096 -281.518667)
			(xy 361.261572 -281.471575) (xy 361.282885 -281.427156) (xy 361.31056 -281.386398) (xy 361.326938 -281.367992)
			(xy 361.333248 -281.360549) (xy 361.340173 -281.34232) (xy 361.339815 -281.322824) (xy 361.332225 -281.304862)
			(xy 361.325668 -281.297634) (xy 361.307164 -281.278232) (xy 361.275837 -281.234723) (xy 361.251652 -281.186875)
			(xy 361.235195 -281.135849) (xy 361.226868 -281.082887) (xy 361.226354 -281.05608) (xy 358.459334 -281.05608)
			(xy 358.453391 -281.060398) (xy 358.407117 -281.083976) (xy 358.357724 -281.100024) (xy 358.306429 -281.108149)
			(xy 358.254495 -281.108149) (xy 358.2032 -281.100024) (xy 358.153807 -281.083976) (xy 358.107533 -281.060398)
			(xy 358.065517 -281.029872) (xy 358.028794 -280.993149) (xy 357.998268 -280.951133) (xy 357.97469 -280.904859)
			(xy 357.958642 -280.855466) (xy 357.950517 -280.804171) (xy 357.950008 -280.778204) (xy 357.950481 -280.753548)
			(xy 357.957799 -280.704782) (xy 357.972274 -280.657642) (xy 357.993585 -280.613172) (xy 358.021259 -280.572358)
			(xy 358.037638 -280.553922) (xy 358.043897 -280.546497) (xy 358.050828 -280.528373) (xy 358.050548 -280.508971)
			(xy 358.043098 -280.491055) (xy 358.036622 -280.483818) (xy 358.01812 -280.464414) (xy 357.986791 -280.420907)
			(xy 357.962604 -280.373059) (xy 357.946147 -280.322034) (xy 357.93782 -280.269071) (xy 357.937308 -280.242264)
			(xy 356.129082 -280.242264) (xy 355.752654 -280.618692) (xy 355.765862 -280.650188) (xy 355.77401 -280.670534)
			(xy 355.785462 -280.712839) (xy 355.791206 -280.756289) (xy 355.791516 -280.778204) (xy 355.790983 -280.804779)
			(xy 355.782469 -280.857243) (xy 355.765662 -280.907665) (xy 355.740995 -280.954745) (xy 355.725476 -280.976324)
			(xy 355.725476 -281.65044) (xy 355.740381 -281.66902) (xy 355.765459 -281.709515) (xy 355.784698 -281.753089)
			(xy 355.797728 -281.798904) (xy 355.8043 -281.84608) (xy 355.804724 -281.869896) (xy 357.937308 -281.869896)
			(xy 357.937756 -281.843976) (xy 357.945549 -281.792725) (xy 357.960956 -281.743227) (xy 357.983627 -281.696608)
			(xy 358.013049 -281.653925) (xy 358.048551 -281.61615) (xy 358.089328 -281.58414) (xy 358.134452 -281.558622)
			(xy 358.1829 -281.540177) (xy 358.23357 -281.529223) (xy 358.28531 -281.526009) (xy 358.336946 -281.530608)
			(xy 358.387303 -281.542917) (xy 358.435239 -281.562654) (xy 358.479664 -281.589372) (xy 358.519568 -281.622464)
			(xy 358.554045 -281.661177) (xy 358.582311 -281.704633) (xy 358.603725 -281.751844) (xy 358.6178 -281.801737)
			(xy 358.624215 -281.853178) (xy 358.622826 -281.905) (xy 358.613664 -281.956024) (xy 358.596937 -282.005091)
			(xy 358.573025 -282.051087) (xy 358.542471 -282.092966) (xy 358.524556 -282.111704) (xy 358.518032 -282.1189)
			(xy 358.510526 -282.1368) (xy 358.510182 -282.156206) (xy 358.517048 -282.174361) (xy 358.523286 -282.181808)
			(xy 358.539688 -282.200194) (xy 358.567363 -282.240957) (xy 358.588674 -282.28538) (xy 358.603147 -282.332477)
			(xy 358.610463 -282.381201) (xy 358.610916 -282.405836) (xy 358.610407 -282.431803) (xy 358.602282 -282.483098)
			(xy 358.586234 -282.532491) (xy 358.562656 -282.578765) (xy 358.53213 -282.620781) (xy 358.495407 -282.657504)
			(xy 358.458985 -282.683966) (xy 361.226354 -282.683966) (xy 361.226834 -282.658267) (xy 361.234495 -282.607443)
			(xy 361.249644 -282.558329) (xy 361.271945 -282.512021) (xy 361.300898 -282.469554) (xy 361.335858 -282.431877)
			(xy 361.376042 -282.399831) (xy 361.420554 -282.374132) (xy 361.468399 -282.355355) (xy 361.518508 -282.343917)
			(xy 361.569762 -282.340077) (xy 361.621016 -282.343917) (xy 361.671125 -282.355355) (xy 361.71897 -282.374132)
			(xy 361.763482 -282.399831) (xy 361.803666 -282.431877) (xy 361.838626 -282.469554) (xy 361.867579 -282.512021)
			(xy 361.88988 -282.558329) (xy 361.905029 -282.607443) (xy 361.91269 -282.658267) (xy 361.912858 -282.667258)
			(xy 364.045733 -282.667258) (xy 364.052151 -282.615826) (xy 364.066225 -282.565943) (xy 364.087637 -282.518743)
			(xy 364.1159 -282.475296) (xy 364.150372 -282.436591) (xy 364.19027 -282.403506) (xy 364.234686 -282.376794)
			(xy 364.282613 -282.357061) (xy 364.332962 -282.344755) (xy 364.384588 -282.340156) (xy 364.436318 -282.343368)
			(xy 364.486979 -282.354319) (xy 364.535418 -282.37276) (xy 364.580535 -282.398271) (xy 364.621306 -282.430274)
			(xy 364.656803 -282.46804) (xy 364.686221 -282.510713) (xy 364.708892 -282.557323) (xy 364.7243 -282.60681)
			(xy 364.732095 -282.658051) (xy 364.73257 -282.683966) (xy 364.732046 -282.710772) (xy 364.723719 -282.763732)
			(xy 364.707262 -282.814755) (xy 364.683074 -282.8626) (xy 364.651745 -282.906104) (xy 364.633256 -282.92552)
			(xy 364.626757 -282.932745) (xy 364.619279 -282.950666) (xy 364.618999 -282.970081) (xy 364.625956 -282.98821)
			(xy 364.63224 -282.995624) (xy 364.648625 -283.014059) (xy 364.676335 -283.054856) (xy 364.697665 -283.099324)
			(xy 364.712139 -283.14647) (xy 364.719434 -283.195246) (xy 364.71987 -283.219906) (xy 364.719361 -283.245873)
			(xy 364.711236 -283.297168) (xy 364.695188 -283.346561) (xy 364.67161 -283.392835) (xy 364.641084 -283.434851)
			(xy 364.604361 -283.471574) (xy 364.562345 -283.5021) (xy 364.516071 -283.525678) (xy 364.466678 -283.541726)
			(xy 364.415383 -283.549851) (xy 364.363449 -283.549851) (xy 364.312154 -283.541726) (xy 364.262761 -283.525678)
			(xy 364.216487 -283.5021) (xy 364.174471 -283.471574) (xy 364.137748 -283.434851) (xy 364.107222 -283.392835)
			(xy 364.083644 -283.346561) (xy 364.067596 -283.297168) (xy 364.059471 -283.245873) (xy 364.058962 -283.219906)
			(xy 364.059436 -283.195273) (xy 364.066755 -283.146554) (xy 364.081231 -283.099462) (xy 364.102542 -283.055044)
			(xy 364.130216 -283.014285) (xy 364.146592 -282.995878) (xy 364.152892 -282.988464) (xy 364.159824 -282.970301)
			(xy 364.159468 -282.950863) (xy 364.151876 -282.932966) (xy 364.145322 -282.925774) (xy 364.127442 -282.907008)
			(xy 364.096898 -282.865134) (xy 364.072994 -282.819144) (xy 364.056274 -282.770085) (xy 364.047118 -282.71907)
			(xy 364.045733 -282.667258) (xy 361.912858 -282.667258) (xy 361.91317 -282.683966) (xy 361.912646 -282.710772)
			(xy 361.904319 -282.763732) (xy 361.887862 -282.814755) (xy 361.863674 -282.8626) (xy 361.832345 -282.906104)
			(xy 361.813856 -282.92552) (xy 361.807328 -282.932773) (xy 361.799722 -282.950719) (xy 361.79936 -282.970207)
			(xy 361.806293 -282.988424) (xy 361.812586 -282.995878) (xy 361.828974 -283.014276) (xy 361.856651 -283.055036)
			(xy 361.877964 -283.099456) (xy 361.892441 -283.14655) (xy 361.899761 -283.195272) (xy 361.900216 -283.219906)
			(xy 361.899707 -283.245873) (xy 361.891582 -283.297168) (xy 361.875534 -283.346561) (xy 361.851956 -283.392835)
			(xy 361.82143 -283.434851) (xy 361.784707 -283.471574) (xy 361.742691 -283.5021) (xy 361.696417 -283.525678)
			(xy 361.647024 -283.541726) (xy 361.595729 -283.549851) (xy 361.543795 -283.549851) (xy 361.4925 -283.541726)
			(xy 361.443107 -283.525678) (xy 361.396833 -283.5021) (xy 361.354817 -283.471574) (xy 361.318094 -283.434851)
			(xy 361.287568 -283.392835) (xy 361.26399 -283.346561) (xy 361.247942 -283.297168) (xy 361.239817 -283.245873)
			(xy 361.239308 -283.219906) (xy 361.23977 -283.195272) (xy 361.24709 -283.146552) (xy 361.261568 -283.09946)
			(xy 361.282882 -283.055042) (xy 361.31056 -283.014284) (xy 361.326938 -282.995878) (xy 361.333262 -282.988445)
			(xy 361.340185 -282.970212) (xy 361.339823 -282.950712) (xy 361.332228 -282.932748) (xy 361.325668 -282.92552)
			(xy 361.307157 -282.906124) (xy 361.275832 -282.862613) (xy 361.251647 -282.814763) (xy 361.235192 -282.763737)
			(xy 361.226867 -282.710773) (xy 361.226354 -282.683966) (xy 358.458985 -282.683966) (xy 358.453391 -282.68803)
			(xy 358.407117 -282.711608) (xy 358.357724 -282.727656) (xy 358.306429 -282.735781) (xy 358.254495 -282.735781)
			(xy 358.2032 -282.727656) (xy 358.153807 -282.711608) (xy 358.107533 -282.68803) (xy 358.065517 -282.657504)
			(xy 358.028794 -282.620781) (xy 357.998268 -282.578765) (xy 357.97469 -282.532491) (xy 357.958642 -282.483098)
			(xy 357.950517 -282.431803) (xy 357.950008 -282.405836) (xy 357.95044 -282.381178) (xy 357.957768 -282.33241)
			(xy 357.972253 -282.28527) (xy 357.993572 -282.240801) (xy 358.021256 -282.199988) (xy 358.037638 -282.181554)
			(xy 358.043866 -282.174105) (xy 358.050801 -282.155992) (xy 358.050531 -282.136599) (xy 358.043092 -282.118687)
			(xy 358.036622 -282.11145) (xy 358.018135 -282.092032) (xy 357.986804 -282.048529) (xy 357.962614 -282.000684)
			(xy 357.946154 -281.949662) (xy 357.937823 -281.896702) (xy 357.937308 -281.869896) (xy 355.804724 -281.869896)
			(xy 355.804193 -281.897611) (xy 355.795284 -281.95232) (xy 355.777696 -282.004886) (xy 355.751887 -282.053941)
			(xy 355.735636 -282.076398) (xy 355.725476 -282.08986) (xy 355.725476 -282.206954) (xy 355.734366 -282.219908)
			(xy 355.747858 -282.240591) (xy 355.769219 -282.285112) (xy 355.783726 -282.332313) (xy 355.791059 -282.381146)
			(xy 355.791516 -282.405836) (xy 355.790981 -282.43241) (xy 355.782462 -282.484871) (xy 355.765651 -282.535291)
			(xy 355.740981 -282.582367) (xy 355.725476 -282.603956) (xy 355.725476 -282.981146) (xy 355.644958 -283.061664)
			(xy 355.634845 -283.072477) (xy 355.620782 -283.098516) (xy 355.614778 -283.127494) (xy 355.617337 -283.156976)
			(xy 355.628244 -283.184487) (xy 355.646582 -283.207713) (xy 355.65842 -283.216604) (xy 355.680603 -283.232815)
			(xy 355.719995 -283.271112) (xy 355.75279 -283.31519) (xy 355.778152 -283.363925) (xy 355.795434 -283.416076)
			(xy 355.804196 -283.470312) (xy 355.804724 -283.497782) (xy 357.937308 -283.497782) (xy 357.937767 -283.471863)
			(xy 357.945561 -283.420615) (xy 357.960969 -283.37112) (xy 357.983641 -283.324503) (xy 358.013063 -283.281824)
			(xy 358.048564 -283.244051) (xy 358.08934 -283.212043) (xy 358.134463 -283.186528) (xy 358.182909 -283.168084)
			(xy 358.233576 -283.157132) (xy 358.285314 -283.153919) (xy 358.336947 -283.158519) (xy 358.387303 -283.170827)
			(xy 358.435236 -283.190564) (xy 358.479658 -283.217281) (xy 358.519561 -283.250371) (xy 358.554036 -283.289082)
			(xy 358.582301 -283.332536) (xy 358.603715 -283.379744) (xy 358.617789 -283.429635) (xy 358.624205 -283.481074)
			(xy 358.622817 -283.532893) (xy 358.613656 -283.583915) (xy 358.596931 -283.63298) (xy 358.573021 -283.678974)
			(xy 358.54247 -283.720852) (xy 358.524556 -283.73959) (xy 358.518046 -283.746797) (xy 358.510537 -283.764691)
			(xy 358.510189 -283.784095) (xy 358.517051 -283.802247) (xy 358.523286 -283.809694) (xy 358.539681 -283.828086)
			(xy 358.567357 -283.868848) (xy 358.588669 -283.913269) (xy 358.603144 -283.960364) (xy 358.610462 -284.009087)
			(xy 358.610916 -284.033722) (xy 358.610407 -284.059689) (xy 358.602282 -284.110984) (xy 358.586234 -284.160377)
			(xy 358.562656 -284.206651) (xy 358.53213 -284.248667) (xy 358.495407 -284.28539) (xy 358.459334 -284.311598)
			(xy 361.226354 -284.311598) (xy 361.226834 -284.285899) (xy 361.234495 -284.235075) (xy 361.249644 -284.185961)
			(xy 361.271945 -284.139653) (xy 361.300898 -284.097186) (xy 361.335858 -284.059509) (xy 361.376042 -284.027463)
			(xy 361.420554 -284.001764) (xy 361.468399 -283.982987) (xy 361.518508 -283.971549) (xy 361.569762 -283.967709)
			(xy 361.621016 -283.971549) (xy 361.671125 -283.982987) (xy 361.71897 -284.001764) (xy 361.763482 -284.027463)
			(xy 361.803666 -284.059509) (xy 361.838626 -284.097186) (xy 361.867579 -284.139653) (xy 361.88988 -284.185961)
			(xy 361.905029 -284.235075) (xy 361.91269 -284.285899) (xy 361.912858 -284.294869) (xy 364.045732 -284.294869)
			(xy 364.052149 -284.243435) (xy 364.066223 -284.19355) (xy 364.087635 -284.146347) (xy 364.115899 -284.102898)
			(xy 364.150372 -284.064191) (xy 364.190271 -284.031105) (xy 364.23469 -284.004392) (xy 364.282619 -283.984659)
			(xy 364.332969 -283.972354) (xy 364.384598 -283.967756) (xy 364.43633 -283.97097) (xy 364.486992 -283.981923)
			(xy 364.535432 -284.000367) (xy 364.58055 -284.025881) (xy 364.621321 -284.057888) (xy 364.656817 -284.095658)
			(xy 364.686234 -284.138334) (xy 364.708902 -284.184947) (xy 364.724306 -284.234438) (xy 364.732097 -284.285682)
			(xy 364.73257 -284.311598) (xy 364.732066 -284.338404) (xy 364.723734 -284.391366) (xy 364.707272 -284.442389)
			(xy 364.68308 -284.490234) (xy 364.651747 -284.533737) (xy 364.633256 -284.553152) (xy 364.626725 -284.560352)
			(xy 364.619253 -284.578284) (xy 364.618981 -284.597708) (xy 364.62595 -284.615842) (xy 364.63224 -284.623256)
			(xy 364.64864 -284.641678) (xy 364.676348 -284.682479) (xy 364.697675 -284.72695) (xy 364.712145 -284.774099)
			(xy 364.719436 -284.822877) (xy 364.71987 -284.847538) (xy 364.719361 -284.873505) (xy 364.711236 -284.9248)
			(xy 364.695188 -284.974193) (xy 364.67161 -285.020467) (xy 364.641084 -285.062483) (xy 364.604361 -285.099206)
			(xy 364.562345 -285.129732) (xy 364.516071 -285.15331) (xy 364.466678 -285.169358) (xy 364.415383 -285.177483)
			(xy 364.363449 -285.177483) (xy 364.312154 -285.169358) (xy 364.262761 -285.15331) (xy 364.216487 -285.129732)
			(xy 364.174471 -285.099206) (xy 364.137748 -285.062483) (xy 364.107222 -285.020467) (xy 364.083644 -284.974193)
			(xy 364.067596 -284.9248) (xy 364.059471 -284.873505) (xy 364.058962 -284.847538) (xy 364.059395 -284.822903)
			(xy 364.066724 -284.774182) (xy 364.081209 -284.72709) (xy 364.102529 -284.682673) (xy 364.130212 -284.641916)
			(xy 364.146592 -284.62351) (xy 364.152861 -284.616072) (xy 364.159798 -284.59792) (xy 364.159451 -284.57849)
			(xy 364.15187 -284.560597) (xy 364.145322 -284.553406) (xy 364.127456 -284.534625) (xy 364.096908 -284.49275)
			(xy 364.073001 -284.44676) (xy 364.056278 -284.3977) (xy 364.047119 -284.346683) (xy 364.045732 -284.294869)
			(xy 361.912858 -284.294869) (xy 361.91317 -284.311598) (xy 361.912666 -284.338404) (xy 361.904334 -284.391366)
			(xy 361.887872 -284.442389) (xy 361.86368 -284.490234) (xy 361.832347 -284.533737) (xy 361.813856 -284.553152)
			(xy 361.807297 -284.56038) (xy 361.799696 -284.578337) (xy 361.799342 -284.597834) (xy 361.806286 -284.616056)
			(xy 361.812586 -284.62351) (xy 361.828989 -284.641895) (xy 361.856664 -284.682659) (xy 361.877974 -284.727082)
			(xy 361.892448 -284.774179) (xy 361.899763 -284.822903) (xy 361.900216 -284.847538) (xy 361.899707 -284.873505)
			(xy 361.891582 -284.9248) (xy 361.875534 -284.974193) (xy 361.851956 -285.020467) (xy 361.82143 -285.062483)
			(xy 361.784707 -285.099206) (xy 361.742691 -285.129732) (xy 361.696417 -285.15331) (xy 361.647024 -285.169358)
			(xy 361.595729 -285.177483) (xy 361.543795 -285.177483) (xy 361.4925 -285.169358) (xy 361.443107 -285.15331)
			(xy 361.396833 -285.129732) (xy 361.354817 -285.099206) (xy 361.318094 -285.062483) (xy 361.287568 -285.020467)
			(xy 361.26399 -284.974193) (xy 361.247942 -284.9248) (xy 361.239817 -284.873505) (xy 361.239308 -284.847538)
			(xy 361.239729 -284.822903) (xy 361.247059 -284.774181) (xy 361.261546 -284.727088) (xy 361.28287 -284.682671)
			(xy 361.310556 -284.641914) (xy 361.326938 -284.62351) (xy 361.333231 -284.616054) (xy 361.340158 -284.597831)
			(xy 361.339805 -284.57834) (xy 361.332222 -284.56038) (xy 361.325668 -284.553152) (xy 361.307173 -284.533742)
			(xy 361.275845 -284.490235) (xy 361.251658 -284.442389) (xy 361.235199 -284.391365) (xy 361.226869 -284.338404)
			(xy 361.226354 -284.311598) (xy 358.459334 -284.311598) (xy 358.453391 -284.315916) (xy 358.407117 -284.339494)
			(xy 358.357724 -284.355542) (xy 358.306429 -284.363667) (xy 358.254495 -284.363667) (xy 358.2032 -284.355542)
			(xy 358.153807 -284.339494) (xy 358.107533 -284.315916) (xy 358.065517 -284.28539) (xy 358.028794 -284.248667)
			(xy 357.998268 -284.206651) (xy 357.97469 -284.160377) (xy 357.958642 -284.110984) (xy 357.950517 -284.059689)
			(xy 357.950008 -284.033722) (xy 357.950432 -284.009064) (xy 357.957762 -283.960296) (xy 357.972248 -283.913155)
			(xy 357.99357 -283.868686) (xy 358.021255 -283.827874) (xy 358.037638 -283.80944) (xy 358.043879 -283.802001)
			(xy 358.050813 -283.783884) (xy 358.050538 -283.764487) (xy 358.043094 -283.746573) (xy 358.036622 -283.739336)
			(xy 358.018128 -283.719924) (xy 357.986798 -283.676419) (xy 357.96261 -283.628573) (xy 357.946151 -283.57755)
			(xy 357.937822 -283.524588) (xy 357.937308 -283.497782) (xy 355.804724 -283.497782) (xy 355.804207 -283.524624)
			(xy 355.795857 -283.577656) (xy 355.779356 -283.628741) (xy 355.755107 -283.676637) (xy 355.7237 -283.720177)
			(xy 355.705156 -283.73959) (xy 355.698607 -283.746783) (xy 355.691025 -283.764678) (xy 355.690673 -283.784109)
			(xy 355.697604 -283.802267) (xy 355.703886 -283.809694) (xy 355.720262 -283.828101) (xy 355.747936 -283.86886)
			(xy 355.769247 -283.913278) (xy 355.783721 -283.96037) (xy 355.791038 -284.009089) (xy 355.791516 -284.033722)
			(xy 355.791007 -284.059689) (xy 355.782882 -284.110984) (xy 355.766834 -284.160377) (xy 355.743256 -284.206651)
			(xy 355.71273 -284.248667) (xy 355.676007 -284.28539) (xy 355.633991 -284.315916) (xy 355.587717 -284.339494)
			(xy 355.538324 -284.355542) (xy 355.487029 -284.363667) (xy 355.435095 -284.363667) (xy 355.3838 -284.355542)
			(xy 355.334407 -284.339494) (xy 355.288133 -284.315916) (xy 355.246117 -284.28539) (xy 355.209394 -284.248667)
			(xy 355.178868 -284.206651) (xy 355.15529 -284.160377) (xy 355.139242 -284.110984) (xy 355.131117 -284.059689)
			(xy 355.130608 -284.033722) (xy 355.131043 -284.009062) (xy 355.138338 -283.960287) (xy 355.152812 -283.91314)
			(xy 355.174144 -283.868674) (xy 355.201858 -283.82788) (xy 355.218238 -283.80944) (xy 355.224527 -283.802027)
			(xy 355.231493 -283.783896) (xy 355.231217 -283.764474) (xy 355.223739 -283.746548) (xy 355.217222 -283.739336)
			(xy 355.201133 -283.72255) (xy 355.173165 -283.685405) (xy 355.150466 -283.644826) (xy 355.133451 -283.601555)
			(xy 355.12756 -283.579062) (xy 355.124724 -283.569561) (xy 355.113034 -283.553568) (xy 355.09616 -283.543191)
			(xy 355.076614 -283.539972) (xy 355.066854 -283.541724) (xy 355.048262 -283.545793) (xy 355.010447 -283.550117)
			(xy 354.991416 -283.55036) (xy 354.963682 -283.549788) (xy 354.908993 -283.540519) (xy 354.856618 -283.522254)
			(xy 354.808025 -283.495506) (xy 354.78593 -283.478732) (xy 354.309172 -283.478732) (xy 354.261166 -283.526738)
			(xy 354.261166 -283.775404) (xy 353.893374 -284.143196) (xy 353.889564 -284.153102) (xy 353.87912 -284.178537)
			(xy 353.851038 -284.225806) (xy 353.815519 -284.267774) (xy 353.773543 -284.303283) (xy 353.726267 -284.331354)
			(xy 353.700842 -284.341824) (xy 353.690936 -284.345634) (xy 353.382326 -284.654244) (xy 353.400868 -284.687772)
			(xy 353.413802 -284.712395) (xy 353.432145 -284.764898) (xy 353.441444 -284.81973) (xy 353.442016 -284.847538)
			(xy 353.441504 -284.87394) (xy 353.433118 -284.926074) (xy 353.41655 -284.976211) (xy 353.392221 -285.023077)
			(xy 353.36075 -285.065478) (xy 353.342194 -285.084266) (xy 353.342194 -285.125414) (xy 355.117908 -285.125414)
			(xy 355.118342 -285.099492) (xy 355.126133 -285.048238) (xy 355.141538 -284.998737) (xy 355.164209 -284.952113)
			(xy 355.193631 -284.909427) (xy 355.229134 -284.871648) (xy 355.269912 -284.839635) (xy 355.315039 -284.814114)
			(xy 355.363489 -284.795667) (xy 355.414161 -284.784711) (xy 355.465905 -284.781496) (xy 355.517543 -284.786095)
			(xy 355.567904 -284.798404) (xy 355.615843 -284.818142) (xy 355.66027 -284.844861) (xy 355.700177 -284.877955)
			(xy 355.734656 -284.916671) (xy 355.762923 -284.960129) (xy 355.784338 -285.007343) (xy 355.798413 -285.057239)
			(xy 355.804828 -285.108684) (xy 355.804379 -285.125414) (xy 357.937308 -285.125414) (xy 357.937742 -285.099492)
			(xy 357.945533 -285.048238) (xy 357.960938 -284.998737) (xy 357.983609 -284.952113) (xy 358.013031 -284.909427)
			(xy 358.048534 -284.871648) (xy 358.089312 -284.839635) (xy 358.134439 -284.814114) (xy 358.182889 -284.795667)
			(xy 358.233561 -284.784711) (xy 358.285305 -284.781496) (xy 358.336943 -284.786095) (xy 358.387304 -284.798404)
			(xy 358.435243 -284.818142) (xy 358.47967 -284.844861) (xy 358.519577 -284.877955) (xy 358.554056 -284.916671)
			(xy 358.582323 -284.960129) (xy 358.603738 -285.007343) (xy 358.617813 -285.057239) (xy 358.624228 -285.108684)
			(xy 358.622838 -285.160508) (xy 358.613674 -285.211535) (xy 358.596945 -285.260605) (xy 358.57303 -285.306603)
			(xy 358.542473 -285.348483) (xy 358.524556 -285.367222) (xy 358.518015 -285.374404) (xy 358.510512 -285.39231)
			(xy 358.510172 -285.411722) (xy 358.517045 -285.429879) (xy 358.523286 -285.437326) (xy 358.539696 -285.455705)
			(xy 358.56737 -285.49647) (xy 358.588679 -285.540895) (xy 358.603151 -285.587993) (xy 358.610464 -285.636718)
			(xy 358.610916 -285.661354) (xy 358.610407 -285.687321) (xy 358.602282 -285.738616) (xy 358.586234 -285.788009)
			(xy 358.562656 -285.834283) (xy 358.53213 -285.876299) (xy 358.495407 -285.913022) (xy 358.458985 -285.939484)
			(xy 361.226354 -285.939484) (xy 361.226834 -285.913785) (xy 361.234495 -285.862961) (xy 361.249644 -285.813847)
			(xy 361.271945 -285.767539) (xy 361.300898 -285.725072) (xy 361.335858 -285.687395) (xy 361.376042 -285.655349)
			(xy 361.420554 -285.62965) (xy 361.468399 -285.610873) (xy 361.518508 -285.599435) (xy 361.569762 -285.595595)
			(xy 361.621016 -285.599435) (xy 361.671125 -285.610873) (xy 361.71897 -285.62965) (xy 361.763482 -285.655349)
			(xy 361.803666 -285.687395) (xy 361.838626 -285.725072) (xy 361.867579 -285.767539) (xy 361.88988 -285.813847)
			(xy 361.905029 -285.862961) (xy 361.91269 -285.913785) (xy 361.912858 -285.922764) (xy 364.045733 -285.922764)
			(xy 364.05215 -285.871331) (xy 364.066224 -285.821447) (xy 364.087636 -285.774245) (xy 364.115899 -285.730797)
			(xy 364.150372 -285.692091) (xy 364.19027 -285.659006) (xy 364.234688 -285.632293) (xy 364.282616 -285.61256)
			(xy 364.332966 -285.600254) (xy 364.384593 -285.595656) (xy 364.436325 -285.598869) (xy 364.486986 -285.609822)
			(xy 364.535426 -285.628264) (xy 364.580544 -285.653777) (xy 364.621314 -285.685782) (xy 364.656811 -285.72355)
			(xy 364.686228 -285.766225) (xy 364.708897 -285.812837) (xy 364.724303 -285.862326) (xy 364.732096 -285.913568)
			(xy 364.73257 -285.939484) (xy 364.732057 -285.96629) (xy 364.723727 -286.019251) (xy 364.707268 -286.070274)
			(xy 364.683078 -286.118119) (xy 364.651746 -286.161623) (xy 364.633256 -286.181038) (xy 364.626739 -286.188249)
			(xy 364.619265 -286.206176) (xy 364.618989 -286.225597) (xy 364.625953 -286.243728) (xy 364.63224 -286.251142)
			(xy 364.648633 -286.26957) (xy 364.676343 -286.310369) (xy 364.697671 -286.354838) (xy 364.712142 -286.401987)
			(xy 364.719435 -286.450764) (xy 364.71987 -286.475424) (xy 364.719361 -286.501391) (xy 364.711236 -286.552686)
			(xy 364.695188 -286.602079) (xy 364.67161 -286.648353) (xy 364.641084 -286.690369) (xy 364.604361 -286.727092)
			(xy 364.562345 -286.757618) (xy 364.516071 -286.781196) (xy 364.466678 -286.797244) (xy 364.415383 -286.805369)
			(xy 364.363449 -286.805369) (xy 364.312154 -286.797244) (xy 364.262761 -286.781196) (xy 364.216487 -286.757618)
			(xy 364.174471 -286.727092) (xy 364.137748 -286.690369) (xy 364.107222 -286.648353) (xy 364.083644 -286.602079)
			(xy 364.067596 -286.552686) (xy 364.059471 -286.501391) (xy 364.058962 -286.475424) (xy 364.059447 -286.450791)
			(xy 364.066763 -286.402072) (xy 364.081236 -286.354981) (xy 364.102545 -286.310563) (xy 364.130217 -286.269803)
			(xy 364.146592 -286.251396) (xy 364.152875 -286.243968) (xy 364.159809 -286.225811) (xy 364.159458 -286.206378)
			(xy 364.151873 -286.188484) (xy 364.145322 -286.181292) (xy 364.12745 -286.162517) (xy 364.096904 -286.120643)
			(xy 364.072998 -286.074653) (xy 364.056277 -286.025593) (xy 364.047119 -285.974577) (xy 364.045733 -285.922764)
			(xy 361.912858 -285.922764) (xy 361.91317 -285.939484) (xy 361.912657 -285.96629) (xy 361.904327 -286.019251)
			(xy 361.887868 -286.070274) (xy 361.863678 -286.118119) (xy 361.832346 -286.161623) (xy 361.813856 -286.181038)
			(xy 361.80731 -286.188277) (xy 361.799707 -286.206229) (xy 361.79935 -286.225722) (xy 361.806289 -286.243942)
			(xy 361.812586 -286.251396) (xy 361.828982 -286.269787) (xy 361.856658 -286.310549) (xy 361.87797 -286.354971)
			(xy 361.892445 -286.402066) (xy 361.899762 -286.450789) (xy 361.900216 -286.475424) (xy 361.899707 -286.501391)
			(xy 361.891582 -286.552686) (xy 361.875534 -286.602079) (xy 361.851956 -286.648353) (xy 361.82143 -286.690369)
			(xy 361.784707 -286.727092) (xy 361.742691 -286.757618) (xy 361.696417 -286.781196) (xy 361.647024 -286.797244)
			(xy 361.595729 -286.805369) (xy 361.543795 -286.805369) (xy 361.4925 -286.797244) (xy 361.443107 -286.781196)
			(xy 361.396833 -286.757618) (xy 361.354817 -286.727092) (xy 361.318094 -286.690369) (xy 361.287568 -286.648353)
			(xy 361.26399 -286.602079) (xy 361.247942 -286.552686) (xy 361.239817 -286.501391) (xy 361.239308 -286.475424)
			(xy 361.239781 -286.450791) (xy 361.247098 -286.402071) (xy 361.261573 -286.354979) (xy 361.282885 -286.310561)
			(xy 361.310561 -286.269802) (xy 361.326938 -286.251396) (xy 361.333245 -286.24395) (xy 361.34017 -286.225723)
			(xy 361.339813 -286.206228) (xy 361.332225 -286.188266) (xy 361.325668 -286.181038) (xy 361.307166 -286.161634)
			(xy 361.275839 -286.118126) (xy 361.251653 -286.070278) (xy 361.235196 -286.019253) (xy 361.226868 -285.966291)
			(xy 361.226354 -285.939484) (xy 358.458985 -285.939484) (xy 358.453391 -285.943548) (xy 358.407117 -285.967126)
			(xy 358.357724 -285.983174) (xy 358.306429 -285.991299) (xy 358.254495 -285.991299) (xy 358.2032 -285.983174)
			(xy 358.153807 -285.967126) (xy 358.107533 -285.943548) (xy 358.065517 -285.913022) (xy 358.028794 -285.876299)
			(xy 357.998268 -285.834283) (xy 357.97469 -285.788009) (xy 357.958642 -285.738616) (xy 357.950517 -285.687321)
			(xy 357.950008 -285.661354) (xy 357.950451 -285.636697) (xy 357.957777 -285.587929) (xy 357.972258 -285.540789)
			(xy 357.993576 -285.49632) (xy 358.021257 -285.455507) (xy 358.037638 -285.437072) (xy 358.043947 -285.429684)
			(xy 358.050869 -285.411543) (xy 358.050575 -285.392128) (xy 358.043107 -285.374205) (xy 358.036622 -285.366968)
			(xy 358.018144 -285.347542) (xy 357.986811 -285.304041) (xy 357.96262 -285.256199) (xy 357.946158 -285.205178)
			(xy 357.937824 -285.152219) (xy 357.937308 -285.125414) (xy 355.804379 -285.125414) (xy 355.803438 -285.160508)
			(xy 355.794274 -285.211535) (xy 355.777545 -285.260605) (xy 355.75363 -285.306603) (xy 355.723073 -285.348483)
			(xy 355.705156 -285.367222) (xy 355.698615 -285.374404) (xy 355.691112 -285.39231) (xy 355.690772 -285.411722)
			(xy 355.697645 -285.429879) (xy 355.703886 -285.437326) (xy 355.720296 -285.455705) (xy 355.74797 -285.49647)
			(xy 355.769279 -285.540895) (xy 355.783751 -285.587993) (xy 355.791064 -285.636718) (xy 355.791516 -285.661354)
			(xy 355.791007 -285.687321) (xy 355.782882 -285.738616) (xy 355.766834 -285.788009) (xy 355.743256 -285.834283)
			(xy 355.71273 -285.876299) (xy 355.676007 -285.913022) (xy 355.633991 -285.943548) (xy 355.587717 -285.967126)
			(xy 355.538324 -285.983174) (xy 355.487029 -285.991299) (xy 355.435095 -285.991299) (xy 355.3838 -285.983174)
			(xy 355.334407 -285.967126) (xy 355.288133 -285.943548) (xy 355.246117 -285.913022) (xy 355.209394 -285.876299)
			(xy 355.178868 -285.834283) (xy 355.15529 -285.788009) (xy 355.139242 -285.738616) (xy 355.131117 -285.687321)
			(xy 355.130608 -285.661354) (xy 355.131051 -285.636697) (xy 355.138377 -285.587929) (xy 355.152858 -285.540789)
			(xy 355.174176 -285.49632) (xy 355.201857 -285.455507) (xy 355.218238 -285.437072) (xy 355.224547 -285.429684)
			(xy 355.231469 -285.411543) (xy 355.231175 -285.392128) (xy 355.223707 -285.374205) (xy 355.217222 -285.366968)
			(xy 355.198744 -285.347542) (xy 355.167411 -285.304041) (xy 355.14322 -285.256199) (xy 355.126758 -285.205178)
			(xy 355.118424 -285.152219) (xy 355.117908 -285.125414) (xy 353.342194 -285.125414) (xy 353.342194 -285.684976)
			(xy 353.363049 -285.704672) (xy 353.398546 -285.749728) (xy 353.426073 -285.80005) (xy 353.444867 -285.854244)
			(xy 353.454406 -285.910804) (xy 353.45497 -285.939484) (xy 353.454467 -285.966147) (xy 353.446228 -286.018833)
			(xy 353.429945 -286.069613) (xy 353.406009 -286.117266) (xy 353.374997 -286.160647) (xy 353.356672 -286.180022)
			(xy 353.342194 -286.194754) (xy 353.342194 -286.23768) (xy 353.355402 -286.252158) (xy 353.37164 -286.270544)
			(xy 353.399066 -286.31121) (xy 353.420183 -286.355482) (xy 353.434528 -286.402388) (xy 353.441786 -286.450899)
			(xy 353.44227 -286.475424) (xy 353.441756 -286.501863) (xy 353.433351 -286.554068) (xy 353.416742 -286.604269)
			(xy 353.392353 -286.651187) (xy 353.360807 -286.693623) (xy 353.342194 -286.712406) (xy 353.342194 -286.7533)
			(xy 355.117908 -286.7533) (xy 355.118353 -286.72738) (xy 355.126145 -286.676128) (xy 355.141552 -286.626629)
			(xy 355.164223 -286.580009) (xy 355.193645 -286.537326) (xy 355.229147 -286.499549) (xy 355.269924 -286.467539)
			(xy 355.315049 -286.44202) (xy 355.363498 -286.423574) (xy 355.414168 -286.41262) (xy 355.465909 -286.409406)
			(xy 355.517545 -286.414005) (xy 355.567904 -286.426314) (xy 355.61584 -286.446051) (xy 355.660265 -286.47277)
			(xy 355.70017 -286.505862) (xy 355.734647 -286.544576) (xy 355.762914 -286.588032) (xy 355.784328 -286.635244)
			(xy 355.798403 -286.685137) (xy 355.804818 -286.736579) (xy 355.80437 -286.7533) (xy 357.937308 -286.7533)
			(xy 357.937753 -286.72738) (xy 357.945545 -286.676128) (xy 357.960952 -286.626629) (xy 357.983623 -286.580009)
			(xy 358.013045 -286.537326) (xy 358.048547 -286.499549) (xy 358.089324 -286.467539) (xy 358.134449 -286.44202)
			(xy 358.182898 -286.423574) (xy 358.233568 -286.41262) (xy 358.285309 -286.409406) (xy 358.336945 -286.414005)
			(xy 358.387304 -286.426314) (xy 358.43524 -286.446051) (xy 358.479665 -286.47277) (xy 358.51957 -286.505862)
			(xy 358.554047 -286.544576) (xy 358.582314 -286.588032) (xy 358.603728 -286.635244) (xy 358.617803 -286.685137)
			(xy 358.624218 -286.736579) (xy 358.622829 -286.788402) (xy 358.613666 -286.839426) (xy 358.596939 -286.888494)
			(xy 358.573026 -286.93449) (xy 358.542471 -286.97637) (xy 358.524556 -286.995108) (xy 358.518028 -287.002301)
			(xy 358.510523 -287.020202) (xy 358.51018 -287.03961) (xy 358.517047 -287.057765) (xy 358.523286 -287.065212)
			(xy 358.53969 -287.083596) (xy 358.567364 -287.12436) (xy 358.588675 -287.168784) (xy 358.603148 -287.21588)
			(xy 358.610463 -287.264605) (xy 358.610916 -287.28924) (xy 358.610407 -287.315207) (xy 358.602282 -287.366502)
			(xy 358.586234 -287.415895) (xy 358.562656 -287.462169) (xy 358.53213 -287.504185) (xy 358.495407 -287.540908)
			(xy 358.453391 -287.571434) (xy 358.407117 -287.595012) (xy 358.357724 -287.61106) (xy 358.306429 -287.619185)
			(xy 358.254495 -287.619185) (xy 358.2032 -287.61106) (xy 358.153807 -287.595012) (xy 358.107533 -287.571434)
			(xy 358.065517 -287.540908) (xy 358.028794 -287.504185) (xy 357.998268 -287.462169) (xy 357.97469 -287.415895)
			(xy 357.958642 -287.366502) (xy 357.950517 -287.315207) (xy 357.950008 -287.28924) (xy 357.950443 -287.264582)
			(xy 357.95777 -287.215815) (xy 357.972254 -287.168674) (xy 357.993573 -287.124205) (xy 358.021256 -287.083392)
			(xy 358.037638 -287.064958) (xy 358.043862 -287.057506) (xy 358.050798 -287.039394) (xy 358.050528 -287.020002)
			(xy 358.043091 -287.00209) (xy 358.036622 -286.994854) (xy 358.018137 -286.975434) (xy 357.986806 -286.931931)
			(xy 357.962616 -286.884087) (xy 357.946155 -286.833066) (xy 357.937823 -286.780106) (xy 357.937308 -286.7533)
			(xy 355.80437 -286.7533) (xy 355.803429 -286.788402) (xy 355.794266 -286.839426) (xy 355.777539 -286.888494)
			(xy 355.753626 -286.93449) (xy 355.723071 -286.97637) (xy 355.705156 -286.995108) (xy 355.698628 -287.002301)
			(xy 355.691123 -287.020202) (xy 355.69078 -287.03961) (xy 355.697647 -287.057765) (xy 355.703886 -287.065212)
			(xy 355.72029 -287.083596) (xy 355.747964 -287.12436) (xy 355.769275 -287.168784) (xy 355.783748 -287.21588)
			(xy 355.791063 -287.264605) (xy 355.791516 -287.28924) (xy 355.791007 -287.315207) (xy 355.782882 -287.366502)
			(xy 355.766834 -287.415895) (xy 355.743256 -287.462169) (xy 355.71273 -287.504185) (xy 355.676007 -287.540908)
			(xy 355.633991 -287.571434) (xy 355.587717 -287.595012) (xy 355.538324 -287.61106) (xy 355.487029 -287.619185)
			(xy 355.435095 -287.619185) (xy 355.3838 -287.61106) (xy 355.334407 -287.595012) (xy 355.288133 -287.571434)
			(xy 355.246117 -287.540908) (xy 355.209394 -287.504185) (xy 355.178868 -287.462169) (xy 355.15529 -287.415895)
			(xy 355.139242 -287.366502) (xy 355.131117 -287.315207) (xy 355.130608 -287.28924) (xy 355.131043 -287.264582)
			(xy 355.13837 -287.215815) (xy 355.152854 -287.168674) (xy 355.174173 -287.124205) (xy 355.201856 -287.083392)
			(xy 355.218238 -287.064958) (xy 355.224462 -287.057506) (xy 355.231398 -287.039394) (xy 355.231128 -287.020002)
			(xy 355.223691 -287.00209) (xy 355.217222 -286.994854) (xy 355.198737 -286.975434) (xy 355.167406 -286.931931)
			(xy 355.143216 -286.884087) (xy 355.126755 -286.833066) (xy 355.118423 -286.780106) (xy 355.117908 -286.7533)
			(xy 353.342194 -286.7533) (xy 353.342194 -287.312608) (xy 353.363047 -287.332304) (xy 353.39854 -287.377362)
			(xy 353.426063 -287.427685) (xy 353.444851 -287.481878) (xy 353.454385 -287.538437) (xy 353.45497 -287.567116)
			(xy 353.454534 -287.592446) (xy 353.447137 -287.642562) (xy 353.440238 -287.666938) (xy 353.437952 -287.67405)
			(xy 353.437952 -288.049716) (xy 353.43846 -288.053526) (xy 353.44023 -288.065832) (xy 353.442139 -288.090624)
			(xy 353.44227 -288.103056) (xy 353.442134 -288.115488) (xy 353.440223 -288.140279) (xy 353.43846 -288.152586)
			(xy 353.437952 -288.156396) (xy 353.437952 -288.19729) (xy 353.42449 -288.210752) (xy 353.420426 -288.220912)
			(xy 353.409973 -288.246687) (xy 353.381718 -288.29459) (xy 353.345841 -288.337086) (xy 353.303354 -288.372973)
			(xy 353.255457 -288.40124) (xy 353.229672 -288.411666) (xy 353.219512 -288.41573) (xy 352.912172 -288.72307)
			(xy 352.930714 -288.756598) (xy 352.940228 -288.774282) (xy 352.955382 -288.81147) (xy 352.96094 -288.830766)
			(xy 352.965219 -288.844794) (xy 352.980574 -288.869768) (xy 353.002398 -288.889343) (xy 353.028887 -288.901904)
			(xy 353.057855 -288.906414) (xy 353.072446 -288.904934) (xy 353.09474 -288.902367) (xy 353.139605 -288.903238)
			(xy 353.183813 -288.910939) (xy 353.22633 -288.925292) (xy 353.26616 -288.94596) (xy 353.302374 -288.97246)
			(xy 353.318572 -288.987992) (xy 353.335242 -289.005311) (xy 353.363265 -289.044363) (xy 353.384535 -289.087468)
			(xy 353.398481 -289.133467) (xy 353.404461 -289.179077) (xy 353.758528 -289.179077) (xy 353.764949 -289.131919)
			(xy 353.77892 -289.086423) (xy 353.800073 -289.043789) (xy 353.827849 -289.005142) (xy 353.844352 -288.987992)
			(xy 353.862823 -288.970309) (xy 353.904704 -288.940984) (xy 353.951042 -288.919376) (xy 354.000428 -288.906143)
			(xy 354.051362 -288.901687) (xy 354.102296 -288.906143) (xy 354.151682 -288.919376) (xy 354.19802 -288.940984)
			(xy 354.239901 -288.970309) (xy 354.258372 -288.987992) (xy 354.275073 -289.005285) (xy 354.303105 -289.044339)
			(xy 354.324378 -289.087449) (xy 354.33832 -289.133456) (xy 354.344289 -289.179077) (xy 354.698328 -289.179077)
			(xy 354.704749 -289.131919) (xy 354.71872 -289.086423) (xy 354.739873 -289.043789) (xy 354.767649 -289.005142)
			(xy 354.784152 -288.987992) (xy 354.80035 -288.972424) (xy 354.836598 -288.945888) (xy 354.876474 -288.925199)
			(xy 354.919042 -288.910844) (xy 354.963303 -288.903158) (xy 355.008219 -288.902322) (xy 355.030532 -288.904934)
			(xy 355.045147 -288.906447) (xy 355.074177 -288.901979) (xy 355.100731 -288.889428) (xy 355.122611 -288.869834)
			(xy 355.138004 -288.84482) (xy 355.142292 -288.830766) (xy 355.149741 -288.805336) (xy 355.171616 -288.757075)
			(xy 355.200901 -288.712916) (xy 355.218492 -288.693098) (xy 355.224802 -288.685653) (xy 355.231734 -288.667426)
			(xy 355.231378 -288.647928) (xy 355.223783 -288.629966) (xy 355.217222 -288.62274) (xy 355.19873 -288.603326)
			(xy 355.1674 -288.559822) (xy 355.143211 -288.511976) (xy 355.126752 -288.460953) (xy 355.118422 -288.407992)
			(xy 355.117908 -288.381186) (xy 355.118388 -288.355487) (xy 355.126049 -288.304663) (xy 355.141198 -288.255549)
			(xy 355.163499 -288.209241) (xy 355.192452 -288.166774) (xy 355.227412 -288.129097) (xy 355.267596 -288.097051)
			(xy 355.312108 -288.071352) (xy 355.359953 -288.052575) (xy 355.410062 -288.041137) (xy 355.461316 -288.037297)
			(xy 355.51257 -288.041137) (xy 355.562679 -288.052575) (xy 355.610524 -288.071352) (xy 355.655036 -288.097051)
			(xy 355.69522 -288.129097) (xy 355.73018 -288.166774) (xy 355.759133 -288.209241) (xy 355.781434 -288.255549)
			(xy 355.796583 -288.304663) (xy 355.804244 -288.355487) (xy 355.804724 -288.381186) (xy 355.804359 -288.399729)
			(xy 357.047895 -288.399729) (xy 357.048054 -288.388806) (xy 357.047895 -288.365033) (xy 357.054329 -288.317933)
			(xy 357.068296 -288.272494) (xy 357.089429 -288.229912) (xy 357.117171 -288.191309) (xy 357.133652 -288.174176)
			(xy 357.152123 -288.156493) (xy 357.194004 -288.127168) (xy 357.240342 -288.10556) (xy 357.289728 -288.092327)
			(xy 357.340662 -288.087871) (xy 357.391596 -288.092327) (xy 357.440982 -288.10556) (xy 357.48732 -288.127168)
			(xy 357.529201 -288.156493) (xy 357.547672 -288.174176) (xy 357.564365 -288.191476) (xy 357.592398 -288.230528)
			(xy 357.613672 -288.273637) (xy 357.627616 -288.319642) (xy 357.633856 -288.367307) (xy 357.633524 -288.391346)
			(xy 357.633273 -288.401884) (xy 357.625404 -288.421418) (xy 357.618284 -288.429192) (xy 357.610814 -288.436128)
			(xy 357.592019 -288.443979) (xy 357.571651 -288.443979) (xy 357.552856 -288.436128) (xy 357.545386 -288.429192)
			(xy 357.540251 -288.423668) (xy 357.533154 -288.410369) (xy 357.531416 -288.40303) (xy 357.531416 -288.382456)
			(xy 357.53167 -288.381694) (xy 357.531261 -288.362875) (xy 357.523897 -288.325964) (xy 357.509474 -288.291199)
			(xy 357.488546 -288.259916) (xy 357.475536 -288.246312) (xy 357.461979 -288.233361) (xy 357.430808 -288.212534)
			(xy 357.396174 -288.198188) (xy 357.359406 -288.190874) (xy 357.321918 -288.190874) (xy 357.28515 -288.198188)
			(xy 357.250516 -288.212534) (xy 357.219345 -288.233361) (xy 357.205788 -288.246312) (xy 357.192969 -288.259775)
			(xy 357.172248 -288.290631) (xy 357.1579 -288.324918) (xy 357.15047 -288.361335) (xy 357.149908 -288.379916)
			(xy 357.149908 -288.380932) (xy 357.149654 -288.381186) (xy 357.149908 -288.38144) (xy 357.149908 -288.402268)
			(xy 357.148152 -288.409543) (xy 357.141049 -288.422709) (xy 357.135938 -288.428176) (xy 357.128468 -288.435112)
			(xy 357.109673 -288.442963) (xy 357.089305 -288.442963) (xy 357.07051 -288.435112) (xy 357.06304 -288.428176)
			(xy 357.055651 -288.420131) (xy 357.047895 -288.399729) (xy 355.804359 -288.399729) (xy 355.804197 -288.407991)
			(xy 355.795868 -288.460951) (xy 355.779411 -288.511973) (xy 355.755225 -288.559818) (xy 355.723897 -288.603323)
			(xy 355.70541 -288.62274) (xy 355.698858 -288.629975) (xy 355.691247 -288.647929) (xy 355.69089 -288.667426)
			(xy 355.697837 -288.685646) (xy 355.70414 -288.693098) (xy 355.721728 -288.712919) (xy 355.751022 -288.757072)
			(xy 355.772891 -288.805336) (xy 355.78034 -288.830766) (xy 355.784606 -288.844794) (xy 355.799985 -288.869746)
			(xy 355.821814 -288.889307) (xy 355.848297 -288.901867) (xy 355.877256 -288.906395) (xy 355.891846 -288.904934)
			(xy 355.914138 -288.902294) (xy 355.959018 -288.903136) (xy 356.003243 -288.910826) (xy 356.045773 -288.925184)
			(xy 356.08561 -288.945872) (xy 356.121818 -288.972404) (xy 356.137972 -288.987992) (xy 356.154673 -289.005285)
			(xy 356.182705 -289.044339) (xy 356.203978 -289.087449) (xy 356.21792 -289.133456) (xy 356.223889 -289.179077)
			(xy 356.577928 -289.179077) (xy 356.584349 -289.131919) (xy 356.59832 -289.086423) (xy 356.619473 -289.043789)
			(xy 356.647249 -289.005142) (xy 356.663752 -288.987992) (xy 356.682223 -288.970309) (xy 356.724104 -288.940984)
			(xy 356.770442 -288.919376) (xy 356.819828 -288.906143) (xy 356.870762 -288.901687) (xy 356.921696 -288.906143)
			(xy 356.971082 -288.919376) (xy 357.01742 -288.940984) (xy 357.059301 -288.970309) (xy 357.077772 -288.987992)
			(xy 357.082923 -288.993326) (xy 357.950262 -288.993326) (xy 357.950673 -288.968631) (xy 357.958017 -288.91979)
			(xy 357.972546 -288.872586) (xy 357.993936 -288.828068) (xy 358.021712 -288.787228) (xy 358.038146 -288.76879)
			(xy 358.051608 -288.754312) (xy 358.051608 -288.70402) (xy 358.039416 -288.689796) (xy 358.021507 -288.668)
			(xy 357.992875 -288.619401) (xy 357.973273 -288.56651) (xy 357.963317 -288.510989) (xy 357.962708 -288.482786)
			(xy 357.962708 -288.381186) (xy 357.963198 -288.356197) (xy 357.971017 -288.306834) (xy 357.986461 -288.259302)
			(xy 358.009151 -288.21477) (xy 358.038527 -288.174337) (xy 358.073867 -288.138997) (xy 358.1143 -288.109621)
			(xy 358.158832 -288.086931) (xy 358.206364 -288.071487) (xy 358.255727 -288.063668) (xy 358.305705 -288.063668)
			(xy 358.355068 -288.071487) (xy 358.4026 -288.086931) (xy 358.447132 -288.109621) (xy 358.487565 -288.138997)
			(xy 358.522905 -288.174337) (xy 358.552281 -288.21477) (xy 358.574971 -288.259302) (xy 358.590415 -288.306834)
			(xy 358.598234 -288.356197) (xy 358.598724 -288.381186) (xy 358.598724 -288.399729) (xy 358.927495 -288.399729)
			(xy 358.927654 -288.388806) (xy 358.927544 -288.365023) (xy 358.934017 -288.31791) (xy 358.948028 -288.272465)
			(xy 358.969208 -288.229887) (xy 358.997 -288.191298) (xy 359.013506 -288.174176) (xy 359.031977 -288.156493)
			(xy 359.073858 -288.127168) (xy 359.120196 -288.10556) (xy 359.169582 -288.092327) (xy 359.220516 -288.087871)
			(xy 359.27145 -288.092327) (xy 359.320836 -288.10556) (xy 359.367174 -288.127168) (xy 359.409055 -288.156493)
			(xy 359.427526 -288.174176) (xy 359.444153 -288.191524) (xy 359.47214 -288.230579) (xy 359.493369 -288.273682)
			(xy 359.507271 -288.319674) (xy 359.513473 -288.36732) (xy 359.513124 -288.391346) (xy 359.512925 -288.399729)
			(xy 359.867295 -288.399729) (xy 359.867454 -288.388806) (xy 359.867344 -288.365023) (xy 359.873817 -288.31791)
			(xy 359.887828 -288.272465) (xy 359.909008 -288.229887) (xy 359.9368 -288.191298) (xy 359.953306 -288.174176)
			(xy 359.971777 -288.156493) (xy 360.013658 -288.127168) (xy 360.059996 -288.10556) (xy 360.109382 -288.092327)
			(xy 360.160316 -288.087871) (xy 360.21125 -288.092327) (xy 360.260636 -288.10556) (xy 360.306974 -288.127168)
			(xy 360.348855 -288.156493) (xy 360.367326 -288.174176) (xy 360.383953 -288.191524) (xy 360.41194 -288.230579)
			(xy 360.433169 -288.273682) (xy 360.447071 -288.319674) (xy 360.453273 -288.36732) (xy 360.452924 -288.391346)
			(xy 360.452725 -288.399729) (xy 360.807095 -288.399729) (xy 360.807254 -288.388806) (xy 360.807095 -288.365033)
			(xy 360.813529 -288.317933) (xy 360.827496 -288.272494) (xy 360.848629 -288.229912) (xy 360.876371 -288.191309)
			(xy 360.892852 -288.174176) (xy 360.909035 -288.158628) (xy 360.945252 -288.13213) (xy 360.985086 -288.111464)
			(xy 361.027606 -288.097115) (xy 361.071816 -288.089416) (xy 361.116684 -288.08855) (xy 361.138978 -288.091118)
			(xy 361.15359 -288.092687) (xy 361.182626 -288.088206) (xy 361.209183 -288.075642) (xy 361.231063 -288.056035)
			(xy 361.246453 -288.031009) (xy 361.250738 -288.01695) (xy 361.258171 -287.991476) (xy 361.280042 -287.943131)
			(xy 361.309337 -287.898888) (xy 361.326938 -287.879028) (xy 361.333212 -287.871558) (xy 361.340143 -287.853342)
			(xy 361.339795 -287.833855) (xy 361.332218 -287.815898) (xy 361.325668 -287.80867) (xy 361.307181 -287.789252)
			(xy 361.275852 -287.745747) (xy 361.251664 -287.697903) (xy 361.235203 -287.646881) (xy 361.22687 -287.593922)
			(xy 361.226354 -287.567116) (xy 361.226834 -287.541417) (xy 361.234495 -287.490593) (xy 361.249644 -287.441479)
			(xy 361.271945 -287.395171) (xy 361.300898 -287.352704) (xy 361.335858 -287.315027) (xy 361.376042 -287.282981)
			(xy 361.420554 -287.257282) (xy 361.468399 -287.238505) (xy 361.518508 -287.227067) (xy 361.569762 -287.223227)
			(xy 361.621016 -287.227067) (xy 361.671125 -287.238505) (xy 361.71897 -287.257282) (xy 361.763482 -287.282981)
			(xy 361.803666 -287.315027) (xy 361.838626 -287.352704) (xy 361.867579 -287.395171) (xy 361.88988 -287.441479)
			(xy 361.905029 -287.490593) (xy 361.91269 -287.541417) (xy 361.912857 -287.550375) (xy 364.045732 -287.550375)
			(xy 364.052148 -287.49894) (xy 364.066222 -287.449054) (xy 364.087634 -287.401849) (xy 364.115898 -287.358399)
			(xy 364.150371 -287.319692) (xy 364.190271 -287.286605) (xy 364.234691 -287.259891) (xy 364.282622 -287.240158)
			(xy 364.332974 -287.227853) (xy 364.384603 -287.223256) (xy 364.436337 -287.226471) (xy 364.487 -287.237426)
			(xy 364.535441 -287.255871) (xy 364.580559 -287.281387) (xy 364.621329 -287.313395) (xy 364.656825 -287.351168)
			(xy 364.686241 -287.393846) (xy 364.708907 -287.440461) (xy 364.72431 -287.489954) (xy 364.732098 -287.541199)
			(xy 364.73257 -287.567116) (xy 364.732077 -287.593923) (xy 364.723743 -287.646885) (xy 364.707278 -287.697908)
			(xy 364.683084 -287.745752) (xy 364.651748 -287.789255) (xy 364.633256 -287.80867) (xy 364.626805 -287.815934)
			(xy 364.61932 -287.833837) (xy 364.619027 -287.853239) (xy 364.625966 -287.871361) (xy 364.63224 -287.878774)
			(xy 364.648649 -287.897189) (xy 364.676356 -287.937992) (xy 364.697681 -287.982464) (xy 364.712149 -288.029615)
			(xy 364.719438 -288.078395) (xy 364.71987 -288.103056) (xy 364.719361 -288.129023) (xy 364.711236 -288.180318)
			(xy 364.695188 -288.229711) (xy 364.67161 -288.275985) (xy 364.641084 -288.318001) (xy 364.604361 -288.354724)
			(xy 364.562345 -288.38525) (xy 364.516071 -288.408828) (xy 364.466678 -288.424876) (xy 364.415383 -288.433001)
			(xy 364.363449 -288.433001) (xy 364.312154 -288.424876) (xy 364.262761 -288.408828) (xy 364.216487 -288.38525)
			(xy 364.174471 -288.354724) (xy 364.137748 -288.318001) (xy 364.107222 -288.275985) (xy 364.083644 -288.229711)
			(xy 364.067596 -288.180318) (xy 364.059471 -288.129023) (xy 364.058962 -288.103056) (xy 364.059406 -288.078422)
			(xy 364.066732 -288.029701) (xy 364.081215 -287.982609) (xy 364.102533 -287.938192) (xy 364.130213 -287.897434)
			(xy 364.146592 -287.879028) (xy 364.152842 -287.871576) (xy 364.159782 -287.853431) (xy 364.159441 -287.834006)
			(xy 364.151867 -287.816116) (xy 364.145322 -287.808924) (xy 364.127464 -287.790134) (xy 364.096914 -287.74826)
			(xy 364.073005 -287.70227) (xy 364.05628 -287.653208) (xy 364.04712 -287.60219) (xy 364.045732 -287.550375)
			(xy 361.912857 -287.550375) (xy 361.91317 -287.567116) (xy 361.912677 -287.593923) (xy 361.904343 -287.646885)
			(xy 361.887878 -287.697908) (xy 361.863684 -287.745752) (xy 361.832348 -287.789255) (xy 361.813856 -287.80867)
			(xy 361.80728 -287.815884) (xy 361.799681 -287.833847) (xy 361.799332 -287.853349) (xy 361.806283 -287.871573)
			(xy 361.812586 -287.879028) (xy 361.830202 -287.898877) (xy 361.859519 -287.94311) (xy 361.881366 -287.99147)
			(xy 361.888786 -288.01695) (xy 361.893052 -288.03101) (xy 361.908458 -288.056016) (xy 361.930345 -288.075603)
			(xy 361.956901 -288.088151) (xy 361.985929 -288.092622) (xy 362.000546 -288.091118) (xy 362.022862 -288.088513)
			(xy 362.067781 -288.089331) (xy 362.112048 -288.097005) (xy 362.154622 -288.111354) (xy 362.194502 -288.132042)
			(xy 362.230752 -288.158582) (xy 362.246926 -288.174176) (xy 362.263553 -288.191524) (xy 362.29154 -288.230579)
			(xy 362.312769 -288.273682) (xy 362.326671 -288.319674) (xy 362.332873 -288.36732) (xy 362.332524 -288.391346)
			(xy 362.332325 -288.399729) (xy 362.686695 -288.399729) (xy 362.686854 -288.388806) (xy 362.686744 -288.365023)
			(xy 362.693217 -288.31791) (xy 362.707228 -288.272465) (xy 362.728408 -288.229887) (xy 362.7562 -288.191298)
			(xy 362.772706 -288.174176) (xy 362.791177 -288.156493) (xy 362.833058 -288.127168) (xy 362.879396 -288.10556)
			(xy 362.928782 -288.092327) (xy 362.979716 -288.087871) (xy 363.03065 -288.092327) (xy 363.080036 -288.10556)
			(xy 363.126374 -288.127168) (xy 363.168255 -288.156493) (xy 363.186726 -288.174176) (xy 363.203353 -288.191524)
			(xy 363.23134 -288.230579) (xy 363.252569 -288.273682) (xy 363.266471 -288.319674) (xy 363.272673 -288.36732)
			(xy 363.272324 -288.391346) (xy 363.272074 -288.401888) (xy 363.264222 -288.421432) (xy 363.257084 -288.429192)
			(xy 363.249579 -288.435998) (xy 363.230881 -288.443743) (xy 363.210643 -288.443743) (xy 363.191945 -288.435998)
			(xy 363.18444 -288.429192) (xy 363.179217 -288.423705) (xy 363.171993 -288.410395) (xy 363.170216 -288.40303)
			(xy 363.170216 -288.382456) (xy 363.170724 -288.381694) (xy 363.170269 -288.362879) (xy 363.162909 -288.325976)
			(xy 363.148492 -288.291217) (xy 363.127573 -288.259937) (xy 363.11459 -288.246312) (xy 363.101033 -288.233361)
			(xy 363.069862 -288.212534) (xy 363.035228 -288.198188) (xy 362.99846 -288.190874) (xy 362.960972 -288.190874)
			(xy 362.924204 -288.198188) (xy 362.88957 -288.212534) (xy 362.858399 -288.233361) (xy 362.844842 -288.246312)
			(xy 362.831963 -288.259738) (xy 362.811178 -288.290587) (xy 362.796772 -288.324882) (xy 362.789291 -288.361321)
			(xy 362.788708 -288.379916) (xy 362.788708 -288.380932) (xy 362.788454 -288.381186) (xy 362.788708 -288.38144)
			(xy 362.788708 -288.402268) (xy 362.786952 -288.409543) (xy 362.779849 -288.422709) (xy 362.774738 -288.428176)
			(xy 362.767268 -288.435112) (xy 362.748473 -288.442963) (xy 362.728105 -288.442963) (xy 362.70931 -288.435112)
			(xy 362.70184 -288.428176) (xy 362.694451 -288.420131) (xy 362.686695 -288.399729) (xy 362.332325 -288.399729)
			(xy 362.332274 -288.401888) (xy 362.324422 -288.421432) (xy 362.317284 -288.429192) (xy 362.309779 -288.435998)
			(xy 362.291081 -288.443743) (xy 362.270843 -288.443743) (xy 362.252145 -288.435998) (xy 362.24464 -288.429192)
			(xy 362.239417 -288.423705) (xy 362.232193 -288.410395) (xy 362.230416 -288.40303) (xy 362.230416 -288.382456)
			(xy 362.230924 -288.381694) (xy 362.230469 -288.362879) (xy 362.223109 -288.325976) (xy 362.208692 -288.291217)
			(xy 362.187773 -288.259937) (xy 362.17479 -288.246312) (xy 362.161233 -288.233361) (xy 362.130062 -288.212534)
			(xy 362.095428 -288.198188) (xy 362.05866 -288.190874) (xy 362.021172 -288.190874) (xy 361.984404 -288.198188)
			(xy 361.94977 -288.212534) (xy 361.918599 -288.233361) (xy 361.905042 -288.246312) (xy 361.892163 -288.259738)
			(xy 361.871378 -288.290587) (xy 361.856972 -288.324882) (xy 361.849491 -288.361321) (xy 361.848908 -288.379916)
			(xy 361.848908 -288.380932) (xy 361.848654 -288.381186) (xy 361.848908 -288.38144) (xy 361.848908 -288.402268)
			(xy 361.847152 -288.409543) (xy 361.840049 -288.422709) (xy 361.834938 -288.428176) (xy 361.827468 -288.435112)
			(xy 361.808673 -288.442963) (xy 361.788305 -288.442963) (xy 361.76951 -288.435112) (xy 361.76204 -288.428176)
			(xy 361.757976 -288.42335) (xy 361.750688 -288.41487) (xy 361.73085 -288.40462) (xy 361.708536 -288.403775)
			(xy 361.698032 -288.407602) (xy 361.677656 -288.415808) (xy 361.635268 -288.427339) (xy 361.591726 -288.433153)
			(xy 361.569762 -288.43351) (xy 361.54789 -288.433182) (xy 361.504527 -288.427429) (xy 361.462306 -288.41599)
			(xy 361.442 -288.407856) (xy 361.431464 -288.404057) (xy 361.409115 -288.404957) (xy 361.389285 -288.415305)
			(xy 361.382056 -288.423858) (xy 361.377484 -288.429192) (xy 361.370014 -288.436128) (xy 361.351219 -288.443979)
			(xy 361.330851 -288.443979) (xy 361.312056 -288.436128) (xy 361.304586 -288.429192) (xy 361.299451 -288.423668)
			(xy 361.292354 -288.410369) (xy 361.290616 -288.40303) (xy 361.290616 -288.382456) (xy 361.29087 -288.381694)
			(xy 361.290461 -288.362875) (xy 361.283097 -288.325964) (xy 361.268674 -288.291199) (xy 361.247746 -288.259916)
			(xy 361.234736 -288.246312) (xy 361.221179 -288.233361) (xy 361.190008 -288.212534) (xy 361.155374 -288.198188)
			(xy 361.118606 -288.190874) (xy 361.081118 -288.190874) (xy 361.04435 -288.198188) (xy 361.009716 -288.212534)
			(xy 360.978545 -288.233361) (xy 360.964988 -288.246312) (xy 360.952169 -288.259775) (xy 360.931448 -288.290631)
			(xy 360.9171 -288.324918) (xy 360.90967 -288.361335) (xy 360.909108 -288.379916) (xy 360.909108 -288.380932)
			(xy 360.908854 -288.381186) (xy 360.909108 -288.38144) (xy 360.909108 -288.402268) (xy 360.907352 -288.409543)
			(xy 360.900249 -288.422709) (xy 360.895138 -288.428176) (xy 360.887668 -288.435112) (xy 360.868873 -288.442963)
			(xy 360.848505 -288.442963) (xy 360.82971 -288.435112) (xy 360.82224 -288.428176) (xy 360.814851 -288.420131)
			(xy 360.807095 -288.399729) (xy 360.452725 -288.399729) (xy 360.452674 -288.401888) (xy 360.444822 -288.421432)
			(xy 360.437684 -288.429192) (xy 360.430179 -288.435998) (xy 360.411481 -288.443743) (xy 360.391243 -288.443743)
			(xy 360.372545 -288.435998) (xy 360.36504 -288.429192) (xy 360.359817 -288.423705) (xy 360.352593 -288.410395)
			(xy 360.350816 -288.40303) (xy 360.350816 -288.382456) (xy 360.351324 -288.381694) (xy 360.350869 -288.362879)
			(xy 360.343509 -288.325976) (xy 360.329092 -288.291217) (xy 360.308173 -288.259937) (xy 360.29519 -288.246312)
			(xy 360.281633 -288.233361) (xy 360.250462 -288.212534) (xy 360.215828 -288.198188) (xy 360.17906 -288.190874)
			(xy 360.141572 -288.190874) (xy 360.104804 -288.198188) (xy 360.07017 -288.212534) (xy 360.038999 -288.233361)
			(xy 360.025442 -288.246312) (xy 360.012563 -288.259738) (xy 359.991778 -288.290587) (xy 359.977372 -288.324882)
			(xy 359.969891 -288.361321) (xy 359.969308 -288.379916) (xy 359.969308 -288.380932) (xy 359.969054 -288.381186)
			(xy 359.969308 -288.38144) (xy 359.969308 -288.402268) (xy 359.967552 -288.409543) (xy 359.960449 -288.422709)
			(xy 359.955338 -288.428176) (xy 359.947868 -288.435112) (xy 359.929073 -288.442963) (xy 359.908705 -288.442963)
			(xy 359.88991 -288.435112) (xy 359.88244 -288.428176) (xy 359.875051 -288.420131) (xy 359.867295 -288.399729)
			(xy 359.512925 -288.399729) (xy 359.512874 -288.401888) (xy 359.505022 -288.421432) (xy 359.497884 -288.429192)
			(xy 359.490379 -288.435998) (xy 359.471681 -288.443743) (xy 359.451443 -288.443743) (xy 359.432745 -288.435998)
			(xy 359.42524 -288.429192) (xy 359.420017 -288.423705) (xy 359.412793 -288.410395) (xy 359.411016 -288.40303)
			(xy 359.411016 -288.382456) (xy 359.411524 -288.381694) (xy 359.411069 -288.362879) (xy 359.403709 -288.325976)
			(xy 359.389292 -288.291217) (xy 359.368373 -288.259937) (xy 359.35539 -288.246312) (xy 359.341833 -288.233361)
			(xy 359.310662 -288.212534) (xy 359.276028 -288.198188) (xy 359.23926 -288.190874) (xy 359.201772 -288.190874)
			(xy 359.165004 -288.198188) (xy 359.13037 -288.212534) (xy 359.099199 -288.233361) (xy 359.085642 -288.246312)
			(xy 359.072763 -288.259738) (xy 359.051978 -288.290587) (xy 359.037572 -288.324882) (xy 359.030091 -288.361321)
			(xy 359.029508 -288.379916) (xy 359.029508 -288.380932) (xy 359.029254 -288.381186) (xy 359.029508 -288.38144)
			(xy 359.029508 -288.402268) (xy 359.027752 -288.409543) (xy 359.020649 -288.422709) (xy 359.015538 -288.428176)
			(xy 359.008068 -288.435112) (xy 358.989273 -288.442963) (xy 358.968905 -288.442963) (xy 358.95011 -288.435112)
			(xy 358.94264 -288.428176) (xy 358.935251 -288.420131) (xy 358.927495 -288.399729) (xy 358.598724 -288.399729)
			(xy 358.598724 -288.482786) (xy 358.598105 -288.510988) (xy 358.588142 -288.566506) (xy 358.568544 -288.619397)
			(xy 358.539926 -288.668002) (xy 358.522016 -288.689796) (xy 358.509824 -288.70402) (xy 358.509824 -288.754312)
			(xy 358.523286 -288.76879) (xy 358.539739 -288.787209) (xy 358.567491 -288.828062) (xy 358.588862 -288.872586)
			(xy 358.603377 -288.919793) (xy 358.610714 -288.968632) (xy 358.61117 -288.993326) (xy 358.610661 -289.019293)
			(xy 358.602536 -289.070588) (xy 358.586488 -289.119981) (xy 358.56291 -289.166255) (xy 358.553594 -289.179077)
			(xy 363.156528 -289.179077) (xy 363.162949 -289.131919) (xy 363.17692 -289.086423) (xy 363.198073 -289.043789)
			(xy 363.225849 -289.005142) (xy 363.242352 -288.987992) (xy 363.260823 -288.970309) (xy 363.302704 -288.940984)
			(xy 363.349042 -288.919376) (xy 363.398428 -288.906143) (xy 363.449362 -288.901687) (xy 363.500296 -288.906143)
			(xy 363.549682 -288.919376) (xy 363.59602 -288.940984) (xy 363.637901 -288.970309) (xy 363.656372 -288.987992)
			(xy 363.673073 -289.005285) (xy 363.701105 -289.044339) (xy 363.722378 -289.087449) (xy 363.73632 -289.133456)
			(xy 363.742289 -289.179077) (xy 364.096328 -289.179077) (xy 364.102749 -289.131919) (xy 364.11672 -289.086423)
			(xy 364.137873 -289.043789) (xy 364.165649 -289.005142) (xy 364.182152 -288.987992) (xy 364.200623 -288.970309)
			(xy 364.242504 -288.940984) (xy 364.288842 -288.919376) (xy 364.338228 -288.906143) (xy 364.389162 -288.901687)
			(xy 364.440096 -288.906143) (xy 364.489482 -288.919376) (xy 364.53582 -288.940984) (xy 364.577701 -288.970309)
			(xy 364.596172 -288.987992) (xy 364.612873 -289.005285) (xy 364.640905 -289.044339) (xy 364.662178 -289.087449)
			(xy 364.67612 -289.133456) (xy 364.682089 -289.179077) (xy 365.036128 -289.179077) (xy 365.042549 -289.131919)
			(xy 365.05652 -289.086423) (xy 365.077673 -289.043789) (xy 365.105449 -289.005142) (xy 365.121952 -288.987992)
			(xy 365.140423 -288.970309) (xy 365.182304 -288.940984) (xy 365.228642 -288.919376) (xy 365.278028 -288.906143)
			(xy 365.328962 -288.901687) (xy 365.379896 -288.906143) (xy 365.429282 -288.919376) (xy 365.47562 -288.940984)
			(xy 365.517501 -288.970309) (xy 365.535972 -288.987992) (xy 365.552673 -289.005285) (xy 365.580705 -289.044339)
			(xy 365.601978 -289.087449) (xy 365.61592 -289.133456) (xy 365.621889 -289.179077) (xy 365.975928 -289.179077)
			(xy 365.982349 -289.131919) (xy 365.99632 -289.086423) (xy 366.017473 -289.043789) (xy 366.045249 -289.005142)
			(xy 366.061752 -288.987992) (xy 366.080223 -288.970309) (xy 366.122104 -288.940984) (xy 366.168442 -288.919376)
			(xy 366.217828 -288.906143) (xy 366.268762 -288.901687) (xy 366.319696 -288.906143) (xy 366.369082 -288.919376)
			(xy 366.41542 -288.940984) (xy 366.457301 -288.970309) (xy 366.475772 -288.987992) (xy 366.492473 -289.005285)
			(xy 366.520505 -289.044339) (xy 366.541778 -289.087449) (xy 366.55572 -289.133456) (xy 366.561957 -289.181123)
			(xy 366.561624 -289.205162) (xy 366.561391 -289.215763) (xy 366.553534 -289.235433) (xy 366.546384 -289.243262)
			(xy 366.538901 -289.250171) (xy 366.52011 -289.257981) (xy 366.49976 -289.257981) (xy 366.480969 -289.250171)
			(xy 366.473486 -289.243262) (xy 366.468338 -289.237674) (xy 366.46124 -289.224246) (xy 366.459516 -289.216846)
			(xy 366.459516 -289.18535) (xy 366.458212 -289.167851) (xy 366.449974 -289.133744) (xy 366.435667 -289.101706)
			(xy 366.41577 -289.072805) (xy 366.403636 -289.060128) (xy 366.390079 -289.047177) (xy 366.358908 -289.02635)
			(xy 366.324274 -289.012004) (xy 366.287506 -289.00469) (xy 366.250018 -289.00469) (xy 366.21325 -289.012004)
			(xy 366.178616 -289.02635) (xy 366.147445 -289.047177) (xy 366.133888 -289.060128) (xy 366.121074 -289.073632)
			(xy 366.100377 -289.104566) (xy 366.086034 -289.138912) (xy 366.078586 -289.17538) (xy 366.078008 -289.193986)
			(xy 366.078008 -289.216084) (xy 366.076309 -289.223436) (xy 366.069193 -289.236734) (xy 366.064038 -289.242246)
			(xy 366.056555 -289.249155) (xy 366.037764 -289.256965) (xy 366.017414 -289.256965) (xy 365.998623 -289.249155)
			(xy 365.99114 -289.242246) (xy 365.983737 -289.234212) (xy 365.975989 -289.213802) (xy 365.976154 -289.202876)
			(xy 365.975928 -289.179077) (xy 365.621889 -289.179077) (xy 365.622157 -289.181123) (xy 365.621824 -289.205162)
			(xy 365.621591 -289.215763) (xy 365.613734 -289.235433) (xy 365.606584 -289.243262) (xy 365.599101 -289.250171)
			(xy 365.58031 -289.257981) (xy 365.55996 -289.257981) (xy 365.541169 -289.250171) (xy 365.533686 -289.243262)
			(xy 365.528538 -289.237674) (xy 365.52144 -289.224246) (xy 365.519716 -289.216846) (xy 365.519716 -289.18535)
			(xy 365.518412 -289.167851) (xy 365.510174 -289.133744) (xy 365.495867 -289.101706) (xy 365.47597 -289.072805)
			(xy 365.463836 -289.060128) (xy 365.450279 -289.047177) (xy 365.419108 -289.02635) (xy 365.384474 -289.012004)
			(xy 365.347706 -289.00469) (xy 365.310218 -289.00469) (xy 365.27345 -289.012004) (xy 365.238816 -289.02635)
			(xy 365.207645 -289.047177) (xy 365.194088 -289.060128) (xy 365.181274 -289.073632) (xy 365.160577 -289.104566)
			(xy 365.146234 -289.138912) (xy 365.138786 -289.17538) (xy 365.138208 -289.193986) (xy 365.138208 -289.216084)
			(xy 365.136509 -289.223436) (xy 365.129393 -289.236734) (xy 365.124238 -289.242246) (xy 365.116755 -289.249155)
			(xy 365.097964 -289.256965) (xy 365.077614 -289.256965) (xy 365.058823 -289.249155) (xy 365.05134 -289.242246)
			(xy 365.043937 -289.234212) (xy 365.036189 -289.213802) (xy 365.036354 -289.202876) (xy 365.036128 -289.179077)
			(xy 364.682089 -289.179077) (xy 364.682357 -289.181123) (xy 364.682024 -289.205162) (xy 364.681791 -289.215763)
			(xy 364.673934 -289.235433) (xy 364.666784 -289.243262) (xy 364.659301 -289.250171) (xy 364.64051 -289.257981)
			(xy 364.62016 -289.257981) (xy 364.601369 -289.250171) (xy 364.593886 -289.243262) (xy 364.588738 -289.237674)
			(xy 364.58164 -289.224246) (xy 364.579916 -289.216846) (xy 364.579916 -289.18535) (xy 364.578612 -289.167851)
			(xy 364.570374 -289.133744) (xy 364.556067 -289.101706) (xy 364.53617 -289.072805) (xy 364.524036 -289.060128)
			(xy 364.510479 -289.047177) (xy 364.479308 -289.02635) (xy 364.444674 -289.012004) (xy 364.407906 -289.00469)
			(xy 364.370418 -289.00469) (xy 364.33365 -289.012004) (xy 364.299016 -289.02635) (xy 364.267845 -289.047177)
			(xy 364.254288 -289.060128) (xy 364.241474 -289.073632) (xy 364.220777 -289.104566) (xy 364.206434 -289.138912)
			(xy 364.198986 -289.17538) (xy 364.198408 -289.193986) (xy 364.198408 -289.216084) (xy 364.196709 -289.223436)
			(xy 364.189593 -289.236734) (xy 364.184438 -289.242246) (xy 364.176955 -289.249155) (xy 364.158164 -289.256965)
			(xy 364.137814 -289.256965) (xy 364.119023 -289.249155) (xy 364.11154 -289.242246) (xy 364.104137 -289.234212)
			(xy 364.096389 -289.213802) (xy 364.096554 -289.202876) (xy 364.096328 -289.179077) (xy 363.742289 -289.179077)
			(xy 363.742557 -289.181123) (xy 363.742224 -289.205162) (xy 363.741991 -289.215763) (xy 363.734134 -289.235433)
			(xy 363.726984 -289.243262) (xy 363.719501 -289.250171) (xy 363.70071 -289.257981) (xy 363.68036 -289.257981)
			(xy 363.661569 -289.250171) (xy 363.654086 -289.243262) (xy 363.648938 -289.237674) (xy 363.64184 -289.224246)
			(xy 363.640116 -289.216846) (xy 363.640116 -289.18535) (xy 363.638812 -289.167851) (xy 363.630574 -289.133744)
			(xy 363.616267 -289.101706) (xy 363.59637 -289.072805) (xy 363.584236 -289.060128) (xy 363.570679 -289.047177)
			(xy 363.539508 -289.02635) (xy 363.504874 -289.012004) (xy 363.468106 -289.00469) (xy 363.430618 -289.00469)
			(xy 363.39385 -289.012004) (xy 363.359216 -289.02635) (xy 363.328045 -289.047177) (xy 363.314488 -289.060128)
			(xy 363.301674 -289.073632) (xy 363.280977 -289.104566) (xy 363.266634 -289.138912) (xy 363.259186 -289.17538)
			(xy 363.258608 -289.193986) (xy 363.258608 -289.216084) (xy 363.256909 -289.223436) (xy 363.249793 -289.236734)
			(xy 363.244638 -289.242246) (xy 363.237155 -289.249155) (xy 363.218364 -289.256965) (xy 363.198014 -289.256965)
			(xy 363.179223 -289.249155) (xy 363.17174 -289.242246) (xy 363.164337 -289.234212) (xy 363.156589 -289.213802)
			(xy 363.156754 -289.202876) (xy 363.156528 -289.179077) (xy 358.553594 -289.179077) (xy 358.532384 -289.208271)
			(xy 358.495661 -289.244994) (xy 358.453645 -289.27552) (xy 358.407371 -289.299098) (xy 358.357978 -289.315146)
			(xy 358.306683 -289.323271) (xy 358.254749 -289.323271) (xy 358.203454 -289.315146) (xy 358.154061 -289.299098)
			(xy 358.107787 -289.27552) (xy 358.065771 -289.244994) (xy 358.029048 -289.208271) (xy 357.998522 -289.166255)
			(xy 357.974944 -289.119981) (xy 357.958896 -289.070588) (xy 357.950771 -289.019293) (xy 357.950262 -288.993326)
			(xy 357.082923 -288.993326) (xy 357.094473 -289.005285) (xy 357.122505 -289.044339) (xy 357.143778 -289.087449)
			(xy 357.15772 -289.133456) (xy 357.163957 -289.181123) (xy 357.163624 -289.205162) (xy 357.163391 -289.215763)
			(xy 357.155534 -289.235433) (xy 357.148384 -289.243262) (xy 357.140901 -289.250171) (xy 357.12211 -289.257981)
			(xy 357.10176 -289.257981) (xy 357.082969 -289.250171) (xy 357.075486 -289.243262) (xy 357.070338 -289.237674)
			(xy 357.06324 -289.224246) (xy 357.061516 -289.216846) (xy 357.061516 -289.18535) (xy 357.060212 -289.167851)
			(xy 357.051974 -289.133744) (xy 357.037667 -289.101706) (xy 357.01777 -289.072805) (xy 357.005636 -289.060128)
			(xy 356.992079 -289.047177) (xy 356.960908 -289.02635) (xy 356.926274 -289.012004) (xy 356.889506 -289.00469)
			(xy 356.852018 -289.00469) (xy 356.81525 -289.012004) (xy 356.780616 -289.02635) (xy 356.749445 -289.047177)
			(xy 356.735888 -289.060128) (xy 356.723074 -289.073632) (xy 356.702377 -289.104566) (xy 356.688034 -289.138912)
			(xy 356.680586 -289.17538) (xy 356.680008 -289.193986) (xy 356.680008 -289.216084) (xy 356.678309 -289.223436)
			(xy 356.671193 -289.236734) (xy 356.666038 -289.242246) (xy 356.658555 -289.249155) (xy 356.639764 -289.256965)
			(xy 356.619414 -289.256965) (xy 356.600623 -289.249155) (xy 356.59314 -289.242246) (xy 356.585737 -289.234212)
			(xy 356.577989 -289.213802) (xy 356.578154 -289.202876) (xy 356.577928 -289.179077) (xy 356.223889 -289.179077)
			(xy 356.224157 -289.181123) (xy 356.223824 -289.205162) (xy 356.223591 -289.215763) (xy 356.215734 -289.235433)
			(xy 356.208584 -289.243262) (xy 356.201101 -289.250171) (xy 356.18231 -289.257981) (xy 356.16196 -289.257981)
			(xy 356.143169 -289.250171) (xy 356.135686 -289.243262) (xy 356.130538 -289.237674) (xy 356.12344 -289.224246)
			(xy 356.121716 -289.216846) (xy 356.121716 -289.18535) (xy 356.120412 -289.167851) (xy 356.112174 -289.133744)
			(xy 356.097867 -289.101706) (xy 356.07797 -289.072805) (xy 356.065836 -289.060128) (xy 356.052279 -289.047177)
			(xy 356.021108 -289.02635) (xy 355.986474 -289.012004) (xy 355.949706 -289.00469) (xy 355.912218 -289.00469)
			(xy 355.87545 -289.012004) (xy 355.840816 -289.02635) (xy 355.809645 -289.047177) (xy 355.796088 -289.060128)
			(xy 355.783274 -289.073632) (xy 355.762577 -289.104566) (xy 355.748234 -289.138912) (xy 355.740786 -289.17538)
			(xy 355.740208 -289.193986) (xy 355.740208 -289.216084) (xy 355.738509 -289.223436) (xy 355.731393 -289.236734)
			(xy 355.726238 -289.242246) (xy 355.718755 -289.249155) (xy 355.699964 -289.256965) (xy 355.679614 -289.256965)
			(xy 355.660823 -289.249155) (xy 355.65334 -289.242246) (xy 355.649276 -289.23742) (xy 355.641992 -289.228937)
			(xy 355.622151 -289.218692) (xy 355.599837 -289.217847) (xy 355.589332 -289.221672) (xy 355.568995 -289.229863)
			(xy 355.526692 -289.241383) (xy 355.483237 -289.247209) (xy 355.461316 -289.24758) (xy 355.439445 -289.247237)
			(xy 355.396082 -289.24149) (xy 355.353861 -289.230056) (xy 355.333554 -289.221926) (xy 355.322995 -289.218055)
			(xy 355.300548 -289.218962) (xy 355.280625 -289.229344) (xy 355.273356 -289.237928) (xy 355.268784 -289.243262)
			(xy 355.261301 -289.250171) (xy 355.24251 -289.257981) (xy 355.22216 -289.257981) (xy 355.203369 -289.250171)
			(xy 355.195886 -289.243262) (xy 355.190738 -289.237674) (xy 355.18364 -289.224246) (xy 355.181916 -289.216846)
			(xy 355.181916 -289.18535) (xy 355.180612 -289.167851) (xy 355.172374 -289.133744) (xy 355.158067 -289.101706)
			(xy 355.13817 -289.072805) (xy 355.126036 -289.060128) (xy 355.112479 -289.047177) (xy 355.081308 -289.02635)
			(xy 355.046674 -289.012004) (xy 355.009906 -289.00469) (xy 354.972418 -289.00469) (xy 354.93565 -289.012004)
			(xy 354.901016 -289.02635) (xy 354.869845 -289.047177) (xy 354.856288 -289.060128) (xy 354.843474 -289.073632)
			(xy 354.822777 -289.104566) (xy 354.808434 -289.138912) (xy 354.800986 -289.17538) (xy 354.800408 -289.193986)
			(xy 354.800408 -289.216084) (xy 354.798709 -289.223436) (xy 354.791593 -289.236734) (xy 354.786438 -289.242246)
			(xy 354.778955 -289.249155) (xy 354.760164 -289.256965) (xy 354.739814 -289.256965) (xy 354.721023 -289.249155)
			(xy 354.71354 -289.242246) (xy 354.706137 -289.234212) (xy 354.698389 -289.213802) (xy 354.698554 -289.202876)
			(xy 354.698328 -289.179077) (xy 354.344289 -289.179077) (xy 354.344557 -289.181123) (xy 354.344224 -289.205162)
			(xy 354.343991 -289.215763) (xy 354.336134 -289.235433) (xy 354.328984 -289.243262) (xy 354.321501 -289.250171)
			(xy 354.30271 -289.257981) (xy 354.28236 -289.257981) (xy 354.263569 -289.250171) (xy 354.256086 -289.243262)
			(xy 354.250938 -289.237674) (xy 354.24384 -289.224246) (xy 354.242116 -289.216846) (xy 354.242116 -289.18535)
			(xy 354.240812 -289.167851) (xy 354.232574 -289.133744) (xy 354.218267 -289.101706) (xy 354.19837 -289.072805)
			(xy 354.186236 -289.060128) (xy 354.172679 -289.047177) (xy 354.141508 -289.02635) (xy 354.106874 -289.012004)
			(xy 354.070106 -289.00469) (xy 354.032618 -289.00469) (xy 353.99585 -289.012004) (xy 353.961216 -289.02635)
			(xy 353.930045 -289.047177) (xy 353.916488 -289.060128) (xy 353.903674 -289.073632) (xy 353.882977 -289.104566)
			(xy 353.868634 -289.138912) (xy 353.861186 -289.17538) (xy 353.860608 -289.193986) (xy 353.860608 -289.216084)
			(xy 353.858909 -289.223436) (xy 353.851793 -289.236734) (xy 353.846638 -289.242246) (xy 353.839155 -289.249155)
			(xy 353.820364 -289.256965) (xy 353.800014 -289.256965) (xy 353.781223 -289.249155) (xy 353.77374 -289.242246)
			(xy 353.766337 -289.234212) (xy 353.758589 -289.213802) (xy 353.758754 -289.202876) (xy 353.758528 -289.179077)
			(xy 353.404461 -289.179077) (xy 353.404729 -289.181125) (xy 353.404424 -289.205162) (xy 353.404223 -289.215767)
			(xy 353.396344 -289.235435) (xy 353.389184 -289.243262) (xy 353.381632 -289.250045) (xy 353.362874 -289.25775)
			(xy 353.342596 -289.25775) (xy 353.323838 -289.250045) (xy 353.316286 -289.243262) (xy 353.311121 -289.237684)
			(xy 353.304017 -289.224255) (xy 353.302316 -289.216846) (xy 353.302316 -289.18535) (xy 353.301017 -289.167846)
			(xy 353.29283 -289.133719) (xy 353.278529 -289.101669) (xy 353.2586 -289.072782) (xy 353.246436 -289.060128)
			(xy 353.232879 -289.047177) (xy 353.201708 -289.02635) (xy 353.167074 -289.012004) (xy 353.130306 -289.00469)
			(xy 353.092818 -289.00469) (xy 353.05605 -289.012004) (xy 353.021416 -289.02635) (xy 352.990245 -289.047177)
			(xy 352.976688 -289.060128) (xy 352.963834 -289.073601) (xy 352.943098 -289.104524) (xy 352.928757 -289.138883)
			(xy 352.921357 -289.175372) (xy 352.920808 -289.193986) (xy 352.920808 -289.216084) (xy 352.919058 -289.223419)
			(xy 352.911968 -289.23672) (xy 352.906838 -289.242246) (xy 352.900795 -289.247778) (xy 352.886176 -289.255152)
			(xy 352.878136 -289.256724) (xy 352.834956 -289.263328) (xy 352.834956 -289.653726) (xy 351.972626 -290.516056)
			(xy 335.319624 -290.516056) (xy 334.677512 -291.157914) (xy 334.677512 -297.515026) (xy 336.155548 -297.515026)
			(xy 336.159529 -297.382006) (xy 336.171458 -297.249461) (xy 336.191293 -297.117868) (xy 336.218962 -296.987696)
			(xy 336.254366 -296.859411) (xy 336.297379 -296.733474) (xy 336.347846 -296.610335) (xy 336.405587 -296.490434)
			(xy 336.470396 -296.374201) (xy 336.54204 -296.262051) (xy 336.620262 -296.154387) (xy 336.704783 -296.051594)
			(xy 336.795301 -295.954039) (xy 336.89149 -295.862073) (xy 336.993008 -295.776023) (xy 337.099489 -295.696199)
			(xy 337.210554 -295.622886) (xy 337.325805 -295.556346) (xy 337.444829 -295.496817) (xy 337.5672 -295.444513)
			(xy 337.692479 -295.399621) (xy 337.82022 -295.362302) (xy 337.949963 -295.332689) (xy 338.081245 -295.310888)
			(xy 338.213596 -295.296978) (xy 338.346542 -295.291007) (xy 338.479607 -295.292998) (xy 338.612315 -295.302943)
			(xy 338.744191 -295.320807) (xy 338.874762 -295.346525) (xy 339.003562 -295.380006) (xy 339.130128 -295.42113)
			(xy 339.254009 -295.46975) (xy 339.37476 -295.525691) (xy 339.49195 -295.588753) (xy 339.605159 -295.658711)
			(xy 339.713981 -295.735315) (xy 339.818027 -295.818289) (xy 339.916925 -295.907337) (xy 340.01032 -296.00214)
			(xy 340.097878 -296.102358) (xy 340.179287 -296.207634) (xy 340.254253 -296.31759) (xy 340.32251 -296.431832)
			(xy 340.383812 -296.549952) (xy 340.437941 -296.671527) (xy 340.484702 -296.796121) (xy 340.523928 -296.923289)
			(xy 340.555478 -297.052575) (xy 340.579241 -297.183516) (xy 340.59513 -297.315644) (xy 340.596423 -297.337226)
			(xy 351.092008 -297.337226) (xy 351.092008 -292.757606) (xy 351.368106 -292.481508) (xy 353.052126 -292.481508)
			(xy 353.302824 -292.732206) (xy 353.302824 -297.341036) (xy 356.654608 -297.341036) (xy 356.654608 -292.856158)
			(xy 357.061262 -292.449504) (xy 359.351326 -292.449504) (xy 359.602024 -292.700202) (xy 359.602024 -297.366436)
			(xy 362.996988 -297.366436) (xy 362.996988 -292.722046) (xy 363.260386 -292.458648) (xy 365.693706 -292.458648)
			(xy 365.944404 -292.709346) (xy 365.944404 -295.038526) (xy 370.181376 -295.038526) (xy 370.185447 -294.982904)
			(xy 370.197573 -294.928467) (xy 370.217496 -294.876376) (xy 370.244792 -294.827741) (xy 370.278878 -294.783598)
			(xy 370.319027 -294.744889) (xy 370.364385 -294.712438) (xy 370.413985 -294.686937) (xy 370.466769 -294.66893)
			(xy 370.521612 -294.6588) (xy 370.577346 -294.656763) (xy 370.632783 -294.662863) (xy 370.68674 -294.676969)
			(xy 370.738069 -294.698781) (xy 370.785675 -294.727835) (xy 370.828543 -294.76351) (xy 370.86576 -294.805047)
			(xy 370.896533 -294.85156) (xy 370.920205 -294.902057) (xy 370.936273 -294.955464) (xy 370.944393 -295.01064)
			(xy 370.944902 -295.038526) (xy 370.944393 -295.066412) (xy 370.936273 -295.121588) (xy 370.920205 -295.174995)
			(xy 370.896533 -295.225492) (xy 370.86576 -295.272005) (xy 370.828543 -295.313542) (xy 370.785675 -295.349217)
			(xy 370.738069 -295.378271) (xy 370.68674 -295.400083) (xy 370.632783 -295.414189) (xy 370.577346 -295.420289)
			(xy 370.521612 -295.418252) (xy 370.466769 -295.408122) (xy 370.413985 -295.390115) (xy 370.364385 -295.364614)
			(xy 370.319027 -295.332163) (xy 370.278878 -295.293454) (xy 370.244792 -295.249311) (xy 370.217496 -295.200676)
			(xy 370.197573 -295.148585) (xy 370.185447 -295.094148) (xy 370.181376 -295.038526) (xy 365.944404 -295.038526)
			(xy 365.944404 -297.197526) (xy 370.181376 -297.197526) (xy 370.185447 -297.141904) (xy 370.197573 -297.087467)
			(xy 370.217496 -297.035376) (xy 370.244792 -296.986741) (xy 370.278878 -296.942598) (xy 370.319027 -296.903889)
			(xy 370.364385 -296.871438) (xy 370.413985 -296.845937) (xy 370.466769 -296.82793) (xy 370.521612 -296.8178)
			(xy 370.577346 -296.815763) (xy 370.632783 -296.821863) (xy 370.68674 -296.835969) (xy 370.738069 -296.857781)
			(xy 370.785675 -296.886835) (xy 370.828543 -296.92251) (xy 370.86576 -296.964047) (xy 370.896533 -297.01056)
			(xy 370.920205 -297.061057) (xy 370.936273 -297.114464) (xy 370.944393 -297.16964) (xy 370.944902 -297.197526)
			(xy 370.944393 -297.225412) (xy 370.936273 -297.280588) (xy 370.920205 -297.333995) (xy 370.896533 -297.384492)
			(xy 370.86576 -297.431005) (xy 370.828543 -297.472542) (xy 370.785675 -297.508217) (xy 370.774518 -297.515026)
			(xy 379.13565 -297.515026) (xy 379.139631 -297.382006) (xy 379.15156 -297.249461) (xy 379.171395 -297.117868)
			(xy 379.199064 -296.987696) (xy 379.234468 -296.859411) (xy 379.277481 -296.733474) (xy 379.327948 -296.610335)
			(xy 379.385689 -296.490434) (xy 379.450498 -296.374201) (xy 379.522142 -296.262051) (xy 379.600364 -296.154387)
			(xy 379.684885 -296.051594) (xy 379.775403 -295.954039) (xy 379.871592 -295.862073) (xy 379.97311 -295.776023)
			(xy 380.079591 -295.696199) (xy 380.190656 -295.622886) (xy 380.305907 -295.556346) (xy 380.424931 -295.496817)
			(xy 380.547302 -295.444513) (xy 380.672581 -295.399621) (xy 380.800322 -295.362302) (xy 380.930065 -295.332689)
			(xy 381.061347 -295.310888) (xy 381.193698 -295.296978) (xy 381.326644 -295.291007) (xy 381.459709 -295.292998)
			(xy 381.592417 -295.302943) (xy 381.724293 -295.320807) (xy 381.854864 -295.346525) (xy 381.983664 -295.380006)
			(xy 382.11023 -295.42113) (xy 382.234111 -295.46975) (xy 382.354862 -295.525691) (xy 382.472052 -295.588753)
			(xy 382.585261 -295.658711) (xy 382.694083 -295.735315) (xy 382.798129 -295.818289) (xy 382.897027 -295.907337)
			(xy 382.990422 -296.00214) (xy 383.07798 -296.102358) (xy 383.159389 -296.207634) (xy 383.234355 -296.31759)
			(xy 383.302612 -296.431832) (xy 383.363914 -296.549952) (xy 383.418043 -296.671527) (xy 383.464804 -296.796121)
			(xy 383.50403 -296.923289) (xy 383.53558 -297.052575) (xy 383.559343 -297.183516) (xy 383.575232 -297.315644)
			(xy 383.58319 -297.448486) (xy 383.583688 -297.515026) (xy 383.58319 -297.581566) (xy 383.575232 -297.714408)
			(xy 383.559343 -297.846536) (xy 383.53558 -297.977477) (xy 383.50403 -298.106763) (xy 383.464804 -298.233931)
			(xy 383.418043 -298.358525) (xy 383.363914 -298.4801) (xy 383.302612 -298.59822) (xy 383.234355 -298.712462)
			(xy 383.159389 -298.822418) (xy 383.07798 -298.927694) (xy 382.990422 -299.027912) (xy 382.897027 -299.122715)
			(xy 382.798129 -299.211763) (xy 382.694083 -299.294737) (xy 382.585261 -299.371341) (xy 382.472052 -299.441299)
			(xy 382.354862 -299.504361) (xy 382.234111 -299.560302) (xy 382.11023 -299.608922) (xy 381.983664 -299.650046)
			(xy 381.854864 -299.683527) (xy 381.724293 -299.709245) (xy 381.592417 -299.727109) (xy 381.459709 -299.737054)
			(xy 381.326644 -299.739045) (xy 381.193698 -299.733074) (xy 381.061347 -299.719164) (xy 380.930065 -299.697363)
			(xy 380.800322 -299.66775) (xy 380.672581 -299.630431) (xy 380.547302 -299.585539) (xy 380.424931 -299.533235)
			(xy 380.305907 -299.473706) (xy 380.190656 -299.407166) (xy 380.079591 -299.333853) (xy 379.97311 -299.254029)
			(xy 379.871592 -299.167979) (xy 379.775403 -299.076013) (xy 379.684885 -298.978458) (xy 379.600364 -298.875665)
			(xy 379.522142 -298.768001) (xy 379.450498 -298.655851) (xy 379.385689 -298.539618) (xy 379.327948 -298.419717)
			(xy 379.277481 -298.296578) (xy 379.234468 -298.170641) (xy 379.199064 -298.042356) (xy 379.171395 -297.912184)
			(xy 379.15156 -297.780591) (xy 379.139631 -297.648046) (xy 379.13565 -297.515026) (xy 370.774518 -297.515026)
			(xy 370.738069 -297.537271) (xy 370.68674 -297.559083) (xy 370.632783 -297.573189) (xy 370.577346 -297.579289)
			(xy 370.521612 -297.577252) (xy 370.466769 -297.567122) (xy 370.413985 -297.549115) (xy 370.364385 -297.523614)
			(xy 370.319027 -297.491163) (xy 370.278878 -297.452454) (xy 370.244792 -297.408311) (xy 370.217496 -297.359676)
			(xy 370.197573 -297.307585) (xy 370.185447 -297.253148) (xy 370.181376 -297.197526) (xy 365.944404 -297.197526)
			(xy 365.944404 -297.377866) (xy 365.628936 -297.69308) (xy 363.323886 -297.69308) (xy 362.996988 -297.366436)
			(xy 359.602024 -297.366436) (xy 359.602024 -297.377866) (xy 359.286556 -297.69308) (xy 357.006906 -297.69308)
			(xy 356.654608 -297.341036) (xy 353.302824 -297.341036) (xy 353.302824 -297.438826) (xy 353.077526 -297.664124)
			(xy 351.418906 -297.664124) (xy 351.092008 -297.337226) (xy 340.596423 -297.337226) (xy 340.603088 -297.448486)
			(xy 340.603586 -297.515026) (xy 340.603088 -297.581566) (xy 340.59513 -297.714408) (xy 340.579241 -297.846536)
			(xy 340.555478 -297.977477) (xy 340.523928 -298.106763) (xy 340.484702 -298.233931) (xy 340.437941 -298.358525)
			(xy 340.383812 -298.4801) (xy 340.32251 -298.59822) (xy 340.254253 -298.712462) (xy 340.179287 -298.822418)
			(xy 340.097878 -298.927694) (xy 340.01032 -299.027912) (xy 339.916925 -299.122715) (xy 339.818027 -299.211763)
			(xy 339.713981 -299.294737) (xy 339.605159 -299.371341) (xy 339.49195 -299.441299) (xy 339.37476 -299.504361)
			(xy 339.254009 -299.560302) (xy 339.130128 -299.608922) (xy 339.003562 -299.650046) (xy 338.874762 -299.683527)
			(xy 338.744191 -299.709245) (xy 338.612315 -299.727109) (xy 338.479607 -299.737054) (xy 338.346542 -299.739045)
			(xy 338.213596 -299.733074) (xy 338.081245 -299.719164) (xy 337.949963 -299.697363) (xy 337.82022 -299.66775)
			(xy 337.692479 -299.630431) (xy 337.5672 -299.585539) (xy 337.444829 -299.533235) (xy 337.325805 -299.473706)
			(xy 337.210554 -299.407166) (xy 337.099489 -299.333853) (xy 336.993008 -299.254029) (xy 336.89149 -299.167979)
			(xy 336.795301 -299.076013) (xy 336.704783 -298.978458) (xy 336.620262 -298.875665) (xy 336.54204 -298.768001)
			(xy 336.470396 -298.655851) (xy 336.405587 -298.539618) (xy 336.347846 -298.419717) (xy 336.297379 -298.296578)
			(xy 336.254366 -298.170641) (xy 336.218962 -298.042356) (xy 336.191293 -297.912184) (xy 336.171458 -297.780591)
			(xy 336.159529 -297.648046) (xy 336.155548 -297.515026) (xy 334.677512 -297.515026) (xy 334.677512 -302.743616)
			(xy 320.966338 -316.45479) (xy 345.576144 -316.45479) (xy 345.576144 -314.87999) (xy 345.576536 -314.866611)
			(xy 345.583474 -314.840769) (xy 345.596873 -314.817609) (xy 345.615818 -314.798713) (xy 345.639013 -314.785374)
			(xy 345.664872 -314.778502) (xy 345.678252 -314.778136) (xy 347.253052 -314.778136) (xy 347.266418 -314.778568)
			(xy 347.292243 -314.785468) (xy 347.315406 -314.79881) (xy 347.334332 -314.817688) (xy 347.347733 -314.840817)
			(xy 347.354698 -314.866625) (xy 347.35516 -314.87999) (xy 347.35516 -315.66739) (xy 347.550237 -315.66739)
			(xy 347.554259 -315.58167) (xy 347.56629 -315.496702) (xy 347.586226 -315.413235) (xy 347.613889 -315.332001)
			(xy 347.649038 -315.253715) (xy 347.691364 -315.179064) (xy 347.740493 -315.108705) (xy 347.795996 -315.043255)
			(xy 347.857383 -314.983291) (xy 347.924116 -314.929338) (xy 347.995608 -314.881871) (xy 348.07123 -314.841307)
			(xy 348.150319 -314.808003) (xy 348.232179 -314.782251) (xy 348.31609 -314.764278) (xy 348.401316 -314.754242)
			(xy 348.487108 -314.75223) (xy 348.57271 -314.758261) (xy 348.657372 -314.772281) (xy 348.740349 -314.794167)
			(xy 348.820912 -314.823728) (xy 348.898352 -314.860702) (xy 348.971991 -314.904766) (xy 349.041179 -314.955532)
			(xy 349.10531 -315.012553) (xy 349.163819 -315.075329) (xy 349.216192 -315.143309) (xy 349.26197 -315.215894)
			(xy 349.30075 -315.292446) (xy 349.332191 -315.372294) (xy 349.356017 -315.454735) (xy 349.372018 -315.539045)
			(xy 349.380053 -315.624483) (xy 349.380556 -315.66739) (xy 349.380053 -315.710297) (xy 349.372018 -315.795735)
			(xy 349.356017 -315.880045) (xy 349.332191 -315.962486) (xy 349.30075 -316.042334) (xy 349.26197 -316.118886)
			(xy 349.216192 -316.191471) (xy 349.163819 -316.259451) (xy 349.10531 -316.322227) (xy 349.041179 -316.379248)
			(xy 348.971991 -316.430014) (xy 348.930586 -316.45479) (xy 351.773744 -316.45479) (xy 351.773744 -314.87999)
			(xy 351.774136 -314.866611) (xy 351.781074 -314.840769) (xy 351.794473 -314.817609) (xy 351.813418 -314.798713)
			(xy 351.836613 -314.785374) (xy 351.862472 -314.778502) (xy 351.875852 -314.778136) (xy 353.450652 -314.778136)
			(xy 353.464018 -314.778568) (xy 353.489843 -314.785468) (xy 353.513006 -314.79881) (xy 353.531932 -314.817688)
			(xy 353.545333 -314.840817) (xy 353.552298 -314.866625) (xy 353.55276 -314.87999) (xy 353.55276 -315.66739)
			(xy 353.747837 -315.66739) (xy 353.751859 -315.58167) (xy 353.76389 -315.496702) (xy 353.783826 -315.413235)
			(xy 353.811489 -315.332001) (xy 353.846638 -315.253715) (xy 353.888964 -315.179064) (xy 353.938093 -315.108705)
			(xy 353.993596 -315.043255) (xy 354.054983 -314.983291) (xy 354.121716 -314.929338) (xy 354.193208 -314.881871)
			(xy 354.26883 -314.841307) (xy 354.347919 -314.808003) (xy 354.429779 -314.782251) (xy 354.51369 -314.764278)
			(xy 354.598916 -314.754242) (xy 354.684708 -314.75223) (xy 354.77031 -314.758261) (xy 354.854972 -314.772281)
			(xy 354.937949 -314.794167) (xy 355.018512 -314.823728) (xy 355.095952 -314.860702) (xy 355.169591 -314.904766)
			(xy 355.238779 -314.955532) (xy 355.30291 -315.012553) (xy 355.361419 -315.075329) (xy 355.413792 -315.143309)
			(xy 355.45957 -315.215894) (xy 355.49835 -315.292446) (xy 355.529791 -315.372294) (xy 355.553617 -315.454735)
			(xy 355.569618 -315.539045) (xy 355.577653 -315.624483) (xy 355.578156 -315.66739) (xy 355.577653 -315.710297)
			(xy 355.569618 -315.795735) (xy 355.553617 -315.880045) (xy 355.529791 -315.962486) (xy 355.49835 -316.042334)
			(xy 355.45957 -316.118886) (xy 355.413792 -316.191471) (xy 355.361419 -316.259451) (xy 355.30291 -316.322227)
			(xy 355.238779 -316.379248) (xy 355.169591 -316.430014) (xy 355.128186 -316.45479) (xy 357.951532 -316.45479)
			(xy 357.951532 -314.87999) (xy 357.951936 -314.866612) (xy 357.958873 -314.840772) (xy 357.97227 -314.817613)
			(xy 357.991212 -314.798718) (xy 358.014404 -314.785377) (xy 358.040262 -314.778504) (xy 358.05364 -314.778136)
			(xy 359.62844 -314.778136) (xy 359.64181 -314.778491) (xy 359.667638 -314.785412) (xy 359.690801 -314.798772)
			(xy 359.709724 -314.817664) (xy 359.723123 -314.840804) (xy 359.730086 -314.866621) (xy 359.730548 -314.87999)
			(xy 359.730548 -315.66739) (xy 359.925625 -315.66739) (xy 359.929647 -315.58167) (xy 359.941678 -315.496702)
			(xy 359.961614 -315.413235) (xy 359.989277 -315.332001) (xy 360.024426 -315.253715) (xy 360.066752 -315.179064)
			(xy 360.115881 -315.108705) (xy 360.171384 -315.043255) (xy 360.232771 -314.983291) (xy 360.299504 -314.929338)
			(xy 360.370996 -314.881871) (xy 360.446618 -314.841307) (xy 360.525707 -314.808003) (xy 360.607567 -314.782251)
			(xy 360.691478 -314.764278) (xy 360.776704 -314.754242) (xy 360.862496 -314.75223) (xy 360.948098 -314.758261)
			(xy 361.03276 -314.772281) (xy 361.115737 -314.794167) (xy 361.1963 -314.823728) (xy 361.27374 -314.860702)
			(xy 361.347379 -314.904766) (xy 361.416567 -314.955532) (xy 361.480698 -315.012553) (xy 361.539207 -315.075329)
			(xy 361.59158 -315.143309) (xy 361.637358 -315.215894) (xy 361.676138 -315.292446) (xy 361.707579 -315.372294)
			(xy 361.731405 -315.454735) (xy 361.747406 -315.539045) (xy 361.755441 -315.624483) (xy 361.755944 -315.66739)
			(xy 361.755441 -315.710297) (xy 361.747406 -315.795735) (xy 361.731405 -315.880045) (xy 361.707579 -315.962486)
			(xy 361.676138 -316.042334) (xy 361.637358 -316.118886) (xy 361.59158 -316.191471) (xy 361.539207 -316.259451)
			(xy 361.480698 -316.322227) (xy 361.416567 -316.379248) (xy 361.347379 -316.430014) (xy 361.305974 -316.45479)
			(xy 364.149132 -316.45479) (xy 364.149132 -314.87999) (xy 364.149536 -314.866612) (xy 364.156473 -314.840772)
			(xy 364.16987 -314.817613) (xy 364.188812 -314.798718) (xy 364.212004 -314.785377) (xy 364.237862 -314.778504)
			(xy 364.25124 -314.778136) (xy 365.82604 -314.778136) (xy 365.83941 -314.778491) (xy 365.865238 -314.785412)
			(xy 365.888401 -314.798772) (xy 365.907324 -314.817664) (xy 365.920723 -314.840804) (xy 365.927686 -314.866621)
			(xy 365.928148 -314.87999) (xy 365.928148 -315.66739) (xy 366.123225 -315.66739) (xy 366.127247 -315.58167)
			(xy 366.139278 -315.496702) (xy 366.159214 -315.413235) (xy 366.186877 -315.332001) (xy 366.222026 -315.253715)
			(xy 366.264352 -315.179064) (xy 366.313481 -315.108705) (xy 366.368984 -315.043255) (xy 366.430371 -314.983291)
			(xy 366.497104 -314.929338) (xy 366.568596 -314.881871) (xy 366.644218 -314.841307) (xy 366.723307 -314.808003)
			(xy 366.805167 -314.782251) (xy 366.889078 -314.764278) (xy 366.974304 -314.754242) (xy 367.060096 -314.75223)
			(xy 367.145698 -314.758261) (xy 367.23036 -314.772281) (xy 367.313337 -314.794167) (xy 367.3939 -314.823728)
			(xy 367.47134 -314.860702) (xy 367.544979 -314.904766) (xy 367.614167 -314.955532) (xy 367.678298 -315.012553)
			(xy 367.736807 -315.075329) (xy 367.78918 -315.143309) (xy 367.834958 -315.215894) (xy 367.873738 -315.292446)
			(xy 367.905179 -315.372294) (xy 367.929005 -315.454735) (xy 367.945006 -315.539045) (xy 367.953041 -315.624483)
			(xy 367.953544 -315.66739) (xy 367.953041 -315.710297) (xy 367.945006 -315.795735) (xy 367.929005 -315.880045)
			(xy 367.905179 -315.962486) (xy 367.873738 -316.042334) (xy 367.834958 -316.118886) (xy 367.78918 -316.191471)
			(xy 367.736807 -316.259451) (xy 367.678298 -316.322227) (xy 367.614167 -316.379248) (xy 367.544979 -316.430014)
			(xy 367.503574 -316.45479) (xy 370.346732 -316.45479) (xy 370.346732 -314.87999) (xy 370.347136 -314.866612)
			(xy 370.354073 -314.840772) (xy 370.36747 -314.817613) (xy 370.386412 -314.798718) (xy 370.409604 -314.785377)
			(xy 370.435462 -314.778504) (xy 370.44884 -314.778136) (xy 372.02364 -314.778136) (xy 372.03701 -314.778491)
			(xy 372.062838 -314.785412) (xy 372.086001 -314.798772) (xy 372.104924 -314.817664) (xy 372.118323 -314.840804)
			(xy 372.125286 -314.866621) (xy 372.125748 -314.87999) (xy 372.125748 -315.66739) (xy 372.320825 -315.66739)
			(xy 372.324847 -315.58167) (xy 372.336878 -315.496702) (xy 372.356814 -315.413235) (xy 372.384477 -315.332001)
			(xy 372.419626 -315.253715) (xy 372.461952 -315.179064) (xy 372.511081 -315.108705) (xy 372.566584 -315.043255)
			(xy 372.627971 -314.983291) (xy 372.694704 -314.929338) (xy 372.766196 -314.881871) (xy 372.841818 -314.841307)
			(xy 372.920907 -314.808003) (xy 373.002767 -314.782251) (xy 373.086678 -314.764278) (xy 373.171904 -314.754242)
			(xy 373.257696 -314.75223) (xy 373.343298 -314.758261) (xy 373.42796 -314.772281) (xy 373.510937 -314.794167)
			(xy 373.5915 -314.823728) (xy 373.66894 -314.860702) (xy 373.742579 -314.904766) (xy 373.811767 -314.955532)
			(xy 373.875898 -315.012553) (xy 373.934407 -315.075329) (xy 373.98678 -315.143309) (xy 374.032558 -315.215894)
			(xy 374.071338 -315.292446) (xy 374.102779 -315.372294) (xy 374.126605 -315.454735) (xy 374.142606 -315.539045)
			(xy 374.150641 -315.624483) (xy 374.151144 -315.66739) (xy 374.150641 -315.710297) (xy 374.142606 -315.795735)
			(xy 374.126605 -315.880045) (xy 374.102779 -315.962486) (xy 374.071338 -316.042334) (xy 374.032558 -316.118886)
			(xy 373.98678 -316.191471) (xy 373.934407 -316.259451) (xy 373.875898 -316.322227) (xy 373.811767 -316.379248)
			(xy 373.742579 -316.430014) (xy 373.66894 -316.474078) (xy 373.5915 -316.511052) (xy 373.510937 -316.540613)
			(xy 373.42796 -316.562499) (xy 373.343298 -316.576519) (xy 373.257696 -316.58255) (xy 373.171904 -316.580538)
			(xy 373.086678 -316.570502) (xy 373.002767 -316.552529) (xy 372.920907 -316.526777) (xy 372.841818 -316.493473)
			(xy 372.766196 -316.452909) (xy 372.694704 -316.405442) (xy 372.627971 -316.351489) (xy 372.566584 -316.291525)
			(xy 372.511081 -316.226075) (xy 372.461952 -316.155716) (xy 372.419626 -316.081065) (xy 372.384477 -316.002779)
			(xy 372.356814 -315.921545) (xy 372.336878 -315.838078) (xy 372.324847 -315.75311) (xy 372.320825 -315.66739)
			(xy 372.125748 -315.66739) (xy 372.125748 -316.45479) (xy 372.125346 -316.468168) (xy 372.118412 -316.494011)
			(xy 372.105015 -316.517172) (xy 372.086073 -316.536068) (xy 372.062878 -316.549408) (xy 372.037019 -316.556278)
			(xy 372.02364 -316.556644) (xy 370.44884 -316.556644) (xy 370.43548 -316.55614) (xy 370.409667 -316.549245)
			(xy 370.386511 -316.535914) (xy 370.367588 -316.517051) (xy 370.354182 -316.493939) (xy 370.347204 -316.468148)
			(xy 370.346732 -316.45479) (xy 367.503574 -316.45479) (xy 367.47134 -316.474078) (xy 367.3939 -316.511052)
			(xy 367.313337 -316.540613) (xy 367.23036 -316.562499) (xy 367.145698 -316.576519) (xy 367.060096 -316.58255)
			(xy 366.974304 -316.580538) (xy 366.889078 -316.570502) (xy 366.805167 -316.552529) (xy 366.723307 -316.526777)
			(xy 366.644218 -316.493473) (xy 366.568596 -316.452909) (xy 366.497104 -316.405442) (xy 366.430371 -316.351489)
			(xy 366.368984 -316.291525) (xy 366.313481 -316.226075) (xy 366.264352 -316.155716) (xy 366.222026 -316.081065)
			(xy 366.186877 -316.002779) (xy 366.159214 -315.921545) (xy 366.139278 -315.838078) (xy 366.127247 -315.75311)
			(xy 366.123225 -315.66739) (xy 365.928148 -315.66739) (xy 365.928148 -316.45479) (xy 365.927746 -316.468168)
			(xy 365.920812 -316.494011) (xy 365.907415 -316.517172) (xy 365.888473 -316.536068) (xy 365.865278 -316.549408)
			(xy 365.839419 -316.556278) (xy 365.82604 -316.556644) (xy 364.25124 -316.556644) (xy 364.23788 -316.55614)
			(xy 364.212067 -316.549245) (xy 364.188911 -316.535914) (xy 364.169988 -316.517051) (xy 364.156582 -316.493939)
			(xy 364.149604 -316.468148) (xy 364.149132 -316.45479) (xy 361.305974 -316.45479) (xy 361.27374 -316.474078)
			(xy 361.1963 -316.511052) (xy 361.115737 -316.540613) (xy 361.03276 -316.562499) (xy 360.948098 -316.576519)
			(xy 360.862496 -316.58255) (xy 360.776704 -316.580538) (xy 360.691478 -316.570502) (xy 360.607567 -316.552529)
			(xy 360.525707 -316.526777) (xy 360.446618 -316.493473) (xy 360.370996 -316.452909) (xy 360.299504 -316.405442)
			(xy 360.232771 -316.351489) (xy 360.171384 -316.291525) (xy 360.115881 -316.226075) (xy 360.066752 -316.155716)
			(xy 360.024426 -316.081065) (xy 359.989277 -316.002779) (xy 359.961614 -315.921545) (xy 359.941678 -315.838078)
			(xy 359.929647 -315.75311) (xy 359.925625 -315.66739) (xy 359.730548 -315.66739) (xy 359.730548 -316.45479)
			(xy 359.730146 -316.468168) (xy 359.723212 -316.494011) (xy 359.709815 -316.517172) (xy 359.690873 -316.536068)
			(xy 359.667678 -316.549408) (xy 359.641819 -316.556278) (xy 359.62844 -316.556644) (xy 358.05364 -316.556644)
			(xy 358.04028 -316.55614) (xy 358.014467 -316.549245) (xy 357.991311 -316.535914) (xy 357.972388 -316.517051)
			(xy 357.958982 -316.493939) (xy 357.952004 -316.468148) (xy 357.951532 -316.45479) (xy 355.128186 -316.45479)
			(xy 355.095952 -316.474078) (xy 355.018512 -316.511052) (xy 354.937949 -316.540613) (xy 354.854972 -316.562499)
			(xy 354.77031 -316.576519) (xy 354.684708 -316.58255) (xy 354.598916 -316.580538) (xy 354.51369 -316.570502)
			(xy 354.429779 -316.552529) (xy 354.347919 -316.526777) (xy 354.26883 -316.493473) (xy 354.193208 -316.452909)
			(xy 354.121716 -316.405442) (xy 354.054983 -316.351489) (xy 353.993596 -316.291525) (xy 353.938093 -316.226075)
			(xy 353.888964 -316.155716) (xy 353.846638 -316.081065) (xy 353.811489 -316.002779) (xy 353.783826 -315.921545)
			(xy 353.76389 -315.838078) (xy 353.751859 -315.75311) (xy 353.747837 -315.66739) (xy 353.55276 -315.66739)
			(xy 353.55276 -316.45479) (xy 353.552346 -316.468167) (xy 353.545413 -316.494008) (xy 353.532018 -316.517168)
			(xy 353.513078 -316.536064) (xy 353.489887 -316.549404) (xy 353.46403 -316.556277) (xy 353.450652 -316.556644)
			(xy 351.875852 -316.556644) (xy 351.862489 -316.556217) (xy 351.836672 -316.549302) (xy 351.813517 -316.535953)
			(xy 351.794595 -316.517076) (xy 351.781192 -316.493953) (xy 351.774215 -316.468152) (xy 351.773744 -316.45479)
			(xy 348.930586 -316.45479) (xy 348.898352 -316.474078) (xy 348.820912 -316.511052) (xy 348.740349 -316.540613)
			(xy 348.657372 -316.562499) (xy 348.57271 -316.576519) (xy 348.487108 -316.58255) (xy 348.401316 -316.580538)
			(xy 348.31609 -316.570502) (xy 348.232179 -316.552529) (xy 348.150319 -316.526777) (xy 348.07123 -316.493473)
			(xy 347.995608 -316.452909) (xy 347.924116 -316.405442) (xy 347.857383 -316.351489) (xy 347.795996 -316.291525)
			(xy 347.740493 -316.226075) (xy 347.691364 -316.155716) (xy 347.649038 -316.081065) (xy 347.613889 -316.002779)
			(xy 347.586226 -315.921545) (xy 347.56629 -315.838078) (xy 347.554259 -315.75311) (xy 347.550237 -315.66739)
			(xy 347.35516 -315.66739) (xy 347.35516 -316.45479) (xy 347.354746 -316.468167) (xy 347.347813 -316.494008)
			(xy 347.334418 -316.517168) (xy 347.315478 -316.536064) (xy 347.292287 -316.549404) (xy 347.26643 -316.556277)
			(xy 347.253052 -316.556644) (xy 345.678252 -316.556644) (xy 345.664889 -316.556217) (xy 345.639072 -316.549302)
			(xy 345.615917 -316.535953) (xy 345.596995 -316.517076) (xy 345.583592 -316.493953) (xy 345.576615 -316.468152)
			(xy 345.576144 -316.45479) (xy 320.966338 -316.45479) (xy 317.7032 -319.717928) (xy 317.7032 -330.561188)
			(xy 318.512444 -331.370432) (xy 330.788264 -331.370432)
		)
		(stroke
			(width 0)
			(type solid)
		)
		(fill yes)
		(layer "F.Cu")
		(net "PVCCIN_CPU0")
	)
	(gr_poly
		(pts
			(xy 82.840576 -331.357224) (xy 82.850538 -331.356737) (xy 82.868962 -331.349149) (xy 82.87639 -331.342492)
			(xy 83.468718 -330.750164) (xy 83.48345 -330.735178) (xy 83.48345 -327.45934) (xy 83.483886 -327.449276)
			(xy 83.491621 -327.430692) (xy 83.498436 -327.423272) (xy 85.381338 -325.54037) (xy 85.388735 -325.533522)
			(xy 85.407334 -325.52579) (xy 85.417406 -325.525384) (xy 91.230704 -325.525384) (xy 91.24569 -325.510652)
			(xy 94.515686 -322.240656) (xy 94.523087 -322.233817) (xy 94.541685 -322.226105) (xy 94.551754 -322.22567)
			(xy 124.229876 -322.22567) (xy 124.239927 -322.226175) (xy 124.258489 -322.233895) (xy 124.265944 -322.240656)
			(xy 127.615188 -325.5899) (xy 127.630174 -325.604632) (xy 132.236718 -325.604632) (xy 132.246786 -325.605059)
			(xy 132.265383 -325.612782) (xy 132.272786 -325.619618) (xy 132.531612 -325.878444) (xy 132.538461 -325.88584)
			(xy 132.546194 -325.90444) (xy 132.546598 -325.914512) (xy 132.546598 -326.924924) (xy 132.56133 -326.93991)
			(xy 134.522464 -328.901044) (xy 134.529307 -328.908443) (xy 134.537031 -328.927042) (xy 134.53745 -328.937112)
			(xy 134.53745 -329.660758) (xy 134.552182 -329.675744) (xy 136.181338 -331.3049) (xy 136.196324 -331.319632)
			(xy 144.663414 -331.319632) (xy 144.665192 -331.317854) (xy 150.749 -331.317854) (xy 150.75408 -331.313028)
			(xy 151.88692 -331.313028) (xy 152.4 -330.799948) (xy 152.4 -317.642748) (xy 136.85901 -302.101758)
			(xy 136.85901 -290.902136) (xy 136.859309 -290.894265) (xy 136.864102 -290.879268) (xy 136.868408 -290.872672)
			(xy 136.877806 -290.859464) (xy 136.877806 -289.4965) (xy 136.86282 -289.481514) (xy 136.796272 -289.414966)
			(xy 136.781286 -289.39998) (xy 134.838186 -289.39998) (xy 134.8232 -289.414966) (xy 134.594854 -289.643312)
			(xy 134.60857 -289.675316) (xy 134.6171 -289.695845) (xy 134.629208 -289.738621) (xy 134.635488 -289.782631)
			(xy 134.636002 -289.804856) (xy 134.636002 -289.81019) (xy 134.635276 -289.835866) (xy 134.626862 -289.886536)
			(xy 134.610715 -289.935295) (xy 134.587223 -289.980972) (xy 134.556952 -290.022467) (xy 134.52063 -290.058784)
			(xy 134.47913 -290.089049) (xy 134.43345 -290.112533) (xy 134.384688 -290.128673) (xy 134.334018 -290.137081)
			(xy 134.308342 -290.13785) (xy 134.30504 -290.13785) (xy 134.282472 -290.137471) (xy 134.237759 -290.131302)
			(xy 134.194302 -290.119101) (xy 134.173468 -290.110418) (xy 134.141464 -290.096702) (xy 133.994398 -290.243768)
			(xy 133.987001 -290.250618) (xy 133.968403 -290.258356) (xy 133.95833 -290.258754) (xy 119.973598 -290.258754)
			(xy 119.963529 -290.258329) (xy 119.944929 -290.250609) (xy 119.93753 -290.243768) (xy 119.8372 -290.143438)
			(xy 119.830363 -290.136036) (xy 119.822651 -290.117438) (xy 119.822214 -290.10737) (xy 119.822214 -289.328606)
			(xy 119.745252 -289.248596) (xy 119.724932 -289.24758) (xy 119.706206 -289.246515) (xy 119.669159 -289.24066)
			(xy 119.651018 -289.235896) (xy 119.644414 -289.234118) (xy 119.586248 -289.234118) (xy 119.586248 -289.296602)
			(xy 119.585658 -289.324792) (xy 119.575751 -289.380295) (xy 119.556213 -289.433181) (xy 119.527656 -289.481794)
			(xy 119.509794 -289.503612) (xy 119.497348 -289.517836) (xy 119.497348 -289.56762) (xy 119.511064 -289.582352)
			(xy 119.527532 -289.600804) (xy 119.555366 -289.641681) (xy 119.576803 -289.686248) (xy 119.591363 -289.733511)
			(xy 119.598722 -289.782415) (xy 119.599202 -289.807142) (xy 119.598692 -289.833129) (xy 119.590562 -289.884464)
			(xy 119.574501 -289.933894) (xy 119.550905 -289.980204) (xy 119.520355 -290.022252) (xy 119.483604 -290.059003)
			(xy 119.441556 -290.089553) (xy 119.395246 -290.113149) (xy 119.345816 -290.12921) (xy 119.294481 -290.13734)
			(xy 119.242507 -290.13734) (xy 119.191172 -290.12921) (xy 119.141742 -290.113149) (xy 119.095432 -290.089553)
			(xy 119.053384 -290.059003) (xy 119.016633 -290.022252) (xy 118.986083 -289.980204) (xy 118.962487 -289.933894)
			(xy 118.946426 -289.884464) (xy 118.938296 -289.833129) (xy 118.937786 -289.807142) (xy 118.938244 -289.782413)
			(xy 118.945603 -289.733506) (xy 118.960164 -289.686239) (xy 118.981601 -289.641669) (xy 119.009437 -289.600788)
			(xy 119.025924 -289.582352) (xy 119.03964 -289.56762) (xy 119.03964 -289.517836) (xy 119.027194 -289.503612)
			(xy 119.009311 -289.481809) (xy 118.98075 -289.433194) (xy 118.961215 -289.380303) (xy 118.951319 -289.324794)
			(xy 118.95074 -289.296602) (xy 118.95074 -289.195002) (xy 118.951229 -289.170032) (xy 118.959041 -289.120708)
			(xy 118.974473 -289.073213) (xy 118.997144 -289.028717) (xy 119.026497 -288.988315) (xy 119.061809 -288.953002)
			(xy 119.10221 -288.923648) (xy 119.146706 -288.900976) (xy 119.1942 -288.885543) (xy 119.243524 -288.87773)
			(xy 119.268494 -288.877248) (xy 119.291354 -288.87801) (xy 119.314468 -288.880296) (xy 119.332502 -288.882836)
			(xy 119.419116 -288.82975) (xy 119.424958 -288.812224) (xy 119.434515 -288.785444) (xy 119.461463 -288.735382)
			(xy 119.478552 -288.712656) (xy 119.483632 -288.706306) (xy 119.495316 -288.674048) (xy 119.494808 -288.642298)
			(xy 119.481854 -288.609532) (xy 119.47652 -288.603182) (xy 119.461247 -288.584479) (xy 119.435542 -288.543603)
			(xy 119.415804 -288.499535) (xy 119.402422 -288.45314) (xy 119.395659 -288.405329) (xy 119.39524 -288.381186)
			(xy 119.395741 -288.3549) (xy 119.403755 -288.302942) (xy 119.419594 -288.252812) (xy 119.442887 -288.205681)
			(xy 119.473091 -288.16265) (xy 119.509499 -288.124725) (xy 119.551262 -288.092792) (xy 119.597403 -288.067596)
			(xy 119.646846 -288.049726) (xy 119.698434 -288.0396) (xy 119.724678 -288.038032) (xy 119.744998 -288.03727)
			(xy 119.822214 -287.957006) (xy 119.822214 -287.70072) (xy 119.745252 -287.62071) (xy 119.724932 -287.619694)
			(xy 119.69967 -287.618167) (xy 119.650016 -287.608395) (xy 119.602431 -287.591172) (xy 119.558025 -287.5669)
			(xy 119.517836 -287.536145) (xy 119.482803 -287.499626) (xy 119.453743 -287.458195) (xy 119.431335 -287.41282)
			(xy 119.416102 -287.36456) (xy 119.4084 -287.314543) (xy 119.40794 -287.28924) (xy 119.408472 -287.261675)
			(xy 119.417578 -287.207304) (xy 119.435577 -287.155197) (xy 119.461972 -287.106798) (xy 119.478552 -287.08477)
			(xy 119.483632 -287.07842) (xy 119.495316 -287.046162) (xy 119.494808 -287.014412) (xy 119.481854 -286.981646)
			(xy 119.47652 -286.975296) (xy 119.462571 -286.95831) (xy 119.438683 -286.921413) (xy 119.419714 -286.881763)
			(xy 119.412512 -286.860996) (xy 119.409718 -286.852614) (xy 119.387874 -286.82442) (xy 119.361204 -286.80791)
			(xy 119.35315 -286.803413) (xy 119.335053 -286.799913) (xy 119.325898 -286.801052) (xy 119.311727 -286.803402)
			(xy 119.283112 -286.805943) (xy 119.268748 -286.806132) (xy 119.242756 -286.805652) (xy 119.19141 -286.797527)
			(xy 119.141967 -286.78147) (xy 119.095646 -286.757875) (xy 119.053586 -286.727324) (xy 119.016823 -286.690569)
			(xy 118.986263 -286.648516) (xy 118.962658 -286.602199) (xy 118.946589 -286.55276) (xy 118.938453 -286.501416)
			(xy 118.93804 -286.475424) (xy 118.938639 -286.446871) (xy 118.948438 -286.390614) (xy 118.967751 -286.336873)
			(xy 118.996002 -286.287246) (xy 119.013732 -286.264858) (xy 119.019228 -286.257677) (xy 119.025205 -286.240625)
			(xy 119.025416 -286.231584) (xy 119.024654 -286.200596) (xy 119.011954 -286.168084) (xy 119.00662 -286.16148)
			(xy 118.991759 -286.143378) (xy 118.96657 -286.103893) (xy 118.946991 -286.061347) (xy 118.939818 -286.039052)
			(xy 118.93423 -286.02051) (xy 118.91772 -286.01035) (xy 118.877334 -285.985458) (xy 118.855744 -285.987236)
			(xy 118.853712 -285.98749) (xy 118.840098 -285.989639) (xy 118.81263 -285.991931) (xy 118.798848 -285.992062)
			(xy 118.772858 -285.991582) (xy 118.721516 -285.983457) (xy 118.672078 -285.967398) (xy 118.625761 -285.943802)
			(xy 118.583707 -285.91325) (xy 118.546951 -285.876494) (xy 118.516399 -285.83444) (xy 118.492802 -285.788124)
			(xy 118.476744 -285.738686) (xy 118.468618 -285.687344) (xy 118.46814 -285.661354) (xy 118.468671 -285.633789)
			(xy 118.477775 -285.579417) (xy 118.495773 -285.527308) (xy 118.522166 -285.478907) (xy 118.538752 -285.456884)
			(xy 118.543832 -285.450534) (xy 118.555516 -285.418276) (xy 118.555008 -285.386526) (xy 118.542054 -285.35376)
			(xy 118.53672 -285.34741) (xy 118.52277 -285.330424) (xy 118.498881 -285.293528) (xy 118.47991 -285.253878)
			(xy 118.472712 -285.23311) (xy 118.469918 -285.224728) (xy 118.448074 -285.196534) (xy 118.421404 -285.180024)
			(xy 118.41335 -285.175526) (xy 118.395253 -285.172025) (xy 118.386098 -285.173166) (xy 118.371927 -285.175516)
			(xy 118.343312 -285.178057) (xy 118.328948 -285.178246) (xy 118.302955 -285.177766) (xy 118.251609 -285.169641)
			(xy 118.202165 -285.153584) (xy 118.155843 -285.129989) (xy 118.113781 -285.099439) (xy 118.077017 -285.062684)
			(xy 118.046456 -285.020631) (xy 118.022849 -284.974314) (xy 118.006779 -284.924875) (xy 117.99864 -284.873531)
			(xy 117.99824 -284.847538) (xy 117.998838 -284.818985) (xy 118.008635 -284.762726) (xy 118.027946 -284.708984)
			(xy 118.056196 -284.659356) (xy 118.073932 -284.636972) (xy 118.07943 -284.629792) (xy 118.085412 -284.612739)
			(xy 118.085616 -284.603698) (xy 118.084854 -284.57271) (xy 118.072154 -284.540198) (xy 118.06682 -284.533594)
			(xy 118.051497 -284.514915) (xy 118.0257 -284.474065) (xy 118.005891 -284.43) (xy 117.992464 -284.38359)
			(xy 117.985683 -284.335755) (xy 117.985286 -284.311598) (xy 117.985815 -284.284613) (xy 117.994258 -284.231307)
			(xy 118.010936 -284.179978) (xy 118.035438 -284.13189) (xy 118.067161 -284.088227) (xy 118.105324 -284.050064)
			(xy 118.148986 -284.01834) (xy 118.197074 -283.993838) (xy 118.248403 -283.977159) (xy 118.301709 -283.968716)
			(xy 118.328694 -283.96819) (xy 118.329456 -283.96819) (xy 118.346528 -283.968427) (xy 118.3805 -283.971863)
			(xy 118.397274 -283.975048) (xy 118.399814 -283.975556) (xy 118.421658 -283.977588) (xy 118.480078 -283.944822)
			(xy 118.486255 -283.923962) (xy 118.503348 -283.883957) (xy 118.525558 -283.846549) (xy 118.538752 -283.829252)
			(xy 118.543832 -283.822648) (xy 118.555262 -283.790898) (xy 118.554754 -283.75864) (xy 118.542054 -283.726128)
			(xy 118.53672 -283.719778) (xy 118.522772 -283.702791) (xy 118.498886 -283.665894) (xy 118.479919 -283.626243)
			(xy 118.472712 -283.605478) (xy 118.469918 -283.597096) (xy 118.448074 -283.568902) (xy 118.421404 -283.552392)
			(xy 118.41335 -283.547896) (xy 118.395253 -283.544397) (xy 118.386098 -283.545534) (xy 118.371927 -283.547884)
			(xy 118.343312 -283.550426) (xy 118.328948 -283.550614) (xy 118.302956 -283.550134) (xy 118.251611 -283.542009)
			(xy 118.20217 -283.525951) (xy 118.15585 -283.502356) (xy 118.113791 -283.471805) (xy 118.07703 -283.43505)
			(xy 118.046472 -283.392996) (xy 118.022869 -283.34668) (xy 118.006803 -283.297241) (xy 117.99867 -283.245898)
			(xy 117.99824 -283.219906) (xy 117.99884 -283.191354) (xy 118.008643 -283.135098) (xy 118.027957 -283.081359)
			(xy 118.056211 -283.031735) (xy 118.073932 -283.00934) (xy 118.079425 -283.002158) (xy 118.085396 -282.985106)
			(xy 118.085616 -282.976066) (xy 118.084854 -282.945078) (xy 118.072154 -282.912566) (xy 118.06682 -282.905962)
			(xy 118.05196 -282.887859) (xy 118.026773 -282.848374) (xy 118.007196 -282.805827) (xy 118.000018 -282.783534)
			(xy 117.99443 -282.764992) (xy 117.97792 -282.754832) (xy 117.937534 -282.72994) (xy 117.915944 -282.731718)
			(xy 117.913912 -282.731972) (xy 117.900298 -282.734121) (xy 117.87283 -282.736413) (xy 117.859048 -282.736544)
			(xy 117.833055 -282.736064) (xy 117.781709 -282.727939) (xy 117.732266 -282.711882) (xy 117.685943 -282.688287)
			(xy 117.643882 -282.657737) (xy 117.607118 -282.620982) (xy 117.576557 -282.578929) (xy 117.55295 -282.532612)
			(xy 117.53688 -282.483173) (xy 117.528742 -282.431829) (xy 117.52834 -282.405836) (xy 117.528864 -282.378269)
			(xy 117.537956 -282.32389) (xy 117.555944 -282.271773) (xy 117.582329 -282.223363) (xy 117.598952 -282.201366)
			(xy 117.604032 -282.195016) (xy 117.615716 -282.162758) (xy 117.615208 -282.131008) (xy 117.602254 -282.098242)
			(xy 117.59692 -282.091892) (xy 117.582971 -282.074906) (xy 117.559083 -282.038009) (xy 117.540115 -281.998358)
			(xy 117.532912 -281.977592) (xy 117.530118 -281.96921) (xy 117.508274 -281.941016) (xy 117.481604 -281.924506)
			(xy 117.47355 -281.920009) (xy 117.455453 -281.916509) (xy 117.446298 -281.917648) (xy 117.432127 -281.919998)
			(xy 117.403512 -281.92254) (xy 117.389148 -281.922728) (xy 117.363156 -281.922248) (xy 117.31181 -281.914123)
			(xy 117.262368 -281.898066) (xy 117.216047 -281.874471) (xy 117.173987 -281.84392) (xy 117.137225 -281.807165)
			(xy 117.106665 -281.765111) (xy 117.08306 -281.718795) (xy 117.066993 -281.669356) (xy 117.058857 -281.618012)
			(xy 117.05844 -281.59202) (xy 117.059039 -281.563468) (xy 117.068839 -281.50721) (xy 117.088152 -281.45347)
			(xy 117.116404 -281.403844) (xy 117.134132 -281.381454) (xy 117.139627 -281.374273) (xy 117.145603 -281.357221)
			(xy 117.145816 -281.34818) (xy 117.145054 -281.317192) (xy 117.132354 -281.28468) (xy 117.12702 -281.278076)
			(xy 117.113044 -281.261085) (xy 117.089069 -281.224197) (xy 117.069997 -281.184551) (xy 117.062758 -281.163776)
			(xy 117.059964 -281.155394) (xy 117.03812 -281.1272) (xy 116.997734 -281.102308) (xy 116.976144 -281.104086)
			(xy 116.974112 -281.10434) (xy 116.960498 -281.106488) (xy 116.93303 -281.10878) (xy 116.919248 -281.108912)
			(xy 116.893256 -281.108432) (xy 116.841912 -281.100307) (xy 116.79247 -281.084249) (xy 116.74615 -281.060654)
			(xy 116.704092 -281.030103) (xy 116.667331 -280.993348) (xy 116.636773 -280.951294) (xy 116.613171 -280.904978)
			(xy 116.597105 -280.855539) (xy 116.588972 -280.804196) (xy 116.58854 -280.778204) (xy 116.589066 -280.750638)
			(xy 116.598163 -280.696261) (xy 116.616155 -280.644148) (xy 116.642543 -280.595741) (xy 116.659152 -280.573734)
			(xy 116.664232 -280.567384) (xy 116.675916 -280.535126) (xy 116.675408 -280.503376) (xy 116.662454 -280.470356)
			(xy 116.65712 -280.464006) (xy 116.643159 -280.446981) (xy 116.619262 -280.410001) (xy 116.600304 -280.370262)
			(xy 116.593112 -280.349452) (xy 116.590318 -280.341324) (xy 116.568474 -280.31313) (xy 116.524786 -280.285952)
			(xy 116.506199 -280.290077) (xy 116.468385 -280.294532) (xy 116.449348 -280.294842) (xy 116.423355 -280.294362)
			(xy 116.372009 -280.286237) (xy 116.322566 -280.27018) (xy 116.276243 -280.246585) (xy 116.234183 -280.216034)
			(xy 116.197419 -280.17928) (xy 116.166858 -280.137227) (xy 116.143252 -280.09091) (xy 116.127182 -280.041471)
			(xy 116.119044 -279.990127) (xy 116.11864 -279.964134) (xy 116.119238 -279.935581) (xy 116.129036 -279.879322)
			(xy 116.148347 -279.825581) (xy 116.176598 -279.775953) (xy 116.194332 -279.753568) (xy 116.199829 -279.746388)
			(xy 116.20581 -279.729335) (xy 116.206016 -279.720294) (xy 116.205254 -279.689306) (xy 116.192554 -279.656794)
			(xy 116.18722 -279.65019) (xy 116.173248 -279.633197) (xy 116.149282 -279.596305) (xy 116.130219 -279.556657)
			(xy 116.122958 -279.53589) (xy 116.120164 -279.527508) (xy 116.09832 -279.499314) (xy 116.07165 -279.482804)
			(xy 116.063597 -279.4783) (xy 116.045498 -279.474784) (xy 116.036344 -279.475946) (xy 116.022173 -279.478298)
			(xy 115.993558 -279.480843) (xy 115.979194 -279.481026) (xy 115.953207 -279.480516) (xy 115.901872 -279.472385)
			(xy 115.852441 -279.456324) (xy 115.806131 -279.432728) (xy 115.764082 -279.402178) (xy 115.72733 -279.365427)
			(xy 115.696779 -279.323379) (xy 115.673181 -279.27707) (xy 115.657118 -279.22764) (xy 115.648985 -279.176305)
			(xy 115.648486 -279.150318) (xy 115.649038 -279.122741) (xy 115.658193 -279.068352) (xy 115.676252 -279.016238)
			(xy 115.702713 -278.967846) (xy 115.719352 -278.945848) (xy 115.724432 -278.939244) (xy 115.735862 -278.907494)
			(xy 115.735354 -278.875236) (xy 115.722654 -278.842724) (xy 115.71732 -278.836374) (xy 115.703372 -278.819387)
			(xy 115.679486 -278.78249) (xy 115.66052 -278.742838) (xy 115.653312 -278.722074) (xy 115.650518 -278.713692)
			(xy 115.628674 -278.685498) (xy 115.602004 -278.668988) (xy 115.593951 -278.664486) (xy 115.575853 -278.66098)
			(xy 115.566698 -278.66213) (xy 115.552527 -278.66448) (xy 115.523912 -278.66702) (xy 115.509548 -278.66721)
			(xy 115.495184 -278.667037) (xy 115.466568 -278.664492) (xy 115.452398 -278.66213) (xy 115.443245 -278.660959)
			(xy 115.425148 -278.664486) (xy 115.417092 -278.668988) (xy 115.390422 -278.685498) (xy 115.368578 -278.713692)
			(xy 115.365784 -278.722074) (xy 115.358549 -278.742851) (xy 115.33949 -278.782506) (xy 115.315515 -278.819396)
			(xy 115.301522 -278.836374) (xy 115.296188 -278.842978) (xy 115.283488 -278.87549) (xy 115.282726 -278.906478)
			(xy 115.28295 -278.915516) (xy 115.288925 -278.932567) (xy 115.29441 -278.939752) (xy 115.312125 -278.962152)
			(xy 115.34038 -279.011774) (xy 115.359696 -279.065511) (xy 115.369498 -279.121766) (xy 115.370102 -279.150318)
			(xy 115.369592 -279.176305) (xy 115.361462 -279.22764) (xy 115.345401 -279.27707) (xy 115.321805 -279.32338)
			(xy 115.291255 -279.365428) (xy 115.254504 -279.402179) (xy 115.212456 -279.432729) (xy 115.166146 -279.456325)
			(xy 115.116716 -279.472386) (xy 115.065381 -279.480516) (xy 115.013407 -279.480516) (xy 114.962072 -279.472386)
			(xy 114.912642 -279.456325) (xy 114.866332 -279.432729) (xy 114.824284 -279.402179) (xy 114.787533 -279.365428)
			(xy 114.756983 -279.32338) (xy 114.733387 -279.27707) (xy 114.717326 -279.22764) (xy 114.709196 -279.176305)
			(xy 114.708686 -279.150318) (xy 114.709238 -279.122741) (xy 114.718393 -279.068352) (xy 114.736452 -279.016238)
			(xy 114.762913 -278.967846) (xy 114.779552 -278.945848) (xy 114.784632 -278.939244) (xy 114.796062 -278.907494)
			(xy 114.795554 -278.875236) (xy 114.782854 -278.842724) (xy 114.77752 -278.836374) (xy 114.763572 -278.819387)
			(xy 114.739686 -278.78249) (xy 114.72072 -278.742838) (xy 114.713512 -278.722074) (xy 114.710718 -278.713692)
			(xy 114.688874 -278.685498) (xy 114.662204 -278.668988) (xy 114.654151 -278.664486) (xy 114.636053 -278.66098)
			(xy 114.626898 -278.66213) (xy 114.612727 -278.66448) (xy 114.584112 -278.66702) (xy 114.569748 -278.66721)
			(xy 114.543756 -278.66673) (xy 114.492412 -278.658605) (xy 114.442971 -278.642547) (xy 114.396651 -278.618952)
			(xy 114.354592 -278.588401) (xy 114.317832 -278.551646) (xy 114.287274 -278.509592) (xy 114.263672 -278.463276)
			(xy 114.247606 -278.413837) (xy 114.239473 -278.362494) (xy 114.23904 -278.336502) (xy 114.239641 -278.30795)
			(xy 114.249444 -278.251694) (xy 114.268759 -278.197956) (xy 114.297012 -278.148332) (xy 114.314732 -278.125936)
			(xy 114.320224 -278.118754) (xy 114.326194 -278.101702) (xy 114.326416 -278.092662) (xy 114.325654 -278.061674)
			(xy 114.312954 -278.029162) (xy 114.30762 -278.022558) (xy 114.290825 -278.002011) (xy 114.263116 -277.956753)
			(xy 114.242701 -277.90777) (xy 114.230068 -277.856229) (xy 114.225518 -277.803358) (xy 114.229158 -277.750417)
			(xy 114.240902 -277.698666) (xy 114.250216 -277.673816) (xy 114.260052 -277.650365) (xy 114.285624 -277.60641)
			(xy 114.317391 -277.566701) (xy 114.354658 -277.532102) (xy 114.396615 -277.503368) (xy 114.442345 -277.481125)
			(xy 114.490852 -277.46586) (xy 114.5159 -277.461472) (xy 114.524028 -277.459948) (xy 114.554254 -277.4442)
			(xy 114.588036 -277.407878) (xy 114.588036 -277.088854) (xy 114.554508 -277.052024) (xy 114.548332 -277.045725)
			(xy 114.53272 -277.037533) (xy 114.524028 -277.036022) (xy 114.498022 -277.0319) (xy 114.447678 -277.016488)
			(xy 114.400416 -276.993286) (xy 114.357432 -276.962882) (xy 114.319814 -276.926044) (xy 114.288516 -276.883707)
			(xy 114.264329 -276.836941) (xy 114.247866 -276.78693) (xy 114.239544 -276.734942) (xy 114.23904 -276.708616)
			(xy 114.239426 -276.685743) (xy 114.245726 -276.640432) (xy 114.258208 -276.596421) (xy 114.276635 -276.55455)
			(xy 114.288316 -276.53488) (xy 114.309398 -276.50059) (xy 114.026442 -276.217634) (xy 114.013488 -276.214078)
			(xy 113.98754 -276.206504) (xy 113.938353 -276.184096) (xy 113.893465 -276.153986) (xy 113.854073 -276.116976)
			(xy 113.821225 -276.074051) (xy 113.795796 -276.026356) (xy 113.778463 -275.975159) (xy 113.769687 -275.921826)
			(xy 113.76914 -275.8948) (xy 113.769667 -275.867875) (xy 113.778382 -275.814736) (xy 113.795583 -275.763708)
			(xy 113.820815 -275.716136) (xy 113.836704 -275.694394) (xy 113.847118 -275.680678) (xy 113.847118 -275.60143)
			(xy 113.841022 -275.58492) (xy 113.835434 -275.577808) (xy 113.83518 -275.577554) (xy 113.81532 -275.552397)
			(xy 113.784385 -275.496271) (xy 113.773712 -275.466048) (xy 113.770918 -275.45792) (xy 113.749074 -275.429726)
			(xy 113.715292 -275.408898) (xy 113.696496 -275.40458) (xy 113.679982 -275.407789) (xy 113.646515 -275.411226)
			(xy 113.629694 -275.411438) (xy 113.603706 -275.410928) (xy 113.552371 -275.402797) (xy 113.502939 -275.386736)
			(xy 113.456628 -275.36314) (xy 113.414578 -275.332591) (xy 113.377825 -275.29584) (xy 113.347272 -275.253792)
			(xy 113.323673 -275.207483) (xy 113.307609 -275.158053) (xy 113.299474 -275.106718) (xy 113.298986 -275.08073)
			(xy 113.29951 -275.053163) (xy 113.308604 -274.998785) (xy 113.326595 -274.946671) (xy 113.352984 -274.898263)
			(xy 113.369598 -274.87626) (xy 113.374678 -274.86991) (xy 113.386362 -274.837652) (xy 113.385854 -274.805902)
			(xy 113.3729 -274.773136) (xy 113.367566 -274.766786) (xy 113.352295 -274.748082) (xy 113.326593 -274.707205)
			(xy 113.306858 -274.663137) (xy 113.293478 -274.616742) (xy 113.286715 -274.568933) (xy 113.286286 -274.54479)
			(xy 113.286811 -274.517871) (xy 113.295211 -274.464692) (xy 113.311805 -274.413474) (xy 113.336187 -274.365473)
			(xy 113.367758 -274.321863) (xy 113.405746 -274.283712) (xy 113.449221 -274.251955) (xy 113.497118 -274.227369)
			(xy 113.522506 -274.2184) (xy 113.557558 -274.20697) (xy 113.557558 -273.777964) (xy 113.523014 -273.76628)
			(xy 113.498851 -273.757515) (xy 113.453362 -273.733586) (xy 113.412119 -273.702915) (xy 113.376111 -273.666237)
			(xy 113.346205 -273.624435) (xy 113.323119 -273.578513) (xy 113.307408 -273.529575) (xy 113.299449 -273.478797)
			(xy 113.298986 -273.453098) (xy 113.299513 -273.425532) (xy 113.308612 -273.371157) (xy 113.326606 -273.319045)
			(xy 113.352998 -273.270642) (xy 113.369598 -273.248628) (xy 113.374678 -273.242278) (xy 113.386362 -273.21002)
			(xy 113.385854 -273.17827) (xy 113.3729 -273.145504) (xy 113.367566 -273.139154) (xy 113.352291 -273.120451)
			(xy 113.326581 -273.079576) (xy 113.306838 -273.035508) (xy 113.293448 -272.989113) (xy 113.286676 -272.941302)
			(xy 113.286286 -272.917158) (xy 113.286805 -272.890236) (xy 113.295197 -272.837049) (xy 113.311785 -272.785824)
			(xy 113.336162 -272.737814) (xy 113.367731 -272.694195) (xy 113.405719 -272.656036) (xy 113.449195 -272.624271)
			(xy 113.497096 -272.599678) (xy 113.522506 -272.590768) (xy 113.557558 -272.579338) (xy 113.557558 -272.150078)
			(xy 113.523014 -272.138394) (xy 113.498854 -272.129628) (xy 113.453373 -272.105697) (xy 113.412138 -272.075023)
			(xy 113.37614 -272.038344) (xy 113.346244 -271.996541) (xy 113.323169 -271.95062) (xy 113.30747 -271.901683)
			(xy 113.299524 -271.850908) (xy 113.298986 -271.825212) (xy 113.299512 -271.797646) (xy 113.308608 -271.743269)
			(xy 113.326601 -271.691156) (xy 113.352992 -271.642751) (xy 113.369598 -271.620742) (xy 113.374678 -271.614392)
			(xy 113.386362 -271.582134) (xy 113.385854 -271.550384) (xy 113.3729 -271.517618) (xy 113.367566 -271.511268)
			(xy 113.352296 -271.492564) (xy 113.326596 -271.451687) (xy 113.306864 -271.407618) (xy 113.293486 -271.361223)
			(xy 113.286725 -271.313414) (xy 113.286286 -271.289272) (xy 113.286804 -271.262349) (xy 113.295195 -271.209161)
			(xy 113.311781 -271.157934) (xy 113.336157 -271.109922) (xy 113.367725 -271.066301) (xy 113.405713 -271.02814)
			(xy 113.44919 -270.996374) (xy 113.497091 -270.97178) (xy 113.522506 -270.962882) (xy 113.557558 -270.951452)
			(xy 113.557558 -270.522446) (xy 113.523014 -270.510762) (xy 113.498851 -270.501997) (xy 113.453365 -270.478068)
			(xy 113.412123 -270.447396) (xy 113.376117 -270.410718) (xy 113.346213 -270.368916) (xy 113.323129 -270.322994)
			(xy 113.307421 -270.274056) (xy 113.299464 -270.223278) (xy 113.298986 -270.19758) (xy 113.299515 -270.170014)
			(xy 113.308616 -270.115641) (xy 113.326613 -270.063531) (xy 113.353006 -270.015129) (xy 113.369598 -269.99311)
			(xy 113.374678 -269.98676) (xy 113.386362 -269.954502) (xy 113.385854 -269.922752) (xy 113.3729 -269.889986)
			(xy 113.367566 -269.883636) (xy 113.352292 -269.864933) (xy 113.326584 -269.824057) (xy 113.306843 -269.779989)
			(xy 113.293456 -269.733594) (xy 113.286686 -269.685784) (xy 113.286286 -269.66164) (xy 113.286807 -269.634719)
			(xy 113.295201 -269.581534) (xy 113.31179 -269.530311) (xy 113.336168 -269.482303) (xy 113.367738 -269.438686)
			(xy 113.405726 -269.400529) (xy 113.449202 -269.368767) (xy 113.497102 -269.344176) (xy 113.522506 -269.33525)
			(xy 113.557558 -269.32382) (xy 113.557558 -268.89456) (xy 113.523014 -268.882876) (xy 113.498851 -268.874111)
			(xy 113.453363 -268.850182) (xy 113.41212 -268.819511) (xy 113.376113 -268.782833) (xy 113.346207 -268.741031)
			(xy 113.323121 -268.695109) (xy 113.307411 -268.646171) (xy 113.299452 -268.595393) (xy 113.298986 -268.569694)
			(xy 113.299513 -268.542128) (xy 113.308613 -268.487753) (xy 113.326608 -268.435642) (xy 113.353 -268.387239)
			(xy 113.369598 -268.365224) (xy 113.374678 -268.358874) (xy 113.386362 -268.326616) (xy 113.385854 -268.294866)
			(xy 113.3729 -268.2621) (xy 113.367566 -268.25575) (xy 113.352292 -268.237047) (xy 113.326582 -268.196172)
			(xy 113.306839 -268.152104) (xy 113.29345 -268.105709) (xy 113.286678 -268.057898) (xy 113.286286 -268.033754)
			(xy 113.286806 -268.006832) (xy 113.295198 -267.953646) (xy 113.311786 -267.902421) (xy 113.336163 -267.854411)
			(xy 113.367733 -267.810793) (xy 113.405721 -267.772634) (xy 113.449197 -267.74087) (xy 113.497097 -267.716278)
			(xy 113.522506 -267.707364) (xy 113.557558 -267.695934) (xy 113.557558 -267.266674) (xy 113.523014 -267.25499)
			(xy 113.49885 -267.246225) (xy 113.453361 -267.222297) (xy 113.412117 -267.191625) (xy 113.376108 -267.154948)
			(xy 113.346201 -267.113146) (xy 113.323113 -267.067224) (xy 113.3074 -267.018286) (xy 113.29944 -266.967507)
			(xy 113.298986 -266.941808) (xy 113.299512 -266.914242) (xy 113.308609 -266.859866) (xy 113.326603 -266.807753)
			(xy 113.352994 -266.759348) (xy 113.369598 -266.737338) (xy 113.374678 -266.730988) (xy 113.386362 -266.69873)
			(xy 113.385854 -266.66698) (xy 113.3729 -266.634214) (xy 113.367566 -266.627864) (xy 113.352296 -266.60916)
			(xy 113.326597 -266.568282) (xy 113.306865 -266.524214) (xy 113.293488 -266.477819) (xy 113.286728 -266.43001)
			(xy 113.286286 -266.405868) (xy 113.286805 -266.378601) (xy 113.295415 -266.324751) (xy 113.312431 -266.27294)
			(xy 113.337423 -266.22447) (xy 113.369763 -266.18056) (xy 113.408638 -266.142315) (xy 113.453071 -266.110697)
			(xy 113.501943 -266.086501) (xy 113.52784 -266.077954) (xy 113.539778 -266.074144) (xy 113.819432 -265.79449)
			(xy 113.800636 -265.760708) (xy 113.786767 -265.734828) (xy 113.76709 -265.679513) (xy 113.757081 -265.621661)
			(xy 113.75644 -265.592306) (xy 113.756941 -265.56532) (xy 113.765384 -265.512012) (xy 113.782064 -265.460681)
			(xy 113.806568 -265.412592) (xy 113.838294 -265.368929) (xy 113.876461 -265.330767) (xy 113.920128 -265.299046)
			(xy 113.96822 -265.274548) (xy 114.019553 -265.257875) (xy 114.072862 -265.249438) (xy 114.099848 -265.248898)
			(xy 114.100102 -265.248898) (xy 114.117238 -265.249126) (xy 114.151337 -265.252563) (xy 114.168174 -265.255756)
			(xy 114.170714 -265.256264) (xy 114.192812 -265.258296) (xy 114.251232 -265.225022) (xy 114.25735 -265.204227)
			(xy 114.274294 -265.164328) (xy 114.296314 -265.126989) (xy 114.309398 -265.109706) (xy 114.314478 -265.103356)
			(xy 114.326162 -265.071098) (xy 114.325654 -265.039348) (xy 114.3127 -265.006582) (xy 114.307366 -265.000232)
			(xy 114.292093 -264.981529) (xy 114.266385 -264.940653) (xy 114.246644 -264.896585) (xy 114.233258 -264.85019)
			(xy 114.226489 -264.80238) (xy 114.226086 -264.778236) (xy 114.226585 -264.751247) (xy 114.235024 -264.697932)
			(xy 114.2517 -264.646594) (xy 114.276202 -264.598497) (xy 114.307927 -264.554825) (xy 114.346093 -264.516654)
			(xy 114.389761 -264.484924) (xy 114.437855 -264.460416) (xy 114.489191 -264.443734) (xy 114.542505 -264.435288)
			(xy 114.569494 -264.434828) (xy 114.570256 -264.434828) (xy 114.587328 -264.435065) (xy 114.6213 -264.438501)
			(xy 114.638074 -264.441686) (xy 114.640614 -264.442194) (xy 114.662458 -264.444226) (xy 114.720878 -264.41146)
			(xy 114.727053 -264.390599) (xy 114.744143 -264.350592) (xy 114.766349 -264.313181) (xy 114.779552 -264.29589)
			(xy 114.784632 -264.289286) (xy 114.796062 -264.257536) (xy 114.795554 -264.225278) (xy 114.782854 -264.192766)
			(xy 114.77752 -264.186416) (xy 114.762245 -264.167714) (xy 114.736536 -264.126839) (xy 114.716794 -264.082771)
			(xy 114.703407 -264.036375) (xy 114.696639 -263.988564) (xy 114.69624 -263.96442) (xy 114.69674 -263.937433)
			(xy 114.705182 -263.884123) (xy 114.72186 -263.832791) (xy 114.746363 -263.7847) (xy 114.778089 -263.741035)
			(xy 114.816256 -263.702871) (xy 114.859924 -263.671149) (xy 114.908017 -263.646649) (xy 114.959351 -263.629975)
			(xy 115.012661 -263.621538) (xy 115.039648 -263.621012) (xy 115.04041 -263.621012) (xy 115.057482 -263.621247)
			(xy 115.091455 -263.624678) (xy 115.108228 -263.62787) (xy 115.110768 -263.628378) (xy 115.132612 -263.63041)
			(xy 115.191032 -263.597644) (xy 115.197943 -263.57444) (xy 115.217615 -263.530202) (xy 115.243532 -263.489307)
			(xy 115.275139 -263.452633) (xy 115.31176 -263.420964) (xy 115.35261 -263.394978) (xy 115.396816 -263.375232)
			(xy 115.443429 -263.362148) (xy 115.467384 -263.35863) (xy 115.51158 -263.353042) (xy 115.51158 -260.57733)
			(xy 115.496594 -260.562344) (xy 115.078256 -260.144006) (xy 115.071403 -260.136611) (xy 115.063657 -260.118012)
			(xy 115.06327 -260.107938) (xy 115.06327 -258.941062) (xy 115.063699 -258.930994) (xy 115.07142 -258.912397)
			(xy 115.078256 -258.904994) (xy 115.284504 -258.698746) (xy 115.291901 -258.691895) (xy 115.310499 -258.684155)
			(xy 115.320572 -258.68376) (xy 119.79021 -258.68376) (xy 119.805196 -258.669028) (xy 119.906288 -258.567936)
			(xy 119.92102 -258.55295) (xy 119.92102 -258.078224) (xy 119.812562 -257.999738) (xy 119.787924 -258.007612)
			(xy 119.763074 -258.015168) (xy 119.711784 -258.023337) (xy 119.685816 -258.023868) (xy 119.661324 -258.023424)
			(xy 119.612876 -258.016194) (xy 119.566027 -258.001889) (xy 119.521803 -257.980823) (xy 119.481175 -257.953458)
			(xy 119.462804 -257.937254) (xy 119.455692 -257.93065) (xy 119.437658 -257.923792) (xy 119.33936 -257.924046)
			(xy 119.324628 -257.937762) (xy 119.306173 -257.954337) (xy 119.265228 -257.982336) (xy 119.220562 -258.003908)
			(xy 119.173175 -258.018571) (xy 119.124131 -258.025995) (xy 119.09933 -258.026408) (xy 119.074975 -258.025976)
			(xy 119.026792 -258.018831) (xy 118.980179 -258.004692) (xy 118.936146 -257.983864) (xy 118.895648 -257.956798)
			(xy 118.85956 -257.924082) (xy 118.843806 -257.905504) (xy 118.828566 -257.886962) (xy 118.702328 -257.886708)
			(xy 118.687088 -257.904996) (xy 118.671288 -257.923259) (xy 118.635295 -257.955453) (xy 118.595001 -257.982069)
			(xy 118.551263 -258.002538) (xy 118.505012 -258.016425) (xy 118.457233 -258.023435) (xy 118.433088 -258.023868)
			(xy 118.405193 -258.023288) (xy 118.350193 -258.013924) (xy 118.297546 -257.995462) (xy 118.248743 -257.968426)
			(xy 118.205169 -257.933585) (xy 118.1862 -257.913124) (xy 118.070884 -257.913124) (xy 118.051908 -257.933582)
			(xy 118.008348 -257.968447) (xy 117.959549 -257.995497) (xy 117.906898 -258.013963) (xy 117.851894 -258.02332)
			(xy 117.823996 -258.023868) (xy 117.798012 -258.023358) (xy 117.746684 -258.015228) (xy 117.697261 -257.999168)
			(xy 117.650957 -257.975575) (xy 117.608915 -257.945029) (xy 117.572168 -257.908282) (xy 117.541623 -257.866239)
			(xy 117.51803 -257.819936) (xy 117.501971 -257.770512) (xy 117.493842 -257.719184) (xy 117.493842 -257.667216)
			(xy 117.501971 -257.615888) (xy 117.51803 -257.566464) (xy 117.541623 -257.520161) (xy 117.572168 -257.478118)
			(xy 117.608915 -257.441371) (xy 117.650957 -257.410825) (xy 117.697261 -257.387232) (xy 117.746684 -257.371172)
			(xy 117.798012 -257.363042) (xy 117.823996 -257.362452) (xy 117.851888 -257.363039) (xy 117.906879 -257.372416)
			(xy 117.959517 -257.390889) (xy 118.008308 -257.417932) (xy 118.051869 -257.45278) (xy 118.070884 -257.473196)
			(xy 118.1862 -257.473196) (xy 118.205177 -257.452742) (xy 118.248739 -257.417887) (xy 118.29754 -257.390847)
			(xy 118.35019 -257.372393) (xy 118.405192 -257.363049) (xy 118.433088 -257.362452) (xy 118.457442 -257.362885)
			(xy 118.505623 -257.370033) (xy 118.552232 -257.384177) (xy 118.59626 -257.405009) (xy 118.636753 -257.432079)
			(xy 118.672834 -257.464799) (xy 118.688612 -257.483356) (xy 118.703852 -257.501898) (xy 118.83009 -257.502152)
			(xy 118.84533 -257.483864) (xy 118.861132 -257.465604) (xy 118.897127 -257.433415) (xy 118.937422 -257.406805)
			(xy 118.981159 -257.386341) (xy 119.027409 -257.372458) (xy 119.075186 -257.365452) (xy 119.09933 -257.364992)
			(xy 119.123821 -257.365439) (xy 119.172266 -257.372675) (xy 119.219112 -257.386984) (xy 119.263333 -257.408052)
			(xy 119.303958 -257.435418) (xy 119.322342 -257.451606) (xy 119.329454 -257.45821) (xy 119.347488 -257.465068)
			(xy 119.445786 -257.464814) (xy 119.460518 -257.451098) (xy 119.478975 -257.434528) (xy 119.519922 -257.406538)
			(xy 119.564589 -257.384974) (xy 119.611974 -257.37032) (xy 119.661016 -257.362903) (xy 119.685816 -257.362452)
			(xy 119.711786 -257.362953) (xy 119.763082 -257.37112) (xy 119.787924 -257.378708) (xy 119.812562 -257.386582)
			(xy 119.92102 -257.308096) (xy 119.92102 -256.83337) (xy 119.906034 -256.818384) (xy 119.797576 -256.709926)
			(xy 119.78259 -256.69494) (xy 115.555776 -256.69494) (xy 115.535547 -256.703035) (xy 115.493495 -256.714439)
			(xy 115.450307 -256.720212) (xy 115.428522 -256.720594) (xy 115.406738 -256.72021) (xy 115.363554 -256.714422)
			(xy 115.321502 -256.703021) (xy 115.301268 -256.69494) (xy 115.270534 -256.69494) (xy 115.26047 -256.694503)
			(xy 115.241889 -256.686765) (xy 115.234466 -256.679954) (xy 115.211606 -256.657348) (xy 115.211098 -256.657348)
			(xy 115.093496 -256.539492) (xy 115.08486 -256.530094) (xy 115.078508 -256.522828) (xy 115.071318 -256.504937)
			(xy 115.07089 -256.495296) (xy 115.07089 -255.240282) (xy 115.071316 -255.230213) (xy 115.079034 -255.211612)
			(xy 115.085876 -255.204214) (xy 115.256564 -255.033526) (xy 115.263965 -255.026687) (xy 115.282563 -255.018972)
			(xy 115.292632 -255.01854) (xy 119.828056 -255.01854) (xy 119.843042 -255.003808) (xy 119.93372 -254.91313)
			(xy 119.948452 -254.898144) (xy 119.948452 -253.085346) (xy 119.933466 -253.07036) (xy 119.895112 -253.032006)
			(xy 119.880126 -253.01702) (xy 115.85321 -253.01702) (xy 115.838224 -253.032006) (xy 115.746276 -253.123954)
			(xy 115.738879 -253.130802) (xy 115.72028 -253.138535) (xy 115.710208 -253.13894) (xy 115.274852 -253.13894)
			(xy 115.264787 -253.138507) (xy 115.246201 -253.130773) (xy 115.238784 -253.123954) (xy 115.088416 -252.973586)
			(xy 115.08157 -252.966187) (xy 115.073838 -252.947589) (xy 115.07343 -252.937518) (xy 115.07343 -251.798582)
			(xy 115.073857 -251.788514) (xy 115.081579 -251.769917) (xy 115.088416 -251.762514) (xy 115.485164 -251.365766)
			(xy 115.492563 -251.358922) (xy 115.511162 -251.351201) (xy 115.521232 -251.35078) (xy 119.782336 -251.35078)
			(xy 119.797322 -251.336048) (xy 119.932958 -251.200412) (xy 119.94769 -251.185426) (xy 119.94769 -249.57532)
			(xy 119.932704 -249.560334) (xy 119.769636 -249.397266) (xy 119.75465 -249.38228) (xy 117.04447 -249.38228)
			(xy 117.039644 -249.377454) (xy 116.400834 -249.377454) (xy 116.230908 -249.54738) (xy 115.464844 -249.54738)
			(xy 115.459002 -249.54865) (xy 115.440233 -249.552872) (xy 115.402037 -249.557459) (xy 115.382802 -249.557794)
			(xy 115.363567 -249.557466) (xy 115.325369 -249.552883) (xy 115.306602 -249.54865) (xy 115.30076 -249.54738)
			(xy 115.224052 -249.54738) (xy 115.213986 -249.546948) (xy 115.195396 -249.539219) (xy 115.187984 -249.532394)
			(xy 115.045236 -249.389646) (xy 115.038394 -249.382246) (xy 115.030674 -249.363648) (xy 115.03025 -249.353578)
			(xy 115.03025 -248.466102) (xy 115.030674 -248.456033) (xy 115.038394 -248.437433) (xy 115.045236 -248.430034)
			(xy 115.754404 -247.720866) (xy 115.761799 -247.714013) (xy 115.780398 -247.706269) (xy 115.790472 -247.70588)
			(xy 118.781576 -247.70588) (xy 118.796562 -247.691148) (xy 118.819422 -247.668288) (xy 118.834154 -247.653302)
			(xy 118.834154 -247.196356) (xy 118.819168 -247.18137) (xy 118.677436 -247.039638) (xy 118.670595 -247.032238)
			(xy 118.662878 -247.013639) (xy 118.66245 -247.00357) (xy 118.66245 -246.945912) (xy 118.59895 -246.945912)
			(xy 118.587774 -246.951754) (xy 118.563843 -246.96383) (xy 118.51304 -246.980918) (xy 118.460142 -246.989572)
			(xy 118.433342 -246.990108) (xy 118.433088 -246.990108) (xy 118.407766 -246.989625) (xy 118.357714 -246.981904)
			(xy 118.309423 -246.966644) (xy 118.264023 -246.944202) (xy 118.222573 -246.915103) (xy 118.20398 -246.897906)
			(xy 118.188994 -246.883428) (xy 118.07571 -246.88546) (xy 118.060978 -246.900446) (xy 118.042175 -246.918986)
			(xy 117.999772 -246.95045) (xy 117.95291 -246.974781) (xy 117.902779 -246.991362) (xy 117.850651 -246.999771)
			(xy 117.82425 -247.000268) (xy 117.823996 -247.000268) (xy 117.798012 -246.999758) (xy 117.746684 -246.991628)
			(xy 117.697261 -246.975568) (xy 117.650957 -246.951975) (xy 117.608915 -246.921429) (xy 117.572168 -246.884682)
			(xy 117.541623 -246.842639) (xy 117.51803 -246.796336) (xy 117.501971 -246.746912) (xy 117.493842 -246.695584)
			(xy 117.493842 -246.643616) (xy 117.501971 -246.592288) (xy 117.51803 -246.542864) (xy 117.541623 -246.496561)
			(xy 117.572168 -246.454518) (xy 117.608915 -246.417771) (xy 117.650957 -246.387225) (xy 117.697261 -246.363632)
			(xy 117.746684 -246.347572) (xy 117.798012 -246.339442) (xy 117.823996 -246.338852) (xy 117.849318 -246.339335)
			(xy 117.89937 -246.347055) (xy 117.947661 -246.362315) (xy 117.99306 -246.384758) (xy 118.034508 -246.41386)
			(xy 118.053104 -246.431054) (xy 118.06809 -246.445532) (xy 118.181374 -246.4435) (xy 118.196106 -246.428514)
			(xy 118.214912 -246.409981) (xy 118.257319 -246.378531) (xy 118.304182 -246.354215) (xy 118.354312 -246.337649)
			(xy 118.406436 -246.329255) (xy 118.432834 -246.328692) (xy 118.433088 -246.328692) (xy 118.461334 -246.329265)
			(xy 118.517006 -246.338856) (xy 118.57024 -246.357763) (xy 118.59514 -246.37111) (xy 118.628922 -246.389906)
			(xy 118.810786 -246.208042) (xy 118.825518 -246.193056) (xy 118.825518 -245.877588) (xy 118.82501 -245.87708)
			(xy 118.82501 -245.75008) (xy 118.810024 -245.735094) (xy 118.776496 -245.701566) (xy 118.76151 -245.68658)
			(xy 115.581684 -245.68658) (xy 115.570254 -245.689374) (xy 115.564666 -245.691914) (xy 115.563904 -245.692422)
			(xy 115.540793 -245.703452) (xy 115.492018 -245.719048) (xy 115.441425 -245.726958) (xy 115.415822 -245.727474)
			(xy 115.390215 -245.727) (xy 115.339612 -245.719106) (xy 115.290837 -245.703488) (xy 115.26774 -245.692422)
			(xy 115.266978 -245.691914) (xy 115.26139 -245.689374) (xy 115.24996 -245.68658) (xy 115.216432 -245.68658)
			(xy 115.206368 -245.686144) (xy 115.187783 -245.67841) (xy 115.180364 -245.671594) (xy 115.073684 -245.564914)
			(xy 115.066842 -245.557515) (xy 115.059126 -245.538916) (xy 115.058698 -245.528846) (xy 115.058698 -244.47373)
			(xy 115.059134 -244.463665) (xy 115.066866 -244.445079) (xy 115.073684 -244.437662) (xy 115.478814 -244.032786)
			(xy 115.486209 -244.025932) (xy 115.504808 -244.01819) (xy 115.514882 -244.0178) (xy 119.812816 -244.0178)
			(xy 119.827802 -244.003068) (xy 119.934228 -243.896642) (xy 119.94896 -243.881656) (xy 119.94896 -242.25631)
			(xy 119.933974 -242.241324) (xy 119.739156 -242.046506) (xy 119.72417 -242.03152) (xy 115.208812 -242.03152)
			(xy 115.19874 -242.0311) (xy 115.180131 -242.023391) (xy 115.172744 -242.016534) (xy 115.063016 -241.906806)
			(xy 115.056167 -241.899408) (xy 115.048428 -241.88081) (xy 115.04803 -241.870738) (xy 115.04803 -240.513108)
			(xy 115.048452 -240.503038) (xy 115.056168 -240.484434) (xy 115.063016 -240.47704) (xy 115.256564 -240.283492)
			(xy 115.263972 -240.276803) (xy 115.282408 -240.269209) (xy 115.292378 -240.26876) (xy 115.292632 -240.26876)
			(xy 117.768116 -240.26876) (xy 117.783102 -240.254028) (xy 117.804438 -240.232692) (xy 117.81917 -240.217706)
			(xy 117.81917 -239.668558) (xy 116.8527 -239.668558) (xy 116.842631 -239.668134) (xy 116.82403 -239.660415)
			(xy 116.816632 -239.653572) (xy 115.444524 -238.281464) (xy 115.429538 -238.266478) (xy 114.587274 -238.266478)
			(xy 114.578638 -238.269526) (xy 114.549927 -238.279454) (xy 114.490138 -238.290188) (xy 114.459766 -238.290862)
			(xy 114.45748 -238.290862) (xy 114.440854 -238.290554) (xy 114.407776 -238.287115) (xy 114.39144 -238.284004)
			(xy 114.3889 -238.283496) (xy 114.366548 -238.281464) (xy 114.325908 -238.304578) (xy 114.303302 -238.33201)
			(xy 114.300254 -238.340138) (xy 114.290047 -238.366124) (xy 114.262215 -238.414517) (xy 114.244882 -238.436404)
			(xy 114.23938 -238.443583) (xy 114.233388 -238.460635) (xy 114.233198 -238.469678) (xy 114.23396 -238.500666)
			(xy 114.24666 -238.533178) (xy 114.251994 -238.539528) (xy 114.267266 -238.558232) (xy 114.292969 -238.599108)
			(xy 114.312704 -238.643176) (xy 114.326084 -238.689571) (xy 114.332846 -238.737381) (xy 114.333274 -238.761524)
			(xy 114.33277 -238.788509) (xy 114.324324 -238.841814) (xy 114.307642 -238.893142) (xy 114.283136 -238.941228)
			(xy 114.25141 -238.984888) (xy 114.213244 -239.023048) (xy 114.169578 -239.054767) (xy 114.121488 -239.079264)
			(xy 114.070158 -239.095937) (xy 114.016851 -239.104375) (xy 113.989866 -239.104932) (xy 113.989104 -239.104932)
			(xy 113.972032 -239.104693) (xy 113.938061 -239.101254) (xy 113.921286 -239.098074) (xy 113.918746 -239.097566)
			(xy 113.896648 -239.095534) (xy 113.856008 -239.118648) (xy 113.83899 -239.128046) (xy 113.832894 -239.146588)
			(xy 113.823377 -239.172801) (xy 113.796816 -239.221831) (xy 113.780062 -239.244124) (xy 113.774982 -239.250474)
			(xy 113.763298 -239.282732) (xy 113.76406 -239.333278) (xy 113.776506 -239.347502) (xy 113.792735 -239.366433)
			(xy 113.820115 -239.408106) (xy 113.841175 -239.453303) (xy 113.855469 -239.501073) (xy 113.862696 -239.550409)
			(xy 113.86312 -239.57534) (xy 113.86264 -239.601039) (xy 113.854979 -239.651863) (xy 113.83983 -239.700977)
			(xy 113.817529 -239.747285) (xy 113.788576 -239.789752) (xy 113.753616 -239.827429) (xy 113.713432 -239.859475)
			(xy 113.66892 -239.885174) (xy 113.621075 -239.903951) (xy 113.570966 -239.915389) (xy 113.519712 -239.91923)
			(xy 113.468458 -239.915389) (xy 113.418349 -239.903951) (xy 113.370504 -239.885174) (xy 113.325992 -239.859475)
			(xy 113.285808 -239.827429) (xy 113.250848 -239.789752) (xy 113.221895 -239.747285) (xy 113.199594 -239.700977)
			(xy 113.184445 -239.651863) (xy 113.176784 -239.601039) (xy 113.176304 -239.57534) (xy 113.17671 -239.551195)
			(xy 113.183464 -239.503381) (xy 113.196844 -239.456983) (xy 113.216587 -239.412914) (xy 113.242304 -239.372043)
			(xy 113.257584 -239.353344) (xy 113.262918 -239.346994) (xy 113.275872 -239.314228) (xy 113.27638 -239.282478)
			(xy 113.264696 -239.25022) (xy 113.25987 -239.24387) (xy 113.243138 -239.221632) (xy 113.21658 -239.172731)
			(xy 113.207038 -239.146588) (xy 113.200942 -239.128046) (xy 113.183924 -239.118648) (xy 113.143284 -239.095534)
			(xy 113.121186 -239.097566) (xy 113.118646 -239.098074) (xy 113.101873 -239.101266) (xy 113.067901 -239.104704)
			(xy 113.050828 -239.104932) (xy 113.050066 -239.104932) (xy 113.023082 -239.1044) (xy 112.969779 -239.095953)
			(xy 112.918453 -239.079273) (xy 112.870368 -239.05477) (xy 112.826708 -239.023046) (xy 112.788547 -238.984885)
			(xy 112.756825 -238.941223) (xy 112.732323 -238.893138) (xy 112.715644 -238.841811) (xy 112.707199 -238.788508)
			(xy 112.706658 -238.761524) (xy 112.707065 -238.73738) (xy 112.71382 -238.689566) (xy 112.7272 -238.643168)
			(xy 112.746943 -238.599099) (xy 112.772658 -238.558227) (xy 112.787938 -238.539528) (xy 112.793272 -238.533178)
			(xy 112.805972 -238.500666) (xy 112.806734 -238.469678) (xy 112.806502 -238.460643) (xy 112.800513 -238.443604)
			(xy 112.79505 -238.436404) (xy 112.777707 -238.414523) (xy 112.749866 -238.366133) (xy 112.739678 -238.340138)
			(xy 112.73663 -238.33201) (xy 112.714024 -238.304578) (xy 112.673384 -238.281464) (xy 112.651032 -238.283496)
			(xy 112.648492 -238.284004) (xy 112.634344 -238.286699) (xy 112.605732 -238.290003) (xy 112.591342 -238.290608)
			(xy 112.579912 -238.290862) (xy 112.562712 -238.290649) (xy 112.528486 -238.287209) (xy 112.511586 -238.284004)
			(xy 112.509046 -238.283496) (xy 112.486948 -238.281464) (xy 112.446308 -238.304578) (xy 112.423702 -238.332264)
			(xy 112.420654 -238.340138) (xy 112.410447 -238.366124) (xy 112.382615 -238.414517) (xy 112.365282 -238.436404)
			(xy 112.35978 -238.443583) (xy 112.353788 -238.460635) (xy 112.353598 -238.469678) (xy 112.35436 -238.500666)
			(xy 112.36706 -238.533178) (xy 112.372394 -238.539528) (xy 112.387666 -238.558232) (xy 112.413369 -238.599108)
			(xy 112.433104 -238.643176) (xy 112.446484 -238.689571) (xy 112.453246 -238.737381) (xy 112.453674 -238.761524)
			(xy 112.453194 -238.787223) (xy 112.445533 -238.838047) (xy 112.430384 -238.887161) (xy 112.408083 -238.933469)
			(xy 112.37913 -238.975936) (xy 112.34417 -239.013613) (xy 112.303986 -239.045659) (xy 112.259474 -239.071358)
			(xy 112.211629 -239.090135) (xy 112.16152 -239.101573) (xy 112.110266 -239.105414) (xy 112.059012 -239.101573)
			(xy 112.008903 -239.090135) (xy 111.961058 -239.071358) (xy 111.916546 -239.045659) (xy 111.876362 -239.013613)
			(xy 111.841402 -238.975936) (xy 111.812449 -238.933469) (xy 111.790148 -238.887161) (xy 111.774999 -238.838047)
			(xy 111.767338 -238.787223) (xy 111.766858 -238.761524) (xy 111.767265 -238.73738) (xy 111.77402 -238.689566)
			(xy 111.7874 -238.643168) (xy 111.807143 -238.599099) (xy 111.832858 -238.558227) (xy 111.848138 -238.539528)
			(xy 111.853472 -238.533178) (xy 111.866172 -238.500666) (xy 111.866934 -238.469678) (xy 111.866702 -238.460643)
			(xy 111.860713 -238.443604) (xy 111.85525 -238.436404) (xy 111.837907 -238.414523) (xy 111.810066 -238.366133)
			(xy 111.799878 -238.340138) (xy 111.79683 -238.33201) (xy 111.774224 -238.304578) (xy 111.733584 -238.281464)
			(xy 111.711232 -238.283496) (xy 111.708692 -238.284004) (xy 111.694544 -238.286699) (xy 111.665932 -238.290003)
			(xy 111.651542 -238.290608) (xy 111.640112 -238.290862) (xy 111.622912 -238.290649) (xy 111.588686 -238.287209)
			(xy 111.571786 -238.284004) (xy 111.569246 -238.283496) (xy 111.547148 -238.281464) (xy 111.506508 -238.304578)
			(xy 111.483902 -238.332264) (xy 111.480854 -238.340138) (xy 111.470647 -238.366124) (xy 111.442815 -238.414517)
			(xy 111.425482 -238.436404) (xy 111.41998 -238.443583) (xy 111.413988 -238.460635) (xy 111.413798 -238.469678)
			(xy 111.41456 -238.500666) (xy 111.42726 -238.533178) (xy 111.432594 -238.539528) (xy 111.447866 -238.558232)
			(xy 111.473569 -238.599108) (xy 111.493304 -238.643176) (xy 111.506684 -238.689571) (xy 111.513446 -238.737381)
			(xy 111.513874 -238.761524) (xy 111.513394 -238.787223) (xy 111.505733 -238.838047) (xy 111.490584 -238.887161)
			(xy 111.468283 -238.933469) (xy 111.43933 -238.975936) (xy 111.40437 -239.013613) (xy 111.364186 -239.045659)
			(xy 111.319674 -239.071358) (xy 111.271829 -239.090135) (xy 111.22172 -239.101573) (xy 111.170466 -239.105414)
			(xy 111.119212 -239.101573) (xy 111.069103 -239.090135) (xy 111.021258 -239.071358) (xy 110.976746 -239.045659)
			(xy 110.936562 -239.013613) (xy 110.901602 -238.975936) (xy 110.872649 -238.933469) (xy 110.850348 -238.887161)
			(xy 110.835199 -238.838047) (xy 110.827538 -238.787223) (xy 110.827058 -238.761524) (xy 110.827465 -238.73738)
			(xy 110.83422 -238.689566) (xy 110.8476 -238.643168) (xy 110.867343 -238.599099) (xy 110.893058 -238.558227)
			(xy 110.908338 -238.539528) (xy 110.913672 -238.533178) (xy 110.926372 -238.500666) (xy 110.927134 -238.469678)
			(xy 110.926902 -238.460643) (xy 110.920913 -238.443604) (xy 110.91545 -238.436404) (xy 110.898107 -238.414523)
			(xy 110.870266 -238.366133) (xy 110.860078 -238.340138) (xy 110.85703 -238.33201) (xy 110.834424 -238.304578)
			(xy 110.793784 -238.281464) (xy 110.771432 -238.283496) (xy 110.768892 -238.284004) (xy 110.751994 -238.287219)
			(xy 110.717766 -238.290653) (xy 110.700566 -238.290862) (xy 110.683366 -238.290652) (xy 110.649138 -238.287217)
			(xy 110.63224 -238.284004) (xy 110.6297 -238.283496) (xy 110.607348 -238.281464) (xy 110.566708 -238.304578)
			(xy 110.544102 -238.33201) (xy 110.541054 -238.340138) (xy 110.530847 -238.366124) (xy 110.503015 -238.414517)
			(xy 110.485682 -238.436404) (xy 110.48018 -238.443583) (xy 110.474188 -238.460635) (xy 110.473998 -238.469678)
			(xy 110.47476 -238.500666) (xy 110.48746 -238.533178) (xy 110.492794 -238.539528) (xy 110.508066 -238.558232)
			(xy 110.533769 -238.599108) (xy 110.553504 -238.643176) (xy 110.566884 -238.689571) (xy 110.573646 -238.737381)
			(xy 110.574074 -238.761524) (xy 110.573594 -238.787223) (xy 110.565933 -238.838047) (xy 110.550784 -238.887161)
			(xy 110.528483 -238.933469) (xy 110.49953 -238.975936) (xy 110.46457 -239.013613) (xy 110.424386 -239.045659)
			(xy 110.379874 -239.071358) (xy 110.332029 -239.090135) (xy 110.28192 -239.101573) (xy 110.230666 -239.105414)
			(xy 110.179412 -239.101573) (xy 110.129303 -239.090135) (xy 110.081458 -239.071358) (xy 110.036946 -239.045659)
			(xy 109.996762 -239.013613) (xy 109.961802 -238.975936) (xy 109.932849 -238.933469) (xy 109.910548 -238.887161)
			(xy 109.895399 -238.838047) (xy 109.887738 -238.787223) (xy 109.887258 -238.761524) (xy 109.887665 -238.73738)
			(xy 109.89442 -238.689566) (xy 109.9078 -238.643168) (xy 109.927543 -238.599099) (xy 109.953258 -238.558227)
			(xy 109.968538 -238.539528) (xy 109.973872 -238.533178) (xy 109.986572 -238.500666) (xy 109.987334 -238.469678)
			(xy 109.987102 -238.460643) (xy 109.981113 -238.443604) (xy 109.97565 -238.436404) (xy 109.958307 -238.414523)
			(xy 109.930466 -238.366133) (xy 109.920278 -238.340138) (xy 109.91723 -238.33201) (xy 109.894624 -238.304578)
			(xy 109.853984 -238.281464) (xy 109.831632 -238.283496) (xy 109.829092 -238.284004) (xy 109.814944 -238.286699)
			(xy 109.786332 -238.290003) (xy 109.771942 -238.290608) (xy 109.760512 -238.290862) (xy 109.743312 -238.290649)
			(xy 109.709086 -238.287209) (xy 109.692186 -238.284004) (xy 109.689646 -238.283496) (xy 109.667548 -238.281464)
			(xy 109.626908 -238.304578) (xy 109.604302 -238.332264) (xy 109.601254 -238.340138) (xy 109.591047 -238.366124)
			(xy 109.563215 -238.414517) (xy 109.545882 -238.436404) (xy 109.54038 -238.443583) (xy 109.534388 -238.460635)
			(xy 109.534198 -238.469678) (xy 109.53496 -238.500666) (xy 109.54766 -238.533178) (xy 109.552994 -238.539528)
			(xy 109.568266 -238.558232) (xy 109.593969 -238.599108) (xy 109.613704 -238.643176) (xy 109.627084 -238.689571)
			(xy 109.633846 -238.737381) (xy 109.634274 -238.761524) (xy 109.633794 -238.787223) (xy 109.626133 -238.838047)
			(xy 109.610984 -238.887161) (xy 109.588683 -238.933469) (xy 109.55973 -238.975936) (xy 109.52477 -239.013613)
			(xy 109.484586 -239.045659) (xy 109.440074 -239.071358) (xy 109.392229 -239.090135) (xy 109.34212 -239.101573)
			(xy 109.290866 -239.105414) (xy 109.239612 -239.101573) (xy 109.189503 -239.090135) (xy 109.141658 -239.071358)
			(xy 109.097146 -239.045659) (xy 109.056962 -239.013613) (xy 109.022002 -238.975936) (xy 108.993049 -238.933469)
			(xy 108.970748 -238.887161) (xy 108.955599 -238.838047) (xy 108.947938 -238.787223) (xy 108.947458 -238.761524)
			(xy 108.947865 -238.73738) (xy 108.95462 -238.689566) (xy 108.968 -238.643168) (xy 108.987743 -238.599099)
			(xy 109.013458 -238.558227) (xy 109.028738 -238.539528) (xy 109.034072 -238.533178) (xy 109.046772 -238.500666)
			(xy 109.047534 -238.469678) (xy 109.047302 -238.460643) (xy 109.041313 -238.443604) (xy 109.03585 -238.436404)
			(xy 109.02328 -238.420714) (xy 109.001631 -238.386837) (xy 108.99267 -238.36884) (xy 108.9787 -238.339884)
			(xy 105.693972 -238.339884) (xy 105.693972 -238.791242) (xy 105.693785 -238.801121) (xy 105.690717 -238.82064)
			(xy 105.687876 -238.830104) (xy 105.680256 -238.854234) (xy 105.754424 -238.961168) (xy 105.77957 -238.962438)
			(xy 105.808239 -238.964418) (xy 105.8643 -238.977026) (xy 105.917336 -238.999138) (xy 105.96575 -239.030088)
			(xy 105.987342 -239.049052) (xy 106.002074 -239.062514) (xy 106.110532 -239.062514) (xy 106.129376 -239.043881)
			(xy 106.171894 -239.012254) (xy 106.218906 -238.987801) (xy 106.269211 -238.971144) (xy 106.321526 -238.96271)
			(xy 106.348022 -238.962184) (xy 106.374009 -238.962695) (xy 106.425342 -238.970829) (xy 106.474771 -238.986892)
			(xy 106.521078 -239.01049) (xy 106.563124 -239.041041) (xy 106.599874 -239.077792) (xy 106.630422 -239.119841)
			(xy 106.654016 -239.16615) (xy 106.670076 -239.21558) (xy 106.678207 -239.266913) (xy 106.678207 -239.318887)
			(xy 106.670076 -239.37022) (xy 106.654016 -239.41965) (xy 106.630422 -239.465959) (xy 106.599874 -239.508008)
			(xy 106.563124 -239.544759) (xy 106.521078 -239.57531) (xy 106.474771 -239.598908) (xy 106.425342 -239.614971)
			(xy 106.374009 -239.623105) (xy 106.348022 -239.6236) (xy 106.321525 -239.623081) (xy 106.269207 -239.614649)
			(xy 106.218898 -239.597995) (xy 106.171881 -239.573546) (xy 106.129356 -239.541924) (xy 106.110532 -239.52327)
			(xy 106.001312 -239.52327) (xy 105.982476 -239.541917) (xy 105.939965 -239.57357) (xy 105.892955 -239.598046)
			(xy 105.842646 -239.614719) (xy 105.790322 -239.623164) (xy 105.737322 -239.623164) (xy 105.684998 -239.614719)
			(xy 105.634689 -239.598046) (xy 105.587679 -239.57357) (xy 105.545168 -239.541917) (xy 105.526332 -239.52327)
			(xy 105.417112 -239.52327) (xy 105.398268 -239.541901) (xy 105.355748 -239.573522) (xy 105.308736 -239.597968)
			(xy 105.258431 -239.614617) (xy 105.206116 -239.623043) (xy 105.179622 -239.6236) (xy 105.165841 -239.623457)
			(xy 105.138373 -239.621167) (xy 105.124758 -239.619028) (xy 105.10139 -239.615218) (xy 105.006394 -239.695736)
			(xy 105.006394 -240.16081) (xy 105.021126 -240.175796) (xy 105.066338 -240.221008) (xy 105.081324 -240.23574)
			(xy 108.613448 -240.23574) (xy 108.623513 -240.236173) (xy 108.642101 -240.243904) (xy 108.649516 -240.250726)
			(xy 108.764324 -240.365534) (xy 108.771173 -240.372931) (xy 108.77792 -240.389156) (xy 109.887258 -240.389156)
			(xy 109.887816 -240.362352) (xy 109.896138 -240.309394) (xy 109.912588 -240.258372) (xy 109.936767 -240.210527)
			(xy 109.968088 -240.16702) (xy 109.986572 -240.147602) (xy 109.993096 -240.140404) (xy 110.000614 -240.122506)
			(xy 110.00096 -240.103096) (xy 109.994086 -240.084942) (xy 109.987842 -240.077498) (xy 109.971488 -240.059083)
			(xy 109.943859 -240.018314) (xy 109.922594 -239.973893) (xy 109.908167 -239.926804) (xy 109.900898 -239.878095)
			(xy 109.900466 -239.85347) (xy 109.900975 -239.827503) (xy 109.9091 -239.776208) (xy 109.925148 -239.726815)
			(xy 109.948726 -239.680541) (xy 109.979252 -239.638525) (xy 110.015975 -239.601802) (xy 110.057991 -239.571276)
			(xy 110.104265 -239.547698) (xy 110.153658 -239.53165) (xy 110.204953 -239.523525) (xy 110.256887 -239.523525)
			(xy 110.308182 -239.53165) (xy 110.357575 -239.547698) (xy 110.403849 -239.571276) (xy 110.445865 -239.601802)
			(xy 110.482588 -239.638525) (xy 110.513114 -239.680541) (xy 110.536692 -239.726815) (xy 110.55274 -239.776208)
			(xy 110.560865 -239.827503) (xy 110.561374 -239.85347) (xy 110.560936 -239.878104) (xy 110.553607 -239.926825)
			(xy 110.539123 -239.973916) (xy 110.517803 -240.018334) (xy 110.490123 -240.059092) (xy 110.473744 -240.077498)
			(xy 110.467433 -240.084944) (xy 110.460495 -240.103171) (xy 110.460851 -240.12267) (xy 110.46845 -240.140632)
			(xy 110.475014 -240.147856) (xy 110.493447 -240.167275) (xy 110.524698 -240.210746) (xy 110.548825 -240.25854)
			(xy 110.565245 -240.309498) (xy 110.573558 -240.362387) (xy 110.574074 -240.389156) (xy 110.573594 -240.414855)
			(xy 110.565933 -240.465679) (xy 110.550784 -240.514793) (xy 110.528483 -240.561101) (xy 110.49953 -240.603568)
			(xy 110.46457 -240.641245) (xy 110.424386 -240.673291) (xy 110.379874 -240.69899) (xy 110.332029 -240.717767)
			(xy 110.28192 -240.729205) (xy 110.230666 -240.733046) (xy 110.179412 -240.729205) (xy 110.129303 -240.717767)
			(xy 110.081458 -240.69899) (xy 110.036946 -240.673291) (xy 109.996762 -240.641245) (xy 109.961802 -240.603568)
			(xy 109.932849 -240.561101) (xy 109.910548 -240.514793) (xy 109.895399 -240.465679) (xy 109.887738 -240.414855)
			(xy 109.887258 -240.389156) (xy 108.77792 -240.389156) (xy 108.778907 -240.39153) (xy 108.77931 -240.401602)
			(xy 108.77931 -241.728498) (xy 108.778888 -241.738569) (xy 108.771175 -241.757175) (xy 108.764324 -241.764566)
			(xy 108.565696 -241.963194) (xy 108.558297 -241.97004) (xy 108.5397 -241.977774) (xy 108.529628 -241.97818)
			(xy 107.605576 -241.97818) (xy 107.605576 -241.979196) (xy 106.971084 -241.979196) (xy 106.971084 -241.97818)
			(xy 106.640376 -241.97818) (xy 106.640376 -241.979196) (xy 106.005884 -241.979196) (xy 106.005884 -241.97818)
			(xy 105.624376 -241.97818) (xy 105.624376 -241.979196) (xy 104.989884 -241.979196) (xy 104.989884 -241.97818)
			(xy 104.659176 -241.97818) (xy 104.659176 -241.979196) (xy 104.024684 -241.979196) (xy 104.024684 -241.97818)
			(xy 103.85171 -241.97818) (xy 103.836724 -241.993166) (xy 103.812848 -242.017042) (xy 109.887258 -242.017042)
			(xy 109.887807 -241.990238) (xy 109.896132 -241.937279) (xy 109.912584 -241.886257) (xy 109.936765 -241.838412)
			(xy 109.968087 -241.794906) (xy 109.986572 -241.775488) (xy 109.993109 -241.768301) (xy 110.000625 -241.750398)
			(xy 110.000968 -241.730985) (xy 109.994089 -241.712828) (xy 109.987842 -241.705384) (xy 109.971482 -241.686974)
			(xy 109.943853 -241.646204) (xy 109.92259 -241.601781) (xy 109.908164 -241.554692) (xy 109.900896 -241.505981)
			(xy 109.900466 -241.481356) (xy 109.900975 -241.455389) (xy 109.9091 -241.404094) (xy 109.925148 -241.354701)
			(xy 109.948726 -241.308427) (xy 109.979252 -241.266411) (xy 110.015975 -241.229688) (xy 110.057991 -241.199162)
			(xy 110.104265 -241.175584) (xy 110.153658 -241.159536) (xy 110.204953 -241.151411) (xy 110.256887 -241.151411)
			(xy 110.308182 -241.159536) (xy 110.357575 -241.175584) (xy 110.403849 -241.199162) (xy 110.432409 -241.219912)
			(xy 113.17622 -241.219912) (xy 113.17761 -241.168097) (xy 113.186772 -241.117079) (xy 113.203498 -241.068018)
			(xy 113.227408 -241.022028) (xy 113.257959 -240.980154) (xy 113.275872 -240.961418) (xy 113.28238 -240.954207)
			(xy 113.2899 -240.936315) (xy 113.290251 -240.91691) (xy 113.283383 -240.898758) (xy 113.277142 -240.891314)
			(xy 113.260826 -240.872901) (xy 113.233223 -240.83218) (xy 113.211966 -240.787815) (xy 113.197526 -240.740787)
			(xy 113.190222 -240.692137) (xy 113.189766 -240.66754) (xy 113.190275 -240.641573) (xy 113.1984 -240.590278)
			(xy 113.214448 -240.540885) (xy 113.238026 -240.494611) (xy 113.268552 -240.452595) (xy 113.305275 -240.415872)
			(xy 113.347291 -240.385346) (xy 113.393565 -240.361768) (xy 113.442958 -240.34572) (xy 113.494253 -240.337595)
			(xy 113.546187 -240.337595) (xy 113.597482 -240.34572) (xy 113.646875 -240.361768) (xy 113.693149 -240.385346)
			(xy 113.735165 -240.415872) (xy 113.771888 -240.452595) (xy 113.802414 -240.494611) (xy 113.825992 -240.540885)
			(xy 113.84204 -240.590278) (xy 113.850165 -240.641573) (xy 113.850674 -240.66754) (xy 113.850232 -240.692197)
			(xy 113.842907 -240.740965) (xy 113.828425 -240.788106) (xy 113.807107 -240.832575) (xy 113.779426 -240.873388)
			(xy 113.763044 -240.891822) (xy 113.756732 -240.89921) (xy 113.749797 -240.917351) (xy 113.750089 -240.936769)
			(xy 113.757567 -240.954693) (xy 113.76406 -240.961926) (xy 113.782517 -240.981323) (xy 113.813767 -241.024799)
			(xy 113.837891 -241.072598) (xy 113.854304 -241.123562) (xy 113.86261 -241.176455) (xy 113.86312 -241.203226)
			(xy 113.862607 -241.229143) (xy 113.854812 -241.280388) (xy 113.839404 -241.329879) (xy 113.816732 -241.376492)
			(xy 113.787312 -241.419167) (xy 113.751812 -241.456936) (xy 113.711038 -241.488941) (xy 113.665917 -241.514453)
			(xy 113.617474 -241.532894) (xy 113.56681 -241.543844) (xy 113.515076 -241.547056) (xy 113.463446 -241.542454)
			(xy 113.413095 -241.530146) (xy 113.365166 -241.510409) (xy 113.320747 -241.483692) (xy 113.280849 -241.450603)
			(xy 113.246377 -241.411893) (xy 113.218115 -241.368441) (xy 113.196705 -241.321235) (xy 113.182633 -241.271348)
			(xy 113.17622 -241.219912) (xy 110.432409 -241.219912) (xy 110.445865 -241.229688) (xy 110.482588 -241.266411)
			(xy 110.513114 -241.308427) (xy 110.536692 -241.354701) (xy 110.55274 -241.404094) (xy 110.560865 -241.455389)
			(xy 110.561374 -241.481356) (xy 110.560928 -241.50599) (xy 110.553601 -241.55471) (xy 110.539118 -241.601802)
			(xy 110.517801 -241.646219) (xy 110.490122 -241.686978) (xy 110.473744 -241.705384) (xy 110.467448 -241.71284)
			(xy 110.460507 -241.731062) (xy 110.460859 -241.750558) (xy 110.468453 -241.768518) (xy 110.475014 -241.775742)
			(xy 110.493488 -241.795123) (xy 110.524734 -241.838605) (xy 110.548853 -241.886408) (xy 110.565263 -241.937375)
			(xy 110.573565 -241.99027) (xy 110.574074 -242.017042) (xy 110.573594 -242.042741) (xy 110.565933 -242.093565)
			(xy 110.550784 -242.142679) (xy 110.528483 -242.188987) (xy 110.49953 -242.231454) (xy 110.46457 -242.269131)
			(xy 110.424386 -242.301177) (xy 110.379874 -242.326876) (xy 110.332029 -242.345653) (xy 110.28192 -242.357091)
			(xy 110.230666 -242.360932) (xy 110.179412 -242.357091) (xy 110.129303 -242.345653) (xy 110.081458 -242.326876)
			(xy 110.036946 -242.301177) (xy 109.996762 -242.269131) (xy 109.961802 -242.231454) (xy 109.932849 -242.188987)
			(xy 109.910548 -242.142679) (xy 109.895399 -242.093565) (xy 109.887738 -242.042741) (xy 109.887258 -242.017042)
			(xy 103.812848 -242.017042) (xy 103.772716 -242.057174) (xy 103.75773 -242.07216) (xy 103.75773 -243.644928)
			(xy 109.887258 -243.644928) (xy 109.887799 -243.618123) (xy 109.896125 -243.565164) (xy 109.912579 -243.514143)
			(xy 109.936762 -243.466297) (xy 109.968086 -243.422791) (xy 109.986572 -243.403374) (xy 109.993123 -243.396198)
			(xy 110.000637 -243.37829) (xy 110.000975 -243.358873) (xy 109.994091 -243.340714) (xy 109.987842 -243.33327)
			(xy 109.971475 -243.314866) (xy 109.943847 -243.274094) (xy 109.922586 -243.22967) (xy 109.908161 -243.182579)
			(xy 109.900895 -243.133868) (xy 109.900466 -243.109242) (xy 109.900975 -243.083275) (xy 109.9091 -243.03198)
			(xy 109.925148 -242.982587) (xy 109.948726 -242.936313) (xy 109.979252 -242.894297) (xy 110.015975 -242.857574)
			(xy 110.057991 -242.827048) (xy 110.104265 -242.80347) (xy 110.153658 -242.787422) (xy 110.204953 -242.779297)
			(xy 110.256887 -242.779297) (xy 110.308182 -242.787422) (xy 110.357575 -242.80347) (xy 110.403849 -242.827048)
			(xy 110.432124 -242.847591) (xy 113.176171 -242.847591) (xy 113.177565 -242.795764) (xy 113.186734 -242.744735)
			(xy 113.203468 -242.695665) (xy 113.227389 -242.649667) (xy 113.257952 -242.607788) (xy 113.275872 -242.58905)
			(xy 113.282349 -242.581815) (xy 113.289874 -242.563933) (xy 113.290234 -242.544537) (xy 113.283377 -242.526389)
			(xy 113.277142 -242.518946) (xy 113.260794 -242.50056) (xy 113.233195 -242.459832) (xy 113.211945 -242.41546)
			(xy 113.197512 -242.368426) (xy 113.190217 -242.319771) (xy 113.189766 -242.295172) (xy 113.190275 -242.269205)
			(xy 113.1984 -242.21791) (xy 113.214448 -242.168517) (xy 113.238026 -242.122243) (xy 113.268552 -242.080227)
			(xy 113.305275 -242.043504) (xy 113.347291 -242.012978) (xy 113.393565 -241.9894) (xy 113.442958 -241.973352)
			(xy 113.494253 -241.965227) (xy 113.546187 -241.965227) (xy 113.597482 -241.973352) (xy 113.646875 -241.9894)
			(xy 113.693149 -242.012978) (xy 113.735165 -242.043504) (xy 113.771888 -242.080227) (xy 113.802414 -242.122243)
			(xy 113.825992 -242.168517) (xy 113.84204 -242.21791) (xy 113.850165 -242.269205) (xy 113.850674 -242.295172)
			(xy 113.850251 -242.31983) (xy 113.842922 -242.368599) (xy 113.828435 -242.415739) (xy 113.807113 -242.460208)
			(xy 113.779428 -242.50102) (xy 113.763044 -242.519454) (xy 113.756799 -242.526893) (xy 113.749853 -242.54501)
			(xy 113.750126 -242.564411) (xy 113.75758 -242.582325) (xy 113.76406 -242.589558) (xy 113.782485 -242.608985)
			(xy 113.813739 -242.652453) (xy 113.837869 -242.700244) (xy 113.85429 -242.751201) (xy 113.862604 -242.804089)
			(xy 113.86312 -242.830858) (xy 113.862659 -242.856781) (xy 113.854873 -242.908039) (xy 113.839469 -242.957543)
			(xy 113.825065 -242.98717) (xy 117.494015 -242.98717) (xy 117.494015 -242.93523) (xy 117.502141 -242.883929)
			(xy 117.518191 -242.834531) (xy 117.541771 -242.788252) (xy 117.572301 -242.746231) (xy 117.609028 -242.709503)
			(xy 117.651048 -242.678973) (xy 117.697327 -242.655392) (xy 117.746725 -242.639341) (xy 117.798026 -242.631216)
			(xy 117.823996 -242.630706) (xy 117.849857 -242.631205) (xy 117.900949 -242.639252) (xy 117.950163 -242.655163)
			(xy 117.996294 -242.678552) (xy 118.038216 -242.708845) (xy 118.056914 -242.726718) (xy 118.066629 -242.735763)
			(xy 118.089638 -242.748975) (xy 118.115275 -242.755812) (xy 118.141809 -242.755812) (xy 118.167446 -242.748975)
			(xy 118.190455 -242.735763) (xy 118.20017 -242.726718) (xy 118.218865 -242.708844) (xy 118.260794 -242.678561)
			(xy 118.306927 -242.655178) (xy 118.356138 -242.639264) (xy 118.407228 -242.631207) (xy 118.433088 -242.630706)
			(xy 118.459055 -242.631268) (xy 118.510349 -242.63939) (xy 118.559741 -242.655437) (xy 118.606015 -242.679013)
			(xy 118.648031 -242.709538) (xy 118.684754 -242.74626) (xy 118.71528 -242.788275) (xy 118.738858 -242.834548)
			(xy 118.754907 -242.883939) (xy 118.763031 -242.935233) (xy 118.763031 -242.987167) (xy 118.754907 -243.038461)
			(xy 118.738858 -243.087852) (xy 118.71528 -243.134125) (xy 118.684754 -243.17614) (xy 118.648031 -243.212862)
			(xy 118.606015 -243.243387) (xy 118.559741 -243.266963) (xy 118.510349 -243.28301) (xy 118.459055 -243.291132)
			(xy 118.433088 -243.291614) (xy 118.407227 -243.291119) (xy 118.356135 -243.283071) (xy 118.306921 -243.267158)
			(xy 118.26079 -243.243768) (xy 118.218868 -243.213475) (xy 118.20017 -243.195602) (xy 118.190455 -243.186557)
			(xy 118.167446 -243.173345) (xy 118.141809 -243.166508) (xy 118.115275 -243.166508) (xy 118.089638 -243.173345)
			(xy 118.066629 -243.186557) (xy 118.056914 -243.195602) (xy 118.038229 -243.213487) (xy 117.996297 -243.243767)
			(xy 117.950162 -243.267149) (xy 117.900948 -243.28306) (xy 117.849857 -243.291114) (xy 117.823996 -243.291614)
			(xy 117.798026 -243.291184) (xy 117.746725 -243.283059) (xy 117.697327 -243.267008) (xy 117.651048 -243.243427)
			(xy 117.609028 -243.212897) (xy 117.572301 -243.176169) (xy 117.541771 -243.134148) (xy 117.518191 -243.087869)
			(xy 117.502141 -243.038471) (xy 117.494015 -242.98717) (xy 113.825065 -242.98717) (xy 113.8168 -243.00417)
			(xy 113.787379 -243.04686) (xy 113.751876 -243.084642) (xy 113.711097 -243.116659) (xy 113.665969 -243.142182)
			(xy 113.617517 -243.160631) (xy 113.566842 -243.171588) (xy 113.515096 -243.174804) (xy 113.463455 -243.170204)
			(xy 113.413092 -243.157895) (xy 113.365151 -243.138155) (xy 113.320722 -243.111433) (xy 113.280815 -243.078336)
			(xy 113.246336 -243.039617) (xy 113.218068 -242.996155) (xy 113.196655 -242.948938) (xy 113.182583 -242.899039)
			(xy 113.176171 -242.847591) (xy 110.432124 -242.847591) (xy 110.445865 -242.857574) (xy 110.482588 -242.894297)
			(xy 110.513114 -242.936313) (xy 110.536692 -242.982587) (xy 110.55274 -243.03198) (xy 110.560865 -243.083275)
			(xy 110.561374 -243.109242) (xy 110.560919 -243.133876) (xy 110.553594 -243.182596) (xy 110.539114 -243.229687)
			(xy 110.517798 -243.274105) (xy 110.490121 -243.314863) (xy 110.473744 -243.33327) (xy 110.467461 -243.340737)
			(xy 110.460519 -243.358954) (xy 110.460867 -243.378446) (xy 110.468455 -243.396404) (xy 110.475014 -243.403628)
			(xy 110.493482 -243.423016) (xy 110.524728 -243.466495) (xy 110.548849 -243.514297) (xy 110.56526 -243.565262)
			(xy 110.573564 -243.618157) (xy 110.574074 -243.644928) (xy 110.573594 -243.670627) (xy 110.565933 -243.721451)
			(xy 110.550784 -243.770565) (xy 110.528483 -243.816873) (xy 110.49953 -243.85934) (xy 110.46457 -243.897017)
			(xy 110.424386 -243.929063) (xy 110.379874 -243.954762) (xy 110.332029 -243.973539) (xy 110.28192 -243.984977)
			(xy 110.230666 -243.988818) (xy 110.179412 -243.984977) (xy 110.129303 -243.973539) (xy 110.081458 -243.954762)
			(xy 110.036946 -243.929063) (xy 109.996762 -243.897017) (xy 109.961802 -243.85934) (xy 109.932849 -243.816873)
			(xy 109.910548 -243.770565) (xy 109.895399 -243.721451) (xy 109.887738 -243.670627) (xy 109.887258 -243.644928)
			(xy 103.75773 -243.644928) (xy 103.75773 -243.900706) (xy 103.772462 -243.915692) (xy 103.839518 -243.982748)
			(xy 103.854504 -243.99748) (xy 108.618528 -243.99748) (xy 108.628596 -243.997908) (xy 108.647195 -244.005627)
			(xy 108.654596 -244.012466) (xy 108.810044 -244.167914) (xy 108.816894 -244.17531) (xy 108.824633 -244.193909)
			(xy 108.82503 -244.203982) (xy 108.82503 -245.27256) (xy 109.887258 -245.27256) (xy 109.887756 -245.245754)
			(xy 109.896093 -245.192793) (xy 109.912557 -245.14177) (xy 109.93675 -245.093926) (xy 109.968082 -245.050422)
			(xy 109.986572 -245.031006) (xy 109.993092 -245.023805) (xy 110.000611 -245.005908) (xy 110.000958 -244.9865)
			(xy 109.994085 -244.968346) (xy 109.987842 -244.960902) (xy 109.97149 -244.942485) (xy 109.94386 -244.901717)
			(xy 109.922596 -244.857296) (xy 109.908168 -244.810208) (xy 109.900898 -244.761499) (xy 109.900466 -244.736874)
			(xy 109.900975 -244.710907) (xy 109.9091 -244.659612) (xy 109.925148 -244.610219) (xy 109.948726 -244.563945)
			(xy 109.979252 -244.521929) (xy 110.015975 -244.485206) (xy 110.057991 -244.45468) (xy 110.104265 -244.431102)
			(xy 110.153658 -244.415054) (xy 110.204953 -244.406929) (xy 110.256887 -244.406929) (xy 110.308182 -244.415054)
			(xy 110.357575 -244.431102) (xy 110.403849 -244.45468) (xy 110.432393 -244.475418) (xy 113.176233 -244.475418)
			(xy 113.177622 -244.423606) (xy 113.186782 -244.372591) (xy 113.203506 -244.323532) (xy 113.227413 -244.277544)
			(xy 113.257961 -244.235672) (xy 113.275872 -244.216936) (xy 113.282363 -244.209711) (xy 113.289886 -244.191825)
			(xy 113.290241 -244.172425) (xy 113.283379 -244.154275) (xy 113.277142 -244.146832) (xy 113.260835 -244.128411)
			(xy 113.23323 -244.087692) (xy 113.211972 -244.043329) (xy 113.19753 -243.996303) (xy 113.190223 -243.947655)
			(xy 113.189766 -243.923058) (xy 113.190275 -243.897091) (xy 113.1984 -243.845796) (xy 113.214448 -243.796403)
			(xy 113.238026 -243.750129) (xy 113.268552 -243.708113) (xy 113.305275 -243.67139) (xy 113.347291 -243.640864)
			(xy 113.393565 -243.617286) (xy 113.442958 -243.601238) (xy 113.494253 -243.593113) (xy 113.546187 -243.593113)
			(xy 113.597482 -243.601238) (xy 113.646875 -243.617286) (xy 113.693149 -243.640864) (xy 113.735165 -243.67139)
			(xy 113.771888 -243.708113) (xy 113.802414 -243.750129) (xy 113.825992 -243.796403) (xy 113.84204 -243.845796)
			(xy 113.850165 -243.897091) (xy 113.850674 -243.923058) (xy 113.850243 -243.947716) (xy 113.842915 -243.996484)
			(xy 113.828431 -244.043625) (xy 113.807111 -244.088094) (xy 113.779427 -244.128906) (xy 113.763044 -244.14734)
			(xy 113.756813 -244.154789) (xy 113.749864 -244.172901) (xy 113.750134 -244.192299) (xy 113.757583 -244.210211)
			(xy 113.76406 -244.217444) (xy 113.782478 -244.236877) (xy 113.813733 -244.280343) (xy 113.837864 -244.328133)
			(xy 113.854287 -244.379089) (xy 113.862603 -244.431976) (xy 113.86312 -244.458744) (xy 113.862592 -244.484659)
			(xy 113.854796 -244.535901) (xy 113.839386 -244.585388) (xy 113.816714 -244.631997) (xy 113.787294 -244.674669)
			(xy 113.751794 -244.712434) (xy 113.711022 -244.744436) (xy 113.665903 -244.769945) (xy 113.617463 -244.788384)
			(xy 113.566802 -244.799332) (xy 113.51507 -244.802542) (xy 113.463444 -244.797941) (xy 113.413096 -244.785632)
			(xy 113.36517 -244.765896) (xy 113.320754 -244.739181) (xy 113.280858 -244.706094) (xy 113.246389 -244.667386)
			(xy 113.218128 -244.623937) (xy 113.196719 -244.576735) (xy 113.182647 -244.52685) (xy 113.176233 -244.475418)
			(xy 110.432393 -244.475418) (xy 110.445865 -244.485206) (xy 110.482588 -244.521929) (xy 110.513114 -244.563945)
			(xy 110.536692 -244.610219) (xy 110.55274 -244.659612) (xy 110.560865 -244.710907) (xy 110.561374 -244.736874)
			(xy 110.560878 -244.761506) (xy 110.553563 -244.810224) (xy 110.539092 -244.857315) (xy 110.517786 -244.901734)
			(xy 110.490118 -244.942494) (xy 110.473744 -244.960902) (xy 110.467429 -244.968345) (xy 110.460492 -244.986573)
			(xy 110.460849 -245.006074) (xy 110.468449 -245.024036) (xy 110.475014 -245.03126) (xy 110.493449 -245.050677)
			(xy 110.5247 -245.094149) (xy 110.548827 -245.141943) (xy 110.565245 -245.192902) (xy 110.573559 -245.245791)
			(xy 110.574074 -245.27256) (xy 110.573594 -245.298259) (xy 110.565933 -245.349083) (xy 110.550784 -245.398197)
			(xy 110.528483 -245.444505) (xy 110.49953 -245.486972) (xy 110.46457 -245.524649) (xy 110.424386 -245.556695)
			(xy 110.379874 -245.582394) (xy 110.332029 -245.601171) (xy 110.28192 -245.612609) (xy 110.230666 -245.61645)
			(xy 110.179412 -245.612609) (xy 110.129303 -245.601171) (xy 110.081458 -245.582394) (xy 110.036946 -245.556695)
			(xy 109.996762 -245.524649) (xy 109.961802 -245.486972) (xy 109.932849 -245.444505) (xy 109.910548 -245.398197)
			(xy 109.895399 -245.349083) (xy 109.887738 -245.298259) (xy 109.887258 -245.27256) (xy 108.82503 -245.27256)
			(xy 108.82503 -245.502938) (xy 108.824601 -245.513006) (xy 108.81688 -245.531603) (xy 108.810044 -245.539006)
			(xy 108.662216 -245.686834) (xy 108.654816 -245.693674) (xy 108.636217 -245.701388) (xy 108.626148 -245.70182)
			(xy 105.155238 -245.70182) (xy 105.140252 -245.716806) (xy 105.040684 -245.816374) (xy 105.025698 -245.83136)
			(xy 105.025698 -246.254778) (xy 105.026313 -246.266627) (xy 105.036902 -246.287825) (xy 105.046018 -246.295418)
			(xy 105.131362 -246.359172) (xy 105.155746 -246.35206) (xy 105.178477 -246.345803) (xy 105.225137 -246.339048)
			(xy 105.24871 -246.338598) (xy 105.273639 -246.33905) (xy 105.322933 -246.34653) (xy 105.370548 -246.361318)
			(xy 105.415406 -246.38308) (xy 105.456493 -246.411323) (xy 105.475024 -246.428006) (xy 105.481882 -246.43461)
			(xy 105.516426 -246.44858) (xy 105.588054 -246.44858) (xy 105.622598 -246.43461) (xy 105.629456 -246.428006)
			(xy 105.647965 -246.411297) (xy 105.689061 -246.383059) (xy 105.733925 -246.361298) (xy 105.781542 -246.346506)
			(xy 105.830839 -246.339015) (xy 105.85577 -246.338598) (xy 105.881784 -246.339079) (xy 105.933172 -246.347214)
			(xy 105.982654 -246.363288) (xy 106.029013 -246.386905) (xy 106.071106 -246.417484) (xy 106.107897 -246.454271)
			(xy 106.138479 -246.496362) (xy 106.162101 -246.542718) (xy 106.178179 -246.592199) (xy 106.186318 -246.643586)
			(xy 106.186318 -246.695614) (xy 106.178179 -246.747001) (xy 106.162101 -246.796482) (xy 106.138479 -246.842838)
			(xy 106.107897 -246.884929) (xy 106.092378 -246.900446) (xy 109.887258 -246.900446) (xy 109.88781 -246.873642)
			(xy 109.896133 -246.820683) (xy 109.912585 -246.769662) (xy 109.936766 -246.721816) (xy 109.968087 -246.67831)
			(xy 109.986572 -246.658892) (xy 109.993106 -246.651702) (xy 110.000622 -246.6338) (xy 110.000966 -246.614388)
			(xy 109.994088 -246.596232) (xy 109.987842 -246.588788) (xy 109.971483 -246.570377) (xy 109.943855 -246.529607)
			(xy 109.922591 -246.485184) (xy 109.908165 -246.438095) (xy 109.900897 -246.389385) (xy 109.900466 -246.36476)
			(xy 109.900975 -246.338793) (xy 109.9091 -246.287498) (xy 109.925148 -246.238105) (xy 109.948726 -246.191831)
			(xy 109.979252 -246.149815) (xy 110.015975 -246.113092) (xy 110.057991 -246.082566) (xy 110.104265 -246.058988)
			(xy 110.153658 -246.04294) (xy 110.204953 -246.034815) (xy 110.256887 -246.034815) (xy 110.308182 -246.04294)
			(xy 110.357575 -246.058988) (xy 110.403849 -246.082566) (xy 110.432407 -246.103314) (xy 113.176223 -246.103314)
			(xy 113.177612 -246.051499) (xy 113.186774 -246.000482) (xy 113.2035 -245.951421) (xy 113.227409 -245.905431)
			(xy 113.257959 -245.863558) (xy 113.275872 -245.844822) (xy 113.282376 -245.837608) (xy 113.289897 -245.819717)
			(xy 113.290249 -245.800313) (xy 113.283382 -245.782162) (xy 113.277142 -245.774718) (xy 113.260828 -245.756303)
			(xy 113.233225 -245.715583) (xy 113.211967 -245.671218) (xy 113.197527 -245.62419) (xy 113.190222 -245.575541)
			(xy 113.189766 -245.550944) (xy 113.190275 -245.524977) (xy 113.1984 -245.473682) (xy 113.214448 -245.424289)
			(xy 113.238026 -245.378015) (xy 113.268552 -245.335999) (xy 113.305275 -245.299276) (xy 113.347291 -245.26875)
			(xy 113.393565 -245.245172) (xy 113.442958 -245.229124) (xy 113.494253 -245.220999) (xy 113.546187 -245.220999)
			(xy 113.597482 -245.229124) (xy 113.646875 -245.245172) (xy 113.693149 -245.26875) (xy 113.735165 -245.299276)
			(xy 113.771888 -245.335999) (xy 113.802414 -245.378015) (xy 113.825992 -245.424289) (xy 113.84204 -245.473682)
			(xy 113.850165 -245.524977) (xy 113.850674 -245.550944) (xy 113.850234 -245.575601) (xy 113.842909 -245.624369)
			(xy 113.828427 -245.67151) (xy 113.807108 -245.715979) (xy 113.779426 -245.756792) (xy 113.763044 -245.775226)
			(xy 113.756728 -245.782611) (xy 113.749793 -245.800753) (xy 113.750087 -245.820173) (xy 113.757567 -245.838097)
			(xy 113.76406 -245.84533) (xy 113.782519 -245.864725) (xy 113.813769 -245.908202) (xy 113.837892 -245.956001)
			(xy 113.854305 -246.006965) (xy 113.86261 -246.059859) (xy 113.86312 -246.08663) (xy 113.862604 -246.112547)
			(xy 113.854809 -246.163791) (xy 113.8394 -246.213281) (xy 113.816728 -246.259893) (xy 113.787308 -246.302568)
			(xy 113.751808 -246.340336) (xy 113.711035 -246.37234) (xy 113.665914 -246.397852) (xy 113.617472 -246.416292)
			(xy 113.566808 -246.427242) (xy 113.515075 -246.430453) (xy 113.463446 -246.425851) (xy 113.413095 -246.413543)
			(xy 113.365166 -246.393806) (xy 113.320749 -246.36709) (xy 113.280851 -246.334001) (xy 113.24638 -246.295291)
			(xy 113.218118 -246.25184) (xy 113.196708 -246.204635) (xy 113.182636 -246.154749) (xy 113.176223 -246.103314)
			(xy 110.432407 -246.103314) (xy 110.445865 -246.113092) (xy 110.482588 -246.149815) (xy 110.513114 -246.191831)
			(xy 110.536692 -246.238105) (xy 110.55274 -246.287498) (xy 110.560865 -246.338793) (xy 110.561374 -246.36476)
			(xy 110.56093 -246.389394) (xy 110.553603 -246.438114) (xy 110.539119 -246.485206) (xy 110.517802 -246.529623)
			(xy 110.490123 -246.570382) (xy 110.473744 -246.588788) (xy 110.467444 -246.596241) (xy 110.460504 -246.614465)
			(xy 110.460857 -246.633961) (xy 110.468452 -246.651922) (xy 110.475014 -246.659146) (xy 110.493442 -246.678569)
			(xy 110.524694 -246.722039) (xy 110.548822 -246.769832) (xy 110.565243 -246.820789) (xy 110.573558 -246.873677)
			(xy 110.574074 -246.900446) (xy 110.573594 -246.926145) (xy 110.565933 -246.976969) (xy 110.550784 -247.026083)
			(xy 110.528483 -247.072391) (xy 110.49953 -247.114858) (xy 110.46457 -247.152535) (xy 110.424386 -247.184581)
			(xy 110.379874 -247.21028) (xy 110.332029 -247.229057) (xy 110.28192 -247.240495) (xy 110.230666 -247.244336)
			(xy 110.179412 -247.240495) (xy 110.129303 -247.229057) (xy 110.081458 -247.21028) (xy 110.036946 -247.184581)
			(xy 109.996762 -247.152535) (xy 109.961802 -247.114858) (xy 109.932849 -247.072391) (xy 109.910548 -247.026083)
			(xy 109.895399 -246.976969) (xy 109.887738 -246.926145) (xy 109.887258 -246.900446) (xy 106.092378 -246.900446)
			(xy 106.071106 -246.921716) (xy 106.029013 -246.952295) (xy 105.982654 -246.975912) (xy 105.933172 -246.991986)
			(xy 105.881784 -247.000121) (xy 105.85577 -247.000522) (xy 105.829123 -246.999984) (xy 105.77652 -246.991433)
			(xy 105.725968 -246.974557) (xy 105.678777 -246.949793) (xy 105.657142 -246.934228) (xy 105.447338 -246.934228)
			(xy 105.426506 -246.949273) (xy 105.381147 -246.973417) (xy 105.332598 -246.990252) (xy 105.28203 -246.999375)
			(xy 105.230659 -247.000565) (xy 105.179723 -246.993793) (xy 105.130447 -246.979223) (xy 105.084019 -246.957206)
			(xy 105.062528 -246.943118) (xy 105.049574 -246.934228) (xy 104.98328 -246.934228) (xy 104.94772 -246.969788)
			(xy 104.94772 -247.622568) (xy 105.005632 -247.68048) (xy 108.593128 -247.68048) (xy 108.603196 -247.680908)
			(xy 108.621795 -247.688627) (xy 108.629196 -247.695466) (xy 108.789724 -247.855994) (xy 108.79658 -247.863388)
			(xy 108.804329 -247.881987) (xy 108.80471 -247.892062) (xy 108.80471 -248.528078) (xy 109.887258 -248.528078)
			(xy 109.887767 -248.501272) (xy 109.896101 -248.448312) (xy 109.912563 -248.39729) (xy 109.936753 -248.349445)
			(xy 109.968083 -248.30594) (xy 109.986572 -248.286524) (xy 109.993074 -248.279309) (xy 110.000595 -248.261419)
			(xy 110.000948 -248.242015) (xy 109.994081 -248.223864) (xy 109.987842 -248.21642) (xy 109.971499 -248.197996)
			(xy 109.943868 -248.15723) (xy 109.922601 -248.11281) (xy 109.908172 -248.065724) (xy 109.900899 -248.017016)
			(xy 109.900466 -247.992392) (xy 109.900975 -247.966425) (xy 109.9091 -247.91513) (xy 109.925148 -247.865737)
			(xy 109.948726 -247.819463) (xy 109.979252 -247.777447) (xy 110.015975 -247.740724) (xy 110.057991 -247.710198)
			(xy 110.104265 -247.68662) (xy 110.153658 -247.670572) (xy 110.204953 -247.662447) (xy 110.256887 -247.662447)
			(xy 110.308182 -247.670572) (xy 110.357575 -247.68662) (xy 110.403849 -247.710198) (xy 110.43247 -247.730992)
			(xy 113.176174 -247.730992) (xy 113.177568 -247.679166) (xy 113.186736 -247.628138) (xy 113.20347 -247.579068)
			(xy 113.22739 -247.533071) (xy 113.257953 -247.491192) (xy 113.275872 -247.472454) (xy 113.282345 -247.465215)
			(xy 113.289871 -247.447336) (xy 113.290232 -247.42794) (xy 113.283376 -247.409793) (xy 113.277142 -247.40235)
			(xy 113.260796 -247.383962) (xy 113.233197 -247.343234) (xy 113.211946 -247.298863) (xy 113.197513 -247.251829)
			(xy 113.190217 -247.203175) (xy 113.189766 -247.178576) (xy 113.190275 -247.152609) (xy 113.1984 -247.101314)
			(xy 113.214448 -247.051921) (xy 113.238026 -247.005647) (xy 113.268552 -246.963631) (xy 113.305275 -246.926908)
			(xy 113.347291 -246.896382) (xy 113.393565 -246.872804) (xy 113.442958 -246.856756) (xy 113.494253 -246.848631)
			(xy 113.546187 -246.848631) (xy 113.597482 -246.856756) (xy 113.646875 -246.872804) (xy 113.693149 -246.896382)
			(xy 113.735165 -246.926908) (xy 113.771888 -246.963631) (xy 113.802414 -247.005647) (xy 113.825992 -247.051921)
			(xy 113.84204 -247.101314) (xy 113.850165 -247.152609) (xy 113.850674 -247.178576) (xy 113.850254 -247.203234)
			(xy 113.842923 -247.252003) (xy 113.828437 -247.299144) (xy 113.807114 -247.343612) (xy 113.779428 -247.384424)
			(xy 113.763044 -247.402858) (xy 113.756795 -247.410294) (xy 113.749849 -247.428412) (xy 113.750124 -247.447814)
			(xy 113.757579 -247.465729) (xy 113.76406 -247.472962) (xy 113.782487 -247.492387) (xy 113.81374 -247.535855)
			(xy 113.83787 -247.583647) (xy 113.854291 -247.634605) (xy 113.862605 -247.687493) (xy 113.86312 -247.714262)
			(xy 113.862656 -247.740185) (xy 113.854869 -247.791441) (xy 113.839465 -247.840945) (xy 113.816796 -247.887572)
			(xy 113.787375 -247.930261) (xy 113.751872 -247.968042) (xy 113.711094 -248.000058) (xy 113.665966 -248.02558)
			(xy 113.617514 -248.044029) (xy 113.56684 -248.054986) (xy 113.515095 -248.058201) (xy 113.463454 -248.053601)
			(xy 113.413092 -248.041292) (xy 113.365152 -248.021552) (xy 113.320723 -247.994831) (xy 113.280817 -247.961734)
			(xy 113.246338 -247.923016) (xy 113.218071 -247.879554) (xy 113.196658 -247.832338) (xy 113.182586 -247.782439)
			(xy 113.176174 -247.730992) (xy 110.43247 -247.730992) (xy 110.445865 -247.740724) (xy 110.482588 -247.777447)
			(xy 110.513114 -247.819463) (xy 110.536692 -247.865737) (xy 110.55274 -247.91513) (xy 110.560865 -247.966425)
			(xy 110.561374 -247.992392) (xy 110.560889 -248.017025) (xy 110.553572 -248.065743) (xy 110.539098 -248.112834)
			(xy 110.517789 -248.157252) (xy 110.490119 -248.198012) (xy 110.473744 -248.21642) (xy 110.467412 -248.223849)
			(xy 110.460477 -248.242084) (xy 110.460839 -248.261589) (xy 110.468446 -248.279554) (xy 110.475014 -248.286778)
			(xy 110.493458 -248.306187) (xy 110.524707 -248.349661) (xy 110.548832 -248.397457) (xy 110.565249 -248.448418)
			(xy 110.57356 -248.501308) (xy 110.574074 -248.528078) (xy 110.573594 -248.553777) (xy 110.565933 -248.604601)
			(xy 110.550784 -248.653715) (xy 110.528483 -248.700023) (xy 110.49953 -248.74249) (xy 110.46457 -248.780167)
			(xy 110.424386 -248.812213) (xy 110.379874 -248.837912) (xy 110.332029 -248.856689) (xy 110.28192 -248.868127)
			(xy 110.230666 -248.871968) (xy 110.179412 -248.868127) (xy 110.129303 -248.856689) (xy 110.081458 -248.837912)
			(xy 110.036946 -248.812213) (xy 109.996762 -248.780167) (xy 109.961802 -248.74249) (xy 109.932849 -248.700023)
			(xy 109.910548 -248.653715) (xy 109.895399 -248.604601) (xy 109.887738 -248.553777) (xy 109.887258 -248.528078)
			(xy 108.80471 -248.528078) (xy 108.80471 -249.196098) (xy 108.804288 -249.206169) (xy 108.796575 -249.224775)
			(xy 108.789724 -249.232166) (xy 108.682536 -249.339354) (xy 108.675136 -249.346195) (xy 108.656538 -249.353914)
			(xy 108.646468 -249.35434) (xy 103.869236 -249.35434) (xy 103.818944 -249.404632) (xy 103.775256 -249.448574)
			(xy 103.76027 -249.46356) (xy 103.76027 -250.363265) (xy 105.127075 -250.363265) (xy 105.127075 -250.311335)
			(xy 105.135199 -250.260044) (xy 105.151246 -250.210655) (xy 105.174821 -250.164385) (xy 105.205345 -250.122372)
			(xy 105.242064 -250.085651) (xy 105.284076 -250.055126) (xy 105.330346 -250.03155) (xy 105.379734 -250.015501)
			(xy 105.431025 -250.007376) (xy 105.45699 -250.006866) (xy 105.482743 -250.007367) (xy 105.533628 -250.015345)
			(xy 105.582657 -250.031124) (xy 105.628643 -250.054321) (xy 105.670471 -250.084376) (xy 105.689146 -250.102116)
			(xy 105.698836 -250.111109) (xy 105.721768 -250.124241) (xy 105.747307 -250.131036) (xy 105.773733 -250.131036)
			(xy 105.799272 -250.124241) (xy 105.822204 -250.111109) (xy 105.831894 -250.102116) (xy 105.850579 -250.084388)
			(xy 105.89241 -250.05434) (xy 105.938394 -250.031143) (xy 105.987418 -250.015356) (xy 106.038298 -250.007362)
			(xy 106.06405 -250.006866) (xy 106.090023 -250.007305) (xy 106.141332 -250.015424) (xy 106.190738 -250.031471)
			(xy 106.237025 -250.055049) (xy 106.279054 -250.085579) (xy 106.315788 -250.122308) (xy 106.340244 -250.155964)
			(xy 109.887258 -250.155964) (xy 109.887759 -250.129158) (xy 109.896095 -250.076197) (xy 109.912559 -250.025175)
			(xy 109.93675 -249.97733) (xy 109.968082 -249.933826) (xy 109.986572 -249.91441) (xy 109.993088 -249.907206)
			(xy 110.000607 -249.889311) (xy 110.000955 -249.869903) (xy 109.994084 -249.85175) (xy 109.987842 -249.844306)
			(xy 109.971492 -249.825887) (xy 109.943862 -249.78512) (xy 109.922597 -249.740699) (xy 109.908169 -249.693611)
			(xy 109.900898 -249.644903) (xy 109.900466 -249.620278) (xy 109.900975 -249.594311) (xy 109.9091 -249.543016)
			(xy 109.925148 -249.493623) (xy 109.948726 -249.447349) (xy 109.979252 -249.405333) (xy 110.015975 -249.36861)
			(xy 110.057991 -249.338084) (xy 110.104265 -249.314506) (xy 110.153658 -249.298458) (xy 110.204953 -249.290333)
			(xy 110.256887 -249.290333) (xy 110.308182 -249.298458) (xy 110.357575 -249.314506) (xy 110.403849 -249.338084)
			(xy 110.432389 -249.358819) (xy 113.176236 -249.358819) (xy 113.177625 -249.307008) (xy 113.186785 -249.255993)
			(xy 113.203508 -249.206935) (xy 113.227414 -249.160948) (xy 113.257961 -249.119076) (xy 113.275872 -249.10034)
			(xy 113.282359 -249.093112) (xy 113.289882 -249.075228) (xy 113.290239 -249.055828) (xy 113.283378 -249.037679)
			(xy 113.277142 -249.030236) (xy 113.260837 -249.011814) (xy 113.233232 -248.971095) (xy 113.211973 -248.926732)
			(xy 113.19753 -248.879707) (xy 113.190224 -248.831059) (xy 113.189766 -248.806462) (xy 113.190275 -248.780495)
			(xy 113.1984 -248.7292) (xy 113.214448 -248.679807) (xy 113.238026 -248.633533) (xy 113.268552 -248.591517)
			(xy 113.305275 -248.554794) (xy 113.347291 -248.524268) (xy 113.393565 -248.50069) (xy 113.442958 -248.484642)
			(xy 113.494253 -248.476517) (xy 113.546187 -248.476517) (xy 113.597482 -248.484642) (xy 113.646875 -248.50069)
			(xy 113.693149 -248.524268) (xy 113.735165 -248.554794) (xy 113.771888 -248.591517) (xy 113.802414 -248.633533)
			(xy 113.825992 -248.679807) (xy 113.84204 -248.7292) (xy 113.850165 -248.780495) (xy 113.850674 -248.806462)
			(xy 113.850245 -248.83112) (xy 113.842917 -248.879888) (xy 113.828432 -248.927029) (xy 113.807111 -248.971498)
			(xy 113.779427 -249.01231) (xy 113.763044 -249.030744) (xy 113.756809 -249.03819) (xy 113.749861 -249.056304)
			(xy 113.750131 -249.075702) (xy 113.757582 -249.093615) (xy 113.76406 -249.100848) (xy 113.78248 -249.120279)
			(xy 113.813735 -249.163746) (xy 113.837865 -249.211536) (xy 113.854288 -249.262492) (xy 113.862604 -249.31538)
			(xy 113.86312 -249.342148) (xy 113.862589 -249.368063) (xy 113.854792 -249.419303) (xy 113.839382 -249.46879)
			(xy 113.81671 -249.515398) (xy 113.78729 -249.558069) (xy 113.751791 -249.595834) (xy 113.711019 -249.627835)
			(xy 113.6659 -249.653343) (xy 113.617461 -249.671782) (xy 113.5668 -249.68273) (xy 113.515069 -249.685939)
			(xy 113.463444 -249.681338) (xy 113.413096 -249.669029) (xy 113.365171 -249.649293) (xy 113.320756 -249.622578)
			(xy 113.28086 -249.589492) (xy 113.246391 -249.550784) (xy 113.218131 -249.507336) (xy 113.196722 -249.460134)
			(xy 113.18265 -249.410251) (xy 113.176236 -249.358819) (xy 110.432389 -249.358819) (xy 110.445865 -249.36861)
			(xy 110.482588 -249.405333) (xy 110.513114 -249.447349) (xy 110.536692 -249.493623) (xy 110.55274 -249.543016)
			(xy 110.560865 -249.594311) (xy 110.561374 -249.620278) (xy 110.56088 -249.64491) (xy 110.553565 -249.693628)
			(xy 110.539094 -249.740719) (xy 110.517787 -249.785138) (xy 110.490118 -249.825898) (xy 110.473744 -249.844306)
			(xy 110.467425 -249.851746) (xy 110.460488 -249.869975) (xy 110.460847 -249.889477) (xy 110.468448 -249.90744)
			(xy 110.475014 -249.914664) (xy 110.493451 -249.934079) (xy 110.524701 -249.977551) (xy 110.548828 -250.025346)
			(xy 110.565246 -250.076305) (xy 110.573559 -250.129195) (xy 110.574074 -250.155964) (xy 110.573594 -250.181663)
			(xy 110.565933 -250.232487) (xy 110.550784 -250.281601) (xy 110.528483 -250.327909) (xy 110.504378 -250.363265)
			(xy 117.494075 -250.363265) (xy 117.494075 -250.311335) (xy 117.502199 -250.260043) (xy 117.518246 -250.210654)
			(xy 117.541822 -250.164383) (xy 117.572346 -250.12237) (xy 117.609067 -250.085649) (xy 117.651079 -250.055124)
			(xy 117.69735 -250.031548) (xy 117.746739 -250.0155) (xy 117.798031 -250.007375) (xy 117.823996 -250.006866)
			(xy 117.849856 -250.007377) (xy 117.900948 -250.015422) (xy 117.95016 -250.031332) (xy 117.996292 -250.054717)
			(xy 118.038215 -250.085007) (xy 118.056914 -250.102878) (xy 118.066629 -250.111923) (xy 118.089638 -250.125135)
			(xy 118.115275 -250.131972) (xy 118.141809 -250.131972) (xy 118.167446 -250.125135) (xy 118.190455 -250.111923)
			(xy 118.20017 -250.102878) (xy 118.218859 -250.084997) (xy 118.26079 -250.054717) (xy 118.306925 -250.031335)
			(xy 118.356137 -250.015423) (xy 118.407227 -250.007367) (xy 118.433088 -250.006866) (xy 118.459059 -250.007308)
			(xy 118.510363 -250.015432) (xy 118.559764 -250.031482) (xy 118.606046 -250.055062) (xy 118.64807 -250.085593)
			(xy 118.6848 -250.122321) (xy 118.715332 -250.164343) (xy 118.738914 -250.210625) (xy 118.754965 -250.260025)
			(xy 118.763091 -250.311329) (xy 118.763091 -250.363271) (xy 118.754965 -250.414575) (xy 118.738914 -250.463975)
			(xy 118.715332 -250.510257) (xy 118.6848 -250.552279) (xy 118.64807 -250.589007) (xy 118.606046 -250.619538)
			(xy 118.559764 -250.643118) (xy 118.510363 -250.659168) (xy 118.459059 -250.667292) (xy 118.433088 -250.667774)
			(xy 118.407228 -250.667262) (xy 118.356137 -250.659216) (xy 118.306925 -250.643306) (xy 118.260793 -250.619921)
			(xy 118.218869 -250.589632) (xy 118.20017 -250.571762) (xy 118.190455 -250.562717) (xy 118.167446 -250.549505)
			(xy 118.141809 -250.542668) (xy 118.115275 -250.542668) (xy 118.089638 -250.549505) (xy 118.066629 -250.562717)
			(xy 118.056914 -250.571762) (xy 118.038222 -250.58964) (xy 117.996293 -250.619923) (xy 117.95016 -250.643306)
			(xy 117.900947 -250.659219) (xy 117.849857 -250.667274) (xy 117.823996 -250.667774) (xy 117.798031 -250.667225)
			(xy 117.746739 -250.6591) (xy 117.69735 -250.643052) (xy 117.651079 -250.619476) (xy 117.609067 -250.588951)
			(xy 117.572346 -250.55223) (xy 117.541822 -250.510217) (xy 117.518246 -250.463946) (xy 117.502199 -250.414557)
			(xy 117.494075 -250.363265) (xy 110.504378 -250.363265) (xy 110.49953 -250.370376) (xy 110.46457 -250.408053)
			(xy 110.424386 -250.440099) (xy 110.379874 -250.465798) (xy 110.332029 -250.484575) (xy 110.28192 -250.496013)
			(xy 110.230666 -250.499854) (xy 110.179412 -250.496013) (xy 110.129303 -250.484575) (xy 110.081458 -250.465798)
			(xy 110.036946 -250.440099) (xy 109.996762 -250.408053) (xy 109.961802 -250.370376) (xy 109.932849 -250.327909)
			(xy 109.910548 -250.281601) (xy 109.895399 -250.232487) (xy 109.887738 -250.181663) (xy 109.887258 -250.155964)
			(xy 106.340244 -250.155964) (xy 106.346325 -250.164332) (xy 106.36991 -250.210616) (xy 106.385964 -250.26002)
			(xy 106.394091 -250.311327) (xy 106.394091 -250.363273) (xy 106.385964 -250.41458) (xy 106.36991 -250.463984)
			(xy 106.346325 -250.510268) (xy 106.315788 -250.552292) (xy 106.279054 -250.589021) (xy 106.237025 -250.619551)
			(xy 106.190738 -250.643129) (xy 106.141332 -250.659176) (xy 106.090023 -250.667295) (xy 106.06405 -250.667774)
			(xy 106.038295 -250.667328) (xy 105.987407 -250.659339) (xy 105.938376 -250.643548) (xy 105.892391 -250.620338)
			(xy 105.850566 -250.590271) (xy 105.831894 -250.572524) (xy 105.822204 -250.563531) (xy 105.799272 -250.550399)
			(xy 105.773733 -250.543604) (xy 105.747307 -250.543604) (xy 105.721768 -250.550399) (xy 105.698836 -250.563531)
			(xy 105.689146 -250.572524) (xy 105.670494 -250.590288) (xy 105.628654 -250.620329) (xy 105.582661 -250.64352)
			(xy 105.533629 -250.659298) (xy 105.482744 -250.667283) (xy 105.45699 -250.667774) (xy 105.431025 -250.667224)
			(xy 105.379734 -250.659099) (xy 105.330346 -250.64305) (xy 105.284076 -250.619474) (xy 105.242064 -250.588949)
			(xy 105.205345 -250.552228) (xy 105.174821 -250.510215) (xy 105.151246 -250.463945) (xy 105.135199 -250.414556)
			(xy 105.127075 -250.363265) (xy 103.76027 -250.363265) (xy 103.76027 -251.187966) (xy 103.775002 -251.202952)
			(xy 103.890318 -251.318268) (xy 103.905304 -251.333) (xy 108.608368 -251.333) (xy 108.618433 -251.333436)
			(xy 108.637019 -251.341167) (xy 108.644436 -251.347986) (xy 108.817664 -251.521214) (xy 108.824512 -251.528612)
			(xy 108.832247 -251.54721) (xy 108.83265 -251.557282) (xy 108.83265 -252.828298) (xy 108.832226 -252.838367)
			(xy 108.824506 -252.856967) (xy 108.817664 -252.864366) (xy 108.692696 -252.989334) (xy 108.685301 -252.996187)
			(xy 108.666702 -253.003931) (xy 108.656628 -253.00432) (xy 103.90251 -253.00432) (xy 103.887524 -253.019306)
			(xy 103.785416 -253.121414) (xy 103.77043 -253.1364) (xy 103.77043 -253.367084) (xy 113.286199 -253.367084)
			(xy 113.292614 -253.315645) (xy 113.306687 -253.265753) (xy 113.328099 -253.218544) (xy 113.356364 -253.17509)
			(xy 113.390839 -253.136377) (xy 113.430742 -253.103286) (xy 113.475164 -253.076569) (xy 113.523098 -253.056832)
			(xy 113.573454 -253.044523) (xy 113.625087 -253.039923) (xy 113.676826 -253.043137) (xy 113.727494 -253.05409)
			(xy 113.77594 -253.072534) (xy 113.821063 -253.098051) (xy 113.861838 -253.130059) (xy 113.897339 -253.167833)
			(xy 113.92676 -253.210514) (xy 113.94943 -253.257132) (xy 113.964837 -253.306628) (xy 113.972629 -253.357877)
			(xy 113.973102 -253.383796) (xy 113.972588 -253.410602) (xy 113.964257 -253.463563) (xy 113.947797 -253.514585)
			(xy 113.923608 -253.56243) (xy 113.892277 -253.605934) (xy 113.873788 -253.62535) (xy 113.867228 -253.632578)
			(xy 113.859622 -253.650535) (xy 113.859268 -253.670033) (xy 113.866216 -253.688255) (xy 113.872518 -253.695708)
			(xy 113.888932 -253.71413) (xy 113.916693 -253.754917) (xy 113.938073 -253.799381) (xy 113.952598 -253.846533)
			(xy 113.959942 -253.895321) (xy 113.960402 -253.91999) (xy 113.959893 -253.945957) (xy 113.951768 -253.997252)
			(xy 113.937501 -254.041164) (xy 117.494095 -254.041164) (xy 117.494095 -253.989236) (xy 117.502218 -253.937948)
			(xy 117.518265 -253.888561) (xy 117.541839 -253.842293) (xy 117.572361 -253.800283) (xy 117.60908 -253.763564)
			(xy 117.65109 -253.733041) (xy 117.697358 -253.709466) (xy 117.746744 -253.693419) (xy 117.798032 -253.685295)
			(xy 117.823996 -253.684786) (xy 117.849857 -253.685291) (xy 117.900948 -253.693337) (xy 117.950162 -253.709247)
			(xy 117.996293 -253.732635) (xy 118.038216 -253.762926) (xy 118.056914 -253.780798) (xy 118.066629 -253.789843)
			(xy 118.089638 -253.803055) (xy 118.115275 -253.809892) (xy 118.141809 -253.809892) (xy 118.167446 -253.803055)
			(xy 118.190455 -253.789843) (xy 118.20017 -253.780798) (xy 118.218862 -253.762921) (xy 118.260792 -253.732639)
			(xy 118.306926 -253.709257) (xy 118.356138 -253.693343) (xy 118.407228 -253.685287) (xy 118.433088 -253.684786)
			(xy 118.459061 -253.685188) (xy 118.510368 -253.693313) (xy 118.559772 -253.709363) (xy 118.606057 -253.732945)
			(xy 118.648083 -253.763477) (xy 118.684815 -253.800208) (xy 118.715349 -253.842233) (xy 118.738932 -253.888517)
			(xy 118.754985 -253.93792) (xy 118.763111 -253.989227) (xy 118.763111 -254.041173) (xy 118.754985 -254.09248)
			(xy 118.738932 -254.141883) (xy 118.715349 -254.188167) (xy 118.684815 -254.230192) (xy 118.648083 -254.266923)
			(xy 118.606057 -254.297455) (xy 118.559772 -254.321037) (xy 118.510368 -254.337087) (xy 118.459061 -254.345212)
			(xy 118.433088 -254.345694) (xy 118.407227 -254.345205) (xy 118.356134 -254.337156) (xy 118.30692 -254.321242)
			(xy 118.260789 -254.297851) (xy 118.218867 -254.267556) (xy 118.20017 -254.249682) (xy 118.190455 -254.240637)
			(xy 118.167446 -254.227425) (xy 118.141809 -254.220588) (xy 118.115275 -254.220588) (xy 118.089638 -254.227425)
			(xy 118.066629 -254.240637) (xy 118.056914 -254.249682) (xy 118.038226 -254.267564) (xy 117.996295 -254.297845)
			(xy 117.950161 -254.321227) (xy 117.900948 -254.33714) (xy 117.849857 -254.345194) (xy 117.823996 -254.345694)
			(xy 117.798032 -254.345105) (xy 117.746744 -254.336981) (xy 117.697358 -254.320934) (xy 117.65109 -254.297359)
			(xy 117.60908 -254.266836) (xy 117.572361 -254.230117) (xy 117.541839 -254.188107) (xy 117.518265 -254.141839)
			(xy 117.502218 -254.092452) (xy 117.494095 -254.041164) (xy 113.937501 -254.041164) (xy 113.93572 -254.046645)
			(xy 113.912142 -254.092919) (xy 113.881616 -254.134935) (xy 113.844893 -254.171658) (xy 113.802877 -254.202184)
			(xy 113.756603 -254.225762) (xy 113.70721 -254.24181) (xy 113.655915 -254.249935) (xy 113.603981 -254.249935)
			(xy 113.552686 -254.24181) (xy 113.503293 -254.225762) (xy 113.457019 -254.202184) (xy 113.415003 -254.171658)
			(xy 113.37828 -254.134935) (xy 113.347754 -254.092919) (xy 113.324176 -254.046645) (xy 113.308128 -253.997252)
			(xy 113.300003 -253.945957) (xy 113.299494 -253.91999) (xy 113.29995 -253.895356) (xy 113.307272 -253.846636)
			(xy 113.321751 -253.799544) (xy 113.343067 -253.755126) (xy 113.370745 -253.714368) (xy 113.387124 -253.695962)
			(xy 113.393367 -253.688468) (xy 113.400305 -253.670263) (xy 113.399967 -253.650784) (xy 113.3924 -253.632831)
			(xy 113.385854 -253.625604) (xy 113.367945 -253.606862) (xy 113.337391 -253.564985) (xy 113.313479 -253.518991)
			(xy 113.296751 -253.469926) (xy 113.287589 -253.418904) (xy 113.286199 -253.367084) (xy 103.77043 -253.367084)
			(xy 103.77043 -254.041164) (xy 105.127095 -254.041164) (xy 105.127095 -253.989236) (xy 105.135218 -253.937949)
			(xy 105.151264 -253.888563) (xy 105.174838 -253.842295) (xy 105.20536 -253.800285) (xy 105.242077 -253.763566)
			(xy 105.284087 -253.733043) (xy 105.330354 -253.709468) (xy 105.379739 -253.69342) (xy 105.431026 -253.685296)
			(xy 105.45699 -253.684786) (xy 105.482743 -253.685281) (xy 105.533628 -253.693259) (xy 105.582658 -253.709039)
			(xy 105.628644 -253.732239) (xy 105.670472 -253.762295) (xy 105.689146 -253.780036) (xy 105.698836 -253.789029)
			(xy 105.721768 -253.802161) (xy 105.747307 -253.808956) (xy 105.773733 -253.808956) (xy 105.799272 -253.802161)
			(xy 105.822204 -253.789029) (xy 105.831894 -253.780036) (xy 105.850582 -253.762311) (xy 105.892412 -253.732263)
			(xy 105.938395 -253.709064) (xy 105.987419 -253.693276) (xy 106.038298 -253.685282) (xy 106.06405 -253.684786)
			(xy 106.090025 -253.685185) (xy 106.141336 -253.693305) (xy 106.190746 -253.709352) (xy 106.237036 -253.732932)
			(xy 106.279067 -253.763464) (xy 106.315804 -253.800195) (xy 106.346342 -253.842222) (xy 106.369928 -253.888508)
			(xy 106.385983 -253.937915) (xy 106.394111 -253.989225) (xy 106.394111 -254.041175) (xy 106.385983 -254.092485)
			(xy 106.369928 -254.141892) (xy 106.350883 -254.179266) (xy 109.997224 -254.179266) (xy 110.003944 -254.127565)
			(xy 110.018401 -254.077473) (xy 110.040264 -254.030142) (xy 110.069031 -253.98666) (xy 110.10404 -253.948026)
			(xy 110.144486 -253.915128) (xy 110.189441 -253.888722) (xy 110.23787 -253.869415) (xy 110.288662 -253.85765)
			(xy 110.340648 -253.853699) (xy 110.392634 -253.85765) (xy 110.443426 -253.869415) (xy 110.491855 -253.888722)
			(xy 110.53681 -253.915128) (xy 110.577256 -253.948026) (xy 110.612265 -253.98666) (xy 110.641032 -254.030142)
			(xy 110.662895 -254.077473) (xy 110.677352 -254.127565) (xy 110.684072 -254.179266) (xy 110.682899 -254.231389)
			(xy 110.67386 -254.282736) (xy 110.657164 -254.332126) (xy 110.633194 -254.378426) (xy 110.6025 -254.420569)
			(xy 110.584488 -254.43942) (xy 110.577986 -254.446644) (xy 110.570503 -254.464564) (xy 110.570223 -254.483982)
			(xy 110.577185 -254.502112) (xy 110.583472 -254.509524) (xy 110.599846 -254.527969) (xy 110.62756 -254.568762)
			(xy 110.648893 -254.613227) (xy 110.663369 -254.660372) (xy 110.670666 -254.709147) (xy 110.671102 -254.733806)
			(xy 110.670593 -254.759773) (xy 110.662468 -254.811068) (xy 110.64642 -254.860461) (xy 110.622842 -254.906735)
			(xy 110.592316 -254.948751) (xy 110.555593 -254.985474) (xy 110.54251 -254.994979) (xy 113.286199 -254.994979)
			(xy 113.292614 -254.943541) (xy 113.306688 -254.893651) (xy 113.3281 -254.846442) (xy 113.356365 -254.802989)
			(xy 113.39084 -254.764277) (xy 113.430741 -254.731187) (xy 113.475163 -254.704469) (xy 113.523096 -254.684732)
			(xy 113.57345 -254.672424) (xy 113.625083 -254.667823) (xy 113.676821 -254.671036) (xy 113.727488 -254.681988)
			(xy 113.775933 -254.700431) (xy 113.821056 -254.725946) (xy 113.861832 -254.757953) (xy 113.897333 -254.795726)
			(xy 113.926754 -254.838405) (xy 113.949426 -254.885021) (xy 113.964834 -254.934515) (xy 113.972628 -254.985763)
			(xy 113.973102 -255.011682) (xy 113.972579 -255.038488) (xy 113.96425 -255.091448) (xy 113.947792 -255.14247)
			(xy 113.923605 -255.190315) (xy 113.892276 -255.23382) (xy 113.873788 -255.253236) (xy 113.867242 -255.260475)
			(xy 113.859634 -255.278427) (xy 113.859275 -255.297922) (xy 113.866218 -255.316141) (xy 113.872518 -255.323594)
			(xy 113.888973 -255.341981) (xy 113.916728 -255.382777) (xy 113.9381 -255.427251) (xy 113.952615 -255.47441)
			(xy 113.959949 -255.523205) (xy 113.960402 -255.547876) (xy 113.959893 -255.573843) (xy 113.951768 -255.625138)
			(xy 113.93572 -255.674531) (xy 113.912142 -255.720805) (xy 113.881616 -255.762821) (xy 113.844893 -255.799544)
			(xy 113.802877 -255.83007) (xy 113.756603 -255.853648) (xy 113.70721 -255.869696) (xy 113.655915 -255.877821)
			(xy 113.603981 -255.877821) (xy 113.552686 -255.869696) (xy 113.503293 -255.853648) (xy 113.457019 -255.83007)
			(xy 113.415003 -255.799544) (xy 113.37828 -255.762821) (xy 113.347754 -255.720805) (xy 113.324176 -255.674531)
			(xy 113.308128 -255.625138) (xy 113.300003 -255.573843) (xy 113.299494 -255.547876) (xy 113.299942 -255.523242)
			(xy 113.307266 -255.474521) (xy 113.321747 -255.427429) (xy 113.343064 -255.383011) (xy 113.370745 -255.342254)
			(xy 113.387124 -255.323848) (xy 113.393381 -255.316364) (xy 113.400317 -255.298155) (xy 113.399974 -255.278672)
			(xy 113.392402 -255.260717) (xy 113.385854 -255.25349) (xy 113.367938 -255.234754) (xy 113.337387 -255.192877)
			(xy 113.313476 -255.146884) (xy 113.29675 -255.097819) (xy 113.287588 -255.046798) (xy 113.286199 -254.994979)
			(xy 110.54251 -254.994979) (xy 110.513577 -255.016) (xy 110.467303 -255.039578) (xy 110.41791 -255.055626)
			(xy 110.366615 -255.063751) (xy 110.314681 -255.063751) (xy 110.263386 -255.055626) (xy 110.213993 -255.039578)
			(xy 110.167719 -255.016) (xy 110.125703 -254.985474) (xy 110.08898 -254.948751) (xy 110.058454 -254.906735)
			(xy 110.034876 -254.860461) (xy 110.018828 -254.811068) (xy 110.010703 -254.759773) (xy 110.010194 -254.733806)
			(xy 110.010672 -254.70915) (xy 110.01799 -254.660384) (xy 110.032463 -254.613244) (xy 110.053773 -254.568775)
			(xy 110.081446 -254.52796) (xy 110.097824 -254.509524) (xy 110.104083 -254.502098) (xy 110.111016 -254.483975)
			(xy 110.110736 -254.464572) (xy 110.103285 -254.446656) (xy 110.096808 -254.43942) (xy 110.078796 -254.420569)
			(xy 110.048102 -254.378426) (xy 110.024132 -254.332126) (xy 110.007436 -254.282736) (xy 109.998397 -254.231389)
			(xy 109.997224 -254.179266) (xy 106.350883 -254.179266) (xy 106.346342 -254.188178) (xy 106.315804 -254.230205)
			(xy 106.279067 -254.266936) (xy 106.237036 -254.297468) (xy 106.190746 -254.321048) (xy 106.141336 -254.337095)
			(xy 106.090025 -254.345215) (xy 106.06405 -254.345694) (xy 106.038295 -254.345242) (xy 105.987408 -254.337254)
			(xy 105.938377 -254.321464) (xy 105.892392 -254.298255) (xy 105.850567 -254.26819) (xy 105.831894 -254.250444)
			(xy 105.822204 -254.241451) (xy 105.799272 -254.228319) (xy 105.773733 -254.221524) (xy 105.747307 -254.221524)
			(xy 105.721768 -254.228319) (xy 105.698836 -254.241451) (xy 105.689146 -254.250444) (xy 105.670481 -254.268194)
			(xy 105.628645 -254.29824) (xy 105.582657 -254.321435) (xy 105.533627 -254.337216) (xy 105.482743 -254.345203)
			(xy 105.45699 -254.345694) (xy 105.431026 -254.345104) (xy 105.379739 -254.33698) (xy 105.330354 -254.320932)
			(xy 105.284087 -254.297357) (xy 105.242077 -254.266834) (xy 105.20536 -254.230115) (xy 105.174838 -254.188105)
			(xy 105.151264 -254.141837) (xy 105.135218 -254.092451) (xy 105.127095 -254.041164) (xy 103.77043 -254.041164)
			(xy 103.77043 -254.787146) (xy 103.785162 -254.802132) (xy 103.938578 -254.955548) (xy 103.953564 -254.97028)
			(xy 108.532168 -254.97028) (xy 108.542233 -254.970715) (xy 108.560822 -254.978444) (xy 108.568236 -254.985266)
			(xy 108.825284 -255.242314) (xy 108.83213 -255.249713) (xy 108.839862 -255.268311) (xy 108.84027 -255.278382)
			(xy 108.84027 -255.825498) (xy 109.99724 -255.825498) (xy 109.997632 -255.799577) (xy 110.005425 -255.748322)
			(xy 110.020832 -255.698822) (xy 110.043504 -255.652199) (xy 110.072927 -255.609514) (xy 110.10843 -255.571736)
			(xy 110.149209 -255.539723) (xy 110.194335 -255.514203) (xy 110.242785 -255.495756) (xy 110.293457 -255.4848)
			(xy 110.345201 -255.481585) (xy 110.396839 -255.486183) (xy 110.4472 -255.49849) (xy 110.495139 -255.518227)
			(xy 110.539567 -255.544945) (xy 110.579475 -255.578037) (xy 110.613955 -255.616751) (xy 110.642225 -255.660208)
			(xy 110.663642 -255.707421) (xy 110.67772 -255.757316) (xy 110.684139 -255.80876) (xy 110.682752 -255.860584)
			(xy 110.673592 -255.911612) (xy 110.656867 -255.960683) (xy 110.632956 -256.006682) (xy 110.602403 -256.048566)
			(xy 110.584488 -256.067306) (xy 110.577874 -256.07449) (xy 110.570276 -256.092467) (xy 110.569937 -256.11198)
			(xy 110.576905 -256.13021) (xy 110.583218 -256.137664) (xy 110.599588 -256.156077) (xy 110.62727 -256.196832)
			(xy 110.648588 -256.241248) (xy 110.663069 -256.288339) (xy 110.670391 -256.337059) (xy 110.670848 -256.361692)
			(xy 110.670339 -256.387659) (xy 110.662214 -256.438954) (xy 110.646166 -256.488347) (xy 110.622588 -256.534621)
			(xy 110.592062 -256.576637) (xy 110.555339 -256.61336) (xy 110.542633 -256.622591) (xy 113.286199 -256.622591)
			(xy 113.292613 -256.57115) (xy 113.306686 -256.521257) (xy 113.328098 -256.474047) (xy 113.356363 -256.430591)
			(xy 113.390839 -256.391877) (xy 113.430742 -256.358786) (xy 113.475166 -256.332068) (xy 113.523101 -256.312331)
			(xy 113.573458 -256.300023) (xy 113.625093 -256.295423) (xy 113.676833 -256.298638) (xy 113.727501 -256.309592)
			(xy 113.775948 -256.328038) (xy 113.821071 -256.353556) (xy 113.861847 -256.385567) (xy 113.897347 -256.423343)
			(xy 113.926767 -256.466026) (xy 113.949436 -256.512646) (xy 113.964841 -256.562144) (xy 113.97263 -256.613394)
			(xy 113.973102 -256.639314) (xy 113.972599 -256.66612) (xy 113.964265 -256.719082) (xy 113.947803 -256.770104)
			(xy 113.923611 -256.817949) (xy 113.892278 -256.861453) (xy 113.873788 -256.880868) (xy 113.867211 -256.888082)
			(xy 113.859608 -256.906045) (xy 113.859258 -256.925548) (xy 113.866212 -256.943773) (xy 113.872518 -256.951226)
			(xy 113.888941 -256.96964) (xy 113.9167 -257.010429) (xy 113.938079 -257.054896) (xy 113.952601 -257.102049)
			(xy 113.959944 -257.150839) (xy 113.960402 -257.175508) (xy 113.959893 -257.201475) (xy 113.951768 -257.25277)
			(xy 113.93572 -257.302163) (xy 113.912142 -257.348437) (xy 113.881616 -257.390453) (xy 113.844893 -257.427176)
			(xy 113.802877 -257.457702) (xy 113.756603 -257.48128) (xy 113.70721 -257.497328) (xy 113.655915 -257.505453)
			(xy 113.603981 -257.505453) (xy 113.552686 -257.497328) (xy 113.503293 -257.48128) (xy 113.457019 -257.457702)
			(xy 113.415003 -257.427176) (xy 113.37828 -257.390453) (xy 113.347754 -257.348437) (xy 113.324176 -257.302163)
			(xy 113.308128 -257.25277) (xy 113.300003 -257.201475) (xy 113.299494 -257.175508) (xy 113.299961 -257.150875)
			(xy 113.30728 -257.102154) (xy 113.321757 -257.055063) (xy 113.34307 -257.010644) (xy 113.370746 -256.969886)
			(xy 113.387124 -256.95148) (xy 113.393448 -256.944047) (xy 113.400373 -256.925814) (xy 113.400011 -256.906313)
			(xy 113.392415 -256.88835) (xy 113.385854 -256.881122) (xy 113.367952 -256.862371) (xy 113.337397 -256.820494)
			(xy 113.313483 -256.7745) (xy 113.296754 -256.725434) (xy 113.28759 -256.674411) (xy 113.286199 -256.622591)
			(xy 110.542633 -256.622591) (xy 110.513323 -256.643886) (xy 110.467049 -256.667464) (xy 110.417656 -256.683512)
			(xy 110.366361 -256.691637) (xy 110.314427 -256.691637) (xy 110.263132 -256.683512) (xy 110.213739 -256.667464)
			(xy 110.167465 -256.643886) (xy 110.125449 -256.61336) (xy 110.088726 -256.576637) (xy 110.0582 -256.534621)
			(xy 110.034622 -256.488347) (xy 110.018574 -256.438954) (xy 110.010449 -256.387659) (xy 110.00994 -256.361692)
			(xy 110.010394 -256.337023) (xy 110.017748 -256.288236) (xy 110.032275 -256.241085) (xy 110.053652 -256.196619)
			(xy 110.081405 -256.155827) (xy 110.097824 -256.13741) (xy 110.104118 -256.129954) (xy 110.111048 -256.111732)
			(xy 110.110695 -256.092239) (xy 110.103109 -256.07428) (xy 110.096554 -256.067052) (xy 110.078056 -256.047644)
			(xy 110.046729 -256.004137) (xy 110.022543 -255.95629) (xy 110.006085 -255.905266) (xy 109.997755 -255.852304)
			(xy 109.99724 -255.825498) (xy 108.84027 -255.825498) (xy 108.84027 -256.460498) (xy 108.839847 -256.470568)
			(xy 108.832129 -256.48917) (xy 108.825284 -256.496566) (xy 108.657136 -256.664714) (xy 108.649738 -256.67156)
			(xy 108.631139 -256.679284) (xy 108.621068 -256.6797) (xy 105.99293 -256.6797) (xy 105.977944 -256.694686)
			(xy 105.885742 -256.786888) (xy 105.870756 -256.801874) (xy 105.870756 -257.294888) (xy 105.960164 -257.367278)
			(xy 105.982516 -257.372358) (xy 105.993946 -257.370072) (xy 105.994454 -257.370072) (xy 106.011639 -257.366552)
			(xy 106.046511 -257.362735) (xy 106.06405 -257.362452) (xy 106.090045 -257.362932) (xy 106.141396 -257.371058)
			(xy 106.190843 -257.387117) (xy 106.237169 -257.410715) (xy 106.270303 -257.434784) (xy 109.997224 -257.434784)
			(xy 110.003944 -257.383083) (xy 110.018401 -257.332991) (xy 110.040264 -257.28566) (xy 110.069031 -257.242178)
			(xy 110.10404 -257.203544) (xy 110.144486 -257.170646) (xy 110.189441 -257.14424) (xy 110.23787 -257.124933)
			(xy 110.288662 -257.113168) (xy 110.340648 -257.109217) (xy 110.392634 -257.113168) (xy 110.443426 -257.124933)
			(xy 110.491855 -257.14424) (xy 110.53681 -257.170646) (xy 110.577256 -257.203544) (xy 110.612265 -257.242178)
			(xy 110.641032 -257.28566) (xy 110.662895 -257.332991) (xy 110.677352 -257.383083) (xy 110.684072 -257.434784)
			(xy 110.682899 -257.486907) (xy 110.67386 -257.538254) (xy 110.657164 -257.587644) (xy 110.633194 -257.633944)
			(xy 110.6025 -257.676087) (xy 110.584488 -257.694938) (xy 110.577968 -257.702148) (xy 110.570489 -257.720075)
			(xy 110.570213 -257.739498) (xy 110.577182 -257.757629) (xy 110.583472 -257.765042) (xy 110.599854 -257.783479)
			(xy 110.627568 -257.824275) (xy 110.648899 -257.868742) (xy 110.663373 -257.915888) (xy 110.670667 -257.964664)
			(xy 110.671102 -257.989324) (xy 110.670593 -258.015291) (xy 110.662468 -258.066586) (xy 110.64642 -258.115979)
			(xy 110.622842 -258.162253) (xy 110.592316 -258.204269) (xy 110.555593 -258.240992) (xy 110.542525 -258.250486)
			(xy 113.286199 -258.250486) (xy 113.292613 -258.199046) (xy 113.306687 -258.149154) (xy 113.328099 -258.101945)
			(xy 113.356364 -258.05849) (xy 113.390839 -258.019777) (xy 113.430742 -257.986686) (xy 113.475165 -257.959968)
			(xy 113.523099 -257.940231) (xy 113.573455 -257.927923) (xy 113.625089 -257.923323) (xy 113.676827 -257.926537)
			(xy 113.727495 -257.93749) (xy 113.775941 -257.955935) (xy 113.821065 -257.981452) (xy 113.86184 -258.013461)
			(xy 113.897341 -258.051236) (xy 113.926761 -258.093917) (xy 113.949432 -258.140535) (xy 113.964838 -258.190031)
			(xy 113.972629 -258.241281) (xy 113.973102 -258.2672) (xy 113.97259 -258.294006) (xy 113.964259 -258.346967)
			(xy 113.947798 -258.397989) (xy 113.923608 -258.445834) (xy 113.892277 -258.489338) (xy 113.873788 -258.508754)
			(xy 113.867224 -258.515979) (xy 113.859619 -258.533937) (xy 113.859265 -258.553437) (xy 113.866215 -258.571659)
			(xy 113.872518 -258.579112) (xy 113.888934 -258.597532) (xy 113.916694 -258.63832) (xy 113.938074 -258.682785)
			(xy 113.952599 -258.729936) (xy 113.959943 -258.778725) (xy 113.960402 -258.803394) (xy 113.959893 -258.829361)
			(xy 113.951768 -258.880656) (xy 113.93572 -258.930049) (xy 113.912142 -258.976323) (xy 113.881616 -259.018339)
			(xy 113.844893 -259.055062) (xy 113.802877 -259.085588) (xy 113.756603 -259.109166) (xy 113.70721 -259.125214)
			(xy 113.655915 -259.133339) (xy 113.603981 -259.133339) (xy 113.552686 -259.125214) (xy 113.503293 -259.109166)
			(xy 113.457019 -259.085588) (xy 113.415003 -259.055062) (xy 113.37828 -259.018339) (xy 113.347754 -258.976323)
			(xy 113.324176 -258.930049) (xy 113.308128 -258.880656) (xy 113.300003 -258.829361) (xy 113.299494 -258.803394)
			(xy 113.299953 -258.77876) (xy 113.307274 -258.73004) (xy 113.321753 -258.682948) (xy 113.343068 -258.63853)
			(xy 113.370746 -258.597772) (xy 113.387124 -258.579366) (xy 113.393462 -258.571943) (xy 113.400384 -258.553705)
			(xy 113.400019 -258.534201) (xy 113.392418 -258.516236) (xy 113.385854 -258.509008) (xy 113.367946 -258.490264)
			(xy 113.337392 -258.448387) (xy 113.31348 -258.402393) (xy 113.296752 -258.353328) (xy 113.287589 -258.302306)
			(xy 113.286199 -258.250486) (xy 110.542525 -258.250486) (xy 110.513577 -258.271518) (xy 110.467303 -258.295096)
			(xy 110.41791 -258.311144) (xy 110.366615 -258.319269) (xy 110.314681 -258.319269) (xy 110.263386 -258.311144)
			(xy 110.213993 -258.295096) (xy 110.167719 -258.271518) (xy 110.125703 -258.240992) (xy 110.08898 -258.204269)
			(xy 110.058454 -258.162253) (xy 110.034876 -258.115979) (xy 110.018828 -258.066586) (xy 110.010703 -258.015291)
			(xy 110.010194 -257.989324) (xy 110.010623 -257.964666) (xy 110.017952 -257.915898) (xy 110.032438 -257.868758)
			(xy 110.053758 -257.824289) (xy 110.081441 -257.783476) (xy 110.097824 -257.765042) (xy 110.104065 -257.757603)
			(xy 110.111001 -257.739485) (xy 110.110727 -257.720088) (xy 110.103282 -257.702174) (xy 110.096808 -257.694938)
			(xy 110.078796 -257.676087) (xy 110.048102 -257.633944) (xy 110.024132 -257.587644) (xy 110.007436 -257.538254)
			(xy 109.998397 -257.486907) (xy 109.997224 -257.434784) (xy 106.270303 -257.434784) (xy 106.279232 -257.44127)
			(xy 106.315997 -257.47803) (xy 106.346559 -257.520089) (xy 106.370164 -257.566411) (xy 106.386231 -257.615856)
			(xy 106.394365 -257.667205) (xy 106.394365 -257.719195) (xy 106.386231 -257.770544) (xy 106.370164 -257.819989)
			(xy 106.346559 -257.866311) (xy 106.315997 -257.90837) (xy 106.279232 -257.94513) (xy 106.237169 -257.975685)
			(xy 106.190843 -257.999283) (xy 106.141396 -258.015342) (xy 106.090045 -258.023468) (xy 106.06405 -258.023868)
			(xy 106.046511 -258.023583) (xy 106.01164 -258.019763) (xy 105.994454 -258.016248) (xy 105.993946 -258.016248)
			(xy 105.982516 -258.013962) (xy 105.960164 -258.019042) (xy 105.870756 -258.091432) (xy 105.870756 -258.459224)
			(xy 105.872534 -258.461256) (xy 105.872534 -258.52755) (xy 105.887266 -258.542536) (xy 105.945178 -258.600448)
			(xy 105.960164 -258.61518) (xy 108.628688 -258.61518) (xy 108.63876 -258.6156) (xy 108.657369 -258.623309)
			(xy 108.664756 -258.630166) (xy 108.822744 -258.788154) (xy 108.829588 -258.795553) (xy 108.837312 -258.814152)
			(xy 108.83773 -258.824222) (xy 108.83773 -259.081016) (xy 109.99724 -259.081016) (xy 109.997618 -259.055093)
			(xy 110.005409 -259.003835) (xy 110.020815 -258.954331) (xy 110.043486 -258.907705) (xy 110.072909 -258.865016)
			(xy 110.108413 -258.827234) (xy 110.149193 -258.795219) (xy 110.194322 -258.769696) (xy 110.242774 -258.751246)
			(xy 110.293449 -258.740288) (xy 110.345195 -258.737072) (xy 110.396837 -258.74167) (xy 110.447201 -258.753977)
			(xy 110.495143 -258.773715) (xy 110.539574 -258.800434) (xy 110.579484 -258.833528) (xy 110.613966 -258.872245)
			(xy 110.642237 -258.915705) (xy 110.663655 -258.96292) (xy 110.677733 -259.012818) (xy 110.684152 -259.064266)
			(xy 110.682764 -259.116093) (xy 110.673602 -259.167123) (xy 110.656875 -259.216197) (xy 110.632961 -259.262198)
			(xy 110.602405 -259.304083) (xy 110.584488 -259.322824) (xy 110.577953 -259.330073) (xy 110.570343 -259.34802)
			(xy 110.569982 -259.367512) (xy 110.576921 -259.385729) (xy 110.583218 -259.393182) (xy 110.599597 -259.411588)
			(xy 110.627277 -259.452345) (xy 110.648594 -259.496763) (xy 110.663073 -259.543855) (xy 110.670393 -259.592576)
			(xy 110.670848 -259.61721) (xy 110.670339 -259.643177) (xy 110.662214 -259.694472) (xy 110.646166 -259.743865)
			(xy 110.622588 -259.790139) (xy 110.592062 -259.832155) (xy 110.555339 -259.868878) (xy 110.54265 -259.878097)
			(xy 113.286198 -259.878097) (xy 113.292612 -259.826655) (xy 113.306684 -259.776761) (xy 113.328097 -259.729549)
			(xy 113.356362 -259.686092) (xy 113.390839 -259.647378) (xy 113.430743 -259.614285) (xy 113.475168 -259.587567)
			(xy 113.523104 -259.56783) (xy 113.573462 -259.555522) (xy 113.625099 -259.550923) (xy 113.676839 -259.554139)
			(xy 113.727509 -259.565094) (xy 113.775956 -259.583542) (xy 113.82108 -259.609062) (xy 113.861855 -259.641075)
			(xy 113.897355 -259.678853) (xy 113.926774 -259.721538) (xy 113.949442 -259.76816) (xy 113.964844 -259.817659)
			(xy 113.972632 -259.868912) (xy 113.973102 -259.894832) (xy 113.97261 -259.921639) (xy 113.964274 -259.9746)
			(xy 113.947809 -260.025623) (xy 113.923614 -260.073468) (xy 113.892279 -260.116971) (xy 113.873788 -260.136386)
			(xy 113.867193 -260.143586) (xy 113.859592 -260.161556) (xy 113.859248 -260.181064) (xy 113.866209 -260.199291)
			(xy 113.872518 -260.206744) (xy 113.888949 -260.225151) (xy 113.916707 -260.265942) (xy 113.938085 -260.31041)
			(xy 113.952605 -260.357565) (xy 113.959945 -260.406356) (xy 113.960402 -260.431026) (xy 113.959893 -260.456993)
			(xy 113.951768 -260.508288) (xy 113.93572 -260.557681) (xy 113.912142 -260.603955) (xy 113.881616 -260.645971)
			(xy 113.844893 -260.682694) (xy 113.802877 -260.71322) (xy 113.756603 -260.736798) (xy 113.70721 -260.752846)
			(xy 113.655915 -260.760971) (xy 113.603981 -260.760971) (xy 113.552686 -260.752846) (xy 113.503293 -260.736798)
			(xy 113.457019 -260.71322) (xy 113.415003 -260.682694) (xy 113.37828 -260.645971) (xy 113.347754 -260.603955)
			(xy 113.324176 -260.557681) (xy 113.308128 -260.508288) (xy 113.300003 -260.456993) (xy 113.299494 -260.431026)
			(xy 113.299972 -260.406393) (xy 113.307288 -260.357673) (xy 113.321763 -260.310582) (xy 113.343073 -260.266163)
			(xy 113.370747 -260.225404) (xy 113.387124 -260.206998) (xy 113.39343 -260.199551) (xy 113.400358 -260.181325)
			(xy 113.400002 -260.161829) (xy 113.392412 -260.143867) (xy 113.385854 -260.13664) (xy 113.36796 -260.11788)
			(xy 113.337403 -260.076003) (xy 113.313487 -260.030009) (xy 113.296756 -259.980943) (xy 113.28759 -259.929919)
			(xy 113.286198 -259.878097) (xy 110.54265 -259.878097) (xy 110.513323 -259.899404) (xy 110.467049 -259.922982)
			(xy 110.417656 -259.93903) (xy 110.366361 -259.947155) (xy 110.314427 -259.947155) (xy 110.263132 -259.93903)
			(xy 110.213739 -259.922982) (xy 110.167465 -259.899404) (xy 110.125449 -259.868878) (xy 110.088726 -259.832155)
			(xy 110.0582 -259.790139) (xy 110.034622 -259.743865) (xy 110.018574 -259.694472) (xy 110.010449 -259.643177)
			(xy 110.00994 -259.61721) (xy 110.010405 -259.592542) (xy 110.017756 -259.543755) (xy 110.03228 -259.496604)
			(xy 110.053655 -259.452138) (xy 110.081406 -259.411345) (xy 110.097824 -259.392928) (xy 110.1041 -259.385459)
			(xy 110.111033 -259.367243) (xy 110.110685 -259.347755) (xy 110.103106 -259.329797) (xy 110.096554 -259.32257)
			(xy 110.078065 -259.303154) (xy 110.046737 -259.259649) (xy 110.022549 -259.211804) (xy 110.006089 -259.160782)
			(xy 109.997756 -259.107822) (xy 109.99724 -259.081016) (xy 108.83773 -259.081016) (xy 108.83773 -260.097778)
			(xy 108.837225 -260.107829) (xy 108.829504 -260.12639) (xy 108.822744 -260.133846) (xy 108.598716 -260.357874)
			(xy 108.591314 -260.36471) (xy 108.572716 -260.372418) (xy 108.562648 -260.37286) (xy 108.10875 -260.37286)
			(xy 108.093764 -260.387846) (xy 107.912408 -260.569202) (xy 107.897422 -260.584188) (xy 107.897422 -260.708902)
			(xy 109.99724 -260.708902) (xy 109.997629 -260.68298) (xy 110.005421 -260.631725) (xy 110.020828 -260.582224)
			(xy 110.0435 -260.535601) (xy 110.072923 -260.492915) (xy 110.108426 -260.455136) (xy 110.149205 -260.423122)
			(xy 110.194332 -260.397602) (xy 110.242783 -260.379154) (xy 110.293455 -260.368197) (xy 110.345199 -260.364982)
			(xy 110.396839 -260.36958) (xy 110.4472 -260.381887) (xy 110.49514 -260.401624) (xy 110.539569 -260.428343)
			(xy 110.579477 -260.461435) (xy 110.613958 -260.50015) (xy 110.642228 -260.543608) (xy 110.663645 -260.590821)
			(xy 110.677723 -260.640716) (xy 110.684141 -260.692161) (xy 110.682755 -260.743986) (xy 110.673594 -260.795014)
			(xy 110.656868 -260.844086) (xy 110.632957 -260.890086) (xy 110.602403 -260.931969) (xy 110.584488 -260.95071)
			(xy 110.577967 -260.95797) (xy 110.570355 -260.975913) (xy 110.569989 -260.9954) (xy 110.576923 -261.013615)
			(xy 110.583218 -261.021068) (xy 110.59959 -261.03948) (xy 110.627271 -261.080235) (xy 110.648589 -261.124651)
			(xy 110.66307 -261.171742) (xy 110.670392 -261.220462) (xy 110.670848 -261.245096) (xy 110.670339 -261.271063)
			(xy 110.662214 -261.322358) (xy 110.646166 -261.371751) (xy 110.622588 -261.418025) (xy 110.592062 -261.460041)
			(xy 110.555339 -261.496764) (xy 110.542638 -261.505992) (xy 113.286199 -261.505992) (xy 113.292612 -261.454551)
			(xy 113.306685 -261.404658) (xy 113.328098 -261.357447) (xy 113.356363 -261.313991) (xy 113.390839 -261.275278)
			(xy 113.430743 -261.242186) (xy 113.475166 -261.215468) (xy 113.523102 -261.19573) (xy 113.573459 -261.183422)
			(xy 113.625094 -261.178823) (xy 113.676834 -261.182038) (xy 113.727503 -261.192993) (xy 113.77595 -261.211439)
			(xy 113.821073 -261.236958) (xy 113.861849 -261.268969) (xy 113.897349 -261.306745) (xy 113.926768 -261.349429)
			(xy 113.949437 -261.396049) (xy 113.964841 -261.445547) (xy 113.972631 -261.496798) (xy 113.973102 -261.522718)
			(xy 113.972601 -261.549524) (xy 113.964267 -261.602486) (xy 113.947804 -261.653508) (xy 113.923612 -261.701353)
			(xy 113.892278 -261.744857) (xy 113.873788 -261.764272) (xy 113.867207 -261.771483) (xy 113.859604 -261.789448)
			(xy 113.859255 -261.808952) (xy 113.866211 -261.827177) (xy 113.872518 -261.83463) (xy 113.888943 -261.853043)
			(xy 113.916702 -261.893832) (xy 113.93808 -261.938299) (xy 113.952602 -261.985453) (xy 113.959944 -262.034242)
			(xy 113.960402 -262.058912) (xy 113.959893 -262.084879) (xy 113.951768 -262.136174) (xy 113.93572 -262.185567)
			(xy 113.912142 -262.231841) (xy 113.881616 -262.273857) (xy 113.844893 -262.31058) (xy 113.802877 -262.341106)
			(xy 113.756603 -262.364684) (xy 113.70721 -262.380732) (xy 113.655915 -262.388857) (xy 113.603981 -262.388857)
			(xy 113.552686 -262.380732) (xy 113.503293 -262.364684) (xy 113.457019 -262.341106) (xy 113.415003 -262.31058)
			(xy 113.37828 -262.273857) (xy 113.347754 -262.231841) (xy 113.324176 -262.185567) (xy 113.308128 -262.136174)
			(xy 113.300003 -262.084879) (xy 113.299494 -262.058912) (xy 113.299964 -262.034279) (xy 113.307282 -261.985559)
			(xy 113.321758 -261.938467) (xy 113.343071 -261.894049) (xy 113.370747 -261.85329) (xy 113.387124 -261.834884)
			(xy 113.393444 -261.827448) (xy 113.40037 -261.809216) (xy 113.400009 -261.789717) (xy 113.392414 -261.771754)
			(xy 113.385854 -261.764526) (xy 113.367954 -261.745773) (xy 113.337398 -261.703896) (xy 113.313484 -261.657902)
			(xy 113.296754 -261.608836) (xy 113.28759 -261.557813) (xy 113.286199 -261.505992) (xy 110.542638 -261.505992)
			(xy 110.513323 -261.52729) (xy 110.467049 -261.550868) (xy 110.417656 -261.566916) (xy 110.366361 -261.575041)
			(xy 110.314427 -261.575041) (xy 110.263132 -261.566916) (xy 110.213739 -261.550868) (xy 110.167465 -261.52729)
			(xy 110.125449 -261.496764) (xy 110.088726 -261.460041) (xy 110.0582 -261.418025) (xy 110.034622 -261.371751)
			(xy 110.018574 -261.322358) (xy 110.010449 -261.271063) (xy 110.00994 -261.245096) (xy 110.010397 -261.220427)
			(xy 110.01775 -261.17164) (xy 110.032276 -261.12449) (xy 110.053653 -261.080023) (xy 110.081405 -261.039231)
			(xy 110.097824 -261.020814) (xy 110.104114 -261.013355) (xy 110.111045 -260.995134) (xy 110.110692 -260.975643)
			(xy 110.103108 -260.957684) (xy 110.096554 -260.950456) (xy 110.078058 -260.931047) (xy 110.046731 -260.887539)
			(xy 110.022544 -260.839693) (xy 110.006086 -260.788669) (xy 109.997755 -260.735708) (xy 109.99724 -260.708902)
			(xy 107.897422 -260.708902) (xy 107.897422 -261.476236) (xy 107.896993 -261.486304) (xy 107.889272 -261.504901)
			(xy 107.882436 -261.512304) (xy 107.186222 -262.208518) (xy 107.184698 -262.2296) (xy 107.184698 -262.318188)
			(xy 109.997224 -262.318188) (xy 110.003944 -262.266487) (xy 110.018401 -262.216395) (xy 110.040264 -262.169064)
			(xy 110.069031 -262.125582) (xy 110.10404 -262.086948) (xy 110.144486 -262.05405) (xy 110.189441 -262.027644)
			(xy 110.23787 -262.008337) (xy 110.288662 -261.996572) (xy 110.340648 -261.992621) (xy 110.392634 -261.996572)
			(xy 110.443426 -262.008337) (xy 110.491855 -262.027644) (xy 110.53681 -262.05405) (xy 110.577256 -262.086948)
			(xy 110.612265 -262.125582) (xy 110.641032 -262.169064) (xy 110.662895 -262.216395) (xy 110.677352 -262.266487)
			(xy 110.684072 -262.318188) (xy 110.682899 -262.370311) (xy 110.67386 -262.421658) (xy 110.657164 -262.471048)
			(xy 110.633194 -262.517348) (xy 110.6025 -262.559491) (xy 110.584488 -262.578342) (xy 110.577964 -262.585549)
			(xy 110.570486 -262.603477) (xy 110.570211 -262.622901) (xy 110.577181 -262.641033) (xy 110.583472 -262.648446)
			(xy 110.599856 -262.666882) (xy 110.627569 -262.707678) (xy 110.6489 -262.752145) (xy 110.663374 -262.799292)
			(xy 110.670667 -262.848068) (xy 110.671102 -262.872728) (xy 110.670593 -262.898695) (xy 110.662468 -262.94999)
			(xy 110.64642 -262.999383) (xy 110.622842 -263.045657) (xy 110.592316 -263.087673) (xy 110.555593 -263.124396)
			(xy 110.51952 -263.150604) (xy 113.286286 -263.150604) (xy 113.286766 -263.124684) (xy 113.294557 -263.073433)
			(xy 113.309963 -263.023936) (xy 113.332634 -262.977316) (xy 113.362055 -262.934634) (xy 113.397556 -262.896858)
			(xy 113.438333 -262.864848) (xy 113.483457 -262.839331) (xy 113.531904 -262.820886) (xy 113.582574 -262.809932)
			(xy 113.634314 -262.806719) (xy 113.685949 -262.811319) (xy 113.736306 -262.823628) (xy 113.784241 -262.843366)
			(xy 113.828665 -262.870085) (xy 113.868567 -262.903178) (xy 113.903043 -262.941892) (xy 113.931308 -262.985348)
			(xy 113.95272 -263.032559) (xy 113.966793 -263.082452) (xy 113.973206 -263.133894) (xy 113.971815 -263.185715)
			(xy 113.96265 -263.236738) (xy 113.945921 -263.285804) (xy 113.922006 -263.331798) (xy 113.89145 -263.373675)
			(xy 113.873534 -263.392412) (xy 113.866996 -263.399599) (xy 113.859479 -263.417502) (xy 113.859137 -263.436916)
			(xy 113.866017 -263.455072) (xy 113.872264 -263.462516) (xy 113.888666 -263.480902) (xy 113.916342 -263.521665)
			(xy 113.937653 -263.566088) (xy 113.952127 -263.613184) (xy 113.959441 -263.661909) (xy 113.959894 -263.686544)
			(xy 113.959385 -263.712511) (xy 113.95126 -263.763806) (xy 113.935212 -263.813199) (xy 113.911634 -263.859473)
			(xy 113.881108 -263.901489) (xy 113.844385 -263.938212) (xy 113.802369 -263.968738) (xy 113.756095 -263.992316)
			(xy 113.706702 -264.008364) (xy 113.655407 -264.016489) (xy 113.603473 -264.016489) (xy 113.552178 -264.008364)
			(xy 113.502785 -263.992316) (xy 113.456511 -263.968738) (xy 113.414495 -263.938212) (xy 113.377772 -263.901489)
			(xy 113.347246 -263.859473) (xy 113.323668 -263.813199) (xy 113.30762 -263.763806) (xy 113.299495 -263.712511)
			(xy 113.298986 -263.686544) (xy 113.299429 -263.661887) (xy 113.306755 -263.61312) (xy 113.321237 -263.565979)
			(xy 113.342555 -263.52151) (xy 113.370235 -263.480697) (xy 113.386616 -263.462262) (xy 113.392838 -263.454808)
			(xy 113.399779 -263.436698) (xy 113.39951 -263.417305) (xy 113.392071 -263.399393) (xy 113.3856 -263.392158)
			(xy 113.367113 -263.37274) (xy 113.335783 -263.329236) (xy 113.311594 -263.281392) (xy 113.295133 -263.23037)
			(xy 113.286801 -263.17741) (xy 113.286286 -263.150604) (xy 110.51952 -263.150604) (xy 110.513577 -263.154922)
			(xy 110.467303 -263.1785) (xy 110.41791 -263.194548) (xy 110.366615 -263.202673) (xy 110.314681 -263.202673)
			(xy 110.263386 -263.194548) (xy 110.213993 -263.1785) (xy 110.167719 -263.154922) (xy 110.125703 -263.124396)
			(xy 110.08898 -263.087673) (xy 110.058454 -263.045657) (xy 110.034876 -262.999383) (xy 110.018828 -262.94999)
			(xy 110.010703 -262.898695) (xy 110.010194 -262.872728) (xy 110.010625 -262.84807) (xy 110.017954 -262.799302)
			(xy 110.032439 -262.752162) (xy 110.053759 -262.707693) (xy 110.081442 -262.666881) (xy 110.097824 -262.648446)
			(xy 110.104061 -262.641004) (xy 110.110998 -262.622888) (xy 110.110725 -262.603491) (xy 110.103281 -262.585578)
			(xy 110.096808 -262.578342) (xy 110.078796 -262.559491) (xy 110.048102 -262.517348) (xy 110.024132 -262.471048)
			(xy 110.007436 -262.421658) (xy 109.998397 -262.370311) (xy 109.997224 -262.318188) (xy 107.184698 -262.318188)
			(xy 107.184698 -263.303258) (xy 107.19943 -263.318244) (xy 107.437936 -263.55675) (xy 107.452922 -263.571482)
			(xy 108.204762 -263.571482) (xy 108.214828 -263.571916) (xy 108.233417 -263.579644) (xy 108.24083 -263.586468)
			(xy 108.309156 -263.654794) (xy 108.33989 -263.64311) (xy 108.368572 -263.632996) (xy 108.428361 -263.621888)
			(xy 108.458762 -263.621012) (xy 108.463842 -263.621012) (xy 108.490541 -263.62174) (xy 108.543235 -263.630445)
			(xy 108.593946 -263.647203) (xy 108.641451 -263.671611) (xy 108.684605 -263.703078) (xy 108.722367 -263.740847)
			(xy 108.753826 -263.784007) (xy 108.778223 -263.831517) (xy 108.794971 -263.882232) (xy 108.803666 -263.934927)
			(xy 108.804456 -263.961626) (xy 108.804456 -263.964674) (xy 108.803781 -263.995592) (xy 108.79267 -264.056423)
			(xy 108.782358 -264.085578) (xy 108.770674 -264.116312) (xy 108.957618 -264.303256) (xy 108.972604 -264.317988)
			(xy 109.008926 -264.317988) (xy 109.018994 -264.318415) (xy 109.037593 -264.326135) (xy 109.044994 -264.332974)
			(xy 109.321092 -264.609072) (xy 109.327928 -264.616474) (xy 109.335637 -264.635072) (xy 109.336078 -264.64514)
			(xy 109.336078 -265.073892) (xy 109.35081 -265.088878) (xy 109.540548 -265.278616) (xy 109.548422 -265.282426)
			(xy 109.574549 -265.295541) (xy 109.622285 -265.32928) (xy 109.66362 -265.370615) (xy 109.697359 -265.418351)
			(xy 109.710474 -265.444478) (xy 109.714284 -265.452352) (xy 110.0963 -265.834368) (xy 110.103136 -265.84177)
			(xy 110.110846 -265.860368) (xy 110.111286 -265.870436) (xy 110.111286 -266.140692) (xy 110.124494 -266.174474)
			(xy 110.130082 -266.181078) (xy 110.145799 -266.199899) (xy 110.172296 -266.241158) (xy 110.192656 -266.285766)
			(xy 110.206465 -266.332816) (xy 110.213443 -266.381351) (xy 110.213902 -266.405868) (xy 110.213727 -266.420098)
			(xy 110.211312 -266.448456) (xy 110.209076 -266.46251) (xy 110.205012 -266.488418) (xy 110.546134 -266.82954)
			(xy 110.552981 -266.836937) (xy 110.560712 -266.855536) (xy 110.56112 -266.865608) (xy 110.56112 -266.95654)
			(xy 110.580011 -266.972955) (xy 110.613307 -267.010318) (xy 110.640832 -267.052115) (xy 110.662004 -267.097462)
			(xy 110.676375 -267.1454) (xy 110.683642 -267.194915) (xy 110.684056 -267.219938) (xy 110.683624 -267.244091)
			(xy 110.676818 -267.291916) (xy 110.663387 -267.338319) (xy 110.643595 -267.382385) (xy 110.617833 -267.423249)
			(xy 110.602522 -267.441934) (xy 110.597188 -267.448538) (xy 110.584488 -267.48105) (xy 110.583726 -267.512038)
			(xy 110.58396 -267.521072) (xy 110.58995 -267.53811) (xy 110.59541 -267.545312) (xy 110.613127 -267.567711)
			(xy 110.641389 -267.617332) (xy 110.660711 -267.671069) (xy 110.67052 -267.727325) (xy 110.671102 -267.755878)
			(xy 110.671102 -267.756132) (xy 110.670657 -267.781005) (xy 110.66321 -267.830189) (xy 110.648473 -267.877702)
			(xy 110.62678 -267.922468) (xy 110.598621 -267.963476) (xy 110.581948 -267.981938) (xy 110.575598 -267.988542)
			(xy 110.56112 -268.023848) (xy 110.56112 -268.584172) (xy 110.58001 -268.600588) (xy 110.613302 -268.637952)
			(xy 110.640823 -268.679749) (xy 110.661991 -268.725096) (xy 110.676358 -268.773034) (xy 110.68362 -268.822548)
			(xy 110.684056 -268.84757) (xy 110.683622 -268.871722) (xy 110.676811 -268.919545) (xy 110.663377 -268.965945)
			(xy 110.643583 -269.010009) (xy 110.617818 -269.050869) (xy 110.602522 -269.069566) (xy 110.597188 -269.07617)
			(xy 110.584488 -269.108682) (xy 110.583726 -269.13967) (xy 110.583948 -269.148708) (xy 110.589921 -269.165761)
			(xy 110.59541 -269.172944) (xy 110.613125 -269.195343) (xy 110.641382 -269.244966) (xy 110.660699 -269.298703)
			(xy 110.670502 -269.354958) (xy 110.671102 -269.38351) (xy 110.671102 -269.383764) (xy 110.670655 -269.408636)
			(xy 110.663203 -269.457818) (xy 110.648463 -269.505328) (xy 110.626767 -269.55009) (xy 110.598606 -269.591095)
			(xy 110.581948 -269.60957) (xy 110.575598 -269.616174) (xy 110.56112 -269.65148) (xy 110.56112 -270.212058)
			(xy 110.58001 -270.228474) (xy 110.613304 -270.265837) (xy 110.640827 -270.307634) (xy 110.661996 -270.352981)
			(xy 110.676365 -270.400919) (xy 110.68363 -270.450434) (xy 110.684056 -270.475456) (xy 110.683623 -270.499609)
			(xy 110.676814 -270.547433) (xy 110.663381 -270.593833) (xy 110.643588 -270.637898) (xy 110.617824 -270.67876)
			(xy 110.602522 -270.697452) (xy 110.597188 -270.704056) (xy 110.584488 -270.736568) (xy 110.583726 -270.767556)
			(xy 110.583963 -270.776589) (xy 110.589957 -270.793623) (xy 110.59541 -270.80083) (xy 110.613126 -270.823229)
			(xy 110.641385 -270.872851) (xy 110.660704 -270.926588) (xy 110.67051 -270.982844) (xy 110.671102 -271.011396)
			(xy 110.671102 -271.01165) (xy 110.670656 -271.036522) (xy 110.663206 -271.085706) (xy 110.648467 -271.133216)
			(xy 110.626773 -271.177981) (xy 110.598613 -271.218987) (xy 110.581948 -271.237456) (xy 110.575598 -271.24406)
			(xy 110.56112 -271.279366) (xy 110.56112 -271.839944) (xy 110.580011 -271.85636) (xy 110.613306 -271.893723)
			(xy 110.640831 -271.935519) (xy 110.662002 -271.980866) (xy 110.676373 -272.028804) (xy 110.68364 -272.078319)
			(xy 110.684056 -272.103342) (xy 110.683623 -272.127495) (xy 110.676817 -272.17532) (xy 110.663385 -272.221722)
			(xy 110.643594 -272.265788) (xy 110.617831 -272.306652) (xy 110.602522 -272.325338) (xy 110.597188 -272.331942)
			(xy 110.584488 -272.364454) (xy 110.583726 -272.395442) (xy 110.58396 -272.404476) (xy 110.589952 -272.421513)
			(xy 110.59541 -272.428716) (xy 110.613127 -272.451115) (xy 110.641388 -272.500736) (xy 110.66071 -272.554473)
			(xy 110.670517 -272.61073) (xy 110.671102 -272.639282) (xy 110.671102 -272.639536) (xy 110.670657 -272.664409)
			(xy 110.663209 -272.713593) (xy 110.648472 -272.761105) (xy 110.626779 -272.805871) (xy 110.59862 -272.846879)
			(xy 110.581948 -272.865342) (xy 110.575598 -272.871946) (xy 110.56112 -272.907252) (xy 110.56112 -273.467576)
			(xy 110.580009 -273.483992) (xy 110.613301 -273.521356) (xy 110.640822 -273.563153) (xy 110.661989 -273.6085)
			(xy 110.676355 -273.656438) (xy 110.683617 -273.705952) (xy 110.684056 -273.730974) (xy 110.683621 -273.755126)
			(xy 110.676811 -273.802949) (xy 110.663376 -273.849348) (xy 110.643581 -273.893412) (xy 110.617816 -273.934272)
			(xy 110.602522 -273.95297) (xy 110.597188 -273.959574) (xy 110.584488 -273.992086) (xy 110.583726 -274.023074)
			(xy 110.583949 -274.032112) (xy 110.589923 -274.049164) (xy 110.59541 -274.056348) (xy 110.613125 -274.078747)
			(xy 110.641381 -274.12837) (xy 110.660697 -274.182107) (xy 110.6705 -274.238362) (xy 110.671102 -274.266914)
			(xy 110.671102 -274.267168) (xy 110.670654 -274.29204) (xy 110.663202 -274.341222) (xy 110.648462 -274.388731)
			(xy 110.626765 -274.433493) (xy 110.598604 -274.474497) (xy 110.581948 -274.492974) (xy 110.575598 -274.499578)
			(xy 110.56112 -274.534884) (xy 110.56112 -275.095462) (xy 110.58001 -275.111878) (xy 110.613303 -275.149241)
			(xy 110.640826 -275.191039) (xy 110.661995 -275.236385) (xy 110.676363 -275.284323) (xy 110.683627 -275.333838)
			(xy 110.684056 -275.35886) (xy 110.683622 -275.383013) (xy 110.676813 -275.430836) (xy 110.66338 -275.477237)
			(xy 110.643587 -275.521301) (xy 110.617823 -275.562163) (xy 110.602522 -275.580856) (xy 110.597188 -275.58746)
			(xy 110.584488 -275.619972) (xy 110.583726 -275.65096) (xy 110.583963 -275.659993) (xy 110.589959 -275.677026)
			(xy 110.59541 -275.684234) (xy 110.613126 -275.706633) (xy 110.641384 -275.756255) (xy 110.660703 -275.809992)
			(xy 110.670508 -275.866248) (xy 110.671102 -275.8948) (xy 110.671102 -275.895054) (xy 110.670655 -275.919926)
			(xy 110.663205 -275.969109) (xy 110.648466 -276.016619) (xy 110.626771 -276.061383) (xy 110.598611 -276.102389)
			(xy 110.581948 -276.12086) (xy 110.575598 -276.127464) (xy 110.56112 -276.16277) (xy 110.56112 -276.22246)
			(xy 110.560687 -276.232526) (xy 110.552959 -276.251116) (xy 110.546134 -276.258528) (xy 110.308644 -276.496018)
			(xy 110.357158 -276.642068) (xy 110.3884 -276.646386) (xy 110.415386 -276.650706) (xy 110.467619 -276.666775)
			(xy 110.516647 -276.690915) (xy 110.561232 -276.722517) (xy 110.600248 -276.760783) (xy 110.632711 -276.804745)
			(xy 110.657799 -276.853295) (xy 110.67488 -276.905206) (xy 110.683522 -276.959167) (xy 110.684056 -276.986492)
			(xy 110.68362 -277.010644) (xy 110.676807 -277.058465) (xy 110.66337 -277.104863) (xy 110.643574 -277.148925)
			(xy 110.617808 -277.189783) (xy 110.602522 -277.208488) (xy 110.597188 -277.215092) (xy 110.584488 -277.247604)
			(xy 110.583726 -277.278592) (xy 110.583952 -277.287629) (xy 110.58993 -277.304677) (xy 110.59541 -277.311866)
			(xy 110.613124 -277.334266) (xy 110.641377 -277.383889) (xy 110.660691 -277.437626) (xy 110.67049 -277.493881)
			(xy 110.671102 -277.522432) (xy 110.67059 -277.548417) (xy 110.662455 -277.599748) (xy 110.646392 -277.649174)
			(xy 110.622794 -277.695478) (xy 110.592244 -277.737521) (xy 110.555492 -277.774268) (xy 110.513446 -277.804814)
			(xy 110.467138 -277.828406) (xy 110.417711 -277.844464) (xy 110.366379 -277.852593) (xy 110.340394 -277.85314)
			(xy 110.321357 -277.852828) (xy 110.283544 -277.848371) (xy 110.264956 -277.84425) (xy 110.221268 -277.871428)
			(xy 110.199424 -277.899622) (xy 110.19663 -277.90775) (xy 110.18647 -277.935182) (xy 110.174786 -277.960074)
			(xy 110.168944 -277.970996) (xy 110.168944 -278.1935) (xy 110.173262 -278.203406) (xy 110.183793 -278.228721)
			(xy 110.197266 -278.281864) (xy 110.201798 -278.336502) (xy 110.197265 -278.391139) (xy 110.183792 -278.444283)
			(xy 110.173262 -278.469598) (xy 110.169452 -278.47798) (xy 110.16869 -278.486108) (xy 110.167429 -278.494739)
			(xy 110.159906 -278.510463) (xy 110.153958 -278.516842) (xy 110.132622 -278.538178) (xy 110.13059 -278.540718)
			(xy 110.130336 -278.540972) (xy 110.117976 -278.556224) (xy 110.090216 -278.583984) (xy 110.074964 -278.596344)
			(xy 110.07471 -278.596598) (xy 110.07217 -278.59863) (xy 110.011464 -278.659336) (xy 110.004067 -278.666184)
			(xy 109.985468 -278.673915) (xy 109.975396 -278.674322) (xy 109.825536 -278.674322) (xy 109.806994 -278.666702)
			(xy 109.80039 -278.660098) (xy 109.786928 -278.656542) (xy 109.761415 -278.64933) (xy 109.712915 -278.62792)
			(xy 109.668442 -278.599063) (xy 109.62913 -278.563494) (xy 109.595981 -278.52212) (xy 109.582458 -278.499316)
			(xy 109.567726 -278.473408) (xy 109.249972 -278.473408) (xy 109.234986 -278.488394) (xy 109.210348 -278.513032)
			(xy 109.207554 -278.51735) (xy 109.194804 -278.536221) (xy 109.164938 -278.570606) (xy 109.130635 -278.600564)
			(xy 109.111796 -278.613362) (xy 109.111542 -278.613362) (xy 109.10697 -278.61641) (xy 108.759244 -278.964136)
			(xy 108.753656 -278.995632) (xy 108.760514 -279.010364) (xy 108.770282 -279.032345) (xy 108.78408 -279.078424)
			(xy 108.791069 -279.126014) (xy 108.791502 -279.150064) (xy 108.791502 -279.150318) (xy 108.790951 -279.17785)
			(xy 108.781823 -279.232152) (xy 108.76382 -279.284191) (xy 108.737443 -279.332526) (xy 108.72089 -279.354534)
			(xy 108.716064 -279.360884) (xy 108.70438 -279.392888) (xy 108.70438 -279.428194) (xy 113.286286 -279.428194)
			(xy 113.286766 -279.402495) (xy 113.294427 -279.351671) (xy 113.309576 -279.302557) (xy 113.331877 -279.256249)
			(xy 113.36083 -279.213782) (xy 113.39579 -279.176105) (xy 113.435974 -279.144059) (xy 113.480486 -279.11836)
			(xy 113.528331 -279.099583) (xy 113.57844 -279.088145) (xy 113.629694 -279.084305) (xy 113.680948 -279.088145)
			(xy 113.731057 -279.099583) (xy 113.778902 -279.11836) (xy 113.823414 -279.144059) (xy 113.863598 -279.176105)
			(xy 113.898558 -279.213782) (xy 113.927511 -279.256249) (xy 113.949812 -279.302557) (xy 113.964961 -279.351671)
			(xy 113.972622 -279.402495) (xy 113.973102 -279.428194) (xy 113.972586 -279.455) (xy 113.964256 -279.50796)
			(xy 113.947796 -279.558983) (xy 113.923607 -279.606828) (xy 113.892277 -279.650332) (xy 113.873788 -279.669748)
			(xy 113.86723 -279.676978) (xy 113.859624 -279.694934) (xy 113.859269 -279.714432) (xy 113.866216 -279.732653)
			(xy 113.872518 -279.740106) (xy 113.888908 -279.758502) (xy 113.916587 -279.799262) (xy 113.937901 -279.843682)
			(xy 113.952378 -279.890777) (xy 113.959694 -279.939499) (xy 113.960148 -279.964134) (xy 113.959639 -279.990101)
			(xy 113.951514 -280.041396) (xy 113.935466 -280.090789) (xy 113.911888 -280.137063) (xy 113.881362 -280.179079)
			(xy 113.844639 -280.215802) (xy 113.802623 -280.246328) (xy 113.756349 -280.269906) (xy 113.706956 -280.285954)
			(xy 113.655661 -280.294079) (xy 113.603727 -280.294079) (xy 113.552432 -280.285954) (xy 113.503039 -280.269906)
			(xy 113.456765 -280.246328) (xy 113.414749 -280.215802) (xy 113.378026 -280.179079) (xy 113.3475 -280.137063)
			(xy 113.323922 -280.090789) (xy 113.307874 -280.041396) (xy 113.299749 -279.990101) (xy 113.29924 -279.964134)
			(xy 113.299677 -279.9395) (xy 113.307005 -279.890779) (xy 113.32149 -279.843687) (xy 113.342809 -279.79927)
			(xy 113.370491 -279.758512) (xy 113.38687 -279.740106) (xy 113.393175 -279.732656) (xy 113.400112 -279.714431)
			(xy 113.399757 -279.694934) (xy 113.392162 -279.676973) (xy 113.3856 -279.669748) (xy 113.367108 -279.650335)
			(xy 113.335779 -279.606829) (xy 113.31159 -279.558984) (xy 113.295131 -279.507961) (xy 113.286801 -279.455)
			(xy 113.286286 -279.428194) (xy 108.70438 -279.428194) (xy 108.70438 -279.706324) (xy 108.703952 -279.716392)
			(xy 108.696229 -279.734988) (xy 108.689394 -279.742392) (xy 108.189522 -280.242264) (xy 109.99724 -280.242264)
			(xy 109.997659 -280.216345) (xy 110.005455 -280.165098) (xy 110.020865 -280.115604) (xy 110.043538 -280.068989)
			(xy 110.07296 -280.026311) (xy 110.108462 -279.988539) (xy 110.149238 -279.956532) (xy 110.194361 -279.931018)
			(xy 110.242806 -279.912574) (xy 110.293473 -279.901622) (xy 110.345211 -279.898409) (xy 110.396843 -279.903008)
			(xy 110.447198 -279.915315) (xy 110.495132 -279.93505) (xy 110.539555 -279.961766) (xy 110.579458 -279.994854)
			(xy 110.613934 -280.033564) (xy 110.642202 -280.077015) (xy 110.663617 -280.124222) (xy 110.677695 -280.174111)
			(xy 110.684114 -280.225549) (xy 110.68273 -280.277368) (xy 110.673573 -280.32839) (xy 110.656852 -280.377456)
			(xy 110.632947 -280.423452) (xy 110.6024 -280.465332) (xy 110.584488 -280.484072) (xy 110.577993 -280.491292)
			(xy 110.570477 -280.50918) (xy 110.570124 -280.52858) (xy 110.576983 -280.546731) (xy 110.583218 -280.554176)
			(xy 110.599594 -280.572585) (xy 110.627275 -280.613341) (xy 110.648592 -280.657758) (xy 110.663071 -280.70485)
			(xy 110.670392 -280.75357) (xy 110.670848 -280.778204) (xy 110.670339 -280.804171) (xy 110.662214 -280.855466)
			(xy 110.646166 -280.904859) (xy 110.622588 -280.951133) (xy 110.592062 -280.993149) (xy 110.555339 -281.029872)
			(xy 110.519266 -281.05608) (xy 113.286286 -281.05608) (xy 113.286766 -281.030381) (xy 113.294427 -280.979557)
			(xy 113.309576 -280.930443) (xy 113.331877 -280.884135) (xy 113.36083 -280.841668) (xy 113.39579 -280.803991)
			(xy 113.435974 -280.771945) (xy 113.480486 -280.746246) (xy 113.528331 -280.727469) (xy 113.57844 -280.716031)
			(xy 113.629694 -280.712191) (xy 113.680948 -280.716031) (xy 113.731057 -280.727469) (xy 113.778902 -280.746246)
			(xy 113.823414 -280.771945) (xy 113.863598 -280.803991) (xy 113.898558 -280.841668) (xy 113.927511 -280.884135)
			(xy 113.949812 -280.930443) (xy 113.964961 -280.979557) (xy 113.972622 -281.030381) (xy 113.973102 -281.05608)
			(xy 113.972578 -281.082886) (xy 113.964249 -281.135846) (xy 113.947792 -281.186868) (xy 113.923605 -281.234713)
			(xy 113.892276 -281.278218) (xy 113.873788 -281.297634) (xy 113.867244 -281.304875) (xy 113.859635 -281.322826)
			(xy 113.859276 -281.34232) (xy 113.866219 -281.360539) (xy 113.872518 -281.367992) (xy 113.888901 -281.386394)
			(xy 113.916581 -281.427152) (xy 113.937897 -281.471571) (xy 113.952375 -281.518664) (xy 113.959693 -281.567386)
			(xy 113.960148 -281.59202) (xy 113.959639 -281.617987) (xy 113.951514 -281.669282) (xy 113.935466 -281.718675)
			(xy 113.911888 -281.764949) (xy 113.881362 -281.806965) (xy 113.844639 -281.843688) (xy 113.802623 -281.874214)
			(xy 113.756349 -281.897792) (xy 113.706956 -281.91384) (xy 113.655661 -281.921965) (xy 113.603727 -281.921965)
			(xy 113.552432 -281.91384) (xy 113.503039 -281.897792) (xy 113.456765 -281.874214) (xy 113.414749 -281.843688)
			(xy 113.378026 -281.806965) (xy 113.3475 -281.764949) (xy 113.323922 -281.718675) (xy 113.307874 -281.669282)
			(xy 113.299749 -281.617987) (xy 113.29924 -281.59202) (xy 113.299729 -281.567388) (xy 113.307045 -281.518669)
			(xy 113.321517 -281.471578) (xy 113.342825 -281.427159) (xy 113.370495 -281.3864) (xy 113.38687 -281.367992)
			(xy 113.393189 -281.360553) (xy 113.400123 -281.342323) (xy 113.399765 -281.322822) (xy 113.392165 -281.304859)
			(xy 113.3856 -281.297634) (xy 113.367102 -281.278227) (xy 113.335773 -281.23472) (xy 113.311586 -281.186873)
			(xy 113.295128 -281.135848) (xy 113.2868 -281.082886) (xy 113.286286 -281.05608) (xy 110.519266 -281.05608)
			(xy 110.513323 -281.060398) (xy 110.467049 -281.083976) (xy 110.417656 -281.100024) (xy 110.366361 -281.108149)
			(xy 110.314427 -281.108149) (xy 110.263132 -281.100024) (xy 110.213739 -281.083976) (xy 110.167465 -281.060398)
			(xy 110.125449 -281.029872) (xy 110.088726 -280.993149) (xy 110.0582 -280.951133) (xy 110.034622 -280.904859)
			(xy 110.018574 -280.855466) (xy 110.010449 -280.804171) (xy 110.00994 -280.778204) (xy 110.010405 -280.753547)
			(xy 110.017724 -280.704781) (xy 110.0322 -280.65764) (xy 110.053513 -280.613171) (xy 110.08119 -280.572357)
			(xy 110.09757 -280.553922) (xy 110.103837 -280.5465) (xy 110.110778 -280.528375) (xy 110.110498 -280.508969)
			(xy 110.103037 -280.491051) (xy 110.096554 -280.483818) (xy 110.07804 -280.464425) (xy 110.046715 -280.420913)
			(xy 110.022532 -280.373063) (xy 110.006078 -280.322035) (xy 109.997752 -280.269071) (xy 109.99724 -280.242264)
			(xy 108.189522 -280.242264) (xy 107.81284 -280.618946) (xy 107.826048 -280.650442) (xy 107.834165 -280.670753)
			(xy 107.845586 -280.712975) (xy 107.851346 -280.756334) (xy 107.851702 -280.778204) (xy 107.851305 -280.802052)
			(xy 107.844489 -280.849258) (xy 107.830956 -280.894994) (xy 107.810988 -280.938308) (xy 107.798362 -280.958544)
			(xy 107.794552 -280.964386) (xy 107.785662 -280.992834) (xy 107.785662 -281.633168) (xy 107.795822 -281.663394)
			(xy 107.80014 -281.669744) (xy 107.815328 -281.691747) (xy 107.839424 -281.739471) (xy 107.85583 -281.790354)
			(xy 107.86415 -281.843165) (xy 107.864656 -281.869896) (xy 109.99724 -281.869896) (xy 109.997634 -281.843975)
			(xy 110.005426 -281.792721) (xy 110.020834 -281.743221) (xy 110.043506 -281.696599) (xy 110.072929 -281.653914)
			(xy 110.108432 -281.616136) (xy 110.14921 -281.584124) (xy 110.194337 -281.558604) (xy 110.242786 -281.540157)
			(xy 110.293458 -281.529201) (xy 110.345201 -281.525986) (xy 110.396839 -281.530584) (xy 110.4472 -281.542892)
			(xy 110.495139 -281.562628) (xy 110.539566 -281.589346) (xy 110.579474 -281.622438) (xy 110.613954 -281.661152)
			(xy 110.642224 -281.704609) (xy 110.663641 -281.751821) (xy 110.677718 -281.801715) (xy 110.684137 -281.853159)
			(xy 110.682751 -281.904983) (xy 110.673591 -281.95601) (xy 110.656866 -282.005081) (xy 110.632955 -282.05108)
			(xy 110.602403 -282.092964) (xy 110.584488 -282.111704) (xy 110.577962 -282.118899) (xy 110.570451 -282.136799)
			(xy 110.570106 -282.156207) (xy 110.576977 -282.174362) (xy 110.583218 -282.181808) (xy 110.599609 -282.200204)
			(xy 110.627288 -282.240963) (xy 110.648602 -282.285384) (xy 110.663078 -282.332478) (xy 110.670395 -282.381201)
			(xy 110.670848 -282.405836) (xy 110.670339 -282.431803) (xy 110.662214 -282.483098) (xy 110.646166 -282.532491)
			(xy 110.622588 -282.578765) (xy 110.592062 -282.620781) (xy 110.555339 -282.657504) (xy 110.518917 -282.683966)
			(xy 113.286286 -282.683966) (xy 113.286766 -282.658267) (xy 113.294427 -282.607443) (xy 113.309576 -282.558329)
			(xy 113.331877 -282.512021) (xy 113.36083 -282.469554) (xy 113.39579 -282.431877) (xy 113.435974 -282.399831)
			(xy 113.480486 -282.374132) (xy 113.528331 -282.355355) (xy 113.57844 -282.343917) (xy 113.629694 -282.340077)
			(xy 113.680948 -282.343917) (xy 113.731057 -282.355355) (xy 113.778902 -282.374132) (xy 113.823414 -282.399831)
			(xy 113.863598 -282.431877) (xy 113.898558 -282.469554) (xy 113.927511 -282.512021) (xy 113.949812 -282.558329)
			(xy 113.964961 -282.607443) (xy 113.972622 -282.658267) (xy 113.97279 -282.667274) (xy 116.105599 -282.667274)
			(xy 116.112015 -282.615836) (xy 116.126089 -282.565947) (xy 116.147502 -282.51874) (xy 116.175766 -282.475288)
			(xy 116.21024 -282.436577) (xy 116.250141 -282.403487) (xy 116.294561 -282.37677) (xy 116.342493 -282.357033)
			(xy 116.392846 -282.344724) (xy 116.444478 -282.340124) (xy 116.496215 -282.343335) (xy 116.546881 -282.354286)
			(xy 116.595326 -282.372728) (xy 116.640448 -282.398241) (xy 116.681224 -282.430247) (xy 116.716726 -282.468017)
			(xy 116.746148 -282.510694) (xy 116.768821 -282.557309) (xy 116.784231 -282.606801) (xy 116.792027 -282.658048)
			(xy 116.792502 -282.683966) (xy 116.791969 -282.710771) (xy 116.783643 -282.763731) (xy 116.767187 -282.814753)
			(xy 116.743002 -282.862598) (xy 116.711675 -282.906104) (xy 116.693188 -282.92552) (xy 116.686686 -282.932744)
			(xy 116.679203 -282.950664) (xy 116.678923 -282.970082) (xy 116.685885 -282.988212) (xy 116.692172 -282.995624)
			(xy 116.708546 -283.014069) (xy 116.73626 -283.054862) (xy 116.757593 -283.099327) (xy 116.772069 -283.146472)
			(xy 116.779366 -283.195247) (xy 116.779802 -283.219906) (xy 116.779293 -283.245873) (xy 116.771168 -283.297168)
			(xy 116.75512 -283.346561) (xy 116.731542 -283.392835) (xy 116.701016 -283.434851) (xy 116.664293 -283.471574)
			(xy 116.622277 -283.5021) (xy 116.576003 -283.525678) (xy 116.52661 -283.541726) (xy 116.475315 -283.549851)
			(xy 116.423381 -283.549851) (xy 116.372086 -283.541726) (xy 116.322693 -283.525678) (xy 116.276419 -283.5021)
			(xy 116.234403 -283.471574) (xy 116.19768 -283.434851) (xy 116.167154 -283.392835) (xy 116.143576 -283.346561)
			(xy 116.127528 -283.297168) (xy 116.119403 -283.245873) (xy 116.118894 -283.219906) (xy 116.11936 -283.195273)
			(xy 116.126679 -283.146552) (xy 116.141156 -283.09946) (xy 116.16247 -283.055042) (xy 116.190146 -283.014284)
			(xy 116.206524 -282.995878) (xy 116.212821 -282.988462) (xy 116.219748 -282.9703) (xy 116.219392 -282.950864)
			(xy 116.211805 -282.932967) (xy 116.205254 -282.925774) (xy 116.187331 -282.907046) (xy 116.156781 -282.865169)
			(xy 116.132872 -282.819176) (xy 116.116148 -282.770112) (xy 116.106988 -282.719092) (xy 116.105599 -282.667274)
			(xy 113.97279 -282.667274) (xy 113.973102 -282.683966) (xy 113.972569 -282.710771) (xy 113.964243 -282.763731)
			(xy 113.947787 -282.814753) (xy 113.923602 -282.862598) (xy 113.892275 -282.906104) (xy 113.873788 -282.92552)
			(xy 113.867257 -282.932772) (xy 113.859647 -282.950718) (xy 113.859284 -282.970208) (xy 113.866221 -282.988425)
			(xy 113.872518 -282.995878) (xy 113.888895 -283.014286) (xy 113.916575 -283.055042) (xy 113.937892 -283.099459)
			(xy 113.952372 -283.146551) (xy 113.959692 -283.195272) (xy 113.960148 -283.219906) (xy 113.959639 -283.245873)
			(xy 113.951514 -283.297168) (xy 113.935466 -283.346561) (xy 113.911888 -283.392835) (xy 113.881362 -283.434851)
			(xy 113.844639 -283.471574) (xy 113.802623 -283.5021) (xy 113.756349 -283.525678) (xy 113.706956 -283.541726)
			(xy 113.655661 -283.549851) (xy 113.603727 -283.549851) (xy 113.552432 -283.541726) (xy 113.503039 -283.525678)
			(xy 113.456765 -283.5021) (xy 113.414749 -283.471574) (xy 113.378026 -283.434851) (xy 113.3475 -283.392835)
			(xy 113.323922 -283.346561) (xy 113.307874 -283.297168) (xy 113.299749 -283.245873) (xy 113.29924 -283.219906)
			(xy 113.29972 -283.195273) (xy 113.307038 -283.146554) (xy 113.321513 -283.099463) (xy 113.342823 -283.055045)
			(xy 113.370495 -283.014285) (xy 113.38687 -282.995878) (xy 113.393203 -282.988449) (xy 113.400135 -282.970214)
			(xy 113.399772 -282.95071) (xy 113.392167 -282.932745) (xy 113.3856 -282.92552) (xy 113.367095 -282.906119)
			(xy 113.335767 -282.86261) (xy 113.311581 -282.814762) (xy 113.295125 -282.763736) (xy 113.286799 -282.710773)
			(xy 113.286286 -282.683966) (xy 110.518917 -282.683966) (xy 110.513323 -282.68803) (xy 110.467049 -282.711608)
			(xy 110.417656 -282.727656) (xy 110.366361 -282.735781) (xy 110.314427 -282.735781) (xy 110.263132 -282.727656)
			(xy 110.213739 -282.711608) (xy 110.167465 -282.68803) (xy 110.125449 -282.657504) (xy 110.088726 -282.620781)
			(xy 110.0582 -282.578765) (xy 110.034622 -282.532491) (xy 110.018574 -282.483098) (xy 110.010449 -282.431803)
			(xy 110.00994 -282.405836) (xy 110.010364 -282.381178) (xy 110.017693 -282.332409) (xy 110.032178 -282.285268)
			(xy 110.0535 -282.240799) (xy 110.081186 -282.199988) (xy 110.09757 -282.181554) (xy 110.103805 -282.174108)
			(xy 110.110751 -282.155994) (xy 110.11048 -282.136596) (xy 110.103031 -282.118683) (xy 110.096554 -282.11145)
			(xy 110.078055 -282.092043) (xy 110.046728 -282.048535) (xy 110.022542 -282.000688) (xy 110.006085 -281.949664)
			(xy 109.997755 -281.896702) (xy 109.99724 -281.869896) (xy 107.864656 -281.869896) (xy 107.8641 -281.897566)
			(xy 107.855227 -281.95219) (xy 107.837711 -282.004685) (xy 107.812003 -282.053692) (xy 107.795822 -282.076144)
			(xy 107.785662 -282.089606) (xy 107.785662 -282.206954) (xy 107.794552 -282.219654) (xy 107.807861 -282.23998)
			(xy 107.82902 -282.283714) (xy 107.843558 -282.330072) (xy 107.851163 -282.378057) (xy 107.85167 -282.426638)
			(xy 107.84507 -282.474771) (xy 107.831504 -282.521422) (xy 107.811263 -282.565589) (xy 107.798362 -282.586176)
			(xy 107.794552 -282.592018) (xy 107.785662 -282.620466) (xy 107.785662 -282.960318) (xy 107.785235 -282.970386)
			(xy 107.777512 -282.988982) (xy 107.770676 -282.996386) (xy 107.688634 -283.078428) (xy 107.699302 -283.203142)
			(xy 107.718606 -283.216858) (xy 107.74076 -283.233058) (xy 107.780097 -283.271324) (xy 107.812841 -283.315366)
			(xy 107.838154 -283.364059) (xy 107.855393 -283.41616) (xy 107.864118 -283.470342) (xy 107.864656 -283.497782)
			(xy 109.99724 -283.497782) (xy 109.997645 -283.471862) (xy 110.005439 -283.420611) (xy 110.020847 -283.371114)
			(xy 110.04352 -283.324494) (xy 110.072942 -283.281812) (xy 110.108445 -283.244037) (xy 110.149223 -283.212028)
			(xy 110.194348 -283.18651) (xy 110.242795 -283.168065) (xy 110.293465 -283.15711) (xy 110.345205 -283.153896)
			(xy 110.396841 -283.158495) (xy 110.447199 -283.170802) (xy 110.495136 -283.190538) (xy 110.539561 -283.217255)
			(xy 110.579467 -283.250345) (xy 110.613945 -283.289057) (xy 110.642214 -283.332512) (xy 110.66363 -283.379721)
			(xy 110.677708 -283.429614) (xy 110.684127 -283.481055) (xy 110.682742 -283.532877) (xy 110.673583 -283.583901)
			(xy 110.65686 -283.63297) (xy 110.632951 -283.678968) (xy 110.602401 -283.72085) (xy 110.584488 -283.73959)
			(xy 110.577975 -283.746796) (xy 110.570462 -283.764691) (xy 110.570114 -283.784096) (xy 110.57698 -283.802249)
			(xy 110.583218 -283.809694) (xy 110.599602 -283.828095) (xy 110.627282 -283.868853) (xy 110.648597 -283.913272)
			(xy 110.663075 -283.960366) (xy 110.670394 -284.009088) (xy 110.670848 -284.033722) (xy 110.670339 -284.059689)
			(xy 110.662214 -284.110984) (xy 110.646166 -284.160377) (xy 110.622588 -284.206651) (xy 110.592062 -284.248667)
			(xy 110.555339 -284.28539) (xy 110.519266 -284.311598) (xy 113.286286 -284.311598) (xy 113.286766 -284.285899)
			(xy 113.294427 -284.235075) (xy 113.309576 -284.185961) (xy 113.331877 -284.139653) (xy 113.36083 -284.097186)
			(xy 113.39579 -284.059509) (xy 113.435974 -284.027463) (xy 113.480486 -284.001764) (xy 113.528331 -283.982987)
			(xy 113.57844 -283.971549) (xy 113.629694 -283.967709) (xy 113.680948 -283.971549) (xy 113.731057 -283.982987)
			(xy 113.778902 -284.001764) (xy 113.823414 -284.027463) (xy 113.863598 -284.059509) (xy 113.898558 -284.097186)
			(xy 113.927511 -284.139653) (xy 113.949812 -284.185961) (xy 113.964961 -284.235075) (xy 113.972622 -284.285899)
			(xy 113.97279 -284.294885) (xy 116.105599 -284.294885) (xy 116.112014 -284.243445) (xy 116.126087 -284.193554)
			(xy 116.147499 -284.146344) (xy 116.175764 -284.10289) (xy 116.210239 -284.064177) (xy 116.250142 -284.031086)
			(xy 116.294564 -284.004369) (xy 116.342498 -283.984631) (xy 116.392854 -283.972323) (xy 116.444488 -283.967723)
			(xy 116.496227 -283.970937) (xy 116.546895 -283.98189) (xy 116.59534 -284.000335) (xy 116.640464 -284.025851)
			(xy 116.681239 -284.05786) (xy 116.71674 -284.095634) (xy 116.74616 -284.138315) (xy 116.768831 -284.184933)
			(xy 116.784237 -284.234429) (xy 116.792029 -284.285679) (xy 116.792502 -284.311598) (xy 116.791989 -284.338404)
			(xy 116.783658 -284.391365) (xy 116.767197 -284.442387) (xy 116.743008 -284.490232) (xy 116.711677 -284.533736)
			(xy 116.693188 -284.553152) (xy 116.686655 -284.560351) (xy 116.679177 -284.578283) (xy 116.678906 -284.597709)
			(xy 116.685879 -284.615843) (xy 116.692172 -284.623256) (xy 116.708561 -284.641688) (xy 116.736273 -284.682485)
			(xy 116.757603 -284.726953) (xy 116.772076 -284.774101) (xy 116.779368 -284.822878) (xy 116.779802 -284.847538)
			(xy 116.779293 -284.873505) (xy 116.771168 -284.9248) (xy 116.75512 -284.974193) (xy 116.731542 -285.020467)
			(xy 116.701016 -285.062483) (xy 116.664293 -285.099206) (xy 116.622277 -285.129732) (xy 116.576003 -285.15331)
			(xy 116.52661 -285.169358) (xy 116.475315 -285.177483) (xy 116.423381 -285.177483) (xy 116.372086 -285.169358)
			(xy 116.322693 -285.15331) (xy 116.276419 -285.129732) (xy 116.234403 -285.099206) (xy 116.19768 -285.062483)
			(xy 116.167154 -285.020467) (xy 116.143576 -284.974193) (xy 116.127528 -284.9248) (xy 116.119403 -284.873505)
			(xy 116.118894 -284.847538) (xy 116.119319 -284.822903) (xy 116.126648 -284.774181) (xy 116.141135 -284.727089)
			(xy 116.162457 -284.682671) (xy 116.190142 -284.641915) (xy 116.206524 -284.62351) (xy 116.212789 -284.61607)
			(xy 116.219721 -284.597919) (xy 116.219374 -284.578492) (xy 116.211799 -284.560599) (xy 116.205254 -284.553406)
			(xy 116.187345 -284.534663) (xy 116.156792 -284.492786) (xy 116.132879 -284.446792) (xy 116.116152 -284.397727)
			(xy 116.106989 -284.346705) (xy 116.105599 -284.294885) (xy 113.97279 -284.294885) (xy 113.973102 -284.311598)
			(xy 113.972589 -284.338404) (xy 113.964258 -284.391365) (xy 113.947797 -284.442387) (xy 113.923608 -284.490232)
			(xy 113.892277 -284.533736) (xy 113.873788 -284.553152) (xy 113.867226 -284.560379) (xy 113.859621 -284.578336)
			(xy 113.859267 -284.597835) (xy 113.866215 -284.616057) (xy 113.872518 -284.62351) (xy 113.88891 -284.641905)
			(xy 113.916588 -284.682665) (xy 113.937902 -284.727085) (xy 113.952378 -284.77418) (xy 113.959695 -284.822903)
			(xy 113.960148 -284.847538) (xy 113.959639 -284.873505) (xy 113.951514 -284.9248) (xy 113.935466 -284.974193)
			(xy 113.911888 -285.020467) (xy 113.881362 -285.062483) (xy 113.844639 -285.099206) (xy 113.802623 -285.129732)
			(xy 113.756349 -285.15331) (xy 113.706956 -285.169358) (xy 113.655661 -285.177483) (xy 113.603727 -285.177483)
			(xy 113.552432 -285.169358) (xy 113.503039 -285.15331) (xy 113.456765 -285.129732) (xy 113.414749 -285.099206)
			(xy 113.378026 -285.062483) (xy 113.3475 -285.020467) (xy 113.323922 -284.974193) (xy 113.307874 -284.9248)
			(xy 113.299749 -284.873505) (xy 113.29924 -284.847538) (xy 113.299679 -284.822904) (xy 113.307007 -284.774183)
			(xy 113.321491 -284.727091) (xy 113.34281 -284.682674) (xy 113.370491 -284.641916) (xy 113.38687 -284.62351)
			(xy 113.393171 -284.616057) (xy 113.400109 -284.597834) (xy 113.399755 -284.578337) (xy 113.392161 -284.560377)
			(xy 113.3856 -284.553152) (xy 113.36711 -284.533737) (xy 113.33578 -284.490232) (xy 113.311592 -284.442387)
			(xy 113.295132 -284.391365) (xy 113.286801 -284.338404) (xy 113.286286 -284.311598) (xy 110.519266 -284.311598)
			(xy 110.513323 -284.315916) (xy 110.467049 -284.339494) (xy 110.417656 -284.355542) (xy 110.366361 -284.363667)
			(xy 110.314427 -284.363667) (xy 110.263132 -284.355542) (xy 110.213739 -284.339494) (xy 110.167465 -284.315916)
			(xy 110.125449 -284.28539) (xy 110.088726 -284.248667) (xy 110.0582 -284.206651) (xy 110.034622 -284.160377)
			(xy 110.018574 -284.110984) (xy 110.010449 -284.059689) (xy 110.00994 -284.033722) (xy 110.010355 -284.009064)
			(xy 110.017686 -283.960294) (xy 110.032174 -283.913154) (xy 110.053498 -283.868685) (xy 110.081185 -283.827873)
			(xy 110.09757 -283.80944) (xy 110.103819 -283.802005) (xy 110.110762 -283.783886) (xy 110.110487 -283.764484)
			(xy 110.103033 -283.74657) (xy 110.096554 -283.739336) (xy 110.078049 -283.719935) (xy 110.046723 -283.676426)
			(xy 110.022538 -283.628577) (xy 110.006082 -283.577551) (xy 109.997754 -283.524589) (xy 109.99724 -283.497782)
			(xy 107.864656 -283.497782) (xy 107.864221 -283.521934) (xy 107.857409 -283.569756) (xy 107.843973 -283.616155)
			(xy 107.824178 -283.660218) (xy 107.798412 -283.701077) (xy 107.783122 -283.719778) (xy 107.777788 -283.726382)
			(xy 107.765088 -283.758894) (xy 107.764326 -283.789882) (xy 107.76455 -283.79892) (xy 107.770526 -283.81597)
			(xy 107.77601 -283.823156) (xy 107.793724 -283.845556) (xy 107.821979 -283.895178) (xy 107.841294 -283.948915)
			(xy 107.851095 -284.005171) (xy 107.851702 -284.033722) (xy 107.851192 -284.059709) (xy 107.843062 -284.111044)
			(xy 107.827001 -284.160474) (xy 107.803405 -284.206784) (xy 107.772855 -284.248832) (xy 107.736104 -284.285583)
			(xy 107.694056 -284.316133) (xy 107.647746 -284.339729) (xy 107.598316 -284.35579) (xy 107.546981 -284.36392)
			(xy 107.495007 -284.36392) (xy 107.443672 -284.35579) (xy 107.394242 -284.339729) (xy 107.347932 -284.316133)
			(xy 107.305884 -284.285583) (xy 107.269133 -284.248832) (xy 107.238583 -284.206784) (xy 107.214987 -284.160474)
			(xy 107.198926 -284.111044) (xy 107.190796 -284.059709) (xy 107.190286 -284.033722) (xy 107.190837 -284.006145)
			(xy 107.199992 -283.951756) (xy 107.21805 -283.899641) (xy 107.244511 -283.851249) (xy 107.261152 -283.829252)
			(xy 107.266232 -283.822648) (xy 107.277662 -283.790898) (xy 107.277154 -283.75864) (xy 107.264454 -283.726128)
			(xy 107.25912 -283.719524) (xy 107.2452 -283.702564) (xy 107.221328 -283.66575) (xy 107.202344 -283.626193)
			(xy 107.195112 -283.605478) (xy 107.192318 -283.597096) (xy 107.170474 -283.568902) (xy 107.143804 -283.552392)
			(xy 107.13575 -283.547896) (xy 107.117653 -283.544397) (xy 107.108498 -283.545534) (xy 107.094327 -283.547884)
			(xy 107.065712 -283.550426) (xy 107.051348 -283.550614) (xy 107.026498 -283.550171) (xy 106.977357 -283.542741)
			(xy 106.929881 -283.528042) (xy 106.885139 -283.506404) (xy 106.864404 -283.492702) (xy 106.858308 -283.488638)
			(xy 106.828844 -283.478986) (xy 106.369358 -283.478986) (xy 106.354372 -283.493972) (xy 106.336338 -283.512006)
			(xy 106.321352 -283.526992) (xy 106.321352 -283.754576) (xy 106.320914 -283.764639) (xy 106.313174 -283.783219)
			(xy 106.306366 -283.790644) (xy 105.95356 -284.14345) (xy 105.94975 -284.153356) (xy 105.939298 -284.178787)
			(xy 105.911207 -284.226048) (xy 105.875687 -284.268013) (xy 105.833718 -284.303528) (xy 105.786454 -284.331614)
			(xy 105.761028 -284.342078) (xy 105.751122 -284.345888) (xy 105.442766 -284.654244) (xy 105.461054 -284.687772)
			(xy 105.461054 -284.688026) (xy 105.473971 -284.71261) (xy 105.492302 -284.765029) (xy 105.501621 -284.819773)
			(xy 105.502202 -284.847538) (xy 105.501762 -284.872032) (xy 105.494538 -284.920483) (xy 105.480239 -284.967338)
			(xy 105.459179 -285.011567) (xy 105.431819 -285.052202) (xy 105.415588 -285.07055) (xy 105.40954 -285.077725)
			(xy 105.402766 -285.09521) (xy 105.40238 -285.104586) (xy 105.40238 -285.125414) (xy 107.17784 -285.125414)
			(xy 107.17822 -285.099491) (xy 107.18601 -285.048234) (xy 107.201417 -284.99873) (xy 107.224088 -284.952104)
			(xy 107.253511 -284.909416) (xy 107.289015 -284.871635) (xy 107.329795 -284.839619) (xy 107.374923 -284.814097)
			(xy 107.423375 -284.795647) (xy 107.47405 -284.78469) (xy 107.525796 -284.781473) (xy 107.577437 -284.786071)
			(xy 107.627801 -284.798379) (xy 107.675743 -284.818116) (xy 107.720173 -284.844835) (xy 107.760083 -284.877929)
			(xy 107.794565 -284.916646) (xy 107.822836 -284.960105) (xy 107.844254 -285.00732) (xy 107.858332 -285.057218)
			(xy 107.86475 -285.108665) (xy 107.864302 -285.125414) (xy 109.99724 -285.125414) (xy 109.99762 -285.099491)
			(xy 110.00541 -285.048234) (xy 110.020817 -284.99873) (xy 110.043488 -284.952104) (xy 110.072911 -284.909416)
			(xy 110.108415 -284.871635) (xy 110.149195 -284.839619) (xy 110.194323 -284.814097) (xy 110.242775 -284.795647)
			(xy 110.29345 -284.78469) (xy 110.345196 -284.781473) (xy 110.396837 -284.786071) (xy 110.447201 -284.798379)
			(xy 110.495143 -284.818116) (xy 110.539573 -284.844835) (xy 110.579483 -284.877929) (xy 110.613965 -284.916646)
			(xy 110.642236 -284.960105) (xy 110.663654 -285.00732) (xy 110.677732 -285.057218) (xy 110.68415 -285.108665)
			(xy 110.682763 -285.160492) (xy 110.673601 -285.211522) (xy 110.656874 -285.260595) (xy 110.63296 -285.306597)
			(xy 110.602404 -285.348481) (xy 110.584488 -285.367222) (xy 110.577945 -285.374403) (xy 110.570436 -285.392309)
			(xy 110.570097 -285.411722) (xy 110.576974 -285.42988) (xy 110.583218 -285.437326) (xy 110.599617 -285.455714)
			(xy 110.627295 -285.496476) (xy 110.648608 -285.540898) (xy 110.663082 -285.587994) (xy 110.670396 -285.636719)
			(xy 110.670848 -285.661354) (xy 110.670339 -285.687321) (xy 110.662214 -285.738616) (xy 110.646166 -285.788009)
			(xy 110.622588 -285.834283) (xy 110.592062 -285.876299) (xy 110.555339 -285.913022) (xy 110.518917 -285.939484)
			(xy 113.286286 -285.939484) (xy 113.286766 -285.913785) (xy 113.294427 -285.862961) (xy 113.309576 -285.813847)
			(xy 113.331877 -285.767539) (xy 113.36083 -285.725072) (xy 113.39579 -285.687395) (xy 113.435974 -285.655349)
			(xy 113.480486 -285.62965) (xy 113.528331 -285.610873) (xy 113.57844 -285.599435) (xy 113.629694 -285.595595)
			(xy 113.680948 -285.599435) (xy 113.731057 -285.610873) (xy 113.778902 -285.62965) (xy 113.823414 -285.655349)
			(xy 113.863598 -285.687395) (xy 113.898558 -285.725072) (xy 113.927511 -285.767539) (xy 113.949812 -285.813847)
			(xy 113.964961 -285.862961) (xy 113.972622 -285.913785) (xy 113.97279 -285.92278) (xy 116.105599 -285.92278)
			(xy 116.112014 -285.871341) (xy 116.126088 -285.821451) (xy 116.1475 -285.774243) (xy 116.175765 -285.730789)
			(xy 116.21024 -285.692077) (xy 116.250141 -285.658987) (xy 116.294563 -285.632269) (xy 116.342496 -285.612532)
			(xy 116.392851 -285.600224) (xy 116.444484 -285.595623) (xy 116.496221 -285.598836) (xy 116.546889 -285.609788)
			(xy 116.595334 -285.628232) (xy 116.640457 -285.653747) (xy 116.681232 -285.685754) (xy 116.716734 -285.723527)
			(xy 116.746155 -285.766206) (xy 116.768827 -285.812823) (xy 116.784235 -285.862317) (xy 116.792028 -285.913565)
			(xy 116.792502 -285.939484) (xy 116.79198 -285.96629) (xy 116.783651 -286.01925) (xy 116.767193 -286.070272)
			(xy 116.743005 -286.118117) (xy 116.711676 -286.161622) (xy 116.693188 -286.181038) (xy 116.686668 -286.188248)
			(xy 116.679189 -286.206175) (xy 116.678913 -286.225598) (xy 116.685882 -286.243729) (xy 116.692172 -286.251142)
			(xy 116.708554 -286.269579) (xy 116.736268 -286.310375) (xy 116.757599 -286.354842) (xy 116.772073 -286.401988)
			(xy 116.779367 -286.450764) (xy 116.779802 -286.475424) (xy 116.779293 -286.501391) (xy 116.771168 -286.552686)
			(xy 116.75512 -286.602079) (xy 116.731542 -286.648353) (xy 116.701016 -286.690369) (xy 116.664293 -286.727092)
			(xy 116.622277 -286.757618) (xy 116.576003 -286.781196) (xy 116.52661 -286.797244) (xy 116.475315 -286.805369)
			(xy 116.423381 -286.805369) (xy 116.372086 -286.797244) (xy 116.322693 -286.781196) (xy 116.276419 -286.757618)
			(xy 116.234403 -286.727092) (xy 116.19768 -286.690369) (xy 116.167154 -286.648353) (xy 116.143576 -286.602079)
			(xy 116.127528 -286.552686) (xy 116.119403 -286.501391) (xy 116.118894 -286.475424) (xy 116.119371 -286.450791)
			(xy 116.126688 -286.402071) (xy 116.141162 -286.35498) (xy 116.162473 -286.310561) (xy 116.190147 -286.269802)
			(xy 116.206524 -286.251396) (xy 116.212802 -286.243967) (xy 116.219732 -286.22581) (xy 116.219382 -286.20638)
			(xy 116.211801 -286.188485) (xy 116.205254 -286.181292) (xy 116.187339 -286.162555) (xy 116.156787 -286.120678)
			(xy 116.132876 -286.074685) (xy 116.11615 -286.02562) (xy 116.106988 -285.974599) (xy 116.105599 -285.92278)
			(xy 113.97279 -285.92278) (xy 113.973102 -285.939484) (xy 113.97258 -285.96629) (xy 113.964251 -286.01925)
			(xy 113.947793 -286.070272) (xy 113.923605 -286.118117) (xy 113.892276 -286.161622) (xy 113.873788 -286.181038)
			(xy 113.86724 -286.188276) (xy 113.859632 -286.206228) (xy 113.859274 -286.225723) (xy 113.866218 -286.243943)
			(xy 113.872518 -286.251396) (xy 113.888903 -286.269797) (xy 113.916583 -286.310555) (xy 113.937898 -286.354974)
			(xy 113.952376 -286.402068) (xy 113.959694 -286.45079) (xy 113.960148 -286.475424) (xy 113.959639 -286.501391)
			(xy 113.951514 -286.552686) (xy 113.935466 -286.602079) (xy 113.911888 -286.648353) (xy 113.881362 -286.690369)
			(xy 113.844639 -286.727092) (xy 113.802623 -286.757618) (xy 113.756349 -286.781196) (xy 113.706956 -286.797244)
			(xy 113.655661 -286.805369) (xy 113.603727 -286.805369) (xy 113.552432 -286.797244) (xy 113.503039 -286.781196)
			(xy 113.456765 -286.757618) (xy 113.414749 -286.727092) (xy 113.378026 -286.690369) (xy 113.3475 -286.648353)
			(xy 113.323922 -286.602079) (xy 113.307874 -286.552686) (xy 113.299749 -286.501391) (xy 113.29924 -286.475424)
			(xy 113.299731 -286.450792) (xy 113.307046 -286.402073) (xy 113.321518 -286.354982) (xy 113.342826 -286.310564)
			(xy 113.370496 -286.269804) (xy 113.38687 -286.251396) (xy 113.393185 -286.243954) (xy 113.40012 -286.225725)
			(xy 113.399763 -286.206225) (xy 113.392164 -286.188263) (xy 113.3856 -286.181038) (xy 113.367104 -286.161629)
			(xy 113.335775 -286.118122) (xy 113.311587 -286.070276) (xy 113.295129 -286.019252) (xy 113.2868 -285.96629)
			(xy 113.286286 -285.939484) (xy 110.518917 -285.939484) (xy 110.513323 -285.943548) (xy 110.467049 -285.967126)
			(xy 110.417656 -285.983174) (xy 110.366361 -285.991299) (xy 110.314427 -285.991299) (xy 110.263132 -285.983174)
			(xy 110.213739 -285.967126) (xy 110.167465 -285.943548) (xy 110.125449 -285.913022) (xy 110.088726 -285.876299)
			(xy 110.0582 -285.834283) (xy 110.034622 -285.788009) (xy 110.018574 -285.738616) (xy 110.010449 -285.687321)
			(xy 110.00994 -285.661354) (xy 110.010375 -285.636696) (xy 110.017701 -285.587928) (xy 110.032184 -285.540787)
			(xy 110.053504 -285.496318) (xy 110.081187 -285.455506) (xy 110.09757 -285.437072) (xy 110.103887 -285.429687)
			(xy 110.110819 -285.411545) (xy 110.110524 -285.392126) (xy 110.103046 -285.374202) (xy 110.096554 -285.366968)
			(xy 110.078064 -285.347553) (xy 110.046736 -285.304047) (xy 110.022548 -285.256202) (xy 110.006088 -285.20518)
			(xy 109.997756 -285.15222) (xy 109.99724 -285.125414) (xy 107.864302 -285.125414) (xy 107.863363 -285.160492)
			(xy 107.854201 -285.211522) (xy 107.837474 -285.260595) (xy 107.81356 -285.306597) (xy 107.783004 -285.348481)
			(xy 107.765088 -285.367222) (xy 107.758545 -285.374403) (xy 107.751036 -285.392309) (xy 107.750697 -285.411722)
			(xy 107.757574 -285.42988) (xy 107.763818 -285.437326) (xy 107.780217 -285.455714) (xy 107.807895 -285.496476)
			(xy 107.829208 -285.540898) (xy 107.843682 -285.587994) (xy 107.850996 -285.636719) (xy 107.851448 -285.661354)
			(xy 107.850939 -285.687321) (xy 107.842814 -285.738616) (xy 107.826766 -285.788009) (xy 107.803188 -285.834283)
			(xy 107.772662 -285.876299) (xy 107.735939 -285.913022) (xy 107.693923 -285.943548) (xy 107.647649 -285.967126)
			(xy 107.598256 -285.983174) (xy 107.546961 -285.991299) (xy 107.495027 -285.991299) (xy 107.443732 -285.983174)
			(xy 107.394339 -285.967126) (xy 107.348065 -285.943548) (xy 107.306049 -285.913022) (xy 107.269326 -285.876299)
			(xy 107.2388 -285.834283) (xy 107.215222 -285.788009) (xy 107.199174 -285.738616) (xy 107.191049 -285.687321)
			(xy 107.19054 -285.661354) (xy 107.190975 -285.636696) (xy 107.198301 -285.587928) (xy 107.212784 -285.540787)
			(xy 107.234104 -285.496318) (xy 107.261787 -285.455506) (xy 107.27817 -285.437072) (xy 107.284487 -285.429687)
			(xy 107.291419 -285.411545) (xy 107.291124 -285.392126) (xy 107.283646 -285.374202) (xy 107.277154 -285.366968)
			(xy 107.258664 -285.347553) (xy 107.227336 -285.304047) (xy 107.203148 -285.256202) (xy 107.186688 -285.20518)
			(xy 107.178356 -285.15222) (xy 107.17784 -285.125414) (xy 105.40238 -285.125414) (xy 105.40238 -285.66364)
			(xy 105.416858 -285.698946) (xy 105.422954 -285.705804) (xy 105.440401 -285.725313) (xy 105.469787 -285.76862)
			(xy 105.492265 -285.815884) (xy 105.507314 -285.866009) (xy 105.514587 -285.917837) (xy 105.513915 -285.970169)
			(xy 105.505315 -286.021793) (xy 105.488984 -286.071516) (xy 105.4653 -286.118187) (xy 105.434813 -286.160726)
			(xy 105.416858 -286.179768) (xy 105.40238 -286.1945) (xy 105.40238 -286.22752) (xy 105.409238 -286.245046)
			(xy 105.415588 -286.252158) (xy 105.415842 -286.252412) (xy 105.432053 -286.270799) (xy 105.459425 -286.311461)
			(xy 105.48049 -286.35572) (xy 105.494785 -286.402606) (xy 105.501997 -286.451089) (xy 105.501968 -286.500105)
			(xy 105.494698 -286.54858) (xy 105.480346 -286.595448) (xy 105.459229 -286.639682) (xy 105.431808 -286.680311)
			(xy 105.415588 -286.69869) (xy 105.409531 -286.705862) (xy 105.402736 -286.723346) (xy 105.40238 -286.732726)
			(xy 105.40238 -286.7533) (xy 107.17784 -286.7533) (xy 107.178231 -286.727378) (xy 107.186023 -286.676124)
			(xy 107.20143 -286.626623) (xy 107.224102 -286.58) (xy 107.253525 -286.537314) (xy 107.289028 -286.499536)
			(xy 107.329807 -286.467523) (xy 107.374934 -286.442002) (xy 107.423384 -286.423555) (xy 107.474056 -286.412599)
			(xy 107.5258 -286.409383) (xy 107.577439 -286.413981) (xy 107.6278 -286.426289) (xy 107.67574 -286.446026)
			(xy 107.720168 -286.472744) (xy 107.760076 -286.505836) (xy 107.794556 -286.544551) (xy 107.822826 -286.588008)
			(xy 107.844244 -286.635221) (xy 107.858321 -286.685116) (xy 107.86474 -286.73656) (xy 107.864292 -286.7533)
			(xy 109.99724 -286.7533) (xy 109.997631 -286.727378) (xy 110.005423 -286.676124) (xy 110.02083 -286.626623)
			(xy 110.043502 -286.58) (xy 110.072925 -286.537314) (xy 110.108428 -286.499536) (xy 110.149207 -286.467523)
			(xy 110.194334 -286.442002) (xy 110.242784 -286.423555) (xy 110.293456 -286.412599) (xy 110.3452 -286.409383)
			(xy 110.396839 -286.413981) (xy 110.4472 -286.426289) (xy 110.49514 -286.446026) (xy 110.539568 -286.472744)
			(xy 110.579476 -286.505836) (xy 110.613956 -286.544551) (xy 110.642226 -286.588008) (xy 110.663644 -286.635221)
			(xy 110.677721 -286.685116) (xy 110.68414 -286.73656) (xy 110.682753 -286.788385) (xy 110.673593 -286.839413)
			(xy 110.656868 -286.888484) (xy 110.632956 -286.934484) (xy 110.602403 -286.976367) (xy 110.584488 -286.995108)
			(xy 110.577958 -287.0023) (xy 110.570448 -287.020201) (xy 110.570104 -287.039611) (xy 110.576976 -287.057766)
			(xy 110.583218 -287.065212) (xy 110.599611 -287.083606) (xy 110.627289 -287.124366) (xy 110.648603 -287.168787)
			(xy 110.663079 -287.215882) (xy 110.670395 -287.264605) (xy 110.670848 -287.28924) (xy 110.670339 -287.315207)
			(xy 110.662214 -287.366502) (xy 110.646166 -287.415895) (xy 110.622588 -287.462169) (xy 110.592062 -287.504185)
			(xy 110.555339 -287.540908) (xy 110.513323 -287.571434) (xy 110.467049 -287.595012) (xy 110.417656 -287.61106)
			(xy 110.366361 -287.619185) (xy 110.314427 -287.619185) (xy 110.263132 -287.61106) (xy 110.213739 -287.595012)
			(xy 110.167465 -287.571434) (xy 110.125449 -287.540908) (xy 110.088726 -287.504185) (xy 110.0582 -287.462169)
			(xy 110.034622 -287.415895) (xy 110.018574 -287.366502) (xy 110.010449 -287.315207) (xy 110.00994 -287.28924)
			(xy 110.010366 -287.264582) (xy 110.017694 -287.215813) (xy 110.03218 -287.168673) (xy 110.053501 -287.124204)
			(xy 110.081186 -287.083392) (xy 110.09757 -287.064958) (xy 110.103802 -287.05751) (xy 110.110748 -287.039397)
			(xy 110.110478 -287.02) (xy 110.10303 -287.002087) (xy 110.096554 -286.994854) (xy 110.078057 -286.975445)
			(xy 110.04673 -286.931938) (xy 110.022544 -286.884091) (xy 110.006085 -286.833067) (xy 109.997755 -286.780106)
			(xy 109.99724 -286.7533) (xy 107.864292 -286.7533) (xy 107.863353 -286.788385) (xy 107.854193 -286.839413)
			(xy 107.837468 -286.888484) (xy 107.813556 -286.934484) (xy 107.783003 -286.976367) (xy 107.765088 -286.995108)
			(xy 107.758558 -287.0023) (xy 107.751048 -287.020201) (xy 107.750704 -287.039611) (xy 107.757576 -287.057766)
			(xy 107.763818 -287.065212) (xy 107.780211 -287.083606) (xy 107.807889 -287.124366) (xy 107.829203 -287.168787)
			(xy 107.843679 -287.215882) (xy 107.850995 -287.264605) (xy 107.851448 -287.28924) (xy 107.850939 -287.315207)
			(xy 107.842814 -287.366502) (xy 107.826766 -287.415895) (xy 107.803188 -287.462169) (xy 107.772662 -287.504185)
			(xy 107.735939 -287.540908) (xy 107.693923 -287.571434) (xy 107.647649 -287.595012) (xy 107.598256 -287.61106)
			(xy 107.546961 -287.619185) (xy 107.495027 -287.619185) (xy 107.443732 -287.61106) (xy 107.394339 -287.595012)
			(xy 107.348065 -287.571434) (xy 107.306049 -287.540908) (xy 107.269326 -287.504185) (xy 107.2388 -287.462169)
			(xy 107.215222 -287.415895) (xy 107.199174 -287.366502) (xy 107.191049 -287.315207) (xy 107.19054 -287.28924)
			(xy 107.190966 -287.264582) (xy 107.198294 -287.215813) (xy 107.21278 -287.168673) (xy 107.234101 -287.124204)
			(xy 107.261786 -287.083392) (xy 107.27817 -287.064958) (xy 107.284402 -287.05751) (xy 107.291348 -287.039397)
			(xy 107.291078 -287.02) (xy 107.28363 -287.002087) (xy 107.277154 -286.994854) (xy 107.258657 -286.975445)
			(xy 107.22733 -286.931938) (xy 107.203144 -286.884091) (xy 107.186685 -286.833067) (xy 107.178355 -286.780106)
			(xy 107.17784 -286.7533) (xy 105.40238 -286.7533) (xy 105.40238 -287.291272) (xy 105.416604 -287.326324)
			(xy 105.422954 -287.333182) (xy 105.439881 -287.352044) (xy 105.468568 -287.393823) (xy 105.490802 -287.439364)
			(xy 105.506098 -287.48768) (xy 105.514125 -287.53772) (xy 105.514902 -287.563052) (xy 105.514902 -287.569402)
			(xy 105.51436 -287.594084) (xy 105.507089 -287.642913) (xy 105.500424 -287.666684) (xy 105.498138 -287.673796)
			(xy 105.498138 -288.050224) (xy 105.498646 -288.054034) (xy 105.500397 -288.066215) (xy 105.502306 -288.090751)
			(xy 105.502456 -288.103056) (xy 105.502307 -288.115361) (xy 105.500403 -288.139898) (xy 105.498646 -288.152078)
			(xy 105.498138 -288.155888) (xy 105.498138 -288.186622) (xy 105.490518 -288.205164) (xy 105.484168 -288.211514)
			(xy 105.475583 -288.234877) (xy 105.4524 -288.27892) (xy 105.422878 -288.318991) (xy 105.387684 -288.354185)
			(xy 105.347611 -288.383706) (xy 105.303567 -288.406887) (xy 105.280206 -288.415476) (xy 104.972612 -288.72307)
			(xy 104.991154 -288.756598) (xy 105.00058 -288.774234) (xy 105.01561 -288.811291) (xy 105.021126 -288.830512)
			(xy 105.021126 -288.830766) (xy 105.026206 -288.849562) (xy 105.113582 -288.907474) (xy 105.132632 -288.904934)
			(xy 105.154906 -288.902333) (xy 105.199743 -288.903182) (xy 105.243922 -288.910874) (xy 105.286407 -288.925227)
			(xy 105.326199 -288.945906) (xy 105.362364 -288.972422) (xy 105.378504 -288.987992) (xy 105.395706 -289.005889)
			(xy 105.424437 -289.046365) (xy 105.435654 -289.06851) (xy 105.44532 -289.089668) (xy 105.458564 -289.134255)
			(xy 105.464405 -289.179077) (xy 105.818479 -289.179077) (xy 105.824899 -289.131922) (xy 105.838867 -289.086427)
			(xy 105.860014 -289.043793) (xy 105.887784 -289.005144) (xy 105.904284 -288.987992) (xy 105.922755 -288.970309)
			(xy 105.964636 -288.940984) (xy 106.010974 -288.919376) (xy 106.06036 -288.906143) (xy 106.111294 -288.901687)
			(xy 106.162228 -288.906143) (xy 106.211614 -288.919376) (xy 106.257952 -288.940984) (xy 106.299833 -288.970309)
			(xy 106.318304 -288.987992) (xy 106.334993 -289.005296) (xy 106.363029 -289.044346) (xy 106.384306 -289.087453)
			(xy 106.398251 -289.133458) (xy 106.404221 -289.179077) (xy 106.758279 -289.179077) (xy 106.764699 -289.131922)
			(xy 106.778667 -289.086427) (xy 106.799814 -289.043793) (xy 106.827584 -289.005144) (xy 106.844084 -288.987992)
			(xy 106.860265 -288.972405) (xy 106.896517 -288.945871) (xy 106.936397 -288.925185) (xy 106.978968 -288.910832)
			(xy 107.023232 -288.903151) (xy 107.06815 -288.90232) (xy 107.090464 -288.904934) (xy 107.105077 -288.906478)
			(xy 107.13411 -288.902001) (xy 107.160665 -288.889443) (xy 107.182545 -288.869842) (xy 107.197937 -288.844823)
			(xy 107.202224 -288.830766) (xy 107.209667 -288.805334) (xy 107.231544 -288.757073) (xy 107.260832 -288.712915)
			(xy 107.278424 -288.693098) (xy 107.28473 -288.685651) (xy 107.291658 -288.667425) (xy 107.291302 -288.647929)
			(xy 107.283712 -288.629967) (xy 107.277154 -288.62274) (xy 107.258651 -288.603337) (xy 107.227324 -288.559828)
			(xy 107.203139 -288.51198) (xy 107.186682 -288.460955) (xy 107.178354 -288.407993) (xy 107.17784 -288.381186)
			(xy 107.17832 -288.355487) (xy 107.185981 -288.304663) (xy 107.20113 -288.255549) (xy 107.223431 -288.209241)
			(xy 107.252384 -288.166774) (xy 107.287344 -288.129097) (xy 107.327528 -288.097051) (xy 107.37204 -288.071352)
			(xy 107.419885 -288.052575) (xy 107.469994 -288.041137) (xy 107.521248 -288.037297) (xy 107.572502 -288.041137)
			(xy 107.622611 -288.052575) (xy 107.670456 -288.071352) (xy 107.714968 -288.097051) (xy 107.755152 -288.129097)
			(xy 107.790112 -288.166774) (xy 107.819065 -288.209241) (xy 107.841366 -288.255549) (xy 107.856515 -288.304663)
			(xy 107.864176 -288.355487) (xy 107.864354 -288.365033) (xy 109.107818 -288.365033) (xy 109.114252 -288.317932)
			(xy 109.128221 -288.272492) (xy 109.149356 -288.22991) (xy 109.177101 -288.191308) (xy 109.193584 -288.174176)
			(xy 109.212055 -288.156493) (xy 109.253936 -288.127168) (xy 109.300274 -288.10556) (xy 109.34966 -288.092327)
			(xy 109.400594 -288.087871) (xy 109.451528 -288.092327) (xy 109.500914 -288.10556) (xy 109.547252 -288.127168)
			(xy 109.589133 -288.156493) (xy 109.607604 -288.174176) (xy 109.624285 -288.191487) (xy 109.652322 -288.230535)
			(xy 109.6736 -288.27364) (xy 109.687547 -288.319644) (xy 109.693788 -288.367308) (xy 109.693456 -288.391346)
			(xy 109.693196 -288.401883) (xy 109.685332 -288.421416) (xy 109.678216 -288.429192) (xy 109.670746 -288.436128)
			(xy 109.651951 -288.443979) (xy 109.631583 -288.443979) (xy 109.612788 -288.436128) (xy 109.605318 -288.429192)
			(xy 109.600188 -288.423664) (xy 109.593088 -288.410368) (xy 109.591348 -288.40303) (xy 109.591348 -288.382456)
			(xy 109.591602 -288.381694) (xy 109.591153 -288.362879) (xy 109.583792 -288.325975) (xy 109.569374 -288.291216)
			(xy 109.548453 -288.259937) (xy 109.535468 -288.246312) (xy 109.521911 -288.233361) (xy 109.49074 -288.212534)
			(xy 109.456106 -288.198188) (xy 109.419338 -288.190874) (xy 109.38185 -288.190874) (xy 109.345082 -288.198188)
			(xy 109.310448 -288.212534) (xy 109.279277 -288.233361) (xy 109.26572 -288.246312) (xy 109.252906 -288.25978)
			(xy 109.232183 -288.290634) (xy 109.217833 -288.324919) (xy 109.210402 -288.361336) (xy 109.20984 -288.379916)
			(xy 109.20984 -288.380932) (xy 109.209586 -288.381186) (xy 109.20984 -288.38144) (xy 109.20984 -288.402268)
			(xy 109.208077 -288.409541) (xy 109.200978 -288.422707) (xy 109.19587 -288.428176) (xy 109.1884 -288.435112)
			(xy 109.169605 -288.442963) (xy 109.149237 -288.442963) (xy 109.130442 -288.435112) (xy 109.122972 -288.428176)
			(xy 109.115588 -288.420127) (xy 109.107828 -288.399729) (xy 109.107986 -288.388806) (xy 109.107818 -288.365033)
			(xy 107.864354 -288.365033) (xy 107.864656 -288.381186) (xy 107.864149 -288.407992) (xy 107.855818 -288.460954)
			(xy 107.839357 -288.511977) (xy 107.815166 -288.559822) (xy 107.783833 -288.603325) (xy 107.765342 -288.62274)
			(xy 107.758787 -288.629975) (xy 107.751172 -288.647928) (xy 107.750814 -288.667427) (xy 107.757766 -288.685647)
			(xy 107.764072 -288.693098) (xy 107.781665 -288.712915) (xy 107.810957 -288.75707) (xy 107.832824 -288.805335)
			(xy 107.840272 -288.830766) (xy 107.844507 -288.844805) (xy 107.859892 -288.86976) (xy 107.881728 -288.889321)
			(xy 107.908219 -288.901879) (xy 107.937185 -288.9064) (xy 107.951778 -288.904934) (xy 107.974075 -288.902346)
			(xy 108.018951 -288.903178) (xy 108.063174 -288.910858) (xy 108.105703 -288.925206) (xy 108.14554 -288.945885)
			(xy 108.181749 -288.972409) (xy 108.197904 -288.987992) (xy 108.214593 -289.005296) (xy 108.242629 -289.044346)
			(xy 108.263906 -289.087453) (xy 108.277851 -289.133458) (xy 108.283821 -289.179077) (xy 108.637879 -289.179077)
			(xy 108.644299 -289.131922) (xy 108.658267 -289.086427) (xy 108.679414 -289.043793) (xy 108.707184 -289.005144)
			(xy 108.723684 -288.987992) (xy 108.742155 -288.970309) (xy 108.784036 -288.940984) (xy 108.830374 -288.919376)
			(xy 108.87976 -288.906143) (xy 108.930694 -288.901687) (xy 108.981628 -288.906143) (xy 109.031014 -288.919376)
			(xy 109.077352 -288.940984) (xy 109.119233 -288.970309) (xy 109.137704 -288.987992) (xy 109.142848 -288.993326)
			(xy 110.010194 -288.993326) (xy 110.010623 -288.968632) (xy 110.017966 -288.919793) (xy 110.032491 -288.872589)
			(xy 110.053877 -288.828071) (xy 110.081647 -288.78723) (xy 110.098078 -288.76879) (xy 110.11154 -288.754312)
			(xy 110.11154 -288.70402) (xy 110.099348 -288.689796) (xy 110.081429 -288.668008) (xy 110.052802 -288.619405)
			(xy 110.033203 -288.566512) (xy 110.023249 -288.51099) (xy 110.02264 -288.482786) (xy 110.02264 -288.381186)
			(xy 110.02313 -288.356197) (xy 110.030949 -288.306834) (xy 110.046393 -288.259302) (xy 110.069083 -288.21477)
			(xy 110.098459 -288.174337) (xy 110.133799 -288.138997) (xy 110.174232 -288.109621) (xy 110.218764 -288.086931)
			(xy 110.266296 -288.071487) (xy 110.315659 -288.063668) (xy 110.365637 -288.063668) (xy 110.415 -288.071487)
			(xy 110.462532 -288.086931) (xy 110.507064 -288.109621) (xy 110.547497 -288.138997) (xy 110.582837 -288.174337)
			(xy 110.612213 -288.21477) (xy 110.634903 -288.259302) (xy 110.650347 -288.306834) (xy 110.658166 -288.356197)
			(xy 110.658656 -288.381186) (xy 110.658656 -288.399729) (xy 110.987428 -288.399729) (xy 110.987586 -288.388806)
			(xy 110.987467 -288.365023) (xy 110.99394 -288.317909) (xy 111.007953 -288.272464) (xy 111.029136 -288.229885)
			(xy 111.05693 -288.191297) (xy 111.073438 -288.174176) (xy 111.091909 -288.156493) (xy 111.13379 -288.127168)
			(xy 111.180128 -288.10556) (xy 111.229514 -288.092327) (xy 111.280448 -288.087871) (xy 111.331382 -288.092327)
			(xy 111.380768 -288.10556) (xy 111.427106 -288.127168) (xy 111.468987 -288.156493) (xy 111.487458 -288.174176)
			(xy 111.504091 -288.191519) (xy 111.532075 -288.230576) (xy 111.553303 -288.27368) (xy 111.567204 -288.319674)
			(xy 111.573405 -288.36732) (xy 111.573056 -288.391346) (xy 111.572872 -288.399729) (xy 111.927228 -288.399729)
			(xy 111.927386 -288.388806) (xy 111.927267 -288.365023) (xy 111.93374 -288.317909) (xy 111.947753 -288.272464)
			(xy 111.968936 -288.229885) (xy 111.99673 -288.191297) (xy 112.013238 -288.174176) (xy 112.031709 -288.156493)
			(xy 112.07359 -288.127168) (xy 112.119928 -288.10556) (xy 112.169314 -288.092327) (xy 112.220248 -288.087871)
			(xy 112.271182 -288.092327) (xy 112.320568 -288.10556) (xy 112.366906 -288.127168) (xy 112.408787 -288.156493)
			(xy 112.427258 -288.174176) (xy 112.443891 -288.191519) (xy 112.471875 -288.230576) (xy 112.493103 -288.27368)
			(xy 112.507004 -288.319674) (xy 112.512907 -288.365033) (xy 112.867018 -288.365033) (xy 112.873452 -288.317932)
			(xy 112.887421 -288.272492) (xy 112.908556 -288.22991) (xy 112.936301 -288.191308) (xy 112.952784 -288.174176)
			(xy 112.96895 -288.158609) (xy 113.005171 -288.132113) (xy 113.045009 -288.11145) (xy 113.087532 -288.097103)
			(xy 113.131745 -288.089409) (xy 113.176615 -288.088547) (xy 113.19891 -288.091118) (xy 113.213526 -288.092621)
			(xy 113.242556 -288.088159) (xy 113.269111 -288.075611) (xy 113.290991 -288.056018) (xy 113.306383 -288.031004)
			(xy 113.31067 -288.01695) (xy 113.318096 -287.991474) (xy 113.33997 -287.943129) (xy 113.369268 -287.898887)
			(xy 113.38687 -287.879028) (xy 113.393153 -287.871562) (xy 113.400093 -287.853344) (xy 113.399745 -287.833853)
			(xy 113.392157 -287.815895) (xy 113.3856 -287.80867) (xy 113.367119 -287.789247) (xy 113.335788 -287.745744)
			(xy 113.311598 -287.697901) (xy 113.295136 -287.646881) (xy 113.286802 -287.593921) (xy 113.286286 -287.567116)
			(xy 113.286766 -287.541417) (xy 113.294427 -287.490593) (xy 113.309576 -287.441479) (xy 113.331877 -287.395171)
			(xy 113.36083 -287.352704) (xy 113.39579 -287.315027) (xy 113.435974 -287.282981) (xy 113.480486 -287.257282)
			(xy 113.528331 -287.238505) (xy 113.57844 -287.227067) (xy 113.629694 -287.223227) (xy 113.680948 -287.227067)
			(xy 113.731057 -287.238505) (xy 113.778902 -287.257282) (xy 113.823414 -287.282981) (xy 113.863598 -287.315027)
			(xy 113.898558 -287.352704) (xy 113.927511 -287.395171) (xy 113.949812 -287.441479) (xy 113.964961 -287.490593)
			(xy 113.972622 -287.541417) (xy 113.97279 -287.550391) (xy 116.105599 -287.550391) (xy 116.112013 -287.49895)
			(xy 116.126086 -287.449057) (xy 116.147498 -287.401847) (xy 116.175763 -287.358391) (xy 116.210239 -287.319678)
			(xy 116.250142 -287.286586) (xy 116.294566 -287.259868) (xy 116.342501 -287.24013) (xy 116.392859 -287.227822)
			(xy 116.444494 -287.223223) (xy 116.496233 -287.226438) (xy 116.546902 -287.237392) (xy 116.595349 -287.255839)
			(xy 116.640472 -287.281357) (xy 116.681248 -287.313368) (xy 116.716748 -287.351144) (xy 116.746167 -287.393827)
			(xy 116.768837 -287.440447) (xy 116.784241 -287.489945) (xy 116.792031 -287.541196) (xy 116.792502 -287.567116)
			(xy 116.792 -287.593922) (xy 116.783666 -287.646884) (xy 116.767203 -287.697906) (xy 116.743011 -287.745751)
			(xy 116.711678 -287.789255) (xy 116.693188 -287.80867) (xy 116.686734 -287.815933) (xy 116.679245 -287.833836)
			(xy 116.678951 -287.85324) (xy 116.685895 -287.871362) (xy 116.692172 -287.878774) (xy 116.708569 -287.897198)
			(xy 116.736281 -287.937997) (xy 116.757609 -287.982467) (xy 116.77208 -288.029617) (xy 116.779369 -288.078395)
			(xy 116.779802 -288.103056) (xy 116.779293 -288.129023) (xy 116.771168 -288.180318) (xy 116.75512 -288.229711)
			(xy 116.731542 -288.275985) (xy 116.701016 -288.318001) (xy 116.664293 -288.354724) (xy 116.622277 -288.38525)
			(xy 116.576003 -288.408828) (xy 116.52661 -288.424876) (xy 116.475315 -288.433001) (xy 116.423381 -288.433001)
			(xy 116.372086 -288.424876) (xy 116.322693 -288.408828) (xy 116.276419 -288.38525) (xy 116.234403 -288.354724)
			(xy 116.19768 -288.318001) (xy 116.167154 -288.275985) (xy 116.143576 -288.229711) (xy 116.127528 -288.180318)
			(xy 116.119403 -288.129023) (xy 116.118894 -288.103056) (xy 116.11933 -288.078421) (xy 116.126657 -288.0297)
			(xy 116.141141 -287.982608) (xy 116.162461 -287.93819) (xy 116.190143 -287.897433) (xy 116.206524 -287.879028)
			(xy 116.212771 -287.871575) (xy 116.219706 -287.853429) (xy 116.219364 -287.834007) (xy 116.211795 -287.816117)
			(xy 116.205254 -287.808924) (xy 116.187353 -287.790172) (xy 116.156797 -287.748295) (xy 116.132883 -287.702301)
			(xy 116.116154 -287.653235) (xy 116.10699 -287.602212) (xy 116.105599 -287.550391) (xy 113.97279 -287.550391)
			(xy 113.973102 -287.567116) (xy 113.9726 -287.593922) (xy 113.964266 -287.646884) (xy 113.947803 -287.697906)
			(xy 113.923611 -287.745751) (xy 113.892278 -287.789255) (xy 113.873788 -287.80867) (xy 113.867209 -287.815882)
			(xy 113.859605 -287.833846) (xy 113.859256 -287.85335) (xy 113.866212 -287.871575) (xy 113.872518 -287.879028)
			(xy 113.890138 -287.898873) (xy 113.919453 -287.943108) (xy 113.941298 -287.99147) (xy 113.948718 -288.01695)
			(xy 113.953051 -288.030985) (xy 113.968444 -288.055985) (xy 113.990314 -288.075572) (xy 114.016853 -288.088127)
			(xy 114.045867 -288.092613) (xy 114.060478 -288.091118) (xy 114.082792 -288.088488) (xy 114.127713 -288.089311)
			(xy 114.171981 -288.09699) (xy 114.214555 -288.111344) (xy 114.254435 -288.132036) (xy 114.290685 -288.15858)
			(xy 114.306858 -288.174176) (xy 114.323491 -288.191519) (xy 114.351475 -288.230576) (xy 114.372703 -288.27368)
			(xy 114.386604 -288.319674) (xy 114.392805 -288.36732) (xy 114.392456 -288.391346) (xy 114.392272 -288.399729)
			(xy 114.746628 -288.399729) (xy 114.746786 -288.388806) (xy 114.746667 -288.365023) (xy 114.75314 -288.317909)
			(xy 114.767153 -288.272464) (xy 114.788336 -288.229885) (xy 114.81613 -288.191297) (xy 114.832638 -288.174176)
			(xy 114.851109 -288.156493) (xy 114.89299 -288.127168) (xy 114.939328 -288.10556) (xy 114.988714 -288.092327)
			(xy 115.039648 -288.087871) (xy 115.090582 -288.092327) (xy 115.139968 -288.10556) (xy 115.186306 -288.127168)
			(xy 115.228187 -288.156493) (xy 115.246658 -288.174176) (xy 115.263291 -288.191519) (xy 115.291275 -288.230576)
			(xy 115.312503 -288.27368) (xy 115.326404 -288.319674) (xy 115.332605 -288.36732) (xy 115.332256 -288.391346)
			(xy 115.332024 -288.401891) (xy 115.324162 -288.421436) (xy 115.317016 -288.429192) (xy 115.309511 -288.435998)
			(xy 115.290813 -288.443743) (xy 115.270575 -288.443743) (xy 115.251877 -288.435998) (xy 115.244372 -288.429192)
			(xy 115.239153 -288.423701) (xy 115.231926 -288.410395) (xy 115.230148 -288.40303) (xy 115.230148 -288.382456)
			(xy 115.230656 -288.381694) (xy 115.230251 -288.362875) (xy 115.222887 -288.325964) (xy 115.208463 -288.291199)
			(xy 115.187533 -288.259916) (xy 115.174522 -288.246312) (xy 115.160965 -288.233361) (xy 115.129794 -288.212534)
			(xy 115.09516 -288.198188) (xy 115.058392 -288.190874) (xy 115.020904 -288.190874) (xy 114.984136 -288.198188)
			(xy 114.949502 -288.212534) (xy 114.918331 -288.233361) (xy 114.904774 -288.246312) (xy 114.891901 -288.259743)
			(xy 114.871113 -288.29059) (xy 114.856705 -288.324884) (xy 114.849223 -288.361321) (xy 114.84864 -288.379916)
			(xy 114.84864 -288.380932) (xy 114.848386 -288.381186) (xy 114.84864 -288.38144) (xy 114.84864 -288.402268)
			(xy 114.846877 -288.409541) (xy 114.839778 -288.422707) (xy 114.83467 -288.428176) (xy 114.8272 -288.435112)
			(xy 114.808405 -288.442963) (xy 114.788037 -288.442963) (xy 114.769242 -288.435112) (xy 114.761772 -288.428176)
			(xy 114.754388 -288.420127) (xy 114.746628 -288.399729) (xy 114.392272 -288.399729) (xy 114.392224 -288.401891)
			(xy 114.384362 -288.421436) (xy 114.377216 -288.429192) (xy 114.369711 -288.435998) (xy 114.351013 -288.443743)
			(xy 114.330775 -288.443743) (xy 114.312077 -288.435998) (xy 114.304572 -288.429192) (xy 114.299353 -288.423701)
			(xy 114.292126 -288.410395) (xy 114.290348 -288.40303) (xy 114.290348 -288.382456) (xy 114.290856 -288.381694)
			(xy 114.290451 -288.362875) (xy 114.283087 -288.325964) (xy 114.268663 -288.291199) (xy 114.247733 -288.259916)
			(xy 114.234722 -288.246312) (xy 114.221165 -288.233361) (xy 114.189994 -288.212534) (xy 114.15536 -288.198188)
			(xy 114.118592 -288.190874) (xy 114.081104 -288.190874) (xy 114.044336 -288.198188) (xy 114.009702 -288.212534)
			(xy 113.978531 -288.233361) (xy 113.964974 -288.246312) (xy 113.952101 -288.259743) (xy 113.931313 -288.29059)
			(xy 113.916905 -288.324884) (xy 113.909423 -288.361321) (xy 113.90884 -288.379916) (xy 113.90884 -288.380932)
			(xy 113.908586 -288.381186) (xy 113.90884 -288.38144) (xy 113.90884 -288.402268) (xy 113.907077 -288.409541)
			(xy 113.899978 -288.422707) (xy 113.89487 -288.428176) (xy 113.8874 -288.435112) (xy 113.868605 -288.442963)
			(xy 113.848237 -288.442963) (xy 113.829442 -288.435112) (xy 113.821972 -288.428176) (xy 113.817908 -288.42335)
			(xy 113.81067 -288.41482) (xy 113.790806 -288.404581) (xy 113.768473 -288.40376) (xy 113.757964 -288.407602)
			(xy 113.737584 -288.415798) (xy 113.695198 -288.427333) (xy 113.651658 -288.433151) (xy 113.629694 -288.43351)
			(xy 113.607823 -288.433172) (xy 113.56446 -288.427423) (xy 113.522239 -288.415987) (xy 113.501932 -288.407856)
			(xy 113.491415 -288.403992) (xy 113.46905 -288.404917) (xy 113.449215 -288.415292) (xy 113.441988 -288.423858)
			(xy 113.437416 -288.429192) (xy 113.429946 -288.436128) (xy 113.411151 -288.443979) (xy 113.390783 -288.443979)
			(xy 113.371988 -288.436128) (xy 113.364518 -288.429192) (xy 113.359388 -288.423664) (xy 113.352288 -288.410368)
			(xy 113.350548 -288.40303) (xy 113.350548 -288.382456) (xy 113.350802 -288.381694) (xy 113.350353 -288.362879)
			(xy 113.342992 -288.325975) (xy 113.328574 -288.291216) (xy 113.307653 -288.259937) (xy 113.294668 -288.246312)
			(xy 113.281111 -288.233361) (xy 113.24994 -288.212534) (xy 113.215306 -288.198188) (xy 113.178538 -288.190874)
			(xy 113.14105 -288.190874) (xy 113.104282 -288.198188) (xy 113.069648 -288.212534) (xy 113.038477 -288.233361)
			(xy 113.02492 -288.246312) (xy 113.012106 -288.25978) (xy 112.991383 -288.290634) (xy 112.977033 -288.324919)
			(xy 112.969602 -288.361336) (xy 112.96904 -288.379916) (xy 112.96904 -288.380932) (xy 112.968786 -288.381186)
			(xy 112.96904 -288.38144) (xy 112.96904 -288.402268) (xy 112.967277 -288.409541) (xy 112.960178 -288.422707)
			(xy 112.95507 -288.428176) (xy 112.9476 -288.435112) (xy 112.928805 -288.442963) (xy 112.908437 -288.442963)
			(xy 112.889642 -288.435112) (xy 112.882172 -288.428176) (xy 112.874788 -288.420127) (xy 112.867028 -288.399729)
			(xy 112.867186 -288.388806) (xy 112.867018 -288.365033) (xy 112.512907 -288.365033) (xy 112.513205 -288.36732)
			(xy 112.512856 -288.391346) (xy 112.512624 -288.401891) (xy 112.504762 -288.421436) (xy 112.497616 -288.429192)
			(xy 112.490111 -288.435998) (xy 112.471413 -288.443743) (xy 112.451175 -288.443743) (xy 112.432477 -288.435998)
			(xy 112.424972 -288.429192) (xy 112.419753 -288.423701) (xy 112.412526 -288.410395) (xy 112.410748 -288.40303)
			(xy 112.410748 -288.382456) (xy 112.411256 -288.381694) (xy 112.410851 -288.362875) (xy 112.403487 -288.325964)
			(xy 112.389063 -288.291199) (xy 112.368133 -288.259916) (xy 112.355122 -288.246312) (xy 112.341565 -288.233361)
			(xy 112.310394 -288.212534) (xy 112.27576 -288.198188) (xy 112.238992 -288.190874) (xy 112.201504 -288.190874)
			(xy 112.164736 -288.198188) (xy 112.130102 -288.212534) (xy 112.098931 -288.233361) (xy 112.085374 -288.246312)
			(xy 112.072501 -288.259743) (xy 112.051713 -288.29059) (xy 112.037305 -288.324884) (xy 112.029823 -288.361321)
			(xy 112.02924 -288.379916) (xy 112.02924 -288.380932) (xy 112.028986 -288.381186) (xy 112.02924 -288.38144)
			(xy 112.02924 -288.402268) (xy 112.027477 -288.409541) (xy 112.020378 -288.422707) (xy 112.01527 -288.428176)
			(xy 112.0078 -288.435112) (xy 111.989005 -288.442963) (xy 111.968637 -288.442963) (xy 111.949842 -288.435112)
			(xy 111.942372 -288.428176) (xy 111.934988 -288.420127) (xy 111.927228 -288.399729) (xy 111.572872 -288.399729)
			(xy 111.572824 -288.401891) (xy 111.564962 -288.421436) (xy 111.557816 -288.429192) (xy 111.550311 -288.435998)
			(xy 111.531613 -288.443743) (xy 111.511375 -288.443743) (xy 111.492677 -288.435998) (xy 111.485172 -288.429192)
			(xy 111.479953 -288.423701) (xy 111.472726 -288.410395) (xy 111.470948 -288.40303) (xy 111.470948 -288.382456)
			(xy 111.471456 -288.381694) (xy 111.471051 -288.362875) (xy 111.463687 -288.325964) (xy 111.449263 -288.291199)
			(xy 111.428333 -288.259916) (xy 111.415322 -288.246312) (xy 111.401765 -288.233361) (xy 111.370594 -288.212534)
			(xy 111.33596 -288.198188) (xy 111.299192 -288.190874) (xy 111.261704 -288.190874) (xy 111.224936 -288.198188)
			(xy 111.190302 -288.212534) (xy 111.159131 -288.233361) (xy 111.145574 -288.246312) (xy 111.132701 -288.259743)
			(xy 111.111913 -288.29059) (xy 111.097505 -288.324884) (xy 111.090023 -288.361321) (xy 111.08944 -288.379916)
			(xy 111.08944 -288.380932) (xy 111.089186 -288.381186) (xy 111.08944 -288.38144) (xy 111.08944 -288.402268)
			(xy 111.087677 -288.409541) (xy 111.080578 -288.422707) (xy 111.07547 -288.428176) (xy 111.068 -288.435112)
			(xy 111.049205 -288.442963) (xy 111.028837 -288.442963) (xy 111.010042 -288.435112) (xy 111.002572 -288.428176)
			(xy 110.995188 -288.420127) (xy 110.987428 -288.399729) (xy 110.658656 -288.399729) (xy 110.658656 -288.482786)
			(xy 110.658053 -288.510989) (xy 110.648088 -288.566509) (xy 110.628486 -288.6194) (xy 110.599861 -288.668003)
			(xy 110.581948 -288.689796) (xy 110.569756 -288.70402) (xy 110.569756 -288.754312) (xy 110.583218 -288.76879)
			(xy 110.59966 -288.787219) (xy 110.627416 -288.828068) (xy 110.64879 -288.87259) (xy 110.663308 -288.919794)
			(xy 110.670646 -288.968633) (xy 110.671102 -288.993326) (xy 110.670593 -289.019293) (xy 110.662468 -289.070588)
			(xy 110.64642 -289.119981) (xy 110.622842 -289.166255) (xy 110.613526 -289.179077) (xy 115.216479 -289.179077)
			(xy 115.222899 -289.131922) (xy 115.236867 -289.086427) (xy 115.258014 -289.043793) (xy 115.285784 -289.005144)
			(xy 115.302284 -288.987992) (xy 115.320755 -288.970309) (xy 115.362636 -288.940984) (xy 115.408974 -288.919376)
			(xy 115.45836 -288.906143) (xy 115.509294 -288.901687) (xy 115.560228 -288.906143) (xy 115.609614 -288.919376)
			(xy 115.655952 -288.940984) (xy 115.697833 -288.970309) (xy 115.716304 -288.987992) (xy 115.732993 -289.005296)
			(xy 115.761029 -289.044346) (xy 115.782306 -289.087453) (xy 115.796251 -289.133458) (xy 115.802221 -289.179077)
			(xy 116.156279 -289.179077) (xy 116.162699 -289.131922) (xy 116.176667 -289.086427) (xy 116.197814 -289.043793)
			(xy 116.225584 -289.005144) (xy 116.242084 -288.987992) (xy 116.260555 -288.970309) (xy 116.302436 -288.940984)
			(xy 116.348774 -288.919376) (xy 116.39816 -288.906143) (xy 116.449094 -288.901687) (xy 116.500028 -288.906143)
			(xy 116.549414 -288.919376) (xy 116.595752 -288.940984) (xy 116.637633 -288.970309) (xy 116.656104 -288.987992)
			(xy 116.672793 -289.005296) (xy 116.700829 -289.044346) (xy 116.722106 -289.087453) (xy 116.736051 -289.133458)
			(xy 116.742021 -289.179077) (xy 117.096079 -289.179077) (xy 117.102499 -289.131922) (xy 117.116467 -289.086427)
			(xy 117.137614 -289.043793) (xy 117.165384 -289.005144) (xy 117.181884 -288.987992) (xy 117.200355 -288.970309)
			(xy 117.242236 -288.940984) (xy 117.288574 -288.919376) (xy 117.33796 -288.906143) (xy 117.388894 -288.901687)
			(xy 117.439828 -288.906143) (xy 117.489214 -288.919376) (xy 117.535552 -288.940984) (xy 117.577433 -288.970309)
			(xy 117.595904 -288.987992) (xy 117.612593 -289.005296) (xy 117.640629 -289.044346) (xy 117.661906 -289.087453)
			(xy 117.675851 -289.133458) (xy 117.681821 -289.179077) (xy 118.035879 -289.179077) (xy 118.042299 -289.131922)
			(xy 118.056267 -289.086427) (xy 118.077414 -289.043793) (xy 118.105184 -289.005144) (xy 118.121684 -288.987992)
			(xy 118.140155 -288.970309) (xy 118.182036 -288.940984) (xy 118.228374 -288.919376) (xy 118.27776 -288.906143)
			(xy 118.328694 -288.901687) (xy 118.379628 -288.906143) (xy 118.429014 -288.919376) (xy 118.475352 -288.940984)
			(xy 118.517233 -288.970309) (xy 118.535704 -288.987992) (xy 118.552393 -289.005296) (xy 118.580429 -289.044346)
			(xy 118.601706 -289.087453) (xy 118.615651 -289.133458) (xy 118.621889 -289.181123) (xy 118.621556 -289.205162)
			(xy 118.621314 -289.215762) (xy 118.613463 -289.235432) (xy 118.606316 -289.243262) (xy 118.598833 -289.250171)
			(xy 118.580042 -289.257981) (xy 118.559692 -289.257981) (xy 118.540901 -289.250171) (xy 118.533418 -289.243262)
			(xy 118.528274 -289.23767) (xy 118.521173 -289.224245) (xy 118.519448 -289.216846) (xy 118.519448 -289.18535)
			(xy 118.518135 -289.167852) (xy 118.509898 -289.133746) (xy 118.495594 -289.101708) (xy 118.4757 -289.072806)
			(xy 118.463568 -289.060128) (xy 118.450011 -289.047177) (xy 118.41884 -289.02635) (xy 118.384206 -289.012004)
			(xy 118.347438 -289.00469) (xy 118.30995 -289.00469) (xy 118.273182 -289.012004) (xy 118.238548 -289.02635)
			(xy 118.207377 -289.047177) (xy 118.19382 -289.060128) (xy 118.181012 -289.073637) (xy 118.160311 -289.104569)
			(xy 118.145967 -289.138913) (xy 118.138518 -289.17538) (xy 118.13794 -289.193986) (xy 118.13794 -289.216084)
			(xy 118.136233 -289.223433) (xy 118.129122 -289.236733) (xy 118.12397 -289.242246) (xy 118.116487 -289.249155)
			(xy 118.097696 -289.256965) (xy 118.077346 -289.256965) (xy 118.058555 -289.249155) (xy 118.051072 -289.242246)
			(xy 118.043673 -289.234208) (xy 118.035922 -289.213801) (xy 118.036086 -289.202876) (xy 118.035879 -289.179077)
			(xy 117.681821 -289.179077) (xy 117.682089 -289.181123) (xy 117.681756 -289.205162) (xy 117.681514 -289.215762)
			(xy 117.673663 -289.235432) (xy 117.666516 -289.243262) (xy 117.659033 -289.250171) (xy 117.640242 -289.257981)
			(xy 117.619892 -289.257981) (xy 117.601101 -289.250171) (xy 117.593618 -289.243262) (xy 117.588474 -289.23767)
			(xy 117.581373 -289.224245) (xy 117.579648 -289.216846) (xy 117.579648 -289.18535) (xy 117.578335 -289.167852)
			(xy 117.570098 -289.133746) (xy 117.555794 -289.101708) (xy 117.5359 -289.072806) (xy 117.523768 -289.060128)
			(xy 117.510211 -289.047177) (xy 117.47904 -289.02635) (xy 117.444406 -289.012004) (xy 117.407638 -289.00469)
			(xy 117.37015 -289.00469) (xy 117.333382 -289.012004) (xy 117.298748 -289.02635) (xy 117.267577 -289.047177)
			(xy 117.25402 -289.060128) (xy 117.241212 -289.073637) (xy 117.220511 -289.104569) (xy 117.206167 -289.138913)
			(xy 117.198718 -289.17538) (xy 117.19814 -289.193986) (xy 117.19814 -289.216084) (xy 117.196433 -289.223433)
			(xy 117.189322 -289.236733) (xy 117.18417 -289.242246) (xy 117.176687 -289.249155) (xy 117.157896 -289.256965)
			(xy 117.137546 -289.256965) (xy 117.118755 -289.249155) (xy 117.111272 -289.242246) (xy 117.103873 -289.234208)
			(xy 117.096122 -289.213801) (xy 117.096286 -289.202876) (xy 117.096079 -289.179077) (xy 116.742021 -289.179077)
			(xy 116.742289 -289.181123) (xy 116.741956 -289.205162) (xy 116.741714 -289.215762) (xy 116.733863 -289.235432)
			(xy 116.726716 -289.243262) (xy 116.719233 -289.250171) (xy 116.700442 -289.257981) (xy 116.680092 -289.257981)
			(xy 116.661301 -289.250171) (xy 116.653818 -289.243262) (xy 116.648674 -289.23767) (xy 116.641573 -289.224245)
			(xy 116.639848 -289.216846) (xy 116.639848 -289.18535) (xy 116.638535 -289.167852) (xy 116.630298 -289.133746)
			(xy 116.615994 -289.101708) (xy 116.5961 -289.072806) (xy 116.583968 -289.060128) (xy 116.570411 -289.047177)
			(xy 116.53924 -289.02635) (xy 116.504606 -289.012004) (xy 116.467838 -289.00469) (xy 116.43035 -289.00469)
			(xy 116.393582 -289.012004) (xy 116.358948 -289.02635) (xy 116.327777 -289.047177) (xy 116.31422 -289.060128)
			(xy 116.301412 -289.073637) (xy 116.280711 -289.104569) (xy 116.266367 -289.138913) (xy 116.258918 -289.17538)
			(xy 116.25834 -289.193986) (xy 116.25834 -289.216084) (xy 116.256633 -289.223433) (xy 116.249522 -289.236733)
			(xy 116.24437 -289.242246) (xy 116.236887 -289.249155) (xy 116.218096 -289.256965) (xy 116.197746 -289.256965)
			(xy 116.178955 -289.249155) (xy 116.171472 -289.242246) (xy 116.164073 -289.234208) (xy 116.156322 -289.213801)
			(xy 116.156486 -289.202876) (xy 116.156279 -289.179077) (xy 115.802221 -289.179077) (xy 115.802489 -289.181123)
			(xy 115.802156 -289.205162) (xy 115.801914 -289.215762) (xy 115.794063 -289.235432) (xy 115.786916 -289.243262)
			(xy 115.779433 -289.250171) (xy 115.760642 -289.257981) (xy 115.740292 -289.257981) (xy 115.721501 -289.250171)
			(xy 115.714018 -289.243262) (xy 115.708874 -289.23767) (xy 115.701773 -289.224245) (xy 115.700048 -289.216846)
			(xy 115.700048 -289.18535) (xy 115.698735 -289.167852) (xy 115.690498 -289.133746) (xy 115.676194 -289.101708)
			(xy 115.6563 -289.072806) (xy 115.644168 -289.060128) (xy 115.630611 -289.047177) (xy 115.59944 -289.02635)
			(xy 115.564806 -289.012004) (xy 115.528038 -289.00469) (xy 115.49055 -289.00469) (xy 115.453782 -289.012004)
			(xy 115.419148 -289.02635) (xy 115.387977 -289.047177) (xy 115.37442 -289.060128) (xy 115.361612 -289.073637)
			(xy 115.340911 -289.104569) (xy 115.326567 -289.138913) (xy 115.319118 -289.17538) (xy 115.31854 -289.193986)
			(xy 115.31854 -289.216084) (xy 115.316833 -289.223433) (xy 115.309722 -289.236733) (xy 115.30457 -289.242246)
			(xy 115.297087 -289.249155) (xy 115.278296 -289.256965) (xy 115.257946 -289.256965) (xy 115.239155 -289.249155)
			(xy 115.231672 -289.242246) (xy 115.224273 -289.234208) (xy 115.216522 -289.213801) (xy 115.216686 -289.202876)
			(xy 115.216479 -289.179077) (xy 110.613526 -289.179077) (xy 110.592316 -289.208271) (xy 110.555593 -289.244994)
			(xy 110.513577 -289.27552) (xy 110.467303 -289.299098) (xy 110.41791 -289.315146) (xy 110.366615 -289.323271)
			(xy 110.314681 -289.323271) (xy 110.263386 -289.315146) (xy 110.213993 -289.299098) (xy 110.167719 -289.27552)
			(xy 110.125703 -289.244994) (xy 110.08898 -289.208271) (xy 110.058454 -289.166255) (xy 110.034876 -289.119981)
			(xy 110.018828 -289.070588) (xy 110.010703 -289.019293) (xy 110.010194 -288.993326) (xy 109.142848 -288.993326)
			(xy 109.154393 -289.005296) (xy 109.182429 -289.044346) (xy 109.203706 -289.087453) (xy 109.217651 -289.133458)
			(xy 109.223889 -289.181123) (xy 109.223556 -289.205162) (xy 109.223314 -289.215762) (xy 109.215463 -289.235432)
			(xy 109.208316 -289.243262) (xy 109.200833 -289.250171) (xy 109.182042 -289.257981) (xy 109.161692 -289.257981)
			(xy 109.142901 -289.250171) (xy 109.135418 -289.243262) (xy 109.130274 -289.23767) (xy 109.123173 -289.224245)
			(xy 109.121448 -289.216846) (xy 109.121448 -289.18535) (xy 109.120135 -289.167852) (xy 109.111898 -289.133746)
			(xy 109.097594 -289.101708) (xy 109.0777 -289.072806) (xy 109.065568 -289.060128) (xy 109.052011 -289.047177)
			(xy 109.02084 -289.02635) (xy 108.986206 -289.012004) (xy 108.949438 -289.00469) (xy 108.91195 -289.00469)
			(xy 108.875182 -289.012004) (xy 108.840548 -289.02635) (xy 108.809377 -289.047177) (xy 108.79582 -289.060128)
			(xy 108.783012 -289.073637) (xy 108.762311 -289.104569) (xy 108.747967 -289.138913) (xy 108.740518 -289.17538)
			(xy 108.73994 -289.193986) (xy 108.73994 -289.216084) (xy 108.738233 -289.223433) (xy 108.731122 -289.236733)
			(xy 108.72597 -289.242246) (xy 108.718487 -289.249155) (xy 108.699696 -289.256965) (xy 108.679346 -289.256965)
			(xy 108.660555 -289.249155) (xy 108.653072 -289.242246) (xy 108.645673 -289.234208) (xy 108.637922 -289.213801)
			(xy 108.638086 -289.202876) (xy 108.637879 -289.179077) (xy 108.283821 -289.179077) (xy 108.284089 -289.181123)
			(xy 108.283756 -289.205162) (xy 108.283514 -289.215762) (xy 108.275663 -289.235432) (xy 108.268516 -289.243262)
			(xy 108.261033 -289.250171) (xy 108.242242 -289.257981) (xy 108.221892 -289.257981) (xy 108.203101 -289.250171)
			(xy 108.195618 -289.243262) (xy 108.190474 -289.23767) (xy 108.183373 -289.224245) (xy 108.181648 -289.216846)
			(xy 108.181648 -289.18535) (xy 108.180335 -289.167852) (xy 108.172098 -289.133746) (xy 108.157794 -289.101708)
			(xy 108.1379 -289.072806) (xy 108.125768 -289.060128) (xy 108.112211 -289.047177) (xy 108.08104 -289.02635)
			(xy 108.046406 -289.012004) (xy 108.009638 -289.00469) (xy 107.97215 -289.00469) (xy 107.935382 -289.012004)
			(xy 107.900748 -289.02635) (xy 107.869577 -289.047177) (xy 107.85602 -289.060128) (xy 107.843212 -289.073637)
			(xy 107.822511 -289.104569) (xy 107.808167 -289.138913) (xy 107.800718 -289.17538) (xy 107.80014 -289.193986)
			(xy 107.80014 -289.216084) (xy 107.798433 -289.223433) (xy 107.791322 -289.236733) (xy 107.78617 -289.242246)
			(xy 107.778687 -289.249155) (xy 107.759896 -289.256965) (xy 107.739546 -289.256965) (xy 107.720755 -289.249155)
			(xy 107.713272 -289.242246) (xy 107.709208 -289.23742) (xy 107.701974 -289.228887) (xy 107.682107 -289.218652)
			(xy 107.659773 -289.217831) (xy 107.649264 -289.221672) (xy 107.628923 -289.229853) (xy 107.586622 -289.241377)
			(xy 107.543169 -289.247207) (xy 107.521248 -289.24758) (xy 107.499377 -289.247227) (xy 107.456014 -289.241484)
			(xy 107.413793 -289.230055) (xy 107.393486 -289.221926) (xy 107.382918 -289.218085) (xy 107.360478 -289.218981)
			(xy 107.340558 -289.22935) (xy 107.333288 -289.237928) (xy 107.328716 -289.243262) (xy 107.321233 -289.250171)
			(xy 107.302442 -289.257981) (xy 107.282092 -289.257981) (xy 107.263301 -289.250171) (xy 107.255818 -289.243262)
			(xy 107.250674 -289.23767) (xy 107.243573 -289.224245) (xy 107.241848 -289.216846) (xy 107.241848 -289.18535)
			(xy 107.240535 -289.167852) (xy 107.232298 -289.133746) (xy 107.217994 -289.101708) (xy 107.1981 -289.072806)
			(xy 107.185968 -289.060128) (xy 107.172411 -289.047177) (xy 107.14124 -289.02635) (xy 107.106606 -289.012004)
			(xy 107.069838 -289.00469) (xy 107.03235 -289.00469) (xy 106.995582 -289.012004) (xy 106.960948 -289.02635)
			(xy 106.929777 -289.047177) (xy 106.91622 -289.060128) (xy 106.903412 -289.073637) (xy 106.882711 -289.104569)
			(xy 106.868367 -289.138913) (xy 106.860918 -289.17538) (xy 106.86034 -289.193986) (xy 106.86034 -289.216084)
			(xy 106.858633 -289.223433) (xy 106.851522 -289.236733) (xy 106.84637 -289.242246) (xy 106.838887 -289.249155)
			(xy 106.820096 -289.256965) (xy 106.799746 -289.256965) (xy 106.780955 -289.249155) (xy 106.773472 -289.242246)
			(xy 106.766073 -289.234208) (xy 106.758322 -289.213801) (xy 106.758486 -289.202876) (xy 106.758279 -289.179077)
			(xy 106.404221 -289.179077) (xy 106.404489 -289.181123) (xy 106.404156 -289.205162) (xy 106.403914 -289.215762)
			(xy 106.396063 -289.235432) (xy 106.388916 -289.243262) (xy 106.381433 -289.250171) (xy 106.362642 -289.257981)
			(xy 106.342292 -289.257981) (xy 106.323501 -289.250171) (xy 106.316018 -289.243262) (xy 106.310874 -289.23767)
			(xy 106.303773 -289.224245) (xy 106.302048 -289.216846) (xy 106.302048 -289.18535) (xy 106.300735 -289.167852)
			(xy 106.292498 -289.133746) (xy 106.278194 -289.101708) (xy 106.2583 -289.072806) (xy 106.246168 -289.060128)
			(xy 106.232611 -289.047177) (xy 106.20144 -289.02635) (xy 106.166806 -289.012004) (xy 106.130038 -289.00469)
			(xy 106.09255 -289.00469) (xy 106.055782 -289.012004) (xy 106.021148 -289.02635) (xy 105.989977 -289.047177)
			(xy 105.97642 -289.060128) (xy 105.963612 -289.073637) (xy 105.942911 -289.104569) (xy 105.928567 -289.138913)
			(xy 105.921118 -289.17538) (xy 105.92054 -289.193986) (xy 105.92054 -289.216084) (xy 105.918833 -289.223433)
			(xy 105.911722 -289.236733) (xy 105.90657 -289.242246) (xy 105.899087 -289.249155) (xy 105.880296 -289.256965)
			(xy 105.859946 -289.256965) (xy 105.841155 -289.249155) (xy 105.833672 -289.242246) (xy 105.826273 -289.234208)
			(xy 105.818522 -289.213801) (xy 105.818686 -289.202876) (xy 105.818479 -289.179077) (xy 105.464405 -289.179077)
			(xy 105.464575 -289.180378) (xy 105.464356 -289.203638) (xy 105.464511 -289.214653) (xy 105.456617 -289.235195)
			(xy 105.449116 -289.243262) (xy 105.447846 -289.244532) (xy 105.43952 -289.251588) (xy 105.418865 -289.258573)
			(xy 105.407968 -289.257994) (xy 105.399086 -289.256821) (xy 105.382845 -289.24929) (xy 105.376218 -289.243262)
			(xy 105.371051 -289.237686) (xy 105.363941 -289.224257) (xy 105.362248 -289.216846) (xy 105.362248 -289.183826)
			(xy 105.361994 -289.181794) (xy 105.359815 -289.159802) (xy 105.346695 -289.117612) (xy 105.324255 -289.079553)
			(xy 105.309416 -289.063176) (xy 105.306368 -289.060128) (xy 105.292811 -289.047177) (xy 105.26164 -289.02635)
			(xy 105.227006 -289.012004) (xy 105.190238 -289.00469) (xy 105.15275 -289.00469) (xy 105.115982 -289.012004)
			(xy 105.081348 -289.02635) (xy 105.050177 -289.047177) (xy 105.03662 -289.060128) (xy 105.023811 -289.073595)
			(xy 105.003133 -289.104472) (xy 104.988788 -289.138753) (xy 104.981314 -289.175156) (xy 104.98074 -289.193732)
			(xy 104.98074 -289.215576) (xy 104.979588 -289.221029) (xy 104.975232 -289.231284) (xy 104.972104 -289.235896)
			(xy 104.964992 -289.245802) (xy 104.95407 -289.25139) (xy 104.950288 -289.253308) (xy 104.942245 -289.255992)
			(xy 104.938068 -289.256724) (xy 104.929224 -289.258454) (xy 104.913484 -289.267205) (xy 104.901757 -289.280872)
			(xy 104.895498 -289.297758) (xy 104.895142 -289.306762) (xy 104.895142 -289.632898) (xy 104.894718 -289.642967)
			(xy 104.886997 -289.661567) (xy 104.880156 -289.668966) (xy 104.047798 -290.501324) (xy 104.040403 -290.508178)
			(xy 104.021804 -290.515924) (xy 104.01173 -290.51631) (xy 87.37981 -290.51631) (xy 87.364824 -290.531296)
			(xy 86.752684 -291.143182) (xy 86.737698 -291.158168) (xy 86.737698 -297.515026) (xy 88.21548 -297.515026)
			(xy 88.219461 -297.382006) (xy 88.23139 -297.249461) (xy 88.251225 -297.117868) (xy 88.278894 -296.987696)
			(xy 88.314298 -296.859411) (xy 88.357311 -296.733474) (xy 88.407778 -296.610335) (xy 88.465519 -296.490434)
			(xy 88.530328 -296.374201) (xy 88.601972 -296.262051) (xy 88.680194 -296.154387) (xy 88.764715 -296.051594)
			(xy 88.855233 -295.954039) (xy 88.951422 -295.862073) (xy 89.05294 -295.776023) (xy 89.159421 -295.696199)
			(xy 89.270486 -295.622886) (xy 89.385737 -295.556346) (xy 89.504761 -295.496817) (xy 89.627132 -295.444513)
			(xy 89.752411 -295.399621) (xy 89.880152 -295.362302) (xy 90.009895 -295.332689) (xy 90.141177 -295.310888)
			(xy 90.273528 -295.296978) (xy 90.406474 -295.291007) (xy 90.539539 -295.292998) (xy 90.672247 -295.302943)
			(xy 90.804123 -295.320807) (xy 90.934694 -295.346525) (xy 91.063494 -295.380006) (xy 91.19006 -295.42113)
			(xy 91.313941 -295.46975) (xy 91.434692 -295.525691) (xy 91.551882 -295.588753) (xy 91.665091 -295.658711)
			(xy 91.773913 -295.735315) (xy 91.877959 -295.818289) (xy 91.976857 -295.907337) (xy 92.070252 -296.00214)
			(xy 92.15781 -296.102358) (xy 92.239219 -296.207634) (xy 92.314185 -296.31759) (xy 92.382442 -296.431832)
			(xy 92.443744 -296.549952) (xy 92.497873 -296.671527) (xy 92.544634 -296.796121) (xy 92.58386 -296.923289)
			(xy 92.61541 -297.052575) (xy 92.639173 -297.183516) (xy 92.650357 -297.27652) (xy 103.094028 -297.27652)
			(xy 103.094028 -292.73754) (xy 103.415846 -292.415976) (xy 104.981756 -292.415976) (xy 105.27284 -292.70706)
			(xy 105.27284 -297.28795) (xy 108.670852 -297.28795) (xy 108.670852 -292.72103) (xy 109.000036 -292.391592)
			(xy 111.293656 -292.391592) (xy 111.624364 -292.7223) (xy 111.624364 -297.28795) (xy 115.020852 -297.28795)
			(xy 115.020852 -292.72103) (xy 115.350036 -292.391592) (xy 117.643656 -292.391592) (xy 117.966744 -292.71468)
			(xy 117.966744 -292.95598) (xy 122.307602 -292.95598) (xy 122.311673 -292.900358) (xy 122.323799 -292.845921)
			(xy 122.343722 -292.79383) (xy 122.371018 -292.745195) (xy 122.405104 -292.701052) (xy 122.445253 -292.662343)
			(xy 122.490611 -292.629892) (xy 122.540211 -292.604391) (xy 122.592995 -292.586384) (xy 122.647838 -292.576254)
			(xy 122.703572 -292.574217) (xy 122.759009 -292.580317) (xy 122.812966 -292.594423) (xy 122.864295 -292.616235)
			(xy 122.911901 -292.645289) (xy 122.954769 -292.680964) (xy 122.991986 -292.722501) (xy 123.022759 -292.769014)
			(xy 123.046431 -292.819511) (xy 123.062499 -292.872918) (xy 123.070619 -292.928094) (xy 123.071128 -292.95598)
			(xy 123.070619 -292.983866) (xy 123.062499 -293.039042) (xy 123.046431 -293.092449) (xy 123.022759 -293.142946)
			(xy 122.991986 -293.189459) (xy 122.954769 -293.230996) (xy 122.911901 -293.266671) (xy 122.864295 -293.295725)
			(xy 122.812966 -293.317537) (xy 122.759009 -293.331643) (xy 122.703572 -293.337743) (xy 122.647838 -293.335706)
			(xy 122.592995 -293.325576) (xy 122.540211 -293.307569) (xy 122.490611 -293.282068) (xy 122.445253 -293.249617)
			(xy 122.405104 -293.210908) (xy 122.371018 -293.166765) (xy 122.343722 -293.11813) (xy 122.323799 -293.066039)
			(xy 122.311673 -293.011602) (xy 122.307602 -292.95598) (xy 117.966744 -292.95598) (xy 117.966744 -295.03878)
			(xy 122.307602 -295.03878) (xy 122.311673 -294.983158) (xy 122.323799 -294.928721) (xy 122.343722 -294.87663)
			(xy 122.371018 -294.827995) (xy 122.405104 -294.783852) (xy 122.445253 -294.745143) (xy 122.490611 -294.712692)
			(xy 122.540211 -294.687191) (xy 122.592995 -294.669184) (xy 122.647838 -294.659054) (xy 122.703572 -294.657017)
			(xy 122.759009 -294.663117) (xy 122.812966 -294.677223) (xy 122.864295 -294.699035) (xy 122.911901 -294.728089)
			(xy 122.954769 -294.763764) (xy 122.991986 -294.805301) (xy 123.022759 -294.851814) (xy 123.046431 -294.902311)
			(xy 123.062499 -294.955718) (xy 123.070619 -295.010894) (xy 123.071128 -295.03878) (xy 123.070619 -295.066666)
			(xy 123.062499 -295.121842) (xy 123.046431 -295.175249) (xy 123.022759 -295.225746) (xy 122.991986 -295.272259)
			(xy 122.954769 -295.313796) (xy 122.911901 -295.349471) (xy 122.864295 -295.378525) (xy 122.812966 -295.400337)
			(xy 122.759009 -295.414443) (xy 122.703572 -295.420543) (xy 122.647838 -295.418506) (xy 122.592995 -295.408376)
			(xy 122.540211 -295.390369) (xy 122.490611 -295.364868) (xy 122.445253 -295.332417) (xy 122.405104 -295.293708)
			(xy 122.371018 -295.249565) (xy 122.343722 -295.20093) (xy 122.323799 -295.148839) (xy 122.311673 -295.094402)
			(xy 122.307602 -295.03878) (xy 117.966744 -295.03878) (xy 117.966744 -297.19778) (xy 122.307602 -297.19778)
			(xy 122.311673 -297.142158) (xy 122.323799 -297.087721) (xy 122.343722 -297.03563) (xy 122.371018 -296.986995)
			(xy 122.405104 -296.942852) (xy 122.445253 -296.904143) (xy 122.490611 -296.871692) (xy 122.540211 -296.846191)
			(xy 122.592995 -296.828184) (xy 122.647838 -296.818054) (xy 122.703572 -296.816017) (xy 122.759009 -296.822117)
			(xy 122.812966 -296.836223) (xy 122.864295 -296.858035) (xy 122.911901 -296.887089) (xy 122.954769 -296.922764)
			(xy 122.991986 -296.964301) (xy 123.022759 -297.010814) (xy 123.046431 -297.061311) (xy 123.062499 -297.114718)
			(xy 123.070619 -297.169894) (xy 123.071128 -297.19778) (xy 123.070619 -297.225666) (xy 123.062499 -297.280842)
			(xy 123.046431 -297.334249) (xy 123.022759 -297.384746) (xy 122.991986 -297.431259) (xy 122.954769 -297.472796)
			(xy 122.911901 -297.508471) (xy 122.90116 -297.515026) (xy 131.195582 -297.515026) (xy 131.199563 -297.382006)
			(xy 131.211492 -297.249461) (xy 131.231327 -297.117868) (xy 131.258996 -296.987696) (xy 131.2944 -296.859411)
			(xy 131.337413 -296.733474) (xy 131.38788 -296.610335) (xy 131.445621 -296.490434) (xy 131.51043 -296.374201)
			(xy 131.582074 -296.262051) (xy 131.660296 -296.154387) (xy 131.744817 -296.051594) (xy 131.835335 -295.954039)
			(xy 131.931524 -295.862073) (xy 132.033042 -295.776023) (xy 132.139523 -295.696199) (xy 132.250588 -295.622886)
			(xy 132.365839 -295.556346) (xy 132.484863 -295.496817) (xy 132.607234 -295.444513) (xy 132.732513 -295.399621)
			(xy 132.860254 -295.362302) (xy 132.989997 -295.332689) (xy 133.121279 -295.310888) (xy 133.25363 -295.296978)
			(xy 133.386576 -295.291007) (xy 133.519641 -295.292998) (xy 133.652349 -295.302943) (xy 133.784225 -295.320807)
			(xy 133.914796 -295.346525) (xy 134.043596 -295.380006) (xy 134.170162 -295.42113) (xy 134.294043 -295.46975)
			(xy 134.414794 -295.525691) (xy 134.531984 -295.588753) (xy 134.645193 -295.658711) (xy 134.754015 -295.735315)
			(xy 134.858061 -295.818289) (xy 134.956959 -295.907337) (xy 135.050354 -296.00214) (xy 135.137912 -296.102358)
			(xy 135.219321 -296.207634) (xy 135.294287 -296.31759) (xy 135.362544 -296.431832) (xy 135.423846 -296.549952)
			(xy 135.477975 -296.671527) (xy 135.524736 -296.796121) (xy 135.563962 -296.923289) (xy 135.595512 -297.052575)
			(xy 135.619275 -297.183516) (xy 135.635164 -297.315644) (xy 135.643122 -297.448486) (xy 135.64362 -297.515026)
			(xy 135.643122 -297.581566) (xy 135.635164 -297.714408) (xy 135.619275 -297.846536) (xy 135.595512 -297.977477)
			(xy 135.563962 -298.106763) (xy 135.524736 -298.233931) (xy 135.477975 -298.358525) (xy 135.423846 -298.4801)
			(xy 135.362544 -298.59822) (xy 135.294287 -298.712462) (xy 135.219321 -298.822418) (xy 135.137912 -298.927694)
			(xy 135.050354 -299.027912) (xy 134.956959 -299.122715) (xy 134.858061 -299.211763) (xy 134.754015 -299.294737)
			(xy 134.645193 -299.371341) (xy 134.531984 -299.441299) (xy 134.414794 -299.504361) (xy 134.294043 -299.560302)
			(xy 134.170162 -299.608922) (xy 134.043596 -299.650046) (xy 133.914796 -299.683527) (xy 133.784225 -299.709245)
			(xy 133.652349 -299.727109) (xy 133.519641 -299.737054) (xy 133.386576 -299.739045) (xy 133.25363 -299.733074)
			(xy 133.121279 -299.719164) (xy 132.989997 -299.697363) (xy 132.860254 -299.66775) (xy 132.732513 -299.630431)
			(xy 132.607234 -299.585539) (xy 132.484863 -299.533235) (xy 132.365839 -299.473706) (xy 132.250588 -299.407166)
			(xy 132.139523 -299.333853) (xy 132.033042 -299.254029) (xy 131.931524 -299.167979) (xy 131.835335 -299.076013)
			(xy 131.744817 -298.978458) (xy 131.660296 -298.875665) (xy 131.582074 -298.768001) (xy 131.51043 -298.655851)
			(xy 131.445621 -298.539618) (xy 131.38788 -298.419717) (xy 131.337413 -298.296578) (xy 131.2944 -298.170641)
			(xy 131.258996 -298.042356) (xy 131.231327 -297.912184) (xy 131.211492 -297.780591) (xy 131.199563 -297.648046)
			(xy 131.195582 -297.515026) (xy 122.90116 -297.515026) (xy 122.864295 -297.537525) (xy 122.812966 -297.559337)
			(xy 122.759009 -297.573443) (xy 122.703572 -297.579543) (xy 122.647838 -297.577506) (xy 122.592995 -297.567376)
			(xy 122.540211 -297.549369) (xy 122.490611 -297.523868) (xy 122.445253 -297.491417) (xy 122.405104 -297.452708)
			(xy 122.371018 -297.408565) (xy 122.343722 -297.35993) (xy 122.323799 -297.307839) (xy 122.311673 -297.253402)
			(xy 122.307602 -297.19778) (xy 117.966744 -297.19778) (xy 117.966744 -297.38574) (xy 117.623336 -297.729148)
			(xy 115.461796 -297.729148) (xy 115.020852 -297.28795) (xy 111.624364 -297.28795) (xy 111.624364 -297.37812)
			(xy 111.273336 -297.729148) (xy 109.111796 -297.729148) (xy 108.670852 -297.28795) (xy 105.27284 -297.28795)
			(xy 105.27284 -297.30827) (xy 104.983026 -297.598084) (xy 103.415846 -297.598084) (xy 103.094028 -297.27652)
			(xy 92.650357 -297.27652) (xy 92.655062 -297.315644) (xy 92.66302 -297.448486) (xy 92.663518 -297.515026)
			(xy 92.66302 -297.581566) (xy 92.655062 -297.714408) (xy 92.639173 -297.846536) (xy 92.61541 -297.977477)
			(xy 92.58386 -298.106763) (xy 92.544634 -298.233931) (xy 92.497873 -298.358525) (xy 92.443744 -298.4801)
			(xy 92.382442 -298.59822) (xy 92.314185 -298.712462) (xy 92.239219 -298.822418) (xy 92.15781 -298.927694)
			(xy 92.070252 -299.027912) (xy 91.976857 -299.122715) (xy 91.877959 -299.211763) (xy 91.773913 -299.294737)
			(xy 91.665091 -299.371341) (xy 91.551882 -299.441299) (xy 91.434692 -299.504361) (xy 91.313941 -299.560302)
			(xy 91.19006 -299.608922) (xy 91.063494 -299.650046) (xy 90.934694 -299.683527) (xy 90.804123 -299.709245)
			(xy 90.672247 -299.727109) (xy 90.539539 -299.737054) (xy 90.406474 -299.739045) (xy 90.273528 -299.733074)
			(xy 90.141177 -299.719164) (xy 90.009895 -299.697363) (xy 89.880152 -299.66775) (xy 89.752411 -299.630431)
			(xy 89.627132 -299.585539) (xy 89.504761 -299.533235) (xy 89.385737 -299.473706) (xy 89.270486 -299.407166)
			(xy 89.159421 -299.333853) (xy 89.05294 -299.254029) (xy 88.951422 -299.167979) (xy 88.855233 -299.076013)
			(xy 88.764715 -298.978458) (xy 88.680194 -298.875665) (xy 88.601972 -298.768001) (xy 88.530328 -298.655851)
			(xy 88.465519 -298.539618) (xy 88.407778 -298.419717) (xy 88.357311 -298.296578) (xy 88.314298 -298.170641)
			(xy 88.278894 -298.042356) (xy 88.251225 -297.912184) (xy 88.23139 -297.780591) (xy 88.219461 -297.648046)
			(xy 88.21548 -297.515026) (xy 86.737698 -297.515026) (xy 86.737698 -302.351948) (xy 72.634856 -316.45479)
			(xy 97.636584 -316.45479) (xy 97.636584 -314.87999) (xy 97.636934 -314.866629) (xy 97.643854 -314.840819)
			(xy 97.657219 -314.81768) (xy 97.676119 -314.79879) (xy 97.699264 -314.785435) (xy 97.725077 -314.778528)
			(xy 97.738438 -314.778136) (xy 99.313238 -314.778136) (xy 99.326591 -314.778548) (xy 99.352385 -314.785468)
			(xy 99.37551 -314.798826) (xy 99.394391 -314.817713) (xy 99.407743 -314.840841) (xy 99.414655 -314.866637)
			(xy 99.415092 -314.87999) (xy 99.415092 -315.66739) (xy 99.610423 -315.66739) (xy 99.614445 -315.58167)
			(xy 99.626476 -315.496702) (xy 99.646412 -315.413235) (xy 99.674075 -315.332001) (xy 99.709224 -315.253715)
			(xy 99.75155 -315.179064) (xy 99.800679 -315.108705) (xy 99.856182 -315.043255) (xy 99.917569 -314.983291)
			(xy 99.984302 -314.929338) (xy 100.055794 -314.881871) (xy 100.131416 -314.841307) (xy 100.210505 -314.808003)
			(xy 100.292365 -314.782251) (xy 100.376276 -314.764278) (xy 100.461502 -314.754242) (xy 100.547294 -314.75223)
			(xy 100.632896 -314.758261) (xy 100.717558 -314.772281) (xy 100.800535 -314.794167) (xy 100.881098 -314.823728)
			(xy 100.958538 -314.860702) (xy 101.032177 -314.904766) (xy 101.101365 -314.955532) (xy 101.165496 -315.012553)
			(xy 101.224005 -315.075329) (xy 101.276378 -315.143309) (xy 101.322156 -315.215894) (xy 101.360936 -315.292446)
			(xy 101.392377 -315.372294) (xy 101.416203 -315.454735) (xy 101.432204 -315.539045) (xy 101.440239 -315.624483)
			(xy 101.440742 -315.66739) (xy 101.440239 -315.710297) (xy 101.432204 -315.795735) (xy 101.416203 -315.880045)
			(xy 101.392377 -315.962486) (xy 101.360936 -316.042334) (xy 101.322156 -316.118886) (xy 101.276378 -316.191471)
			(xy 101.224005 -316.259451) (xy 101.165496 -316.322227) (xy 101.101365 -316.379248) (xy 101.032177 -316.430014)
			(xy 100.990772 -316.45479) (xy 103.834184 -316.45479) (xy 103.834184 -314.87999) (xy 103.834534 -314.866629)
			(xy 103.841454 -314.840819) (xy 103.854819 -314.81768) (xy 103.873719 -314.79879) (xy 103.896864 -314.785435)
			(xy 103.922677 -314.778528) (xy 103.936038 -314.778136) (xy 105.510838 -314.778136) (xy 105.524191 -314.778548)
			(xy 105.549985 -314.785468) (xy 105.57311 -314.798826) (xy 105.591991 -314.817713) (xy 105.605343 -314.840841)
			(xy 105.612255 -314.866637) (xy 105.612692 -314.87999) (xy 105.612692 -315.66739) (xy 105.808023 -315.66739)
			(xy 105.812045 -315.58167) (xy 105.824076 -315.496702) (xy 105.844012 -315.413235) (xy 105.871675 -315.332001)
			(xy 105.906824 -315.253715) (xy 105.94915 -315.179064) (xy 105.998279 -315.108705) (xy 106.053782 -315.043255)
			(xy 106.115169 -314.983291) (xy 106.181902 -314.929338) (xy 106.253394 -314.881871) (xy 106.329016 -314.841307)
			(xy 106.408105 -314.808003) (xy 106.489965 -314.782251) (xy 106.573876 -314.764278) (xy 106.659102 -314.754242)
			(xy 106.744894 -314.75223) (xy 106.830496 -314.758261) (xy 106.915158 -314.772281) (xy 106.998135 -314.794167)
			(xy 107.078698 -314.823728) (xy 107.156138 -314.860702) (xy 107.229777 -314.904766) (xy 107.298965 -314.955532)
			(xy 107.363096 -315.012553) (xy 107.421605 -315.075329) (xy 107.473978 -315.143309) (xy 107.519756 -315.215894)
			(xy 107.558536 -315.292446) (xy 107.589977 -315.372294) (xy 107.613803 -315.454735) (xy 107.629804 -315.539045)
			(xy 107.637839 -315.624483) (xy 107.638342 -315.66739) (xy 107.637839 -315.710297) (xy 107.629804 -315.795735)
			(xy 107.613803 -315.880045) (xy 107.589977 -315.962486) (xy 107.558536 -316.042334) (xy 107.519756 -316.118886)
			(xy 107.473978 -316.191471) (xy 107.421605 -316.259451) (xy 107.363096 -316.322227) (xy 107.298965 -316.379248)
			(xy 107.229777 -316.430014) (xy 107.188372 -316.45479) (xy 110.011972 -316.45479) (xy 110.011972 -314.87999)
			(xy 110.012334 -314.86663) (xy 110.019253 -314.840822) (xy 110.032616 -314.817684) (xy 110.051513 -314.798794)
			(xy 110.074655 -314.785439) (xy 110.100466 -314.778529) (xy 110.113826 -314.778136) (xy 111.688626 -314.778136)
			(xy 111.701978 -314.778559) (xy 111.727772 -314.785476) (xy 111.750897 -314.798831) (xy 111.769779 -314.817716)
			(xy 111.783131 -314.840843) (xy 111.790043 -314.866638) (xy 111.79048 -314.87999) (xy 111.79048 -315.66739)
			(xy 111.985811 -315.66739) (xy 111.989833 -315.58167) (xy 112.001864 -315.496702) (xy 112.0218 -315.413235)
			(xy 112.049463 -315.332001) (xy 112.084612 -315.253715) (xy 112.126938 -315.179064) (xy 112.176067 -315.108705)
			(xy 112.23157 -315.043255) (xy 112.292957 -314.983291) (xy 112.35969 -314.929338) (xy 112.431182 -314.881871)
			(xy 112.506804 -314.841307) (xy 112.585893 -314.808003) (xy 112.667753 -314.782251) (xy 112.751664 -314.764278)
			(xy 112.83689 -314.754242) (xy 112.922682 -314.75223) (xy 113.008284 -314.758261) (xy 113.092946 -314.772281)
			(xy 113.175923 -314.794167) (xy 113.256486 -314.823728) (xy 113.333926 -314.860702) (xy 113.407565 -314.904766)
			(xy 113.476753 -314.955532) (xy 113.540884 -315.012553) (xy 113.599393 -315.075329) (xy 113.651766 -315.143309)
			(xy 113.697544 -315.215894) (xy 113.736324 -315.292446) (xy 113.767765 -315.372294) (xy 113.791591 -315.454735)
			(xy 113.807592 -315.539045) (xy 113.815627 -315.624483) (xy 113.81613 -315.66739) (xy 113.815627 -315.710297)
			(xy 113.807592 -315.795735) (xy 113.791591 -315.880045) (xy 113.767765 -315.962486) (xy 113.736324 -316.042334)
			(xy 113.697544 -316.118886) (xy 113.651766 -316.191471) (xy 113.599393 -316.259451) (xy 113.540884 -316.322227)
			(xy 113.476753 -316.379248) (xy 113.407565 -316.430014) (xy 113.36616 -316.45479) (xy 116.209572 -316.45479)
			(xy 116.209572 -314.87999) (xy 116.209934 -314.86663) (xy 116.216853 -314.840822) (xy 116.230216 -314.817684)
			(xy 116.249113 -314.798794) (xy 116.272255 -314.785439) (xy 116.298066 -314.778529) (xy 116.311426 -314.778136)
			(xy 117.886226 -314.778136) (xy 117.899578 -314.778559) (xy 117.925372 -314.785476) (xy 117.948497 -314.798831)
			(xy 117.967379 -314.817716) (xy 117.980731 -314.840843) (xy 117.987643 -314.866638) (xy 117.98808 -314.87999)
			(xy 117.98808 -315.66739) (xy 118.183411 -315.66739) (xy 118.187433 -315.58167) (xy 118.199464 -315.496702)
			(xy 118.2194 -315.413235) (xy 118.247063 -315.332001) (xy 118.282212 -315.253715) (xy 118.324538 -315.179064)
			(xy 118.373667 -315.108705) (xy 118.42917 -315.043255) (xy 118.490557 -314.983291) (xy 118.55729 -314.929338)
			(xy 118.628782 -314.881871) (xy 118.704404 -314.841307) (xy 118.783493 -314.808003) (xy 118.865353 -314.782251)
			(xy 118.949264 -314.764278) (xy 119.03449 -314.754242) (xy 119.120282 -314.75223) (xy 119.205884 -314.758261)
			(xy 119.290546 -314.772281) (xy 119.373523 -314.794167) (xy 119.454086 -314.823728) (xy 119.531526 -314.860702)
			(xy 119.605165 -314.904766) (xy 119.674353 -314.955532) (xy 119.738484 -315.012553) (xy 119.796993 -315.075329)
			(xy 119.849366 -315.143309) (xy 119.895144 -315.215894) (xy 119.933924 -315.292446) (xy 119.965365 -315.372294)
			(xy 119.989191 -315.454735) (xy 120.005192 -315.539045) (xy 120.013227 -315.624483) (xy 120.01373 -315.66739)
			(xy 120.013227 -315.710297) (xy 120.005192 -315.795735) (xy 119.989191 -315.880045) (xy 119.965365 -315.962486)
			(xy 119.933924 -316.042334) (xy 119.895144 -316.118886) (xy 119.849366 -316.191471) (xy 119.796993 -316.259451)
			(xy 119.738484 -316.322227) (xy 119.674353 -316.379248) (xy 119.605165 -316.430014) (xy 119.56376 -316.45479)
			(xy 122.407172 -316.45479) (xy 122.407172 -314.87999) (xy 122.407534 -314.86663) (xy 122.414453 -314.840822)
			(xy 122.427816 -314.817684) (xy 122.446713 -314.798794) (xy 122.469855 -314.785439) (xy 122.495666 -314.778529)
			(xy 122.509026 -314.778136) (xy 124.083826 -314.778136) (xy 124.097178 -314.778559) (xy 124.122972 -314.785476)
			(xy 124.146097 -314.798831) (xy 124.164979 -314.817716) (xy 124.178331 -314.840843) (xy 124.185243 -314.866638)
			(xy 124.18568 -314.87999) (xy 124.18568 -315.66739) (xy 124.381011 -315.66739) (xy 124.385033 -315.58167)
			(xy 124.397064 -315.496702) (xy 124.417 -315.413235) (xy 124.444663 -315.332001) (xy 124.479812 -315.253715)
			(xy 124.522138 -315.179064) (xy 124.571267 -315.108705) (xy 124.62677 -315.043255) (xy 124.688157 -314.983291)
			(xy 124.75489 -314.929338) (xy 124.826382 -314.881871) (xy 124.902004 -314.841307) (xy 124.981093 -314.808003)
			(xy 125.062953 -314.782251) (xy 125.146864 -314.764278) (xy 125.23209 -314.754242) (xy 125.317882 -314.75223)
			(xy 125.403484 -314.758261) (xy 125.488146 -314.772281) (xy 125.571123 -314.794167) (xy 125.651686 -314.823728)
			(xy 125.729126 -314.860702) (xy 125.802765 -314.904766) (xy 125.871953 -314.955532) (xy 125.936084 -315.012553)
			(xy 125.994593 -315.075329) (xy 126.046966 -315.143309) (xy 126.092744 -315.215894) (xy 126.131524 -315.292446)
			(xy 126.162965 -315.372294) (xy 126.186791 -315.454735) (xy 126.202792 -315.539045) (xy 126.210827 -315.624483)
			(xy 126.21133 -315.66739) (xy 126.210827 -315.710297) (xy 126.202792 -315.795735) (xy 126.186791 -315.880045)
			(xy 126.162965 -315.962486) (xy 126.131524 -316.042334) (xy 126.092744 -316.118886) (xy 126.046966 -316.191471)
			(xy 125.994593 -316.259451) (xy 125.936084 -316.322227) (xy 125.871953 -316.379248) (xy 125.802765 -316.430014)
			(xy 125.729126 -316.474078) (xy 125.651686 -316.511052) (xy 125.571123 -316.540613) (xy 125.488146 -316.562499)
			(xy 125.403484 -316.576519) (xy 125.317882 -316.58255) (xy 125.23209 -316.580538) (xy 125.146864 -316.570502)
			(xy 125.062953 -316.552529) (xy 124.981093 -316.526777) (xy 124.902004 -316.493473) (xy 124.826382 -316.452909)
			(xy 124.75489 -316.405442) (xy 124.688157 -316.351489) (xy 124.62677 -316.291525) (xy 124.571267 -316.226075)
			(xy 124.522138 -316.155716) (xy 124.479812 -316.081065) (xy 124.444663 -316.002779) (xy 124.417 -315.921545)
			(xy 124.397064 -315.838078) (xy 124.385033 -315.75311) (xy 124.381011 -315.66739) (xy 124.18568 -315.66739)
			(xy 124.18568 -316.45479) (xy 124.18521 -316.468139) (xy 124.178303 -316.493929) (xy 124.164957 -316.517053)
			(xy 124.146082 -316.535935) (xy 124.122963 -316.549289) (xy 124.097175 -316.556205) (xy 124.083826 -316.556644)
			(xy 122.509026 -316.556644) (xy 122.495669 -316.556234) (xy 122.469865 -316.549325) (xy 122.446729 -316.535972)
			(xy 122.427838 -316.517084) (xy 122.414481 -316.49395) (xy 122.407568 -316.468147) (xy 122.407172 -316.45479)
			(xy 119.56376 -316.45479) (xy 119.531526 -316.474078) (xy 119.454086 -316.511052) (xy 119.373523 -316.540613)
			(xy 119.290546 -316.562499) (xy 119.205884 -316.576519) (xy 119.120282 -316.58255) (xy 119.03449 -316.580538)
			(xy 118.949264 -316.570502) (xy 118.865353 -316.552529) (xy 118.783493 -316.526777) (xy 118.704404 -316.493473)
			(xy 118.628782 -316.452909) (xy 118.55729 -316.405442) (xy 118.490557 -316.351489) (xy 118.42917 -316.291525)
			(xy 118.373667 -316.226075) (xy 118.324538 -316.155716) (xy 118.282212 -316.081065) (xy 118.247063 -316.002779)
			(xy 118.2194 -315.921545) (xy 118.199464 -315.838078) (xy 118.187433 -315.75311) (xy 118.183411 -315.66739)
			(xy 117.98808 -315.66739) (xy 117.98808 -316.45479) (xy 117.98761 -316.468139) (xy 117.980703 -316.493929)
			(xy 117.967357 -316.517053) (xy 117.948482 -316.535935) (xy 117.925363 -316.549289) (xy 117.899575 -316.556205)
			(xy 117.886226 -316.556644) (xy 116.311426 -316.556644) (xy 116.298069 -316.556234) (xy 116.272265 -316.549325)
			(xy 116.249129 -316.535972) (xy 116.230238 -316.517084) (xy 116.216881 -316.49395) (xy 116.209968 -316.468147)
			(xy 116.209572 -316.45479) (xy 113.36616 -316.45479) (xy 113.333926 -316.474078) (xy 113.256486 -316.511052)
			(xy 113.175923 -316.540613) (xy 113.092946 -316.562499) (xy 113.008284 -316.576519) (xy 112.922682 -316.58255)
			(xy 112.83689 -316.580538) (xy 112.751664 -316.570502) (xy 112.667753 -316.552529) (xy 112.585893 -316.526777)
			(xy 112.506804 -316.493473) (xy 112.431182 -316.452909) (xy 112.35969 -316.405442) (xy 112.292957 -316.351489)
			(xy 112.23157 -316.291525) (xy 112.176067 -316.226075) (xy 112.126938 -316.155716) (xy 112.084612 -316.081065)
			(xy 112.049463 -316.002779) (xy 112.0218 -315.921545) (xy 112.001864 -315.838078) (xy 111.989833 -315.75311)
			(xy 111.985811 -315.66739) (xy 111.79048 -315.66739) (xy 111.79048 -316.45479) (xy 111.79001 -316.468139)
			(xy 111.783103 -316.493929) (xy 111.769757 -316.517053) (xy 111.750882 -316.535935) (xy 111.727763 -316.549289)
			(xy 111.701975 -316.556205) (xy 111.688626 -316.556644) (xy 110.113826 -316.556644) (xy 110.100469 -316.556234)
			(xy 110.074665 -316.549325) (xy 110.051529 -316.535972) (xy 110.032638 -316.517084) (xy 110.019281 -316.49395)
			(xy 110.012368 -316.468147) (xy 110.011972 -316.45479) (xy 107.188372 -316.45479) (xy 107.156138 -316.474078)
			(xy 107.078698 -316.511052) (xy 106.998135 -316.540613) (xy 106.915158 -316.562499) (xy 106.830496 -316.576519)
			(xy 106.744894 -316.58255) (xy 106.659102 -316.580538) (xy 106.573876 -316.570502) (xy 106.489965 -316.552529)
			(xy 106.408105 -316.526777) (xy 106.329016 -316.493473) (xy 106.253394 -316.452909) (xy 106.181902 -316.405442)
			(xy 106.115169 -316.351489) (xy 106.053782 -316.291525) (xy 105.998279 -316.226075) (xy 105.94915 -316.155716)
			(xy 105.906824 -316.081065) (xy 105.871675 -316.002779) (xy 105.844012 -315.921545) (xy 105.824076 -315.838078)
			(xy 105.812045 -315.75311) (xy 105.808023 -315.66739) (xy 105.612692 -315.66739) (xy 105.612692 -316.45479)
			(xy 105.61221 -316.468138) (xy 105.605304 -316.493926) (xy 105.59196 -316.517049) (xy 105.573087 -316.535931)
			(xy 105.549971 -316.549286) (xy 105.524186 -316.556204) (xy 105.510838 -316.556644) (xy 103.936038 -316.556644)
			(xy 103.922682 -316.556224) (xy 103.896878 -316.549318) (xy 103.873741 -316.535967) (xy 103.85485 -316.517081)
			(xy 103.841493 -316.493948) (xy 103.83458 -316.468146) (xy 103.834184 -316.45479) (xy 100.990772 -316.45479)
			(xy 100.958538 -316.474078) (xy 100.881098 -316.511052) (xy 100.800535 -316.540613) (xy 100.717558 -316.562499)
			(xy 100.632896 -316.576519) (xy 100.547294 -316.58255) (xy 100.461502 -316.580538) (xy 100.376276 -316.570502)
			(xy 100.292365 -316.552529) (xy 100.210505 -316.526777) (xy 100.131416 -316.493473) (xy 100.055794 -316.452909)
			(xy 99.984302 -316.405442) (xy 99.917569 -316.351489) (xy 99.856182 -316.291525) (xy 99.800679 -316.226075)
			(xy 99.75155 -316.155716) (xy 99.709224 -316.081065) (xy 99.674075 -316.002779) (xy 99.646412 -315.921545)
			(xy 99.626476 -315.838078) (xy 99.614445 -315.75311) (xy 99.610423 -315.66739) (xy 99.415092 -315.66739)
			(xy 99.415092 -316.45479) (xy 99.41461 -316.468138) (xy 99.407704 -316.493926) (xy 99.39436 -316.517049)
			(xy 99.375487 -316.535931) (xy 99.352371 -316.549286) (xy 99.326586 -316.556204) (xy 99.313238 -316.556644)
			(xy 97.738438 -316.556644) (xy 97.725082 -316.556224) (xy 97.699278 -316.549318) (xy 97.676141 -316.535967)
			(xy 97.65725 -316.517081) (xy 97.643893 -316.493948) (xy 97.63698 -316.468146) (xy 97.636584 -316.45479)
			(xy 72.634856 -316.45479) (xy 70.1802 -318.909446) (xy 70.1802 -330.95692) (xy 70.25005 -331.02677)
			(xy 70.25005 -331.047598) (xy 70.264782 -331.062584) (xy 70.559422 -331.357224)
		)
		(stroke
			(width 0)
			(type solid)
		)
		(fill yes)
		(layer "F.Cu")
		(net "PVCCIN_CPU1")
	)
	(gr_line
		(start 18.640806 -396.410688)
		(end 18.653506 -396.410688)
		(stroke
			(width 0.06477)
			(type default)
		)
		(layer "F.Cu")
	)
	(gr_line
		(start 18.640806 -395.278102)
		(end 18.640806 -395.610588)
		(stroke
			(width 0.06604)
			(type default)
		)
		(layer "F.Cu")
	)
	(gr_line
		(start 18.653506 -396.410688)
		(end 18.736818 -396.494)
		(stroke
			(width 0.06477)
			(type default)
		)
		(layer "F.Cu")
	)
	(gr_line
		(start 18.654014 -395.264894)
		(end 18.640806 -395.278102)
		(stroke
			(width 0.06604)
			(type default)
		)
		(layer "F.Cu")
	)
	(gr_line
		(start 18.736818 -396.494)
		(end 19.0373 -396.494)
		(stroke
			(width 0.06477)
			(type default)
		)
		(layer "F.Cu")
	)
	(gr_line
		(start 19.0373 -396.494)
		(end 19.284188 -396.740888)
		(stroke
			(width 0.06477)
			(type default)
		)
		(layer "F.Cu")
	)
	(gr_line
		(start 19.154648 -394.763498)
		(end 18.654014 -395.264894)
		(stroke
			(width 0.06604)
			(type default)
		)
		(layer "F.Cu")
	)
	(gr_line
		(start 19.284188 -396.740888)
		(end 19.284188 -396.842996)
		(stroke
			(width 0.06477)
			(type default)
		)
		(layer "F.Cu")
	)
	(gr_line
		(start 19.414998 -394.788644)
		(end 19.915632 -395.290294)
		(stroke
			(width 0.06604)
			(type default)
		)
		(layer "F.Cu")
	)
	(gr_line
		(start 19.414998 -394.762228)
		(end 19.414998 -394.788644)
		(stroke
			(width 0.06604)
			(type default)
		)
		(layer "F.Cu")
	)
	(gr_line
		(start 19.581114 -385.465574)
		(end 19.19859 -385.465574)
		(stroke
			(width 0.06604)
			(type default)
		)
		(layer "F.Cu")
	)
	(gr_line
		(start 19.71675 -396.411958)
		(end 19.284188 -395.979396)
		(stroke
			(width 0.06477)
			(type default)
		)
		(layer "F.Cu")
	)
	(gr_line
		(start 19.84248 -385.784344)
		(end 19.84248 -385.72694)
		(stroke
			(width 0.06604)
			(type default)
		)
		(layer "F.Cu")
	)
	(gr_line
		(start 19.84248 -385.72694)
		(end 19.581114 -385.465574)
		(stroke
			(width 0.06604)
			(type default)
		)
		(layer "F.Cu")
	)
	(gr_line
		(start 19.84248 -384.920744)
		(end 20.38858 -385.466844)
		(stroke
			(width 0.06604)
			(type default)
		)
		(layer "F.Cu")
	)
	(gr_line
		(start 19.915632 -395.290294)
		(end 19.927824 -395.302486)
		(stroke
			(width 0.06604)
			(type default)
		)
		(layer "F.Cu")
	)
	(gr_line
		(start 19.927824 -396.411958)
		(end 19.71675 -396.411958)
		(stroke
			(width 0.06477)
			(type default)
		)
		(layer "F.Cu")
	)
	(gr_line
		(start 19.927824 -395.302486)
		(end 19.927824 -395.611858)
		(stroke
			(width 0.06604)
			(type default)
		)
		(layer "F.Cu")
	)
	(gr_line
		(start 19.97202 -383.209038)
		(end 19.97202 -383.18313)
		(stroke
			(width 0.06604)
			(type default)
		)
		(layer "F.Cu")
	)
	(gr_line
		(start 19.97202 -383.18313)
		(end 20.261326 -382.893824)
		(stroke
			(width 0.06604)
			(type default)
		)
		(layer "F.Cu")
	)
	(gr_line
		(start 20.38858 -385.466844)
		(end 20.485608 -385.466844)
		(stroke
			(width 0.06604)
			(type default)
		)
		(layer "F.Cu")
	)
	(gr_line
		(start 20.485608 -384.666744)
		(end 20.485608 -384.221482)
		(stroke
			(width 0.06604)
			(type default)
		)
		(layer "F.Cu")
	)
	(gr_line
		(start 20.485608 -384.221482)
		(end 19.97329 -383.708656)
		(stroke
			(width 0.06604)
			(type default)
		)
		(layer "F.Cu")
	)
	(gr_line
		(start 20.513548 -392.255248)
		(end 20.55368 -392.29538)
		(stroke
			(width 0.06604)
			(type default)
		)
		(layer "F.Cu")
	)
	(gr_line
		(start 20.513548 -391.92581)
		(end 20.513548 -392.255248)
		(stroke
			(width 0.06604)
			(type default)
		)
		(layer "F.Cu")
	)
	(gr_line
		(start 20.55368 -392.29538)
		(end 20.55368 -392.317478)
		(stroke
			(width 0.06604)
			(type default)
		)
		(layer "F.Cu")
	)
	(gr_line
		(start 20.913598 -392.21664)
		(end 20.81403 -392.316208)
		(stroke
			(width 0.06604)
			(type default)
		)
		(layer "F.Cu")
	)
	(gr_line
		(start 20.913598 -391.92581)
		(end 20.913598 -392.21664)
		(stroke
			(width 0.06604)
			(type default)
		)
		(layer "F.Cu")
	)
	(gr_line
		(start 22.460204 -386.599938)
		(end 22.460204 -386.178298)
		(stroke
			(width 0.06604)
			(type default)
		)
		(layer "F.Cu")
	)
	(gr_line
		(start 22.460204 -385.378198)
		(end 22.681692 -385.378198)
		(stroke
			(width 0.06477)
			(type default)
		)
		(layer "F.Cu")
	)
	(gr_line
		(start 22.681692 -385.378198)
		(end 23.113492 -385.809998)
		(stroke
			(width 0.06477)
			(type default)
		)
		(layer "F.Cu")
	)
	(gr_line
		(start 22.913594 -389.425942)
		(end 22.913594 -389.186166)
		(stroke
			(width 0.06604)
			(type default)
		)
		(layer "F.Cu")
	)
	(gr_line
		(start 22.913594 -389.186166)
		(end 22.982936 -389.116824)
		(stroke
			(width 0.06604)
			(type default)
		)
		(layer "F.Cu")
	)
	(gr_line
		(start 22.983952 -387.123686)
		(end 22.460204 -386.599938)
		(stroke
			(width 0.06604)
			(type default)
		)
		(layer "F.Cu")
	)
	(gr_line
		(start 23.243286 -389.120126)
		(end 23.243286 -389.115554)
		(stroke
			(width 0.06604)
			(type default)
		)
		(layer "F.Cu")
	)
	(gr_line
		(start 23.243286 -387.123686)
		(end 23.767034 -386.599938)
		(stroke
			(width 0.06604)
			(type default)
		)
		(layer "F.Cu")
	)
	(gr_line
		(start 23.313644 -389.425942)
		(end 23.313644 -389.190484)
		(stroke
			(width 0.06604)
			(type default)
		)
		(layer "F.Cu")
	)
	(gr_line
		(start 23.313644 -389.190484)
		(end 23.243286 -389.120126)
		(stroke
			(width 0.06604)
			(type default)
		)
		(layer "F.Cu")
	)
	(gr_line
		(start 23.545292 -385.378198)
		(end 23.113492 -384.946398)
		(stroke
			(width 0.06477)
			(type default)
		)
		(layer "F.Cu")
	)
	(gr_line
		(start 23.767034 -386.599938)
		(end 23.767034 -386.178298)
		(stroke
			(width 0.06604)
			(type default)
		)
		(layer "F.Cu")
	)
	(gr_line
		(start 23.767034 -385.378198)
		(end 23.545292 -385.378198)
		(stroke
			(width 0.06477)
			(type default)
		)
		(layer "F.Cu")
	)
	(gr_line
		(start 40.710104 -390.345676)
		(end 40.710104 -390.530334)
		(stroke
			(width 0.06604)
			(type default)
		)
		(layer "F.Cu")
	)
	(gr_line
		(start 40.82923 -390.22655)
		(end 40.710104 -390.345676)
		(stroke
			(width 0.06604)
			(type default)
		)
		(layer "F.Cu")
	)
	(gr_line
		(start 41.83634 -385.575556)
		(end 42.13987 -385.879086)
		(stroke
			(width 0.06604)
			(type default)
		)
		(layer "F.Cu")
	)
	(gr_line
		(start 97.38995 -401.49653)
		(end 97.311464 -402.277072)
		(stroke
			(width 0.06604)
			(type default)
		)
		(layer "F.Cu")
	)
	(gr_line
		(start 97.452434 -400.874738)
		(end 97.38995 -401.49653)
		(stroke
			(width 0.06604)
			(type default)
		)
		(layer "F.Cu")
	)
	(gr_line
		(start 97.553272 -399.873724)
		(end 97.490534 -400.49577)
		(stroke
			(width 0.06604)
			(type default)
		)
		(layer "F.Cu")
	)
	(gr_line
		(start 97.647506 -401.522438)
		(end 97.56902 -402.30298)
		(stroke
			(width 0.06604)
			(type default)
		)
		(layer "F.Cu")
	)
	(gr_line
		(start 97.653856 -398.87271)
		(end 97.591372 -399.494756)
		(stroke
			(width 0.06604)
			(type default)
		)
		(layer "F.Cu")
	)
	(gr_line
		(start 97.711514 -400.901662)
		(end 97.819464 -401.033996)
		(stroke
			(width 0.06604)
			(type default)
		)
		(layer "F.Cu")
	)
	(gr_line
		(start 97.754694 -397.871696)
		(end 97.691956 -398.493742)
		(stroke
			(width 0.06604)
			(type default)
		)
		(layer "F.Cu")
	)
	(gr_line
		(start 97.781364 -401.413472)
		(end 97.64903 -401.521168)
		(stroke
			(width 0.06604)
			(type default)
		)
		(layer "F.Cu")
	)
	(gr_line
		(start 97.812098 -399.900648)
		(end 97.920302 -400.033236)
		(stroke
			(width 0.06604)
			(type default)
		)
		(layer "F.Cu")
	)
	(gr_line
		(start 97.819464 -401.033996)
		(end 97.781364 -401.413472)
		(stroke
			(width 0.06604)
			(type default)
		)
		(layer "F.Cu")
	)
	(gr_line
		(start 97.855278 -396.870682)
		(end 97.792794 -397.492728)
		(stroke
			(width 0.06604)
			(type default)
		)
		(layer "F.Cu")
	)
	(gr_line
		(start 97.882202 -400.412712)
		(end 97.749868 -400.520662)
		(stroke
			(width 0.06604)
			(type default)
		)
		(layer "F.Cu")
	)
	(gr_line
		(start 97.912936 -398.89938)
		(end 98.02114 -399.032222)
		(stroke
			(width 0.06604)
			(type default)
		)
		(layer "F.Cu")
	)
	(gr_line
		(start 97.920302 -400.033236)
		(end 97.882202 -400.412712)
		(stroke
			(width 0.06604)
			(type default)
		)
		(layer "F.Cu")
	)
	(gr_line
		(start 97.956116 -395.869668)
		(end 97.893632 -396.491714)
		(stroke
			(width 0.06604)
			(type default)
		)
		(layer "F.Cu")
	)
	(gr_line
		(start 97.98304 -399.411444)
		(end 97.850452 -399.519902)
		(stroke
			(width 0.06604)
			(type default)
		)
		(layer "F.Cu")
	)
	(gr_line
		(start 98.01352 -397.898366)
		(end 98.121978 -398.031208)
		(stroke
			(width 0.06604)
			(type default)
		)
		(layer "F.Cu")
	)
	(gr_line
		(start 98.02114 -399.032222)
		(end 97.98304 -399.411444)
		(stroke
			(width 0.06604)
			(type default)
		)
		(layer "F.Cu")
	)
	(gr_line
		(start 98.056954 -394.868654)
		(end 97.994216 -395.4907)
		(stroke
			(width 0.06604)
			(type default)
		)
		(layer "F.Cu")
	)
	(gr_line
		(start 98.083878 -398.41043)
		(end 97.95129 -398.518888)
		(stroke
			(width 0.06604)
			(type default)
		)
		(layer "F.Cu")
	)
	(gr_line
		(start 98.114358 -396.897352)
		(end 98.222816 -397.030194)
		(stroke
			(width 0.06604)
			(type default)
		)
		(layer "F.Cu")
	)
	(gr_line
		(start 98.121978 -398.031208)
		(end 98.083878 -398.41043)
		(stroke
			(width 0.06604)
			(type default)
		)
		(layer "F.Cu")
	)
	(gr_line
		(start 98.161856 -393.82573)
		(end 98.099118 -394.447522)
		(stroke
			(width 0.06604)
			(type default)
		)
		(layer "F.Cu")
	)
	(gr_line
		(start 98.184716 -397.409416)
		(end 98.051874 -397.517874)
		(stroke
			(width 0.06604)
			(type default)
		)
		(layer "F.Cu")
	)
	(gr_line
		(start 98.215196 -395.896084)
		(end 98.323654 -396.02918)
		(stroke
			(width 0.06604)
			(type default)
		)
		(layer "F.Cu")
	)
	(gr_line
		(start 98.222816 -397.030194)
		(end 98.184716 -397.409416)
		(stroke
			(width 0.06604)
			(type default)
		)
		(layer "F.Cu")
	)
	(gr_line
		(start 98.26244 -392.824716)
		(end 98.199956 -393.446762)
		(stroke
			(width 0.06604)
			(type default)
		)
		(layer "F.Cu")
	)
	(gr_line
		(start 98.285554 -396.408402)
		(end 98.152712 -396.517114)
		(stroke
			(width 0.06604)
			(type default)
		)
		(layer "F.Cu")
	)
	(gr_line
		(start 98.31578 -394.89507)
		(end 98.424492 -395.028166)
		(stroke
			(width 0.06604)
			(type default)
		)
		(layer "F.Cu")
	)
	(gr_line
		(start 98.323654 -396.02918)
		(end 98.285554 -396.408402)
		(stroke
			(width 0.06604)
			(type default)
		)
		(layer "F.Cu")
	)
	(gr_line
		(start 98.386392 -395.407388)
		(end 98.253296 -395.5161)
		(stroke
			(width 0.06604)
			(type default)
		)
		(layer "F.Cu")
	)
	(gr_line
		(start 98.420936 -393.852146)
		(end 98.529648 -393.984988)
		(stroke
			(width 0.06604)
			(type default)
		)
		(layer "F.Cu")
	)
	(gr_line
		(start 98.424492 -395.028166)
		(end 98.386392 -395.407388)
		(stroke
			(width 0.06604)
			(type default)
		)
		(layer "F.Cu")
	)
	(gr_line
		(start 98.491548 -394.364464)
		(end 98.358452 -394.472922)
		(stroke
			(width 0.06604)
			(type default)
		)
		(layer "F.Cu")
	)
	(gr_line
		(start 98.52152 -392.851386)
		(end 98.630232 -392.984228)
		(stroke
			(width 0.06604)
			(type default)
		)
		(layer "F.Cu")
	)
	(gr_line
		(start 98.529648 -393.984988)
		(end 98.491548 -394.364464)
		(stroke
			(width 0.06604)
			(type default)
		)
		(layer "F.Cu")
	)
	(gr_line
		(start 98.592132 -393.36345)
		(end 98.459036 -393.471908)
		(stroke
			(width 0.06604)
			(type default)
		)
		(layer "F.Cu")
	)
	(gr_line
		(start 98.630232 -392.984228)
		(end 98.592132 -393.36345)
		(stroke
			(width 0.06604)
			(type default)
		)
		(layer "F.Cu")
	)
	(gr_line
		(start 98.83648 -402.93163)
		(end 98.53422 -402.62937)
		(stroke
			(width 0.06604)
			(type default)
		)
		(layer "F.Cu")
	)
	(gr_line
		(start 99.09556 -402.93163)
		(end 99.39782 -402.62937)
		(stroke
			(width 0.06604)
			(type default)
		)
		(layer "F.Cu")
	)
	(gr_line
		(start 100.098098 -397.91005)
		(end 100.096828 -397.891)
		(stroke
			(width 0.06604)
			(type default)
		)
		(layer "F.Cu")
	)
	(gr_line
		(start 100.101908 -397.928338)
		(end 100.098098 -397.91005)
		(stroke
			(width 0.06604)
			(type default)
		)
		(layer "F.Cu")
	)
	(gr_line
		(start 100.62083 -400.410172)
		(end 100.294694 -398.850866)
		(stroke
			(width 0.06604)
			(type default)
		)
		(layer "F.Cu")
	)
	(gr_line
		(start 100.750624 -401.031964)
		(end 100.62083 -400.410172)
		(stroke
			(width 0.06604)
			(type default)
		)
		(layer "F.Cu")
	)
	(gr_line
		(start 100.830634 -401.414742)
		(end 100.775262 -401.149058)
		(stroke
			(width 0.06604)
			(type default)
		)
		(layer "F.Cu")
	)
	(gr_line
		(start 100.874068 -400.35734)
		(end 100.54844 -398.79778)
		(stroke
			(width 0.06604)
			(type default)
		)
		(layer "F.Cu")
	)
	(gr_line
		(start 100.960682 -402.036788)
		(end 100.830634 -401.414742)
		(stroke
			(width 0.06604)
			(type default)
		)
		(layer "F.Cu")
	)
	(gr_line
		(start 101.005386 -400.977608)
		(end 101.098604 -400.83486)
		(stroke
			(width 0.06604)
			(type default)
		)
		(layer "F.Cu")
	)
	(gr_line
		(start 101.018594 -400.451828)
		(end 100.875846 -400.35861)
		(stroke
			(width 0.06604)
			(type default)
		)
		(layer "F.Cu")
	)
	(gr_line
		(start 101.040692 -402.419566)
		(end 100.960682 -402.036788)
		(stroke
			(width 0.06604)
			(type default)
		)
		(layer "F.Cu")
	)
	(gr_line
		(start 101.084126 -401.36191)
		(end 101.028754 -401.096226)
		(stroke
			(width 0.06604)
			(type default)
		)
		(layer "F.Cu")
	)
	(gr_line
		(start 101.098604 -400.83486)
		(end 101.018594 -400.451828)
		(stroke
			(width 0.06604)
			(type default)
		)
		(layer "F.Cu")
	)
	(gr_line
		(start 101.17074 -403.041358)
		(end 101.040692 -402.419566)
		(stroke
			(width 0.06604)
			(type default)
		)
		(layer "F.Cu")
	)
	(gr_line
		(start 101.21519 -401.982178)
		(end 101.308662 -401.83943)
		(stroke
			(width 0.06604)
			(type default)
		)
		(layer "F.Cu")
	)
	(gr_line
		(start 101.228652 -401.456398)
		(end 101.085904 -401.362926)
		(stroke
			(width 0.06604)
			(type default)
		)
		(layer "F.Cu")
	)
	(gr_line
		(start 101.25075 -403.424136)
		(end 101.17074 -403.041358)
		(stroke
			(width 0.06604)
			(type default)
		)
		(layer "F.Cu")
	)
	(gr_line
		(start 101.294184 -402.36648)
		(end 101.214174 -401.983702)
		(stroke
			(width 0.06604)
			(type default)
		)
		(layer "F.Cu")
	)
	(gr_line
		(start 101.308662 -401.83943)
		(end 101.228652 -401.456398)
		(stroke
			(width 0.06604)
			(type default)
		)
		(layer "F.Cu")
	)
	(gr_line
		(start 101.380544 -404.045928)
		(end 101.25075 -403.424136)
		(stroke
			(width 0.06604)
			(type default)
		)
		(layer "F.Cu")
	)
	(gr_line
		(start 101.425248 -402.986748)
		(end 101.51872 -402.844)
		(stroke
			(width 0.06604)
			(type default)
		)
		(layer "F.Cu")
	)
	(gr_line
		(start 101.43871 -402.460968)
		(end 101.295708 -402.367496)
		(stroke
			(width 0.06604)
			(type default)
		)
		(layer "F.Cu")
	)
	(gr_line
		(start 101.504242 -403.37105)
		(end 101.424232 -402.988272)
		(stroke
			(width 0.06604)
			(type default)
		)
		(layer "F.Cu")
	)
	(gr_line
		(start 101.51872 -402.844)
		(end 101.43871 -402.460968)
		(stroke
			(width 0.06604)
			(type default)
		)
		(layer "F.Cu")
	)
	(gr_line
		(start 101.635306 -403.991826)
		(end 101.729032 -403.84857)
		(stroke
			(width 0.06604)
			(type default)
		)
		(layer "F.Cu")
	)
	(gr_line
		(start 101.648768 -403.465538)
		(end 101.505766 -403.372066)
		(stroke
			(width 0.06604)
			(type default)
		)
		(layer "F.Cu")
	)
	(gr_line
		(start 101.729032 -403.84857)
		(end 101.648768 -403.465538)
		(stroke
			(width 0.06604)
			(type default)
		)
		(layer "F.Cu")
	)
	(gr_line
		(start 102.306374 -409.84424)
		(end 102.56012 -410.097986)
		(stroke
			(width 0.06604)
			(type default)
		)
		(layer "F.Cu")
	)
	(gr_line
		(start 102.35946 -404.62962)
		(end 102.28326 -404.62962)
		(stroke
			(width 0.06604)
			(type default)
		)
		(layer "F.Cu")
	)
	(gr_line
		(start 102.56012 -410.911548)
		(end 102.25786 -411.213808)
		(stroke
			(width 0.06604)
			(type default)
		)
		(layer "F.Cu")
	)
	(gr_line
		(start 102.56012 -410.097986)
		(end 102.56012 -410.128466)
		(stroke
			(width 0.06604)
			(type default)
		)
		(layer "F.Cu")
	)
	(gr_line
		(start 102.57282 -409.044394)
		(end 102.306374 -409.31084)
		(stroke
			(width 0.06604)
			(type default)
		)
		(layer "F.Cu")
	)
	(gr_line
		(start 102.57282 -409.039314)
		(end 102.57282 -409.044394)
		(stroke
			(width 0.06604)
			(type default)
		)
		(layer "F.Cu")
	)
	(gr_line
		(start 102.62362 -405.22906)
		(end 102.28453 -404.88997)
		(stroke
			(width 0.06604)
			(type default)
		)
		(layer "F.Cu")
	)
	(gr_line
		(start 102.62362 -404.36546)
		(end 102.35946 -404.62962)
		(stroke
			(width 0.06604)
			(type default)
		)
		(layer "F.Cu")
	)
	(gr_line
		(start 102.8192 -410.911548)
		(end 103.12146 -411.213808)
		(stroke
			(width 0.06604)
			(type default)
		)
		(layer "F.Cu")
	)
	(gr_line
		(start 102.83317 -409.040584)
		(end 103.103426 -409.31084)
		(stroke
			(width 0.06604)
			(type default)
		)
		(layer "F.Cu")
	)
	(gr_line
		(start 103.103426 -409.84424)
		(end 102.82047 -410.127196)
		(stroke
			(width 0.06604)
			(type default)
		)
		(layer "F.Cu")
	)
	(gr_line
		(start 104.81818 -396.981426)
		(end 104.81818 -397.033242)
		(stroke
			(width 0.06604)
			(type default)
		)
		(layer "F.Cu")
	)
	(gr_line
		(start 104.837992 -396.933674)
		(end 104.81818 -396.981426)
		(stroke
			(width 0.06604)
			(type default)
		)
		(layer "F.Cu")
	)
	(gr_line
		(start 105.07726 -397.033242)
		(end 105.077514 -397.032988)
		(stroke
			(width 0.06604)
			(type default)
		)
		(layer "F.Cu")
	)
	(gr_line
		(start 132.020056 -10.243312)
		(end 132.3213 -10.544556)
		(stroke
			(width 0.06604)
			(type default)
		)
		(layer "F.Cu")
	)
	(gr_line
		(start 132.147056 -17.088612)
		(end 132.315458 -17.257014)
		(stroke
			(width 0.06604)
			(type default)
		)
		(layer "F.Cu")
	)
	(gr_line
		(start 132.147056 -16.550132)
		(end 132.147056 -17.088612)
		(stroke
			(width 0.06604)
			(type default)
		)
		(layer "F.Cu")
	)
	(gr_line
		(start 132.147056 -13.027152)
		(end 132.147056 -13.600176)
		(stroke
			(width 0.06604)
			(type default)
		)
		(layer "F.Cu")
	)
	(gr_line
		(start 132.316728 -17.842484)
		(end 132.014468 -18.144744)
		(stroke
			(width 0.06604)
			(type default)
		)
		(layer "F.Cu")
	)
	(gr_line
		(start 132.317236 -12.856972)
		(end 132.147056 -13.027152)
		(stroke
			(width 0.06604)
			(type default)
		)
		(layer "F.Cu")
	)
	(gr_line
		(start 132.317236 -12.848844)
		(end 132.317236 -12.856972)
		(stroke
			(width 0.06604)
			(type default)
		)
		(layer "F.Cu")
	)
	(gr_line
		(start 132.3213 -10.544556)
		(end 132.3213 -10.546588)
		(stroke
			(width 0.06604)
			(type default)
		)
		(layer "F.Cu")
	)
	(gr_line
		(start 132.575808 -17.842484)
		(end 132.878068 -18.144744)
		(stroke
			(width 0.06604)
			(type default)
		)
		(layer "F.Cu")
	)
	(gr_line
		(start 132.575808 -17.245584)
		(end 132.575808 -17.258284)
		(stroke
			(width 0.06604)
			(type default)
		)
		(layer "F.Cu")
	)
	(gr_line
		(start 132.577586 -12.850114)
		(end 132.747004 -13.019532)
		(stroke
			(width 0.06604)
			(type default)
		)
		(layer "F.Cu")
	)
	(gr_line
		(start 132.747004 -17.074388)
		(end 132.575808 -17.245584)
		(stroke
			(width 0.06604)
			(type default)
		)
		(layer "F.Cu")
	)
	(gr_line
		(start 132.747004 -16.550132)
		(end 132.747004 -17.074388)
		(stroke
			(width 0.06604)
			(type default)
		)
		(layer "F.Cu")
	)
	(gr_line
		(start 132.747004 -13.019532)
		(end 132.747004 -13.600176)
		(stroke
			(width 0.06604)
			(type default)
		)
		(layer "F.Cu")
	)
	(gr_line
		(start 132.883656 -10.243312)
		(end 132.58165 -10.545318)
		(stroke
			(width 0.06604)
			(type default)
		)
		(layer "F.Cu")
	)
	(gr_line
		(start 170.537632 -383.29743)
		(end 170.505882 -383.29743)
		(stroke
			(width 0.06604)
			(type default)
		)
		(layer "F.Cu")
	)
	(gr_line
		(start 170.56354 -383.291588)
		(end 170.537632 -383.29743)
		(stroke
			(width 0.06604)
			(type default)
		)
		(layer "F.Cu")
	)
	(gr_line
		(start 197.799452 -361.90301)
		(end 197.799706 -361.902756)
		(stroke
			(width 0.06604)
			(type default)
		)
		(layer "F.Cu")
	)
	(gr_line
		(start 228.518466 -309.497476)
		(end 228.51872 -309.497222)
		(stroke
			(width 0.06604)
			(type default)
		)
		(layer "F.Cu")
	)
	(gr_line
		(start 247.2436 -246.351044)
		(end 247.2436 -246.347742)
		(stroke
			(width 0.06604)
			(type default)
		)
		(layer "F.Cu")
	)
	(gr_line
		(start 292.95598 -162.100768)
		(end 293.25824 -162.403028)
		(stroke
			(width 0.06604)
			(type default)
		)
		(layer "F.Cu")
	)
	(gr_line
		(start 293.81958 -162.100768)
		(end 293.51732 -162.403028)
		(stroke
			(width 0.06604)
			(type default)
		)
		(layer "F.Cu")
	)
	(gr_line
		(start 295.4147 -163.398708)
		(end 295.11244 -163.096448)
		(stroke
			(width 0.06604)
			(type default)
		)
		(layer "F.Cu")
	)
	(gr_line
		(start 295.67378 -163.398708)
		(end 295.97604 -163.096448)
		(stroke
			(width 0.06604)
			(type default)
		)
		(layer "F.Cu")
	)
	(gr_line
		(start 297.13428 -161.557208)
		(end 297.43654 -161.859468)
		(stroke
			(width 0.06604)
			(type default)
		)
		(layer "F.Cu")
	)
	(gr_line
		(start 297.99788 -161.557208)
		(end 297.69562 -161.859468)
		(stroke
			(width 0.06604)
			(type default)
		)
		(layer "F.Cu")
	)
	(gr_line
		(start 343.81948 -50.799746)
		(end 343.81948 -50.79873)
		(stroke
			(width 0.06604)
			(type default)
		)
		(layer "F.Cu")
	)
	(gr_line
		(start 343.81948 -50.79873)
		(end 343.550494 -50.329592)
		(stroke
			(width 0.06604)
			(type default)
		)
		(layer "F.Cu")
	)
	(gr_line
		(start 344.63355 -52.209446)
		(end 344.36431 -51.739546)
		(stroke
			(width 0.06604)
			(type default)
		)
		(layer "F.Cu")
	)
	(gr_line
		(start 344.63355 -51.269646)
		(end 344.36431 -50.799746)
		(stroke
			(width 0.06604)
			(type default)
		)
		(layer "F.Cu")
	)
	(gr_line
		(start 344.63355 -50.329846)
		(end 344.365834 -49.859692)
		(stroke
			(width 0.06604)
			(type default)
		)
		(layer "F.Cu")
	)
	(gr_line
		(start 346.253562 -54.453028)
		(end 345.96959 -54.453028)
		(stroke
			(width 0.04445)
			(type default)
		)
		(layer "F.Cu")
	)
	(gr_line
		(start 346.422726 -54.382924)
		(end 346.253562 -54.453028)
		(stroke
			(width 0.04445)
			(type default)
		)
		(layer "F.Cu")
	)
	(gr_line
		(start 346.622624 -54.183026)
		(end 346.422726 -54.382924)
		(stroke
			(width 0.04445)
			(type default)
		)
		(layer "F.Cu")
	)
	(gr_line
		(start 346.700348 -54.150768)
		(end 346.622624 -54.183026)
		(stroke
			(width 0.04445)
			(type default)
		)
		(layer "F.Cu")
	)
	(gr_line
		(start 346.831666 -54.422548)
		(end 346.799662 -54.453028)
		(stroke
			(width 0.04445)
			(type default)
		)
		(layer "F.Cu")
	)
	(gr_line
		(start 346.88145 -54.150768)
		(end 346.700348 -54.150768)
		(stroke
			(width 0.04445)
			(type default)
		)
		(layer "F.Cu")
	)
	(gr_line
		(start 347.068902 -54.422548)
		(end 346.831666 -54.422548)
		(stroke
			(width 0.04445)
			(type default)
		)
		(layer "F.Cu")
	)
	(gr_line
		(start 347.071696 -54.419754)
		(end 347.068902 -54.422548)
		(stroke
			(width 0.04445)
			(type default)
		)
		(layer "F.Cu")
	)
	(gr_line
		(start 347.071696 -54.229508)
		(end 346.88145 -54.150768)
		(stroke
			(width 0.04445)
			(type default)
		)
		(layer "F.Cu")
	)
	(gr_line
		(start 347.794072 -54.571138)
		(end 347.755718 -54.571138)
		(stroke
			(width 0.04445)
			(type default)
		)
		(layer "F.Cu")
	)
	(gr_line
		(start 347.794072 -54.381146)
		(end 347.793564 -54.380892)
		(stroke
			(width 0.04445)
			(type default)
		)
		(layer "F.Cu")
	)
	(gr_line
		(start 347.85554 -54.571138)
		(end 347.794072 -54.571138)
		(stroke
			(width 0.04445)
			(type default)
		)
		(layer "F.Cu")
	)
	(gr_line
		(start 347.85554 -54.381146)
		(end 347.794072 -54.381146)
		(stroke
			(width 0.04445)
			(type default)
		)
		(layer "F.Cu")
	)
	(gr_line
		(start 347.954854 -54.670452)
		(end 347.857064 -54.572662)
		(stroke
			(width 0.04445)
			(type default)
		)
		(layer "F.Cu")
	)
	(gr_line
		(start 348.132654 -54.670452)
		(end 347.954854 -54.670452)
		(stroke
			(width 0.04445)
			(type default)
		)
		(layer "F.Cu")
	)
	(gr_line
		(start 348.230444 -54.572662)
		(end 348.132654 -54.670452)
		(stroke
			(width 0.04445)
			(type default)
		)
		(layer "F.Cu")
	)
	(gr_line
		(start 348.231714 -54.381146)
		(end 347.85554 -54.381146)
		(stroke
			(width 0.04445)
			(type default)
		)
		(layer "F.Cu")
	)
	(gr_line
		(start 348.508574 -54.670452)
		(end 348.410784 -54.572662)
		(stroke
			(width 0.04445)
			(type default)
		)
		(layer "F.Cu")
	)
	(gr_line
		(start 348.686374 -54.670452)
		(end 348.508574 -54.670452)
		(stroke
			(width 0.04445)
			(type default)
		)
		(layer "F.Cu")
	)
	(gr_line
		(start 348.784164 -54.572662)
		(end 348.686374 -54.670452)
		(stroke
			(width 0.04445)
			(type default)
		)
		(layer "F.Cu")
	)
	(gr_line
		(start 348.785434 -54.381146)
		(end 348.409514 -54.381146)
		(stroke
			(width 0.04445)
			(type default)
		)
		(layer "F.Cu")
	)
	(gr_line
		(start 349.062294 -54.670452)
		(end 348.964504 -54.572662)
		(stroke
			(width 0.04445)
			(type default)
		)
		(layer "F.Cu")
	)
	(gr_line
		(start 349.240094 -54.670452)
		(end 349.062294 -54.670452)
		(stroke
			(width 0.04445)
			(type default)
		)
		(layer "F.Cu")
	)
	(gr_line
		(start 349.337884 -54.572662)
		(end 349.240094 -54.670452)
		(stroke
			(width 0.04445)
			(type default)
		)
		(layer "F.Cu")
	)
	(gr_line
		(start 349.339154 -54.381146)
		(end 348.963234 -54.381146)
		(stroke
			(width 0.04445)
			(type default)
		)
		(layer "F.Cu")
	)
	(gr_line
		(start 349.616014 -54.670452)
		(end 349.518224 -54.572662)
		(stroke
			(width 0.04445)
			(type default)
		)
		(layer "F.Cu")
	)
	(gr_line
		(start 349.793814 -54.670452)
		(end 349.616014 -54.670452)
		(stroke
			(width 0.04445)
			(type default)
		)
		(layer "F.Cu")
	)
	(gr_line
		(start 349.891604 -54.572662)
		(end 349.793814 -54.670452)
		(stroke
			(width 0.04445)
			(type default)
		)
		(layer "F.Cu")
	)
	(gr_line
		(start 349.892874 -54.381146)
		(end 349.516954 -54.381146)
		(stroke
			(width 0.04445)
			(type default)
		)
		(layer "F.Cu")
	)
	(gr_line
		(start 350.169734 -54.670452)
		(end 350.071944 -54.572662)
		(stroke
			(width 0.04445)
			(type default)
		)
		(layer "F.Cu")
	)
	(gr_line
		(start 350.347534 -54.670452)
		(end 350.169734 -54.670452)
		(stroke
			(width 0.04445)
			(type default)
		)
		(layer "F.Cu")
	)
	(gr_line
		(start 350.445324 -54.572662)
		(end 350.347534 -54.670452)
		(stroke
			(width 0.04445)
			(type default)
		)
		(layer "F.Cu")
	)
	(gr_line
		(start 350.446594 -54.381146)
		(end 350.070674 -54.381146)
		(stroke
			(width 0.04445)
			(type default)
		)
		(layer "F.Cu")
	)
	(gr_line
		(start 350.993964 -54.850284)
		(end 350.939862 -54.718966)
		(stroke
			(width 0.04445)
			(type default)
		)
		(layer "F.Cu")
	)
	(gr_line
		(start 351.181924 -54.928008)
		(end 350.993964 -54.850284)
		(stroke
			(width 0.04445)
			(type default)
		)
		(layer "F.Cu")
	)
	(gr_line
		(start 351.313242 -54.873652)
		(end 351.181924 -54.928008)
		(stroke
			(width 0.04445)
			(type default)
		)
		(layer "F.Cu")
	)
	(gr_line
		(start 351.387664 -54.697376)
		(end 351.011998 -54.541674)
		(stroke
			(width 0.04445)
			(type default)
		)
		(layer "F.Cu")
	)
	(gr_line
		(start 351.785936 -55.080154)
		(end 351.688146 -54.982364)
		(stroke
			(width 0.04445)
			(type default)
		)
		(layer "F.Cu")
	)
	(gr_line
		(start 352.050096 -55.080154)
		(end 351.785936 -55.080154)
		(stroke
			(width 0.04445)
			(type default)
		)
		(layer "F.Cu")
	)
	(gr_line
		(start 352.147886 -54.982364)
		(end 352.050096 -55.080154)
		(stroke
			(width 0.04445)
			(type default)
		)
		(layer "F.Cu")
	)
	(gr_line
		(start 352.149156 -54.790848)
		(end 351.686876 -54.790848)
		(stroke
			(width 0.04445)
			(type default)
		)
		(layer "F.Cu")
	)
	(gr_line
		(start 352.512376 -55.080154)
		(end 352.414586 -54.982364)
		(stroke
			(width 0.04445)
			(type default)
		)
		(layer "F.Cu")
	)
	(gr_line
		(start 352.776536 -55.080154)
		(end 352.512376 -55.080154)
		(stroke
			(width 0.04445)
			(type default)
		)
		(layer "F.Cu")
	)
	(gr_line
		(start 352.874326 -54.982364)
		(end 352.776536 -55.080154)
		(stroke
			(width 0.04445)
			(type default)
		)
		(layer "F.Cu")
	)
	(gr_line
		(start 352.875596 -54.790848)
		(end 352.413316 -54.790848)
		(stroke
			(width 0.04445)
			(type default)
		)
		(layer "F.Cu")
	)
	(gr_line
		(start 353.477576 -55.367428)
		(end 353.477576 -55.31866)
		(stroke
			(width 0.04445)
			(type default)
		)
		(layer "F.Cu")
	)
	(gr_line
		(start 353.49307 -55.382922)
		(end 353.477576 -55.367428)
		(stroke
			(width 0.04445)
			(type default)
		)
		(layer "F.Cu")
	)
	(gr_line
		(start 353.660964 -55.18404)
		(end 353.612196 -55.18404)
		(stroke
			(width 0.04445)
			(type default)
		)
		(layer "F.Cu")
	)
	(gr_line
		(start 353.676458 -55.199534)
		(end 353.660964 -55.18404)
		(stroke
			(width 0.04445)
			(type default)
		)
		(layer "F.Cu")
	)
	(gr_line
		(start 354.097844 -56.16194)
		(end 354.097844 -55.98922)
		(stroke
			(width 0.06604)
			(type default)
		)
		(layer "F.Cu")
	)
	(gr_line
		(start 354.378514 -56.442356)
		(end 354.097844 -56.16194)
		(stroke
			(width 0.06604)
			(type default)
		)
		(layer "F.Cu")
	)
	(gr_line
		(start 354.55098 -56.442356)
		(end 354.378514 -56.442356)
		(stroke
			(width 0.06604)
			(type default)
		)
		(layer "F.Cu")
	)
	(gr_line
		(start 354.735892 -56.258968)
		(end 354.281232 -55.804308)
		(stroke
			(width 0.06604)
			(type default)
		)
		(layer "F.Cu")
	)
	(gr_line
		(start 354.832666 -56.896762)
		(end 354.832666 -56.724042)
		(stroke
			(width 0.06604)
			(type default)
		)
		(layer "F.Cu")
	)
	(gr_line
		(start 355.113336 -57.177178)
		(end 354.832666 -56.896762)
		(stroke
			(width 0.06604)
			(type default)
		)
		(layer "F.Cu")
	)
	(gr_line
		(start 355.285802 -57.177178)
		(end 355.113336 -57.177178)
		(stroke
			(width 0.06604)
			(type default)
		)
		(layer "F.Cu")
	)
	(gr_line
		(start 355.470714 -56.99379)
		(end 355.016054 -56.53913)
		(stroke
			(width 0.06604)
			(type default)
		)
		(layer "F.Cu")
	)
	(gr_line
		(start 355.567488 -57.631584)
		(end 355.567488 -57.458864)
		(stroke
			(width 0.06604)
			(type default)
		)
		(layer "F.Cu")
	)
	(gr_line
		(start 355.848158 -57.912)
		(end 355.567488 -57.631584)
		(stroke
			(width 0.06604)
			(type default)
		)
		(layer "F.Cu")
	)
	(gr_line
		(start 355.85019 -61.195966)
		(end 355.969316 -61.195966)
		(stroke
			(width 0.06604)
			(type default)
		)
		(layer "F.Cu")
	)
	(gr_line
		(start 355.969316 -61.195966)
		(end 356.222046 -60.943236)
		(stroke
			(width 0.06604)
			(type default)
		)
		(layer "F.Cu")
	)
	(gr_line
		(start 356.02037 -57.912)
		(end 355.848158 -57.912)
		(stroke
			(width 0.06604)
			(type default)
		)
		(layer "F.Cu")
	)
	(gr_line
		(start 356.100126 -60.039758)
		(end 356.100126 -59.643518)
		(stroke
			(width 0.06604)
			(type default)
		)
		(layer "F.Cu")
	)
	(gr_line
		(start 356.100126 -59.643518)
		(end 356.222046 -59.521598)
		(stroke
			(width 0.06604)
			(type default)
		)
		(layer "F.Cu")
	)
	(gr_line
		(start 356.100126 -59.000898)
		(end 356.100126 -58.604658)
		(stroke
			(width 0.06604)
			(type default)
		)
		(layer "F.Cu")
	)
	(gr_line
		(start 356.100126 -58.604658)
		(end 356.222046 -58.482738)
		(stroke
			(width 0.06604)
			(type default)
		)
		(layer "F.Cu")
	)
	(gr_line
		(start 356.129844 -57.65292)
		(end 355.750876 -57.273952)
		(stroke
			(width 0.06604)
			(type default)
		)
		(layer "F.Cu")
	)
	(gr_line
		(start 356.129844 -57.65292)
		(end 356.12959 -57.65292)
		(stroke
			(width 0.06604)
			(type default)
		)
		(layer "F.Cu")
	)
	(gr_line
		(start 356.205282 -57.728612)
		(end 356.12959 -57.65292)
		(stroke
			(width 0.06604)
			(type default)
		)
		(layer "F.Cu")
	)
	(gr_line
		(start 356.222046 -60.161678)
		(end 356.100126 -60.039758)
		(stroke
			(width 0.06604)
			(type default)
		)
		(layer "F.Cu")
	)
	(gr_line
		(start 356.222046 -59.122818)
		(end 356.100126 -59.000898)
		(stroke
			(width 0.06604)
			(type default)
		)
		(layer "F.Cu")
	)
	(gr_line
		(start 356.482396 -60.964572)
		(end 356.482396 -60.941966)
		(stroke
			(width 0.06604)
			(type default)
		)
		(layer "F.Cu")
	)
	(gr_line
		(start 356.482396 -60.162948)
		(end 356.482396 -59.520328)
		(stroke
			(width 0.06604)
			(type default)
		)
		(layer "F.Cu")
	)
	(gr_line
		(start 356.482396 -59.124088)
		(end 356.482396 -58.481468)
		(stroke
			(width 0.06604)
			(type default)
		)
		(layer "F.Cu")
	)
	(gr_line
		(start 356.71379 -61.195966)
		(end 356.482396 -60.964572)
		(stroke
			(width 0.06604)
			(type default)
		)
		(layer "F.Cu")
	)
	(gr_poly
		(pts
			(xy 9.028684 -323.332856) (xy 9.028684 -322.062856) (xy 8.901684 -321.935856) (xy 7.377684 -321.935856)
			(xy 7.250684 -322.062856) (xy 7.250684 -323.332856) (xy 7.631684 -323.713856) (xy 8.647684 -323.713856)
		)
		(stroke
			(width 0)
			(type solid)
		)
		(fill yes)
		(layer "B.Cu")
		(net "GND")
	)
	(gr_poly
		(pts
			(xy 13.092684 -323.332856) (xy 13.092684 -322.062856) (xy 12.965684 -321.935856) (xy 11.441684 -321.935856)
			(xy 11.314684 -322.062856) (xy 11.314684 -323.332856) (xy 11.695684 -323.713856) (xy 12.711684 -323.713856)
		)
		(stroke
			(width 0)
			(type solid)
		)
		(fill yes)
		(layer "B.Cu")
		(net "GND")
	)
	(gr_poly
		(pts
			(xy 16.44396 -111.658908) (xy 16.44396 -111.354108) (xy 16.26616 -111.176308) (xy 13.44676 -111.176308)
			(xy 12.98956 -111.633508) (xy 12.619736 -111.633508) (xy 12.619736 -111.785908) (xy 16.31696 -111.785908)
		)
		(stroke
			(width 0)
			(type solid)
		)
		(fill yes)
		(layer "B.Cu")
		(net "P3V3_AUX")
	)
	(gr_poly
		(pts
			(xy 16.572484 -323.332856) (xy 16.572484 -322.062856) (xy 16.445484 -321.935856) (xy 14.921484 -321.935856)
			(xy 14.794484 -322.062856) (xy 14.794484 -323.332856) (xy 15.175484 -323.713856) (xy 16.191484 -323.713856)
		)
		(stroke
			(width 0)
			(type solid)
		)
		(fill yes)
		(layer "B.Cu")
		(net "GND")
	)
	(gr_poly
		(pts
			(xy 20.12188 -96.957388) (xy 20.12188 -95.992188) (xy 19.99488 -95.865188) (xy 18.67408 -95.865188)
			(xy 18.57248 -95.966788) (xy 18.57248 -97.135188) (xy 18.59788 -97.160588) (xy 19.91868 -97.160588)
		)
		(stroke
			(width 0)
			(type solid)
		)
		(fill yes)
		(layer "B.Cu")
		(net "P3V3_AUX")
	)
	(gr_poly
		(pts
			(xy 20.636484 -323.332856) (xy 20.636484 -322.062856) (xy 20.509484 -321.935856) (xy 18.985484 -321.935856)
			(xy 18.858484 -322.062856) (xy 18.858484 -323.332856) (xy 19.239484 -323.713856) (xy 20.255484 -323.713856)
		)
		(stroke
			(width 0)
			(type solid)
		)
		(fill yes)
		(layer "B.Cu")
		(net "GND")
	)
	(gr_poly
		(pts
			(xy 24.116284 -323.332856) (xy 24.116284 -322.062856) (xy 23.989284 -321.935856) (xy 22.465284 -321.935856)
			(xy 22.338284 -322.062856) (xy 22.338284 -323.332856) (xy 22.719284 -323.713856) (xy 23.735284 -323.713856)
		)
		(stroke
			(width 0)
			(type solid)
		)
		(fill yes)
		(layer "B.Cu")
		(net "GND")
	)
	(gr_poly
		(pts
			(xy 24.41448 -391.099548) (xy 24.41448 -390.439148) (xy 24.10968 -390.134348) (xy 19.51228 -390.134348)
			(xy 19.30908 -390.337548) (xy 19.30908 -391.048748) (xy 19.58848 -391.328148) (xy 24.18588 -391.328148)
		)
		(stroke
			(width 0)
			(type solid)
		)
		(fill yes)
		(layer "B.Cu")
		(net "GND")
	)
	(gr_poly
		(pts
			(xy 28.180284 -323.332856) (xy 28.180284 -322.062856) (xy 28.053284 -321.935856) (xy 26.529284 -321.935856)
			(xy 26.402284 -322.062856) (xy 26.402284 -323.332856) (xy 26.783284 -323.713856) (xy 27.799284 -323.713856)
		)
		(stroke
			(width 0)
			(type solid)
		)
		(fill yes)
		(layer "B.Cu")
		(net "GND")
	)
	(gr_poly
		(pts
			(xy 31.660084 -323.332856) (xy 31.660084 -322.062856) (xy 31.533084 -321.935856) (xy 30.009084 -321.935856)
			(xy 29.882084 -322.062856) (xy 29.882084 -323.332856) (xy 30.263084 -323.713856) (xy 31.279084 -323.713856)
		)
		(stroke
			(width 0)
			(type solid)
		)
		(fill yes)
		(layer "B.Cu")
		(net "GND")
	)
	(gr_poly
		(pts
			(xy 33.94075 -131.462272) (xy 33.94075 -127.042672) (xy 33.88995 -126.991872) (xy 30.23235 -126.991872)
			(xy 30.18155 -127.042672) (xy 30.18155 -131.462272) (xy 30.23235 -131.513072) (xy 33.88995 -131.513072)
		)
		(stroke
			(width 0)
			(type solid)
		)
		(fill yes)
		(layer "B.Cu")
		(net "GND")
	)
	(gr_poly
		(pts
			(xy 34.65322 -397.23314) (xy 34.65322 -396.35176) (xy 34.57956 -396.2781) (xy 32.8168 -396.2781)
			(xy 32.639 -396.4559) (xy 32.639 -397.21028) (xy 32.75838 -397.32966) (xy 34.5567 -397.32966)
		)
		(stroke
			(width 0)
			(type solid)
		)
		(fill yes)
		(layer "B.Cu")
		(net "GND")
	)
	(gr_poly
		(pts
			(xy 35.724084 -323.332856) (xy 35.724084 -322.062856) (xy 35.597084 -321.935856) (xy 34.073084 -321.935856)
			(xy 33.946084 -322.062856) (xy 33.946084 -323.332856) (xy 34.327084 -323.713856) (xy 35.343084 -323.713856)
		)
		(stroke
			(width 0)
			(type solid)
		)
		(fill yes)
		(layer "B.Cu")
		(net "GND")
	)
	(gr_poly
		(pts
			(xy 39.203884 -323.332856) (xy 39.203884 -322.062856) (xy 39.076884 -321.935856) (xy 37.552884 -321.935856)
			(xy 37.425884 -322.062856) (xy 37.425884 -323.332856) (xy 37.806884 -323.713856) (xy 38.822884 -323.713856)
		)
		(stroke
			(width 0)
			(type solid)
		)
		(fill yes)
		(layer "B.Cu")
		(net "GND")
	)
	(gr_poly
		(pts
			(xy 41.534334 -393.564618) (xy 41.534334 -391.131806) (xy 41.450514 -391.047986) (xy 38.818312 -391.047986)
			(xy 38.55212 -391.314178) (xy 38.55212 -393.591796) (xy 38.797484 -393.83716) (xy 41.261792 -393.83716)
		)
		(stroke
			(width 0)
			(type solid)
		)
		(fill yes)
		(layer "B.Cu")
		(net "GND")
	)
	(gr_poly
		(pts
			(xy 43.267884 -323.332856) (xy 43.267884 -322.062856) (xy 43.140884 -321.935856) (xy 41.616884 -321.935856)
			(xy 41.489884 -322.062856) (xy 41.489884 -323.332856) (xy 41.870884 -323.713856) (xy 42.886884 -323.713856)
		)
		(stroke
			(width 0)
			(type solid)
		)
		(fill yes)
		(layer "B.Cu")
		(net "GND")
	)
	(gr_poly
		(pts
			(xy 46.747684 -323.332856) (xy 46.747684 -322.062856) (xy 46.620684 -321.935856) (xy 45.096684 -321.935856)
			(xy 44.969684 -322.062856) (xy 44.969684 -323.332856) (xy 45.350684 -323.713856) (xy 46.366684 -323.713856)
		)
		(stroke
			(width 0)
			(type solid)
		)
		(fill yes)
		(layer "B.Cu")
		(net "GND")
	)
	(gr_poly
		(pts
			(xy 50.811684 -323.332856) (xy 50.811684 -322.062856) (xy 50.684684 -321.935856) (xy 48.709326 -321.935856)
			(xy 48.594518 -322.050664) (xy 48.594518 -323.51218) (xy 48.796194 -323.713856) (xy 50.430684 -323.713856)
		)
		(stroke
			(width 0)
			(type solid)
		)
		(fill yes)
		(layer "B.Cu")
		(net "GND")
	)
	(gr_poly
		(pts
			(xy 54.291484 -323.332856) (xy 54.291484 -322.062856) (xy 54.164484 -321.935856) (xy 52.353464 -321.935856)
			(xy 52.130452 -322.158868) (xy 52.130452 -323.550534) (xy 52.293774 -323.713856) (xy 53.910484 -323.713856)
		)
		(stroke
			(width 0)
			(type solid)
		)
		(fill yes)
		(layer "B.Cu")
		(net "GND")
	)
	(gr_poly
		(pts
			(xy 58.355484 -323.332856) (xy 58.355484 -322.062856) (xy 58.228484 -321.935856) (xy 56.704484 -321.935856)
			(xy 56.577484 -322.062856) (xy 56.577484 -323.332856) (xy 56.958484 -323.713856) (xy 57.974484 -323.713856)
		)
		(stroke
			(width 0)
			(type solid)
		)
		(fill yes)
		(layer "B.Cu")
		(net "GND")
	)
	(gr_poly
		(pts
			(xy 61.835284 -323.332856) (xy 61.835284 -322.062856) (xy 61.708284 -321.935856) (xy 60.184284 -321.935856)
			(xy 60.057284 -322.062856) (xy 60.057284 -323.332856) (xy 60.438284 -323.713856) (xy 61.454284 -323.713856)
		)
		(stroke
			(width 0)
			(type solid)
		)
		(fill yes)
		(layer "B.Cu")
		(net "GND")
	)
	(gr_poly
		(pts
			(xy 65.899284 -323.332856) (xy 65.899284 -322.062856) (xy 65.772284 -321.935856) (xy 64.248284 -321.935856)
			(xy 64.121284 -322.062856) (xy 64.121284 -323.332856) (xy 64.502284 -323.713856) (xy 65.518284 -323.713856)
		)
		(stroke
			(width 0)
			(type solid)
		)
		(fill yes)
		(layer "B.Cu")
		(net "GND")
	)
	(gr_poly
		(pts
			(xy 83.62188 -44.978828) (xy 83.62188 -42.268648) (xy 83.05038 -41.697148) (xy 77.26934 -41.697148)
			(xy 77.17536 -41.791128) (xy 77.17536 -45.179488) (xy 77.388466 -45.39234) (xy 83.208114 -45.39234)
		)
		(stroke
			(width 0)
			(type solid)
		)
		(fill yes)
		(layer "B.Cu")
		(net "P3V3_OCP_V3_2")
	)
	(gr_poly
		(pts
			(xy 105.252774 -297.215052) (xy 105.252774 -292.772592) (xy 105.05313 -292.573202) (xy 103.228648 -292.573202)
			(xy 102.931468 -292.870382) (xy 102.931468 -297.188382) (xy 103.225346 -297.48226) (xy 104.985566 -297.48226)
		)
		(stroke
			(width 0)
			(type solid)
		)
		(fill yes)
		(layer "B.Cu")
		(net "GND")
	)
	(gr_poly
		(pts
			(xy 111.589058 -297.208448) (xy 111.589058 -292.816788) (xy 111.345218 -292.573202) (xy 109.520736 -292.573202)
			(xy 109.268006 -292.825932) (xy 109.268006 -297.22318) (xy 109.527086 -297.48226) (xy 111.315246 -297.48226)
		)
		(stroke
			(width 0)
			(type solid)
		)
		(fill yes)
		(layer "B.Cu")
		(net "GND")
	)
	(gr_poly
		(pts
			(xy 111.72952 -409.219908) (xy 111.72952 -408.42438) (xy 111.61649 -408.31135) (xy 110.43285 -408.31135)
			(xy 110.27918 -408.46502) (xy 110.27918 -409.362148) (xy 110.36808 -409.451048) (xy 111.49838 -409.451048)
		)
		(stroke
			(width 0)
			(type solid)
		)
		(fill yes)
		(layer "B.Cu")
		(net "GND")
	)
	(gr_poly
		(pts
			(xy 117.952266 -297.230546) (xy 117.952266 -292.837108) (xy 117.703346 -292.588188) (xy 115.838986 -292.588188)
			(xy 115.628166 -292.799008) (xy 115.628166 -297.225212) (xy 115.9002 -297.497246) (xy 117.685566 -297.497246)
		)
		(stroke
			(width 0)
			(type solid)
		)
		(fill yes)
		(layer "B.Cu")
		(net "GND")
	)
	(gr_poly
		(pts
			(xy 118.96471 -261.2771) (xy 118.96471 -259.9309) (xy 118.866412 -259.832348) (xy 115.832128 -259.832348)
			(xy 115.70335 -259.96138) (xy 115.70335 -261.35076) (xy 115.83162 -261.47903) (xy 118.76278 -261.47903)
		)
		(stroke
			(width 0)
			(type solid)
		)
		(fill yes)
		(layer "B.Cu")
		(net "PVCCFA_EHV_FIVRA_CPU1")
	)
	(gr_poly
		(pts
			(xy 123.027186 -297.48226) (xy 123.027186 -292.778434) (xy 122.890026 -292.641274) (xy 122.133106 -292.641274)
			(xy 121.978166 -292.796214) (xy 121.978166 -297.47464) (xy 122.12574 -297.622214) (xy 122.887232 -297.622214)
		)
		(stroke
			(width 0)
			(type solid)
		)
		(fill yes)
		(layer "B.Cu")
		(net "GND")
	)
	(gr_poly
		(pts
			(xy 159.701484 -323.332856) (xy 159.701484 -322.062856) (xy 159.574484 -321.935856) (xy 158.050484 -321.935856)
			(xy 157.923484 -322.062856) (xy 157.923484 -323.332856) (xy 158.304484 -323.713856) (xy 159.320484 -323.713856)
		)
		(stroke
			(width 0)
			(type solid)
		)
		(fill yes)
		(layer "B.Cu")
		(net "GND")
	)
	(gr_poly
		(pts
			(xy 163.765484 -323.332856) (xy 163.765484 -322.062856) (xy 163.638484 -321.935856) (xy 162.114484 -321.935856)
			(xy 161.987484 -322.062856) (xy 161.987484 -323.332856) (xy 162.368484 -323.713856) (xy 163.384484 -323.713856)
		)
		(stroke
			(width 0)
			(type solid)
		)
		(fill yes)
		(layer "B.Cu")
		(net "GND")
	)
	(gr_poly
		(pts
			(xy 167.245284 -323.332856) (xy 167.245284 -322.062856) (xy 167.118284 -321.935856) (xy 165.594284 -321.935856)
			(xy 165.467284 -322.062856) (xy 165.467284 -323.332856) (xy 165.848284 -323.713856) (xy 166.864284 -323.713856)
		)
		(stroke
			(width 0)
			(type solid)
		)
		(fill yes)
		(layer "B.Cu")
		(net "GND")
	)
	(gr_poly
		(pts
			(xy 168.50868 -101.920548) (xy 168.50868 -101.209348) (xy 168.45788 -101.158548) (xy 167.08628 -101.158548)
			(xy 167.03548 -101.209348) (xy 167.03548 -101.920548) (xy 167.08628 -101.971348) (xy 168.45788 -101.971348)
		)
		(stroke
			(width 0)
			(type solid)
		)
		(fill yes)
		(layer "B.Cu")
		(net "P3V3_AUX")
	)
	(gr_poly
		(pts
			(xy 168.68648 -103.977948) (xy 168.68648 -102.479348) (xy 168.58488 -102.377748) (xy 167.54348 -102.377748)
			(xy 167.41648 -102.504748) (xy 167.41648 -104.003348) (xy 167.46728 -104.054148) (xy 168.61028 -104.054148)
		)
		(stroke
			(width 0)
			(type solid)
		)
		(fill yes)
		(layer "B.Cu")
		(net "GND")
	)
	(gr_poly
		(pts
			(xy 170.71848 -103.927148) (xy 170.71848 -101.209348) (xy 170.66768 -101.158548) (xy 169.04208 -101.158548)
			(xy 168.99128 -101.209348) (xy 168.99128 -103.952548) (xy 169.06748 -104.028748) (xy 170.61688 -104.028748)
		)
		(stroke
			(width 0)
			(type solid)
		)
		(fill yes)
		(layer "B.Cu")
		(net "P3V3_AUX_FPGA_VCCIO0")
	)
	(gr_poly
		(pts
			(xy 171.309284 -323.332856) (xy 171.309284 -322.062856) (xy 171.182284 -321.935856) (xy 169.658284 -321.935856)
			(xy 169.531284 -322.062856) (xy 169.531284 -323.332856) (xy 169.912284 -323.713856) (xy 170.928284 -323.713856)
		)
		(stroke
			(width 0)
			(type solid)
		)
		(fill yes)
		(layer "B.Cu")
		(net "GND")
	)
	(gr_poly
		(pts
			(xy 172.71873 -101.920548) (xy 172.71873 -101.209348) (xy 172.66793 -101.158548) (xy 171.29633 -101.158548)
			(xy 171.24553 -101.209348) (xy 171.24553 -101.920548) (xy 171.29633 -101.971348) (xy 172.66793 -101.971348)
		)
		(stroke
			(width 0)
			(type solid)
		)
		(fill yes)
		(layer "B.Cu")
		(net "P3V3_AUX")
	)
	(gr_poly
		(pts
			(xy 172.89653 -103.977948) (xy 172.89653 -102.479348) (xy 172.79493 -102.377748) (xy 171.75353 -102.377748)
			(xy 171.62653 -102.504748) (xy 171.62653 -104.003348) (xy 171.67733 -104.054148) (xy 172.82033 -104.054148)
		)
		(stroke
			(width 0)
			(type solid)
		)
		(fill yes)
		(layer "B.Cu")
		(net "GND")
	)
	(gr_poly
		(pts
			(xy 174.70628 -125.034548) (xy 174.70628 -124.272548) (xy 174.65548 -124.221748) (xy 173.33468 -124.221748)
			(xy 173.28388 -124.272548) (xy 173.28388 -125.034548) (xy 173.33468 -125.085348) (xy 174.65548 -125.085348)
		)
		(stroke
			(width 0)
			(type solid)
		)
		(fill yes)
		(layer "B.Cu")
		(net "P3V3_AUX")
	)
	(gr_poly
		(pts
			(xy 174.789084 -323.332856) (xy 174.789084 -322.062856) (xy 174.662084 -321.935856) (xy 173.138084 -321.935856)
			(xy 173.011084 -322.062856) (xy 173.011084 -323.332856) (xy 173.392084 -323.713856) (xy 174.408084 -323.713856)
		)
		(stroke
			(width 0)
			(type solid)
		)
		(fill yes)
		(layer "B.Cu")
		(net "GND")
	)
	(gr_poly
		(pts
			(xy 176.86528 -125.263148) (xy 176.86528 -124.170948) (xy 176.81448 -124.120148) (xy 175.13808 -124.120148)
			(xy 175.11268 -124.145548) (xy 175.11268 -125.263148) (xy 175.16348 -125.313948) (xy 176.81448 -125.313948)
		)
		(stroke
			(width 0)
			(type solid)
		)
		(fill yes)
		(layer "B.Cu")
		(net "GND")
	)
	(gr_poly
		(pts
			(xy 177.77968 -101.920548) (xy 177.77968 -101.209348) (xy 177.72888 -101.158548) (xy 176.35728 -101.158548)
			(xy 176.30648 -101.209348) (xy 176.30648 -101.920548) (xy 176.35728 -101.971348) (xy 177.72888 -101.971348)
		)
		(stroke
			(width 0)
			(type solid)
		)
		(fill yes)
		(layer "B.Cu")
		(net "P3V3_AUX")
	)
	(gr_poly
		(pts
			(xy 178.853084 -323.332856) (xy 178.853084 -322.062856) (xy 178.726084 -321.935856) (xy 177.202084 -321.935856)
			(xy 177.075084 -322.062856) (xy 177.075084 -323.332856) (xy 177.456084 -323.713856) (xy 178.472084 -323.713856)
		)
		(stroke
			(width 0)
			(type solid)
		)
		(fill yes)
		(layer "B.Cu")
		(net "GND")
	)
	(gr_poly
		(pts
			(xy 179.98948 -103.927148) (xy 179.98948 -101.209348) (xy 179.93868 -101.158548) (xy 178.31308 -101.158548)
			(xy 178.26228 -101.209348) (xy 178.26228 -103.952548) (xy 178.33848 -104.028748) (xy 179.88788 -104.028748)
		)
		(stroke
			(width 0)
			(type solid)
		)
		(fill yes)
		(layer "B.Cu")
		(net "P3V3_AUX_FPGA_VCCIO4")
	)
	(gr_poly
		(pts
			(xy 181.69763 -124.399548) (xy 181.69763 -122.900948) (xy 181.62143 -122.824748) (xy 180.47843 -122.824748)
			(xy 180.42763 -122.875548) (xy 180.42763 -124.374148) (xy 180.55463 -124.501148) (xy 181.59603 -124.501148)
		)
		(stroke
			(width 0)
			(type solid)
		)
		(fill yes)
		(layer "B.Cu")
		(net "GND")
	)
	(gr_poly
		(pts
			(xy 181.70652 -126.020068) (xy 181.70652 -125.059694) (xy 181.579774 -124.932948) (xy 179.99583 -124.932948)
			(xy 179.94503 -124.983748) (xy 179.94503 -126.107698) (xy 180.04028 -126.202948) (xy 181.52364 -126.202948)
		)
		(stroke
			(width 0)
			(type solid)
		)
		(fill yes)
		(layer "B.Cu")
		(net "P3V3_AUX")
	)
	(gr_poly
		(pts
			(xy 182.332884 -323.332856) (xy 182.332884 -322.062856) (xy 182.205884 -321.935856) (xy 180.681884 -321.935856)
			(xy 180.554884 -322.062856) (xy 180.554884 -323.332856) (xy 180.935884 -323.713856) (xy 181.951884 -323.713856)
		)
		(stroke
			(width 0)
			(type solid)
		)
		(fill yes)
		(layer "B.Cu")
		(net "GND")
	)
	(gr_poly
		(pts
			(xy 182.35168 -101.920548) (xy 182.35168 -101.209348) (xy 182.30088 -101.158548) (xy 180.92928 -101.158548)
			(xy 180.87848 -101.209348) (xy 180.87848 -101.920548) (xy 180.92928 -101.971348) (xy 182.30088 -101.971348)
		)
		(stroke
			(width 0)
			(type solid)
		)
		(fill yes)
		(layer "B.Cu")
		(net "P3V3_AUX")
	)
	(gr_poly
		(pts
			(xy 184.56148 -103.927148) (xy 184.56148 -101.209348) (xy 184.51068 -101.158548) (xy 182.88508 -101.158548)
			(xy 182.83428 -101.209348) (xy 182.83428 -103.952548) (xy 182.91048 -104.028748) (xy 184.45988 -104.028748)
		)
		(stroke
			(width 0)
			(type solid)
		)
		(fill yes)
		(layer "B.Cu")
		(net "P3V3_AUX_FPGA_VCCIO3")
	)
	(gr_poly
		(pts
			(xy 184.798208 -404.264622) (xy 184.798208 -403.070822) (xy 184.620916 -402.893276) (xy 183.3245 -402.893276)
			(xy 183.191912 -403.025864) (xy 183.191912 -404.30958) (xy 183.325008 -404.442422) (xy 184.620408 -404.442422)
		)
		(stroke
			(width 0)
			(type solid)
		)
		(fill yes)
		(layer "B.Cu")
		(net "AGND_HSC")
	)
	(gr_poly
		(pts
			(xy 186.396884 -323.332856) (xy 186.396884 -322.062856) (xy 186.269884 -321.935856) (xy 184.745884 -321.935856)
			(xy 184.618884 -322.062856) (xy 184.618884 -323.332856) (xy 184.999884 -323.713856) (xy 186.015884 -323.713856)
		)
		(stroke
			(width 0)
			(type solid)
		)
		(fill yes)
		(layer "B.Cu")
		(net "GND")
	)
	(gr_poly
		(pts
			(xy 189.31128 -103.854758) (xy 189.31128 -102.504748) (xy 189.18428 -102.377748) (xy 188.14288 -102.377748)
			(xy 188.04128 -102.479348) (xy 188.04128 -103.977948) (xy 188.11748 -104.054148) (xy 189.11189 -104.054148)
		)
		(stroke
			(width 0)
			(type solid)
		)
		(fill yes)
		(layer "B.Cu")
		(net "GND")
	)
	(gr_poly
		(pts
			(xy 189.876684 -323.332856) (xy 189.876684 -322.062856) (xy 189.749684 -321.935856) (xy 188.225684 -321.935856)
			(xy 188.098684 -322.062856) (xy 188.098684 -323.332856) (xy 188.479684 -323.713856) (xy 189.495684 -323.713856)
		)
		(stroke
			(width 0)
			(type solid)
		)
		(fill yes)
		(layer "B.Cu")
		(net "GND")
	)
	(gr_poly
		(pts
			(xy 193.940684 -323.332856) (xy 193.940684 -322.062856) (xy 193.813684 -321.935856) (xy 192.289684 -321.935856)
			(xy 192.162684 -322.062856) (xy 192.162684 -323.332856) (xy 192.543684 -323.713856) (xy 193.559684 -323.713856)
		)
		(stroke
			(width 0)
			(type solid)
		)
		(fill yes)
		(layer "B.Cu")
		(net "GND")
	)
	(gr_poly
		(pts
			(xy 197.420484 -323.332856) (xy 197.420484 -322.062856) (xy 197.293484 -321.935856) (xy 195.769484 -321.935856)
			(xy 195.642484 -322.062856) (xy 195.642484 -323.332856) (xy 196.023484 -323.713856) (xy 197.039484 -323.713856)
		)
		(stroke
			(width 0)
			(type solid)
		)
		(fill yes)
		(layer "B.Cu")
		(net "GND")
	)
	(gr_poly
		(pts
			(xy 201.484484 -323.332856) (xy 201.484484 -322.062856) (xy 201.357484 -321.935856) (xy 199.833484 -321.935856)
			(xy 199.706484 -322.062856) (xy 199.706484 -323.332856) (xy 200.087484 -323.713856) (xy 201.103484 -323.713856)
		)
		(stroke
			(width 0)
			(type solid)
		)
		(fill yes)
		(layer "B.Cu")
		(net "GND")
	)
	(gr_poly
		(pts
			(xy 204.964284 -323.332856) (xy 204.964284 -322.062856) (xy 204.837284 -321.935856) (xy 203.313284 -321.935856)
			(xy 203.186284 -322.062856) (xy 203.186284 -323.332856) (xy 203.567284 -323.713856) (xy 204.583284 -323.713856)
		)
		(stroke
			(width 0)
			(type solid)
		)
		(fill yes)
		(layer "B.Cu")
		(net "GND")
	)
	(gr_poly
		(pts
			(xy 209.028284 -323.332856) (xy 209.028284 -322.062856) (xy 208.901284 -321.935856) (xy 207.377284 -321.935856)
			(xy 207.250284 -322.062856) (xy 207.250284 -323.332856) (xy 207.631284 -323.713856) (xy 208.647284 -323.713856)
		)
		(stroke
			(width 0)
			(type solid)
		)
		(fill yes)
		(layer "B.Cu")
		(net "GND")
	)
	(gr_poly
		(pts
			(xy 210.27136 -35.535108) (xy 210.27136 -34.016188) (xy 210.19262 -33.937448) (xy 208.44256 -33.937448)
			(xy 208.25714 -34.122868) (xy 208.25714 -35.573208) (xy 208.36382 -35.679888) (xy 210.12658 -35.679888)
		)
		(stroke
			(width 0)
			(type solid)
		)
		(fill yes)
		(layer "B.Cu")
		(net "GND")
	)
	(gr_poly
		(pts
			(xy 214.387684 -323.282056) (xy 214.387684 -321.961256) (xy 214.286084 -321.859656) (xy 210.933284 -321.859656)
			(xy 210.730084 -322.062856) (xy 210.730084 -323.332856) (xy 211.111084 -323.713856) (xy 213.955884 -323.713856)
		)
		(stroke
			(width 0)
			(type solid)
		)
		(fill yes)
		(layer "B.Cu")
		(net "GND")
	)
	(gr_poly
		(pts
			(xy 216.0524 -55.982108) (xy 216.0524 -52.931568) (xy 215.93556 -52.814728) (xy 214.82812 -52.814728)
			(xy 214.49284 -53.150008) (xy 214.49284 -56.162448) (xy 214.63762 -56.307228) (xy 215.72728 -56.307228)
		)
		(stroke
			(width 0)
			(type solid)
		)
		(fill yes)
		(layer "B.Cu")
		(net "GND")
	)
	(gr_poly
		(pts
			(xy 217.33256 -26.947368) (xy 217.33256 -25.212548) (xy 216.7382 -24.618188) (xy 213.22538 -24.618188)
			(xy 213.03488 -24.808688) (xy 213.03488 -27.396948) (xy 213.26856 -27.630628) (xy 216.6493 -27.630628)
		)
		(stroke
			(width 0)
			(type solid)
		)
		(fill yes)
		(layer "B.Cu")
		(net "GND")
	)
	(gr_poly
		(pts
			(xy 238.905034 -98.138996) (xy 238.905034 -96.471232) (xy 238.718344 -96.284542) (xy 236.570012 -96.284542)
			(xy 236.36986 -96.484694) (xy 236.36986 -98.285554) (xy 236.503464 -98.419158) (xy 238.624872 -98.419158)
		)
		(stroke
			(width 0)
			(type solid)
		)
		(fill yes)
		(layer "B.Cu")
		(net "P3V3_AUX")
	)
	(gr_poly
		(pts
			(xy 241.77498 -246.205248) (xy 241.77498 -244.130068) (xy 241.5921 -243.947188) (xy 238.67364 -243.947188)
			(xy 238.3917 -244.229128) (xy 238.3917 -246.238268) (xy 238.57458 -246.421148) (xy 241.55908 -246.421148)
		)
		(stroke
			(width 0)
			(type solid)
		)
		(fill yes)
		(layer "B.Cu")
		(net "P3V3_AUX")
	)
	(gr_poly
		(pts
			(xy 249.511312 -89.374472) (xy 249.511312 -86.478872) (xy 249.333512 -86.301072) (xy 245.904512 -86.301072)
			(xy 245.752112 -86.453472) (xy 245.752112 -89.653872) (xy 245.929912 -89.831672) (xy 249.054112 -89.831672)
		)
		(stroke
			(width 0)
			(type solid)
		)
		(fill yes)
		(layer "B.Cu")
		(net "GND")
	)
	(gr_poly
		(pts
			(xy 252.02388 -99.659948) (xy 252.02388 -99.050348) (xy 251.97308 -98.999548) (xy 250.67768 -98.999548)
			(xy 250.44908 -99.228148) (xy 250.44908 -99.736148) (xy 250.52528 -99.812348) (xy 251.87148 -99.812348)
		)
		(stroke
			(width 0)
			(type solid)
		)
		(fill yes)
		(layer "B.Cu")
		(net "P3V3_AUX_CLK_GEN_VDDPT_CK440")
	)
	(gr_poly
		(pts
			(xy 258.899152 -323.302376) (xy 258.899152 -322.032376) (xy 258.772152 -321.905376) (xy 257.248152 -321.905376)
			(xy 257.121152 -322.032376) (xy 257.121152 -323.302376) (xy 257.502152 -323.683376) (xy 258.518152 -323.683376)
		)
		(stroke
			(width 0)
			(type solid)
		)
		(fill yes)
		(layer "B.Cu")
		(net "GND")
	)
	(gr_poly
		(pts
			(xy 261.032752 -323.327776) (xy 261.032752 -322.057776) (xy 260.905752 -321.930776) (xy 259.381752 -321.930776)
			(xy 259.254752 -322.057776) (xy 259.254752 -323.327776) (xy 259.635752 -323.708776) (xy 260.651752 -323.708776)
		)
		(stroke
			(width 0)
			(type solid)
		)
		(fill yes)
		(layer "B.Cu")
		(net "GND")
	)
	(gr_poly
		(pts
			(xy 264.06348 -108.524548) (xy 264.06348 -107.279948) (xy 263.98728 -107.203748) (xy 261.75208 -107.203748)
			(xy 261.59968 -107.356148) (xy 261.59968 -108.651548) (xy 261.98068 -109.032548) (xy 263.55548 -109.032548)
		)
		(stroke
			(width 0)
			(type solid)
		)
		(fill yes)
		(layer "B.Cu")
		(net "GND")
	)
	(gr_poly
		(pts
			(xy 264.512552 -323.327776) (xy 264.512552 -322.057776) (xy 264.385552 -321.930776) (xy 262.861552 -321.930776)
			(xy 262.734552 -322.057776) (xy 262.734552 -323.327776) (xy 263.115552 -323.708776) (xy 264.131552 -323.708776)
		)
		(stroke
			(width 0)
			(type solid)
		)
		(fill yes)
		(layer "B.Cu")
		(net "GND")
	)
	(gr_poly
		(pts
			(xy 268.576552 -323.327776) (xy 268.576552 -322.057776) (xy 268.449552 -321.930776) (xy 266.925552 -321.930776)
			(xy 266.798552 -322.057776) (xy 266.798552 -323.327776) (xy 267.179552 -323.708776) (xy 268.195552 -323.708776)
		)
		(stroke
			(width 0)
			(type solid)
		)
		(fill yes)
		(layer "B.Cu")
		(net "GND")
	)
	(gr_poly
		(pts
			(xy 272.056352 -323.327776) (xy 272.056352 -322.057776) (xy 271.929352 -321.930776) (xy 270.405352 -321.930776)
			(xy 270.278352 -322.057776) (xy 270.278352 -323.327776) (xy 270.659352 -323.708776) (xy 271.675352 -323.708776)
		)
		(stroke
			(width 0)
			(type solid)
		)
		(fill yes)
		(layer "B.Cu")
		(net "GND")
	)
	(gr_poly
		(pts
			(xy 276.120352 -323.327776) (xy 276.120352 -322.057776) (xy 275.993352 -321.930776) (xy 274.469352 -321.930776)
			(xy 274.342352 -322.057776) (xy 274.342352 -323.327776) (xy 274.723352 -323.708776) (xy 275.739352 -323.708776)
		)
		(stroke
			(width 0)
			(type solid)
		)
		(fill yes)
		(layer "B.Cu")
		(net "GND")
	)
	(gr_poly
		(pts
			(xy 279.600152 -323.327776) (xy 279.600152 -322.057776) (xy 279.473152 -321.930776) (xy 277.949152 -321.930776)
			(xy 277.822152 -322.057776) (xy 277.822152 -323.327776) (xy 278.203152 -323.708776) (xy 279.219152 -323.708776)
		)
		(stroke
			(width 0)
			(type solid)
		)
		(fill yes)
		(layer "B.Cu")
		(net "GND")
	)
	(gr_poly
		(pts
			(xy 283.664152 -323.327776) (xy 283.664152 -322.057776) (xy 283.537152 -321.930776) (xy 282.013152 -321.930776)
			(xy 281.886152 -322.057776) (xy 281.886152 -323.327776) (xy 282.267152 -323.708776) (xy 283.283152 -323.708776)
		)
		(stroke
			(width 0)
			(type solid)
		)
		(fill yes)
		(layer "B.Cu")
		(net "GND")
	)
	(gr_poly
		(pts
			(xy 287.143952 -323.327776) (xy 287.143952 -322.057776) (xy 287.016952 -321.930776) (xy 285.492952 -321.930776)
			(xy 285.365952 -322.057776) (xy 285.365952 -323.327776) (xy 285.746952 -323.708776) (xy 286.762952 -323.708776)
		)
		(stroke
			(width 0)
			(type solid)
		)
		(fill yes)
		(layer "B.Cu")
		(net "GND")
	)
	(gr_poly
		(pts
			(xy 291.758878 -323.21373) (xy 291.758878 -322.116196) (xy 291.573458 -321.930776) (xy 289.101276 -321.930776)
			(xy 288.766504 -322.265548) (xy 288.766504 -323.251576) (xy 288.921698 -323.40677) (xy 291.565838 -323.40677)
		)
		(stroke
			(width 0)
			(type solid)
		)
		(fill yes)
		(layer "B.Cu")
		(net "GND")
	)
	(gr_poly
		(pts
			(xy 299.233844 -323.13245) (xy 299.233844 -322.162424) (xy 299.002196 -321.930776) (xy 297.100752 -321.930776)
			(xy 296.973752 -322.057776) (xy 296.973752 -323.08419) (xy 297.258232 -323.36867) (xy 298.997624 -323.36867)
		)
		(stroke
			(width 0)
			(type solid)
		)
		(fill yes)
		(layer "B.Cu")
		(net "GND")
	)
	(gr_poly
		(pts
			(xy 306.295552 -323.327776) (xy 306.295552 -322.057776) (xy 306.168552 -321.930776) (xy 304.644552 -321.930776)
			(xy 304.517552 -322.057776) (xy 304.517552 -323.327776) (xy 304.898552 -323.708776) (xy 305.914552 -323.708776)
		)
		(stroke
			(width 0)
			(type solid)
		)
		(fill yes)
		(layer "B.Cu")
		(net "GND")
	)
	(gr_poly
		(pts
			(xy 310.420258 -323.162676) (xy 310.420258 -322.09867) (xy 310.252364 -321.930776) (xy 308.124352 -321.930776)
			(xy 307.997352 -322.057776) (xy 307.997352 -323.327776) (xy 308.116732 -323.447156) (xy 310.135778 -323.447156)
		)
		(stroke
			(width 0)
			(type solid)
		)
		(fill yes)
		(layer "B.Cu")
		(net "GND")
	)
	(gr_poly
		(pts
			(xy 337.575652 -46.566328) (xy 337.575652 -45.282104) (xy 337.541616 -45.248068) (xy 337.119976 -45.248068)
			(xy 337.047078 -45.320966) (xy 337.047078 -46.505368) (xy 337.224878 -46.683168) (xy 337.458812 -46.683168)
		)
		(stroke
			(width 0)
			(type solid)
		)
		(fill yes)
		(layer "B.Cu")
		(net "GND")
	)
	(gr_poly
		(pts
			(xy 353.193096 -297.019726) (xy 353.193096 -293.221918) (xy 352.657664 -292.686486) (xy 351.392744 -292.686486)
			(xy 350.851724 -293.227506) (xy 350.851724 -297.027346) (xy 351.13087 -297.306492) (xy 352.90633 -297.306492)
		)
		(stroke
			(width 0)
			(type solid)
		)
		(fill yes)
		(layer "B.Cu")
		(net "GND")
	)
	(gr_poly
		(pts
			(xy 359.520744 -297.278806) (xy 359.520744 -292.808406) (xy 359.285032 -292.572948) (xy 357.46055 -292.572948)
			(xy 357.200708 -292.83279) (xy 357.200708 -297.27525) (xy 357.407464 -297.482006) (xy 359.317544 -297.482006)
		)
		(stroke
			(width 0)
			(type solid)
		)
		(fill yes)
		(layer "B.Cu")
		(net "GND")
	)
	(gr_poly
		(pts
			(xy 365.883444 -297.273726) (xy 365.883444 -292.763194) (xy 365.708184 -292.587934) (xy 363.744764 -292.587934)
			(xy 363.564424 -292.768274) (xy 363.564424 -297.344846) (xy 363.71657 -297.496992) (xy 365.660178 -297.496992)
		)
		(stroke
			(width 0)
			(type solid)
		)
		(fill yes)
		(layer "B.Cu")
		(net "GND")
	)
	(gr_poly
		(pts
			(xy 366.904524 -261.276846) (xy 366.904524 -259.930646) (xy 366.806226 -259.832348) (xy 363.771942 -259.832348)
			(xy 363.643164 -259.961126) (xy 363.643164 -261.350506) (xy 363.771434 -261.478776) (xy 366.702594 -261.478776)
		)
		(stroke
			(width 0)
			(type solid)
		)
		(fill yes)
		(layer "B.Cu")
		(net "PVCCFA_EHV_FIVRA_CPU0")
	)
	(gr_poly
		(pts
			(xy 370.960904 -297.283886) (xy 370.960904 -293.283386) (xy 370.877084 -293.199566) (xy 370.023644 -293.199566)
			(xy 369.922044 -293.301166) (xy 369.922044 -297.370246) (xy 370.016024 -297.464226) (xy 370.780564 -297.464226)
		)
		(stroke
			(width 0)
			(type solid)
		)
		(fill yes)
		(layer "B.Cu")
		(net "GND")
	)
	(gr_poly
		(pts
			(xy 393.560046 -78.046072) (xy 393.560046 -76.321158) (xy 393.336526 -76.097638) (xy 391.416286 -76.097638)
			(xy 391.157206 -76.356718) (xy 391.157206 -79.092298) (xy 391.368026 -79.303118) (xy 392.303 -79.303118)
		)
		(stroke
			(width 0)
			(type solid)
		)
		(fill yes)
		(layer "B.Cu")
		(net "P12V_AUX")
	)
	(gr_poly
		(pts
			(xy 407.648156 -323.556376) (xy 407.648156 -321.905376) (xy 407.597356 -321.854576) (xy 406.098756 -321.854576)
			(xy 406.022556 -321.930776) (xy 406.022556 -323.607176) (xy 406.124156 -323.708776) (xy 407.495756 -323.708776)
		)
		(stroke
			(width 0)
			(type solid)
		)
		(fill yes)
		(layer "B.Cu")
		(net "GND")
	)
	(gr_poly
		(pts
			(xy 411.712156 -323.556376) (xy 411.712156 -321.905376) (xy 411.661356 -321.854576) (xy 410.162756 -321.854576)
			(xy 410.086556 -321.930776) (xy 410.086556 -323.607176) (xy 410.188156 -323.708776) (xy 411.559756 -323.708776)
		)
		(stroke
			(width 0)
			(type solid)
		)
		(fill yes)
		(layer "B.Cu")
		(net "GND")
	)
	(gr_poly
		(pts
			(xy 415.191956 -323.556376) (xy 415.191956 -321.905376) (xy 415.141156 -321.854576) (xy 413.642556 -321.854576)
			(xy 413.566356 -321.930776) (xy 413.566356 -323.607176) (xy 413.667956 -323.708776) (xy 415.039556 -323.708776)
		)
		(stroke
			(width 0)
			(type solid)
		)
		(fill yes)
		(layer "B.Cu")
		(net "GND")
	)
	(gr_poly
		(pts
			(xy 419.255956 -323.556376) (xy 419.255956 -321.905376) (xy 419.205156 -321.854576) (xy 417.706556 -321.854576)
			(xy 417.630356 -321.930776) (xy 417.630356 -323.607176) (xy 417.731956 -323.708776) (xy 419.103556 -323.708776)
		)
		(stroke
			(width 0)
			(type solid)
		)
		(fill yes)
		(layer "B.Cu")
		(net "GND")
	)
	(gr_poly
		(pts
			(xy 422.735756 -323.556376) (xy 422.735756 -321.905376) (xy 422.684956 -321.854576) (xy 421.186356 -321.854576)
			(xy 421.110156 -321.930776) (xy 421.110156 -323.607176) (xy 421.211756 -323.708776) (xy 422.583356 -323.708776)
		)
		(stroke
			(width 0)
			(type solid)
		)
		(fill yes)
		(layer "B.Cu")
		(net "GND")
	)
	(gr_poly
		(pts
			(xy 426.799756 -323.556376) (xy 426.799756 -321.905376) (xy 426.748956 -321.854576) (xy 425.250356 -321.854576)
			(xy 425.174156 -321.930776) (xy 425.174156 -323.607176) (xy 425.275756 -323.708776) (xy 426.647356 -323.708776)
		)
		(stroke
			(width 0)
			(type solid)
		)
		(fill yes)
		(layer "B.Cu")
		(net "GND")
	)
	(gr_poly
		(pts
			(xy 427.559216 -138.21791) (xy 427.559216 -133.59511) (xy 427.508416 -133.54431) (xy 423.901616 -133.54431)
			(xy 423.850816 -133.59511) (xy 423.850816 -138.21791) (xy 423.901616 -138.26871) (xy 427.508416 -138.26871)
		)
		(stroke
			(width 0)
			(type solid)
		)
		(fill yes)
		(layer "B.Cu")
		(net "GND")
	)
	(gr_poly
		(pts
			(xy 430.279556 -323.556376) (xy 430.279556 -321.905376) (xy 430.228756 -321.854576) (xy 428.730156 -321.854576)
			(xy 428.653956 -321.930776) (xy 428.653956 -323.607176) (xy 428.755556 -323.708776) (xy 430.127156 -323.708776)
		)
		(stroke
			(width 0)
			(type solid)
		)
		(fill yes)
		(layer "B.Cu")
		(net "GND")
	)
	(gr_poly
		(pts
			(xy 434.343556 -323.556376) (xy 434.343556 -321.905376) (xy 434.292756 -321.854576) (xy 432.794156 -321.854576)
			(xy 432.717956 -321.930776) (xy 432.717956 -323.607176) (xy 432.819556 -323.708776) (xy 434.191156 -323.708776)
		)
		(stroke
			(width 0)
			(type solid)
		)
		(fill yes)
		(layer "B.Cu")
		(net "GND")
	)
	(gr_poly
		(pts
			(xy 435.33568 -13.503148) (xy 435.33568 -9.921748) (xy 435.23408 -9.820148) (xy 434.19268 -9.820148)
			(xy 433.81168 -10.201148) (xy 433.81168 -13.477748) (xy 433.98948 -13.655548) (xy 435.18328 -13.655548)
		)
		(stroke
			(width 0)
			(type solid)
		)
		(fill yes)
		(layer "B.Cu")
		(net "P3V3_OCP_SFF")
	)
	(gr_poly
		(pts
			(xy 437.823356 -323.556376) (xy 437.823356 -321.905376) (xy 437.772556 -321.854576) (xy 436.273956 -321.854576)
			(xy 436.197756 -321.930776) (xy 436.197756 -323.607176) (xy 436.299356 -323.708776) (xy 437.670956 -323.708776)
		)
		(stroke
			(width 0)
			(type solid)
		)
		(fill yes)
		(layer "B.Cu")
		(net "GND")
	)
	(gr_poly
		(pts
			(xy 441.887356 -323.556376) (xy 441.887356 -321.905376) (xy 441.836556 -321.854576) (xy 440.337956 -321.854576)
			(xy 440.261756 -321.930776) (xy 440.261756 -323.607176) (xy 440.363356 -323.708776) (xy 441.734956 -323.708776)
		)
		(stroke
			(width 0)
			(type solid)
		)
		(fill yes)
		(layer "B.Cu")
		(net "GND")
	)
	(gr_poly
		(pts
			(xy 442.4426 -372.430548) (xy 442.4426 -368.849148) (xy 442.0616 -368.468148) (xy 439.4454 -368.468148)
			(xy 439.039 -368.874548) (xy 439.039 -372.303548) (xy 439.4708 -372.735348) (xy 442.1378 -372.735348)
		)
		(stroke
			(width 0)
			(type solid)
		)
		(fill yes)
		(layer "B.Cu")
		(net "P5V")
	)
	(gr_poly
		(pts
			(xy 445.367156 -323.556376) (xy 445.367156 -321.905376) (xy 445.316356 -321.854576) (xy 443.817756 -321.854576)
			(xy 443.741556 -321.930776) (xy 443.741556 -323.607176) (xy 443.843156 -323.708776) (xy 445.214756 -323.708776)
		)
		(stroke
			(width 0)
			(type solid)
		)
		(fill yes)
		(layer "B.Cu")
		(net "GND")
	)
	(gr_poly
		(pts
			(xy 449.431156 -323.556376) (xy 449.431156 -321.905376) (xy 449.380356 -321.854576) (xy 447.881756 -321.854576)
			(xy 447.805556 -321.930776) (xy 447.805556 -323.607176) (xy 447.907156 -323.708776) (xy 449.278756 -323.708776)
		)
		(stroke
			(width 0)
			(type solid)
		)
		(fill yes)
		(layer "B.Cu")
		(net "GND")
	)
	(gr_poly
		(pts
			(xy 450.626988 -184.289192) (xy 450.626988 -176.3395) (xy 449.883276 -175.595788) (xy 447.28892 -175.595788)
			(xy 447.068956 -175.815752) (xy 447.068956 -184.3151) (xy 447.449448 -184.695592) (xy 450.220588 -184.695592)
		)
		(stroke
			(width 0)
			(type solid)
		)
		(fill yes)
		(layer "B.Cu")
		(net "GND")
	)
	(gr_poly
		(pts
			(xy 452.910956 -323.556376) (xy 452.910956 -321.905376) (xy 452.860156 -321.854576) (xy 451.361556 -321.854576)
			(xy 451.285356 -321.930776) (xy 451.285356 -323.607176) (xy 451.386956 -323.708776) (xy 452.758556 -323.708776)
		)
		(stroke
			(width 0)
			(type solid)
		)
		(fill yes)
		(layer "B.Cu")
		(net "GND")
	)
	(gr_poly
		(pts
			(xy 456.974956 -323.556376) (xy 456.974956 -321.905376) (xy 456.924156 -321.854576) (xy 455.425556 -321.854576)
			(xy 455.349356 -321.930776) (xy 455.349356 -323.607176) (xy 455.450956 -323.708776) (xy 456.822556 -323.708776)
		)
		(stroke
			(width 0)
			(type solid)
		)
		(fill yes)
		(layer "B.Cu")
		(net "GND")
	)
	(gr_poly
		(pts
			(xy 462.207356 -323.530976) (xy 462.207356 -322.032376) (xy 462.080356 -321.905376) (xy 458.905356 -321.905376)
			(xy 458.727556 -322.083176) (xy 458.727556 -323.480176) (xy 458.930756 -323.683376) (xy 462.054956 -323.683376)
		)
		(stroke
			(width 0)
			(type solid)
		)
		(fill yes)
		(layer "B.Cu")
		(net "GND")
	)
	(gr_poly
		(pts
			(xy 173.47692 -364.743492) (xy 173.47692 -361.583732) (xy 173.17974 -361.286552) (xy 169.62882 -361.286552)
			(xy 169.452544 -361.462828) (xy 169.452544 -364.573312) (xy 169.452544 -364.666276) (xy 169.67962 -364.893352)
			(xy 173.32706 -364.893352)
		)
		(stroke
			(width 0)
			(type solid)
		)
		(fill yes)
		(layer "B.Cu")
		(net "P12V_AUX")
	)
	(gr_poly
		(pts
			(xy 290.227258 -373.976392) (xy 290.227258 -370.823998) (xy 289.911028 -370.507768) (xy 286.390842 -370.507768)
			(xy 286.214566 -370.684044) (xy 286.214566 -373.794528) (xy 286.214566 -373.887492) (xy 286.441642 -374.114568)
			(xy 290.089082 -374.114568)
		)
		(stroke
			(width 0)
			(type solid)
		)
		(fill yes)
		(layer "B.Cu")
		(net "P12V_AUX")
	)
	(gr_poly
		(pts
			(xy 34.959798 -395.15796) (xy 37.80155 -395.15796) (xy 38.28796 -394.67155) (xy 38.28796 -392.478006)
			(xy 38.157912 -392.347958) (xy 34.519108 -392.347958) (xy 32.463994 -394.403072) (xy 32.463994 -395.409674)
			(xy 32.642302 -395.587982) (xy 34.529776 -395.587982)
		)
		(stroke
			(width 0)
			(type solid)
		)
		(fill yes)
		(layer "B.Cu")
		(net "P3V3_AUX")
	)
	(gr_poly
		(pts
			(xy 40.26916 -183.479948) (xy 40.26916 -178.948588) (xy 38.80104 -177.480468) (xy 38.80104 -175.758348)
			(xy 38.31082 -175.268128) (xy 37.27704 -175.268128) (xy 36.94938 -175.595788) (xy 36.94938 -183.548528)
			(xy 37.084 -183.683148) (xy 40.06596 -183.683148)
		)
		(stroke
			(width 0)
			(type solid)
		)
		(fill yes)
		(layer "B.Cu")
		(net "GND")
	)
	(gr_poly
		(pts
			(xy 104.272588 -259.164836) (xy 104.587548 -259.164836) (xy 104.733344 -259.01904) (xy 104.733344 -256.51714)
			(xy 104.50068 -256.284476) (xy 102.921816 -256.284476) (xy 102.757986 -256.44856) (xy 102.757986 -259.0419)
			(xy 102.882192 -259.16636) (xy 104.271064 -259.16636)
		)
		(stroke
			(width 0)
			(type solid)
		)
		(fill yes)
		(layer "B.Cu")
		(net "PVCCFA_EHV_CPU1")
	)
	(gr_poly
		(pts
			(xy 104.698546 -236.16666) (xy 104.698546 -235.68914) (xy 104.657906 -235.6485) (xy 104.617266 -235.60786)
			(xy 104.457246 -235.60786) (xy 102.984046 -235.60786) (xy 102.935786 -235.65612) (xy 102.935786 -235.88726)
			(xy 103.278686 -236.23016) (xy 104.635046 -236.23016)
		)
		(stroke
			(width 0)
			(type solid)
		)
		(fill yes)
		(layer "B.Cu")
		(net "P3V3_AUX")
	)
	(gr_poly
		(pts
			(xy 109.60862 -417.304728) (xy 109.60862 -415.348928) (xy 109.54258 -415.282888) (xy 108.31068 -415.282888)
			(xy 108.10748 -415.486088) (xy 108.10748 -416.243008) (xy 108.56468 -416.700208) (xy 108.56468 -417.459668)
			(xy 108.59008 -417.485068) (xy 109.42828 -417.485068)
		)
		(stroke
			(width 0)
			(type solid)
		)
		(fill yes)
		(layer "B.Cu")
		(net "P3V3_9ZXL045_VDDA")
	)
	(gr_poly
		(pts
			(xy 113.28908 -417.121848) (xy 113.28908 -416.753548) (xy 112.733328 -416.197796) (xy 110.61065 -416.197796)
			(xy 110.485936 -416.072828) (xy 110.10646 -416.072828) (xy 109.9058 -416.273488) (xy 109.9058 -416.865308)
			(xy 110.32744 -417.286948) (xy 113.12398 -417.286948)
		)
		(stroke
			(width 0)
			(type solid)
		)
		(fill yes)
		(layer "B.Cu")
		(net "P3V3_9ZXL045_VDD")
	)
	(gr_poly
		(pts
			(xy 237.285276 -121.459244) (xy 237.285276 -119.796814) (xy 237.079536 -119.591074) (xy 235.817156 -119.591074)
			(xy 235.199936 -120.208294) (xy 234.694476 -120.208294) (xy 234.463336 -120.439434) (xy 234.463336 -121.450354)
			(xy 234.613196 -121.600214) (xy 237.144306 -121.600214)
		)
		(stroke
			(width 0)
			(type solid)
		)
		(fill yes)
		(layer "B.Cu")
		(net "P3V3_DB2000_VDDR")
	)
	(gr_poly
		(pts
			(xy 244.508782 -98.292412) (xy 244.508782 -97.451926) (xy 244.41531 -97.358454) (xy 243.894864 -97.358454)
			(xy 243.394484 -97.858834) (xy 242.660678 -97.858834) (xy 242.640866 -97.878646) (xy 242.640866 -99.159568)
			(xy 242.720876 -99.239578) (xy 243.561616 -99.239578)
		)
		(stroke
			(width 0)
			(type solid)
		)
		(fill yes)
		(layer "B.Cu")
		(net "GND")
	)
	(gr_poly
		(pts
			(xy 252.20422 -51.957986) (xy 252.20422 -48.709326) (xy 251.20854 -47.713646) (xy 242.87734 -47.713646)
			(xy 241.75212 -48.838866) (xy 241.75212 -50.027586) (xy 244.21084 -52.486306) (xy 245.11508 -52.486306)
			(xy 245.3132 -52.684426) (xy 251.47778 -52.684426)
		)
		(stroke
			(width 0)
			(type solid)
		)
		(fill yes)
		(layer "B.Cu")
		(net "P12V_E1S_0")
	)
	(gr_poly
		(pts
			(xy 264.62228 -106.746548) (xy 264.62228 -104.739948) (xy 264.39368 -104.511348) (xy 261.77748 -104.511348)
			(xy 261.585456 -104.703372) (xy 261.585456 -105.63606) (xy 261.54888 -105.672636) (xy 261.54888 -106.848148)
			(xy 261.62508 -106.924348) (xy 264.44448 -106.924348)
		)
		(stroke
			(width 0)
			(type solid)
		)
		(fill yes)
		(layer "B.Cu")
		(net "P3V3_AUX_CLK_GEN_VDDPT_CK440")
	)
	(gr_poly
		(pts
			(xy 277.4188 -405.92248) (xy 280.90622 -405.92248) (xy 281.051508 -405.777192) (xy 281.051508 -397.72844)
			(xy 280.706068 -397.383) (xy 275.6408 -397.383) (xy 275.3868 -397.637) (xy 275.3868 -405.8285) (xy 275.48332 -405.92502)
			(xy 277.41626 -405.92502)
		)
		(stroke
			(width 0)
			(type solid)
		)
		(fill yes)
		(layer "B.Cu")
		(net "P12V_MAIN_R_0")
	)
	(gr_poly
		(pts
			(xy 295.384474 -323.373242) (xy 295.384474 -322.092574) (xy 295.222422 -321.930776) (xy 293.036752 -321.930776)
			(xy 293.03472 -321.932808) (xy 292.673532 -321.932808) (xy 292.436296 -322.170044) (xy 292.436296 -323.284088)
			(xy 292.709092 -323.556884) (xy 295.200832 -323.556884)
		)
		(stroke
			(width 0)
			(type solid)
		)
		(fill yes)
		(layer "B.Cu")
		(net "GND")
	)
	(gr_poly
		(pts
			(xy 313.846972 -324.35927) (xy 313.846972 -323.335396) (xy 313.839352 -323.327776) (xy 313.839352 -322.057776)
			(xy 313.712352 -321.930776) (xy 312.188352 -321.930776) (xy 312.061352 -322.057776) (xy 312.061352 -324.252844)
			(xy 312.279538 -324.47103) (xy 313.735212 -324.47103)
		)
		(stroke
			(width 0)
			(type solid)
		)
		(fill yes)
		(layer "B.Cu")
		(net "GND")
	)
	(gr_poly
		(pts
			(xy 339.26145 -49.622202) (xy 339.087968 -49.44872) (xy 338.94014 -49.596548) (xy 338.01812 -49.596548)
			(xy 337.826604 -49.788318) (xy 337.826604 -50.268378) (xy 337.733386 -50.361342) (xy 337.733386 -50.442368)
			(xy 337.830668 -50.539396) (xy 339.26145 -50.539396)
		)
		(stroke
			(width 0)
			(type solid)
		)
		(fill yes)
		(layer "B.Cu")
		(net "GND")
	)
	(gr_poly
		(pts
			(xy 344.006678 -360.86161) (xy 344.006678 -355.97211) (xy 343.703402 -355.668834) (xy 335.759044 -355.668834)
			(xy 335.75371 -355.674422) (xy 335.117186 -355.674422) (xy 334.822038 -355.96957) (xy 334.822038 -362.19003)
			(xy 335.030318 -362.39831) (xy 342.469978 -362.39831)
		)
		(stroke
			(width 0)
			(type solid)
		)
		(fill yes)
		(layer "B.Cu")
		(net "P12V_AUX")
	)
	(gr_poly
		(pts
			(xy 352.672904 -259.0292) (xy 352.672904 -256.44602) (xy 352.51136 -256.284476) (xy 350.861884 -256.284476)
			(xy 350.6978 -256.448306) (xy 350.6978 -259.041646) (xy 350.82226 -259.165852) (xy 352.488754 -259.165852)
			(xy 352.495104 -259.172456) (xy 352.529902 -259.172456)
		)
		(stroke
			(width 0)
			(type solid)
		)
		(fill yes)
		(layer "B.Cu")
		(net "PVCCFA_EHV_CPU0")
	)
	(gr_poly
		(pts
			(xy 417.608258 -379.13183) (xy 417.608258 -373.281702) (xy 417.608258 -370.09959) (xy 417.328858 -369.819936)
			(xy 413.764984 -369.819936) (xy 410.003752 -369.819936) (xy 409.52547 -370.298218) (xy 409.52547 -378.555758)
			(xy 410.57576 -379.606048) (xy 417.13404 -379.606048)
		)
		(stroke
			(width 0)
			(type solid)
		)
		(fill yes)
		(layer "B.Cu")
		(net "P12V_AUX")
	)
	(gr_poly
		(pts
			(xy 454.524618 -343.89695) (xy 454.524618 -336.47761) (xy 453.992488 -335.94548) (xy 447.406268 -335.94548)
			(xy 446.998598 -336.35315) (xy 446.020698 -336.35315) (xy 445.753998 -336.61985) (xy 445.753998 -344.00617)
			(xy 446.061338 -344.31351) (xy 454.108058 -344.31351)
		)
		(stroke
			(width 0)
			(type solid)
		)
		(fill yes)
		(layer "B.Cu")
		(net "P12V_AUX")
	)
	(gr_poly
		(pts
			(xy 469.5698 -59.426348) (xy 469.5698 -55.997348) (xy 469.3158 -55.743348) (xy 463.042 -55.743348)
			(xy 462.892648 -55.8927) (xy 462.892648 -56.582056) (xy 462.892648 -59.630056) (xy 462.943448 -59.680856)
			(xy 467.839298 -59.680856) (xy 469.315292 -59.680856)
		)
		(stroke
			(width 0)
			(type solid)
		)
		(fill yes)
		(layer "B.Cu")
		(net "P12V_AUX")
	)
	(gr_poly
		(pts
			(xy 171.83608 -54.033928) (xy 171.83608 -50.366168) (xy 171.20108 -49.731168) (xy 170.54322 -49.731168)
			(xy 170.34256 -49.931828) (xy 170.34256 -50.660808) (xy 169.857928 -51.14544) (xy 169.857928 -53.684678)
			(xy 169.8498 -53.692552) (xy 169.8498 -54.280308) (xy 171.5897 -54.280308)
		)
		(stroke
			(width 0)
			(type solid)
		)
		(fill yes)
		(layer "B.Cu")
		(net "GND")
	)
	(gr_poly
		(pts
			(xy 177.95748 -103.977948) (xy 177.95748 -102.479348) (xy 177.85588 -102.377748) (xy 176.81448 -102.377748)
			(xy 176.68748 -102.504748) (xy 176.68748 -103.914194)
			(arc
				(start 176.76114 -103.987854)
				(mid 176.78934 -104.019486)
				(end 176.813718 -104.054148)
			)
			(xy 177.88128 -104.054148)
		)
		(stroke
			(width 0)
			(type solid)
		)
		(fill yes)
		(layer "B.Cu")
		(net "GND")
	)
	(gr_poly
		(pts
			(xy 433.434998 -167.216582) (xy 433.434998 -166.934134) (xy 433.434998 -162.291014) (xy 433.287932 -162.143694)
			(xy 431.85588 -162.143694) (xy 431.16754 -162.143694) (xy 431.042572 -162.268662) (xy 431.042572 -167.087042)
			(xy 431.14722 -167.19169) (xy 431.44821 -167.49268) (xy 433.1589 -167.49268)
		)
		(stroke
			(width 0)
			(type solid)
		)
		(fill yes)
		(layer "B.Cu")
		(net "P12V_AUX")
	)
	(gr_poly
		(pts
			(xy 446.575434 -184.680606) (xy 446.799462 -184.456578) (xy 446.814448 -184.441592) (xy 446.814448 -175.766476)
			(xy 446.6336 -175.585628) (xy 442.046106 -175.585628) (xy 441.694824 -175.93691) (xy 441.694824 -183.893968)
			(xy 441.70981 -183.908954) (xy 442.496448 -184.695592) (xy 446.560448 -184.695592)
		)
		(stroke
			(width 0)
			(type solid)
		)
		(fill yes)
		(layer "B.Cu")
		(net "PVNN_MAIN_CPU0")
	)
	(gr_poly
		(pts
			(xy 11.965686 -113.284254) (xy 11.965686 -112.725708) (xy 11.965686 -111.912908) (xy 11.965686 -111.325406)
			(xy 11.936222 -111.295942) (xy 11.802618 -111.295942) (xy 11.787886 -111.310674) (xy 11.787886 -111.912908)
			(xy 11.787886 -112.725708) (xy 11.787886 -113.264442) (xy 11.824208 -113.300764) (xy 11.949176 -113.300764)
		)
		(stroke
			(width 0)
			(type solid)
		)
		(fill yes)
		(layer "B.Cu")
		(net "USB2_HUB_BUF_SWB_R_DP")
	)
	(gr_poly
		(pts
			(xy 12.365482 -113.262664) (xy 12.365482 -112.725708) (xy 12.365482 -111.912908) (xy 12.365482 -111.27613)
			(xy 12.334494 -111.245142) (xy 12.216384 -111.245142) (xy 12.187682 -111.273844) (xy 12.187682 -111.912908)
			(xy 12.187682 -112.725708) (xy 12.187682 -113.294922) (xy 12.207748 -113.314988) (xy 12.313158 -113.314988)
		)
		(stroke
			(width 0)
			(type solid)
		)
		(fill yes)
		(layer "B.Cu")
		(net "USB2_HUB_BUF_SWB_R_DN")
	)
	(gr_poly
		(pts
			(xy 41.705022 -359.145586) (xy 41.705022 -358.531414) (xy 41.596056 -358.422448) (xy 41.473374 -358.299766)
			(xy 41.17721 -358.299766) (xy 40.917368 -358.559608) (xy 38.62959 -358.559608) (xy 38.463728 -358.72547)
			(xy 38.463728 -359.31729) (xy 38.539674 -359.393236) (xy 39.239444 -359.393236) (xy 41.457372 -359.393236)
		)
		(stroke
			(width 0)
			(type solid)
		)
		(fill yes)
		(layer "B.Cu")
		(net "GND")
	)
	(gr_poly
		(pts
			(xy 48.90008 -147.109688) (xy 48.90008 -146.852132) (xy 48.901096 -146.851116) (xy 48.901096 -145.011902)
			(xy 48.753776 -144.864836) (xy 43.316652 -144.864836) (xy 43.169332 -145.011902) (xy 43.169332 -146.851116)
			(xy 43.170348 -146.852132) (xy 43.170348 -147.109688) (xy 43.325796 -147.265136) (xy 48.744632 -147.265136)
		)
		(stroke
			(width 0)
			(type solid)
		)
		(fill yes)
		(layer "B.Cu")
		(net "P12V_AUX")
	)
	(gr_poly
		(pts
			(xy 121.24055 -240.625376)
			(arc
				(start 121.24055 -240.04778)
				(mid 121.209024 -239.994627)
				(end 121.187972 -239.936528)
			)
			(xy 121.184416 -239.923066) (xy 121.07799 -239.81664) (xy 119.334788 -239.81664) (xy 119.20728 -239.944148)
			(xy 119.20728 -240.833148) (xy 119.328692 -240.95456) (xy 120.911366 -240.95456)
		)
		(stroke
			(width 0)
			(type solid)
		)
		(fill yes)
		(layer "B.Cu")
		(net "GND")
	)
	(gr_poly
		(pts
			(xy 140.566902 -29.415232) (xy 140.566902 -28.835858) (xy 140.566902 -28.023058) (xy 140.566902 -27.461718)
			(xy 140.52423 -27.419046) (xy 140.401802 -27.419046) (xy 140.389102 -27.431746) (xy 140.389102 -28.023058)
			(xy 140.389102 -28.835858) (xy 140.389102 -29.4132) (xy 140.41628 -29.440378) (xy 140.541756 -29.440378)
		)
		(stroke
			(width 0)
			(type solid)
		)
		(fill yes)
		(layer "B.Cu")
		(net "USB2_HUB_2_BUF_EXT_R_DN")
	)
	(gr_poly
		(pts
			(xy 140.966698 -29.44876) (xy 140.966698 -28.835858) (xy 140.966698 -28.023058) (xy 140.966698 -27.423364)
			(xy 140.948156 -27.404822) (xy 140.817346 -27.404822) (xy 140.788898 -27.43327) (xy 140.788898 -28.023058)
			(xy 140.788898 -28.835858) (xy 140.788898 -29.438346) (xy 140.816076 -29.465524) (xy 140.949934 -29.465524)
		)
		(stroke
			(width 0)
			(type solid)
		)
		(fill yes)
		(layer "B.Cu")
		(net "USB2_HUB_2_BUF_EXT_R_DP")
	)
	(gr_poly
		(pts
			(xy 172.164248 -359.151936) (xy 172.164248 -358.537764) (xy 172.055282 -358.428798) (xy 171.9326 -358.306116)
			(xy 171.636436 -358.306116) (xy 171.376594 -358.565958) (xy 169.088816 -358.565958) (xy 168.922954 -358.73182)
			(xy 168.922954 -359.32364) (xy 168.9989 -359.399586) (xy 169.69867 -359.399586) (xy 171.916598 -359.399586)
		)
		(stroke
			(width 0)
			(type solid)
		)
		(fill yes)
		(layer "B.Cu")
		(net "GND")
	)
	(gr_poly
		(pts
			(xy 174.9298 -26.741628) (xy 174.9298 -22.799548) (xy 174.8663 -22.736048) (xy 174.2059 -22.736048)
			(xy 174.09414 -22.847808) (xy 174.09414 -23.409148) (xy 173.91634 -23.586948) (xy 173.00448 -23.586948)
			(xy 172.77588 -23.815548) (xy 172.77588 -25.827228) (xy 173.863 -26.914348) (xy 174.75708 -26.914348)
		)
		(stroke
			(width 0)
			(type solid)
		)
		(fill yes)
		(layer "B.Cu")
		(net "GND")
	)
	(gr_poly
		(pts
			(xy 176.8094 -110.620048) (xy 177.09896 -110.620048) (xy 177.25644 -110.777528) (xy 177.44694 -110.777528)
			(xy 177.57394 -110.650528) (xy 177.57394 -110.556548) (xy 176.9618 -109.944408) (xy 176.04994 -109.944408)
			(xy 175.92548 -110.068868) (xy 175.92548 -110.254288) (xy 176.44872 -110.777528) (xy 176.65192 -110.777528)
		)
		(stroke
			(width 0)
			(type solid)
		)
		(fill yes)
		(layer "B.Cu")
		(net "P3V3_AUX_FPGA_VCCIO5")
	)
	(gr_poly
		(pts
			(xy 176.91608 -123.688348) (xy 176.91608 -123.273058) (xy 177.630836 -122.558302) (xy 177.630836 -122.057668)
			(xy 177.414936 -121.841768) (xy 175.41494 -121.841768) (xy 175.14316 -122.113548) (xy 173.81728 -122.113548)
			(xy 173.74108 -122.189748) (xy 173.74108 -123.713748) (xy 173.81728 -123.789948) (xy 176.81448 -123.789948)
		)
		(stroke
			(width 0)
			(type solid)
		)
		(fill yes)
		(layer "B.Cu")
		(net "P3V3_AUX_FPGA_VCCIO1")
	)
	(gr_poly
		(pts
			(xy 179.99964 -110.625128) (xy 180.31206 -110.625128) (xy 180.46954 -110.782608) (xy 180.64988 -110.782608)
			(xy 181.18836 -110.244128) (xy 181.18836 -110.048548) (xy 181.102 -109.962188) (xy 180.04282 -109.962188)
			(xy 179.53228 -110.472728) (xy 179.53228 -110.660688) (xy 179.6542 -110.782608) (xy 179.84216 -110.782608)
		)
		(stroke
			(width 0)
			(type solid)
		)
		(fill yes)
		(layer "B.Cu")
		(net "P3V3_AUX_FPGA_VCCIO3")
	)
	(gr_poly
		(pts
			(xy 181.85257 -359.145586) (xy 181.85257 -358.531414) (xy 181.743604 -358.422448) (xy 181.620922 -358.299766)
			(xy 181.324758 -358.299766) (xy 181.064916 -358.559608) (xy 178.777138 -358.559608) (xy 178.611276 -358.72547)
			(xy 178.611276 -359.31729) (xy 178.687222 -359.393236) (xy 179.386992 -359.393236) (xy 181.60492 -359.393236)
		)
		(stroke
			(width 0)
			(type solid)
		)
		(fill yes)
		(layer "B.Cu")
		(net "GND")
	)
	(gr_poly
		(pts
			(xy 240.007394 -250.601734) (xy 240.007394 -247.150382) (xy 239.69472 -246.837708) (xy 238.42218 -246.837708)
			(xy 238.25454 -247.005348) (xy 238.25454 -248.712228) (xy 239.18418 -249.641868) (xy 239.18418 -249.741944)
			(xy 239.337088 -249.894598) (xy 239.337088 -250.569476) (xy 239.500664 -250.733052) (xy 239.876076 -250.733052)
		)
		(stroke
			(width 0)
			(type solid)
		)
		(fill yes)
		(layer "B.Cu")
		(net "GND")
	)
	(gr_poly
		(pts
			(xy 265.64336 -419.70706) (xy 265.64336 -415.01314) (xy 265.19124 -414.56102) (xy 255.19634 -414.56102)
			(xy 253.546864 -416.211004) (xy 248.75871 -416.211004) (xy 248.62536 -416.3441) (xy 248.62536 -419.79596)
			(xy 249.03684 -420.20744) (xy 252.1458 -420.20744) (xy 252.58014 -420.64178) (xy 264.70864 -420.64178)
		)
		(stroke
			(width 0)
			(type solid)
		)
		(fill yes)
		(layer "B.Cu")
		(net "P12V_PSU_FUSE")
	)
	(gr_poly
		(pts
			(xy 273.826986 -406.766014) (xy 274.32 -406.273) (xy 274.32 -397.637) (xy 274.305014 -397.622014)
			(xy 274.066 -397.383) (xy 247.260872 -397.383) (xy 246.625872 -398.018) (xy 239.91316 -398.018) (xy 239.67694 -398.25422)
			(xy 239.67694 -406.47112) (xy 239.98682 -406.781) (xy 273.812 -406.781)
		)
		(stroke
			(width 0)
			(type solid)
		)
		(fill yes)
		(layer "B.Cu")
		(net "P12V_MAIN_R")
	)
	(gr_poly
		(pts
			(xy 328.229722 -70.84695) (xy 328.229722 -68.707762) (xy 328.03338 -68.51142) (xy 326.67194 -68.51142)
			(xy 326.655938 -68.527422) (xy 326.655938 -69.404738) (xy 326.862694 -69.611494) (xy 326.862694 -69.793358)
			(xy 326.874124 -69.804788) (xy 326.874124 -70.692264) (xy 327.165462 -70.983348) (xy 328.093324 -70.983348)
		)
		(stroke
			(width 0)
			(type solid)
		)
		(fill yes)
		(layer "B.Cu")
		(net "P1V05_PCH_AUX")
	)
	(gr_poly
		(pts
			(xy 334.506316 -51.562508) (xy 334.506316 -50.117248) (xy 334.440022 -50.050954) (xy 334.440022 -49.607724)
			(xy 334.301846 -49.469548) (xy 333.640176 -49.469548) (xy 333.276956 -49.832768) (xy 333.276956 -51.100736)
			(xy 333.533496 -51.357276) (xy 333.76108 -51.357276) (xy 334.020668 -51.616864) (xy 334.45196 -51.616864)
		)
		(stroke
			(width 0)
			(type solid)
		)
		(fill yes)
		(layer "B.Cu")
		(net "GND")
	)
	(gr_poly
		(pts
			(xy 334.9752 -63.642748) (xy 334.9752 -62.719458) (xy 333.56296 -61.306964) (xy 333.302356 -61.306964)
			(xy 327.997566 -66.612008) (xy 327.879964 -66.612008) (xy 327.48855 -67.003422) (xy 326.61225 -67.003422)
			(xy 326.51192 -67.103752) (xy 326.51192 -68.025772) (xy 326.674734 -68.188586) (xy 330.429362 -68.188586)
		)
		(stroke
			(width 0)
			(type solid)
		)
		(fill yes)
		(layer "B.Cu")
		(net "P1V05_PCH_PLL_AUX")
	)
	(gr_poly
		(pts
			(xy 369.180364 -240.625122)
			(arc
				(start 369.180364 -240.047272)
				(mid 369.149018 -239.994348)
				(end 369.12804 -239.936528)
			)
			(xy 369.124484 -239.923066) (xy 369.017804 -239.816386) (xy 367.289842 -239.816386) (xy 367.16208 -239.944148)
			(xy 367.16208 -240.807748) (xy 367.308638 -240.954306) (xy 368.85118 -240.954306)
		)
		(stroke
			(width 0)
			(type solid)
		)
		(fill yes)
		(layer "B.Cu")
		(net "GND")
	)
	(gr_poly
		(pts
			(xy 416.300412 -367.68532) (xy 416.300412 -367.071148) (xy 416.191446 -366.962182) (xy 416.068764 -366.8395)
			(xy 415.7726 -366.8395) (xy 415.512758 -367.099342) (xy 413.22498 -367.099342) (xy 413.059118 -367.265204)
			(xy 413.059118 -367.857024) (xy 413.135064 -367.93297) (xy 413.834834 -367.93297) (xy 416.052762 -367.93297)
		)
		(stroke
			(width 0)
			(type solid)
		)
		(fill yes)
		(layer "B.Cu")
		(net "GND")
	)
	(gr_poly
		(pts
			(xy 51.393344 -359.139236) (xy 51.393344 -358.525064) (xy 51.30673 -358.43845) (xy 50.720498 -358.43845)
			(xy 50.60569 -358.553258) (xy 49.46142 -358.553258) (xy 49.209198 -358.80548) (xy 48.27651 -358.80548)
			(xy 48.15205 -358.92994) (xy 48.15205 -359.31094) (xy 48.227996 -359.386886) (xy 48.927766 -359.386886)
			(xy 51.145694 -359.386886)
		)
		(stroke
			(width 0)
			(type solid)
		)
		(fill yes)
		(layer "B.Cu")
		(net "GND")
	)
	(gr_poly
		(pts
			(xy 189.667388 -101.94544)
			(arc
				(start 189.667388 -101.601016)
				(mid 189.672846 -101.537202)
				(end 189.689232 -101.475286)
			)
			(xy 189.69228 -101.466904) (xy 189.69228 -101.209348) (xy 189.64148 -101.158548) (xy 188.26988 -101.158548)
			(xy 188.21908 -101.209348) (xy 188.21908 -101.920548) (xy 188.26988 -101.971348) (xy 189.64148 -101.971348)
		)
		(stroke
			(width 0)
			(type solid)
		)
		(fill yes)
		(layer "B.Cu")
		(net "P3V3_AUX")
	)
	(gr_poly
		(pts
			(xy 245.66372 -396.10792) (xy 245.66372 -394.68552) (xy 245.4656 -394.4874) (xy 245.20652 -394.4874)
			(xy 244.9576 -394.73632) (xy 244.9576 -395.29258) (xy 244.48516 -395.76502) (xy 243.7384 -395.76502)
			(xy 243.66982 -395.76502) (xy 243.60886 -395.82598) (xy 243.60886 -396.2654) (xy 243.64696 -396.3035)
			(xy 245.46814 -396.3035)
		)
		(stroke
			(width 0)
			(type solid)
		)
		(fill yes)
		(layer "B.Cu")
		(net "P12V_HSC_GATE2")
	)
	(gr_poly
		(pts
			(xy 350.94418 -53.792628) (xy 350.94418 -53.464968) (xy 350.78924 -53.310028) (xy 349.98406 -53.310028)
			(xy 349.86722 -53.193188) (xy 349.86722 -52.873148) (xy 349.69958 -52.705508) (xy 349.01378 -52.705508)
			(xy 348.68612 -53.033168) (xy 348.2848 -53.434488) (xy 348.2848 -53.990748) (xy 348.37624 -54.082188)
			(xy 350.65462 -54.082188)
		)
		(stroke
			(width 0)
			(type solid)
		)
		(fill yes)
		(layer "B.Cu")
		(net "GND")
	)
	(gr_poly
		(pts
			(xy 352.63836 -236.166406) (xy 352.63836 -235.688886) (xy 352.59772 -235.648246) (xy 352.55708 -235.607606)
			(xy 352.39706 -235.607606) (xy 351.555304 -235.607606) (xy 351.429828 -235.48213) (xy 351.045018 -235.48213)
			(xy 350.945958 -235.58119) (xy 350.945958 -235.81995) (xy 351.355914 -236.229906) (xy 351.570544 -236.229906)
			(xy 352.57486 -236.229906)
		)
		(stroke
			(width 0)
			(type solid)
		)
		(fill yes)
		(layer "B.Cu")
		(net "P3V3_AUX")
	)
	(gr_poly
		(pts
			(xy 16.108172 -100.691696) (xy 16.108172 -97.563178) (xy 16.10868 -97.562924) (xy 16.10868 -97.338388)
			(xy 16.28648 -97.160588) (xy 17.91208 -97.160588) (xy 17.98828 -97.084388) (xy 17.98828 -96.322388)
			(xy 17.86128 -96.195388) (xy 12.65428 -96.195388) (xy 12.17168 -96.677988) (xy 12.17168 -100.741988)
			(xy 12.552172 -101.12248) (xy 15.677388 -101.12248)
		)
		(stroke
			(width 0)
			(type solid)
		)
		(fill yes)
		(layer "B.Cu")
		(net "GND")
	)
	(gr_poly
		(pts
			(xy 120.91289 -239.45088) (xy 120.91289 -238.04626) (xy 120.83923 -237.9726) (xy 119.87911 -237.9726)
			(xy 119.80799 -238.04372) (xy 119.80799 -238.73968) (xy 119.680736 -238.86668) (xy 119.680736 -238.905542)
			(xy 119.478552 -239.10798) (xy 119.122698 -239.10798) (xy 119.017288 -239.21339) (xy 119.017288 -239.495584)
			(xy 119.06885 -239.5474) (xy 120.81637 -239.5474)
		)
		(stroke
			(width 0)
			(type solid)
		)
		(fill yes)
		(layer "B.Cu")
		(net "PVCCFA_EHV_FIVRA_CPU1")
	)
	(gr_poly
		(pts
			(xy 159.178752 -39.345616) (xy 159.178752 -36.217098) (xy 159.17926 -36.216844) (xy 159.17926 -35.992308)
			(xy 159.35706 -35.814508) (xy 160.98266 -35.814508) (xy 161.05886 -35.738308) (xy 161.05886 -34.976308)
			(xy 160.93186 -34.849308) (xy 155.72486 -34.849308) (xy 155.24226 -35.331908) (xy 155.24226 -39.395908)
			(xy 155.622752 -39.7764) (xy 158.747968 -39.7764)
		)
		(stroke
			(width 0)
			(type solid)
		)
		(fill yes)
		(layer "B.Cu")
		(net "GND")
	)
	(gr_poly
		(pts
			(xy 179.21732 -110.635288) (xy 179.21732 -110.513368) (xy 179.277772 -110.452916) (xy 179.277772 -110.367318)
			(xy 179.58816 -110.057184) (xy 179.58816 -110.056168) (xy 179.46624 -109.934248) (xy 177.6603 -109.934248)
			(xy 177.54092 -110.053628) (xy 177.54092 -110.163864) (xy 177.828448 -110.451138) (xy 177.828448 -110.572296)
			(xy 178.03876 -110.782608) (xy 179.07 -110.782608)
		)
		(stroke
			(width 0)
			(type solid)
		)
		(fill yes)
		(layer "B.Cu")
		(net "P3V3_AUX_FPGA_VCCIO4")
	)
	(gr_poly
		(pts
			(xy 179.45608 -125.618748) (xy 179.45608 -124.755148) (xy 179.68468 -124.526548) (xy 180.04028 -124.526548)
			(xy 180.09743 -124.469398) (xy 180.09743 -122.951748) (xy 179.99583 -122.850148) (xy 178.44643 -122.850148)
			(xy 178.2064 -123.090178) (xy 178.2064 -124.675138) (xy 178.37023 -124.838968) (xy 178.37023 -125.669548)
			(xy 178.42103 -125.720348) (xy 179.35448 -125.720348)
		)
		(stroke
			(width 0)
			(type solid)
		)
		(fill yes)
		(layer "B.Cu")
		(net "VCC_PLD_CORE")
	)
	(gr_poly
		(pts
			(xy 265.198606 -103.705152) (xy 265.198606 -98.412554) (xy 265.176 -98.389948) (xy 263.778746 -98.389948)
			(xy 263.603486 -98.565208) (xy 263.603486 -99.717352) (xy 263.895586 -100.009452) (xy 263.895586 -101.823012)
			(xy 263.532366 -102.186232) (xy 262.082026 -102.186232) (xy 261.937246 -102.331012) (xy 261.937246 -103.796592)
			(xy 262.092186 -103.951532) (xy 264.952226 -103.951532)
		)
		(stroke
			(width 0)
			(type solid)
		)
		(fill yes)
		(layer "B.Cu")
		(net "P3V3_AUX")
	)
	(gr_poly
		(pts
			(xy 298.614338 -368.366802) (xy 298.614338 -367.75263) (xy 298.505372 -367.643664) (xy 298.38269 -367.520982)
			(xy 298.086526 -367.520982) (xy 297.826684 -367.780824) (xy 297.10634 -367.780824) (xy 296.749724 -368.13744)
			(xy 295.428924 -368.13744) (xy 295.373044 -368.19332) (xy 295.373044 -368.538506) (xy 295.44899 -368.614452)
			(xy 296.14876 -368.614452) (xy 298.366688 -368.614452)
		)
		(stroke
			(width 0)
			(type solid)
		)
		(fill yes)
		(layer "B.Cu")
		(net "GND")
	)
	(gr_poly
		(pts
			(xy 339.889846 -51.600354) (xy 339.889846 -51.172618) (xy 339.741256 -51.024028) (xy 339.474556 -51.024028)
			(xy 339.253576 -50.803048) (xy 337.803236 -50.803048) (xy 337.765136 -50.841148) (xy 337.765136 -51.236118)
			(xy 338.0232 -51.494182) (xy 338.3788 -51.494182) (xy 338.5312 -51.646582) (xy 338.5312 -52.2732)
			(xy 338.6074 -52.3494) (xy 339.1408 -52.3494)
		)
		(stroke
			(width 0)
			(type solid)
		)
		(fill yes)
		(layer "B.Cu")
		(net "P1V05_PCH_PLL_AUX")
	)
	(gr_poly
		(pts
			(xy 354.295456 -236.076998) (xy 354.295456 -235.69803) (xy 354.872798 -235.120688) (xy 354.872798 -235.03001)
			(xy 354.728018 -234.88523) (xy 354.408994 -234.88523) (xy 354.161344 -235.13288) (xy 353.664266 -235.629958)
			(xy 353.571302 -235.629958) (xy 352.940112 -235.629958) (xy 352.90252 -235.66755) (xy 352.90252 -236.15777)
			(xy 352.948494 -236.203744) (xy 354.168964 -236.203744)
		)
		(stroke
			(width 0)
			(type solid)
		)
		(fill yes)
		(layer "B.Cu")
		(net "GND")
	)
	(gr_poly
		(pts
			(xy 365.858044 -261.820406) (xy 365.776764 -261.739126) (xy 363.986064 -261.739126) (xy 363.808264 -261.916926)
			(xy 363.808264 -263.38784)
			(arc
				(start 363.920532 -263.38784)
				(mid 364.034895 -263.410494)
				(end 364.13186 -263.475216)
			)
			(xy 364.163356 -263.506712) (xy 365.858044 -263.506712)
		)
		(stroke
			(width 0)
			(type solid)
		)
		(fill yes)
		(layer "B.Cu")
		(net "PVPP_HBM_CPU0")
	)
	(gr_poly
		(pts
			(xy 367.450624 -237.266226) (xy 367.450624 -236.476286) (xy 367.999264 -235.927646) (xy 367.999264 -234.931966)
			(xy 367.824004 -234.756706) (xy 364.341664 -234.756706) (xy 364.262924 -234.835446) (xy 364.262924 -235.937806)
			(xy 364.323884 -235.998766) (xy 365.080804 -235.998766) (xy 365.319564 -236.237526) (xy 365.319564 -237.164626)
			(xy 365.478314 -237.323376) (xy 367.393474 -237.323376)
		)
		(stroke
			(width 0)
			(type solid)
		)
		(fill yes)
		(layer "B.Cu")
		(net "PVCCINFAON_CPU0")
	)
	(gr_poly
		(pts
			(xy 368.852704 -239.450626) (xy 368.852704 -238.046006) (xy 368.779044 -237.972346) (xy 367.818924 -237.972346)
			(xy 367.747804 -238.043466) (xy 367.747804 -238.739426) (xy 367.620804 -238.86668) (xy 367.620804 -238.905288)
			(xy 367.418366 -239.107472) (xy 367.062512 -239.107472) (xy 366.956848 -239.213136) (xy 366.956848 -239.495584)
			(xy 367.008664 -239.547146) (xy 368.756184 -239.547146)
		)
		(stroke
			(width 0)
			(type solid)
		)
		(fill yes)
		(layer "B.Cu")
		(net "PVCCFA_EHV_FIVRA_CPU0")
	)
	(gr_poly
		(pts
			(xy 387.610858 -348.174056) (xy 387.610858 -347.219016) (xy 387.529578 -347.137736) (xy 386.422392 -347.137736)
			(xy 386.333238 -347.22689) (xy 386.333238 -347.54693) (xy 386.183378 -347.69679) (xy 385.787138 -347.69679)
			(xy 385.782058 -347.701616) (xy 385.266438 -347.701616) (xy 385.162298 -347.805756) (xy 385.162298 -348.138496)
			(xy 385.268978 -348.245176) (xy 387.539738 -348.245176)
		)
		(stroke
			(width 0)
			(type solid)
		)
		(fill yes)
		(layer "B.Cu")
		(net "GND")
	)
	(gr_poly
		(pts
			(xy 413.566356 -261.977632) (xy 413.566356 -257.262376) (xy 413.35071 -257.046476) (xy 411.902402 -257.046476)
			(xy 411.763464 -257.185668) (xy 411.763464 -257.951986) (xy 411.712156 -258.00304) (xy 411.712156 -258.125976)
			(xy 411.534356 -258.303776) (xy 404.413212 -258.303776) (xy 404.080218 -258.63677) (xy 404.080218 -261.90575)
			(xy 404.364698 -262.19023) (xy 413.353758 -262.19023)
		)
		(stroke
			(width 0)
			(type solid)
		)
		(fill yes)
		(layer "B.Cu")
		(net "GND")
	)
	(gr_poly
		(pts
			(xy 425.988734 -367.67897) (xy 425.988734 -367.064798) (xy 425.879768 -366.955832) (xy 425.757086 -366.83315)
			(xy 425.460922 -366.83315) (xy 425.20108 -367.092992) (xy 424.14698 -367.092992) (xy 423.879772 -367.3602)
			(xy 422.91254 -367.3602) (xy 422.74744 -367.5253) (xy 422.74744 -367.850674) (xy 422.823386 -367.92662)
			(xy 423.523156 -367.92662) (xy 425.741084 -367.92662)
		)
		(stroke
			(width 0)
			(type solid)
		)
		(fill yes)
		(layer "B.Cu")
		(net "GND")
	)
	(gr_poly
		(pts
			(xy 62.77991 -261.746238) (xy 67.60591 -261.746238) (xy 67.8688 -261.483348) (xy 67.8688 -258.409948)
			(xy 67.696334 -258.237482) (xy 67.66433 -258.237482) (xy 67.526154 -258.375912) (xy 56.222646 -258.375912)
			(xy 56.142382 -258.295648) (xy 56.026558 -258.411472) (xy 56.026558 -261.490714) (xy 56.282082 -261.746238)
			(xy 59.1566 -261.746238) (xy 59.553348 -262.142732) (xy 62.383416 -262.142732)
		)
		(stroke
			(width 0)
			(type solid)
		)
		(fill yes)
		(layer "B.Cu")
		(net "GND")
	)
	(gr_poly
		(pts
			(xy 106.313986 -236.15904) (xy 106.313986 -235.68914) (xy 106.349546 -235.65358) (xy 106.352086 -235.65358)
			(xy 106.471466 -235.5342) (xy 106.471466 -235.210604) (xy 106.39425 -235.133134) (xy 106.22153 -235.133134)
			(xy 105.724452 -235.630212) (xy 105.631488 -235.630212) (xy 105.000298 -235.630212) (xy 104.962706 -235.667804)
			(xy 104.962706 -236.158024) (xy 105.00868 -236.203998) (xy 106.269028 -236.203998)
		)
		(stroke
			(width 0)
			(type solid)
		)
		(fill yes)
		(layer "B.Cu")
		(net "GND")
	)
	(gr_poly
		(pts
			(xy 246.77751 -397.07185) (xy 246.77751 -396.785084) (xy 246.549926 -396.5575) (xy 246.42445 -396.5575)
			(xy 245.4402 -396.5575) (xy 244.06098 -396.5575) (xy 243.7511 -396.5575) (xy 243.72824 -396.5575)
			(xy 243.62156 -396.66418) (xy 243.62156 -397.2687) (xy 243.69522 -397.34236) (xy 243.7257 -397.34236)
			(xy 243.96446 -397.34236) (xy 245.34876 -397.34236) (xy 246.507 -397.34236)
		)
		(stroke
			(width 0)
			(type solid)
		)
		(fill yes)
		(layer "B.Cu")
		(net "P12V_HSC_GATE_RC")
	)
	(gr_poly
		(pts
			(xy 288.926016 -368.373152) (xy 288.926016 -367.75898) (xy 288.81705 -367.650014) (xy 288.694368 -367.527332)
			(xy 288.398204 -367.527332) (xy 288.138362 -367.787174) (xy 286.63138 -367.787174) (xy 286.362394 -367.518188)
			(xy 285.80588 -367.518188) (xy 285.684722 -367.639346) (xy 285.684722 -367.953036) (xy 285.684722 -368.544856)
			(xy 285.760668 -368.620802) (xy 286.460438 -368.620802) (xy 288.678366 -368.620802)
		)
		(stroke
			(width 0)
			(type solid)
		)
		(fill yes)
		(layer "B.Cu")
		(net "GND")
	)
	(gr_poly
		(pts
			(xy 42.4942 -185.562748) (xy 42.4942 -179.542948) (xy 42.2275 -179.276248) (xy 40.7289 -179.276248)
			(xy 40.6146 -179.390548) (xy 40.6146 -183.657748) (xy 40.2082 -184.064148) (xy 36.9824 -184.064148)
			(xy 36.65728 -183.739028) (xy 36.65728 -175.294798) (xy 36.554664 -175.192182) (xy 31.969456 -175.192182)
			(xy 31.587186 -175.574452) (xy 31.587186 -185.628534) (xy 31.8516 -185.892948) (xy 42.164 -185.892948)
		)
		(stroke
			(width 0)
			(type solid)
		)
		(fill yes)
		(layer "B.Cu")
		(net "PVNN_MAIN_CPU1")
	)
	(gr_poly
		(pts
			(xy 110.74908 -360.885486) (xy 110.74908 -359.095294) (xy 110.891574 -358.9528) (xy 111.297212 -358.9528)
			(xy 111.385858 -358.864154) (xy 111.385858 -358.259634) (xy 111.262668 -358.136444) (xy 110.860586 -358.136444)
			(xy 110.74908 -358.024938) (xy 110.74908 -356.786688) (xy 110.645194 -356.682802) (xy 106.4768 -356.682802)
			(xy 106.360976 -356.798626) (xy 106.360976 -360.832908) (xy 106.552238 -361.02417) (xy 110.610396 -361.02417)
		)
		(stroke
			(width 0)
			(type solid)
		)
		(fill yes)
		(layer "B.Cu")
		(net "GND")
	)
	(gr_poly
		(pts
			(xy 356.2858 -237.34395) (xy 356.2858 -237.278926) (xy 356.2858 -235.353606) (xy 356.17404 -235.241846)
			(xy 355.115876 -235.241846) (xy 354.616512 -235.74121) (xy 354.616512 -236.453934) (xy 354.605082 -236.465364)
			(xy 354.5078 -236.562646) (xy 354.47224 -236.598206) (xy 351.21342 -236.598206) (xy 351.194878 -236.616748)
			(xy 351.194878 -237.41761) (xy 351.38614 -237.609126) (xy 351.50552 -237.728506) (xy 355.901244 -237.728506)
		)
		(stroke
			(width 0)
			(type solid)
		)
		(fill yes)
		(layer "B.Cu")
		(net "PVNN_MAIN_CPU0")
	)
	(gr_poly
		(pts
			(xy 358.688894 -360.885486) (xy 358.688894 -359.095294) (xy 358.831388 -358.9528) (xy 359.237026 -358.9528)
			(xy 359.325672 -358.864154) (xy 359.325672 -358.259634) (xy 359.202482 -358.136444) (xy 358.8004 -358.136444)
			(xy 358.688894 -358.024938) (xy 358.688894 -356.786688) (xy 358.585008 -356.682802) (xy 354.416614 -356.682802)
			(xy 354.30079 -356.798626) (xy 354.30079 -360.832908) (xy 354.492052 -361.02417) (xy 358.55021 -361.02417)
		)
		(stroke
			(width 0)
			(type solid)
		)
		(fill yes)
		(layer "B.Cu")
		(net "GND")
	)
	(gr_poly
		(pts
			(xy 376.523504 -81.098644) (xy 376.523504 -71.485252) (xy 376.301 -71.262748) (xy 375.48312 -71.262748)
			(arc
				(start 375.3739 -71.371968)
				(mid 375.253853 -71.452088)
				(end 375.11228 -71.480172)
			)
			(xy 372.573042 -71.480172) (xy 372.150132 -71.903336) (xy 372.150132 -81.13268) (xy 372.2878 -81.270348)
			(xy 376.3518 -81.270348)
		)
		(stroke
			(width 0)
			(type solid)
		)
		(fill yes)
		(layer "B.Cu")
		(net "P1V8_PCH_AUX")
	)
	(gr_poly
		(pts
			(xy 413.871156 -250.379992) (xy 413.871156 -247.790716) (xy 413.388556 -247.308116) (xy 409.21559 -247.308116)
			(arc
				(start 408.56535 -247.958102)
				(mid 408.461895 -248.027385)
				(end 408.339798 -248.051828)
			)
			(xy 405.710898 -248.051828) (xy 405.285956 -248.47677) (xy 405.285956 -250.361704) (xy 405.4348 -250.510548)
			(xy 413.7406 -250.510548)
		)
		(stroke
			(width 0)
			(type solid)
		)
		(fill yes)
		(layer "B.Cu")
		(net "GND")
	)
	(gr_poly
		(pts
			(xy 440.21248 -21.123148) (xy 440.21248 -14.630908) (xy 439.8518 -14.270228) (xy 438.16778 -14.270228)
			(xy 436.89016 -12.992608) (xy 436.89016 -9.982708) (xy 436.7276 -9.820148) (xy 435.84368 -9.820148)
			(xy 435.66588 -9.997948) (xy 435.66588 -13.622528) (xy 438.81548 -16.772128) (xy 438.81548 -17.490948)
			(xy 437.46928 -18.837148) (xy 437.46928 -21.377148) (xy 437.64708 -21.554948) (xy 439.78068 -21.554948)
		)
		(stroke
			(width 0)
			(type solid)
		)
		(fill yes)
		(layer "B.Cu")
		(net "GND")
	)
	(gr_poly
		(pts
			(xy 106.160824 -261.547356) (xy 107.940856 -261.547356) (xy 108.121196 -261.36727) (xy 108.121196 -259.87756)
			(xy 108.037884 -259.794248) (xy 105.111804 -259.794248) (xy 104.904286 -260.001766) (xy 104.904286 -260.95706)
			(xy 104.764586 -261.09676) (xy 104.693974 -261.09676) (xy 104.6099 -261.181088) (xy 104.428544 -261.181088)
			(xy 104.428544 -261.502652) (xy 104.43972 -261.51332) (xy 105.275888 -261.51332) (xy 105.309924 -261.54761)
			(xy 106.15295 -261.54761)
		)
		(stroke
			(width 0)
			(type solid)
		)
		(fill yes)
		(layer "B.Cu")
		(net "PVCCFA_EHV_FIVRA_CPU1")
	)
	(gr_poly
		(pts
			(xy 117.91823 -263.6393) (xy 117.91823 -261.82066) (xy 117.83695 -261.73938) (xy 116.04625 -261.73938)
			(xy 115.86845 -261.91718)
			(arc
				(start 115.86845 -263.46912)
				(mid 115.882706 -263.504407)
				(end 115.917472 -263.51992)
			)
			(arc
				(start 115.917472 -263.51992)
				(mid 115.978123 -263.533651)
				(end 116.029486 -263.568688)
			)
			(xy 116.155978 -263.69518) (xy 117.86235 -263.69518)
		)
		(stroke
			(width 0)
			(type solid)
		)
		(fill yes)
		(layer "B.Cu")
		(net "PVPP_HBM_CPU1")
	)
	(gr_poly
		(pts
			(arc
				(start 118.93804 -263.59739)
				(mid 118.992098 -263.561177)
				(end 119.055896 -263.548368)
			)
			(xy 120.23725 -263.548368) (xy 120.46458 -263.321292) (xy 120.46458 -262.17753) (xy 120.37314 -262.08609)
			(xy 119.82958 -262.08609) (xy 119.49557 -261.75208) (xy 118.50497 -261.75208) (xy 118.44528 -261.811516)
			(xy 118.44528 -263.53008) (xy 118.53418 -263.61898) (xy 118.91645 -263.61898)
		)
		(stroke
			(width 0)
			(type solid)
		)
		(fill yes)
		(layer "B.Cu")
		(net "GND")
	)
	(gr_poly
		(pts
			(arc
				(start 186.609482 -104.024938)
				(mid 186.74588 -103.99776)
				(end 186.882278 -104.024938)
			)
			(xy 186.891422 -104.028748) (xy 187.66028 -104.028748) (xy 187.73648 -103.952548) (xy 187.73648 -101.209348)
			(xy 187.68568 -101.158548) (xy 186.06008 -101.158548) (xy 186.00928 -101.209348) (xy 186.00928 -103.927148)
			(xy 186.11088 -104.028748) (xy 186.600338 -104.028748)
		)
		(stroke
			(width 0)
			(type solid)
		)
		(fill yes)
		(layer "B.Cu")
		(net "P3V3_AUX_FPGA_VCCIO2")
	)
	(gr_poly
		(pts
			(xy 232.779824 -123.623324) (xy 232.779824 -123.201684) (xy 233.016298 -122.96521) (xy 233.8832 -122.96521)
			(xy 234.059476 -122.788934) (xy 234.059476 -120.520714) (xy 233.942636 -120.403874) (xy 233.101896 -120.403874)
			(xy 232.997756 -120.508014) (xy 232.997756 -121.539254) (xy 232.621836 -121.915174) (xy 231.387396 -121.915174)
			(xy 231.334818 -121.967752) (xy 231.375204 -122.007884) (xy 231.375204 -123.353068) (xy 232.04043 -124.018548)
			(xy 232.3846 -124.018548)
		)
		(stroke
			(width 0)
			(type solid)
		)
		(fill yes)
		(layer "B.Cu")
		(net "P3V3_DB2000_FB_VDD")
	)
	(gr_poly
		(pts
			(xy 353.986084 -261.535672) (xy 355.892608 -261.535672) (xy 356.06101 -261.367016) (xy 356.06101 -259.877306)
			(xy 355.977698 -259.794248) (xy 353.033838 -259.794248) (xy 352.8441 -259.983732) (xy 352.8441 -260.956806)
			(xy 352.7044 -261.096506) (xy 352.633788 -261.096506) (xy 352.549714 -261.18058) (xy 352.368612 -261.18058)
			(xy 352.368612 -261.502144) (xy 352.37928 -261.51332) (xy 353.215702 -261.51332) (xy 353.249738 -261.547356)
			(xy 353.9744 -261.547356)
		)
		(stroke
			(width 0)
			(type solid)
		)
		(fill yes)
		(layer "B.Cu")
		(net "PVCCFA_EHV_FIVRA_CPU0")
	)
	(gr_poly
		(pts
			(xy 157.696662 -250.266708) (xy 164.021008 -250.266708) (xy 164.278056 -250.009914) (xy 164.278056 -248.83364)
			(xy 163.968684 -248.524268) (xy 160.872678 -248.524268)
			(arc
				(start 160.33115 -249.065542)
				(mid 160.227695 -249.134825)
				(end 160.105598 -249.159268)
			)
			(xy 157.415992 -249.159268) (xy 157.39364 -249.181366) (xy 157.39364 -250.132596) (xy 157.53334 -250.272296)
			(xy 157.691328 -250.272296)
		)
		(stroke
			(width 0)
			(type solid)
		)
		(fill yes)
		(layer "B.Cu")
		(net "GND")
	)
	(gr_poly
		(pts
			(xy 236.87786 -251.935488) (xy 237.39856 -251.935488) (xy 237.50524 -251.828808) (xy 237.50524 -251.526548)
			(xy 237.31982 -251.341128) (xy 236.89818 -251.341128) (xy 236.75848 -251.201428) (xy 236.75848 -248.907808)
			(xy 236.67212 -248.821448) (xy 236.17428 -248.821448) (xy 235.96854 -249.027188) (xy 235.96854 -249.309128)
			(xy 235.90504 -249.372628) (xy 234.4674 -249.372628) (xy 234.07624 -249.763788) (xy 234.07624 -252.087888)
			(xy 234.10926 -252.120908) (xy 236.69244 -252.120908)
		)
		(stroke
			(width 0)
			(type solid)
		)
		(fill yes)
		(layer "B.Cu")
		(net "GND")
	)
	(gr_poly
		(pts
			(xy 368.683032 -247.883172) (xy 368.906552 -247.883172) (xy 369.205764 -247.583706)
			(arc
				(start 369.205764 -246.62511)
				(mid 369.153776 -246.564482)
				(end 369.11661 -246.493792)
			)
			(xy 369.10391 -246.46128) (xy 366.943894 -246.46128) (xy 366.894872 -246.510556) (xy 366.894872 -246.853456)
			(xy 367.07572 -247.034304) (xy 367.07572 -247.139968) (xy 367.082324 -247.146826) (xy 367.082324 -248.035826)
			(xy 367.18875 -248.142252) (xy 368.423698 -248.142252)
		)
		(stroke
			(width 0)
			(type solid)
		)
		(fill yes)
		(layer "B.Cu")
		(net "PVCCD_HV_CPU0")
	)
	(gr_poly
		(pts
			(arc
				(start 168.196768 -54.024784)
				(mid 168.243142 -54.016042)
				(end 168.29024 -54.0131)
			)
			(arc
				(start 168.29024 -54.0131)
				(mid 168.337337 -54.01605)
				(end 168.383712 -54.024784)
			)
			(xy 168.390062 -54.026308) (xy 169.15638 -54.026308) (xy 169.60342 -53.579268) (xy 169.60342 -50.843688)
			(xy 169.81424 -50.632868) (xy 169.81424 -49.530508) (xy 169.58564 -49.301908) (xy 167.95242 -49.301908)
			(xy 167.259 -49.995328) (xy 167.259 -53.670708) (xy 167.6146 -54.026308) (xy 168.190418 -54.026308)
		)
		(stroke
			(width 0)
			(type solid)
		)
		(fill yes)
		(layer "B.Cu")
		(net "P3V3_M2_0")
	)
	(gr_poly
		(pts
			(xy 19.05508 -393.004548) (xy 19.05508 -389.956548) (xy 19.23288 -389.778748) (xy 24.49068 -389.778748)
			(xy 24.71928 -390.007348) (xy 24.71928 -391.505948) (xy 24.54148 -391.683748) (xy 23.93188 -391.683748)
			(xy 23.75408 -391.861548) (xy 23.75408 -393.004548) (xy 23.85568 -393.106148) (xy 26.59888 -393.106148)
			(xy 26.95448 -392.750548) (xy 26.95448 -389.321548) (xy 25.81148 -388.178548) (xy 19.41068 -388.178548)
			(xy 17.93748 -389.651748) (xy 17.93748 -392.826748) (xy 18.31848 -393.207748) (xy 18.85188 -393.207748)
		)
		(stroke
			(width 0)
			(type solid)
		)
		(fill yes)
		(layer "B.Cu")
		(net "P3V3_AUX")
	)
	(gr_poly
		(pts
			(xy 120.743218 -247.883172) (xy 120.966484 -247.883172) (xy 121.26595 -247.58396)
			(arc
				(start 121.26595 -246.625364)
				(mid 121.213826 -246.564756)
				(end 121.176542 -246.494046)
			)
			(xy 121.163842 -246.461788) (xy 119.00408 -246.461788) (xy 118.954804 -246.51081) (xy 118.954804 -246.89181)
			(xy 118.921022 -246.925592) (xy 119.046244 -247.05056) (xy 119.050308 -247.054878) (xy 119.050562 -247.055132)
			(xy 119.14251 -247.14708) (xy 119.14251 -248.03608) (xy 119.248936 -248.14276) (xy 120.483884 -248.14276)
		)
		(stroke
			(width 0)
			(type solid)
		)
		(fill yes)
		(layer "B.Cu")
		(net "PVCCD_HV_CPU1")
	)
	(gr_poly
		(pts
			(xy 121.209816 -237.544356)
			(arc
				(start 121.209816 -236.792516)
				(mid 121.151915 -236.597952)
				(end 121.209816 -236.403388)
			)
			(xy 121.209816 -236.044486) (xy 121.14149 -235.97616) (xy 120.509792 -235.97616) (xy 119.765064 -236.720888)
			(xy 119.765064 -237.37189) (xy 119.75211 -237.384844) (xy 119.75211 -237.581186) (xy 119.867934 -237.69701)
			(xy 121.057162 -237.69701)
		)
		(stroke
			(width 0)
			(type solid)
		)
		(fill yes)
		(layer "B.Cu")
		(net "GND")
	)
	(gr_poly
		(pts
			(xy 247.43918 -55.008526) (xy 247.43918 -53.611526) (xy 247.07596 -53.248306) (xy 244.38356 -53.248306)
			(xy 244.27688 -53.354986)
			(arc
				(start 244.27688 -53.772562)
				(mid 244.374662 -54.017672)
				(end 244.27688 -54.262782)
			)
			(xy 244.27688 -55.117746) (xy 244.40388 -55.244746) (xy 247.20296 -55.244746)
		)
		(stroke
			(width 0)
			(type solid)
		)
		(fill yes)
		(layer "B.Cu")
		(net "GND")
	)
	(gr_poly
		(pts
			(xy 369.14963 -237.544102)
			(arc
				(start 369.14963 -236.7915)
				(mid 369.092487 -236.597952)
				(end 369.14963 -236.404404)
			)
			(xy 369.14963 -236.044232) (xy 369.081304 -235.975906) (xy 368.449606 -235.975906) (xy 367.705132 -236.72038)
			(xy 367.705132 -237.371636) (xy 367.691924 -237.38459) (xy 367.691924 -237.580932) (xy 367.807748 -237.696756)
			(xy 368.996976 -237.696756)
		)
		(stroke
			(width 0)
			(type solid)
		)
		(fill yes)
		(layer "B.Cu")
		(net "GND")
	)
	(gr_poly
		(pts
			(xy 29.542486 -167.291004) (xy 29.542486 -163.894262) (xy 30.057598 -163.37915) (xy 30.057598 -163.093146)
			(xy 29.4894 -162.524948) (xy 28.17622 -162.524948) (xy 28.0162 -162.364928) (xy 27.67838 -162.364928)
			(xy 27.49042 -162.364928) (xy 27.3812 -162.474148) (xy 27.3812 -162.719004) (xy 27.1526 -162.947604)
			(xy 25.834086 -162.947604) (xy 25.682956 -162.796474) (xy 25.228042 -162.796474) (xy 25.078182 -162.946334)
			(xy 25.078182 -165.394386) (xy 25.783286 -166.09949) (xy 25.783286 -167.291004) (xy 25.834086 -167.341804)
			(xy 29.491686 -167.341804)
		)
		(stroke
			(width 0)
			(type solid)
		)
		(fill yes)
		(layer "B.Cu")
		(net "GND")
	)
	(gr_poly
		(pts
			(arc
				(start 104.333802 -418.902134)
				(mid 104.501382 -418.68388)
				(end 104.763824 -418.601144)
			)
			(xy 104.804718 -418.602922) (xy 104.82834 -418.605208) (xy 104.95026 -418.483288) (xy 104.95026 -414.830768)
			(xy 104.67848 -414.558988) (xy 102.07498 -414.558988) (xy 101.66096 -414.973008) (xy 101.66096 -418.663628)
			(xy 101.93274 -418.935408) (xy 104.32161 -418.935408)
		)
		(stroke
			(width 0)
			(type solid)
		)
		(fill yes)
		(layer "B.Cu")
		(net "P3V3")
	)
	(gr_poly
		(pts
			(xy 79.2734 -58.130948) (xy 79.2734 -56.802528) (xy 80.31988 -55.756048) (xy 81.3308 -55.756048)
			(xy 81.71434 -55.372508) (xy 81.71434 -54.343808) (xy 81.40954 -54.039008) (xy 80.49514 -54.039008)
			(xy 79.75346 -53.297328) (xy 79.75346 -51.387248) (xy 80.74406 -50.396648) (xy 82.80654 -50.396648)
			(xy 83.75904 -49.444148) (xy 83.75904 -46.182788) (xy 83.2231 -45.646848) (xy 77.37348 -45.646848)
			(xy 77.25156 -45.768768) (xy 77.25156 -47.932848) (xy 73.96988 -51.214528) (xy 73.96988 -57.569608)
			(xy 74.70394 -58.303668) (xy 79.10068 -58.303668)
		)
		(stroke
			(width 0)
			(type solid)
		)
		(fill yes)
		(layer "B.Cu")
		(net "P3V3_OCP_V3_2_R")
	)
	(gr_poly
		(pts
			(xy 237.374938 -123.571254) (xy 238.4552 -123.571254) (xy 239.253776 -122.772678) (xy 239.253776 -120.934734)
			(xy 239.139476 -120.820434) (xy 237.663736 -120.820434) (xy 237.567216 -120.916954) (xy 237.567216 -121.57202)
			(xy 237.292388 -121.846848) (xy 237.257336 -121.846848) (xy 237.249716 -121.854468) (xy 234.534964 -121.854468)
			(xy 234.430316 -121.959116) (xy 234.430316 -122.914664) (xy 234.54106 -123.025408) (xy 235.469176 -123.025408)
			(xy 235.75137 -123.307602) (xy 236.396022 -123.307602) (xy 236.526832 -123.438412) (xy 236.526832 -123.66371)
			(xy 236.619796 -123.756674) (xy 237.189518 -123.756674)
		)
		(stroke
			(width 0)
			(type solid)
		)
		(fill yes)
		(layer "B.Cu")
		(net "GND")
	)
	(gr_poly
		(pts
			(xy 256.495042 -94.249748) (xy 255.936242 -93.690948) (xy 255.453642 -93.690948) (xy 255.016 -94.12859)
			(xy 255.016 -95.13951)
			(arc
				(start 255.133602 -95.257366)
				(mid 255.202885 -95.360821)
				(end 255.227328 -95.482918)
			)
			(xy 255.227328 -96.463358)
			(arc
				(start 255.233932 -96.475042)
				(mid 255.256673 -96.530178)
				(end 255.264158 -96.589342)
			)
			(xy 255.263904 -96.589342) (xy 255.263904 -96.732852) (xy 255.397 -96.865948) (xy 256.495042 -96.865948)
		)
		(stroke
			(width 0)
			(type solid)
		)
		(fill yes)
		(layer "B.Cu")
		(net "P3V3_AUX_CLK_GEN_VDDA100M_CK440")
	)
	(gr_poly
		(pts
			(xy 355.195632 -58.33745) (xy 355.195632 -58.05805)
			(arc
				(start 354.359718 -57.222136)
				(mid 354.207644 -56.994541)
				(end 354.154232 -56.726074)
			)
			(xy 354.154232 -56.476392) (xy 353.778312 -56.476392) (xy 353.778312 -57.410858) (xy 353.714812 -57.474104)
			(xy 353.714812 -57.509156) (xy 353.2632 -57.960768) (xy 353.2632 -58.873136) (xy 353.714812 -59.324748)
			(xy 353.714812 -59.353704) (xy 353.815396 -59.454288) (xy 354.079048 -59.454288)
		)
		(stroke
			(width 0)
			(type solid)
		)
		(fill yes)
		(layer "B.Cu")
		(net "P1V8_PCH_AUX")
	)
	(gr_poly
		(pts
			(arc
				(start 150.250652 -39.515288)
				(mid 150.54834 -39.354795)
				(end 150.846028 -39.515288)
			)
			(xy 151.5364 -39.515288) (xy 151.70658 -39.345108) (xy 151.70658 -35.753548) (xy 151.38908 -35.436048)
			(xy 149.12848 -35.436048) (xy 148.74748 -35.817048) (xy 148.74748 -39.271448) (xy 148.99132 -39.515288)
		)
		(stroke
			(width 0)
			(type solid)
		)
		(fill yes)
		(layer "B.Cu")
		(net "GND")
	)
	(gr_poly
		(pts
			(xy 182.52948 -103.977948) (xy 182.52948 -102.479348) (xy 182.42788 -102.377748) (xy 181.38648 -102.377748)
			(xy 181.25948 -102.504748)
			(arc
				(start 181.25948 -103.018336)
				(mid 181.425126 -103.332788)
				(end 181.25948 -103.64724)
			)
			(xy 181.25948 -104.003348) (xy 181.31028 -104.054148) (xy 182.45328 -104.054148)
		)
		(stroke
			(width 0)
			(type solid)
		)
		(fill yes)
		(layer "B.Cu")
		(net "GND")
	)
	(gr_poly
		(pts
			(arc
				(start 311.317386 -260.326378)
				(mid 311.420841 -260.257095)
				(end 311.542938 -260.232652)
			)
			(xy 314.855098 -260.232652) (xy 314.855098 -258.41325) (xy 314.73902 -258.297172) (xy 304.252376 -258.297172)
			(xy 304.159158 -258.39039) (xy 304.159158 -260.264148) (xy 304.188622 -260.293612)
			(arc
				(start 306.788058 -260.293612)
				(mid 306.910172 -260.318014)
				(end 307.01361 -260.387338)
			)
			(xy 307.743098 -261.116572) (xy 310.526938 -261.116572)
		)
		(stroke
			(width 0)
			(type solid)
		)
		(fill yes)
		(layer "B.Cu")
		(net "GND")
	)
	(gr_poly
		(pts
			(xy 352.87712 -58.588148) (xy 352.87712 -57.952132) (xy 353.523804 -57.305448) (xy 353.523804 -55.447184)
			(xy 352.878644 -54.80177) (xy 345.68638 -54.80177) (xy 345.653614 -54.834536) (xy 345.653614 -55.19039)
			(arc
				(start 345.686634 -55.202582)
				(mid 345.820487 -55.269673)
				(end 345.937078 -55.363618)
			)
			(xy 347.026738 -56.453532) (xy 347.973904 -56.453532) (xy 348.587314 -57.066942) (xy 348.587314 -58.014108)
			(arc
				(start 349.279718 -58.706258)
				(mid 349.326469 -58.758043)
				(end 349.367856 -58.814208)
			)
			(xy 352.65106 -58.814208)
		)
		(stroke
			(width 0)
			(type solid)
		)
		(fill yes)
		(layer "B.Cu")
		(net "P1V8_PCH_PLL_AUX")
	)
	(gr_poly
		(pts
			(arc
				(start 367.07953 -263.477502)
				(mid 367.176474 -263.412663)
				(end 367.290858 -263.389872)
			)
			(xy 368.10696 -263.389872) (xy 368.34572 -263.151112)
			(arc
				(start 368.34572 -262.90143)
				(mid 368.360797 -262.807941)
				(end 368.404394 -262.723884)
			)
			(xy 368.404394 -262.177276) (xy 368.312954 -262.085836) (xy 367.769394 -262.085836) (xy 367.435384 -261.751826)
			(xy 366.444784 -261.751826) (xy 366.385094 -261.811262) (xy 366.385094 -263.506712) (xy 367.05032 -263.506712)
		)
		(stroke
			(width 0)
			(type solid)
		)
		(fill yes)
		(layer "B.Cu")
		(net "GND")
	)
	(gr_poly
		(pts
			(xy 113.8301 -415.554668) (xy 113.8301 -413.611568) (xy 113.95964 -413.482028) (xy 113.95964 -412.135828)
			(xy 113.71326 -411.889448) (xy 110.75924 -411.889448) (xy 110.43666 -411.566868) (xy 109.622844 -411.566868)
			(xy 109.571028 -411.618938) (xy 109.571028 -412.197296) (xy 109.6772 -412.303468) (xy 110.15726 -412.303468)
			(xy 110.44174 -412.587948) (xy 110.44174 -413.682688) (xy 110.20044 -413.923988) (xy 108.87456 -413.923988)
			(xy 108.78566 -414.012888) (xy 108.78566 -414.602168) (xy 108.91012 -414.726628) (xy 110.11916 -414.726628)
			(xy 110.5281 -415.135568) (xy 110.5281 -415.755328) (xy 110.71606 -415.943288) (xy 113.44148 -415.943288)
		)
		(stroke
			(width 0)
			(type solid)
		)
		(fill yes)
		(layer "B.Cu")
		(net "GND")
	)
	(gr_poly
		(pts
			(xy 181.23916 -116.774468) (xy 181.23916 -116.566188) (xy 180.63972 -115.966748) (xy 180.467 -115.966748)
			(xy 180.30444 -116.129308) (xy 180.00726 -116.129308) (xy 179.8447 -115.966748) (xy 179.65674 -115.966748)
			(xy 179.49164 -116.131848) (xy 179.21732 -116.131848) (xy 179.05222 -115.966748) (xy 178.05654 -115.966748)
			(xy 177.89398 -116.129308) (xy 177.6095 -116.129308) (xy 177.44694 -115.966748) (xy 177.25644 -115.966748)
			(xy 177.09388 -116.129308) (xy 176.8094 -116.129308) (xy 176.64684 -115.966748) (xy 176.46396 -115.966748)
			(xy 175.92294 -116.507768) (xy 175.92294 -116.799868) (xy 176.04232 -116.919248) (xy 181.09438 -116.919248)
		)
		(stroke
			(width 0)
			(type solid)
		)
		(fill yes)
		(layer "B.Cu")
		(net "P3V3_AUX_FPGA_VCCIO1")
	)
	(gr_poly
		(pts
			(xy 431.42408 -124.811028) (xy 434.325776 -124.811028) (xy 434.331618 -124.805186) (xy 435.026562 -124.805186)
			(xy 435.12486 -124.706888) (xy 435.12486 -123.050808) (xy 434.354732 -122.28068) (xy 434.354732 -121.176796)
			(xy 434.354986 -121.176542) (xy 434.354986 -120.612916) (xy 434.191918 -120.449848) (xy 430.803304 -120.449848)
			(xy 430.68367 -120.569482) (xy 430.68367 -121.194068) (xy 430.673764 -121.204228) (xy 430.673764 -121.963688)
			(xy 430.77638 -121.963688) (xy 430.77638 -122.598688) (xy 430.673764 -122.598688) (xy 430.673764 -123.993148)
			(xy 430.10328 -124.563632) (xy 430.10328 -124.955554) (xy 430.199292 -125.051566) (xy 431.183542 -125.051566)
		)
		(stroke
			(width 0)
			(type solid)
		)
		(fill yes)
		(layer "B.Cu")
		(net "GND")
	)
	(gr_poly
		(pts
			(xy 165.51402 -260.29539)
			(arc
				(start 165.51402 -257.68681)
				(mid 165.523233 -257.610697)
				(end 165.550342 -257.538982)
			)
			(xy 165.556184 -257.52806) (xy 165.556184 -256.740914) (xy 164.011356 -256.740914) (xy 163.968176 -256.78384)
			(xy 163.968176 -257.889248) (xy 163.909248 -257.948176) (xy 163.909248 -258.132072) (xy 163.705286 -258.336034)
			(xy 160.19526 -258.336034) (xy 160.132776 -258.273296) (xy 160.048702 -258.273296) (xy 159.968946 -258.19354)
			(xy 156.883608 -258.19354) (xy 156.732478 -258.34467) (xy 156.732478 -260.28015) (xy 157.006798 -260.55447)
			(xy 160.920176 -260.55447) (xy 161.699702 -261.333996) (xy 164.475414 -261.333996)
		)
		(stroke
			(width 0)
			(type solid)
		)
		(fill yes)
		(layer "B.Cu")
		(net "GND")
	)
	(gr_poly
		(pts
			(xy 235.687616 -125.151134) (xy 235.687616 -124.772674) (xy 236.226096 -124.234194) (xy 236.226096 -123.636278)
			(xy 236.16412 -123.574302) (xy 235.504482 -123.574302) (xy 235.277914 -123.347734) (xy 233.26344 -123.347734)
			(xy 233.129836 -123.481338) (xy 233.129836 -124.381514) (xy 233.218736 -124.470414) (xy 235.039916 -124.470414)
			(xy 235.187236 -124.617734) (xy 235.187236 -124.824998)
			(arc
				(start 235.192062 -124.835158)
				(mid 235.218082 -124.911993)
				(end 235.22686 -124.992638)
			)
			(arc
				(start 235.22686 -124.992638)
				(mid 235.222364 -125.050094)
				(end 235.20908 -125.106176)
			)
			(xy 235.199682 -125.13564) (xy 235.298996 -125.234954) (xy 235.603796 -125.234954)
		)
		(stroke
			(width 0)
			(type solid)
		)
		(fill yes)
		(layer "B.Cu")
		(net "P3V3_DB2000_VDDA")
	)
	(gr_poly
		(pts
			(arc
				(start 19.322796 -383.527808)
				(mid 19.063716 -383.527808)
				(end 19.322796 -383.527808)
			)
		)
		(stroke
			(width 0)
			(type solid)
		)
		(fill yes)
		(layer "B.Cu")
		(net "GND")
	)
	(gr_poly
		(pts
			(arc
				(start 19.97202 -386.419344)
				(mid 19.71294 -386.419344)
				(end 19.97202 -386.419344)
			)
		)
		(stroke
			(width 0)
			(type solid)
		)
		(fill yes)
		(layer "B.Cu")
		(net "GND")
	)
	(gr_poly
		(pts
			(arc
				(start 19.97202 -384.285744)
				(mid 19.71294 -384.285744)
				(end 19.97202 -384.285744)
			)
		)
		(stroke
			(width 0)
			(type solid)
		)
		(fill yes)
		(layer "B.Cu")
		(net "GND")
	)
	(gr_poly
		(pts
			(arc
				(start 20.614386 -383.525776)
				(mid 20.355306 -383.525776)
				(end 20.614386 -383.525776)
			)
		)
		(stroke
			(width 0)
			(type solid)
		)
		(fill yes)
		(layer "B.Cu")
		(net "GND")
	)
	(gr_poly
		(pts
			(arc
				(start 22.598126 -383.567178)
				(mid 22.339046 -383.567178)
				(end 22.598126 -383.567178)
			)
		)
		(stroke
			(width 0)
			(type solid)
		)
		(fill yes)
		(layer "B.Cu")
		(net "GND")
	)
	(gr_poly
		(pts
			(arc
				(start 23.243032 -386.444998)
				(mid 22.983952 -386.444998)
				(end 23.243032 -386.444998)
			)
		)
		(stroke
			(width 0)
			(type solid)
		)
		(fill yes)
		(layer "B.Cu")
		(net "GND")
	)
	(gr_poly
		(pts
			(arc
				(start 23.243032 -384.311398)
				(mid 22.983952 -384.311398)
				(end 23.243032 -384.311398)
			)
		)
		(stroke
			(width 0)
			(type solid)
		)
		(fill yes)
		(layer "B.Cu")
		(net "GND")
	)
	(gr_poly
		(pts
			(arc
				(start 23.515574 -379.193552)
				(mid 23.256494 -379.193552)
				(end 23.515574 -379.193552)
			)
		)
		(stroke
			(width 0)
			(type solid)
		)
		(fill yes)
		(layer "B.Cu")
		(net "GND")
	)
	(gr_poly
		(pts
			(arc
				(start 23.889716 -383.565146)
				(mid 23.630636 -383.565146)
				(end 23.889716 -383.565146)
			)
		)
		(stroke
			(width 0)
			(type solid)
		)
		(fill yes)
		(layer "B.Cu")
		(net "GND")
	)
	(gr_poly
		(pts
			(arc
				(start 30.677358 -337.235038)
				(mid 30.418278 -337.235038)
				(end 30.677358 -337.235038)
			)
		)
		(stroke
			(width 0)
			(type solid)
		)
		(fill yes)
		(layer "B.Cu")
		(net "GND")
	)
	(gr_poly
		(pts
			(arc
				(start 37.092128 -399.293334)
				(mid 36.833048 -399.293334)
				(end 37.092128 -399.293334)
			)
		)
		(stroke
			(width 0)
			(type solid)
		)
		(fill yes)
		(layer "B.Cu")
		(net "GND")
	)
	(gr_poly
		(pts
			(arc
				(start 38.357048 -399.293334)
				(mid 38.097968 -399.293334)
				(end 38.357048 -399.293334)
			)
		)
		(stroke
			(width 0)
			(type solid)
		)
		(fill yes)
		(layer "B.Cu")
		(net "GND")
	)
	(gr_poly
		(pts
			(xy 354.171504 -246.745506) (xy 354.171504 -246.494554) (xy 354.39477 -246.271288) (xy 354.407978 -246.271288)
			(xy 354.444554 -246.234712) (xy 355.932994 -246.234712) (xy 356.563676 -245.603776) (xy 356.563676 -244.652292)
			(xy 356.504494 -244.592856) (xy 356.258368 -244.592856) (xy 356.11689 -244.73408) (xy 351.142554 -244.73408)
			(xy 351.136204 -244.72773) (xy 351.098866 -244.72773) (xy 351.022158 -244.651022) (xy 351.022158 -244.647466)
			(xy 350.927924 -244.553486) (xy 350.714564 -244.553486) (xy 350.549464 -244.718586) (xy 350.549464 -246.092726)
			(xy 350.576896 -246.120412) (xy 352.76917 -246.120412) (xy 353.045268 -246.396256) (xy 353.045268 -246.825516)
			(xy 353.053904 -246.834406) (xy 354.082604 -246.834406)
		)
		(stroke
			(width 0)
			(type solid)
		)
		(fill yes)
		(layer "B.Cu")
		(net "GND")
	)
	(gr_poly
		(pts
			(arc
				(start 69.806058 -189.636908)
				(mid 69.523102 -189.636908)
				(end 69.806058 -189.636908)
			)
		)
		(stroke
			(width 0)
			(type solid)
		)
		(fill yes)
		(layer "B.Cu")
		(net "GND")
	)
	(gr_poly
		(pts
			(arc
				(start 70.885558 -187.470288)
				(mid 70.602602 -187.470288)
				(end 70.885558 -187.470288)
			)
		)
		(stroke
			(width 0)
			(type solid)
		)
		(fill yes)
		(layer "B.Cu")
		(net "GND")
	)
	(gr_poly
		(pts
			(arc
				(start 71.430134 -35.749484)
				(mid 71.158862 -35.749484)
				(end 71.430134 -35.749484)
			)
		)
		(stroke
			(width 0)
			(type solid)
		)
		(fill yes)
		(layer "B.Cu")
		(net "GND")
	)
	(gr_poly
		(pts
			(arc
				(start 73.247758 -184.902348)
				(mid 72.964802 -184.902348)
				(end 73.247758 -184.902348)
			)
		)
		(stroke
			(width 0)
			(type solid)
		)
		(fill yes)
		(layer "B.Cu")
		(net "GND")
	)
	(gr_poly
		(pts
			(arc
				(start 73.559416 -193.10223)
				(mid 73.27646 -193.10223)
				(end 73.559416 -193.10223)
			)
		)
		(stroke
			(width 0)
			(type solid)
		)
		(fill yes)
		(layer "B.Cu")
		(net "GND")
	)
	(gr_poly
		(pts
			(arc
				(start 73.821036 -187.89269)
				(mid 73.53808 -187.89269)
				(end 73.821036 -187.89269)
			)
		)
		(stroke
			(width 0)
			(type solid)
		)
		(fill yes)
		(layer "B.Cu")
		(net "GND")
	)
	(gr_poly
		(pts
			(arc
				(start 73.974198 -189.309248)
				(mid 73.691242 -189.309248)
				(end 73.974198 -189.309248)
			)
		)
		(stroke
			(width 0)
			(type solid)
		)
		(fill yes)
		(layer "B.Cu")
		(net "GND")
	)
	(gr_poly
		(pts
			(arc
				(start 77.06995 -36.019994)
				(mid 76.798678 -36.019994)
				(end 77.06995 -36.019994)
			)
		)
		(stroke
			(width 0)
			(type solid)
		)
		(fill yes)
		(layer "B.Cu")
		(net "GND")
	)
	(gr_poly
		(pts
			(arc
				(start 80.506316 -197.13575)
				(mid 80.22336 -197.13575)
				(end 80.506316 -197.13575)
			)
		)
		(stroke
			(width 0)
			(type solid)
		)
		(fill yes)
		(layer "B.Cu")
		(net "GND")
	)
	(gr_poly
		(pts
			(arc
				(start 91.816936 -192.44691)
				(mid 91.53398 -192.44691)
				(end 91.816936 -192.44691)
			)
		)
		(stroke
			(width 0)
			(type solid)
		)
		(fill yes)
		(layer "B.Cu")
		(net "GND")
	)
	(gr_poly
		(pts
			(xy 121.30151 -262.21436) (xy 121.30151 -261.408418)
			(arc
				(start 121.296684 -261.398004)
				(mid 121.27076 -261.323363)
				(end 121.261886 -261.244842)
			)
			(arc
				(start 121.261886 -261.244842)
				(mid 121.270711 -261.16631)
				(end 121.296684 -261.09168)
			)
			(xy 121.30151 -261.081266) (xy 121.30151 -260.2992) (xy 121.2342 -260.23189) (xy 120.76938 -260.23189)
			(xy 120.41759 -259.8801) (xy 119.35587 -259.8801) (xy 119.29491 -259.94106) (xy 119.29491 -261.44728)
			(xy 119.345456 -261.497572) (xy 119.60098 -261.497572) (xy 119.923814 -261.82066) (xy 120.47601 -261.82066)
			(xy 120.76811 -262.11276) (xy 120.76811 -262.26516) (xy 120.81891 -262.31596) (xy 121.19991 -262.31596)
		)
		(stroke
			(width 0)
			(type solid)
		)
		(fill yes)
		(layer "B.Cu")
		(net "PVCCINFAON_CPU1")
	)
	(gr_poly
		(pts
			(arc
				(start 159.198056 -189.88659)
				(mid 158.9151 -189.88659)
				(end 159.198056 -189.88659)
			)
		)
		(stroke
			(width 0)
			(type solid)
		)
		(fill yes)
		(layer "B.Cu")
		(net "GND")
	)
	(gr_poly
		(pts
			(arc
				(start 170.729656 -188.68009)
				(mid 170.4467 -188.68009)
				(end 170.729656 -188.68009)
			)
		)
		(stroke
			(width 0)
			(type solid)
		)
		(fill yes)
		(layer "B.Cu")
		(net "GND")
	)
	(gr_poly
		(pts
			(xy 233.508296 -125.151134) (xy 233.508296 -124.792994) (xy 233.452416 -124.737114) (xy 232.322116 -124.737114)
			(xy 231.120696 -123.535694) (xy 231.120696 -122.113294) (xy 231.054656 -122.047254) (xy 228.341174 -122.047254)
			(xy 228.19868 -122.189748) (xy 228.19868 -124.760228) (xy 228.317806 -124.879354) (xy 230.165656 -124.879354)
			(xy 230.38181 -124.6632) (xy 231.392222 -124.6632) (xy 231.728772 -125.000004)
			(arc
				(start 231.818434 -125.000004)
				(mid 231.978656 -125.066845)
				(end 232.04424 -125.227588)
			)
			(xy 232.04424 -125.257814) (xy 233.401616 -125.257814)
		)
		(stroke
			(width 0)
			(type solid)
		)
		(fill yes)
		(layer "B.Cu")
		(net "P3V3_DB2000_VDD")
	)
	(gr_poly
		(pts
			(arc
				(start 315.739526 -42.001948)
				(mid 315.460634 -42.001948)
				(end 315.739526 -42.001948)
			)
		)
		(stroke
			(width 0)
			(type solid)
		)
		(fill yes)
		(layer "B.Cu")
		(net "GND")
	)
	(gr_poly
		(pts
			(arc
				(start 321.369436 -44.578524)
				(mid 321.090544 -44.578524)
				(end 321.369436 -44.578524)
			)
		)
		(stroke
			(width 0)
			(type solid)
		)
		(fill yes)
		(layer "B.Cu")
		(net "GND")
	)
	(gr_poly
		(pts
			(arc
				(start 325.221092 -64.275208)
				(mid 324.938136 -64.275208)
				(end 325.221092 -64.275208)
			)
		)
		(stroke
			(width 0)
			(type solid)
		)
		(fill yes)
		(layer "B.Cu")
		(net "GND")
	)
	(gr_poly
		(pts
			(arc
				(start 325.31812 -65.237614)
				(mid 325.035164 -65.237614)
				(end 325.31812 -65.237614)
			)
		)
		(stroke
			(width 0)
			(type solid)
		)
		(fill yes)
		(layer "B.Cu")
		(net "GND")
	)
	(gr_poly
		(pts
			(arc
				(start 330.456794 -24.206708)
				(mid 330.173838 -24.206708)
				(end 330.456794 -24.206708)
			)
		)
		(stroke
			(width 0)
			(type solid)
		)
		(fill yes)
		(layer "B.Cu")
		(net "GND")
	)
	(gr_poly
		(pts
			(arc
				(start 353.06 -37.561266)
				(mid 352.777044 -37.561266)
				(end 353.06 -37.561266)
			)
		)
		(stroke
			(width 0)
			(type solid)
		)
		(fill yes)
		(layer "B.Cu")
		(net "GND")
	)
	(gr_poly
		(pts
			(arc
				(start 353.102164 -36.908994)
				(mid 352.819208 -36.908994)
				(end 353.102164 -36.908994)
			)
		)
		(stroke
			(width 0)
			(type solid)
		)
		(fill yes)
		(layer "B.Cu")
		(net "GND")
	)
	(gr_poly
		(pts
			(arc
				(start 369.41252 -52.324508)
				(mid 369.129564 -52.324508)
				(end 369.41252 -52.324508)
			)
		)
		(stroke
			(width 0)
			(type solid)
		)
		(fill yes)
		(layer "B.Cu")
		(net "GND")
	)
	(gr_poly
		(pts
			(arc
				(start 370.07292 -53.183028)
				(mid 369.789964 -53.183028)
				(end 370.07292 -53.183028)
			)
		)
		(stroke
			(width 0)
			(type solid)
		)
		(fill yes)
		(layer "B.Cu")
		(net "GND")
	)
	(gr_poly
		(pts
			(arc
				(start 372.296944 -54.122828)
				(mid 372.013988 -54.122828)
				(end 372.296944 -54.122828)
			)
		)
		(stroke
			(width 0)
			(type solid)
		)
		(fill yes)
		(layer "B.Cu")
		(net "GND")
	)
	(gr_poly
		(pts
			(arc
				(start 375.477278 -60.071508)
				(mid 375.194322 -60.071508)
				(end 375.477278 -60.071508)
			)
		)
		(stroke
			(width 0)
			(type solid)
		)
		(fill yes)
		(layer "B.Cu")
		(net "GND")
	)
	(gr_poly
		(pts
			(xy 379.526546 -342.796876) (xy 379.526546 -341.63) (xy 379.482096 -341.58555) (xy 378.041154 -341.58555)
			(arc
				(start 378.02693 -341.612982)
				(mid 377.68784 -341.819701)
				(end 377.34875 -341.612982)
			)
			(xy 377.334526 -341.58555) (xy 376.927364 -341.58555) (xy 376.833638 -341.679276) (xy 376.833638 -342.883236)
			(xy 376.993658 -343.043256) (xy 379.280166 -343.043256)
		)
		(stroke
			(width 0)
			(type solid)
		)
		(fill yes)
		(layer "B.Cu")
		(net "GND")
	)
	(gr_poly
		(pts
			(arc
				(start 382.50749 -57.272428)
				(mid 382.224534 -57.272428)
				(end 382.50749 -57.272428)
			)
		)
		(stroke
			(width 0)
			(type solid)
		)
		(fill yes)
		(layer "B.Cu")
		(net "GND")
	)
	(gr_poly
		(pts
			(arc
				(start 382.620012 -54.818788)
				(mid 382.337056 -54.818788)
				(end 382.620012 -54.818788)
			)
		)
		(stroke
			(width 0)
			(type solid)
		)
		(fill yes)
		(layer "B.Cu")
		(net "GND")
	)
	(gr_poly
		(pts
			(arc
				(start 383.137918 -63.442088)
				(mid 382.854962 -63.442088)
				(end 383.137918 -63.442088)
			)
		)
		(stroke
			(width 0)
			(type solid)
		)
		(fill yes)
		(layer "B.Cu")
		(net "GND")
	)
	(gr_poly
		(pts
			(arc
				(start 383.572512 -60.714382)
				(mid 383.289556 -60.714382)
				(end 383.572512 -60.714382)
			)
		)
		(stroke
			(width 0)
			(type solid)
		)
		(fill yes)
		(layer "B.Cu")
		(net "GND")
	)
	(gr_poly
		(pts
			(arc
				(start 384.471418 -62.837568)
				(mid 384.188462 -62.837568)
				(end 384.471418 -62.837568)
			)
		)
		(stroke
			(width 0)
			(type solid)
		)
		(fill yes)
		(layer "B.Cu")
		(net "GND")
	)
	(gr_poly
		(pts
			(arc
				(start 386.526532 -54.755034)
				(mid 386.243576 -54.755034)
				(end 386.526532 -54.755034)
			)
		)
		(stroke
			(width 0)
			(type solid)
		)
		(fill yes)
		(layer "B.Cu")
		(net "GND")
	)
	(gr_poly
		(pts
			(arc
				(start 387.433058 -49.736248)
				(mid 387.150102 -49.736248)
				(end 387.433058 -49.736248)
			)
		)
		(stroke
			(width 0)
			(type solid)
		)
		(fill yes)
		(layer "B.Cu")
		(net "GND")
	)
	(gr_poly
		(pts
			(arc
				(start 388.662418 -53.755036)
				(mid 388.379462 -53.755036)
				(end 388.662418 -53.755036)
			)
		)
		(stroke
			(width 0)
			(type solid)
		)
		(fill yes)
		(layer "B.Cu")
		(net "GND")
	)
	(gr_poly
		(pts
			(arc
				(start 389.205978 -50.744628)
				(mid 388.923022 -50.744628)
				(end 389.205978 -50.744628)
			)
		)
		(stroke
			(width 0)
			(type solid)
		)
		(fill yes)
		(layer "B.Cu")
		(net "GND")
	)
	(gr_poly
		(pts
			(arc
				(start 389.419338 -57.264808)
				(mid 389.136382 -57.264808)
				(end 389.419338 -57.264808)
			)
		)
		(stroke
			(width 0)
			(type solid)
		)
		(fill yes)
		(layer "B.Cu")
		(net "GND")
	)
	(gr_poly
		(pts
			(arc
				(start 407.567638 -55.806848)
				(mid 407.284682 -55.806848)
				(end 407.567638 -55.806848)
			)
		)
		(stroke
			(width 0)
			(type solid)
		)
		(fill yes)
		(layer "B.Cu")
		(net "GND")
	)
	(gr_poly
		(pts
			(arc
				(start 407.631138 -61.592968)
				(mid 407.348182 -61.592968)
				(end 407.631138 -61.592968)
			)
		)
		(stroke
			(width 0)
			(type solid)
		)
		(fill yes)
		(layer "B.Cu")
		(net "GND")
	)
	(gr_poly
		(pts
			(arc
				(start 47.566834 -403.883876)
				(mid 47.275242 -403.883876)
				(end 47.566834 -403.883876)
			)
		)
		(stroke
			(width 0)
			(type solid)
		)
		(fill yes)
		(layer "B.Cu")
		(net "GND")
	)
	(gr_poly
		(pts
			(arc
				(start 47.566834 -400.858228)
				(mid 47.275242 -400.858228)
				(end 47.566834 -400.858228)
			)
		)
		(stroke
			(width 0)
			(type solid)
		)
		(fill yes)
		(layer "B.Cu")
		(net "GND")
	)
	(gr_poly
		(pts
			(arc
				(start 48.913034 -410.030168)
				(mid 48.621442 -410.030168)
				(end 48.913034 -410.030168)
			)
		)
		(stroke
			(width 0)
			(type solid)
		)
		(fill yes)
		(layer "B.Cu")
		(net "GND")
	)
	(gr_poly
		(pts
			(arc
				(start 48.913034 -407.00452)
				(mid 48.621442 -407.00452)
				(end 48.913034 -407.00452)
			)
		)
		(stroke
			(width 0)
			(type solid)
		)
		(fill yes)
		(layer "B.Cu")
		(net "GND")
	)
	(gr_poly
		(pts
			(arc
				(start 49.548034 -403.883876)
				(mid 49.256442 -403.883876)
				(end 49.548034 -403.883876)
			)
		)
		(stroke
			(width 0)
			(type solid)
		)
		(fill yes)
		(layer "B.Cu")
		(net "GND")
	)
	(gr_poly
		(pts
			(arc
				(start 49.548034 -400.858228)
				(mid 49.256442 -400.858228)
				(end 49.548034 -400.858228)
			)
		)
		(stroke
			(width 0)
			(type solid)
		)
		(fill yes)
		(layer "B.Cu")
		(net "GND")
	)
	(gr_poly
		(pts
			(arc
				(start 50.630074 -403.883876)
				(mid 50.338482 -403.883876)
				(end 50.630074 -403.883876)
			)
		)
		(stroke
			(width 0)
			(type solid)
		)
		(fill yes)
		(layer "B.Cu")
		(net "GND")
	)
	(gr_poly
		(pts
			(arc
				(start 50.630074 -400.858228)
				(mid 50.338482 -400.858228)
				(end 50.630074 -400.858228)
			)
		)
		(stroke
			(width 0)
			(type solid)
		)
		(fill yes)
		(layer "B.Cu")
		(net "GND")
	)
	(gr_poly
		(pts
			(arc
				(start 50.894234 -410.030168)
				(mid 50.602642 -410.030168)
				(end 50.894234 -410.030168)
			)
		)
		(stroke
			(width 0)
			(type solid)
		)
		(fill yes)
		(layer "B.Cu")
		(net "GND")
	)
	(gr_poly
		(pts
			(arc
				(start 50.894234 -407.00452)
				(mid 50.602642 -407.00452)
				(end 50.894234 -407.00452)
			)
		)
		(stroke
			(width 0)
			(type solid)
		)
		(fill yes)
		(layer "B.Cu")
		(net "GND")
	)
	(gr_poly
		(pts
			(arc
				(start 51.976274 -410.030168)
				(mid 51.684682 -410.030168)
				(end 51.976274 -410.030168)
			)
		)
		(stroke
			(width 0)
			(type solid)
		)
		(fill yes)
		(layer "B.Cu")
		(net "GND")
	)
	(gr_poly
		(pts
			(arc
				(start 51.976274 -407.00452)
				(mid 51.684682 -407.00452)
				(end 51.976274 -407.00452)
			)
		)
		(stroke
			(width 0)
			(type solid)
		)
		(fill yes)
		(layer "B.Cu")
		(net "GND")
	)
	(gr_poly
		(pts
			(arc
				(start 52.611274 -403.883876)
				(mid 52.319682 -403.883876)
				(end 52.611274 -403.883876)
			)
		)
		(stroke
			(width 0)
			(type solid)
		)
		(fill yes)
		(layer "B.Cu")
		(net "GND")
	)
	(gr_poly
		(pts
			(arc
				(start 52.611274 -400.858228)
				(mid 52.319682 -400.858228)
				(end 52.611274 -400.858228)
			)
		)
		(stroke
			(width 0)
			(type solid)
		)
		(fill yes)
		(layer "B.Cu")
		(net "GND")
	)
	(gr_poly
		(pts
			(arc
				(start 53.693314 -403.883876)
				(mid 53.401722 -403.883876)
				(end 53.693314 -403.883876)
			)
		)
		(stroke
			(width 0)
			(type solid)
		)
		(fill yes)
		(layer "B.Cu")
		(net "GND")
	)
	(gr_poly
		(pts
			(arc
				(start 53.693314 -400.858228)
				(mid 53.401722 -400.858228)
				(end 53.693314 -400.858228)
			)
		)
		(stroke
			(width 0)
			(type solid)
		)
		(fill yes)
		(layer "B.Cu")
		(net "GND")
	)
	(gr_poly
		(pts
			(arc
				(start 53.957474 -410.030168)
				(mid 53.665882 -410.030168)
				(end 53.957474 -410.030168)
			)
		)
		(stroke
			(width 0)
			(type solid)
		)
		(fill yes)
		(layer "B.Cu")
		(net "GND")
	)
	(gr_poly
		(pts
			(arc
				(start 53.957474 -407.00452)
				(mid 53.665882 -407.00452)
				(end 53.957474 -407.00452)
			)
		)
		(stroke
			(width 0)
			(type solid)
		)
		(fill yes)
		(layer "B.Cu")
		(net "GND")
	)
	(gr_poly
		(pts
			(arc
				(start 55.039514 -410.030168)
				(mid 54.747922 -410.030168)
				(end 55.039514 -410.030168)
			)
		)
		(stroke
			(width 0)
			(type solid)
		)
		(fill yes)
		(layer "B.Cu")
		(net "GND")
	)
	(gr_poly
		(pts
			(arc
				(start 55.039514 -407.00452)
				(mid 54.747922 -407.00452)
				(end 55.039514 -407.00452)
			)
		)
		(stroke
			(width 0)
			(type solid)
		)
		(fill yes)
		(layer "B.Cu")
		(net "GND")
	)
	(gr_poly
		(pts
			(arc
				(start 55.674514 -403.883876)
				(mid 55.382922 -403.883876)
				(end 55.674514 -403.883876)
			)
		)
		(stroke
			(width 0)
			(type solid)
		)
		(fill yes)
		(layer "B.Cu")
		(net "GND")
	)
	(gr_poly
		(pts
			(arc
				(start 55.674514 -400.858228)
				(mid 55.382922 -400.858228)
				(end 55.674514 -400.858228)
			)
		)
		(stroke
			(width 0)
			(type solid)
		)
		(fill yes)
		(layer "B.Cu")
		(net "GND")
	)
	(gr_poly
		(pts
			(arc
				(start 56.756554 -403.883876)
				(mid 56.464962 -403.883876)
				(end 56.756554 -403.883876)
			)
		)
		(stroke
			(width 0)
			(type solid)
		)
		(fill yes)
		(layer "B.Cu")
		(net "GND")
	)
	(gr_poly
		(pts
			(arc
				(start 56.756554 -400.858228)
				(mid 56.464962 -400.858228)
				(end 56.756554 -400.858228)
			)
		)
		(stroke
			(width 0)
			(type solid)
		)
		(fill yes)
		(layer "B.Cu")
		(net "GND")
	)
	(gr_poly
		(pts
			(arc
				(start 57.020714 -410.030168)
				(mid 56.729122 -410.030168)
				(end 57.020714 -410.030168)
			)
		)
		(stroke
			(width 0)
			(type solid)
		)
		(fill yes)
		(layer "B.Cu")
		(net "GND")
	)
	(gr_poly
		(pts
			(arc
				(start 57.020714 -407.00452)
				(mid 56.729122 -407.00452)
				(end 57.020714 -407.00452)
			)
		)
		(stroke
			(width 0)
			(type solid)
		)
		(fill yes)
		(layer "B.Cu")
		(net "GND")
	)
	(gr_poly
		(pts
			(arc
				(start 58.102754 -410.030168)
				(mid 57.811162 -410.030168)
				(end 58.102754 -410.030168)
			)
		)
		(stroke
			(width 0)
			(type solid)
		)
		(fill yes)
		(layer "B.Cu")
		(net "GND")
	)
	(gr_poly
		(pts
			(arc
				(start 58.102754 -407.00452)
				(mid 57.811162 -407.00452)
				(end 58.102754 -407.00452)
			)
		)
		(stroke
			(width 0)
			(type solid)
		)
		(fill yes)
		(layer "B.Cu")
		(net "GND")
	)
	(gr_poly
		(pts
			(arc
				(start 58.737754 -403.883876)
				(mid 58.446162 -403.883876)
				(end 58.737754 -403.883876)
			)
		)
		(stroke
			(width 0)
			(type solid)
		)
		(fill yes)
		(layer "B.Cu")
		(net "GND")
	)
	(gr_poly
		(pts
			(arc
				(start 58.737754 -400.858228)
				(mid 58.446162 -400.858228)
				(end 58.737754 -400.858228)
			)
		)
		(stroke
			(width 0)
			(type solid)
		)
		(fill yes)
		(layer "B.Cu")
		(net "GND")
	)
	(gr_poly
		(pts
			(arc
				(start 59.819794 -403.883876)
				(mid 59.528202 -403.883876)
				(end 59.819794 -403.883876)
			)
		)
		(stroke
			(width 0)
			(type solid)
		)
		(fill yes)
		(layer "B.Cu")
		(net "GND")
	)
	(gr_poly
		(pts
			(arc
				(start 59.819794 -400.858228)
				(mid 59.528202 -400.858228)
				(end 59.819794 -400.858228)
			)
		)
		(stroke
			(width 0)
			(type solid)
		)
		(fill yes)
		(layer "B.Cu")
		(net "GND")
	)
	(gr_poly
		(pts
			(arc
				(start 60.083954 -410.030168)
				(mid 59.792362 -410.030168)
				(end 60.083954 -410.030168)
			)
		)
		(stroke
			(width 0)
			(type solid)
		)
		(fill yes)
		(layer "B.Cu")
		(net "GND")
	)
	(gr_poly
		(pts
			(arc
				(start 60.083954 -407.00452)
				(mid 59.792362 -407.00452)
				(end 60.083954 -407.00452)
			)
		)
		(stroke
			(width 0)
			(type solid)
		)
		(fill yes)
		(layer "B.Cu")
		(net "GND")
	)
	(gr_poly
		(pts
			(arc
				(start 61.165994 -410.030168)
				(mid 60.874402 -410.030168)
				(end 61.165994 -410.030168)
			)
		)
		(stroke
			(width 0)
			(type solid)
		)
		(fill yes)
		(layer "B.Cu")
		(net "GND")
	)
	(gr_poly
		(pts
			(arc
				(start 61.165994 -407.00452)
				(mid 60.874402 -407.00452)
				(end 61.165994 -407.00452)
			)
		)
		(stroke
			(width 0)
			(type solid)
		)
		(fill yes)
		(layer "B.Cu")
		(net "GND")
	)
	(gr_poly
		(pts
			(arc
				(start 61.800994 -403.883876)
				(mid 61.509402 -403.883876)
				(end 61.800994 -403.883876)
			)
		)
		(stroke
			(width 0)
			(type solid)
		)
		(fill yes)
		(layer "B.Cu")
		(net "GND")
	)
	(gr_poly
		(pts
			(arc
				(start 61.800994 -400.858228)
				(mid 61.509402 -400.858228)
				(end 61.800994 -400.858228)
			)
		)
		(stroke
			(width 0)
			(type solid)
		)
		(fill yes)
		(layer "B.Cu")
		(net "GND")
	)
	(gr_poly
		(pts
			(arc
				(start 62.883034 -403.883876)
				(mid 62.591442 -403.883876)
				(end 62.883034 -403.883876)
			)
		)
		(stroke
			(width 0)
			(type solid)
		)
		(fill yes)
		(layer "B.Cu")
		(net "GND")
	)
	(gr_poly
		(pts
			(arc
				(start 62.883034 -400.858228)
				(mid 62.591442 -400.858228)
				(end 62.883034 -400.858228)
			)
		)
		(stroke
			(width 0)
			(type solid)
		)
		(fill yes)
		(layer "B.Cu")
		(net "GND")
	)
	(gr_poly
		(pts
			(arc
				(start 63.147194 -410.030168)
				(mid 62.855602 -410.030168)
				(end 63.147194 -410.030168)
			)
		)
		(stroke
			(width 0)
			(type solid)
		)
		(fill yes)
		(layer "B.Cu")
		(net "GND")
	)
	(gr_poly
		(pts
			(arc
				(start 63.147194 -407.00452)
				(mid 62.855602 -407.00452)
				(end 63.147194 -407.00452)
			)
		)
		(stroke
			(width 0)
			(type solid)
		)
		(fill yes)
		(layer "B.Cu")
		(net "GND")
	)
	(gr_poly
		(pts
			(arc
				(start 64.229234 -410.030168)
				(mid 63.937642 -410.030168)
				(end 64.229234 -410.030168)
			)
		)
		(stroke
			(width 0)
			(type solid)
		)
		(fill yes)
		(layer "B.Cu")
		(net "GND")
	)
	(gr_poly
		(pts
			(arc
				(start 64.229234 -407.00452)
				(mid 63.937642 -407.00452)
				(end 64.229234 -407.00452)
			)
		)
		(stroke
			(width 0)
			(type solid)
		)
		(fill yes)
		(layer "B.Cu")
		(net "GND")
	)
	(gr_poly
		(pts
			(arc
				(start 64.864234 -403.883876)
				(mid 64.572642 -403.883876)
				(end 64.864234 -403.883876)
			)
		)
		(stroke
			(width 0)
			(type solid)
		)
		(fill yes)
		(layer "B.Cu")
		(net "GND")
	)
	(gr_poly
		(pts
			(arc
				(start 64.864234 -400.858228)
				(mid 64.572642 -400.858228)
				(end 64.864234 -400.858228)
			)
		)
		(stroke
			(width 0)
			(type solid)
		)
		(fill yes)
		(layer "B.Cu")
		(net "GND")
	)
	(gr_poly
		(pts
			(arc
				(start 65.946274 -403.883876)
				(mid 65.654682 -403.883876)
				(end 65.946274 -403.883876)
			)
		)
		(stroke
			(width 0)
			(type solid)
		)
		(fill yes)
		(layer "B.Cu")
		(net "GND")
	)
	(gr_poly
		(pts
			(arc
				(start 65.946274 -400.858228)
				(mid 65.654682 -400.858228)
				(end 65.946274 -400.858228)
			)
		)
		(stroke
			(width 0)
			(type solid)
		)
		(fill yes)
		(layer "B.Cu")
		(net "GND")
	)
	(gr_poly
		(pts
			(arc
				(start 66.210434 -410.030168)
				(mid 65.918842 -410.030168)
				(end 66.210434 -410.030168)
			)
		)
		(stroke
			(width 0)
			(type solid)
		)
		(fill yes)
		(layer "B.Cu")
		(net "GND")
	)
	(gr_poly
		(pts
			(arc
				(start 66.210434 -407.00452)
				(mid 65.918842 -407.00452)
				(end 66.210434 -407.00452)
			)
		)
		(stroke
			(width 0)
			(type solid)
		)
		(fill yes)
		(layer "B.Cu")
		(net "GND")
	)
	(gr_poly
		(pts
			(arc
				(start 67.292474 -410.030168)
				(mid 67.000882 -410.030168)
				(end 67.292474 -410.030168)
			)
		)
		(stroke
			(width 0)
			(type solid)
		)
		(fill yes)
		(layer "B.Cu")
		(net "GND")
	)
	(gr_poly
		(pts
			(arc
				(start 67.292474 -407.00452)
				(mid 67.000882 -407.00452)
				(end 67.292474 -407.00452)
			)
		)
		(stroke
			(width 0)
			(type solid)
		)
		(fill yes)
		(layer "B.Cu")
		(net "GND")
	)
	(gr_poly
		(pts
			(arc
				(start 67.927474 -403.883876)
				(mid 67.635882 -403.883876)
				(end 67.927474 -403.883876)
			)
		)
		(stroke
			(width 0)
			(type solid)
		)
		(fill yes)
		(layer "B.Cu")
		(net "GND")
	)
	(gr_poly
		(pts
			(arc
				(start 67.927474 -400.858228)
				(mid 67.635882 -400.858228)
				(end 67.927474 -400.858228)
			)
		)
		(stroke
			(width 0)
			(type solid)
		)
		(fill yes)
		(layer "B.Cu")
		(net "GND")
	)
	(gr_poly
		(pts
			(arc
				(start 69.009514 -403.883876)
				(mid 68.717922 -403.883876)
				(end 69.009514 -403.883876)
			)
		)
		(stroke
			(width 0)
			(type solid)
		)
		(fill yes)
		(layer "B.Cu")
		(net "GND")
	)
	(gr_poly
		(pts
			(arc
				(start 69.009514 -400.858228)
				(mid 68.717922 -400.858228)
				(end 69.009514 -400.858228)
			)
		)
		(stroke
			(width 0)
			(type solid)
		)
		(fill yes)
		(layer "B.Cu")
		(net "GND")
	)
	(gr_poly
		(pts
			(arc
				(start 69.273674 -410.030168)
				(mid 68.982082 -410.030168)
				(end 69.273674 -410.030168)
			)
		)
		(stroke
			(width 0)
			(type solid)
		)
		(fill yes)
		(layer "B.Cu")
		(net "GND")
	)
	(gr_poly
		(pts
			(arc
				(start 69.273674 -407.00452)
				(mid 68.982082 -407.00452)
				(end 69.273674 -407.00452)
			)
		)
		(stroke
			(width 0)
			(type solid)
		)
		(fill yes)
		(layer "B.Cu")
		(net "GND")
	)
	(gr_poly
		(pts
			(arc
				(start 70.355714 -410.030168)
				(mid 70.064122 -410.030168)
				(end 70.355714 -410.030168)
			)
		)
		(stroke
			(width 0)
			(type solid)
		)
		(fill yes)
		(layer "B.Cu")
		(net "GND")
	)
	(gr_poly
		(pts
			(arc
				(start 70.355714 -407.00452)
				(mid 70.064122 -407.00452)
				(end 70.355714 -407.00452)
			)
		)
		(stroke
			(width 0)
			(type solid)
		)
		(fill yes)
		(layer "B.Cu")
		(net "GND")
	)
	(gr_poly
		(pts
			(arc
				(start 70.990714 -403.883876)
				(mid 70.699122 -403.883876)
				(end 70.990714 -403.883876)
			)
		)
		(stroke
			(width 0)
			(type solid)
		)
		(fill yes)
		(layer "B.Cu")
		(net "GND")
	)
	(gr_poly
		(pts
			(arc
				(start 70.990714 -400.858228)
				(mid 70.699122 -400.858228)
				(end 70.990714 -400.858228)
			)
		)
		(stroke
			(width 0)
			(type solid)
		)
		(fill yes)
		(layer "B.Cu")
		(net "GND")
	)
	(gr_poly
		(pts
			(arc
				(start 72.072754 -403.883876)
				(mid 71.781162 -403.883876)
				(end 72.072754 -403.883876)
			)
		)
		(stroke
			(width 0)
			(type solid)
		)
		(fill yes)
		(layer "B.Cu")
		(net "GND")
	)
	(gr_poly
		(pts
			(arc
				(start 72.072754 -400.858228)
				(mid 71.781162 -400.858228)
				(end 72.072754 -400.858228)
			)
		)
		(stroke
			(width 0)
			(type solid)
		)
		(fill yes)
		(layer "B.Cu")
		(net "GND")
	)
	(gr_poly
		(pts
			(arc
				(start 72.336914 -410.030168)
				(mid 72.045322 -410.030168)
				(end 72.336914 -410.030168)
			)
		)
		(stroke
			(width 0)
			(type solid)
		)
		(fill yes)
		(layer "B.Cu")
		(net "GND")
	)
	(gr_poly
		(pts
			(arc
				(start 72.336914 -407.00452)
				(mid 72.045322 -407.00452)
				(end 72.336914 -407.00452)
			)
		)
		(stroke
			(width 0)
			(type solid)
		)
		(fill yes)
		(layer "B.Cu")
		(net "GND")
	)
	(gr_poly
		(pts
			(arc
				(start 73.418954 -410.030168)
				(mid 73.127362 -410.030168)
				(end 73.418954 -410.030168)
			)
		)
		(stroke
			(width 0)
			(type solid)
		)
		(fill yes)
		(layer "B.Cu")
		(net "GND")
	)
	(gr_poly
		(pts
			(arc
				(start 73.418954 -407.00452)
				(mid 73.127362 -407.00452)
				(end 73.418954 -407.00452)
			)
		)
		(stroke
			(width 0)
			(type solid)
		)
		(fill yes)
		(layer "B.Cu")
		(net "GND")
	)
	(gr_poly
		(pts
			(arc
				(start 74.053954 -403.883876)
				(mid 73.762362 -403.883876)
				(end 74.053954 -403.883876)
			)
		)
		(stroke
			(width 0)
			(type solid)
		)
		(fill yes)
		(layer "B.Cu")
		(net "GND")
	)
	(gr_poly
		(pts
			(arc
				(start 74.053954 -400.858228)
				(mid 73.762362 -400.858228)
				(end 74.053954 -400.858228)
			)
		)
		(stroke
			(width 0)
			(type solid)
		)
		(fill yes)
		(layer "B.Cu")
		(net "GND")
	)
	(gr_poly
		(pts
			(arc
				(start 75.135994 -403.883876)
				(mid 74.844402 -403.883876)
				(end 75.135994 -403.883876)
			)
		)
		(stroke
			(width 0)
			(type solid)
		)
		(fill yes)
		(layer "B.Cu")
		(net "GND")
	)
	(gr_poly
		(pts
			(arc
				(start 75.135994 -400.858228)
				(mid 74.844402 -400.858228)
				(end 75.135994 -400.858228)
			)
		)
		(stroke
			(width 0)
			(type solid)
		)
		(fill yes)
		(layer "B.Cu")
		(net "GND")
	)
	(gr_poly
		(pts
			(arc
				(start 75.400154 -410.030168)
				(mid 75.108562 -410.030168)
				(end 75.400154 -410.030168)
			)
		)
		(stroke
			(width 0)
			(type solid)
		)
		(fill yes)
		(layer "B.Cu")
		(net "GND")
	)
	(gr_poly
		(pts
			(arc
				(start 75.400154 -407.00452)
				(mid 75.108562 -407.00452)
				(end 75.400154 -407.00452)
			)
		)
		(stroke
			(width 0)
			(type solid)
		)
		(fill yes)
		(layer "B.Cu")
		(net "GND")
	)
	(gr_poly
		(pts
			(arc
				(start 76.482194 -410.030168)
				(mid 76.190602 -410.030168)
				(end 76.482194 -410.030168)
			)
		)
		(stroke
			(width 0)
			(type solid)
		)
		(fill yes)
		(layer "B.Cu")
		(net "GND")
	)
	(gr_poly
		(pts
			(arc
				(start 76.482194 -407.00452)
				(mid 76.190602 -407.00452)
				(end 76.482194 -407.00452)
			)
		)
		(stroke
			(width 0)
			(type solid)
		)
		(fill yes)
		(layer "B.Cu")
		(net "GND")
	)
	(gr_poly
		(pts
			(arc
				(start 77.117194 -403.883876)
				(mid 76.825602 -403.883876)
				(end 77.117194 -403.883876)
			)
		)
		(stroke
			(width 0)
			(type solid)
		)
		(fill yes)
		(layer "B.Cu")
		(net "GND")
	)
	(gr_poly
		(pts
			(arc
				(start 77.117194 -400.858228)
				(mid 76.825602 -400.858228)
				(end 77.117194 -400.858228)
			)
		)
		(stroke
			(width 0)
			(type solid)
		)
		(fill yes)
		(layer "B.Cu")
		(net "GND")
	)
	(gr_poly
		(pts
			(arc
				(start 78.199234 -403.883876)
				(mid 77.907642 -403.883876)
				(end 78.199234 -403.883876)
			)
		)
		(stroke
			(width 0)
			(type solid)
		)
		(fill yes)
		(layer "B.Cu")
		(net "GND")
	)
	(gr_poly
		(pts
			(arc
				(start 78.199234 -400.858228)
				(mid 77.907642 -400.858228)
				(end 78.199234 -400.858228)
			)
		)
		(stroke
			(width 0)
			(type solid)
		)
		(fill yes)
		(layer "B.Cu")
		(net "GND")
	)
	(gr_poly
		(pts
			(arc
				(start 78.463394 -410.030168)
				(mid 78.171802 -410.030168)
				(end 78.463394 -410.030168)
			)
		)
		(stroke
			(width 0)
			(type solid)
		)
		(fill yes)
		(layer "B.Cu")
		(net "GND")
	)
	(gr_poly
		(pts
			(arc
				(start 78.463394 -407.00452)
				(mid 78.171802 -407.00452)
				(end 78.463394 -407.00452)
			)
		)
		(stroke
			(width 0)
			(type solid)
		)
		(fill yes)
		(layer "B.Cu")
		(net "GND")
	)
	(gr_poly
		(pts
			(arc
				(start 79.545434 -410.030168)
				(mid 79.253842 -410.030168)
				(end 79.545434 -410.030168)
			)
		)
		(stroke
			(width 0)
			(type solid)
		)
		(fill yes)
		(layer "B.Cu")
		(net "GND")
	)
	(gr_poly
		(pts
			(arc
				(start 79.545434 -407.00452)
				(mid 79.253842 -407.00452)
				(end 79.545434 -407.00452)
			)
		)
		(stroke
			(width 0)
			(type solid)
		)
		(fill yes)
		(layer "B.Cu")
		(net "GND")
	)
	(gr_poly
		(pts
			(arc
				(start 80.180434 -403.883876)
				(mid 79.888842 -403.883876)
				(end 80.180434 -403.883876)
			)
		)
		(stroke
			(width 0)
			(type solid)
		)
		(fill yes)
		(layer "B.Cu")
		(net "GND")
	)
	(gr_poly
		(pts
			(arc
				(start 80.180434 -400.858228)
				(mid 79.888842 -400.858228)
				(end 80.180434 -400.858228)
			)
		)
		(stroke
			(width 0)
			(type solid)
		)
		(fill yes)
		(layer "B.Cu")
		(net "GND")
	)
	(gr_poly
		(pts
			(arc
				(start 81.262474 -403.883876)
				(mid 80.970882 -403.883876)
				(end 81.262474 -403.883876)
			)
		)
		(stroke
			(width 0)
			(type solid)
		)
		(fill yes)
		(layer "B.Cu")
		(net "GND")
	)
	(gr_poly
		(pts
			(arc
				(start 81.262474 -400.858228)
				(mid 80.970882 -400.858228)
				(end 81.262474 -400.858228)
			)
		)
		(stroke
			(width 0)
			(type solid)
		)
		(fill yes)
		(layer "B.Cu")
		(net "GND")
	)
	(gr_poly
		(pts
			(arc
				(start 81.526634 -410.030168)
				(mid 81.235042 -410.030168)
				(end 81.526634 -410.030168)
			)
		)
		(stroke
			(width 0)
			(type solid)
		)
		(fill yes)
		(layer "B.Cu")
		(net "GND")
	)
	(gr_poly
		(pts
			(arc
				(start 81.526634 -407.00452)
				(mid 81.235042 -407.00452)
				(end 81.526634 -407.00452)
			)
		)
		(stroke
			(width 0)
			(type solid)
		)
		(fill yes)
		(layer "B.Cu")
		(net "GND")
	)
	(gr_poly
		(pts
			(arc
				(start 82.608674 -410.030168)
				(mid 82.317082 -410.030168)
				(end 82.608674 -410.030168)
			)
		)
		(stroke
			(width 0)
			(type solid)
		)
		(fill yes)
		(layer "B.Cu")
		(net "GND")
	)
	(gr_poly
		(pts
			(arc
				(start 82.608674 -407.00452)
				(mid 82.317082 -407.00452)
				(end 82.608674 -407.00452)
			)
		)
		(stroke
			(width 0)
			(type solid)
		)
		(fill yes)
		(layer "B.Cu")
		(net "GND")
	)
	(gr_poly
		(pts
			(arc
				(start 83.243674 -403.883876)
				(mid 82.952082 -403.883876)
				(end 83.243674 -403.883876)
			)
		)
		(stroke
			(width 0)
			(type solid)
		)
		(fill yes)
		(layer "B.Cu")
		(net "GND")
	)
	(gr_poly
		(pts
			(arc
				(start 83.243674 -400.858228)
				(mid 82.952082 -400.858228)
				(end 83.243674 -400.858228)
			)
		)
		(stroke
			(width 0)
			(type solid)
		)
		(fill yes)
		(layer "B.Cu")
		(net "GND")
	)
	(gr_poly
		(pts
			(arc
				(start 84.325714 -403.883876)
				(mid 84.034122 -403.883876)
				(end 84.325714 -403.883876)
			)
		)
		(stroke
			(width 0)
			(type solid)
		)
		(fill yes)
		(layer "B.Cu")
		(net "GND")
	)
	(gr_poly
		(pts
			(arc
				(start 84.325714 -400.858228)
				(mid 84.034122 -400.858228)
				(end 84.325714 -400.858228)
			)
		)
		(stroke
			(width 0)
			(type solid)
		)
		(fill yes)
		(layer "B.Cu")
		(net "GND")
	)
	(gr_poly
		(pts
			(arc
				(start 84.589874 -410.030168)
				(mid 84.298282 -410.030168)
				(end 84.589874 -410.030168)
			)
		)
		(stroke
			(width 0)
			(type solid)
		)
		(fill yes)
		(layer "B.Cu")
		(net "GND")
	)
	(gr_poly
		(pts
			(arc
				(start 84.589874 -407.00452)
				(mid 84.298282 -407.00452)
				(end 84.589874 -407.00452)
			)
		)
		(stroke
			(width 0)
			(type solid)
		)
		(fill yes)
		(layer "B.Cu")
		(net "GND")
	)
	(gr_poly
		(pts
			(arc
				(start 85.671914 -410.030168)
				(mid 85.380322 -410.030168)
				(end 85.671914 -410.030168)
			)
		)
		(stroke
			(width 0)
			(type solid)
		)
		(fill yes)
		(layer "B.Cu")
		(net "GND")
	)
	(gr_poly
		(pts
			(arc
				(start 85.671914 -407.00452)
				(mid 85.380322 -407.00452)
				(end 85.671914 -407.00452)
			)
		)
		(stroke
			(width 0)
			(type solid)
		)
		(fill yes)
		(layer "B.Cu")
		(net "GND")
	)
	(gr_poly
		(pts
			(arc
				(start 86.306914 -403.883876)
				(mid 86.015322 -403.883876)
				(end 86.306914 -403.883876)
			)
		)
		(stroke
			(width 0)
			(type solid)
		)
		(fill yes)
		(layer "B.Cu")
		(net "GND")
	)
	(gr_poly
		(pts
			(arc
				(start 86.306914 -400.858228)
				(mid 86.015322 -400.858228)
				(end 86.306914 -400.858228)
			)
		)
		(stroke
			(width 0)
			(type solid)
		)
		(fill yes)
		(layer "B.Cu")
		(net "GND")
	)
	(gr_poly
		(pts
			(arc
				(start 87.388954 -403.883876)
				(mid 87.097362 -403.883876)
				(end 87.388954 -403.883876)
			)
		)
		(stroke
			(width 0)
			(type solid)
		)
		(fill yes)
		(layer "B.Cu")
		(net "GND")
	)
	(gr_poly
		(pts
			(arc
				(start 87.388954 -400.858228)
				(mid 87.097362 -400.858228)
				(end 87.388954 -400.858228)
			)
		)
		(stroke
			(width 0)
			(type solid)
		)
		(fill yes)
		(layer "B.Cu")
		(net "GND")
	)
	(gr_poly
		(pts
			(arc
				(start 87.653114 -410.030168)
				(mid 87.361522 -410.030168)
				(end 87.653114 -410.030168)
			)
		)
		(stroke
			(width 0)
			(type solid)
		)
		(fill yes)
		(layer "B.Cu")
		(net "GND")
	)
	(gr_poly
		(pts
			(arc
				(start 87.653114 -407.00452)
				(mid 87.361522 -407.00452)
				(end 87.653114 -407.00452)
			)
		)
		(stroke
			(width 0)
			(type solid)
		)
		(fill yes)
		(layer "B.Cu")
		(net "GND")
	)
	(gr_poly
		(pts
			(arc
				(start 88.735154 -410.030168)
				(mid 88.443562 -410.030168)
				(end 88.735154 -410.030168)
			)
		)
		(stroke
			(width 0)
			(type solid)
		)
		(fill yes)
		(layer "B.Cu")
		(net "GND")
	)
	(gr_poly
		(pts
			(arc
				(start 88.735154 -407.00452)
				(mid 88.443562 -407.00452)
				(end 88.735154 -407.00452)
			)
		)
		(stroke
			(width 0)
			(type solid)
		)
		(fill yes)
		(layer "B.Cu")
		(net "GND")
	)
	(gr_poly
		(pts
			(arc
				(start 89.370154 -403.883876)
				(mid 89.078562 -403.883876)
				(end 89.370154 -403.883876)
			)
		)
		(stroke
			(width 0)
			(type solid)
		)
		(fill yes)
		(layer "B.Cu")
		(net "GND")
	)
	(gr_poly
		(pts
			(arc
				(start 89.370154 -400.858228)
				(mid 89.078562 -400.858228)
				(end 89.370154 -400.858228)
			)
		)
		(stroke
			(width 0)
			(type solid)
		)
		(fill yes)
		(layer "B.Cu")
		(net "GND")
	)
	(gr_poly
		(pts
			(arc
				(start 90.452194 -403.883876)
				(mid 90.160602 -403.883876)
				(end 90.452194 -403.883876)
			)
		)
		(stroke
			(width 0)
			(type solid)
		)
		(fill yes)
		(layer "B.Cu")
		(net "GND")
	)
	(gr_poly
		(pts
			(arc
				(start 90.452194 -400.834352)
				(mid 90.160602 -400.834352)
				(end 90.452194 -400.834352)
			)
		)
		(stroke
			(width 0)
			(type solid)
		)
		(fill yes)
		(layer "B.Cu")
		(net "GND")
	)
	(gr_poly
		(pts
			(arc
				(start 90.716354 -410.030168)
				(mid 90.424762 -410.030168)
				(end 90.716354 -410.030168)
			)
		)
		(stroke
			(width 0)
			(type solid)
		)
		(fill yes)
		(layer "B.Cu")
		(net "GND")
	)
	(gr_poly
		(pts
			(arc
				(start 90.716354 -407.00452)
				(mid 90.424762 -407.00452)
				(end 90.716354 -407.00452)
			)
		)
		(stroke
			(width 0)
			(type solid)
		)
		(fill yes)
		(layer "B.Cu")
		(net "GND")
	)
	(gr_poly
		(pts
			(arc
				(start 91.798394 -410.030168)
				(mid 91.506802 -410.030168)
				(end 91.798394 -410.030168)
			)
		)
		(stroke
			(width 0)
			(type solid)
		)
		(fill yes)
		(layer "B.Cu")
		(net "GND")
	)
	(gr_poly
		(pts
			(arc
				(start 91.798394 -406.980644)
				(mid 91.506802 -406.980644)
				(end 91.798394 -406.980644)
			)
		)
		(stroke
			(width 0)
			(type solid)
		)
		(fill yes)
		(layer "B.Cu")
		(net "GND")
	)
	(gr_poly
		(pts
			(arc
				(start 92.433394 -403.883876)
				(mid 92.141802 -403.883876)
				(end 92.433394 -403.883876)
			)
		)
		(stroke
			(width 0)
			(type solid)
		)
		(fill yes)
		(layer "B.Cu")
		(net "GND")
	)
	(gr_poly
		(pts
			(arc
				(start 92.433394 -400.834352)
				(mid 92.141802 -400.834352)
				(end 92.433394 -400.834352)
			)
		)
		(stroke
			(width 0)
			(type solid)
		)
		(fill yes)
		(layer "B.Cu")
		(net "GND")
	)
	(gr_poly
		(pts
			(arc
				(start 93.515434 -403.883876)
				(mid 93.223842 -403.883876)
				(end 93.515434 -403.883876)
			)
		)
		(stroke
			(width 0)
			(type solid)
		)
		(fill yes)
		(layer "B.Cu")
		(net "GND")
	)
	(gr_poly
		(pts
			(arc
				(start 93.515434 -400.858228)
				(mid 93.223842 -400.858228)
				(end 93.515434 -400.858228)
			)
		)
		(stroke
			(width 0)
			(type solid)
		)
		(fill yes)
		(layer "B.Cu")
		(net "GND")
	)
	(gr_poly
		(pts
			(arc
				(start 93.779594 -410.030168)
				(mid 93.488002 -410.030168)
				(end 93.779594 -410.030168)
			)
		)
		(stroke
			(width 0)
			(type solid)
		)
		(fill yes)
		(layer "B.Cu")
		(net "GND")
	)
	(gr_poly
		(pts
			(arc
				(start 93.779594 -406.980644)
				(mid 93.488002 -406.980644)
				(end 93.779594 -406.980644)
			)
		)
		(stroke
			(width 0)
			(type solid)
		)
		(fill yes)
		(layer "B.Cu")
		(net "GND")
	)
	(gr_poly
		(pts
			(arc
				(start 94.861634 -410.030168)
				(mid 94.570042 -410.030168)
				(end 94.861634 -410.030168)
			)
		)
		(stroke
			(width 0)
			(type solid)
		)
		(fill yes)
		(layer "B.Cu")
		(net "GND")
	)
	(gr_poly
		(pts
			(arc
				(start 94.861634 -407.00452)
				(mid 94.570042 -407.00452)
				(end 94.861634 -407.00452)
			)
		)
		(stroke
			(width 0)
			(type solid)
		)
		(fill yes)
		(layer "B.Cu")
		(net "GND")
	)
	(gr_poly
		(pts
			(arc
				(start 95.496634 -403.883876)
				(mid 95.205042 -403.883876)
				(end 95.496634 -403.883876)
			)
		)
		(stroke
			(width 0)
			(type solid)
		)
		(fill yes)
		(layer "B.Cu")
		(net "GND")
	)
	(gr_poly
		(pts
			(arc
				(start 95.496634 -400.858228)
				(mid 95.205042 -400.858228)
				(end 95.496634 -400.858228)
			)
		)
		(stroke
			(width 0)
			(type solid)
		)
		(fill yes)
		(layer "B.Cu")
		(net "GND")
	)
	(gr_poly
		(pts
			(arc
				(start 96.842834 -410.030168)
				(mid 96.551242 -410.030168)
				(end 96.842834 -410.030168)
			)
		)
		(stroke
			(width 0)
			(type solid)
		)
		(fill yes)
		(layer "B.Cu")
		(net "GND")
	)
	(gr_poly
		(pts
			(arc
				(start 96.842834 -407.00452)
				(mid 96.551242 -407.00452)
				(end 96.842834 -407.00452)
			)
		)
		(stroke
			(width 0)
			(type solid)
		)
		(fill yes)
		(layer "B.Cu")
		(net "GND")
	)
	(gr_poly
		(pts
			(arc
				(start 119.74195 -403.883876)
				(mid 119.450358 -403.883876)
				(end 119.74195 -403.883876)
			)
		)
		(stroke
			(width 0)
			(type solid)
		)
		(fill yes)
		(layer "B.Cu")
		(net "GND")
	)
	(gr_poly
		(pts
			(arc
				(start 119.74195 -400.858228)
				(mid 119.450358 -400.858228)
				(end 119.74195 -400.858228)
			)
		)
		(stroke
			(width 0)
			(type solid)
		)
		(fill yes)
		(layer "B.Cu")
		(net "GND")
	)
	(gr_poly
		(pts
			(arc
				(start 121.08815 -410.030168)
				(mid 120.796558 -410.030168)
				(end 121.08815 -410.030168)
			)
		)
		(stroke
			(width 0)
			(type solid)
		)
		(fill yes)
		(layer "B.Cu")
		(net "GND")
	)
	(gr_poly
		(pts
			(arc
				(start 121.08815 -407.00452)
				(mid 120.796558 -407.00452)
				(end 121.08815 -407.00452)
			)
		)
		(stroke
			(width 0)
			(type solid)
		)
		(fill yes)
		(layer "B.Cu")
		(net "GND")
	)
	(gr_poly
		(pts
			(arc
				(start 121.72315 -403.883876)
				(mid 121.431558 -403.883876)
				(end 121.72315 -403.883876)
			)
		)
		(stroke
			(width 0)
			(type solid)
		)
		(fill yes)
		(layer "B.Cu")
		(net "GND")
	)
	(gr_poly
		(pts
			(arc
				(start 121.72315 -400.858228)
				(mid 121.431558 -400.858228)
				(end 121.72315 -400.858228)
			)
		)
		(stroke
			(width 0)
			(type solid)
		)
		(fill yes)
		(layer "B.Cu")
		(net "GND")
	)
	(gr_poly
		(pts
			(arc
				(start 122.80519 -403.883876)
				(mid 122.513598 -403.883876)
				(end 122.80519 -403.883876)
			)
		)
		(stroke
			(width 0)
			(type solid)
		)
		(fill yes)
		(layer "B.Cu")
		(net "GND")
	)
	(gr_poly
		(pts
			(arc
				(start 122.80519 -400.858228)
				(mid 122.513598 -400.858228)
				(end 122.80519 -400.858228)
			)
		)
		(stroke
			(width 0)
			(type solid)
		)
		(fill yes)
		(layer "B.Cu")
		(net "GND")
	)
	(gr_poly
		(pts
			(arc
				(start 123.06935 -410.030168)
				(mid 122.777758 -410.030168)
				(end 123.06935 -410.030168)
			)
		)
		(stroke
			(width 0)
			(type solid)
		)
		(fill yes)
		(layer "B.Cu")
		(net "GND")
	)
	(gr_poly
		(pts
			(arc
				(start 123.06935 -407.00452)
				(mid 122.777758 -407.00452)
				(end 123.06935 -407.00452)
			)
		)
		(stroke
			(width 0)
			(type solid)
		)
		(fill yes)
		(layer "B.Cu")
		(net "GND")
	)
	(gr_poly
		(pts
			(arc
				(start 124.15139 -410.030168)
				(mid 123.859798 -410.030168)
				(end 124.15139 -410.030168)
			)
		)
		(stroke
			(width 0)
			(type solid)
		)
		(fill yes)
		(layer "B.Cu")
		(net "GND")
	)
	(gr_poly
		(pts
			(arc
				(start 124.15139 -407.00452)
				(mid 123.859798 -407.00452)
				(end 124.15139 -407.00452)
			)
		)
		(stroke
			(width 0)
			(type solid)
		)
		(fill yes)
		(layer "B.Cu")
		(net "GND")
	)
	(gr_poly
		(pts
			(arc
				(start 124.78639 -403.883876)
				(mid 124.494798 -403.883876)
				(end 124.78639 -403.883876)
			)
		)
		(stroke
			(width 0)
			(type solid)
		)
		(fill yes)
		(layer "B.Cu")
		(net "GND")
	)
	(gr_poly
		(pts
			(arc
				(start 124.78639 -400.858228)
				(mid 124.494798 -400.858228)
				(end 124.78639 -400.858228)
			)
		)
		(stroke
			(width 0)
			(type solid)
		)
		(fill yes)
		(layer "B.Cu")
		(net "GND")
	)
	(gr_poly
		(pts
			(arc
				(start 125.86843 -403.883876)
				(mid 125.576838 -403.883876)
				(end 125.86843 -403.883876)
			)
		)
		(stroke
			(width 0)
			(type solid)
		)
		(fill yes)
		(layer "B.Cu")
		(net "GND")
	)
	(gr_poly
		(pts
			(arc
				(start 125.86843 -400.858228)
				(mid 125.576838 -400.858228)
				(end 125.86843 -400.858228)
			)
		)
		(stroke
			(width 0)
			(type solid)
		)
		(fill yes)
		(layer "B.Cu")
		(net "GND")
	)
	(gr_poly
		(pts
			(arc
				(start 126.13259 -410.030168)
				(mid 125.840998 -410.030168)
				(end 126.13259 -410.030168)
			)
		)
		(stroke
			(width 0)
			(type solid)
		)
		(fill yes)
		(layer "B.Cu")
		(net "GND")
	)
	(gr_poly
		(pts
			(arc
				(start 126.13259 -407.00452)
				(mid 125.840998 -407.00452)
				(end 126.13259 -407.00452)
			)
		)
		(stroke
			(width 0)
			(type solid)
		)
		(fill yes)
		(layer "B.Cu")
		(net "GND")
	)
	(gr_poly
		(pts
			(arc
				(start 127.21463 -410.030168)
				(mid 126.923038 -410.030168)
				(end 127.21463 -410.030168)
			)
		)
		(stroke
			(width 0)
			(type solid)
		)
		(fill yes)
		(layer "B.Cu")
		(net "GND")
	)
	(gr_poly
		(pts
			(arc
				(start 127.21463 -407.00452)
				(mid 126.923038 -407.00452)
				(end 127.21463 -407.00452)
			)
		)
		(stroke
			(width 0)
			(type solid)
		)
		(fill yes)
		(layer "B.Cu")
		(net "GND")
	)
	(gr_poly
		(pts
			(arc
				(start 127.84963 -403.883876)
				(mid 127.558038 -403.883876)
				(end 127.84963 -403.883876)
			)
		)
		(stroke
			(width 0)
			(type solid)
		)
		(fill yes)
		(layer "B.Cu")
		(net "GND")
	)
	(gr_poly
		(pts
			(arc
				(start 127.84963 -400.858228)
				(mid 127.558038 -400.858228)
				(end 127.84963 -400.858228)
			)
		)
		(stroke
			(width 0)
			(type solid)
		)
		(fill yes)
		(layer "B.Cu")
		(net "GND")
	)
	(gr_poly
		(pts
			(arc
				(start 128.93167 -403.883876)
				(mid 128.640078 -403.883876)
				(end 128.93167 -403.883876)
			)
		)
		(stroke
			(width 0)
			(type solid)
		)
		(fill yes)
		(layer "B.Cu")
		(net "GND")
	)
	(gr_poly
		(pts
			(arc
				(start 128.93167 -400.858228)
				(mid 128.640078 -400.858228)
				(end 128.93167 -400.858228)
			)
		)
		(stroke
			(width 0)
			(type solid)
		)
		(fill yes)
		(layer "B.Cu")
		(net "GND")
	)
	(gr_poly
		(pts
			(arc
				(start 129.19583 -410.030168)
				(mid 128.904238 -410.030168)
				(end 129.19583 -410.030168)
			)
		)
		(stroke
			(width 0)
			(type solid)
		)
		(fill yes)
		(layer "B.Cu")
		(net "GND")
	)
	(gr_poly
		(pts
			(arc
				(start 129.19583 -407.00452)
				(mid 128.904238 -407.00452)
				(end 129.19583 -407.00452)
			)
		)
		(stroke
			(width 0)
			(type solid)
		)
		(fill yes)
		(layer "B.Cu")
		(net "GND")
	)
	(gr_poly
		(pts
			(arc
				(start 130.27787 -410.030168)
				(mid 129.986278 -410.030168)
				(end 130.27787 -410.030168)
			)
		)
		(stroke
			(width 0)
			(type solid)
		)
		(fill yes)
		(layer "B.Cu")
		(net "GND")
	)
	(gr_poly
		(pts
			(arc
				(start 130.27787 -407.00452)
				(mid 129.986278 -407.00452)
				(end 130.27787 -407.00452)
			)
		)
		(stroke
			(width 0)
			(type solid)
		)
		(fill yes)
		(layer "B.Cu")
		(net "GND")
	)
	(gr_poly
		(pts
			(arc
				(start 130.91287 -403.883876)
				(mid 130.621278 -403.883876)
				(end 130.91287 -403.883876)
			)
		)
		(stroke
			(width 0)
			(type solid)
		)
		(fill yes)
		(layer "B.Cu")
		(net "GND")
	)
	(gr_poly
		(pts
			(arc
				(start 130.91287 -400.858228)
				(mid 130.621278 -400.858228)
				(end 130.91287 -400.858228)
			)
		)
		(stroke
			(width 0)
			(type solid)
		)
		(fill yes)
		(layer "B.Cu")
		(net "GND")
	)
	(gr_poly
		(pts
			(arc
				(start 131.99491 -403.883876)
				(mid 131.703318 -403.883876)
				(end 131.99491 -403.883876)
			)
		)
		(stroke
			(width 0)
			(type solid)
		)
		(fill yes)
		(layer "B.Cu")
		(net "GND")
	)
	(gr_poly
		(pts
			(arc
				(start 131.99491 -400.858228)
				(mid 131.703318 -400.858228)
				(end 131.99491 -400.858228)
			)
		)
		(stroke
			(width 0)
			(type solid)
		)
		(fill yes)
		(layer "B.Cu")
		(net "GND")
	)
	(gr_poly
		(pts
			(arc
				(start 132.25907 -410.030168)
				(mid 131.967478 -410.030168)
				(end 132.25907 -410.030168)
			)
		)
		(stroke
			(width 0)
			(type solid)
		)
		(fill yes)
		(layer "B.Cu")
		(net "GND")
	)
	(gr_poly
		(pts
			(arc
				(start 132.25907 -407.00452)
				(mid 131.967478 -407.00452)
				(end 132.25907 -407.00452)
			)
		)
		(stroke
			(width 0)
			(type solid)
		)
		(fill yes)
		(layer "B.Cu")
		(net "GND")
	)
	(gr_poly
		(pts
			(arc
				(start 133.34111 -410.030168)
				(mid 133.049518 -410.030168)
				(end 133.34111 -410.030168)
			)
		)
		(stroke
			(width 0)
			(type solid)
		)
		(fill yes)
		(layer "B.Cu")
		(net "GND")
	)
	(gr_poly
		(pts
			(arc
				(start 133.34111 -407.00452)
				(mid 133.049518 -407.00452)
				(end 133.34111 -407.00452)
			)
		)
		(stroke
			(width 0)
			(type solid)
		)
		(fill yes)
		(layer "B.Cu")
		(net "GND")
	)
	(gr_poly
		(pts
			(arc
				(start 133.97611 -403.883876)
				(mid 133.684518 -403.883876)
				(end 133.97611 -403.883876)
			)
		)
		(stroke
			(width 0)
			(type solid)
		)
		(fill yes)
		(layer "B.Cu")
		(net "GND")
	)
	(gr_poly
		(pts
			(arc
				(start 133.97611 -400.858228)
				(mid 133.684518 -400.858228)
				(end 133.97611 -400.858228)
			)
		)
		(stroke
			(width 0)
			(type solid)
		)
		(fill yes)
		(layer "B.Cu")
		(net "GND")
	)
	(gr_poly
		(pts
			(arc
				(start 135.05815 -403.883876)
				(mid 134.766558 -403.883876)
				(end 135.05815 -403.883876)
			)
		)
		(stroke
			(width 0)
			(type solid)
		)
		(fill yes)
		(layer "B.Cu")
		(net "GND")
	)
	(gr_poly
		(pts
			(arc
				(start 135.05815 -400.858228)
				(mid 134.766558 -400.858228)
				(end 135.05815 -400.858228)
			)
		)
		(stroke
			(width 0)
			(type solid)
		)
		(fill yes)
		(layer "B.Cu")
		(net "GND")
	)
	(gr_poly
		(pts
			(arc
				(start 135.32231 -410.030168)
				(mid 135.030718 -410.030168)
				(end 135.32231 -410.030168)
			)
		)
		(stroke
			(width 0)
			(type solid)
		)
		(fill yes)
		(layer "B.Cu")
		(net "GND")
	)
	(gr_poly
		(pts
			(arc
				(start 135.32231 -407.00452)
				(mid 135.030718 -407.00452)
				(end 135.32231 -407.00452)
			)
		)
		(stroke
			(width 0)
			(type solid)
		)
		(fill yes)
		(layer "B.Cu")
		(net "GND")
	)
	(gr_poly
		(pts
			(arc
				(start 136.40435 -410.030168)
				(mid 136.112758 -410.030168)
				(end 136.40435 -410.030168)
			)
		)
		(stroke
			(width 0)
			(type solid)
		)
		(fill yes)
		(layer "B.Cu")
		(net "GND")
	)
	(gr_poly
		(pts
			(arc
				(start 136.40435 -407.00452)
				(mid 136.112758 -407.00452)
				(end 136.40435 -407.00452)
			)
		)
		(stroke
			(width 0)
			(type solid)
		)
		(fill yes)
		(layer "B.Cu")
		(net "GND")
	)
	(gr_poly
		(pts
			(arc
				(start 137.03935 -403.883876)
				(mid 136.747758 -403.883876)
				(end 137.03935 -403.883876)
			)
		)
		(stroke
			(width 0)
			(type solid)
		)
		(fill yes)
		(layer "B.Cu")
		(net "GND")
	)
	(gr_poly
		(pts
			(arc
				(start 137.03935 -400.858228)
				(mid 136.747758 -400.858228)
				(end 137.03935 -400.858228)
			)
		)
		(stroke
			(width 0)
			(type solid)
		)
		(fill yes)
		(layer "B.Cu")
		(net "GND")
	)
	(gr_poly
		(pts
			(arc
				(start 138.12139 -403.883876)
				(mid 137.829798 -403.883876)
				(end 138.12139 -403.883876)
			)
		)
		(stroke
			(width 0)
			(type solid)
		)
		(fill yes)
		(layer "B.Cu")
		(net "GND")
	)
	(gr_poly
		(pts
			(arc
				(start 138.12139 -400.858228)
				(mid 137.829798 -400.858228)
				(end 138.12139 -400.858228)
			)
		)
		(stroke
			(width 0)
			(type solid)
		)
		(fill yes)
		(layer "B.Cu")
		(net "GND")
	)
	(gr_poly
		(pts
			(arc
				(start 138.38555 -410.030168)
				(mid 138.093958 -410.030168)
				(end 138.38555 -410.030168)
			)
		)
		(stroke
			(width 0)
			(type solid)
		)
		(fill yes)
		(layer "B.Cu")
		(net "GND")
	)
	(gr_poly
		(pts
			(arc
				(start 138.38555 -407.00452)
				(mid 138.093958 -407.00452)
				(end 138.38555 -407.00452)
			)
		)
		(stroke
			(width 0)
			(type solid)
		)
		(fill yes)
		(layer "B.Cu")
		(net "GND")
	)
	(gr_poly
		(pts
			(arc
				(start 139.46759 -410.030168)
				(mid 139.175998 -410.030168)
				(end 139.46759 -410.030168)
			)
		)
		(stroke
			(width 0)
			(type solid)
		)
		(fill yes)
		(layer "B.Cu")
		(net "GND")
	)
	(gr_poly
		(pts
			(arc
				(start 139.46759 -407.00452)
				(mid 139.175998 -407.00452)
				(end 139.46759 -407.00452)
			)
		)
		(stroke
			(width 0)
			(type solid)
		)
		(fill yes)
		(layer "B.Cu")
		(net "GND")
	)
	(gr_poly
		(pts
			(arc
				(start 140.10259 -403.883876)
				(mid 139.810998 -403.883876)
				(end 140.10259 -403.883876)
			)
		)
		(stroke
			(width 0)
			(type solid)
		)
		(fill yes)
		(layer "B.Cu")
		(net "GND")
	)
	(gr_poly
		(pts
			(arc
				(start 140.10259 -400.858228)
				(mid 139.810998 -400.858228)
				(end 140.10259 -400.858228)
			)
		)
		(stroke
			(width 0)
			(type solid)
		)
		(fill yes)
		(layer "B.Cu")
		(net "GND")
	)
	(gr_poly
		(pts
			(arc
				(start 141.18463 -403.883876)
				(mid 140.893038 -403.883876)
				(end 141.18463 -403.883876)
			)
		)
		(stroke
			(width 0)
			(type solid)
		)
		(fill yes)
		(layer "B.Cu")
		(net "GND")
	)
	(gr_poly
		(pts
			(arc
				(start 141.18463 -400.858228)
				(mid 140.893038 -400.858228)
				(end 141.18463 -400.858228)
			)
		)
		(stroke
			(width 0)
			(type solid)
		)
		(fill yes)
		(layer "B.Cu")
		(net "GND")
	)
	(gr_poly
		(pts
			(arc
				(start 141.44879 -410.030168)
				(mid 141.157198 -410.030168)
				(end 141.44879 -410.030168)
			)
		)
		(stroke
			(width 0)
			(type solid)
		)
		(fill yes)
		(layer "B.Cu")
		(net "GND")
	)
	(gr_poly
		(pts
			(arc
				(start 141.44879 -407.00452)
				(mid 141.157198 -407.00452)
				(end 141.44879 -407.00452)
			)
		)
		(stroke
			(width 0)
			(type solid)
		)
		(fill yes)
		(layer "B.Cu")
		(net "GND")
	)
	(gr_poly
		(pts
			(arc
				(start 142.53083 -410.030168)
				(mid 142.239238 -410.030168)
				(end 142.53083 -410.030168)
			)
		)
		(stroke
			(width 0)
			(type solid)
		)
		(fill yes)
		(layer "B.Cu")
		(net "GND")
	)
	(gr_poly
		(pts
			(arc
				(start 142.53083 -407.00452)
				(mid 142.239238 -407.00452)
				(end 142.53083 -407.00452)
			)
		)
		(stroke
			(width 0)
			(type solid)
		)
		(fill yes)
		(layer "B.Cu")
		(net "GND")
	)
	(gr_poly
		(pts
			(arc
				(start 143.16583 -403.883876)
				(mid 142.874238 -403.883876)
				(end 143.16583 -403.883876)
			)
		)
		(stroke
			(width 0)
			(type solid)
		)
		(fill yes)
		(layer "B.Cu")
		(net "GND")
	)
	(gr_poly
		(pts
			(arc
				(start 143.16583 -400.858228)
				(mid 142.874238 -400.858228)
				(end 143.16583 -400.858228)
			)
		)
		(stroke
			(width 0)
			(type solid)
		)
		(fill yes)
		(layer "B.Cu")
		(net "GND")
	)
	(gr_poly
		(pts
			(arc
				(start 144.24787 -403.883876)
				(mid 143.956278 -403.883876)
				(end 144.24787 -403.883876)
			)
		)
		(stroke
			(width 0)
			(type solid)
		)
		(fill yes)
		(layer "B.Cu")
		(net "GND")
	)
	(gr_poly
		(pts
			(arc
				(start 144.24787 -400.858228)
				(mid 143.956278 -400.858228)
				(end 144.24787 -400.858228)
			)
		)
		(stroke
			(width 0)
			(type solid)
		)
		(fill yes)
		(layer "B.Cu")
		(net "GND")
	)
	(gr_poly
		(pts
			(arc
				(start 144.51203 -410.030168)
				(mid 144.220438 -410.030168)
				(end 144.51203 -410.030168)
			)
		)
		(stroke
			(width 0)
			(type solid)
		)
		(fill yes)
		(layer "B.Cu")
		(net "GND")
	)
	(gr_poly
		(pts
			(arc
				(start 144.51203 -407.00452)
				(mid 144.220438 -407.00452)
				(end 144.51203 -407.00452)
			)
		)
		(stroke
			(width 0)
			(type solid)
		)
		(fill yes)
		(layer "B.Cu")
		(net "GND")
	)
	(gr_poly
		(pts
			(arc
				(start 145.59407 -410.030168)
				(mid 145.302478 -410.030168)
				(end 145.59407 -410.030168)
			)
		)
		(stroke
			(width 0)
			(type solid)
		)
		(fill yes)
		(layer "B.Cu")
		(net "GND")
	)
	(gr_poly
		(pts
			(arc
				(start 145.59407 -407.00452)
				(mid 145.302478 -407.00452)
				(end 145.59407 -407.00452)
			)
		)
		(stroke
			(width 0)
			(type solid)
		)
		(fill yes)
		(layer "B.Cu")
		(net "GND")
	)
	(gr_poly
		(pts
			(arc
				(start 146.22907 -403.883876)
				(mid 145.937478 -403.883876)
				(end 146.22907 -403.883876)
			)
		)
		(stroke
			(width 0)
			(type solid)
		)
		(fill yes)
		(layer "B.Cu")
		(net "GND")
	)
	(gr_poly
		(pts
			(arc
				(start 146.22907 -400.858228)
				(mid 145.937478 -400.858228)
				(end 146.22907 -400.858228)
			)
		)
		(stroke
			(width 0)
			(type solid)
		)
		(fill yes)
		(layer "B.Cu")
		(net "GND")
	)
	(gr_poly
		(pts
			(arc
				(start 147.31111 -403.883876)
				(mid 147.019518 -403.883876)
				(end 147.31111 -403.883876)
			)
		)
		(stroke
			(width 0)
			(type solid)
		)
		(fill yes)
		(layer "B.Cu")
		(net "GND")
	)
	(gr_poly
		(pts
			(arc
				(start 147.31111 -400.858228)
				(mid 147.019518 -400.858228)
				(end 147.31111 -400.858228)
			)
		)
		(stroke
			(width 0)
			(type solid)
		)
		(fill yes)
		(layer "B.Cu")
		(net "GND")
	)
	(gr_poly
		(pts
			(arc
				(start 147.57527 -410.030168)
				(mid 147.283678 -410.030168)
				(end 147.57527 -410.030168)
			)
		)
		(stroke
			(width 0)
			(type solid)
		)
		(fill yes)
		(layer "B.Cu")
		(net "GND")
	)
	(gr_poly
		(pts
			(arc
				(start 147.57527 -407.00452)
				(mid 147.283678 -407.00452)
				(end 147.57527 -407.00452)
			)
		)
		(stroke
			(width 0)
			(type solid)
		)
		(fill yes)
		(layer "B.Cu")
		(net "GND")
	)
	(gr_poly
		(pts
			(arc
				(start 148.65731 -410.030168)
				(mid 148.365718 -410.030168)
				(end 148.65731 -410.030168)
			)
		)
		(stroke
			(width 0)
			(type solid)
		)
		(fill yes)
		(layer "B.Cu")
		(net "GND")
	)
	(gr_poly
		(pts
			(arc
				(start 148.65731 -407.00452)
				(mid 148.365718 -407.00452)
				(end 148.65731 -407.00452)
			)
		)
		(stroke
			(width 0)
			(type solid)
		)
		(fill yes)
		(layer "B.Cu")
		(net "GND")
	)
	(gr_poly
		(pts
			(arc
				(start 149.29231 -403.883876)
				(mid 149.000718 -403.883876)
				(end 149.29231 -403.883876)
			)
		)
		(stroke
			(width 0)
			(type solid)
		)
		(fill yes)
		(layer "B.Cu")
		(net "GND")
	)
	(gr_poly
		(pts
			(arc
				(start 149.29231 -400.858228)
				(mid 149.000718 -400.858228)
				(end 149.29231 -400.858228)
			)
		)
		(stroke
			(width 0)
			(type solid)
		)
		(fill yes)
		(layer "B.Cu")
		(net "GND")
	)
	(gr_poly
		(pts
			(arc
				(start 150.37435 -403.883876)
				(mid 150.082758 -403.883876)
				(end 150.37435 -403.883876)
			)
		)
		(stroke
			(width 0)
			(type solid)
		)
		(fill yes)
		(layer "B.Cu")
		(net "GND")
	)
	(gr_poly
		(pts
			(arc
				(start 150.37435 -400.858228)
				(mid 150.082758 -400.858228)
				(end 150.37435 -400.858228)
			)
		)
		(stroke
			(width 0)
			(type solid)
		)
		(fill yes)
		(layer "B.Cu")
		(net "GND")
	)
	(gr_poly
		(pts
			(arc
				(start 150.63851 -410.030168)
				(mid 150.346918 -410.030168)
				(end 150.63851 -410.030168)
			)
		)
		(stroke
			(width 0)
			(type solid)
		)
		(fill yes)
		(layer "B.Cu")
		(net "GND")
	)
	(gr_poly
		(pts
			(arc
				(start 150.63851 -407.00452)
				(mid 150.346918 -407.00452)
				(end 150.63851 -407.00452)
			)
		)
		(stroke
			(width 0)
			(type solid)
		)
		(fill yes)
		(layer "B.Cu")
		(net "GND")
	)
	(gr_poly
		(pts
			(arc
				(start 151.72055 -410.030168)
				(mid 151.428958 -410.030168)
				(end 151.72055 -410.030168)
			)
		)
		(stroke
			(width 0)
			(type solid)
		)
		(fill yes)
		(layer "B.Cu")
		(net "GND")
	)
	(gr_poly
		(pts
			(arc
				(start 151.72055 -407.00452)
				(mid 151.428958 -407.00452)
				(end 151.72055 -407.00452)
			)
		)
		(stroke
			(width 0)
			(type solid)
		)
		(fill yes)
		(layer "B.Cu")
		(net "GND")
	)
	(gr_poly
		(pts
			(arc
				(start 152.35555 -403.883876)
				(mid 152.063958 -403.883876)
				(end 152.35555 -403.883876)
			)
		)
		(stroke
			(width 0)
			(type solid)
		)
		(fill yes)
		(layer "B.Cu")
		(net "GND")
	)
	(gr_poly
		(pts
			(arc
				(start 152.35555 -400.858228)
				(mid 152.063958 -400.858228)
				(end 152.35555 -400.858228)
			)
		)
		(stroke
			(width 0)
			(type solid)
		)
		(fill yes)
		(layer "B.Cu")
		(net "GND")
	)
	(gr_poly
		(pts
			(arc
				(start 153.43759 -403.883876)
				(mid 153.145998 -403.883876)
				(end 153.43759 -403.883876)
			)
		)
		(stroke
			(width 0)
			(type solid)
		)
		(fill yes)
		(layer "B.Cu")
		(net "GND")
	)
	(gr_poly
		(pts
			(arc
				(start 153.43759 -400.858228)
				(mid 153.145998 -400.858228)
				(end 153.43759 -400.858228)
			)
		)
		(stroke
			(width 0)
			(type solid)
		)
		(fill yes)
		(layer "B.Cu")
		(net "GND")
	)
	(gr_poly
		(pts
			(arc
				(start 153.70175 -410.030168)
				(mid 153.410158 -410.030168)
				(end 153.70175 -410.030168)
			)
		)
		(stroke
			(width 0)
			(type solid)
		)
		(fill yes)
		(layer "B.Cu")
		(net "GND")
	)
	(gr_poly
		(pts
			(arc
				(start 153.70175 -407.00452)
				(mid 153.410158 -407.00452)
				(end 153.70175 -407.00452)
			)
		)
		(stroke
			(width 0)
			(type solid)
		)
		(fill yes)
		(layer "B.Cu")
		(net "GND")
	)
	(gr_poly
		(pts
			(arc
				(start 154.78379 -410.030168)
				(mid 154.492198 -410.030168)
				(end 154.78379 -410.030168)
			)
		)
		(stroke
			(width 0)
			(type solid)
		)
		(fill yes)
		(layer "B.Cu")
		(net "GND")
	)
	(gr_poly
		(pts
			(arc
				(start 154.78379 -407.00452)
				(mid 154.492198 -407.00452)
				(end 154.78379 -407.00452)
			)
		)
		(stroke
			(width 0)
			(type solid)
		)
		(fill yes)
		(layer "B.Cu")
		(net "GND")
	)
	(gr_poly
		(pts
			(arc
				(start 155.41879 -403.883876)
				(mid 155.127198 -403.883876)
				(end 155.41879 -403.883876)
			)
		)
		(stroke
			(width 0)
			(type solid)
		)
		(fill yes)
		(layer "B.Cu")
		(net "GND")
	)
	(gr_poly
		(pts
			(arc
				(start 155.41879 -400.858228)
				(mid 155.127198 -400.858228)
				(end 155.41879 -400.858228)
			)
		)
		(stroke
			(width 0)
			(type solid)
		)
		(fill yes)
		(layer "B.Cu")
		(net "GND")
	)
	(gr_poly
		(pts
			(arc
				(start 156.50083 -403.883876)
				(mid 156.209238 -403.883876)
				(end 156.50083 -403.883876)
			)
		)
		(stroke
			(width 0)
			(type solid)
		)
		(fill yes)
		(layer "B.Cu")
		(net "GND")
	)
	(gr_poly
		(pts
			(arc
				(start 156.50083 -400.858228)
				(mid 156.209238 -400.858228)
				(end 156.50083 -400.858228)
			)
		)
		(stroke
			(width 0)
			(type solid)
		)
		(fill yes)
		(layer "B.Cu")
		(net "GND")
	)
	(gr_poly
		(pts
			(arc
				(start 156.76499 -410.030168)
				(mid 156.473398 -410.030168)
				(end 156.76499 -410.030168)
			)
		)
		(stroke
			(width 0)
			(type solid)
		)
		(fill yes)
		(layer "B.Cu")
		(net "GND")
	)
	(gr_poly
		(pts
			(arc
				(start 156.76499 -407.00452)
				(mid 156.473398 -407.00452)
				(end 156.76499 -407.00452)
			)
		)
		(stroke
			(width 0)
			(type solid)
		)
		(fill yes)
		(layer "B.Cu")
		(net "GND")
	)
	(gr_poly
		(pts
			(arc
				(start 157.84703 -410.030168)
				(mid 157.555438 -410.030168)
				(end 157.84703 -410.030168)
			)
		)
		(stroke
			(width 0)
			(type solid)
		)
		(fill yes)
		(layer "B.Cu")
		(net "GND")
	)
	(gr_poly
		(pts
			(arc
				(start 157.84703 -407.00452)
				(mid 157.555438 -407.00452)
				(end 157.84703 -407.00452)
			)
		)
		(stroke
			(width 0)
			(type solid)
		)
		(fill yes)
		(layer "B.Cu")
		(net "GND")
	)
	(gr_poly
		(pts
			(arc
				(start 158.48203 -403.883876)
				(mid 158.190438 -403.883876)
				(end 158.48203 -403.883876)
			)
		)
		(stroke
			(width 0)
			(type solid)
		)
		(fill yes)
		(layer "B.Cu")
		(net "GND")
	)
	(gr_poly
		(pts
			(arc
				(start 158.48203 -400.858228)
				(mid 158.190438 -400.858228)
				(end 158.48203 -400.858228)
			)
		)
		(stroke
			(width 0)
			(type solid)
		)
		(fill yes)
		(layer "B.Cu")
		(net "GND")
	)
	(gr_poly
		(pts
			(arc
				(start 159.56407 -403.883876)
				(mid 159.272478 -403.883876)
				(end 159.56407 -403.883876)
			)
		)
		(stroke
			(width 0)
			(type solid)
		)
		(fill yes)
		(layer "B.Cu")
		(net "GND")
	)
	(gr_poly
		(pts
			(arc
				(start 159.56407 -400.858228)
				(mid 159.272478 -400.858228)
				(end 159.56407 -400.858228)
			)
		)
		(stroke
			(width 0)
			(type solid)
		)
		(fill yes)
		(layer "B.Cu")
		(net "GND")
	)
	(gr_poly
		(pts
			(arc
				(start 159.82823 -410.030168)
				(mid 159.536638 -410.030168)
				(end 159.82823 -410.030168)
			)
		)
		(stroke
			(width 0)
			(type solid)
		)
		(fill yes)
		(layer "B.Cu")
		(net "GND")
	)
	(gr_poly
		(pts
			(arc
				(start 159.82823 -407.00452)
				(mid 159.536638 -407.00452)
				(end 159.82823 -407.00452)
			)
		)
		(stroke
			(width 0)
			(type solid)
		)
		(fill yes)
		(layer "B.Cu")
		(net "GND")
	)
	(gr_poly
		(pts
			(arc
				(start 160.91027 -410.030168)
				(mid 160.618678 -410.030168)
				(end 160.91027 -410.030168)
			)
		)
		(stroke
			(width 0)
			(type solid)
		)
		(fill yes)
		(layer "B.Cu")
		(net "GND")
	)
	(gr_poly
		(pts
			(arc
				(start 160.91027 -407.00452)
				(mid 160.618678 -407.00452)
				(end 160.91027 -407.00452)
			)
		)
		(stroke
			(width 0)
			(type solid)
		)
		(fill yes)
		(layer "B.Cu")
		(net "GND")
	)
	(gr_poly
		(pts
			(arc
				(start 161.54527 -403.883876)
				(mid 161.253678 -403.883876)
				(end 161.54527 -403.883876)
			)
		)
		(stroke
			(width 0)
			(type solid)
		)
		(fill yes)
		(layer "B.Cu")
		(net "GND")
	)
	(gr_poly
		(pts
			(arc
				(start 161.54527 -400.858228)
				(mid 161.253678 -400.858228)
				(end 161.54527 -400.858228)
			)
		)
		(stroke
			(width 0)
			(type solid)
		)
		(fill yes)
		(layer "B.Cu")
		(net "GND")
	)
	(gr_poly
		(pts
			(arc
				(start 162.62731 -403.883876)
				(mid 162.335718 -403.883876)
				(end 162.62731 -403.883876)
			)
		)
		(stroke
			(width 0)
			(type solid)
		)
		(fill yes)
		(layer "B.Cu")
		(net "GND")
	)
	(gr_poly
		(pts
			(arc
				(start 162.62731 -400.858228)
				(mid 162.335718 -400.858228)
				(end 162.62731 -400.858228)
			)
		)
		(stroke
			(width 0)
			(type solid)
		)
		(fill yes)
		(layer "B.Cu")
		(net "GND")
	)
	(gr_poly
		(pts
			(arc
				(start 162.89147 -410.030168)
				(mid 162.599878 -410.030168)
				(end 162.89147 -410.030168)
			)
		)
		(stroke
			(width 0)
			(type solid)
		)
		(fill yes)
		(layer "B.Cu")
		(net "GND")
	)
	(gr_poly
		(pts
			(arc
				(start 162.89147 -407.00452)
				(mid 162.599878 -407.00452)
				(end 162.89147 -407.00452)
			)
		)
		(stroke
			(width 0)
			(type solid)
		)
		(fill yes)
		(layer "B.Cu")
		(net "GND")
	)
	(gr_poly
		(pts
			(arc
				(start 163.97351 -410.030168)
				(mid 163.681918 -410.030168)
				(end 163.97351 -410.030168)
			)
		)
		(stroke
			(width 0)
			(type solid)
		)
		(fill yes)
		(layer "B.Cu")
		(net "GND")
	)
	(gr_poly
		(pts
			(arc
				(start 163.97351 -407.00452)
				(mid 163.681918 -407.00452)
				(end 163.97351 -407.00452)
			)
		)
		(stroke
			(width 0)
			(type solid)
		)
		(fill yes)
		(layer "B.Cu")
		(net "GND")
	)
	(gr_poly
		(pts
			(arc
				(start 164.60851 -403.883876)
				(mid 164.316918 -403.883876)
				(end 164.60851 -403.883876)
			)
		)
		(stroke
			(width 0)
			(type solid)
		)
		(fill yes)
		(layer "B.Cu")
		(net "GND")
	)
	(gr_poly
		(pts
			(arc
				(start 164.60851 -400.834352)
				(mid 164.316918 -400.834352)
				(end 164.60851 -400.834352)
			)
		)
		(stroke
			(width 0)
			(type solid)
		)
		(fill yes)
		(layer "B.Cu")
		(net "GND")
	)
	(gr_poly
		(pts
			(arc
				(start 165.69055 -403.883876)
				(mid 165.398958 -403.883876)
				(end 165.69055 -403.883876)
			)
		)
		(stroke
			(width 0)
			(type solid)
		)
		(fill yes)
		(layer "B.Cu")
		(net "GND")
	)
	(gr_poly
		(pts
			(arc
				(start 165.69055 -400.858228)
				(mid 165.398958 -400.858228)
				(end 165.69055 -400.858228)
			)
		)
		(stroke
			(width 0)
			(type solid)
		)
		(fill yes)
		(layer "B.Cu")
		(net "GND")
	)
	(gr_poly
		(pts
			(arc
				(start 165.95471 -410.030168)
				(mid 165.663118 -410.030168)
				(end 165.95471 -410.030168)
			)
		)
		(stroke
			(width 0)
			(type solid)
		)
		(fill yes)
		(layer "B.Cu")
		(net "GND")
	)
	(gr_poly
		(pts
			(arc
				(start 165.95471 -406.980644)
				(mid 165.663118 -406.980644)
				(end 165.95471 -406.980644)
			)
		)
		(stroke
			(width 0)
			(type solid)
		)
		(fill yes)
		(layer "B.Cu")
		(net "GND")
	)
	(gr_poly
		(pts
			(arc
				(start 167.03675 -410.030168)
				(mid 166.745158 -410.030168)
				(end 167.03675 -410.030168)
			)
		)
		(stroke
			(width 0)
			(type solid)
		)
		(fill yes)
		(layer "B.Cu")
		(net "GND")
	)
	(gr_poly
		(pts
			(arc
				(start 167.03675 -407.00452)
				(mid 166.745158 -407.00452)
				(end 167.03675 -407.00452)
			)
		)
		(stroke
			(width 0)
			(type solid)
		)
		(fill yes)
		(layer "B.Cu")
		(net "GND")
	)
	(gr_poly
		(pts
			(arc
				(start 167.67175 -403.883876)
				(mid 167.380158 -403.883876)
				(end 167.67175 -403.883876)
			)
		)
		(stroke
			(width 0)
			(type solid)
		)
		(fill yes)
		(layer "B.Cu")
		(net "GND")
	)
	(gr_poly
		(pts
			(arc
				(start 167.67175 -400.858228)
				(mid 167.380158 -400.858228)
				(end 167.67175 -400.858228)
			)
		)
		(stroke
			(width 0)
			(type solid)
		)
		(fill yes)
		(layer "B.Cu")
		(net "GND")
	)
	(gr_poly
		(pts
			(arc
				(start 169.01795 -410.030168)
				(mid 168.726358 -410.030168)
				(end 169.01795 -410.030168)
			)
		)
		(stroke
			(width 0)
			(type solid)
		)
		(fill yes)
		(layer "B.Cu")
		(net "GND")
	)
	(gr_poly
		(pts
			(arc
				(start 169.01795 -407.00452)
				(mid 168.726358 -407.00452)
				(end 169.01795 -407.00452)
			)
		)
		(stroke
			(width 0)
			(type solid)
		)
		(fill yes)
		(layer "B.Cu")
		(net "GND")
	)
	(gr_poly
		(pts
			(xy 237.7821 -126.566168) (xy 237.7821 -125.270768) (xy 237.776512 -125.26518) (xy 237.776512 -125.127004)
			(xy 238.336836 -124.56668) (xy 238.336836 -124.006864) (xy 238.236506 -123.906534) (xy 237.51159 -123.906534)
			(xy 237.30966 -124.108464) (xy 237.30966 -125.159008) (xy 237.16615 -125.302518)
			(arc
				(start 237.16234 -125.311916)
				(mid 237.142302 -125.354492)
				(end 237.11789 -125.39472)
			)
			(xy 237.109 -125.407674) (xy 237.109 -125.527308) (xy 237.0582 -125.578108) (xy 236.845856 -125.578108)
			(arc
				(start 236.840776 -125.579124)
				(mid 236.8141 -125.583884)
				(end 236.787182 -125.586998)
			)
			(xy 236.768386 -125.588522) (xy 236.701584 -125.655324) (xy 236.701584 -126.194312) (xy 237.1852 -126.677928)
			(xy 237.67034 -126.677928)
		)
		(stroke
			(width 0)
			(type solid)
		)
		(fill yes)
		(layer "B.Cu")
		(net "FM_DB2000_VSBEN")
	)
	(gr_poly
		(pts
			(arc
				(start 303.567084 -403.883876)
				(mid 303.275492 -403.883876)
				(end 303.567084 -403.883876)
			)
		)
		(stroke
			(width 0)
			(type solid)
		)
		(fill yes)
		(layer "B.Cu")
		(net "GND")
	)
	(gr_poly
		(pts
			(arc
				(start 303.567084 -400.858228)
				(mid 303.275492 -400.858228)
				(end 303.567084 -400.858228)
			)
		)
		(stroke
			(width 0)
			(type solid)
		)
		(fill yes)
		(layer "B.Cu")
		(net "GND")
	)
	(gr_poly
		(pts
			(arc
				(start 304.913284 -410.030168)
				(mid 304.621692 -410.030168)
				(end 304.913284 -410.030168)
			)
		)
		(stroke
			(width 0)
			(type solid)
		)
		(fill yes)
		(layer "B.Cu")
		(net "GND")
	)
	(gr_poly
		(pts
			(arc
				(start 304.913284 -407.00452)
				(mid 304.621692 -407.00452)
				(end 304.913284 -407.00452)
			)
		)
		(stroke
			(width 0)
			(type solid)
		)
		(fill yes)
		(layer "B.Cu")
		(net "GND")
	)
	(gr_poly
		(pts
			(arc
				(start 305.548284 -403.883876)
				(mid 305.256692 -403.883876)
				(end 305.548284 -403.883876)
			)
		)
		(stroke
			(width 0)
			(type solid)
		)
		(fill yes)
		(layer "B.Cu")
		(net "GND")
	)
	(gr_poly
		(pts
			(arc
				(start 305.548284 -400.858228)
				(mid 305.256692 -400.858228)
				(end 305.548284 -400.858228)
			)
		)
		(stroke
			(width 0)
			(type solid)
		)
		(fill yes)
		(layer "B.Cu")
		(net "GND")
	)
	(gr_poly
		(pts
			(arc
				(start 306.630324 -403.883876)
				(mid 306.338732 -403.883876)
				(end 306.630324 -403.883876)
			)
		)
		(stroke
			(width 0)
			(type solid)
		)
		(fill yes)
		(layer "B.Cu")
		(net "GND")
	)
	(gr_poly
		(pts
			(arc
				(start 306.630324 -400.858228)
				(mid 306.338732 -400.858228)
				(end 306.630324 -400.858228)
			)
		)
		(stroke
			(width 0)
			(type solid)
		)
		(fill yes)
		(layer "B.Cu")
		(net "GND")
	)
	(gr_poly
		(pts
			(arc
				(start 306.894484 -410.030168)
				(mid 306.602892 -410.030168)
				(end 306.894484 -410.030168)
			)
		)
		(stroke
			(width 0)
			(type solid)
		)
		(fill yes)
		(layer "B.Cu")
		(net "GND")
	)
	(gr_poly
		(pts
			(arc
				(start 306.894484 -407.00452)
				(mid 306.602892 -407.00452)
				(end 306.894484 -407.00452)
			)
		)
		(stroke
			(width 0)
			(type solid)
		)
		(fill yes)
		(layer "B.Cu")
		(net "GND")
	)
	(gr_poly
		(pts
			(arc
				(start 307.976524 -410.030168)
				(mid 307.684932 -410.030168)
				(end 307.976524 -410.030168)
			)
		)
		(stroke
			(width 0)
			(type solid)
		)
		(fill yes)
		(layer "B.Cu")
		(net "GND")
	)
	(gr_poly
		(pts
			(arc
				(start 307.976524 -407.00452)
				(mid 307.684932 -407.00452)
				(end 307.976524 -407.00452)
			)
		)
		(stroke
			(width 0)
			(type solid)
		)
		(fill yes)
		(layer "B.Cu")
		(net "GND")
	)
	(gr_poly
		(pts
			(arc
				(start 308.611524 -403.883876)
				(mid 308.319932 -403.883876)
				(end 308.611524 -403.883876)
			)
		)
		(stroke
			(width 0)
			(type solid)
		)
		(fill yes)
		(layer "B.Cu")
		(net "GND")
	)
	(gr_poly
		(pts
			(arc
				(start 308.611524 -400.858228)
				(mid 308.319932 -400.858228)
				(end 308.611524 -400.858228)
			)
		)
		(stroke
			(width 0)
			(type solid)
		)
		(fill yes)
		(layer "B.Cu")
		(net "GND")
	)
	(gr_poly
		(pts
			(arc
				(start 309.693564 -403.883876)
				(mid 309.401972 -403.883876)
				(end 309.693564 -403.883876)
			)
		)
		(stroke
			(width 0)
			(type solid)
		)
		(fill yes)
		(layer "B.Cu")
		(net "GND")
	)
	(gr_poly
		(pts
			(arc
				(start 309.693564 -400.858228)
				(mid 309.401972 -400.858228)
				(end 309.693564 -400.858228)
			)
		)
		(stroke
			(width 0)
			(type solid)
		)
		(fill yes)
		(layer "B.Cu")
		(net "GND")
	)
	(gr_poly
		(pts
			(arc
				(start 309.957724 -410.030168)
				(mid 309.666132 -410.030168)
				(end 309.957724 -410.030168)
			)
		)
		(stroke
			(width 0)
			(type solid)
		)
		(fill yes)
		(layer "B.Cu")
		(net "GND")
	)
	(gr_poly
		(pts
			(arc
				(start 309.957724 -407.00452)
				(mid 309.666132 -407.00452)
				(end 309.957724 -407.00452)
			)
		)
		(stroke
			(width 0)
			(type solid)
		)
		(fill yes)
		(layer "B.Cu")
		(net "GND")
	)
	(gr_poly
		(pts
			(arc
				(start 311.039764 -410.030168)
				(mid 310.748172 -410.030168)
				(end 311.039764 -410.030168)
			)
		)
		(stroke
			(width 0)
			(type solid)
		)
		(fill yes)
		(layer "B.Cu")
		(net "GND")
	)
	(gr_poly
		(pts
			(arc
				(start 311.039764 -407.00452)
				(mid 310.748172 -407.00452)
				(end 311.039764 -407.00452)
			)
		)
		(stroke
			(width 0)
			(type solid)
		)
		(fill yes)
		(layer "B.Cu")
		(net "GND")
	)
	(gr_poly
		(pts
			(arc
				(start 311.674764 -403.883876)
				(mid 311.383172 -403.883876)
				(end 311.674764 -403.883876)
			)
		)
		(stroke
			(width 0)
			(type solid)
		)
		(fill yes)
		(layer "B.Cu")
		(net "GND")
	)
	(gr_poly
		(pts
			(arc
				(start 311.674764 -400.858228)
				(mid 311.383172 -400.858228)
				(end 311.674764 -400.858228)
			)
		)
		(stroke
			(width 0)
			(type solid)
		)
		(fill yes)
		(layer "B.Cu")
		(net "GND")
	)
	(gr_poly
		(pts
			(arc
				(start 312.756804 -403.883876)
				(mid 312.465212 -403.883876)
				(end 312.756804 -403.883876)
			)
		)
		(stroke
			(width 0)
			(type solid)
		)
		(fill yes)
		(layer "B.Cu")
		(net "GND")
	)
	(gr_poly
		(pts
			(arc
				(start 312.756804 -400.858228)
				(mid 312.465212 -400.858228)
				(end 312.756804 -400.858228)
			)
		)
		(stroke
			(width 0)
			(type solid)
		)
		(fill yes)
		(layer "B.Cu")
		(net "GND")
	)
	(gr_poly
		(pts
			(arc
				(start 313.020964 -410.030168)
				(mid 312.729372 -410.030168)
				(end 313.020964 -410.030168)
			)
		)
		(stroke
			(width 0)
			(type solid)
		)
		(fill yes)
		(layer "B.Cu")
		(net "GND")
	)
	(gr_poly
		(pts
			(arc
				(start 313.020964 -407.00452)
				(mid 312.729372 -407.00452)
				(end 313.020964 -407.00452)
			)
		)
		(stroke
			(width 0)
			(type solid)
		)
		(fill yes)
		(layer "B.Cu")
		(net "GND")
	)
	(gr_poly
		(pts
			(arc
				(start 314.103004 -410.030168)
				(mid 313.811412 -410.030168)
				(end 314.103004 -410.030168)
			)
		)
		(stroke
			(width 0)
			(type solid)
		)
		(fill yes)
		(layer "B.Cu")
		(net "GND")
	)
	(gr_poly
		(pts
			(arc
				(start 314.103004 -407.00452)
				(mid 313.811412 -407.00452)
				(end 314.103004 -407.00452)
			)
		)
		(stroke
			(width 0)
			(type solid)
		)
		(fill yes)
		(layer "B.Cu")
		(net "GND")
	)
	(gr_poly
		(pts
			(arc
				(start 314.738004 -403.883876)
				(mid 314.446412 -403.883876)
				(end 314.738004 -403.883876)
			)
		)
		(stroke
			(width 0)
			(type solid)
		)
		(fill yes)
		(layer "B.Cu")
		(net "GND")
	)
	(gr_poly
		(pts
			(arc
				(start 314.738004 -400.858228)
				(mid 314.446412 -400.858228)
				(end 314.738004 -400.858228)
			)
		)
		(stroke
			(width 0)
			(type solid)
		)
		(fill yes)
		(layer "B.Cu")
		(net "GND")
	)
	(gr_poly
		(pts
			(arc
				(start 315.820044 -403.883876)
				(mid 315.528452 -403.883876)
				(end 315.820044 -403.883876)
			)
		)
		(stroke
			(width 0)
			(type solid)
		)
		(fill yes)
		(layer "B.Cu")
		(net "GND")
	)
	(gr_poly
		(pts
			(arc
				(start 315.820044 -400.858228)
				(mid 315.528452 -400.858228)
				(end 315.820044 -400.858228)
			)
		)
		(stroke
			(width 0)
			(type solid)
		)
		(fill yes)
		(layer "B.Cu")
		(net "GND")
	)
	(gr_poly
		(pts
			(arc
				(start 316.084204 -410.030168)
				(mid 315.792612 -410.030168)
				(end 316.084204 -410.030168)
			)
		)
		(stroke
			(width 0)
			(type solid)
		)
		(fill yes)
		(layer "B.Cu")
		(net "GND")
	)
	(gr_poly
		(pts
			(arc
				(start 316.084204 -407.00452)
				(mid 315.792612 -407.00452)
				(end 316.084204 -407.00452)
			)
		)
		(stroke
			(width 0)
			(type solid)
		)
		(fill yes)
		(layer "B.Cu")
		(net "GND")
	)
	(gr_poly
		(pts
			(arc
				(start 317.166244 -410.030168)
				(mid 316.874652 -410.030168)
				(end 317.166244 -410.030168)
			)
		)
		(stroke
			(width 0)
			(type solid)
		)
		(fill yes)
		(layer "B.Cu")
		(net "GND")
	)
	(gr_poly
		(pts
			(arc
				(start 317.166244 -407.00452)
				(mid 316.874652 -407.00452)
				(end 317.166244 -407.00452)
			)
		)
		(stroke
			(width 0)
			(type solid)
		)
		(fill yes)
		(layer "B.Cu")
		(net "GND")
	)
	(gr_poly
		(pts
			(arc
				(start 317.801244 -403.883876)
				(mid 317.509652 -403.883876)
				(end 317.801244 -403.883876)
			)
		)
		(stroke
			(width 0)
			(type solid)
		)
		(fill yes)
		(layer "B.Cu")
		(net "GND")
	)
	(gr_poly
		(pts
			(arc
				(start 317.801244 -400.858228)
				(mid 317.509652 -400.858228)
				(end 317.801244 -400.858228)
			)
		)
		(stroke
			(width 0)
			(type solid)
		)
		(fill yes)
		(layer "B.Cu")
		(net "GND")
	)
	(gr_poly
		(pts
			(arc
				(start 318.883284 -403.883876)
				(mid 318.591692 -403.883876)
				(end 318.883284 -403.883876)
			)
		)
		(stroke
			(width 0)
			(type solid)
		)
		(fill yes)
		(layer "B.Cu")
		(net "GND")
	)
	(gr_poly
		(pts
			(arc
				(start 318.883284 -400.858228)
				(mid 318.591692 -400.858228)
				(end 318.883284 -400.858228)
			)
		)
		(stroke
			(width 0)
			(type solid)
		)
		(fill yes)
		(layer "B.Cu")
		(net "GND")
	)
	(gr_poly
		(pts
			(arc
				(start 319.147444 -410.030168)
				(mid 318.855852 -410.030168)
				(end 319.147444 -410.030168)
			)
		)
		(stroke
			(width 0)
			(type solid)
		)
		(fill yes)
		(layer "B.Cu")
		(net "GND")
	)
	(gr_poly
		(pts
			(arc
				(start 319.147444 -407.00452)
				(mid 318.855852 -407.00452)
				(end 319.147444 -407.00452)
			)
		)
		(stroke
			(width 0)
			(type solid)
		)
		(fill yes)
		(layer "B.Cu")
		(net "GND")
	)
	(gr_poly
		(pts
			(arc
				(start 320.229484 -410.030168)
				(mid 319.937892 -410.030168)
				(end 320.229484 -410.030168)
			)
		)
		(stroke
			(width 0)
			(type solid)
		)
		(fill yes)
		(layer "B.Cu")
		(net "GND")
	)
	(gr_poly
		(pts
			(arc
				(start 320.229484 -407.00452)
				(mid 319.937892 -407.00452)
				(end 320.229484 -407.00452)
			)
		)
		(stroke
			(width 0)
			(type solid)
		)
		(fill yes)
		(layer "B.Cu")
		(net "GND")
	)
	(gr_poly
		(pts
			(arc
				(start 320.864484 -403.883876)
				(mid 320.572892 -403.883876)
				(end 320.864484 -403.883876)
			)
		)
		(stroke
			(width 0)
			(type solid)
		)
		(fill yes)
		(layer "B.Cu")
		(net "GND")
	)
	(gr_poly
		(pts
			(arc
				(start 320.864484 -400.858228)
				(mid 320.572892 -400.858228)
				(end 320.864484 -400.858228)
			)
		)
		(stroke
			(width 0)
			(type solid)
		)
		(fill yes)
		(layer "B.Cu")
		(net "GND")
	)
	(gr_poly
		(pts
			(arc
				(start 321.946524 -403.883876)
				(mid 321.654932 -403.883876)
				(end 321.946524 -403.883876)
			)
		)
		(stroke
			(width 0)
			(type solid)
		)
		(fill yes)
		(layer "B.Cu")
		(net "GND")
	)
	(gr_poly
		(pts
			(arc
				(start 321.946524 -400.858228)
				(mid 321.654932 -400.858228)
				(end 321.946524 -400.858228)
			)
		)
		(stroke
			(width 0)
			(type solid)
		)
		(fill yes)
		(layer "B.Cu")
		(net "GND")
	)
	(gr_poly
		(pts
			(arc
				(start 322.210684 -410.030168)
				(mid 321.919092 -410.030168)
				(end 322.210684 -410.030168)
			)
		)
		(stroke
			(width 0)
			(type solid)
		)
		(fill yes)
		(layer "B.Cu")
		(net "GND")
	)
	(gr_poly
		(pts
			(arc
				(start 322.210684 -407.00452)
				(mid 321.919092 -407.00452)
				(end 322.210684 -407.00452)
			)
		)
		(stroke
			(width 0)
			(type solid)
		)
		(fill yes)
		(layer "B.Cu")
		(net "GND")
	)
	(gr_poly
		(pts
			(arc
				(start 323.292724 -410.030168)
				(mid 323.001132 -410.030168)
				(end 323.292724 -410.030168)
			)
		)
		(stroke
			(width 0)
			(type solid)
		)
		(fill yes)
		(layer "B.Cu")
		(net "GND")
	)
	(gr_poly
		(pts
			(arc
				(start 323.292724 -407.00452)
				(mid 323.001132 -407.00452)
				(end 323.292724 -407.00452)
			)
		)
		(stroke
			(width 0)
			(type solid)
		)
		(fill yes)
		(layer "B.Cu")
		(net "GND")
	)
	(gr_poly
		(pts
			(arc
				(start 323.927724 -403.883876)
				(mid 323.636132 -403.883876)
				(end 323.927724 -403.883876)
			)
		)
		(stroke
			(width 0)
			(type solid)
		)
		(fill yes)
		(layer "B.Cu")
		(net "GND")
	)
	(gr_poly
		(pts
			(arc
				(start 323.927724 -400.858228)
				(mid 323.636132 -400.858228)
				(end 323.927724 -400.858228)
			)
		)
		(stroke
			(width 0)
			(type solid)
		)
		(fill yes)
		(layer "B.Cu")
		(net "GND")
	)
	(gr_poly
		(pts
			(arc
				(start 325.009764 -403.883876)
				(mid 324.718172 -403.883876)
				(end 325.009764 -403.883876)
			)
		)
		(stroke
			(width 0)
			(type solid)
		)
		(fill yes)
		(layer "B.Cu")
		(net "GND")
	)
	(gr_poly
		(pts
			(arc
				(start 325.009764 -400.858228)
				(mid 324.718172 -400.858228)
				(end 325.009764 -400.858228)
			)
		)
		(stroke
			(width 0)
			(type solid)
		)
		(fill yes)
		(layer "B.Cu")
		(net "GND")
	)
	(gr_poly
		(pts
			(arc
				(start 325.273924 -410.030168)
				(mid 324.982332 -410.030168)
				(end 325.273924 -410.030168)
			)
		)
		(stroke
			(width 0)
			(type solid)
		)
		(fill yes)
		(layer "B.Cu")
		(net "GND")
	)
	(gr_poly
		(pts
			(arc
				(start 325.273924 -407.00452)
				(mid 324.982332 -407.00452)
				(end 325.273924 -407.00452)
			)
		)
		(stroke
			(width 0)
			(type solid)
		)
		(fill yes)
		(layer "B.Cu")
		(net "GND")
	)
	(gr_poly
		(pts
			(arc
				(start 326.355964 -410.030168)
				(mid 326.064372 -410.030168)
				(end 326.355964 -410.030168)
			)
		)
		(stroke
			(width 0)
			(type solid)
		)
		(fill yes)
		(layer "B.Cu")
		(net "GND")
	)
	(gr_poly
		(pts
			(arc
				(start 326.355964 -407.00452)
				(mid 326.064372 -407.00452)
				(end 326.355964 -407.00452)
			)
		)
		(stroke
			(width 0)
			(type solid)
		)
		(fill yes)
		(layer "B.Cu")
		(net "GND")
	)
	(gr_poly
		(pts
			(arc
				(start 326.990964 -403.883876)
				(mid 326.699372 -403.883876)
				(end 326.990964 -403.883876)
			)
		)
		(stroke
			(width 0)
			(type solid)
		)
		(fill yes)
		(layer "B.Cu")
		(net "GND")
	)
	(gr_poly
		(pts
			(arc
				(start 326.990964 -400.858228)
				(mid 326.699372 -400.858228)
				(end 326.990964 -400.858228)
			)
		)
		(stroke
			(width 0)
			(type solid)
		)
		(fill yes)
		(layer "B.Cu")
		(net "GND")
	)
	(gr_poly
		(pts
			(arc
				(start 328.073004 -403.883876)
				(mid 327.781412 -403.883876)
				(end 328.073004 -403.883876)
			)
		)
		(stroke
			(width 0)
			(type solid)
		)
		(fill yes)
		(layer "B.Cu")
		(net "GND")
	)
	(gr_poly
		(pts
			(arc
				(start 328.073004 -400.858228)
				(mid 327.781412 -400.858228)
				(end 328.073004 -400.858228)
			)
		)
		(stroke
			(width 0)
			(type solid)
		)
		(fill yes)
		(layer "B.Cu")
		(net "GND")
	)
	(gr_poly
		(pts
			(arc
				(start 328.337164 -410.030168)
				(mid 328.045572 -410.030168)
				(end 328.337164 -410.030168)
			)
		)
		(stroke
			(width 0)
			(type solid)
		)
		(fill yes)
		(layer "B.Cu")
		(net "GND")
	)
	(gr_poly
		(pts
			(arc
				(start 328.337164 -407.00452)
				(mid 328.045572 -407.00452)
				(end 328.337164 -407.00452)
			)
		)
		(stroke
			(width 0)
			(type solid)
		)
		(fill yes)
		(layer "B.Cu")
		(net "GND")
	)
	(gr_poly
		(pts
			(arc
				(start 329.419204 -410.030168)
				(mid 329.127612 -410.030168)
				(end 329.419204 -410.030168)
			)
		)
		(stroke
			(width 0)
			(type solid)
		)
		(fill yes)
		(layer "B.Cu")
		(net "GND")
	)
	(gr_poly
		(pts
			(arc
				(start 329.419204 -407.00452)
				(mid 329.127612 -407.00452)
				(end 329.419204 -407.00452)
			)
		)
		(stroke
			(width 0)
			(type solid)
		)
		(fill yes)
		(layer "B.Cu")
		(net "GND")
	)
	(gr_poly
		(pts
			(arc
				(start 330.054204 -403.883876)
				(mid 329.762612 -403.883876)
				(end 330.054204 -403.883876)
			)
		)
		(stroke
			(width 0)
			(type solid)
		)
		(fill yes)
		(layer "B.Cu")
		(net "GND")
	)
	(gr_poly
		(pts
			(arc
				(start 330.054204 -400.858228)
				(mid 329.762612 -400.858228)
				(end 330.054204 -400.858228)
			)
		)
		(stroke
			(width 0)
			(type solid)
		)
		(fill yes)
		(layer "B.Cu")
		(net "GND")
	)
	(gr_poly
		(pts
			(arc
				(start 331.136244 -403.883876)
				(mid 330.844652 -403.883876)
				(end 331.136244 -403.883876)
			)
		)
		(stroke
			(width 0)
			(type solid)
		)
		(fill yes)
		(layer "B.Cu")
		(net "GND")
	)
	(gr_poly
		(pts
			(arc
				(start 331.136244 -400.858228)
				(mid 330.844652 -400.858228)
				(end 331.136244 -400.858228)
			)
		)
		(stroke
			(width 0)
			(type solid)
		)
		(fill yes)
		(layer "B.Cu")
		(net "GND")
	)
	(gr_poly
		(pts
			(arc
				(start 331.400404 -410.030168)
				(mid 331.108812 -410.030168)
				(end 331.400404 -410.030168)
			)
		)
		(stroke
			(width 0)
			(type solid)
		)
		(fill yes)
		(layer "B.Cu")
		(net "GND")
	)
	(gr_poly
		(pts
			(arc
				(start 331.400404 -407.00452)
				(mid 331.108812 -407.00452)
				(end 331.400404 -407.00452)
			)
		)
		(stroke
			(width 0)
			(type solid)
		)
		(fill yes)
		(layer "B.Cu")
		(net "GND")
	)
	(gr_poly
		(pts
			(arc
				(start 332.482444 -410.030168)
				(mid 332.190852 -410.030168)
				(end 332.482444 -410.030168)
			)
		)
		(stroke
			(width 0)
			(type solid)
		)
		(fill yes)
		(layer "B.Cu")
		(net "GND")
	)
	(gr_poly
		(pts
			(arc
				(start 332.482444 -407.00452)
				(mid 332.190852 -407.00452)
				(end 332.482444 -407.00452)
			)
		)
		(stroke
			(width 0)
			(type solid)
		)
		(fill yes)
		(layer "B.Cu")
		(net "GND")
	)
	(gr_poly
		(pts
			(arc
				(start 333.117444 -403.883876)
				(mid 332.825852 -403.883876)
				(end 333.117444 -403.883876)
			)
		)
		(stroke
			(width 0)
			(type solid)
		)
		(fill yes)
		(layer "B.Cu")
		(net "GND")
	)
	(gr_poly
		(pts
			(arc
				(start 333.117444 -400.858228)
				(mid 332.825852 -400.858228)
				(end 333.117444 -400.858228)
			)
		)
		(stroke
			(width 0)
			(type solid)
		)
		(fill yes)
		(layer "B.Cu")
		(net "GND")
	)
	(gr_poly
		(pts
			(arc
				(start 334.199484 -403.883876)
				(mid 333.907892 -403.883876)
				(end 334.199484 -403.883876)
			)
		)
		(stroke
			(width 0)
			(type solid)
		)
		(fill yes)
		(layer "B.Cu")
		(net "GND")
	)
	(gr_poly
		(pts
			(arc
				(start 334.199484 -400.858228)
				(mid 333.907892 -400.858228)
				(end 334.199484 -400.858228)
			)
		)
		(stroke
			(width 0)
			(type solid)
		)
		(fill yes)
		(layer "B.Cu")
		(net "GND")
	)
	(gr_poly
		(pts
			(arc
				(start 334.463644 -410.030168)
				(mid 334.172052 -410.030168)
				(end 334.463644 -410.030168)
			)
		)
		(stroke
			(width 0)
			(type solid)
		)
		(fill yes)
		(layer "B.Cu")
		(net "GND")
	)
	(gr_poly
		(pts
			(arc
				(start 334.463644 -407.00452)
				(mid 334.172052 -407.00452)
				(end 334.463644 -407.00452)
			)
		)
		(stroke
			(width 0)
			(type solid)
		)
		(fill yes)
		(layer "B.Cu")
		(net "GND")
	)
	(gr_poly
		(pts
			(arc
				(start 335.545684 -410.030168)
				(mid 335.254092 -410.030168)
				(end 335.545684 -410.030168)
			)
		)
		(stroke
			(width 0)
			(type solid)
		)
		(fill yes)
		(layer "B.Cu")
		(net "GND")
	)
	(gr_poly
		(pts
			(arc
				(start 335.545684 -407.00452)
				(mid 335.254092 -407.00452)
				(end 335.545684 -407.00452)
			)
		)
		(stroke
			(width 0)
			(type solid)
		)
		(fill yes)
		(layer "B.Cu")
		(net "GND")
	)
	(gr_poly
		(pts
			(arc
				(start 336.180684 -403.883876)
				(mid 335.889092 -403.883876)
				(end 336.180684 -403.883876)
			)
		)
		(stroke
			(width 0)
			(type solid)
		)
		(fill yes)
		(layer "B.Cu")
		(net "GND")
	)
	(gr_poly
		(pts
			(arc
				(start 336.180684 -400.858228)
				(mid 335.889092 -400.858228)
				(end 336.180684 -400.858228)
			)
		)
		(stroke
			(width 0)
			(type solid)
		)
		(fill yes)
		(layer "B.Cu")
		(net "GND")
	)
	(gr_poly
		(pts
			(arc
				(start 337.262724 -403.883876)
				(mid 336.971132 -403.883876)
				(end 337.262724 -403.883876)
			)
		)
		(stroke
			(width 0)
			(type solid)
		)
		(fill yes)
		(layer "B.Cu")
		(net "GND")
	)
	(gr_poly
		(pts
			(arc
				(start 337.262724 -400.858228)
				(mid 336.971132 -400.858228)
				(end 337.262724 -400.858228)
			)
		)
		(stroke
			(width 0)
			(type solid)
		)
		(fill yes)
		(layer "B.Cu")
		(net "GND")
	)
	(gr_poly
		(pts
			(arc
				(start 337.526884 -410.030168)
				(mid 337.235292 -410.030168)
				(end 337.526884 -410.030168)
			)
		)
		(stroke
			(width 0)
			(type solid)
		)
		(fill yes)
		(layer "B.Cu")
		(net "GND")
	)
	(gr_poly
		(pts
			(arc
				(start 337.526884 -407.00452)
				(mid 337.235292 -407.00452)
				(end 337.526884 -407.00452)
			)
		)
		(stroke
			(width 0)
			(type solid)
		)
		(fill yes)
		(layer "B.Cu")
		(net "GND")
	)
	(gr_poly
		(pts
			(arc
				(start 338.608924 -410.030168)
				(mid 338.317332 -410.030168)
				(end 338.608924 -410.030168)
			)
		)
		(stroke
			(width 0)
			(type solid)
		)
		(fill yes)
		(layer "B.Cu")
		(net "GND")
	)
	(gr_poly
		(pts
			(arc
				(start 338.608924 -407.00452)
				(mid 338.317332 -407.00452)
				(end 338.608924 -407.00452)
			)
		)
		(stroke
			(width 0)
			(type solid)
		)
		(fill yes)
		(layer "B.Cu")
		(net "GND")
	)
	(gr_poly
		(pts
			(arc
				(start 339.243924 -403.883876)
				(mid 338.952332 -403.883876)
				(end 339.243924 -403.883876)
			)
		)
		(stroke
			(width 0)
			(type solid)
		)
		(fill yes)
		(layer "B.Cu")
		(net "GND")
	)
	(gr_poly
		(pts
			(arc
				(start 339.243924 -400.858228)
				(mid 338.952332 -400.858228)
				(end 339.243924 -400.858228)
			)
		)
		(stroke
			(width 0)
			(type solid)
		)
		(fill yes)
		(layer "B.Cu")
		(net "GND")
	)
	(gr_poly
		(pts
			(arc
				(start 340.325964 -403.883876)
				(mid 340.034372 -403.883876)
				(end 340.325964 -403.883876)
			)
		)
		(stroke
			(width 0)
			(type solid)
		)
		(fill yes)
		(layer "B.Cu")
		(net "GND")
	)
	(gr_poly
		(pts
			(arc
				(start 340.325964 -400.858228)
				(mid 340.034372 -400.858228)
				(end 340.325964 -400.858228)
			)
		)
		(stroke
			(width 0)
			(type solid)
		)
		(fill yes)
		(layer "B.Cu")
		(net "GND")
	)
	(gr_poly
		(pts
			(arc
				(start 340.590124 -410.030168)
				(mid 340.298532 -410.030168)
				(end 340.590124 -410.030168)
			)
		)
		(stroke
			(width 0)
			(type solid)
		)
		(fill yes)
		(layer "B.Cu")
		(net "GND")
	)
	(gr_poly
		(pts
			(arc
				(start 340.590124 -407.00452)
				(mid 340.298532 -407.00452)
				(end 340.590124 -407.00452)
			)
		)
		(stroke
			(width 0)
			(type solid)
		)
		(fill yes)
		(layer "B.Cu")
		(net "GND")
	)
	(gr_poly
		(pts
			(arc
				(start 341.672164 -410.030168)
				(mid 341.380572 -410.030168)
				(end 341.672164 -410.030168)
			)
		)
		(stroke
			(width 0)
			(type solid)
		)
		(fill yes)
		(layer "B.Cu")
		(net "GND")
	)
	(gr_poly
		(pts
			(arc
				(start 341.672164 -407.00452)
				(mid 341.380572 -407.00452)
				(end 341.672164 -407.00452)
			)
		)
		(stroke
			(width 0)
			(type solid)
		)
		(fill yes)
		(layer "B.Cu")
		(net "GND")
	)
	(gr_poly
		(pts
			(arc
				(start 342.307164 -403.883876)
				(mid 342.015572 -403.883876)
				(end 342.307164 -403.883876)
			)
		)
		(stroke
			(width 0)
			(type solid)
		)
		(fill yes)
		(layer "B.Cu")
		(net "GND")
	)
	(gr_poly
		(pts
			(arc
				(start 342.307164 -400.858228)
				(mid 342.015572 -400.858228)
				(end 342.307164 -400.858228)
			)
		)
		(stroke
			(width 0)
			(type solid)
		)
		(fill yes)
		(layer "B.Cu")
		(net "GND")
	)
	(gr_poly
		(pts
			(arc
				(start 343.389204 -403.883876)
				(mid 343.097612 -403.883876)
				(end 343.389204 -403.883876)
			)
		)
		(stroke
			(width 0)
			(type solid)
		)
		(fill yes)
		(layer "B.Cu")
		(net "GND")
	)
	(gr_poly
		(pts
			(arc
				(start 343.389204 -400.858228)
				(mid 343.097612 -400.858228)
				(end 343.389204 -400.858228)
			)
		)
		(stroke
			(width 0)
			(type solid)
		)
		(fill yes)
		(layer "B.Cu")
		(net "GND")
	)
	(gr_poly
		(pts
			(arc
				(start 343.653364 -410.030168)
				(mid 343.361772 -410.030168)
				(end 343.653364 -410.030168)
			)
		)
		(stroke
			(width 0)
			(type solid)
		)
		(fill yes)
		(layer "B.Cu")
		(net "GND")
	)
	(gr_poly
		(pts
			(arc
				(start 343.653364 -407.00452)
				(mid 343.361772 -407.00452)
				(end 343.653364 -407.00452)
			)
		)
		(stroke
			(width 0)
			(type solid)
		)
		(fill yes)
		(layer "B.Cu")
		(net "GND")
	)
	(gr_poly
		(pts
			(arc
				(start 344.735404 -410.030168)
				(mid 344.443812 -410.030168)
				(end 344.735404 -410.030168)
			)
		)
		(stroke
			(width 0)
			(type solid)
		)
		(fill yes)
		(layer "B.Cu")
		(net "GND")
	)
	(gr_poly
		(pts
			(arc
				(start 344.735404 -407.00452)
				(mid 344.443812 -407.00452)
				(end 344.735404 -407.00452)
			)
		)
		(stroke
			(width 0)
			(type solid)
		)
		(fill yes)
		(layer "B.Cu")
		(net "GND")
	)
	(gr_poly
		(pts
			(arc
				(start 345.370404 -403.883876)
				(mid 345.078812 -403.883876)
				(end 345.370404 -403.883876)
			)
		)
		(stroke
			(width 0)
			(type solid)
		)
		(fill yes)
		(layer "B.Cu")
		(net "GND")
	)
	(gr_poly
		(pts
			(arc
				(start 345.370404 -400.858228)
				(mid 345.078812 -400.858228)
				(end 345.370404 -400.858228)
			)
		)
		(stroke
			(width 0)
			(type solid)
		)
		(fill yes)
		(layer "B.Cu")
		(net "GND")
	)
	(gr_poly
		(pts
			(arc
				(start 346.452444 -403.883876)
				(mid 346.160852 -403.883876)
				(end 346.452444 -403.883876)
			)
		)
		(stroke
			(width 0)
			(type solid)
		)
		(fill yes)
		(layer "B.Cu")
		(net "GND")
	)
	(gr_poly
		(pts
			(arc
				(start 346.452444 -400.858228)
				(mid 346.160852 -400.858228)
				(end 346.452444 -400.858228)
			)
		)
		(stroke
			(width 0)
			(type solid)
		)
		(fill yes)
		(layer "B.Cu")
		(net "GND")
	)
	(gr_poly
		(pts
			(arc
				(start 346.716604 -410.030168)
				(mid 346.425012 -410.030168)
				(end 346.716604 -410.030168)
			)
		)
		(stroke
			(width 0)
			(type solid)
		)
		(fill yes)
		(layer "B.Cu")
		(net "GND")
	)
	(gr_poly
		(pts
			(arc
				(start 346.716604 -407.00452)
				(mid 346.425012 -407.00452)
				(end 346.716604 -407.00452)
			)
		)
		(stroke
			(width 0)
			(type solid)
		)
		(fill yes)
		(layer "B.Cu")
		(net "GND")
	)
	(gr_poly
		(pts
			(arc
				(start 347.798644 -410.030168)
				(mid 347.507052 -410.030168)
				(end 347.798644 -410.030168)
			)
		)
		(stroke
			(width 0)
			(type solid)
		)
		(fill yes)
		(layer "B.Cu")
		(net "GND")
	)
	(gr_poly
		(pts
			(arc
				(start 347.798644 -407.00452)
				(mid 347.507052 -407.00452)
				(end 347.798644 -407.00452)
			)
		)
		(stroke
			(width 0)
			(type solid)
		)
		(fill yes)
		(layer "B.Cu")
		(net "GND")
	)
	(gr_poly
		(pts
			(arc
				(start 348.433644 -403.883876)
				(mid 348.142052 -403.883876)
				(end 348.433644 -403.883876)
			)
		)
		(stroke
			(width 0)
			(type solid)
		)
		(fill yes)
		(layer "B.Cu")
		(net "GND")
	)
	(gr_poly
		(pts
			(arc
				(start 348.433644 -400.858228)
				(mid 348.142052 -400.858228)
				(end 348.433644 -400.858228)
			)
		)
		(stroke
			(width 0)
			(type solid)
		)
		(fill yes)
		(layer "B.Cu")
		(net "GND")
	)
	(gr_poly
		(pts
			(arc
				(start 349.515684 -403.883876)
				(mid 349.224092 -403.883876)
				(end 349.515684 -403.883876)
			)
		)
		(stroke
			(width 0)
			(type solid)
		)
		(fill yes)
		(layer "B.Cu")
		(net "GND")
	)
	(gr_poly
		(pts
			(arc
				(start 349.515684 -400.858228)
				(mid 349.224092 -400.858228)
				(end 349.515684 -400.858228)
			)
		)
		(stroke
			(width 0)
			(type solid)
		)
		(fill yes)
		(layer "B.Cu")
		(net "GND")
	)
	(gr_poly
		(pts
			(arc
				(start 349.779844 -410.030168)
				(mid 349.488252 -410.030168)
				(end 349.779844 -410.030168)
			)
		)
		(stroke
			(width 0)
			(type solid)
		)
		(fill yes)
		(layer "B.Cu")
		(net "GND")
	)
	(gr_poly
		(pts
			(arc
				(start 349.779844 -406.980644)
				(mid 349.488252 -406.980644)
				(end 349.779844 -406.980644)
			)
		)
		(stroke
			(width 0)
			(type solid)
		)
		(fill yes)
		(layer "B.Cu")
		(net "GND")
	)
	(gr_poly
		(pts
			(arc
				(start 350.861884 -410.030168)
				(mid 350.570292 -410.030168)
				(end 350.861884 -410.030168)
			)
		)
		(stroke
			(width 0)
			(type solid)
		)
		(fill yes)
		(layer "B.Cu")
		(net "GND")
	)
	(gr_poly
		(pts
			(arc
				(start 350.861884 -407.00452)
				(mid 350.570292 -407.00452)
				(end 350.861884 -407.00452)
			)
		)
		(stroke
			(width 0)
			(type solid)
		)
		(fill yes)
		(layer "B.Cu")
		(net "GND")
	)
	(gr_poly
		(pts
			(arc
				(start 351.496884 -403.883876)
				(mid 351.205292 -403.883876)
				(end 351.496884 -403.883876)
			)
		)
		(stroke
			(width 0)
			(type solid)
		)
		(fill yes)
		(layer "B.Cu")
		(net "GND")
	)
	(gr_poly
		(pts
			(arc
				(start 351.496884 -400.858228)
				(mid 351.205292 -400.858228)
				(end 351.496884 -400.858228)
			)
		)
		(stroke
			(width 0)
			(type solid)
		)
		(fill yes)
		(layer "B.Cu")
		(net "GND")
	)
	(gr_poly
		(pts
			(arc
				(start 352.843084 -410.030168)
				(mid 352.551492 -410.030168)
				(end 352.843084 -410.030168)
			)
		)
		(stroke
			(width 0)
			(type solid)
		)
		(fill yes)
		(layer "B.Cu")
		(net "GND")
	)
	(gr_poly
		(pts
			(arc
				(start 352.843084 -407.00452)
				(mid 352.551492 -407.00452)
				(end 352.843084 -407.00452)
			)
		)
		(stroke
			(width 0)
			(type solid)
		)
		(fill yes)
		(layer "B.Cu")
		(net "GND")
	)
	(gr_poly
		(pts
			(arc
				(start 371.009926 -403.883876)
				(mid 370.718334 -403.883876)
				(end 371.009926 -403.883876)
			)
		)
		(stroke
			(width 0)
			(type solid)
		)
		(fill yes)
		(layer "B.Cu")
		(net "GND")
	)
	(gr_poly
		(pts
			(arc
				(start 371.009926 -400.858228)
				(mid 370.718334 -400.858228)
				(end 371.009926 -400.858228)
			)
		)
		(stroke
			(width 0)
			(type solid)
		)
		(fill yes)
		(layer "B.Cu")
		(net "GND")
	)
	(gr_poly
		(pts
			(arc
				(start 372.356126 -410.030168)
				(mid 372.064534 -410.030168)
				(end 372.356126 -410.030168)
			)
		)
		(stroke
			(width 0)
			(type solid)
		)
		(fill yes)
		(layer "B.Cu")
		(net "GND")
	)
	(gr_poly
		(pts
			(arc
				(start 372.356126 -407.00452)
				(mid 372.064534 -407.00452)
				(end 372.356126 -407.00452)
			)
		)
		(stroke
			(width 0)
			(type solid)
		)
		(fill yes)
		(layer "B.Cu")
		(net "GND")
	)
	(gr_poly
		(pts
			(arc
				(start 372.991126 -403.883876)
				(mid 372.699534 -403.883876)
				(end 372.991126 -403.883876)
			)
		)
		(stroke
			(width 0)
			(type solid)
		)
		(fill yes)
		(layer "B.Cu")
		(net "GND")
	)
	(gr_poly
		(pts
			(arc
				(start 372.991126 -400.858228)
				(mid 372.699534 -400.858228)
				(end 372.991126 -400.858228)
			)
		)
		(stroke
			(width 0)
			(type solid)
		)
		(fill yes)
		(layer "B.Cu")
		(net "GND")
	)
	(gr_poly
		(pts
			(arc
				(start 374.073166 -403.883876)
				(mid 373.781574 -403.883876)
				(end 374.073166 -403.883876)
			)
		)
		(stroke
			(width 0)
			(type solid)
		)
		(fill yes)
		(layer "B.Cu")
		(net "GND")
	)
	(gr_poly
		(pts
			(arc
				(start 374.073166 -400.858228)
				(mid 373.781574 -400.858228)
				(end 374.073166 -400.858228)
			)
		)
		(stroke
			(width 0)
			(type solid)
		)
		(fill yes)
		(layer "B.Cu")
		(net "GND")
	)
	(gr_poly
		(pts
			(arc
				(start 374.337326 -410.030168)
				(mid 374.045734 -410.030168)
				(end 374.337326 -410.030168)
			)
		)
		(stroke
			(width 0)
			(type solid)
		)
		(fill yes)
		(layer "B.Cu")
		(net "GND")
	)
	(gr_poly
		(pts
			(arc
				(start 374.337326 -407.00452)
				(mid 374.045734 -407.00452)
				(end 374.337326 -407.00452)
			)
		)
		(stroke
			(width 0)
			(type solid)
		)
		(fill yes)
		(layer "B.Cu")
		(net "GND")
	)
	(gr_poly
		(pts
			(arc
				(start 375.419366 -410.030168)
				(mid 375.127774 -410.030168)
				(end 375.419366 -410.030168)
			)
		)
		(stroke
			(width 0)
			(type solid)
		)
		(fill yes)
		(layer "B.Cu")
		(net "GND")
	)
	(gr_poly
		(pts
			(arc
				(start 375.419366 -407.00452)
				(mid 375.127774 -407.00452)
				(end 375.419366 -407.00452)
			)
		)
		(stroke
			(width 0)
			(type solid)
		)
		(fill yes)
		(layer "B.Cu")
		(net "GND")
	)
	(gr_poly
		(pts
			(arc
				(start 376.054366 -403.883876)
				(mid 375.762774 -403.883876)
				(end 376.054366 -403.883876)
			)
		)
		(stroke
			(width 0)
			(type solid)
		)
		(fill yes)
		(layer "B.Cu")
		(net "GND")
	)
	(gr_poly
		(pts
			(arc
				(start 376.054366 -400.858228)
				(mid 375.762774 -400.858228)
				(end 376.054366 -400.858228)
			)
		)
		(stroke
			(width 0)
			(type solid)
		)
		(fill yes)
		(layer "B.Cu")
		(net "GND")
	)
	(gr_poly
		(pts
			(arc
				(start 377.136406 -403.883876)
				(mid 376.844814 -403.883876)
				(end 377.136406 -403.883876)
			)
		)
		(stroke
			(width 0)
			(type solid)
		)
		(fill yes)
		(layer "B.Cu")
		(net "GND")
	)
	(gr_poly
		(pts
			(arc
				(start 377.136406 -400.858228)
				(mid 376.844814 -400.858228)
				(end 377.136406 -400.858228)
			)
		)
		(stroke
			(width 0)
			(type solid)
		)
		(fill yes)
		(layer "B.Cu")
		(net "GND")
	)
	(gr_poly
		(pts
			(arc
				(start 377.400566 -410.030168)
				(mid 377.108974 -410.030168)
				(end 377.400566 -410.030168)
			)
		)
		(stroke
			(width 0)
			(type solid)
		)
		(fill yes)
		(layer "B.Cu")
		(net "GND")
	)
	(gr_poly
		(pts
			(arc
				(start 377.400566 -407.00452)
				(mid 377.108974 -407.00452)
				(end 377.400566 -407.00452)
			)
		)
		(stroke
			(width 0)
			(type solid)
		)
		(fill yes)
		(layer "B.Cu")
		(net "GND")
	)
	(gr_poly
		(pts
			(arc
				(start 378.482606 -410.030168)
				(mid 378.191014 -410.030168)
				(end 378.482606 -410.030168)
			)
		)
		(stroke
			(width 0)
			(type solid)
		)
		(fill yes)
		(layer "B.Cu")
		(net "GND")
	)
	(gr_poly
		(pts
			(arc
				(start 378.482606 -407.00452)
				(mid 378.191014 -407.00452)
				(end 378.482606 -407.00452)
			)
		)
		(stroke
			(width 0)
			(type solid)
		)
		(fill yes)
		(layer "B.Cu")
		(net "GND")
	)
	(gr_poly
		(pts
			(arc
				(start 379.117606 -403.883876)
				(mid 378.826014 -403.883876)
				(end 379.117606 -403.883876)
			)
		)
		(stroke
			(width 0)
			(type solid)
		)
		(fill yes)
		(layer "B.Cu")
		(net "GND")
	)
	(gr_poly
		(pts
			(arc
				(start 379.117606 -400.858228)
				(mid 378.826014 -400.858228)
				(end 379.117606 -400.858228)
			)
		)
		(stroke
			(width 0)
			(type solid)
		)
		(fill yes)
		(layer "B.Cu")
		(net "GND")
	)
	(gr_poly
		(pts
			(arc
				(start 380.199646 -403.883876)
				(mid 379.908054 -403.883876)
				(end 380.199646 -403.883876)
			)
		)
		(stroke
			(width 0)
			(type solid)
		)
		(fill yes)
		(layer "B.Cu")
		(net "GND")
	)
	(gr_poly
		(pts
			(arc
				(start 380.199646 -400.858228)
				(mid 379.908054 -400.858228)
				(end 380.199646 -400.858228)
			)
		)
		(stroke
			(width 0)
			(type solid)
		)
		(fill yes)
		(layer "B.Cu")
		(net "GND")
	)
	(gr_poly
		(pts
			(arc
				(start 380.463806 -410.030168)
				(mid 380.172214 -410.030168)
				(end 380.463806 -410.030168)
			)
		)
		(stroke
			(width 0)
			(type solid)
		)
		(fill yes)
		(layer "B.Cu")
		(net "GND")
	)
	(gr_poly
		(pts
			(arc
				(start 380.463806 -407.00452)
				(mid 380.172214 -407.00452)
				(end 380.463806 -407.00452)
			)
		)
		(stroke
			(width 0)
			(type solid)
		)
		(fill yes)
		(layer "B.Cu")
		(net "GND")
	)
	(gr_poly
		(pts
			(arc
				(start 381.545846 -410.030168)
				(mid 381.254254 -410.030168)
				(end 381.545846 -410.030168)
			)
		)
		(stroke
			(width 0)
			(type solid)
		)
		(fill yes)
		(layer "B.Cu")
		(net "GND")
	)
	(gr_poly
		(pts
			(arc
				(start 381.545846 -407.00452)
				(mid 381.254254 -407.00452)
				(end 381.545846 -407.00452)
			)
		)
		(stroke
			(width 0)
			(type solid)
		)
		(fill yes)
		(layer "B.Cu")
		(net "GND")
	)
	(gr_poly
		(pts
			(arc
				(start 382.180846 -403.883876)
				(mid 381.889254 -403.883876)
				(end 382.180846 -403.883876)
			)
		)
		(stroke
			(width 0)
			(type solid)
		)
		(fill yes)
		(layer "B.Cu")
		(net "GND")
	)
	(gr_poly
		(pts
			(arc
				(start 382.180846 -400.858228)
				(mid 381.889254 -400.858228)
				(end 382.180846 -400.858228)
			)
		)
		(stroke
			(width 0)
			(type solid)
		)
		(fill yes)
		(layer "B.Cu")
		(net "GND")
	)
	(gr_poly
		(pts
			(arc
				(start 383.262886 -403.883876)
				(mid 382.971294 -403.883876)
				(end 383.262886 -403.883876)
			)
		)
		(stroke
			(width 0)
			(type solid)
		)
		(fill yes)
		(layer "B.Cu")
		(net "GND")
	)
	(gr_poly
		(pts
			(arc
				(start 383.262886 -400.858228)
				(mid 382.971294 -400.858228)
				(end 383.262886 -400.858228)
			)
		)
		(stroke
			(width 0)
			(type solid)
		)
		(fill yes)
		(layer "B.Cu")
		(net "GND")
	)
	(gr_poly
		(pts
			(arc
				(start 383.527046 -410.030168)
				(mid 383.235454 -410.030168)
				(end 383.527046 -410.030168)
			)
		)
		(stroke
			(width 0)
			(type solid)
		)
		(fill yes)
		(layer "B.Cu")
		(net "GND")
	)
	(gr_poly
		(pts
			(arc
				(start 383.527046 -407.00452)
				(mid 383.235454 -407.00452)
				(end 383.527046 -407.00452)
			)
		)
		(stroke
			(width 0)
			(type solid)
		)
		(fill yes)
		(layer "B.Cu")
		(net "GND")
	)
	(gr_poly
		(pts
			(arc
				(start 384.609086 -410.030168)
				(mid 384.317494 -410.030168)
				(end 384.609086 -410.030168)
			)
		)
		(stroke
			(width 0)
			(type solid)
		)
		(fill yes)
		(layer "B.Cu")
		(net "GND")
	)
	(gr_poly
		(pts
			(arc
				(start 384.609086 -407.00452)
				(mid 384.317494 -407.00452)
				(end 384.609086 -407.00452)
			)
		)
		(stroke
			(width 0)
			(type solid)
		)
		(fill yes)
		(layer "B.Cu")
		(net "GND")
	)
	(gr_poly
		(pts
			(arc
				(start 385.244086 -403.883876)
				(mid 384.952494 -403.883876)
				(end 385.244086 -403.883876)
			)
		)
		(stroke
			(width 0)
			(type solid)
		)
		(fill yes)
		(layer "B.Cu")
		(net "GND")
	)
	(gr_poly
		(pts
			(arc
				(start 385.244086 -400.858228)
				(mid 384.952494 -400.858228)
				(end 385.244086 -400.858228)
			)
		)
		(stroke
			(width 0)
			(type solid)
		)
		(fill yes)
		(layer "B.Cu")
		(net "GND")
	)
	(gr_poly
		(pts
			(arc
				(start 386.326126 -403.883876)
				(mid 386.034534 -403.883876)
				(end 386.326126 -403.883876)
			)
		)
		(stroke
			(width 0)
			(type solid)
		)
		(fill yes)
		(layer "B.Cu")
		(net "GND")
	)
	(gr_poly
		(pts
			(arc
				(start 386.326126 -400.858228)
				(mid 386.034534 -400.858228)
				(end 386.326126 -400.858228)
			)
		)
		(stroke
			(width 0)
			(type solid)
		)
		(fill yes)
		(layer "B.Cu")
		(net "GND")
	)
	(gr_poly
		(pts
			(arc
				(start 386.590286 -410.030168)
				(mid 386.298694 -410.030168)
				(end 386.590286 -410.030168)
			)
		)
		(stroke
			(width 0)
			(type solid)
		)
		(fill yes)
		(layer "B.Cu")
		(net "GND")
	)
	(gr_poly
		(pts
			(arc
				(start 386.590286 -407.00452)
				(mid 386.298694 -407.00452)
				(end 386.590286 -407.00452)
			)
		)
		(stroke
			(width 0)
			(type solid)
		)
		(fill yes)
		(layer "B.Cu")
		(net "GND")
	)
	(gr_poly
		(pts
			(arc
				(start 387.672326 -410.030168)
				(mid 387.380734 -410.030168)
				(end 387.672326 -410.030168)
			)
		)
		(stroke
			(width 0)
			(type solid)
		)
		(fill yes)
		(layer "B.Cu")
		(net "GND")
	)
	(gr_poly
		(pts
			(arc
				(start 387.672326 -407.00452)
				(mid 387.380734 -407.00452)
				(end 387.672326 -407.00452)
			)
		)
		(stroke
			(width 0)
			(type solid)
		)
		(fill yes)
		(layer "B.Cu")
		(net "GND")
	)
	(gr_poly
		(pts
			(arc
				(start 388.307326 -403.883876)
				(mid 388.015734 -403.883876)
				(end 388.307326 -403.883876)
			)
		)
		(stroke
			(width 0)
			(type solid)
		)
		(fill yes)
		(layer "B.Cu")
		(net "GND")
	)
	(gr_poly
		(pts
			(arc
				(start 388.307326 -400.858228)
				(mid 388.015734 -400.858228)
				(end 388.307326 -400.858228)
			)
		)
		(stroke
			(width 0)
			(type solid)
		)
		(fill yes)
		(layer "B.Cu")
		(net "GND")
	)
	(gr_poly
		(pts
			(arc
				(start 389.389366 -403.883876)
				(mid 389.097774 -403.883876)
				(end 389.389366 -403.883876)
			)
		)
		(stroke
			(width 0)
			(type solid)
		)
		(fill yes)
		(layer "B.Cu")
		(net "GND")
	)
	(gr_poly
		(pts
			(arc
				(start 389.389366 -400.858228)
				(mid 389.097774 -400.858228)
				(end 389.389366 -400.858228)
			)
		)
		(stroke
			(width 0)
			(type solid)
		)
		(fill yes)
		(layer "B.Cu")
		(net "GND")
	)
	(gr_poly
		(pts
			(arc
				(start 389.653526 -410.030168)
				(mid 389.361934 -410.030168)
				(end 389.653526 -410.030168)
			)
		)
		(stroke
			(width 0)
			(type solid)
		)
		(fill yes)
		(layer "B.Cu")
		(net "GND")
	)
	(gr_poly
		(pts
			(arc
				(start 389.653526 -407.00452)
				(mid 389.361934 -407.00452)
				(end 389.653526 -407.00452)
			)
		)
		(stroke
			(width 0)
			(type solid)
		)
		(fill yes)
		(layer "B.Cu")
		(net "GND")
	)
	(gr_poly
		(pts
			(arc
				(start 390.735566 -410.030168)
				(mid 390.443974 -410.030168)
				(end 390.735566 -410.030168)
			)
		)
		(stroke
			(width 0)
			(type solid)
		)
		(fill yes)
		(layer "B.Cu")
		(net "GND")
	)
	(gr_poly
		(pts
			(arc
				(start 390.735566 -407.00452)
				(mid 390.443974 -407.00452)
				(end 390.735566 -407.00452)
			)
		)
		(stroke
			(width 0)
			(type solid)
		)
		(fill yes)
		(layer "B.Cu")
		(net "GND")
	)
	(gr_poly
		(pts
			(arc
				(start 391.370566 -403.883876)
				(mid 391.078974 -403.883876)
				(end 391.370566 -403.883876)
			)
		)
		(stroke
			(width 0)
			(type solid)
		)
		(fill yes)
		(layer "B.Cu")
		(net "GND")
	)
	(gr_poly
		(pts
			(arc
				(start 391.370566 -400.858228)
				(mid 391.078974 -400.858228)
				(end 391.370566 -400.858228)
			)
		)
		(stroke
			(width 0)
			(type solid)
		)
		(fill yes)
		(layer "B.Cu")
		(net "GND")
	)
	(gr_poly
		(pts
			(arc
				(start 392.452606 -403.883876)
				(mid 392.161014 -403.883876)
				(end 392.452606 -403.883876)
			)
		)
		(stroke
			(width 0)
			(type solid)
		)
		(fill yes)
		(layer "B.Cu")
		(net "GND")
	)
	(gr_poly
		(pts
			(arc
				(start 392.452606 -400.858228)
				(mid 392.161014 -400.858228)
				(end 392.452606 -400.858228)
			)
		)
		(stroke
			(width 0)
			(type solid)
		)
		(fill yes)
		(layer "B.Cu")
		(net "GND")
	)
	(gr_poly
		(pts
			(arc
				(start 392.716766 -410.030168)
				(mid 392.425174 -410.030168)
				(end 392.716766 -410.030168)
			)
		)
		(stroke
			(width 0)
			(type solid)
		)
		(fill yes)
		(layer "B.Cu")
		(net "GND")
	)
	(gr_poly
		(pts
			(arc
				(start 392.716766 -407.00452)
				(mid 392.425174 -407.00452)
				(end 392.716766 -407.00452)
			)
		)
		(stroke
			(width 0)
			(type solid)
		)
		(fill yes)
		(layer "B.Cu")
		(net "GND")
	)
	(gr_poly
		(pts
			(arc
				(start 393.798806 -410.030168)
				(mid 393.507214 -410.030168)
				(end 393.798806 -410.030168)
			)
		)
		(stroke
			(width 0)
			(type solid)
		)
		(fill yes)
		(layer "B.Cu")
		(net "GND")
	)
	(gr_poly
		(pts
			(arc
				(start 393.798806 -407.00452)
				(mid 393.507214 -407.00452)
				(end 393.798806 -407.00452)
			)
		)
		(stroke
			(width 0)
			(type solid)
		)
		(fill yes)
		(layer "B.Cu")
		(net "GND")
	)
	(gr_poly
		(pts
			(arc
				(start 394.433806 -403.883876)
				(mid 394.142214 -403.883876)
				(end 394.433806 -403.883876)
			)
		)
		(stroke
			(width 0)
			(type solid)
		)
		(fill yes)
		(layer "B.Cu")
		(net "GND")
	)
	(gr_poly
		(pts
			(arc
				(start 394.433806 -400.858228)
				(mid 394.142214 -400.858228)
				(end 394.433806 -400.858228)
			)
		)
		(stroke
			(width 0)
			(type solid)
		)
		(fill yes)
		(layer "B.Cu")
		(net "GND")
	)
	(gr_poly
		(pts
			(arc
				(start 395.515846 -403.883876)
				(mid 395.224254 -403.883876)
				(end 395.515846 -403.883876)
			)
		)
		(stroke
			(width 0)
			(type solid)
		)
		(fill yes)
		(layer "B.Cu")
		(net "GND")
	)
	(gr_poly
		(pts
			(arc
				(start 395.515846 -400.858228)
				(mid 395.224254 -400.858228)
				(end 395.515846 -400.858228)
			)
		)
		(stroke
			(width 0)
			(type solid)
		)
		(fill yes)
		(layer "B.Cu")
		(net "GND")
	)
	(gr_poly
		(pts
			(arc
				(start 395.780006 -410.030168)
				(mid 395.488414 -410.030168)
				(end 395.780006 -410.030168)
			)
		)
		(stroke
			(width 0)
			(type solid)
		)
		(fill yes)
		(layer "B.Cu")
		(net "GND")
	)
	(gr_poly
		(pts
			(arc
				(start 395.780006 -407.00452)
				(mid 395.488414 -407.00452)
				(end 395.780006 -407.00452)
			)
		)
		(stroke
			(width 0)
			(type solid)
		)
		(fill yes)
		(layer "B.Cu")
		(net "GND")
	)
	(gr_poly
		(pts
			(arc
				(start 396.862046 -410.030168)
				(mid 396.570454 -410.030168)
				(end 396.862046 -410.030168)
			)
		)
		(stroke
			(width 0)
			(type solid)
		)
		(fill yes)
		(layer "B.Cu")
		(net "GND")
	)
	(gr_poly
		(pts
			(arc
				(start 396.862046 -407.00452)
				(mid 396.570454 -407.00452)
				(end 396.862046 -407.00452)
			)
		)
		(stroke
			(width 0)
			(type solid)
		)
		(fill yes)
		(layer "B.Cu")
		(net "GND")
	)
	(gr_poly
		(pts
			(arc
				(start 397.497046 -403.883876)
				(mid 397.205454 -403.883876)
				(end 397.497046 -403.883876)
			)
		)
		(stroke
			(width 0)
			(type solid)
		)
		(fill yes)
		(layer "B.Cu")
		(net "GND")
	)
	(gr_poly
		(pts
			(arc
				(start 397.497046 -400.858228)
				(mid 397.205454 -400.858228)
				(end 397.497046 -400.858228)
			)
		)
		(stroke
			(width 0)
			(type solid)
		)
		(fill yes)
		(layer "B.Cu")
		(net "GND")
	)
	(gr_poly
		(pts
			(arc
				(start 398.579086 -403.883876)
				(mid 398.287494 -403.883876)
				(end 398.579086 -403.883876)
			)
		)
		(stroke
			(width 0)
			(type solid)
		)
		(fill yes)
		(layer "B.Cu")
		(net "GND")
	)
	(gr_poly
		(pts
			(arc
				(start 398.579086 -400.858228)
				(mid 398.287494 -400.858228)
				(end 398.579086 -400.858228)
			)
		)
		(stroke
			(width 0)
			(type solid)
		)
		(fill yes)
		(layer "B.Cu")
		(net "GND")
	)
	(gr_poly
		(pts
			(arc
				(start 398.843246 -410.030168)
				(mid 398.551654 -410.030168)
				(end 398.843246 -410.030168)
			)
		)
		(stroke
			(width 0)
			(type solid)
		)
		(fill yes)
		(layer "B.Cu")
		(net "GND")
	)
	(gr_poly
		(pts
			(arc
				(start 398.843246 -407.00452)
				(mid 398.551654 -407.00452)
				(end 398.843246 -407.00452)
			)
		)
		(stroke
			(width 0)
			(type solid)
		)
		(fill yes)
		(layer "B.Cu")
		(net "GND")
	)
	(gr_poly
		(pts
			(arc
				(start 399.925286 -410.030168)
				(mid 399.633694 -410.030168)
				(end 399.925286 -410.030168)
			)
		)
		(stroke
			(width 0)
			(type solid)
		)
		(fill yes)
		(layer "B.Cu")
		(net "GND")
	)
	(gr_poly
		(pts
			(arc
				(start 399.925286 -407.00452)
				(mid 399.633694 -407.00452)
				(end 399.925286 -407.00452)
			)
		)
		(stroke
			(width 0)
			(type solid)
		)
		(fill yes)
		(layer "B.Cu")
		(net "GND")
	)
	(gr_poly
		(pts
			(arc
				(start 400.560286 -403.883876)
				(mid 400.268694 -403.883876)
				(end 400.560286 -403.883876)
			)
		)
		(stroke
			(width 0)
			(type solid)
		)
		(fill yes)
		(layer "B.Cu")
		(net "GND")
	)
	(gr_poly
		(pts
			(arc
				(start 400.560286 -400.858228)
				(mid 400.268694 -400.858228)
				(end 400.560286 -400.858228)
			)
		)
		(stroke
			(width 0)
			(type solid)
		)
		(fill yes)
		(layer "B.Cu")
		(net "GND")
	)
	(gr_poly
		(pts
			(arc
				(start 401.642326 -403.883876)
				(mid 401.350734 -403.883876)
				(end 401.642326 -403.883876)
			)
		)
		(stroke
			(width 0)
			(type solid)
		)
		(fill yes)
		(layer "B.Cu")
		(net "GND")
	)
	(gr_poly
		(pts
			(arc
				(start 401.642326 -400.858228)
				(mid 401.350734 -400.858228)
				(end 401.642326 -400.858228)
			)
		)
		(stroke
			(width 0)
			(type solid)
		)
		(fill yes)
		(layer "B.Cu")
		(net "GND")
	)
	(gr_poly
		(pts
			(arc
				(start 401.906486 -410.030168)
				(mid 401.614894 -410.030168)
				(end 401.906486 -410.030168)
			)
		)
		(stroke
			(width 0)
			(type solid)
		)
		(fill yes)
		(layer "B.Cu")
		(net "GND")
	)
	(gr_poly
		(pts
			(arc
				(start 401.906486 -407.00452)
				(mid 401.614894 -407.00452)
				(end 401.906486 -407.00452)
			)
		)
		(stroke
			(width 0)
			(type solid)
		)
		(fill yes)
		(layer "B.Cu")
		(net "GND")
	)
	(gr_poly
		(pts
			(arc
				(start 402.988526 -410.030168)
				(mid 402.696934 -410.030168)
				(end 402.988526 -410.030168)
			)
		)
		(stroke
			(width 0)
			(type solid)
		)
		(fill yes)
		(layer "B.Cu")
		(net "GND")
	)
	(gr_poly
		(pts
			(arc
				(start 402.988526 -407.00452)
				(mid 402.696934 -407.00452)
				(end 402.988526 -407.00452)
			)
		)
		(stroke
			(width 0)
			(type solid)
		)
		(fill yes)
		(layer "B.Cu")
		(net "GND")
	)
	(gr_poly
		(pts
			(arc
				(start 403.623526 -403.883876)
				(mid 403.331934 -403.883876)
				(end 403.623526 -403.883876)
			)
		)
		(stroke
			(width 0)
			(type solid)
		)
		(fill yes)
		(layer "B.Cu")
		(net "GND")
	)
	(gr_poly
		(pts
			(arc
				(start 403.623526 -400.858228)
				(mid 403.331934 -400.858228)
				(end 403.623526 -400.858228)
			)
		)
		(stroke
			(width 0)
			(type solid)
		)
		(fill yes)
		(layer "B.Cu")
		(net "GND")
	)
	(gr_poly
		(pts
			(arc
				(start 404.705566 -403.883876)
				(mid 404.413974 -403.883876)
				(end 404.705566 -403.883876)
			)
		)
		(stroke
			(width 0)
			(type solid)
		)
		(fill yes)
		(layer "B.Cu")
		(net "GND")
	)
	(gr_poly
		(pts
			(arc
				(start 404.705566 -400.858228)
				(mid 404.413974 -400.858228)
				(end 404.705566 -400.858228)
			)
		)
		(stroke
			(width 0)
			(type solid)
		)
		(fill yes)
		(layer "B.Cu")
		(net "GND")
	)
	(gr_poly
		(pts
			(arc
				(start 404.969726 -410.030168)
				(mid 404.678134 -410.030168)
				(end 404.969726 -410.030168)
			)
		)
		(stroke
			(width 0)
			(type solid)
		)
		(fill yes)
		(layer "B.Cu")
		(net "GND")
	)
	(gr_poly
		(pts
			(arc
				(start 404.969726 -407.00452)
				(mid 404.678134 -407.00452)
				(end 404.969726 -407.00452)
			)
		)
		(stroke
			(width 0)
			(type solid)
		)
		(fill yes)
		(layer "B.Cu")
		(net "GND")
	)
	(gr_poly
		(pts
			(arc
				(start 406.051766 -410.030168)
				(mid 405.760174 -410.030168)
				(end 406.051766 -410.030168)
			)
		)
		(stroke
			(width 0)
			(type solid)
		)
		(fill yes)
		(layer "B.Cu")
		(net "GND")
	)
	(gr_poly
		(pts
			(arc
				(start 406.051766 -407.00452)
				(mid 405.760174 -407.00452)
				(end 406.051766 -407.00452)
			)
		)
		(stroke
			(width 0)
			(type solid)
		)
		(fill yes)
		(layer "B.Cu")
		(net "GND")
	)
	(gr_poly
		(pts
			(arc
				(start 406.686766 -403.883876)
				(mid 406.395174 -403.883876)
				(end 406.686766 -403.883876)
			)
		)
		(stroke
			(width 0)
			(type solid)
		)
		(fill yes)
		(layer "B.Cu")
		(net "GND")
	)
	(gr_poly
		(pts
			(arc
				(start 406.686766 -400.858228)
				(mid 406.395174 -400.858228)
				(end 406.686766 -400.858228)
			)
		)
		(stroke
			(width 0)
			(type solid)
		)
		(fill yes)
		(layer "B.Cu")
		(net "GND")
	)
	(gr_poly
		(pts
			(arc
				(start 407.768806 -403.883876)
				(mid 407.477214 -403.883876)
				(end 407.768806 -403.883876)
			)
		)
		(stroke
			(width 0)
			(type solid)
		)
		(fill yes)
		(layer "B.Cu")
		(net "GND")
	)
	(gr_poly
		(pts
			(arc
				(start 407.768806 -400.858228)
				(mid 407.477214 -400.858228)
				(end 407.768806 -400.858228)
			)
		)
		(stroke
			(width 0)
			(type solid)
		)
		(fill yes)
		(layer "B.Cu")
		(net "GND")
	)
	(gr_poly
		(pts
			(arc
				(start 408.032966 -410.030168)
				(mid 407.741374 -410.030168)
				(end 408.032966 -410.030168)
			)
		)
		(stroke
			(width 0)
			(type solid)
		)
		(fill yes)
		(layer "B.Cu")
		(net "GND")
	)
	(gr_poly
		(pts
			(arc
				(start 408.032966 -407.00452)
				(mid 407.741374 -407.00452)
				(end 408.032966 -407.00452)
			)
		)
		(stroke
			(width 0)
			(type solid)
		)
		(fill yes)
		(layer "B.Cu")
		(net "GND")
	)
	(gr_poly
		(pts
			(arc
				(start 409.115006 -410.030168)
				(mid 408.823414 -410.030168)
				(end 409.115006 -410.030168)
			)
		)
		(stroke
			(width 0)
			(type solid)
		)
		(fill yes)
		(layer "B.Cu")
		(net "GND")
	)
	(gr_poly
		(pts
			(arc
				(start 409.115006 -407.00452)
				(mid 408.823414 -407.00452)
				(end 409.115006 -407.00452)
			)
		)
		(stroke
			(width 0)
			(type solid)
		)
		(fill yes)
		(layer "B.Cu")
		(net "GND")
	)
	(gr_poly
		(pts
			(arc
				(start 409.750006 -403.883876)
				(mid 409.458414 -403.883876)
				(end 409.750006 -403.883876)
			)
		)
		(stroke
			(width 0)
			(type solid)
		)
		(fill yes)
		(layer "B.Cu")
		(net "GND")
	)
	(gr_poly
		(pts
			(arc
				(start 409.750006 -400.858228)
				(mid 409.458414 -400.858228)
				(end 409.750006 -400.858228)
			)
		)
		(stroke
			(width 0)
			(type solid)
		)
		(fill yes)
		(layer "B.Cu")
		(net "GND")
	)
	(gr_poly
		(pts
			(arc
				(start 410.832046 -403.883876)
				(mid 410.540454 -403.883876)
				(end 410.832046 -403.883876)
			)
		)
		(stroke
			(width 0)
			(type solid)
		)
		(fill yes)
		(layer "B.Cu")
		(net "GND")
	)
	(gr_poly
		(pts
			(arc
				(start 410.832046 -400.858228)
				(mid 410.540454 -400.858228)
				(end 410.832046 -400.858228)
			)
		)
		(stroke
			(width 0)
			(type solid)
		)
		(fill yes)
		(layer "B.Cu")
		(net "GND")
	)
	(gr_poly
		(pts
			(arc
				(start 411.096206 -410.030168)
				(mid 410.804614 -410.030168)
				(end 411.096206 -410.030168)
			)
		)
		(stroke
			(width 0)
			(type solid)
		)
		(fill yes)
		(layer "B.Cu")
		(net "GND")
	)
	(gr_poly
		(pts
			(arc
				(start 411.096206 -407.00452)
				(mid 410.804614 -407.00452)
				(end 411.096206 -407.00452)
			)
		)
		(stroke
			(width 0)
			(type solid)
		)
		(fill yes)
		(layer "B.Cu")
		(net "GND")
	)
	(gr_poly
		(pts
			(arc
				(start 412.178246 -410.030168)
				(mid 411.886654 -410.030168)
				(end 412.178246 -410.030168)
			)
		)
		(stroke
			(width 0)
			(type solid)
		)
		(fill yes)
		(layer "B.Cu")
		(net "GND")
	)
	(gr_poly
		(pts
			(arc
				(start 412.178246 -407.00452)
				(mid 411.886654 -407.00452)
				(end 412.178246 -407.00452)
			)
		)
		(stroke
			(width 0)
			(type solid)
		)
		(fill yes)
		(layer "B.Cu")
		(net "GND")
	)
	(gr_poly
		(pts
			(arc
				(start 412.813246 -403.883876)
				(mid 412.521654 -403.883876)
				(end 412.813246 -403.883876)
			)
		)
		(stroke
			(width 0)
			(type solid)
		)
		(fill yes)
		(layer "B.Cu")
		(net "GND")
	)
	(gr_poly
		(pts
			(arc
				(start 412.813246 -400.858228)
				(mid 412.521654 -400.858228)
				(end 412.813246 -400.858228)
			)
		)
		(stroke
			(width 0)
			(type solid)
		)
		(fill yes)
		(layer "B.Cu")
		(net "GND")
	)
	(gr_poly
		(pts
			(arc
				(start 413.895286 -403.883876)
				(mid 413.603694 -403.883876)
				(end 413.895286 -403.883876)
			)
		)
		(stroke
			(width 0)
			(type solid)
		)
		(fill yes)
		(layer "B.Cu")
		(net "GND")
	)
	(gr_poly
		(pts
			(arc
				(start 413.895286 -400.858228)
				(mid 413.603694 -400.858228)
				(end 413.895286 -400.858228)
			)
		)
		(stroke
			(width 0)
			(type solid)
		)
		(fill yes)
		(layer "B.Cu")
		(net "GND")
	)
	(gr_poly
		(pts
			(arc
				(start 414.159446 -410.030168)
				(mid 413.867854 -410.030168)
				(end 414.159446 -410.030168)
			)
		)
		(stroke
			(width 0)
			(type solid)
		)
		(fill yes)
		(layer "B.Cu")
		(net "GND")
	)
	(gr_poly
		(pts
			(arc
				(start 414.159446 -407.00452)
				(mid 413.867854 -407.00452)
				(end 414.159446 -407.00452)
			)
		)
		(stroke
			(width 0)
			(type solid)
		)
		(fill yes)
		(layer "B.Cu")
		(net "GND")
	)
	(gr_poly
		(pts
			(arc
				(start 415.241486 -410.030168)
				(mid 414.949894 -410.030168)
				(end 415.241486 -410.030168)
			)
		)
		(stroke
			(width 0)
			(type solid)
		)
		(fill yes)
		(layer "B.Cu")
		(net "GND")
	)
	(gr_poly
		(pts
			(arc
				(start 415.241486 -407.00452)
				(mid 414.949894 -407.00452)
				(end 415.241486 -407.00452)
			)
		)
		(stroke
			(width 0)
			(type solid)
		)
		(fill yes)
		(layer "B.Cu")
		(net "GND")
	)
	(gr_poly
		(pts
			(arc
				(start 415.876486 -403.883876)
				(mid 415.584894 -403.883876)
				(end 415.876486 -403.883876)
			)
		)
		(stroke
			(width 0)
			(type solid)
		)
		(fill yes)
		(layer "B.Cu")
		(net "GND")
	)
	(gr_poly
		(pts
			(arc
				(start 415.876486 -400.834352)
				(mid 415.584894 -400.834352)
				(end 415.876486 -400.834352)
			)
		)
		(stroke
			(width 0)
			(type solid)
		)
		(fill yes)
		(layer "B.Cu")
		(net "GND")
	)
	(gr_poly
		(pts
			(arc
				(start 416.958526 -403.883876)
				(mid 416.666934 -403.883876)
				(end 416.958526 -403.883876)
			)
		)
		(stroke
			(width 0)
			(type solid)
		)
		(fill yes)
		(layer "B.Cu")
		(net "GND")
	)
	(gr_poly
		(pts
			(arc
				(start 416.958526 -400.858228)
				(mid 416.666934 -400.858228)
				(end 416.958526 -400.858228)
			)
		)
		(stroke
			(width 0)
			(type solid)
		)
		(fill yes)
		(layer "B.Cu")
		(net "GND")
	)
	(gr_poly
		(pts
			(arc
				(start 417.222686 -410.030168)
				(mid 416.931094 -410.030168)
				(end 417.222686 -410.030168)
			)
		)
		(stroke
			(width 0)
			(type solid)
		)
		(fill yes)
		(layer "B.Cu")
		(net "GND")
	)
	(gr_poly
		(pts
			(arc
				(start 417.222686 -407.00452)
				(mid 416.931094 -407.00452)
				(end 417.222686 -407.00452)
			)
		)
		(stroke
			(width 0)
			(type solid)
		)
		(fill yes)
		(layer "B.Cu")
		(net "GND")
	)
	(gr_poly
		(pts
			(arc
				(start 418.304726 -410.030168)
				(mid 418.013134 -410.030168)
				(end 418.304726 -410.030168)
			)
		)
		(stroke
			(width 0)
			(type solid)
		)
		(fill yes)
		(layer "B.Cu")
		(net "GND")
	)
	(gr_poly
		(pts
			(arc
				(start 418.304726 -407.00452)
				(mid 418.013134 -407.00452)
				(end 418.304726 -407.00452)
			)
		)
		(stroke
			(width 0)
			(type solid)
		)
		(fill yes)
		(layer "B.Cu")
		(net "GND")
	)
	(gr_poly
		(pts
			(arc
				(start 418.939726 -403.883876)
				(mid 418.648134 -403.883876)
				(end 418.939726 -403.883876)
			)
		)
		(stroke
			(width 0)
			(type solid)
		)
		(fill yes)
		(layer "B.Cu")
		(net "GND")
	)
	(gr_poly
		(pts
			(arc
				(start 418.939726 -400.858228)
				(mid 418.648134 -400.858228)
				(end 418.939726 -400.858228)
			)
		)
		(stroke
			(width 0)
			(type solid)
		)
		(fill yes)
		(layer "B.Cu")
		(net "GND")
	)
	(gr_poly
		(pts
			(arc
				(start 420.285926 -410.030168)
				(mid 419.994334 -410.030168)
				(end 420.285926 -410.030168)
			)
		)
		(stroke
			(width 0)
			(type solid)
		)
		(fill yes)
		(layer "B.Cu")
		(net "GND")
	)
	(gr_poly
		(pts
			(arc
				(start 420.285926 -407.00452)
				(mid 419.994334 -407.00452)
				(end 420.285926 -407.00452)
			)
		)
		(stroke
			(width 0)
			(type solid)
		)
		(fill yes)
		(layer "B.Cu")
		(net "GND")
	)
	(gr_poly
		(pts
			(xy 371.411246 -339.327236) (xy 371.411246 -338.16036) (xy 371.366796 -338.11591) (xy 369.900454 -338.11591)
			(arc
				(start 369.88877 -338.150454)
				(mid 369.527328 -338.409467)
				(end 369.165886 -338.150454)
			)
			(xy 369.154202 -338.11591) (xy 368.812064 -338.11591) (xy 368.718338 -338.209636) (xy 368.718338 -339.413596)
			(xy 368.878358 -339.573616) (xy 371.164866 -339.573616)
		)
		(stroke
			(width 0)
			(type solid)
		)
		(fill yes)
		(layer "B.Cu")
		(net "GND")
	)
	(gr_poly
		(pts
			(xy 465.15528 -77.074268) (xy 465.15528 -66.647568) (xy 464.7946 -66.286888) (xy 462.08188 -66.286888)
			(xy 461.83804 -66.530728) (xy 461.83804 -69.982588) (xy 461.45704 -70.363588) (xy 456.6031 -70.363588)
			(xy 455.80808 -71.158608) (xy 452.518272 -71.158608) (xy 452.39305 -71.28383) (xy 452.39305 -73.44283)
			(xy 452.432928 -73.482708)
			(arc
				(start 452.4375 -73.485756)
				(mid 452.759273 -73.742849)
				(end 453.016366 -74.064622)
			)
			(xy 453.019414 -74.069194) (xy 454.106026 -75.155806) (xy 454.106026 -76.207366) (xy 454.569068 -76.670408)
			(xy 460.97952 -76.670408) (xy 461.56626 -77.257148) (xy 464.9724 -77.257148)
		)
		(stroke
			(width 0)
			(type solid)
		)
		(fill yes)
		(layer "B.Cu")
		(net "SW_P3V3_AUX_FLT")
	)
	(gr_poly
		(pts
			(xy 174.804324 -103.685848)
			(arc
				(start 174.803054 -103.680006)
				(mid 174.79865 -103.654393)
				(end 174.797212 -103.628444)
			)
			(xy 174.797212 -103.360728) (xy 174.82947 -103.360728) (xy 174.843694 -103.332788) (xy 174.857156 -103.308404)
			(xy 174.857156 -102.835964) (xy 174.797212 -102.835964)
			(arc
				(start 174.797212 -102.568248)
				(mid 174.825818 -102.458179)
				(end 174.9044 -102.37597)
			)
			(xy 174.92853 -102.361238) (xy 174.92853 -102.236778) (xy 175.12792 -102.037388) (xy 175.60798 -102.037388)
			(xy 175.75784 -101.887528) (xy 175.75784 -101.343968) (xy 175.57242 -101.158548) (xy 173.25213 -101.158548)
			(xy 173.20133 -101.209348) (xy 173.20133 -103.952548) (xy 173.27753 -104.028748) (xy 174.804324 -104.028748)
		)
		(stroke
			(width 0)
			(type solid)
		)
		(fill yes)
		(layer "B.Cu")
		(net "P3V3_AUX_FPGA_VCCIO5")
	)
	(gr_poly
		(pts
			(arc
				(start 199.0725 -150.769828)
				(mid 198.7423 -150.769828)
				(end 199.0725 -150.769828)
			)
		)
		(stroke
			(width 0)
			(type solid)
		)
		(fill yes)
		(layer "B.Cu")
		(net "GND")
	)
	(gr_poly
		(pts
			(arc
				(start 200.75398 -147.792948)
				(mid 200.42378 -147.792948)
				(end 200.75398 -147.792948)
			)
		)
		(stroke
			(width 0)
			(type solid)
		)
		(fill yes)
		(layer "B.Cu")
		(net "GND")
	)
	(gr_poly
		(pts
			(arc
				(start 201.51598 -149.824948)
				(mid 201.18578 -149.824948)
				(end 201.51598 -149.824948)
			)
		)
		(stroke
			(width 0)
			(type solid)
		)
		(fill yes)
		(layer "B.Cu")
		(net "GND")
	)
	(gr_poly
		(pts
			(arc
				(start 202.78598 -156.936948)
				(mid 202.45578 -156.936948)
				(end 202.78598 -156.936948)
			)
		)
		(stroke
			(width 0)
			(type solid)
		)
		(fill yes)
		(layer "B.Cu")
		(net "GND")
	)
	(gr_poly
		(pts
			(arc
				(start 202.91298 -151.729948)
				(mid 202.58278 -151.729948)
				(end 202.91298 -151.729948)
			)
		)
		(stroke
			(width 0)
			(type solid)
		)
		(fill yes)
		(layer "B.Cu")
		(net "GND")
	)
	(gr_poly
		(pts
			(arc
				(start 203.03998 -148.681948)
				(mid 202.70978 -148.681948)
				(end 203.03998 -148.681948)
			)
		)
		(stroke
			(width 0)
			(type solid)
		)
		(fill yes)
		(layer "B.Cu")
		(net "GND")
	)
	(gr_poly
		(pts
			(arc
				(start 205.61554 -153.365708)
				(mid 205.28534 -153.365708)
				(end 205.61554 -153.365708)
			)
		)
		(stroke
			(width 0)
			(type solid)
		)
		(fill yes)
		(layer "B.Cu")
		(net "GND")
	)
	(gr_poly
		(pts
			(arc
				(start 207.18526 -150.056088)
				(mid 206.85506 -150.056088)
				(end 207.18526 -150.056088)
			)
		)
		(stroke
			(width 0)
			(type solid)
		)
		(fill yes)
		(layer "B.Cu")
		(net "GND")
	)
	(gr_poly
		(pts
			(arc
				(start 211.4169 -151.628348)
				(mid 211.0867 -151.628348)
				(end 211.4169 -151.628348)
			)
		)
		(stroke
			(width 0)
			(type solid)
		)
		(fill yes)
		(layer "B.Cu")
		(net "GND")
	)
	(gr_poly
		(pts
			(arc
				(start 217.766392 -150.878794)
				(mid 217.436192 -150.878794)
				(end 217.766392 -150.878794)
			)
		)
		(stroke
			(width 0)
			(type solid)
		)
		(fill yes)
		(layer "B.Cu")
		(net "GND")
	)
	(gr_poly
		(pts
			(arc
				(start 245.71198 -129.885948)
				(mid 245.38178 -129.885948)
				(end 245.71198 -129.885948)
			)
		)
		(stroke
			(width 0)
			(type solid)
		)
		(fill yes)
		(layer "B.Cu")
		(net "GND")
	)
	(gr_poly
		(pts
			(arc
				(start 250.02998 -130.139948)
				(mid 249.69978 -130.139948)
				(end 250.02998 -130.139948)
			)
		)
		(stroke
			(width 0)
			(type solid)
		)
		(fill yes)
		(layer "B.Cu")
		(net "GND")
	)
	(gr_poly
		(pts
			(arc
				(start 254.09398 -130.266948)
				(mid 253.76378 -130.266948)
				(end 254.09398 -130.266948)
			)
		)
		(stroke
			(width 0)
			(type solid)
		)
		(fill yes)
		(layer "B.Cu")
		(net "GND")
	)
	(gr_poly
		(pts
			(arc
				(start 256.37998 -126.583948)
				(mid 256.04978 -126.583948)
				(end 256.37998 -126.583948)
			)
		)
		(stroke
			(width 0)
			(type solid)
		)
		(fill yes)
		(layer "B.Cu")
		(net "GND")
	)
	(gr_poly
		(pts
			(arc
				(start 256.86512 -190.180214)
				(mid 256.53492 -190.180214)
				(end 256.86512 -190.180214)
			)
		)
		(stroke
			(width 0)
			(type solid)
		)
		(fill yes)
		(layer "B.Cu")
		(net "GND")
	)
	(gr_poly
		(pts
			(arc
				(start 257.14198 -149.697948)
				(mid 256.81178 -149.697948)
				(end 257.14198 -149.697948)
			)
		)
		(stroke
			(width 0)
			(type solid)
		)
		(fill yes)
		(layer "B.Cu")
		(net "GND")
	)
	(gr_poly
		(pts
			(arc
				(start 258.91998 -150.459948)
				(mid 258.58978 -150.459948)
				(end 258.91998 -150.459948)
			)
		)
		(stroke
			(width 0)
			(type solid)
		)
		(fill yes)
		(layer "B.Cu")
		(net "GND")
	)
	(gr_poly
		(pts
			(arc
				(start 259.68198 -152.872948)
				(mid 259.35178 -152.872948)
				(end 259.68198 -152.872948)
			)
		)
		(stroke
			(width 0)
			(type solid)
		)
		(fill yes)
		(layer "B.Cu")
		(net "GND")
	)
	(gr_poly
		(pts
			(arc
				(start 319.388998 -190.39967)
				(mid 319.058798 -190.39967)
				(end 319.388998 -190.39967)
			)
		)
		(stroke
			(width 0)
			(type solid)
		)
		(fill yes)
		(layer "B.Cu")
		(net "GND")
	)
	(gr_poly
		(pts
			(arc
				(start 328.489056 -200.63714)
				(mid 328.158856 -200.63714)
				(end 328.489056 -200.63714)
			)
		)
		(stroke
			(width 0)
			(type solid)
		)
		(fill yes)
		(layer "B.Cu")
		(net "GND")
	)
	(gr_poly
		(pts
			(arc
				(start 328.562716 -198.640192)
				(mid 328.232516 -198.640192)
				(end 328.562716 -198.640192)
			)
		)
		(stroke
			(width 0)
			(type solid)
		)
		(fill yes)
		(layer "B.Cu")
		(net "GND")
	)
	(gr_poly
		(pts
			(arc
				(start 331.131418 -199.602598)
				(mid 330.801218 -199.602598)
				(end 331.131418 -199.602598)
			)
		)
		(stroke
			(width 0)
			(type solid)
		)
		(fill yes)
		(layer "B.Cu")
		(net "GND")
	)
	(gr_poly
		(pts
			(arc
				(start 348.635574 -174.060612)
				(mid 348.305374 -174.060612)
				(end 348.635574 -174.060612)
			)
		)
		(stroke
			(width 0)
			(type solid)
		)
		(fill yes)
		(layer "B.Cu")
		(net "GND")
	)
	(gr_poly
		(pts
			(arc
				(start 348.714822 -183.161432)
				(mid 348.384622 -183.161432)
				(end 348.714822 -183.161432)
			)
		)
		(stroke
			(width 0)
			(type solid)
		)
		(fill yes)
		(layer "B.Cu")
		(net "GND")
	)
	(gr_poly
		(pts
			(arc
				(start 348.714822 -180.113432)
				(mid 348.384622 -180.113432)
				(end 348.714822 -180.113432)
			)
		)
		(stroke
			(width 0)
			(type solid)
		)
		(fill yes)
		(layer "B.Cu")
		(net "GND")
	)
	(gr_poly
		(pts
			(arc
				(start 348.714822 -177.065432)
				(mid 348.384622 -177.065432)
				(end 348.714822 -177.065432)
			)
		)
		(stroke
			(width 0)
			(type solid)
		)
		(fill yes)
		(layer "B.Cu")
		(net "GND")
	)
	(gr_poly
		(pts
			(arc
				(start 348.749874 -168.002712)
				(mid 348.419674 -168.002712)
				(end 348.749874 -168.002712)
			)
		)
		(stroke
			(width 0)
			(type solid)
		)
		(fill yes)
		(layer "B.Cu")
		(net "GND")
	)
	(gr_poly
		(pts
			(arc
				(start 350.870774 -181.916832)
				(mid 350.540574 -181.916832)
				(end 350.870774 -181.916832)
			)
		)
		(stroke
			(width 0)
			(type solid)
		)
		(fill yes)
		(layer "B.Cu")
		(net "GND")
	)
	(gr_poly
		(pts
			(arc
				(start 350.870774 -178.868832)
				(mid 350.540574 -178.868832)
				(end 350.870774 -178.868832)
			)
		)
		(stroke
			(width 0)
			(type solid)
		)
		(fill yes)
		(layer "B.Cu")
		(net "GND")
	)
	(gr_poly
		(pts
			(arc
				(start 350.870774 -175.820832)
				(mid 350.540574 -175.820832)
				(end 350.870774 -175.820832)
			)
		)
		(stroke
			(width 0)
			(type solid)
		)
		(fill yes)
		(layer "B.Cu")
		(net "GND")
	)
	(gr_poly
		(pts
			(arc
				(start 350.972374 -169.768012)
				(mid 350.642174 -169.768012)
				(end 350.972374 -169.768012)
			)
		)
		(stroke
			(width 0)
			(type solid)
		)
		(fill yes)
		(layer "B.Cu")
		(net "GND")
	)
	(gr_poly
		(pts
			(arc
				(start 350.972374 -166.720012)
				(mid 350.642174 -166.720012)
				(end 350.972374 -166.720012)
			)
		)
		(stroke
			(width 0)
			(type solid)
		)
		(fill yes)
		(layer "B.Cu")
		(net "GND")
	)
	(gr_poly
		(pts
			(arc
				(start 351.42678 -186.36615)
				(mid 351.09658 -186.36615)
				(end 351.42678 -186.36615)
			)
		)
		(stroke
			(width 0)
			(type solid)
		)
		(fill yes)
		(layer "B.Cu")
		(net "GND")
	)
	(gr_poly
		(pts
			(arc
				(start 352.445574 -167.888412)
				(mid 352.115374 -167.888412)
				(end 352.445574 -167.888412)
			)
		)
		(stroke
			(width 0)
			(type solid)
		)
		(fill yes)
		(layer "B.Cu")
		(net "GND")
	)
	(gr_poly
		(pts
			(arc
				(start 352.499422 -182.68569)
				(mid 352.169222 -182.68569)
				(end 352.499422 -182.68569)
			)
		)
		(stroke
			(width 0)
			(type solid)
		)
		(fill yes)
		(layer "B.Cu")
		(net "GND")
	)
	(gr_poly
		(pts
			(arc
				(start 352.499422 -178.995832)
				(mid 352.169222 -178.995832)
				(end 352.499422 -178.995832)
			)
		)
		(stroke
			(width 0)
			(type solid)
		)
		(fill yes)
		(layer "B.Cu")
		(net "GND")
	)
	(gr_poly
		(pts
			(arc
				(start 352.499422 -175.312832)
				(mid 352.169222 -175.312832)
				(end 352.499422 -175.312832)
			)
		)
		(stroke
			(width 0)
			(type solid)
		)
		(fill yes)
		(layer "B.Cu")
		(net "GND")
	)
	(gr_poly
		(pts
			(arc
				(start 353.582732 -187.61075)
				(mid 353.252532 -187.61075)
				(end 353.582732 -187.61075)
			)
		)
		(stroke
			(width 0)
			(type solid)
		)
		(fill yes)
		(layer "B.Cu")
		(net "GND")
	)
	(gr_poly
		(pts
			(arc
				(start 354.655374 -183.93029)
				(mid 354.325174 -183.93029)
				(end 354.655374 -183.93029)
			)
		)
		(stroke
			(width 0)
			(type solid)
		)
		(fill yes)
		(layer "B.Cu")
		(net "GND")
	)
	(gr_poly
		(pts
			(arc
				(start 354.655374 -180.240432)
				(mid 354.325174 -180.240432)
				(end 354.655374 -180.240432)
			)
		)
		(stroke
			(width 0)
			(type solid)
		)
		(fill yes)
		(layer "B.Cu")
		(net "GND")
	)
	(gr_poly
		(pts
			(arc
				(start 354.655374 -176.557432)
				(mid 354.325174 -176.557432)
				(end 354.655374 -176.557432)
			)
		)
		(stroke
			(width 0)
			(type solid)
		)
		(fill yes)
		(layer "B.Cu")
		(net "GND")
	)
	(gr_poly
		(pts
			(arc
				(start 354.706174 -169.234612)
				(mid 354.375974 -169.234612)
				(end 354.706174 -169.234612)
			)
		)
		(stroke
			(width 0)
			(type solid)
		)
		(fill yes)
		(layer "B.Cu")
		(net "GND")
	)
	(gr_poly
		(pts
			(arc
				(start 354.756974 -172.892212)
				(mid 354.426774 -172.892212)
				(end 354.756974 -172.892212)
			)
		)
		(stroke
			(width 0)
			(type solid)
		)
		(fill yes)
		(layer "B.Cu")
		(net "GND")
	)
	(gr_poly
		(pts
			(arc
				(start 369.592606 -173.370748)
				(mid 369.262406 -173.370748)
				(end 369.592606 -173.370748)
			)
		)
		(stroke
			(width 0)
			(type solid)
		)
		(fill yes)
		(layer "B.Cu")
		(net "GND")
	)
	(gr_poly
		(pts
			(arc
				(start 369.592606 -170.246548)
				(mid 369.262406 -170.246548)
				(end 369.592606 -170.246548)
			)
		)
		(stroke
			(width 0)
			(type solid)
		)
		(fill yes)
		(layer "B.Cu")
		(net "GND")
	)
	(gr_poly
		(pts
			(arc
				(start 369.671854 -179.423568)
				(mid 369.341654 -179.423568)
				(end 369.671854 -179.423568)
			)
		)
		(stroke
			(width 0)
			(type solid)
		)
		(fill yes)
		(layer "B.Cu")
		(net "GND")
	)
	(gr_poly
		(pts
			(arc
				(start 369.671854 -176.375568)
				(mid 369.341654 -176.375568)
				(end 369.671854 -176.375568)
			)
		)
		(stroke
			(width 0)
			(type solid)
		)
		(fill yes)
		(layer "B.Cu")
		(net "GND")
	)
	(gr_poly
		(pts
			(arc
				(start 369.706906 -167.312848)
				(mid 369.376706 -167.312848)
				(end 369.706906 -167.312848)
			)
		)
		(stroke
			(width 0)
			(type solid)
		)
		(fill yes)
		(layer "B.Cu")
		(net "GND")
	)
	(gr_poly
		(pts
			(arc
				(start 371.51564 -164.043868)
				(mid 371.18544 -164.043868)
				(end 371.51564 -164.043868)
			)
		)
		(stroke
			(width 0)
			(type solid)
		)
		(fill yes)
		(layer "B.Cu")
		(net "GND")
	)
	(gr_poly
		(pts
			(arc
				(start 371.827806 -178.178968)
				(mid 371.497606 -178.178968)
				(end 371.827806 -178.178968)
			)
		)
		(stroke
			(width 0)
			(type solid)
		)
		(fill yes)
		(layer "B.Cu")
		(net "GND")
	)
	(gr_poly
		(pts
			(arc
				(start 371.827806 -175.130968)
				(mid 371.497606 -175.130968)
				(end 371.827806 -175.130968)
			)
		)
		(stroke
			(width 0)
			(type solid)
		)
		(fill yes)
		(layer "B.Cu")
		(net "GND")
	)
	(gr_poly
		(pts
			(arc
				(start 371.929406 -172.100748)
				(mid 371.599206 -172.100748)
				(end 371.929406 -172.100748)
			)
		)
		(stroke
			(width 0)
			(type solid)
		)
		(fill yes)
		(layer "B.Cu")
		(net "GND")
	)
	(gr_poly
		(pts
			(arc
				(start 371.929406 -169.078148)
				(mid 371.599206 -169.078148)
				(end 371.929406 -169.078148)
			)
		)
		(stroke
			(width 0)
			(type solid)
		)
		(fill yes)
		(layer "B.Cu")
		(net "GND")
	)
	(gr_poly
		(pts
			(arc
				(start 371.929406 -166.030148)
				(mid 371.599206 -166.030148)
				(end 371.929406 -166.030148)
			)
		)
		(stroke
			(width 0)
			(type solid)
		)
		(fill yes)
		(layer "B.Cu")
		(net "GND")
	)
	(gr_poly
		(pts
			(arc
				(start 373.402606 -170.246548)
				(mid 373.072406 -170.246548)
				(end 373.402606 -170.246548)
			)
		)
		(stroke
			(width 0)
			(type solid)
		)
		(fill yes)
		(layer "B.Cu")
		(net "GND")
	)
	(gr_poly
		(pts
			(arc
				(start 373.412258 -177.66665)
				(mid 373.082058 -177.66665)
				(end 373.412258 -177.66665)
			)
		)
		(stroke
			(width 0)
			(type solid)
		)
		(fill yes)
		(layer "B.Cu")
		(net "GND")
	)
	(gr_poly
		(pts
			(arc
				(start 373.456454 -173.987968)
				(mid 373.126254 -173.987968)
				(end 373.456454 -173.987968)
			)
		)
		(stroke
			(width 0)
			(type solid)
		)
		(fill yes)
		(layer "B.Cu")
		(net "GND")
	)
	(gr_poly
		(pts
			(arc
				(start 373.456454 -166.621968)
				(mid 373.126254 -166.621968)
				(end 373.456454 -166.621968)
			)
		)
		(stroke
			(width 0)
			(type solid)
		)
		(fill yes)
		(layer "B.Cu")
		(net "GND")
	)
	(gr_poly
		(pts
			(arc
				(start 375.612406 -178.915568)
				(mid 375.282206 -178.915568)
				(end 375.612406 -178.915568)
			)
		)
		(stroke
			(width 0)
			(type solid)
		)
		(fill yes)
		(layer "B.Cu")
		(net "GND")
	)
	(gr_poly
		(pts
			(arc
				(start 375.612406 -175.232568)
				(mid 375.282206 -175.232568)
				(end 375.612406 -175.232568)
			)
		)
		(stroke
			(width 0)
			(type solid)
		)
		(fill yes)
		(layer "B.Cu")
		(net "GND")
	)
	(gr_poly
		(pts
			(arc
				(start 375.612406 -167.866568)
				(mid 375.282206 -167.866568)
				(end 375.612406 -167.866568)
			)
		)
		(stroke
			(width 0)
			(type solid)
		)
		(fill yes)
		(layer "B.Cu")
		(net "GND")
	)
	(gr_poly
		(pts
			(arc
				(start 375.714006 -171.567348)
				(mid 375.383806 -171.567348)
				(end 375.714006 -171.567348)
			)
		)
		(stroke
			(width 0)
			(type solid)
		)
		(fill yes)
		(layer "B.Cu")
		(net "GND")
	)
	(gr_poly
		(pts
			(arc
				(start 393.478766 -179.346352)
				(mid 393.148566 -179.346352)
				(end 393.478766 -179.346352)
			)
		)
		(stroke
			(width 0)
			(type solid)
		)
		(fill yes)
		(layer "B.Cu")
		(net "GND")
	)
	(gr_poly
		(pts
			(arc
				(start 393.879578 -176.14519)
				(mid 393.549378 -176.14519)
				(end 393.879578 -176.14519)
			)
		)
		(stroke
			(width 0)
			(type solid)
		)
		(fill yes)
		(layer "B.Cu")
		(net "GND")
	)
	(gr_poly
		(pts
			(arc
				(start 393.971018 -171.96943)
				(mid 393.640818 -171.96943)
				(end 393.971018 -171.96943)
			)
		)
		(stroke
			(width 0)
			(type solid)
		)
		(fill yes)
		(layer "B.Cu")
		(net "GND")
	)
	(gr_poly
		(pts
			(arc
				(start 432.179984 -115.797076)
				(mid 431.849784 -115.797076)
				(end 432.179984 -115.797076)
			)
		)
		(stroke
			(width 0)
			(type solid)
		)
		(fill yes)
		(layer "B.Cu")
		(net "GND")
	)
	(gr_poly
		(pts
			(arc
				(start 18.730214 -10.164318)
				(mid 18.363438 -10.164318)
				(end 18.730214 -10.164318)
			)
		)
		(stroke
			(width 0)
			(type solid)
		)
		(fill yes)
		(layer "B.Cu")
		(net "GND")
	)
	(gr_poly
		(pts
			(arc
				(start 18.732754 -9.424162)
				(mid 18.365978 -9.424162)
				(end 18.732754 -9.424162)
			)
		)
		(stroke
			(width 0)
			(type solid)
		)
		(fill yes)
		(layer "B.Cu")
		(net "GND")
	)
	(gr_poly
		(pts
			(arc
				(start 20.530058 -10.164318)
				(mid 20.163282 -10.164318)
				(end 20.530058 -10.164318)
			)
		)
		(stroke
			(width 0)
			(type solid)
		)
		(fill yes)
		(layer "B.Cu")
		(net "GND")
	)
	(gr_poly
		(pts
			(arc
				(start 20.532598 -9.424162)
				(mid 20.165822 -9.424162)
				(end 20.532598 -9.424162)
			)
		)
		(stroke
			(width 0)
			(type solid)
		)
		(fill yes)
		(layer "B.Cu")
		(net "GND")
	)
	(gr_poly
		(pts
			(arc
				(start 22.330156 -10.164318)
				(mid 21.96338 -10.164318)
				(end 22.330156 -10.164318)
			)
		)
		(stroke
			(width 0)
			(type solid)
		)
		(fill yes)
		(layer "B.Cu")
		(net "GND")
	)
	(gr_poly
		(pts
			(arc
				(start 22.332696 -9.424162)
				(mid 21.96592 -9.424162)
				(end 22.332696 -9.424162)
			)
		)
		(stroke
			(width 0)
			(type solid)
		)
		(fill yes)
		(layer "B.Cu")
		(net "GND")
	)
	(gr_poly
		(pts
			(arc
				(start 24.13 -10.164318)
				(mid 23.763224 -10.164318)
				(end 24.13 -10.164318)
			)
		)
		(stroke
			(width 0)
			(type solid)
		)
		(fill yes)
		(layer "B.Cu")
		(net "GND")
	)
	(gr_poly
		(pts
			(arc
				(start 24.13254 -9.424162)
				(mid 23.765764 -9.424162)
				(end 24.13254 -9.424162)
			)
		)
		(stroke
			(width 0)
			(type solid)
		)
		(fill yes)
		(layer "B.Cu")
		(net "GND")
	)
	(gr_poly
		(pts
			(arc
				(start 25.930098 -10.164318)
				(mid 25.563322 -10.164318)
				(end 25.930098 -10.164318)
			)
		)
		(stroke
			(width 0)
			(type solid)
		)
		(fill yes)
		(layer "B.Cu")
		(net "GND")
	)
	(gr_poly
		(pts
			(arc
				(start 25.932638 -9.424162)
				(mid 25.565862 -9.424162)
				(end 25.932638 -9.424162)
			)
		)
		(stroke
			(width 0)
			(type solid)
		)
		(fill yes)
		(layer "B.Cu")
		(net "GND")
	)
	(gr_poly
		(pts
			(arc
				(start 27.730196 -10.164318)
				(mid 27.36342 -10.164318)
				(end 27.730196 -10.164318)
			)
		)
		(stroke
			(width 0)
			(type solid)
		)
		(fill yes)
		(layer "B.Cu")
		(net "GND")
	)
	(gr_poly
		(pts
			(arc
				(start 27.732736 -9.424162)
				(mid 27.36596 -9.424162)
				(end 27.732736 -9.424162)
			)
		)
		(stroke
			(width 0)
			(type solid)
		)
		(fill yes)
		(layer "B.Cu")
		(net "GND")
	)
	(gr_poly
		(pts
			(arc
				(start 29.53004 -10.164318)
				(mid 29.163264 -10.164318)
				(end 29.53004 -10.164318)
			)
		)
		(stroke
			(width 0)
			(type solid)
		)
		(fill yes)
		(layer "B.Cu")
		(net "GND")
	)
	(gr_poly
		(pts
			(arc
				(start 29.53258 -9.424162)
				(mid 29.165804 -9.424162)
				(end 29.53258 -9.424162)
			)
		)
		(stroke
			(width 0)
			(type solid)
		)
		(fill yes)
		(layer "B.Cu")
		(net "GND")
	)
	(gr_poly
		(pts
			(arc
				(start 31.330138 -10.164318)
				(mid 30.963362 -10.164318)
				(end 31.330138 -10.164318)
			)
		)
		(stroke
			(width 0)
			(type solid)
		)
		(fill yes)
		(layer "B.Cu")
		(net "GND")
	)
	(gr_poly
		(pts
			(arc
				(start 31.332678 -9.424162)
				(mid 30.965902 -9.424162)
				(end 31.332678 -9.424162)
			)
		)
		(stroke
			(width 0)
			(type solid)
		)
		(fill yes)
		(layer "B.Cu")
		(net "GND")
	)
	(gr_poly
		(pts
			(arc
				(start 33.130236 -10.164318)
				(mid 32.76346 -10.164318)
				(end 33.130236 -10.164318)
			)
		)
		(stroke
			(width 0)
			(type solid)
		)
		(fill yes)
		(layer "B.Cu")
		(net "GND")
	)
	(gr_poly
		(pts
			(arc
				(start 33.132776 -9.424162)
				(mid 32.766 -9.424162)
				(end 33.132776 -9.424162)
			)
		)
		(stroke
			(width 0)
			(type solid)
		)
		(fill yes)
		(layer "B.Cu")
		(net "GND")
	)
	(gr_poly
		(pts
			(arc
				(start 38.640004 -10.164318)
				(mid 38.273228 -10.164318)
				(end 38.640004 -10.164318)
			)
		)
		(stroke
			(width 0)
			(type solid)
		)
		(fill yes)
		(layer "B.Cu")
		(net "GND")
	)
	(gr_poly
		(pts
			(arc
				(start 38.642544 -9.424162)
				(mid 38.275768 -9.424162)
				(end 38.642544 -9.424162)
			)
		)
		(stroke
			(width 0)
			(type solid)
		)
		(fill yes)
		(layer "B.Cu")
		(net "GND")
	)
	(gr_poly
		(pts
			(arc
				(start 40.440102 -10.164318)
				(mid 40.073326 -10.164318)
				(end 40.440102 -10.164318)
			)
		)
		(stroke
			(width 0)
			(type solid)
		)
		(fill yes)
		(layer "B.Cu")
		(net "GND")
	)
	(gr_poly
		(pts
			(arc
				(start 40.442642 -9.424162)
				(mid 40.075866 -9.424162)
				(end 40.442642 -9.424162)
			)
		)
		(stroke
			(width 0)
			(type solid)
		)
		(fill yes)
		(layer "B.Cu")
		(net "GND")
	)
	(gr_poly
		(pts
			(arc
				(start 42.2402 -10.164318)
				(mid 41.873424 -10.164318)
				(end 42.2402 -10.164318)
			)
		)
		(stroke
			(width 0)
			(type solid)
		)
		(fill yes)
		(layer "B.Cu")
		(net "GND")
	)
	(gr_poly
		(pts
			(arc
				(start 42.24274 -9.424162)
				(mid 41.875964 -9.424162)
				(end 42.24274 -9.424162)
			)
		)
		(stroke
			(width 0)
			(type solid)
		)
		(fill yes)
		(layer "B.Cu")
		(net "GND")
	)
	(gr_poly
		(pts
			(arc
				(start 44.040044 -10.164318)
				(mid 43.673268 -10.164318)
				(end 44.040044 -10.164318)
			)
		)
		(stroke
			(width 0)
			(type solid)
		)
		(fill yes)
		(layer "B.Cu")
		(net "GND")
	)
	(gr_poly
		(pts
			(arc
				(start 44.042584 -9.424162)
				(mid 43.675808 -9.424162)
				(end 44.042584 -9.424162)
			)
		)
		(stroke
			(width 0)
			(type solid)
		)
		(fill yes)
		(layer "B.Cu")
		(net "GND")
	)
	(gr_poly
		(pts
			(arc
				(start 45.840142 -10.164318)
				(mid 45.473366 -10.164318)
				(end 45.840142 -10.164318)
			)
		)
		(stroke
			(width 0)
			(type solid)
		)
		(fill yes)
		(layer "B.Cu")
		(net "GND")
	)
	(gr_poly
		(pts
			(arc
				(start 45.842682 -9.424162)
				(mid 45.475906 -9.424162)
				(end 45.842682 -9.424162)
			)
		)
		(stroke
			(width 0)
			(type solid)
		)
		(fill yes)
		(layer "B.Cu")
		(net "GND")
	)
	(gr_poly
		(pts
			(arc
				(start 49.85004 -10.164318)
				(mid 49.483264 -10.164318)
				(end 49.85004 -10.164318)
			)
		)
		(stroke
			(width 0)
			(type solid)
		)
		(fill yes)
		(layer "B.Cu")
		(net "GND")
	)
	(gr_poly
		(pts
			(arc
				(start 49.85258 -9.424162)
				(mid 49.485804 -9.424162)
				(end 49.85258 -9.424162)
			)
		)
		(stroke
			(width 0)
			(type solid)
		)
		(fill yes)
		(layer "B.Cu")
		(net "GND")
	)
	(gr_poly
		(pts
			(arc
				(start 51.650138 -10.164318)
				(mid 51.283362 -10.164318)
				(end 51.650138 -10.164318)
			)
		)
		(stroke
			(width 0)
			(type solid)
		)
		(fill yes)
		(layer "B.Cu")
		(net "GND")
	)
	(gr_poly
		(pts
			(arc
				(start 51.652678 -9.424162)
				(mid 51.285902 -9.424162)
				(end 51.652678 -9.424162)
			)
		)
		(stroke
			(width 0)
			(type solid)
		)
		(fill yes)
		(layer "B.Cu")
		(net "GND")
	)
	(gr_poly
		(pts
			(arc
				(start 53.450236 -10.164318)
				(mid 53.08346 -10.164318)
				(end 53.450236 -10.164318)
			)
		)
		(stroke
			(width 0)
			(type solid)
		)
		(fill yes)
		(layer "B.Cu")
		(net "GND")
	)
	(gr_poly
		(pts
			(arc
				(start 53.452776 -9.424162)
				(mid 53.086 -9.424162)
				(end 53.452776 -9.424162)
			)
		)
		(stroke
			(width 0)
			(type solid)
		)
		(fill yes)
		(layer "B.Cu")
		(net "GND")
	)
	(gr_poly
		(pts
			(arc
				(start 55.25008 -10.164318)
				(mid 54.883304 -10.164318)
				(end 55.25008 -10.164318)
			)
		)
		(stroke
			(width 0)
			(type solid)
		)
		(fill yes)
		(layer "B.Cu")
		(net "GND")
	)
	(gr_poly
		(pts
			(arc
				(start 55.25262 -9.424162)
				(mid 54.885844 -9.424162)
				(end 55.25262 -9.424162)
			)
		)
		(stroke
			(width 0)
			(type solid)
		)
		(fill yes)
		(layer "B.Cu")
		(net "GND")
	)
	(gr_poly
		(pts
			(arc
				(start 57.050178 -10.164318)
				(mid 56.683402 -10.164318)
				(end 57.050178 -10.164318)
			)
		)
		(stroke
			(width 0)
			(type solid)
		)
		(fill yes)
		(layer "B.Cu")
		(net "GND")
	)
	(gr_poly
		(pts
			(arc
				(start 57.052718 -9.424162)
				(mid 56.685942 -9.424162)
				(end 57.052718 -9.424162)
			)
		)
		(stroke
			(width 0)
			(type solid)
		)
		(fill yes)
		(layer "B.Cu")
		(net "GND")
	)
	(gr_poly
		(pts
			(arc
				(start 58.850022 -10.164318)
				(mid 58.483246 -10.164318)
				(end 58.850022 -10.164318)
			)
		)
		(stroke
			(width 0)
			(type solid)
		)
		(fill yes)
		(layer "B.Cu")
		(net "GND")
	)
	(gr_poly
		(pts
			(arc
				(start 58.852562 -9.424162)
				(mid 58.485786 -9.424162)
				(end 58.852562 -9.424162)
			)
		)
		(stroke
			(width 0)
			(type solid)
		)
		(fill yes)
		(layer "B.Cu")
		(net "GND")
	)
	(gr_poly
		(pts
			(xy 107.81792 -415.836608) (xy 107.81792 -413.789368) (xy 108.03382 -413.573468) (xy 109.78388 -413.573468)
			(xy 110.08106 -413.276288) (xy 110.08106 -412.773368) (xy 110.02518 -412.717488) (xy 109.52226 -412.717488)
			(xy 109.31652 -412.511748) (xy 109.31652 -411.513528) (xy 109.5756 -411.254448) (xy 110.486444 -411.254448)
			(xy 110.752128 -411.520132) (xy 112.176306 -411.520132) (xy 112.318546 -411.377892) (xy 112.318546 -410.855922)
			(xy 112.8649 -410.309568) (xy 112.8649 -410.012388) (xy 112.63122 -409.778708) (xy 109.91088 -409.778708)
			(xy 109.10824 -410.581348) (xy 109.10824 -410.726128) (xy 108.51388 -411.320488) (xy 108.2929 -411.320488)
			(xy 105.97388 -413.639508) (xy 105.97388 -414.012888) (xy 105.49382 -414.492948) (xy 105.46842 -414.492948)
			(xy 105.46842 -415.955988) (xy 105.53446 -416.022028) (xy 107.6325 -416.022028)
		)
		(stroke
			(width 0)
			(type solid)
		)
		(fill yes)
		(layer "B.Cu")
		(net "P3V3_9ZXL045_VDD")
	)
	(gr_poly
		(pts
			(xy 258.849876 -101.751384) (xy 258.849876 -101.330506) (xy 258.852416 -101.327966) (xy 258.852416 -96.127316)
			(xy 258.84632 -96.12122) (xy 257.919728 -96.12122) (xy 257.048 -96.992948) (xy 256.749296 -96.992948)
			(xy 256.749296 -97.120456) (xy 255.396492 -97.120456) (xy 255.27 -97.246948) (xy 254.127 -97.246948)
			(xy 253.996444 -97.116392)
			(arc
				(start 253.97587 -97.116138)
				(mid 253.870397 -97.08895)
				(end 253.789942 -97.015554)
			)
			(xy 253.774956 -96.992948) (xy 252.603 -96.992948) (xy 252.349 -97.246948) (xy 252.338332 -97.246948)
			(xy 252.338332 -98.778314) (xy 252.337824 -98.778568) (xy 252.337824 -101.930708) (xy 252.525276 -102.11816)
			(xy 252.902974 -102.11816) (xy 252.966474 -102.181914) (xy 258.419346 -102.181914)
		)
		(stroke
			(width 0)
			(type solid)
		)
		(fill yes)
		(layer "B.Cu")
		(net "GND")
	)
	(gr_poly
		(pts
			(arc
				(start 393.230354 -10.16508)
				(mid 392.863578 -10.16508)
				(end 393.230354 -10.16508)
			)
		)
		(stroke
			(width 0)
			(type solid)
		)
		(fill yes)
		(layer "B.Cu")
		(net "GND")
	)
	(gr_poly
		(pts
			(arc
				(start 393.230354 -9.424924)
				(mid 392.863578 -9.424924)
				(end 393.230354 -9.424924)
			)
		)
		(stroke
			(width 0)
			(type solid)
		)
		(fill yes)
		(layer "B.Cu")
		(net "GND")
	)
	(gr_poly
		(pts
			(arc
				(start 395.030198 -10.16508)
				(mid 394.663422 -10.16508)
				(end 395.030198 -10.16508)
			)
		)
		(stroke
			(width 0)
			(type solid)
		)
		(fill yes)
		(layer "B.Cu")
		(net "GND")
	)
	(gr_poly
		(pts
			(arc
				(start 395.030198 -9.424924)
				(mid 394.663422 -9.424924)
				(end 395.030198 -9.424924)
			)
		)
		(stroke
			(width 0)
			(type solid)
		)
		(fill yes)
		(layer "B.Cu")
		(net "GND")
	)
	(gr_poly
		(pts
			(arc
				(start 396.830296 -10.16508)
				(mid 396.46352 -10.16508)
				(end 396.830296 -10.16508)
			)
		)
		(stroke
			(width 0)
			(type solid)
		)
		(fill yes)
		(layer "B.Cu")
		(net "GND")
	)
	(gr_poly
		(pts
			(arc
				(start 396.830296 -9.424924)
				(mid 396.46352 -9.424924)
				(end 396.830296 -9.424924)
			)
		)
		(stroke
			(width 0)
			(type solid)
		)
		(fill yes)
		(layer "B.Cu")
		(net "GND")
	)
	(gr_poly
		(pts
			(arc
				(start 398.63014 -10.16508)
				(mid 398.263364 -10.16508)
				(end 398.63014 -10.16508)
			)
		)
		(stroke
			(width 0)
			(type solid)
		)
		(fill yes)
		(layer "B.Cu")
		(net "GND")
	)
	(gr_poly
		(pts
			(arc
				(start 398.63014 -9.424924)
				(mid 398.263364 -9.424924)
				(end 398.63014 -9.424924)
			)
		)
		(stroke
			(width 0)
			(type solid)
		)
		(fill yes)
		(layer "B.Cu")
		(net "GND")
	)
	(gr_poly
		(pts
			(arc
				(start 400.430238 -10.16508)
				(mid 400.063462 -10.16508)
				(end 400.430238 -10.16508)
			)
		)
		(stroke
			(width 0)
			(type solid)
		)
		(fill yes)
		(layer "B.Cu")
		(net "GND")
	)
	(gr_poly
		(pts
			(arc
				(start 400.430238 -9.424924)
				(mid 400.063462 -9.424924)
				(end 400.430238 -9.424924)
			)
		)
		(stroke
			(width 0)
			(type solid)
		)
		(fill yes)
		(layer "B.Cu")
		(net "GND")
	)
	(gr_poly
		(pts
			(arc
				(start 402.230336 -10.16508)
				(mid 401.86356 -10.16508)
				(end 402.230336 -10.16508)
			)
		)
		(stroke
			(width 0)
			(type solid)
		)
		(fill yes)
		(layer "B.Cu")
		(net "GND")
	)
	(gr_poly
		(pts
			(arc
				(start 402.230336 -9.424924)
				(mid 401.86356 -9.424924)
				(end 402.230336 -9.424924)
			)
		)
		(stroke
			(width 0)
			(type solid)
		)
		(fill yes)
		(layer "B.Cu")
		(net "GND")
	)
	(gr_poly
		(pts
			(arc
				(start 404.03018 -10.16508)
				(mid 403.663404 -10.16508)
				(end 404.03018 -10.16508)
			)
		)
		(stroke
			(width 0)
			(type solid)
		)
		(fill yes)
		(layer "B.Cu")
		(net "GND")
	)
	(gr_poly
		(pts
			(arc
				(start 404.03018 -9.424924)
				(mid 403.663404 -9.424924)
				(end 404.03018 -9.424924)
			)
		)
		(stroke
			(width 0)
			(type solid)
		)
		(fill yes)
		(layer "B.Cu")
		(net "GND")
	)
	(gr_poly
		(pts
			(arc
				(start 405.830278 -10.16508)
				(mid 405.463502 -10.16508)
				(end 405.830278 -10.16508)
			)
		)
		(stroke
			(width 0)
			(type solid)
		)
		(fill yes)
		(layer "B.Cu")
		(net "GND")
	)
	(gr_poly
		(pts
			(arc
				(start 405.830278 -9.424924)
				(mid 405.463502 -9.424924)
				(end 405.830278 -9.424924)
			)
		)
		(stroke
			(width 0)
			(type solid)
		)
		(fill yes)
		(layer "B.Cu")
		(net "GND")
	)
	(gr_poly
		(pts
			(arc
				(start 407.630376 -10.16508)
				(mid 407.2636 -10.16508)
				(end 407.630376 -10.16508)
			)
		)
		(stroke
			(width 0)
			(type solid)
		)
		(fill yes)
		(layer "B.Cu")
		(net "GND")
	)
	(gr_poly
		(pts
			(arc
				(start 407.630376 -9.424924)
				(mid 407.2636 -9.424924)
				(end 407.630376 -9.424924)
			)
		)
		(stroke
			(width 0)
			(type solid)
		)
		(fill yes)
		(layer "B.Cu")
		(net "GND")
	)
	(gr_poly
		(pts
			(arc
				(start 413.140144 -10.16508)
				(mid 412.773368 -10.16508)
				(end 413.140144 -10.16508)
			)
		)
		(stroke
			(width 0)
			(type solid)
		)
		(fill yes)
		(layer "B.Cu")
		(net "GND")
	)
	(gr_poly
		(pts
			(arc
				(start 413.140144 -9.424924)
				(mid 412.773368 -9.424924)
				(end 413.140144 -9.424924)
			)
		)
		(stroke
			(width 0)
			(type solid)
		)
		(fill yes)
		(layer "B.Cu")
		(net "GND")
	)
	(gr_poly
		(pts
			(arc
				(start 414.940242 -10.16508)
				(mid 414.573466 -10.16508)
				(end 414.940242 -10.16508)
			)
		)
		(stroke
			(width 0)
			(type solid)
		)
		(fill yes)
		(layer "B.Cu")
		(net "GND")
	)
	(gr_poly
		(pts
			(arc
				(start 414.940242 -9.424924)
				(mid 414.573466 -9.424924)
				(end 414.940242 -9.424924)
			)
		)
		(stroke
			(width 0)
			(type solid)
		)
		(fill yes)
		(layer "B.Cu")
		(net "GND")
	)
	(gr_poly
		(pts
			(arc
				(start 416.74034 -10.16508)
				(mid 416.373564 -10.16508)
				(end 416.74034 -10.16508)
			)
		)
		(stroke
			(width 0)
			(type solid)
		)
		(fill yes)
		(layer "B.Cu")
		(net "GND")
	)
	(gr_poly
		(pts
			(arc
				(start 416.74034 -9.424924)
				(mid 416.373564 -9.424924)
				(end 416.74034 -9.424924)
			)
		)
		(stroke
			(width 0)
			(type solid)
		)
		(fill yes)
		(layer "B.Cu")
		(net "GND")
	)
	(gr_poly
		(pts
			(arc
				(start 418.540184 -10.16508)
				(mid 418.173408 -10.16508)
				(end 418.540184 -10.16508)
			)
		)
		(stroke
			(width 0)
			(type solid)
		)
		(fill yes)
		(layer "B.Cu")
		(net "GND")
	)
	(gr_poly
		(pts
			(arc
				(start 418.540184 -9.424924)
				(mid 418.173408 -9.424924)
				(end 418.540184 -9.424924)
			)
		)
		(stroke
			(width 0)
			(type solid)
		)
		(fill yes)
		(layer "B.Cu")
		(net "GND")
	)
	(gr_poly
		(pts
			(arc
				(start 420.340282 -10.16508)
				(mid 419.973506 -10.16508)
				(end 420.340282 -10.16508)
			)
		)
		(stroke
			(width 0)
			(type solid)
		)
		(fill yes)
		(layer "B.Cu")
		(net "GND")
	)
	(gr_poly
		(pts
			(arc
				(start 420.340282 -9.424924)
				(mid 419.973506 -9.424924)
				(end 420.340282 -9.424924)
			)
		)
		(stroke
			(width 0)
			(type solid)
		)
		(fill yes)
		(layer "B.Cu")
		(net "GND")
	)
	(gr_poly
		(pts
			(arc
				(start 424.35018 -10.16508)
				(mid 423.983404 -10.16508)
				(end 424.35018 -10.16508)
			)
		)
		(stroke
			(width 0)
			(type solid)
		)
		(fill yes)
		(layer "B.Cu")
		(net "GND")
	)
	(gr_poly
		(pts
			(arc
				(start 424.35018 -9.424924)
				(mid 423.983404 -9.424924)
				(end 424.35018 -9.424924)
			)
		)
		(stroke
			(width 0)
			(type solid)
		)
		(fill yes)
		(layer "B.Cu")
		(net "GND")
	)
	(gr_poly
		(pts
			(arc
				(start 426.150278 -10.16508)
				(mid 425.783502 -10.16508)
				(end 426.150278 -10.16508)
			)
		)
		(stroke
			(width 0)
			(type solid)
		)
		(fill yes)
		(layer "B.Cu")
		(net "GND")
	)
	(gr_poly
		(pts
			(arc
				(start 426.150278 -9.424924)
				(mid 425.783502 -9.424924)
				(end 426.150278 -9.424924)
			)
		)
		(stroke
			(width 0)
			(type solid)
		)
		(fill yes)
		(layer "B.Cu")
		(net "GND")
	)
	(gr_poly
		(pts
			(arc
				(start 427.950376 -10.16508)
				(mid 427.5836 -10.16508)
				(end 427.950376 -10.16508)
			)
		)
		(stroke
			(width 0)
			(type solid)
		)
		(fill yes)
		(layer "B.Cu")
		(net "GND")
	)
	(gr_poly
		(pts
			(arc
				(start 427.950376 -9.424924)
				(mid 427.5836 -9.424924)
				(end 427.950376 -9.424924)
			)
		)
		(stroke
			(width 0)
			(type solid)
		)
		(fill yes)
		(layer "B.Cu")
		(net "GND")
	)
	(gr_poly
		(pts
			(arc
				(start 429.75022 -10.16508)
				(mid 429.383444 -10.16508)
				(end 429.75022 -10.16508)
			)
		)
		(stroke
			(width 0)
			(type solid)
		)
		(fill yes)
		(layer "B.Cu")
		(net "GND")
	)
	(gr_poly
		(pts
			(arc
				(start 429.75022 -9.424924)
				(mid 429.383444 -9.424924)
				(end 429.75022 -9.424924)
			)
		)
		(stroke
			(width 0)
			(type solid)
		)
		(fill yes)
		(layer "B.Cu")
		(net "GND")
	)
	(gr_poly
		(pts
			(arc
				(start 431.430684 -10.153396)
				(mid 431.063908 -10.153396)
				(end 431.430684 -10.153396)
			)
		)
		(stroke
			(width 0)
			(type solid)
		)
		(fill yes)
		(layer "B.Cu")
		(net "GND")
	)
	(gr_poly
		(pts
			(xy 65.757552 -179.331874) (xy 69.258434 -179.331874) (xy 69.42836 -179.161948) (xy 69.42836 -178.794664)
			(arc
				(start 67.856608 -178.794664)
				(mid 67.784407 -178.764757)
				(end 67.7545 -178.692556)
			)
			(arc
				(start 67.7545 -177.117756)
				(mid 67.784407 -177.045555)
				(end 67.856608 -177.015648)
			)
			(xy 69.42836 -177.015648) (xy 69.42836 -176.035208) (xy 67.2846 -173.891448) (xy 67.2846 -172.240448)
			(xy 65.10782 -170.063668) (xy 62.35192 -170.063668) (xy 62.1284 -170.287188) (xy 62.1284 -176.654968)
			(xy 61.862208 -176.92116) (xy 61.862208 -179.711096) (xy 62.04966 -179.898548) (xy 65.190878 -179.898548)
		)
		(stroke
			(width 0)
			(type solid)
		)
		(fill yes)
		(layer "B.Cu")
		(net "PVCCFA_EHV_CPU1")
	)
	(gr_poly
		(pts
			(arc
				(start 95.685356 -360.42219)
				(mid 95.704879 -360.418289)
				(end 95.721424 -360.407204)
			)
			(arc
				(start 96.743012 -359.385616)
				(mid 96.754123 -359.369082)
				(end 96.757998 -359.349548)
			)
			(arc
				(start 96.757998 -355.228652)
				(mid 96.754097 -355.209129)
				(end 96.743012 -355.192584)
			)
			(arc
				(start 96.623886 -355.073458)
				(mid 96.607352 -355.062347)
				(end 96.587818 -355.058472)
			)
			(arc
				(start 87.443818 -355.058472)
				(mid 87.424295 -355.062373)
				(end 87.40775 -355.073458)
			)
			(arc
				(start 87.247984 -355.233224)
				(mid 87.236873 -355.249758)
				(end 87.232998 -355.269292)
			)
			(arc
				(start 87.232998 -359.999788)
				(mid 87.236899 -360.019311)
				(end 87.247984 -360.035856)
			)
			(arc
				(start 87.619332 -360.407204)
				(mid 87.635866 -360.418315)
				(end 87.6554 -360.42219)
			)
		)
		(stroke
			(width 0)
			(type solid)
		)
		(fill yes)
		(layer "B.Cu")
		(net "P12V_AUX")
	)
	(gr_poly
		(pts
			(xy 108.233972 -237.444534)
			(arc
				(start 108.233972 -235.392468)
				(mid 108.201468 -235.317981)
				(end 108.124752 -235.291122)
			)
			(arc
				(start 108.0897 -235.292392)
				(mid 107.987971 -235.280944)
				(end 107.891326 -235.24718)
			)
			(xy 107.880912 -235.2421)
			(arc
				(start 107.39755 -235.2421)
				(mid 107.259016 -235.33533)
				(end 107.09529 -235.368084)
			)
			(xy 107.003088 -235.368084) (xy 106.570526 -235.800392) (xy 106.570526 -236.45114) (xy 106.423206 -236.59846)
			(xy 103.273606 -236.59846) (xy 103.222806 -236.64926) (xy 103.222806 -237.384082) (xy 103.56215 -237.723172)
			(xy 107.955334 -237.723172)
		)
		(stroke
			(width 0)
			(type solid)
		)
		(fill yes)
		(layer "B.Cu")
		(net "PVNN_MAIN_CPU1")
	)
	(gr_poly
		(pts
			(xy 119.51081 -237.26648) (xy 119.51081 -236.47654) (xy 120.05945 -235.9279) (xy 120.05945 -234.93222)
			(xy 119.88419 -234.75696) (xy 118.046754 -234.75696)
			(arc
				(start 117.86489 -234.938824)
				(mid 117.767917 -235.003526)
				(end 117.653562 -235.0262)
			)
			(xy 116.32311 -235.0262) (xy 116.32311 -235.152946)
			(arc
				(start 116.327174 -235.162598)
				(mid 116.35523 -235.251356)
				(end 116.364766 -235.343954)
			)
			(arc
				(start 116.364766 -235.343954)
				(mid 116.355248 -235.436556)
				(end 116.327174 -235.52531)
			)
			(xy 116.32311 -235.534962) (xy 116.32311 -235.93806) (xy 116.38407 -235.99902) (xy 117.14099 -235.99902)
			(xy 117.37975 -236.23778) (xy 117.37975 -237.16488) (xy 117.5385 -237.32363) (xy 119.45366 -237.32363)
		)
		(stroke
			(width 0)
			(type solid)
		)
		(fill yes)
		(layer "B.Cu")
		(net "PVCCINFAON_CPU1")
	)
	(gr_poly
		(pts
			(arc
				(start 445.911224 -391.476484)
				(mid 445.930747 -391.472583)
				(end 445.947292 -391.461498)
			)
			(arc
				(start 446.446656 -390.96188)
				(mid 446.457767 -390.945346)
				(end 446.461642 -390.925812)
			)
			(arc
				(start 446.461642 -379.988572)
				(mid 446.457741 -379.969049)
				(end 446.446656 -379.952504)
			)
			(arc
				(start 446.178432 -379.68428)
				(mid 446.161898 -379.673169)
				(end 446.142364 -379.669294)
			)
			(arc
				(start 437.639206 -379.669294)
				(mid 437.619683 -379.673195)
				(end 437.603138 -379.68428)
			)
			(arc
				(start 437.567832 -379.719586)
				(mid 437.556721 -379.73612)
				(end 437.552846 -379.755654)
			)
			(arc
				(start 437.552846 -390.925812)
				(mid 437.556747 -390.945335)
				(end 437.567832 -390.96188)
			)
			(arc
				(start 438.067196 -391.461498)
				(mid 438.08373 -391.472609)
				(end 438.103264 -391.476484)
			)
		)
		(stroke
			(width 0)
			(type solid)
		)
		(fill yes)
		(layer "B.Cu")
		(net "P5V_AUX")
	)
	(gr_poly
		(pts
			(xy 106.23169 -246.74576) (xy 106.23169 -246.494808) (xy 106.454956 -246.271542) (xy 106.586528 -246.271542)
			(xy 106.594402 -246.271288) (xy 107.961938 -246.271288) (xy 108.106972 -246.126508) (xy 108.58754 -245.64594)
			(xy 108.587794 -245.64594) (xy 108.651548 -245.581932) (xy 108.651548 -244.680232) (xy 108.528104 -244.556788)
			(xy 108.27893 -244.556788) (xy 108.24464 -244.591078) (xy 108.197142 -244.63883) (xy 108.193332 -244.642386)
			(xy 108.193078 -244.64264) (xy 108.107734 -244.727984) (xy 103.159052 -244.727984) (xy 103.082344 -244.651276)
			(xy 103.082344 -244.64772) (xy 102.98811 -244.55374) (xy 102.77475 -244.55374) (xy 102.60965 -244.71884)
			(xy 102.60965 -246.09298) (xy 102.637336 -246.120412) (xy 104.717596 -246.120412) (xy 104.83723 -246.2403)
			(xy 104.84231 -246.2403) (xy 105.06329 -246.46128) (xy 105.06329 -246.78386) (xy 105.11409 -246.83466)
			(xy 106.14279 -246.83466)
		)
		(stroke
			(width 0)
			(type solid)
		)
		(fill yes)
		(layer "B.Cu")
		(net "GND")
	)
	(gr_poly
		(pts
			(xy 306.76723 -250.90628) (xy 310.460898 -250.90628)
			(arc
				(start 310.472836 -250.872752)
				(mid 310.903874 -250.569148)
				(end 311.334912 -250.872752)
			)
			(xy 311.34685 -250.90628) (xy 314.640468 -250.90628) (xy 314.7568 -250.789948) (xy 314.7568 -249.062748)
			(xy 314.599828 -248.905776) (xy 306.359814 -248.905776) (xy 306.232814 -249.032776) (xy 306.232814 -250.851162)
			(xy 306.3494 -250.967748) (xy 306.706016 -250.967748)
		)
		(stroke
			(width 0)
			(type solid)
		)
		(fill yes)
		(layer "B.Cu")
		(net "GND")
	)
	(gr_poly
		(pts
			(xy 366.581944 -243.032026) (xy 366.581944 -242.717066) (xy 366.848644 -242.450112) (xy 366.848644 -241.15649)
			(xy 366.692688 -241.00028) (xy 363.591094 -241.00028) (xy 363.52734 -240.936526) (xy 363.526324 -240.936526)
			(xy 363.46892 -240.878868) (xy 363.190028 -240.878868) (xy 363.158532 -240.910618) (xy 363.158532 -242.413536)
			(xy 363.28223 -242.537488) (xy 365.17707 -242.537488) (xy 365.303816 -242.664234)
			(arc
				(start 365.31042 -242.66779)
				(mid 365.447217 -242.798699)
				(end 365.497618 -242.981226)
			)
			(arc
				(start 365.496602 -243.006626)
				(mid 365.523538 -243.08319)
				(end 365.597948 -243.115592)
			)
			(xy 366.498632 -243.115592)
		)
		(stroke
			(width 0)
			(type solid)
		)
		(fill yes)
		(layer "B.Cu")
		(net "GND")
	)
	(gr_poly
		(pts
			(xy 369.172744 -261.950708)
			(arc
				(start 369.172744 -261.817866)
				(mid 369.19045 -261.716763)
				(end 369.241324 -261.62762)
			)
			(xy 369.241324 -261.40791)
			(arc
				(start 369.236498 -261.39775)
				(mid 369.210727 -261.323218)
				(end 369.201954 -261.244842)
			)
			(arc
				(start 369.201954 -261.244842)
				(mid 369.210688 -261.166457)
				(end 369.236498 -261.091934)
			)
			(xy 369.241324 -261.081774) (xy 369.241324 -260.298946) (xy 369.174014 -260.231636) (xy 368.709194 -260.231636)
			(xy 368.357404 -259.879846) (xy 367.295684 -259.879846) (xy 367.234724 -259.940806) (xy 367.234724 -261.447026)
			(xy 367.285016 -261.497572) (xy 367.540794 -261.497572) (xy 367.863628 -261.820406) (xy 368.415824 -261.820406)
			(xy 368.707924 -262.112506) (xy 368.707924 -262.264906) (xy 368.758724 -262.315706) (xy 368.807746 -262.315706)
		)
		(stroke
			(width 0)
			(type solid)
		)
		(fill yes)
		(layer "B.Cu")
		(net "PVCCINFAON_CPU0")
	)
	(gr_poly
		(pts
			(arc
				(start 430.404016 -130.964178)
				(mid 429.996092 -130.964178)
				(end 430.404016 -130.964178)
			)
		)
		(stroke
			(width 0)
			(type solid)
		)
		(fill yes)
		(layer "B.Cu")
		(net "GND")
	)
	(gr_poly
		(pts
			(arc
				(start 431.204116 -130.964178)
				(mid 430.796192 -130.964178)
				(end 431.204116 -130.964178)
			)
		)
		(stroke
			(width 0)
			(type solid)
		)
		(fill yes)
		(layer "B.Cu")
		(net "GND")
	)
	(gr_poly
		(pts
			(xy 65.97904 -20.528788) (xy 65.97904 -13.960348) (xy 64.64808 -13.960348) (xy 64.147954 -14.460474)
			(xy 64.147954 -17.178274) (xy 63.813182 -17.513046)
			(arc
				(start 63.825628 -17.544034)
				(mid 63.845591 -17.612879)
				(end 63.852298 -17.684242)
			)
			(arc
				(start 63.852298 -17.684242)
				(mid 63.740557 -17.954009)
				(end 63.47079 -18.06575)
			)
			(arc
				(start 63.47079 -18.06575)
				(mid 63.399431 -18.059017)
				(end 63.330582 -18.03908)
			)
			(xy 63.299594 -18.026634) (xy 63.25108 -18.075148) (xy 62.64148 -18.075148) (xy 62.41288 -18.303748)
			(xy 62.41288 -20.869148) (xy 62.61608 -21.072348) (xy 65.43548 -21.072348)
		)
		(stroke
			(width 0)
			(type solid)
		)
		(fill yes)
		(layer "B.Cu")
		(net "GND")
	)
	(gr_poly
		(pts
			(xy 41.010332 -372.433596)
			(arc
				(start 41.010332 -366.611916)
				(mid 41.021443 -366.595382)
				(end 41.025318 -366.575848)
			)
			(arc
				(start 41.025318 -360.969052)
				(mid 41.021417 -360.949529)
				(end 41.010332 -360.932984)
			)
			(xy 40.877744 -360.800396) (xy 40.870632 -360.79303) (xy 40.851836 -360.78541)
			(arc
				(start 36.86048 -360.78541)
				(mid 36.840957 -360.781509)
				(end 36.824412 -360.770424)
			)
			(arc
				(start 33.882584 -357.828596)
				(mid 33.871473 -357.812062)
				(end 33.867598 -357.792528)
			)
			(arc
				(start 33.867598 -338.998052)
				(mid 33.863697 -338.978529)
				(end 33.852612 -338.961984)
			)
			(xy 32.726884 -337.836256) (xy 32.719772 -337.82889) (xy 32.700976 -337.82127) (xy 15.88643 -337.82127)
			(xy 15.52448 -338.18322) (xy 15.52448 -340.832948) (xy 18.49628 -343.804748) (xy 18.49628 -365.928148)
			(xy 18.49628 -371.752368) (xy 19.72818 -372.984268) (xy 40.45966 -372.984268)
		)
		(stroke
			(width 0)
			(type solid)
		)
		(fill yes)
		(layer "B.Cu")
		(net "P12V_AUX")
	)
	(gr_poly
		(pts
			(xy 118.558564 -243.115592) (xy 118.64213 -243.03228) (xy 118.64213 -242.71732) (xy 118.876064 -242.483132)
			(xy 118.876064 -241.113564) (xy 118.69928 -240.93678) (xy 115.58651 -240.93678) (xy 115.528852 -240.879376)
			(xy 115.51031 -240.86058) (xy 115.26901 -240.86058) (xy 115.250468 -240.879376) (xy 115.175284 -240.95456)
			(xy 115.175284 -242.38458) (xy 115.33124 -242.540536) (xy 117.110002 -242.540536) (xy 117.117876 -242.54079)
			(xy 117.23624 -242.54079) (xy 117.32133 -242.62588) (xy 117.321584 -242.626134) (xy 117.325902 -242.630198)
			(xy 117.355874 -242.660424)
			(arc
				(start 117.36324 -242.66398)
				(mid 117.505285 -242.795297)
				(end 117.557804 -242.98148)
			)
			(arc
				(start 117.557804 -242.98148)
				(mid 117.555819 -243.018772)
				(end 117.54993 -243.055648)
			)
			(xy 117.544342 -243.082572) (xy 117.620796 -243.158772) (xy 118.515384 -243.158772)
		)
		(stroke
			(width 0)
			(type solid)
		)
		(fill yes)
		(layer "B.Cu")
		(net "GND")
	)
	(gr_poly
		(pts
			(xy 326.70242 -32.253428) (xy 326.70242 -31.360872) (xy 324.038976 -28.697428)
			(arc
				(start 323.00164 -29.735018)
				(mid 322.881622 -29.815275)
				(end 322.74002 -29.843476)
			)
			(xy 322.465446 -29.843476) (xy 322.251578 -30.05709)
			(arc
				(start 322.248784 -30.072584)
				(mid 322.122883 -30.310157)
				(end 321.88531 -30.436058)
			)
			(xy 321.869816 -30.438852) (xy 321.5005 -30.808168) (xy 321.5005 -31.72714)
			(arc
				(start 323.200522 -33.426908)
				(mid 323.280779 -33.546926)
				(end 323.30898 -33.688528)
			)
			(xy 323.30898 -33.929066) (xy 323.990462 -34.610548) (xy 324.3453 -34.610548)
		)
		(stroke
			(width 0)
			(type solid)
		)
		(fill yes)
		(layer "B.Cu")
		(net "GND")
	)
	(gr_poly
		(pts
			(xy 339.006688 -342.59647) (xy 339.006688 -341.429594) (xy 338.962238 -341.385144) (xy 337.266788 -341.385144)
			(xy 337.266788 -341.436198)
			(arc
				(start 337.266788 -341.43823)
				(mid 336.88528 -341.819738)
				(end 336.503772 -341.43823)
			)
			(xy 336.503772 -341.436198) (xy 336.503772 -341.385144) (xy 336.407506 -341.385144) (xy 336.31378 -341.47887)
			(xy 336.31378 -342.68283) (xy 336.4738 -342.84285) (xy 338.760308 -342.84285)
		)
		(stroke
			(width 0)
			(type solid)
		)
		(fill yes)
		(layer "B.Cu")
		(net "GND")
	)
	(gr_poly
		(pts
			(xy 347.1672 -339.186266) (xy 347.1672 -338.01939) (xy 347.12275 -337.97494) (xy 345.4273 -337.97494)
			(xy 345.4273 -338.025994)
			(arc
				(start 345.4273 -338.028026)
				(mid 345.045792 -338.409534)
				(end 344.664284 -338.028026)
			)
			(xy 344.664284 -338.025994) (xy 344.664284 -337.97494) (xy 344.568018 -337.97494) (xy 344.474292 -338.068666)
			(xy 344.474292 -339.272626) (xy 344.496136 -339.294216) (xy 347.058996 -339.294216)
		)
		(stroke
			(width 0)
			(type solid)
		)
		(fill yes)
		(layer "B.Cu")
		(net "GND")
	)
	(gr_poly
		(pts
			(xy 355.327712 -339.186266) (xy 355.327712 -338.01939) (xy 355.283262 -337.97494) (xy 353.587812 -337.97494)
			(xy 353.587812 -338.025994)
			(arc
				(start 353.587812 -338.028026)
				(mid 353.206304 -338.409534)
				(end 352.824796 -338.028026)
			)
			(xy 352.824796 -338.025994) (xy 352.824796 -337.97494) (xy 352.72853 -337.97494) (xy 352.634804 -338.068666)
			(xy 352.634804 -339.272626) (xy 352.794824 -339.432646) (xy 355.081332 -339.432646)
		)
		(stroke
			(width 0)
			(type solid)
		)
		(fill yes)
		(layer "B.Cu")
		(net "GND")
	)
	(gr_poly
		(pts
			(xy 363.488224 -339.186266) (xy 363.488224 -338.01939) (xy 363.443774 -337.97494) (xy 361.748324 -337.97494)
			(xy 361.748324 -338.025994)
			(arc
				(start 361.748324 -338.028026)
				(mid 361.366816 -338.409534)
				(end 360.985308 -338.028026)
			)
			(xy 360.985308 -338.025994) (xy 360.985308 -337.97494) (xy 360.889042 -337.97494) (xy 360.795316 -338.068666)
			(xy 360.795316 -339.272626) (xy 360.955336 -339.432646) (xy 363.241844 -339.432646)
		)
		(stroke
			(width 0)
			(type solid)
		)
		(fill yes)
		(layer "B.Cu")
		(net "GND")
	)
	(gr_poly
		(pts
			(xy 19.20748 -101.91496) (xy 19.20748 -97.592388) (xy 19.05508 -97.439988) (xy 16.59128 -97.439988)
			(xy 16.36268 -97.668588) (xy 16.36268 -101.173788) (xy 16.15948 -101.376988) (xy 12.27328 -101.376988)
			(xy 11.79068 -100.894388) (xy 11.79068 -97.163128) (xy 11.64082 -97.013268) (xy 10.19556 -97.013268)
			(xy 10.106152 -97.102676) (xy 10.610088 -97.606358)
			(arc
				(start 10.610088 -97.968562)
				(mid 10.85646 -98.374708)
				(end 10.610088 -98.780854)
			)
			(xy 10.610088 -101.081078) (xy 10.075926 -101.614986) (xy 10.075926 -102.413562) (xy 10.487152 -102.824788)
			(xy 18.297652 -102.824788)
		)
		(stroke
			(width 0)
			(type solid)
		)
		(fill yes)
		(layer "B.Cu")
		(net "P3V3_AUX_USB_HUB")
	)
	(gr_poly
		(pts
			(xy 66.73088 -8.092948) (xy 66.73088 -7.147306) (xy 66.406522 -6.822948) (xy 63.035434 -6.822948)
			(arc
				(start 63.030608 -6.868414)
				(mid 62.881635 -7.160595)
				(end 62.57544 -7.278116)
			)
			(arc
				(start 62.57544 -7.278116)
				(mid 62.395978 -7.241466)
				(end 62.24524 -7.1374)
			)
			(arc
				(start 62.24524 -7.1374)
				(mid 62.172912 -7.106084)
				(end 62.099952 -7.135876)
			)
			(xy 61.14288 -8.092948) (xy 61.14288 -8.727948) (xy 61.269372 -8.85444) (xy 64.86271 -8.85444) (xy 64.862964 -8.854948)
			(xy 65.96888 -8.854948)
		)
		(stroke
			(width 0)
			(type solid)
		)
		(fill yes)
		(layer "B.Cu")
		(net "GND")
	)
	(gr_poly
		(pts
			(xy 175.59274 -115.991132) (xy 175.59274 -115.892072) (xy 175.295052 -115.594638) (xy 175.295052 -115.523772)
			(xy 175.21682 -115.523772) (xy 175.16094 -115.467892) (xy 175.16094 -115.288568) (xy 174.99838 -115.126008)
			(xy 174.99838 -114.827812) (xy 175.16094 -114.665252)
			(arc
				(start 175.16094 -114.443002)
				(mid 175.107889 -114.394807)
				(end 175.066452 -114.336322)
			)
			(arc
				(start 175.066452 -114.336322)
				(mid 174.975363 -114.284337)
				(end 174.886874 -114.34064)
			)
			(arc
				(start 174.886874 -114.34064)
				(mid 174.770543 -114.47675)
				(end 174.603918 -114.542316)
			)
			(xy 174.586646 -114.544602) (xy 174.34306 -114.788188) (xy 174.34306 -115.089432) (xy 175.33112 -116.077492)
			(xy 175.50638 -116.077492)
		)
		(stroke
			(width 0)
			(type solid)
		)
		(fill yes)
		(layer "B.Cu")
		(net "P3V3_AUX_FPGA_VCCIO0")
	)
	(gr_poly
		(pts
			(arc
				(start 90.796872 -342.914478)
				(mid 90.816395 -342.910577)
				(end 90.83294 -342.899492)
			)
			(arc
				(start 91.030552 -342.70188)
				(mid 91.041663 -342.685346)
				(end 91.045538 -342.665812)
			)
			(arc
				(start 91.045538 -341.448898)
				(mid 91.041637 -341.429375)
				(end 91.030552 -341.41283)
			)
			(arc
				(start 90.984324 -341.366602)
				(mid 90.96779 -341.355491)
				(end 90.948256 -341.351616)
			)
			(arc
				(start 89.616534 -341.351616)
				(mid 89.597011 -341.355517)
				(end 89.580466 -341.366602)
			)
			(arc
				(start 89.141554 -341.805514)
				(mid 89.12502 -341.816625)
				(end 89.105486 -341.8205)
			)
			(arc
				(start 88.146382 -341.8205)
				(mid 88.126859 -341.824401)
				(end 88.110314 -341.835486)
			)
			(arc
				(start 87.971884 -341.973916)
				(mid 87.960773 -341.99045)
				(end 87.956898 -342.009984)
			)
			(arc
				(start 87.956898 -342.786716)
				(mid 87.960799 -342.806239)
				(end 87.971884 -342.822784)
			)
			(arc
				(start 88.048592 -342.899492)
				(mid 88.065126 -342.910603)
				(end 88.08466 -342.914478)
			)
		)
		(stroke
			(width 0)
			(type solid)
		)
		(fill yes)
		(layer "B.Cu")
		(net "GND")
	)
	(gr_poly
		(pts
			(xy 162.26155 -41.007538) (xy 162.26155 -39.945818) (xy 162.27806 -39.929308) (xy 162.27806 -37.275516)
			(xy 161.788602 -36.093908) (xy 159.66186 -36.093908) (xy 159.43326 -36.322508) (xy 159.43326 -39.827708)
			(xy 159.23006 -40.030908) (xy 155.34386 -40.030908) (xy 154.86126 -39.548308) (xy 154.86126 -36.170108)
			(xy 154.75966 -36.068508) (xy 153.99766 -36.068508) (xy 153.64206 -36.424108) (xy 153.64206 -40.462708)
			(xy 153.815034 -40.635682)
			(arc
				(start 153.844752 -40.625522)
				(mid 153.916442 -40.607849)
				(end 153.99004 -40.6019)
			)
			(arc
				(start 153.99004 -40.6019)
				(mid 154.313688 -40.73596)
				(end 154.447748 -41.059608)
			)
			(arc
				(start 154.447748 -41.059608)
				(mid 154.441833 -41.133212)
				(end 154.424126 -41.204896)
			)
			(xy 154.413966 -41.234614) (xy 154.79014 -41.610788) (xy 161.6583 -41.610788)
		)
		(stroke
			(width 0)
			(type solid)
		)
		(fill yes)
		(layer "B.Cu")
		(net "P3V3_AUX_USB_HUB_2")
	)
	(gr_poly
		(pts
			(xy 50.640742 -158.663132)
			(arc
				(start 50.640742 -157.094682)
				(mid 50.625773 -157.058671)
				(end 50.589688 -157.043882)
			)
			(arc
				(start 50.587656 -157.043882)
				(mid 50.264008 -156.909822)
				(end 50.129948 -156.586174)
			)
			(arc
				(start 50.129948 -156.586174)
				(mid 50.256638 -156.270067)
				(end 50.566574 -156.128974)
			)
			(xy 50.586132 -156.127958) (xy 50.635916 -156.078174) (xy 50.547016 -155.989274) (xy 49.317656 -155.989274)
			(xy 49.157636 -156.149294) (xy 49.157636 -158.461202) (xy 49.404016 -158.707582) (xy 50.596292 -158.707582)
		)
		(stroke
			(width 0)
			(type solid)
		)
		(fill yes)
		(layer "B.Cu")
		(net "GND")
	)
	(gr_poly
		(pts
			(xy 64.91224 -10.711688) (xy 64.91224 -9.263888) (xy 64.7573 -9.108948) (xy 60.900056 -9.108948)
			(arc
				(start 60.900056 -9.439148)
				(mid 60.773526 -9.744746)
				(end 60.468002 -9.871456)
			)
			(arc
				(start 60.468002 -9.871456)
				(mid 60.198773 -9.777317)
				(end 60.04687 -9.535922)
			)
			(arc
				(start 60.04687 -9.535922)
				(mid 59.975837 -9.461058)
				(end 59.875928 -9.4869)
			)
			(xy 59.49188 -9.870948) (xy 59.49188 -10.378948) (xy 59.99988 -10.886948) (xy 64.73698 -10.886948)
		)
		(stroke
			(width 0)
			(type solid)
		)
		(fill yes)
		(layer "B.Cu")
		(net "P3V3_OCP_V3_2")
	)
	(gr_poly
		(pts
			(xy 303.284382 -323.247258)
			(arc
				(start 303.284382 -322.608956)
				(mid 303.253902 -322.536399)
				(end 303.18075 -322.507356)
			)
			(arc
				(start 303.17186 -322.507356)
				(mid 302.848212 -322.373296)
				(end 302.714152 -322.049648)
			)
			(arc
				(start 302.714152 -322.049648)
				(mid 302.718131 -321.988915)
				(end 302.730154 -321.929252)
			)
			(arc
				(start 302.730154 -321.929252)
				(mid 302.712914 -321.840982)
				(end 302.632364 -321.800982)
			)
			(xy 302.485044 -321.800982) (xy 302.365156 -321.92087) (xy 302.114458 -321.92087) (xy 302.104552 -321.930776)
			(xy 300.580552 -321.930776) (xy 300.453552 -322.057776) (xy 300.453552 -323.327776) (xy 300.579282 -323.453506)
			(xy 303.078134 -323.453506)
		)
		(stroke
			(width 0)
			(type solid)
		)
		(fill yes)
		(layer "B.Cu")
		(net "GND")
	)
	(gr_poly
		(pts
			(xy 345.721686 -54.177692) (xy 352.6155 -54.177692) (xy 352.744786 -54.048406) (xy 352.744786 -53.075586)
			(xy 352.667062 -52.998116)
			(arc
				(start 349.677482 -52.998116)
				(mid 349.3262 -53.295378)
				(end 348.974918 -52.998116)
			)
			(arc
				(start 348.563692 -52.998116)
				(mid 348.295221 -52.944714)
				(end 348.06763 -52.79263)
			)
			(xy 347.712538 -52.437284) (xy 345.811348 -52.437284) (xy 345.745054 -52.37099) (xy 344.982546 -52.37099)
			(xy 344.845132 -52.508404) (xy 344.845132 -54.565296) (xy 344.906092 -54.626256) (xy 345.273122 -54.626256)
		)
		(stroke
			(width 0)
			(type solid)
		)
		(fill yes)
		(layer "B.Cu")
		(net "GND")
	)
	(gr_poly
		(pts
			(xy 50.640742 -167.299132)
			(arc
				(start 50.640742 -165.654482)
				(mid 50.625773 -165.618471)
				(end 50.589688 -165.603682)
			)
			(arc
				(start 50.587656 -165.603682)
				(mid 50.206148 -165.222174)
				(end 50.587656 -164.840666)
			)
			(arc
				(start 50.589688 -164.840666)
				(mid 50.625774 -164.825877)
				(end 50.640742 -164.789866)
			)
			(xy 50.640742 -164.719) (xy 50.547016 -164.625274) (xy 49.317656 -164.625274) (xy 49.157636 -164.785294)
			(xy 49.157636 -167.097202) (xy 49.404016 -167.343582) (xy 50.596292 -167.343582)
		)
		(stroke
			(width 0)
			(type solid)
		)
		(fill yes)
		(layer "B.Cu")
		(net "GND")
	)
	(gr_poly
		(pts
			(xy 50.640742 -150.027132)
			(arc
				(start 50.640742 -148.382482)
				(mid 50.625773 -148.346471)
				(end 50.589688 -148.331682)
			)
			(arc
				(start 50.587656 -148.331682)
				(mid 50.206148 -147.950174)
				(end 50.587656 -147.568666)
			)
			(arc
				(start 50.589688 -147.568666)
				(mid 50.625774 -147.553877)
				(end 50.640742 -147.517866)
			)
			(xy 50.640742 -147.447) (xy 50.547016 -147.353274) (xy 49.317656 -147.353274) (xy 49.157636 -147.513294)
			(xy 49.157636 -149.825202) (xy 49.404016 -150.071582) (xy 50.596292 -150.071582)
		)
		(stroke
			(width 0)
			(type solid)
		)
		(fill yes)
		(layer "B.Cu")
		(net "GND")
	)
	(gr_poly
		(pts
			(arc
				(start 82.63636 -348.70517)
				(mid 82.655883 -348.701269)
				(end 82.672428 -348.690184)
			)
			(arc
				(start 82.87004 -348.492572)
				(mid 82.881151 -348.476038)
				(end 82.885026 -348.456504)
			)
			(arc
				(start 82.885026 -347.23959)
				(mid 82.881125 -347.220067)
				(end 82.87004 -347.203522)
			)
			(arc
				(start 82.823812 -347.157294)
				(mid 82.807278 -347.146183)
				(end 82.787744 -347.142308)
			)
			(arc
				(start 81.456022 -347.142308)
				(mid 81.436499 -347.146209)
				(end 81.419954 -347.157294)
			)
			(arc
				(start 80.981042 -347.596206)
				(mid 80.964508 -347.607317)
				(end 80.944974 -347.611192)
			)
			(arc
				(start 80.621378 -347.611192)
				(mid 80.601855 -347.615093)
				(end 80.58531 -347.626178)
			)
			(arc
				(start 80.400144 -347.811344)
				(mid 80.389033 -347.827878)
				(end 80.385158 -347.847412)
			)
			(xy 80.385158 -348.442534)
			(arc
				(start 80.38973 -348.45244)
				(mid 80.413128 -348.520886)
				(end 80.422242 -348.592648)
			)
			(xy 80.422496 -348.602554) (xy 80.429862 -348.620334)
			(arc
				(start 80.499712 -348.690184)
				(mid 80.516246 -348.701295)
				(end 80.53578 -348.70517)
			)
		)
		(stroke
			(width 0)
			(type solid)
		)
		(fill yes)
		(layer "B.Cu")
		(net "GND")
	)
	(gr_poly
		(pts
			(xy 366.640364 -246.786146) (xy 366.640364 -246.405146) (xy 366.838484 -246.207026) (xy 369.055904 -246.207026)
			(xy 369.16233 -246.100346)
			(arc
				(start 369.16233 -244.949218)
				(mid 369.091969 -244.73662)
				(end 369.16233 -244.524022)
			)
			(xy 369.16233 -243.75237) (xy 369.02263 -243.61267) (xy 368.80673 -243.61267) (xy 368.765836 -243.65331)
			(arc
				(start 368.765836 -244.89156)
				(mid 368.734476 -244.938493)
				(end 368.679222 -244.927374)
			)
			(xy 368.44097 -244.689122) (xy 363.55655 -244.689122) (xy 363.51083 -244.643656) (xy 363.493812 -244.643656)
			(xy 363.436662 -244.586252) (xy 363.248956 -244.586252) (xy 363.168692 -244.66677) (xy 363.168692 -245.7323)
			(xy 363.650784 -246.214646) (xy 365.319564 -246.214646) (xy 365.320072 -246.2149) (xy 365.324136 -246.2149)
			(xy 365.568992 -246.459756) (xy 365.568992 -246.748554) (xy 365.659416 -246.839232) (xy 366.587532 -246.839232)
		)
		(stroke
			(width 0)
			(type solid)
		)
		(fill yes)
		(layer "B.Cu")
		(net "GND")
	)
	(gr_poly
		(pts
			(xy 421.751506 -179.786534) (xy 421.751506 -177.474626) (xy 421.505126 -177.228246) (xy 420.31285 -177.228246)
			(xy 420.2684 -177.272696)
			(arc
				(start 420.2684 -178.917346)
				(mid 420.283369 -178.953357)
				(end 420.319454 -178.968146)
			)
			(arc
				(start 420.321486 -178.968146)
				(mid 420.702994 -179.349654)
				(end 420.321486 -179.731162)
			)
			(arc
				(start 420.319454 -179.731162)
				(mid 420.283368 -179.745951)
				(end 420.2684 -179.781962)
			)
			(xy 420.2684 -179.852828) (xy 420.362126 -179.946554) (xy 421.591486 -179.946554)
		)
		(stroke
			(width 0)
			(type solid)
		)
		(fill yes)
		(layer "B.Cu")
		(net "GND")
	)
	(gr_poly
		(pts
			(xy 421.751506 -171.150534) (xy 421.751506 -168.838626) (xy 421.505126 -168.592246) (xy 420.31285 -168.592246)
			(xy 420.2684 -168.636696)
			(arc
				(start 420.2684 -170.281346)
				(mid 420.283369 -170.317357)
				(end 420.319454 -170.332146)
			)
			(arc
				(start 420.321486 -170.332146)
				(mid 420.702994 -170.713654)
				(end 420.321486 -171.095162)
			)
			(arc
				(start 420.319454 -171.095162)
				(mid 420.283368 -171.109951)
				(end 420.2684 -171.145962)
			)
			(xy 420.2684 -171.216828) (xy 420.362126 -171.310554) (xy 421.591486 -171.310554)
		)
		(stroke
			(width 0)
			(type solid)
		)
		(fill yes)
		(layer "B.Cu")
		(net "GND")
	)
	(gr_poly
		(pts
			(xy 421.751506 -162.514534) (xy 421.751506 -160.202626) (xy 421.505126 -159.956246) (xy 420.31285 -159.956246)
			(xy 420.2684 -160.000696)
			(arc
				(start 420.2684 -161.645346)
				(mid 420.283369 -161.681357)
				(end 420.319454 -161.696146)
			)
			(arc
				(start 420.321486 -161.696146)
				(mid 420.702994 -162.077654)
				(end 420.321486 -162.459162)
			)
			(arc
				(start 420.319454 -162.459162)
				(mid 420.283368 -162.473951)
				(end 420.2684 -162.509962)
			)
			(xy 420.2684 -162.580828) (xy 420.362126 -162.674554) (xy 421.591486 -162.674554)
		)
		(stroke
			(width 0)
			(type solid)
		)
		(fill yes)
		(layer "B.Cu")
		(net "GND")
	)
	(gr_poly
		(pts
			(xy 118.70055 -246.7864) (xy 118.70055 -246.4054) (xy 118.89867 -246.20728) (xy 121.11609 -246.20728)
			(xy 121.222516 -246.1006)
			(arc
				(start 121.222516 -244.949472)
				(mid 121.151903 -244.73662)
				(end 121.222516 -244.523768)
			)
			(xy 121.222516 -243.752624) (xy 121.082816 -243.612924) (xy 120.866916 -243.612924) (xy 120.774968 -243.704872)
			(xy 120.774968 -244.5893) (xy 120.674892 -244.689376) (xy 115.616736 -244.689376) (xy 115.532916 -244.60581)
			(xy 115.532408 -244.605302) (xy 115.527074 -244.599968) (xy 115.493038 -244.565932) (xy 115.32997 -244.565932)
			(xy 115.198652 -244.697504) (xy 115.198652 -245.702328) (xy 115.71097 -246.2149) (xy 117.37975 -246.2149)
			(xy 117.465348 -246.300498) (xy 117.465602 -246.300752) (xy 117.46992 -246.304816) (xy 117.529102 -246.363998)
			(xy 117.533166 -246.368316) (xy 117.53342 -246.36857) (xy 117.61851 -246.45366) (xy 117.61851 -246.572024)
			(xy 117.618764 -246.579898) (xy 117.618764 -246.73814) (xy 117.628924 -246.748554) (xy 117.628924 -246.748808)
			(xy 117.759734 -246.879364) (xy 118.607586 -246.879364)
		)
		(stroke
			(width 0)
			(type solid)
		)
		(fill yes)
		(layer "B.Cu")
		(net "GND")
	)
	(gr_poly
		(pts
			(xy 370.036344 -243.049806)
			(arc
				(start 370.039646 -243.035074)
				(mid 370.104079 -242.893833)
				(end 370.222526 -242.79352)
			)
			(xy 370.249704 -242.779296) (xy 370.249704 -241.81054)
			(arc
				(start 370.222526 -241.796316)
				(mid 370.032064 -241.481102)
				(end 370.222526 -241.165888)
			)
			(xy 370.249704 -241.151664) (xy 370.249704 -240.423446) (xy 370.125244 -240.298986) (xy 369.866164 -240.298986)
			(xy 368.949224 -241.215926) (xy 367.261902 -241.215926) (xy 367.16208 -241.315748) (xy 367.16208 -242.484148)
			(xy 367.208816 -242.530884) (xy 368.513614 -242.530884) (xy 368.521488 -242.539012) (xy 368.682016 -242.539012)
			(xy 368.930174 -242.786916) (xy 368.930174 -243.213636) (xy 369.0747 -243.358416) (xy 369.12804 -243.358416)
			(xy 369.12931 -243.359686) (xy 369.726464 -243.359686)
		)
		(stroke
			(width 0)
			(type solid)
		)
		(fill yes)
		(layer "B.Cu")
		(net "PVCCD_HV_CPU0")
	)
	(gr_poly
		(pts
			(xy 330.846176 -348.655132) (xy 330.846176 -347.220286) (xy 330.801726 -347.175836)
			(arc
				(start 329.238102 -347.175836)
				(mid 329.165621 -347.206497)
				(end 329.136756 -347.279722)
			)
			(arc
				(start 329.136756 -347.288866)
				(mid 328.755248 -347.670374)
				(end 328.37374 -347.288866)
			)
			(arc
				(start 328.37374 -347.279722)
				(mid 328.344893 -347.206479)
				(end 328.272394 -347.175836)
			)
			(xy 328.246994 -347.175836) (xy 328.153268 -347.269562) (xy 328.153268 -348.81566) (xy 328.245978 -348.90837)
			(xy 330.592938 -348.90837)
		)
		(stroke
			(width 0)
			(type solid)
		)
		(fill yes)
		(layer "B.Cu")
		(net "GND")
	)
	(gr_poly
		(pts
			(xy 60.047124 -251.867924) (xy 60.047124 -251.217938) (xy 60.054998 -251.210064) (xy 60.054998 -251.170948)
			(xy 60.232798 -250.993148) (xy 60.271914 -250.993148) (xy 60.322968 -250.94184) (xy 62.693042 -250.94184)
			(arc
				(start 62.704726 -250.90755)
				(mid 63.13805 -250.597188)
				(end 63.571374 -250.90755)
			)
			(xy 63.583058 -250.94184) (xy 66.853308 -250.94184) (xy 66.929 -250.866148) (xy 66.929 -249.088148)
			(xy 66.8655 -249.024648) (xy 62.445392 -249.024648)
			(arc
				(start 62.378844 -249.090942)
				(mid 62.275389 -249.160225)
				(end 62.153292 -249.184668)
			)
			(xy 59.234832 -249.184668) (xy 58.845958 -249.573542) (xy 57.949846 -249.573542) (xy 57.673748 -249.84964)
			(xy 57.673748 -251.73432) (xy 57.956958 -252.01753) (xy 59.897518 -252.01753)
		)
		(stroke
			(width 0)
			(type solid)
		)
		(fill yes)
		(layer "B.Cu")
		(net "GND")
	)
	(gr_poly
		(pts
			(xy 61.6077 -179.657248) (xy 61.6077 -176.192688) (xy 61.7728 -176.027588) (xy 61.7728 -169.890948)
			(xy 62.3316 -169.332148) (xy 62.4332 -169.332148) (xy 62.6872 -169.078148) (xy 62.6872 -143.322548)
			(xy 62.8396 -143.170148) (xy 62.8396 -142.763748) (xy 62.7888 -142.712948) (xy 55.6514 -142.712948)
			(xy 55.1434 -143.220948) (xy 55.1434 -145.913348) (xy 55.0164 -146.040348) (xy 52.8828 -146.040348)
			(xy 52.705 -146.218148) (xy 52.705 -147.691348) (xy 52.8574 -147.843748) (xy 54.6862 -147.843748)
			(xy 55.0418 -148.199348) (xy 55.0418 -154.549348) (xy 54.8894 -154.701748) (xy 52.832 -154.701748)
			(xy 52.6542 -154.879548) (xy 52.6542 -156.479748) (xy 52.6796 -156.505148) (xy 54.8132 -156.505148)
			(xy 55.0418 -156.733748) (xy 55.0418 -162.931348) (xy 54.61 -163.363148) (xy 52.8574 -163.363148)
			(xy 52.6796 -163.540948) (xy 52.6796 -164.963348) (xy 52.832 -165.115748) (xy 54.8132 -165.115748)
			(xy 55.0164 -165.318948) (xy 55.0164 -171.338748) (xy 53.5178 -172.837348) (xy 51.5366 -172.837348)
			(xy 51.3842 -172.989748) (xy 51.3842 -174.462948) (xy 51.5112 -174.589948) (xy 53.0606 -174.589948)
			(xy 53.3146 -174.843948) (xy 53.3146 -179.669948) (xy 53.5178 -179.873148) (xy 53.5178 -179.923948)
			(xy 61.341 -179.923948)
		)
		(stroke
			(width 0)
			(type solid)
		)
		(fill yes)
		(layer "B.Cu")
		(net "GND")
	)
	(gr_poly
		(pts
			(xy 122.096276 -243.050314)
			(arc
				(start 122.099324 -243.035582)
				(mid 122.163895 -242.893992)
				(end 122.282712 -242.79352)
			)
			(xy 122.30989 -242.779296) (xy 122.30989 -241.810794)
			(arc
				(start 122.282712 -241.79657)
				(mid 122.092025 -241.481102)
				(end 122.282712 -241.165634)
			)
			(xy 122.30989 -241.15141) (xy 122.30989 -240.4237) (xy 122.18543 -240.29924) (xy 121.92635 -240.29924)
			(xy 121.00941 -241.21618) (xy 119.357648 -241.21618) (xy 119.20728 -241.366548) (xy 119.20728 -242.357148)
			(xy 119.310404 -242.460272)
			(arc
				(start 120.461278 -242.460272)
				(mid 120.51257 -242.464741)
				(end 120.56237 -242.477798)
			)
			(xy 120.570498 -242.480592) (xy 120.684036 -242.480592) (xy 120.99036 -242.78717) (xy 120.99036 -243.21389)
			(xy 121.13514 -243.358416) (xy 121.188226 -243.358416) (xy 121.189496 -243.35994) (xy 121.78665 -243.35994)
		)
		(stroke
			(width 0)
			(type solid)
		)
		(fill yes)
		(layer "B.Cu")
		(net "PVCCD_HV_CPU1")
	)
	(gr_poly
		(pts
			(xy 297.1038 -52.517548) (xy 297.1038 -45.735748) (xy 296.8752 -45.507148) (xy 293.9542 -45.507148)
			(xy 293.5478 -45.913548) (xy 293.5478 -48.979836)
			(arc
				(start 294.174672 -48.979836)
				(mid 294.324711 -48.877267)
				(end 294.50284 -48.841152)
			)
			(arc
				(start 294.50284 -48.841152)
				(mid 294.960548 -49.29886)
				(end 294.50284 -49.756568)
			)
			(arc
				(start 294.50284 -49.756568)
				(mid 294.3247 -49.720479)
				(end 294.174672 -49.617884)
			)
			(xy 293.5478 -49.617884) (xy 293.5478 -52.492148) (xy 294.005 -52.949348) (xy 296.672 -52.949348)
		)
		(stroke
			(width 0)
			(type solid)
		)
		(fill yes)
		(layer "B.Cu")
		(net "GND")
	)
	(gr_poly
		(pts
			(arc
				(start 131.31927 -343.043256)
				(mid 131.338793 -343.039355)
				(end 131.355338 -343.02827)
			)
			(arc
				(start 131.571746 -342.811862)
				(mid 131.582857 -342.795328)
				(end 131.586732 -342.775794)
			)
			(arc
				(start 131.586732 -341.651082)
				(mid 131.582831 -341.631559)
				(end 131.571746 -341.615014)
			)
			(arc
				(start 131.557268 -341.600536)
				(mid 131.540734 -341.589425)
				(end 131.5212 -341.58555)
			)
			(xy 130.11785 -341.58555) (xy 130.09372 -341.600282)
			(arc
				(start 130.087116 -341.612982)
				(mid 129.748026 -341.819701)
				(end 129.408936 -341.612982)
			)
			(xy 129.402332 -341.600282) (xy 129.378202 -341.58555)
			(arc
				(start 129.08026 -341.58555)
				(mid 129.060737 -341.589451)
				(end 129.044192 -341.600536)
			)
			(arc
				(start 128.858264 -341.786464)
				(mid 128.847153 -341.802998)
				(end 128.843278 -341.822532)
			)
			(arc
				(start 128.843278 -342.765634)
				(mid 128.847179 -342.785157)
				(end 128.858264 -342.801702)
			)
			(arc
				(start 129.084832 -343.02827)
				(mid 129.101366 -343.039381)
				(end 129.1209 -343.043256)
			)
		)
		(stroke
			(width 0)
			(type solid)
		)
		(fill yes)
		(layer "B.Cu")
		(net "GND")
	)
	(gr_poly
		(pts
			(xy 128.55448 -26.830528) (xy 128.55448 -26.789888) (xy 128.651 -26.693368) (xy 129.27838 -26.693368)
			(xy 129.30632 -26.665428) (xy 129.30632 -26.594308) (xy 129.27584 -26.563828) (xy 128.58496 -26.563828)
			(xy 128.53416 -26.513028) (xy 128.53416 -26.360628) (xy 128.56718 -26.327608) (xy 129.29616 -26.327608)
			(xy 129.3241 -26.299668) (xy 129.3241 -26.226008) (xy 129.26822 -26.170128) (xy 128.53924 -26.170128)
			(xy 128.53924 -26.022808) (xy 128.58496 -25.977088) (xy 129.29362 -25.977088) (xy 129.31648 -25.954228)
			(xy 129.31648 -25.888188) (xy 129.26568 -25.837388) (xy 128.55702 -25.837388) (xy 128.54178 -25.822148)
			(xy 128.54178 -25.598628) (xy 128.50622 -25.563068) (xy 127.2159 -25.563068) (xy 127.13208 -25.646888)
			(xy 127.13208 -25.814528) (xy 127.08382 -25.862788) (xy 126.3777 -25.862788) (xy 126.35992 -25.880568)
			(xy 126.35992 -25.964388) (xy 126.38532 -25.989788) (xy 127.127 -25.989788) (xy 127.14732 -26.010108)
			(xy 127.14732 -26.200608) (xy 127.13208 -26.215848) (xy 126.37262 -26.215848) (xy 126.3523 -26.236168)
			(xy 126.3523 -26.309828) (xy 126.38532 -26.342848) (xy 127.11938 -26.342848) (xy 127.13462 -26.358088)
			(xy 127.13462 -26.510488) (xy 127.08128 -26.563828) (xy 126.38278 -26.563828) (xy 126.36246 -26.584148)
			(xy 126.36246 -26.660348) (xy 126.3904 -26.688288) (xy 126.98984 -26.688288) (xy 127.17018 -26.868628)
			(xy 127.17018 -26.977848) (xy 127.18542 -26.993088) (xy 128.39192 -26.993088)
		)
		(stroke
			(width 0)
			(type solid)
		)
		(fill yes)
		(layer "B.Cu")
		(net "GND")
	)
	(gr_poly
		(pts
			(arc
				(start 139.329668 -348.445074)
				(mid 139.349191 -348.441173)
				(end 139.365736 -348.430088)
			)
			(arc
				(start 139.6619 -348.134178)
				(mid 139.673011 -348.117644)
				(end 139.676886 -348.09811)
			)
			(arc
				(start 139.676886 -347.217492)
				(mid 139.672985 -347.197969)
				(end 139.6619 -347.181424)
			)
			(arc
				(start 139.627356 -347.14688)
				(mid 139.610822 -347.135769)
				(end 139.591288 -347.131894)
			)
			(arc
				(start 138.391646 -347.131894)
				(mid 138.372289 -347.135727)
				(end 138.355832 -347.146626)
			)
			(xy 138.29792 -347.20403) (xy 138.290046 -347.222318)
			(arc
				(start 138.290046 -347.232478)
				(mid 138.177056 -347.499955)
				(end 137.908538 -347.61043)
			)
			(arc
				(start 137.908538 -347.61043)
				(mid 137.872695 -347.608814)
				(end 137.837164 -347.603826)
			)
			(xy 137.832592 -347.60281)
			(arc
				(start 137.098532 -347.60281)
				(mid 137.079009 -347.606711)
				(end 137.062464 -347.617796)
			)
			(arc
				(start 137.031984 -347.648276)
				(mid 137.020873 -347.66481)
				(end 137.016998 -347.684344)
			)
			(arc
				(start 137.016998 -348.32544)
				(mid 137.020899 -348.344963)
				(end 137.031984 -348.361508)
			)
			(arc
				(start 137.100564 -348.430088)
				(mid 137.117098 -348.441199)
				(end 137.136632 -348.445074)
			)
		)
		(stroke
			(width 0)
			(type solid)
		)
		(fill yes)
		(layer "B.Cu")
		(net "GND")
	)
	(gr_poly
		(pts
			(arc
				(start 115.36299 -339.606128)
				(mid 115.382513 -339.602227)
				(end 115.399058 -339.591142)
			)
			(arc
				(start 115.516152 -339.474048)
				(mid 115.527263 -339.457514)
				(end 115.531138 -339.43798)
			)
			(arc
				(start 115.531138 -338.013548)
				(mid 115.527237 -337.994025)
				(end 115.516152 -337.97748)
			)
			(arc
				(start 115.469924 -337.931252)
				(mid 115.45339 -337.920141)
				(end 115.433856 -337.916266)
			)
			(arc
				(start 114.085624 -337.916266)
				(mid 114.066101 -337.920167)
				(end 114.049556 -337.931252)
			)
			(xy 113.750598 -338.23021)
			(arc
				(start 113.74755 -338.234782)
				(mid 113.696723 -338.297747)
				(end 113.633758 -338.348574)
			)
			(xy 113.629186 -338.351622)
			(arc
				(start 113.603532 -338.377276)
				(mid 113.586998 -338.388387)
				(end 113.567464 -338.392262)
			)
			(xy 113.540794 -338.392262)
			(arc
				(start 113.533682 -338.394294)
				(mid 113.480882 -338.40569)
				(end 113.427002 -338.409534)
			)
			(arc
				(start 113.427002 -338.409534)
				(mid 113.373119 -338.40571)
				(end 113.320322 -338.394294)
			)
			(xy 113.31321 -338.392262)
			(arc
				(start 112.80648 -338.392262)
				(mid 112.786957 -338.396163)
				(end 112.770412 -338.407248)
			)
			(arc
				(start 112.561624 -338.616036)
				(mid 112.550513 -338.63257)
				(end 112.546638 -338.652104)
			)
			(arc
				(start 112.546638 -339.386926)
				(mid 112.550539 -339.406449)
				(end 112.561624 -339.422994)
			)
			(arc
				(start 112.729772 -339.591142)
				(mid 112.746306 -339.602253)
				(end 112.76584 -339.606128)
			)
		)
		(stroke
			(width 0)
			(type solid)
		)
		(fill yes)
		(layer "B.Cu")
		(net "GND")
	)
	(gr_poly
		(pts
			(arc
				(start 107.056428 -339.612732)
				(mid 107.075951 -339.608831)
				(end 107.092496 -339.597746)
			)
			(arc
				(start 107.334812 -339.35543)
				(mid 107.345923 -339.338896)
				(end 107.349798 -339.319362)
			)
			(arc
				(start 107.349798 -338.033106)
				(mid 107.345897 -338.013583)
				(end 107.334812 -337.997038)
			)
			(arc
				(start 107.221274 -337.8835)
				(mid 107.20474 -337.872389)
				(end 107.185206 -337.868514)
			)
			(arc
				(start 106.057192 -337.868514)
				(mid 106.047224 -337.869451)
				(end 106.037634 -337.872324)
			)
			(arc
				(start 106.020362 -337.87969)
				(mid 106.011579 -337.88435)
				(end 106.003852 -337.890612)
			)
			(arc
				(start 105.514648 -338.379816)
				(mid 105.506937 -338.386101)
				(end 105.498138 -338.390738)
			)
			(arc
				(start 105.480866 -338.398104)
				(mid 105.471276 -338.400977)
				(end 105.461308 -338.401914)
			)
			(xy 105.342436 -338.401914)
			(arc
				(start 105.337864 -338.40293)
				(mid 105.302332 -338.407906)
				(end 105.26649 -338.409534)
			)
			(arc
				(start 105.26649 -338.409534)
				(mid 105.230647 -338.407918)
				(end 105.195116 -338.40293)
			)
			(xy 105.190544 -338.401914)
			(arc
				(start 105.029508 -338.401914)
				(mid 105.009985 -338.405815)
				(end 104.99344 -338.4169)
			)
			(arc
				(start 104.847644 -338.562696)
				(mid 104.836533 -338.57923)
				(end 104.832658 -338.598764)
			)
			(arc
				(start 104.832658 -339.42147)
				(mid 104.836559 -339.440993)
				(end 104.847644 -339.457538)
			)
			(arc
				(start 104.987852 -339.597746)
				(mid 105.004386 -339.608857)
				(end 105.02392 -339.612732)
			)
		)
		(stroke
			(width 0)
			(type solid)
		)
		(fill yes)
		(layer "B.Cu")
		(net "GND")
	)
	(gr_poly
		(pts
			(xy 294.709088 -368.464846) (xy 294.709088 -368.218466) (xy 294.539416 -368.048794) (xy 294.404288 -367.913666)
			(xy 294.404288 -362.951522) (xy 294.539416 -362.816394) (xy 294.620188 -362.735368) (xy 294.876728 -362.735368)
			(xy 296.04843 -362.735368) (xy 296.461688 -363.148626) (xy 296.461688 -364.901226) (xy 296.633646 -365.073184)
			(xy 298.39412 -365.073184) (xy 298.534328 -364.932976) (xy 298.534328 -362.991146) (xy 298.789344 -362.73613)
			(xy 303.624742 -362.73613) (xy 303.97196 -363.083348) (xy 303.97196 -366.657128) (xy 304.15738 -366.842548)
			(xy 306.685188 -366.842548) (xy 306.926488 -366.601248) (xy 306.926488 -354.272596) (xy 306.749958 -354.096066)
			(xy 300.429422 -354.096066) (xy 300.222666 -354.302822) (xy 297.098974 -354.302822) (xy 296.892218 -354.096066)
			(xy 290.454842 -354.096066) (xy 290.314126 -354.236782) (xy 286.88411 -354.236782) (xy 286.743394 -354.096066)
			(xy 284.587442 -354.096066) (xy 284.480762 -354.202746) (xy 284.480762 -362.368846) (xy 284.678628 -362.566712)
			(xy 284.881574 -362.769658) (xy 286.666432 -362.769658) (xy 286.996886 -363.100112) (xy 286.996886 -364.955836)
			(xy 287.114742 -365.073692) (xy 288.743644 -365.073692) (xy 288.779712 -365.058706)
			(arc
				(start 288.82594 -365.012478)
				(mid 288.831996 -365.005228)
				(end 288.836608 -364.996984)
			)
			(xy 288.836608 -362.837222) (xy 288.9377 -362.73613) (xy 292.472364 -362.73613) (xy 293.20871 -362.73613)
			(xy 293.471092 -362.73613) (xy 293.705788 -362.970826) (xy 293.705788 -365.122206) (xy 293.342568 -365.485426)
			(xy 293.342568 -367.941606) (xy 294.023288 -368.622326) (xy 294.551608 -368.622326)
		)
		(stroke
			(width 0)
			(type solid)
		)
		(fill yes)
		(layer "B.Cu")
		(net "GND")
	)
	(gr_poly
		(pts
			(arc
				(start 123.335796 -339.620098)
				(mid 123.355319 -339.616197)
				(end 123.371864 -339.605112)
			)
			(arc
				(start 123.481084 -339.495892)
				(mid 123.492195 -339.479358)
				(end 123.49607 -339.459824)
			)
			(xy 123.49607 -338.30641) (xy 123.501658 -338.300822)
			(arc
				(start 123.501658 -338.098892)
				(mid 123.497757 -338.079369)
				(end 123.486672 -338.062824)
			)
			(arc
				(start 123.415044 -337.991196)
				(mid 123.39851 -337.980085)
				(end 123.378976 -337.97621)
			)
			(arc
				(start 122.164094 -337.97621)
				(mid 122.144571 -337.980111)
				(end 122.128026 -337.991196)
			)
			(xy 121.936256 -338.182966)
			(arc
				(start 121.932446 -338.19084)
				(mid 121.79174 -338.350298)
				(end 121.587514 -338.409534)
			)
			(arc
				(start 121.587514 -338.409534)
				(mid 121.430656 -338.37591)
				(end 121.30151 -338.280756)
			)
			(arc
				(start 121.30151 -338.280756)
				(mid 121.284432 -338.268091)
				(end 121.263664 -338.263484)
			)
			(arc
				(start 120.95226 -338.263484)
				(mid 120.932737 -338.267385)
				(end 120.916192 -338.27847)
			)
			(arc
				(start 120.641364 -338.553298)
				(mid 120.630253 -338.569832)
				(end 120.626378 -338.589366)
			)
			(arc
				(start 120.626378 -339.451696)
				(mid 120.630279 -339.471219)
				(end 120.641364 -339.487764)
			)
			(arc
				(start 120.758712 -339.605112)
				(mid 120.775246 -339.616223)
				(end 120.79478 -339.620098)
			)
		)
		(stroke
			(width 0)
			(type solid)
		)
		(fill yes)
		(layer "B.Cu")
		(net "GND")
	)
	(gr_poly
		(pts
			(xy 108.08462 -419.6207) (xy 108.08462 -416.707828) (xy 107.90428 -416.527488) (xy 105.58526 -416.527488)
			(xy 105.39222 -416.720528) (xy 105.39222 -419.148256) (xy 105.704622 -419.148256) (xy 105.704622 -419.08832)
			(xy 105.712445 -419.028898) (xy 105.727958 -418.971005) (xy 105.750894 -418.915632) (xy 105.780861 -418.863726)
			(xy 105.817348 -418.816176) (xy 105.859728 -418.773796) (xy 105.907278 -418.737309) (xy 105.959184 -418.707342)
			(xy 106.014557 -418.684406) (xy 106.07245 -418.668893) (xy 106.131872 -418.66107) (xy 106.191808 -418.66107)
			(xy 106.25123 -418.668893) (xy 106.309123 -418.684406) (xy 106.364496 -418.707342) (xy 106.416402 -418.737309)
			(xy 106.463952 -418.773796) (xy 106.506332 -418.816176) (xy 106.542819 -418.863726) (xy 106.572786 -418.915632)
			(xy 106.595722 -418.971005) (xy 106.611235 -419.028898) (xy 106.619058 -419.08832) (xy 106.619548 -419.118288)
			(xy 106.619058 -419.148256) (xy 106.611235 -419.207678) (xy 106.595722 -419.265571) (xy 106.572786 -419.320944)
			(xy 106.542819 -419.37285) (xy 106.506332 -419.4204) (xy 106.463952 -419.46278) (xy 106.416402 -419.499267)
			(xy 106.364496 -419.529234) (xy 106.309123 -419.55217) (xy 106.25123 -419.567683) (xy 106.191808 -419.575506)
			(xy 106.131872 -419.575506) (xy 106.07245 -419.567683) (xy 106.014557 -419.55217) (xy 105.959184 -419.529234)
			(xy 105.907278 -419.499267) (xy 105.859728 -419.46278) (xy 105.817348 -419.4204) (xy 105.780861 -419.37285)
			(xy 105.750894 -419.320944) (xy 105.727958 -419.265571) (xy 105.712445 -419.207678) (xy 105.704622 -419.148256)
			(xy 105.39222 -419.148256) (xy 105.39222 -420.0652) (xy 105.68178 -420.35476) (xy 107.35056 -420.35476)
		)
		(stroke
			(width 0)
			(type solid)
		)
		(fill yes)
		(layer "B.Cu")
		(net "P3V3_9ZXL045")
	)
	(gr_poly
		(pts
			(xy 245.02872 -251.803408) (xy 245.02872 -247.211088) (xy 244.63248 -246.814848) (xy 240.55324 -246.814848)
			(xy 240.20272 -247.165368) (xy 240.20272 -249.303536) (xy 240.731022 -249.303536) (xy 240.731022 -249.2436)
			(xy 240.738845 -249.184178) (xy 240.754358 -249.126285) (xy 240.777294 -249.070912) (xy 240.807261 -249.019006)
			(xy 240.843748 -248.971456) (xy 240.886128 -248.929076) (xy 240.933678 -248.892589) (xy 240.985584 -248.862622)
			(xy 241.040957 -248.839686) (xy 241.09885 -248.824173) (xy 241.158272 -248.81635) (xy 241.218208 -248.81635)
			(xy 241.27763 -248.824173) (xy 241.335523 -248.839686) (xy 241.390896 -248.862622) (xy 241.442802 -248.892589)
			(xy 241.490352 -248.929076) (xy 241.532732 -248.971456) (xy 241.569219 -249.019006) (xy 241.599186 -249.070912)
			(xy 241.622122 -249.126285) (xy 241.637635 -249.184178) (xy 241.645458 -249.2436) (xy 241.645948 -249.273568)
			(xy 241.645458 -249.303536) (xy 241.637635 -249.362958) (xy 241.622122 -249.420851) (xy 241.599186 -249.476224)
			(xy 241.569219 -249.52813) (xy 241.532732 -249.57568) (xy 241.490352 -249.61806) (xy 241.442802 -249.654547)
			(xy 241.390896 -249.684514) (xy 241.335523 -249.70745) (xy 241.27763 -249.722963) (xy 241.218208 -249.730786)
			(xy 241.158272 -249.730786) (xy 241.09885 -249.722963) (xy 241.040957 -249.70745) (xy 240.985584 -249.684514)
			(xy 240.933678 -249.654547) (xy 240.886128 -249.61806) (xy 240.843748 -249.57568) (xy 240.807261 -249.52813)
			(xy 240.777294 -249.476224) (xy 240.754358 -249.420851) (xy 240.738845 -249.362958) (xy 240.731022 -249.303536)
			(xy 240.20272 -249.303536) (xy 240.20272 -251.915168) (xy 240.46942 -252.181868) (xy 244.65026 -252.181868)
		)
		(stroke
			(width 0)
			(type solid)
		)
		(fill yes)
		(layer "B.Cu")
		(net "GND")
	)
	(gr_poly
		(pts
			(xy 250.812808 -103.050848) (xy 252.776482 -103.050848) (xy 252.924818 -102.902512) (xy 252.924818 -102.499922)
			(xy 252.797564 -102.372668) (xy 252.345444 -102.372668) (xy 252.041914 -102.069138) (xy 252.041914 -100.339144)
			(xy 251.893578 -100.190808) (xy 250.98883 -100.190808) (xy 250.855226 -100.324412) (xy 250.855226 -101.765608)
			(xy 249.174508 -103.446326)
			(arc
				(start 245.526306 -103.446326)
				(mid 245.33606 -103.497109)
				(end 245.145814 -103.446326)
			)
			(xy 241.362484 -103.446326) (xy 241.110516 -103.194358)
			(arc
				(start 241.101372 -103.190548)
				(mid 240.955972 -103.092616)
				(end 240.85804 -102.947216)
			)
			(xy 240.85423 -102.938072) (xy 240.740946 -102.824788) (xy 240.740946 -101.694996) (xy 241.011456 -101.424486)
			(arc
				(start 241.013742 -101.407214)
				(mid 241.144015 -101.142263)
				(end 241.408966 -101.01199)
			)
			(xy 241.426238 -101.009704) (xy 242.407948 -100.027994) (xy 242.407948 -99.286314) (xy 242.386612 -99.264978)
			(xy 242.386612 -98.044508) (xy 242.25377 -97.91192) (xy 241.199924 -97.91192) (xy 241.033046 -98.078798)
			(xy 241.033046 -98.106738) (xy 241.009424 -98.106738) (xy 239.893602 -99.22256) (xy 239.893602 -103.135684)
			(xy 240.903506 -104.145588) (xy 249.718068 -104.145588)
		)
		(stroke
			(width 0)
			(type solid)
		)
		(fill yes)
		(layer "B.Cu")
		(net "P3V3_AUX_CLK_GEN_VDDA25M_CK440")
	)
	(gr_poly
		(pts
			(arc
				(start 99.152456 -339.155532)
				(mid 99.171979 -339.151631)
				(end 99.188524 -339.140546)
			)
			(arc
				(start 99.197922 -339.131148)
				(mid 99.209033 -339.114614)
				(end 99.212908 -339.09508)
			)
			(arc
				(start 99.212908 -338.054696)
				(mid 99.209007 -338.035173)
				(end 99.197922 -338.018628)
			)
			(arc
				(start 99.1235 -337.944206)
				(mid 99.106966 -337.933095)
				(end 99.087432 -337.92922)
			)
			(arc
				(start 97.804732 -337.92922)
				(mid 97.785209 -337.933121)
				(end 97.768664 -337.944206)
			)
			(arc
				(start 97.538794 -338.174076)
				(mid 97.52226 -338.185187)
				(end 97.502726 -338.189062)
			)
			(arc
				(start 97.482914 -338.189062)
				(mid 97.457135 -338.195939)
				(end 97.438464 -338.21497)
			)
			(arc
				(start 97.438464 -338.21497)
				(mid 97.105978 -338.409594)
				(end 96.773492 -338.21497)
			)
			(arc
				(start 96.773492 -338.21497)
				(mid 96.754782 -338.196006)
				(end 96.729042 -338.189062)
			)
			(arc
				(start 96.42348 -338.189062)
				(mid 96.403957 -338.192963)
				(end 96.387412 -338.204048)
			)
			(arc
				(start 96.216724 -338.374736)
				(mid 96.205613 -338.39127)
				(end 96.201738 -338.410804)
			)
			(arc
				(start 96.201738 -339.03539)
				(mid 96.205639 -339.054913)
				(end 96.216724 -339.071458)
			)
			(arc
				(start 96.285812 -339.140546)
				(mid 96.302346 -339.151657)
				(end 96.32188 -339.155532)
			)
		)
		(stroke
			(width 0)
			(type solid)
		)
		(fill yes)
		(layer "B.Cu")
		(net "GND")
	)
	(gr_poly
		(pts
			(xy 191.28232 -359.766108) (xy 191.28232 -348.785688) (xy 192.00876 -348.059248) (xy 194.21856 -348.059248)
			(xy 194.90182 -347.375988) (xy 194.90182 -334.495648) (xy 194.48272 -334.076548) (xy 186.58078 -334.076548)
			(xy 186.58078 -336.037428) (xy 186.68746 -336.144108) (xy 187.07354 -336.144108) (xy 187.36818 -336.438748)
			(xy 187.36818 -344.269568) (xy 186.763152 -344.874596) (xy 167.769032 -344.874596) (xy 167.718994 -344.924634)
			(xy 167.718994 -351.838514) (xy 167.39108 -352.166428) (xy 167.39108 -352.819716) (xy 167.718994 -353.14763)
			(xy 167.91686 -353.345496) (xy 168.119806 -353.548442) (xy 169.904664 -353.548442) (xy 170.235118 -353.878896)
			(xy 170.235118 -355.73462) (xy 170.352974 -355.852476) (xy 171.981876 -355.852476) (xy 172.017944 -355.83749)
			(arc
				(start 172.064172 -355.791262)
				(mid 172.070228 -355.784012)
				(end 172.07484 -355.775768)
			)
			(xy 172.07484 -353.616006) (xy 172.175932 -353.514914) (xy 175.710596 -353.514914) (xy 176.446942 -353.514914)
			(xy 176.709324 -353.514914) (xy 176.94402 -353.74961) (xy 176.94402 -355.90099) (xy 176.5808 -356.26421)
			(xy 176.5808 -358.72039) (xy 177.26152 -359.40111) (xy 177.78984 -359.40111) (xy 177.94732 -359.24363)
			(xy 177.94732 -358.99725) (xy 177.777648 -358.827578) (xy 177.64252 -358.69245) (xy 177.64252 -353.730306)
			(xy 177.777648 -353.595178) (xy 177.85842 -353.514152) (xy 178.11496 -353.514152) (xy 179.286662 -353.514152)
			(xy 179.69992 -353.92741) (xy 179.69992 -355.68001) (xy 179.871878 -355.851968) (xy 181.632352 -355.851968)
			(xy 181.77256 -355.71176) (xy 181.77256 -353.76993) (xy 182.027576 -353.514914) (xy 183.642254 -353.514914)
			(xy 187.064904 -353.514914) (xy 187.39866 -353.84867) (xy 187.39866 -359.97261) (xy 187.58408 -360.15803)
			(xy 189.85738 -360.15803) (xy 190.890398 -360.15803)
		)
		(stroke
			(width 0)
			(type solid)
		)
		(fill yes)
		(layer "B.Cu")
		(net "GND")
	)
	(gr_poly
		(pts
			(xy 304.7746 -56.302148)
			(arc
				(start 304.7746 -54.282086)
				(mid 304.663121 -54.012592)
				(end 304.7746 -53.743098)
			)
			(arc
				(start 304.7746 -52.623974)
				(mid 304.667547 -52.490934)
				(end 304.629312 -52.324508)
			)
			(arc
				(start 304.629312 -52.324508)
				(mid 304.631841 -52.280397)
				(end 304.639472 -52.236878)
			)
			(xy 304.640996 -52.231036)
			(arc
				(start 304.640996 -51.209448)
				(mid 304.669064 -51.067869)
				(end 304.7492 -50.947828)
			)
			(xy 304.7746 -50.922428)
			(arc
				(start 304.7746 -48.03648)
				(mid 304.601345 -47.716948)
				(end 304.7746 -47.397416)
			)
			(arc
				(start 304.7746 -47.27448)
				(mid 304.647587 -47.136772)
				(end 304.601372 -46.955202)
			)
			(xy 304.601372 -46.93412) (xy 304.038 -46.370748) (xy 302.8188 -46.370748) (xy 302.4378 -46.751748)
			(xy 302.4378 -56.352948) (xy 302.5902 -56.505348) (xy 304.5714 -56.505348)
		)
		(stroke
			(width 0)
			(type solid)
		)
		(fill yes)
		(layer "B.Cu")
		(net "GND")
	)
	(gr_poly
		(pts
			(xy 336.164936 -48.463708) (xy 336.164936 -47.371762)
			(arc
				(start 336.162396 -47.363888)
				(mid 336.148379 -47.307756)
				(end 336.1436 -47.250096)
			)
			(arc
				(start 336.1436 -47.250096)
				(mid 336.148342 -47.192429)
				(end 336.162396 -47.136304)
			)
			(xy 336.164936 -47.12843) (xy 336.164936 -47.038768) (xy 336.089244 -46.963076) (xy 335.524348 -46.963076)
			(xy 335.3308 -46.769528) (xy 335.3308 -45.237908) (xy 335.555336 -45.013372) (xy 336.089752 -45.013372)
			(xy 336.162396 -44.940728) (xy 336.162396 -44.506388) (xy 336.071972 -44.415964)
			(arc
				(start 336.071972 -42.3291)
				(mid 336.040855 -42.255924)
				(end 335.966562 -42.2275)
			)
			(arc
				(start 335.953608 -42.227754)
				(mid 335.777586 -42.181209)
				(end 335.647538 -42.053764)
			)
			(xy 335.145634 -42.053764)
			(arc
				(start 335.135474 -42.091356)
				(mid 335.100538 -42.193861)
				(end 335.05267 -42.291)
			)
			(arc
				(start 335.05267 -42.291)
				(mid 335.016092 -42.348715)
				(end 334.974946 -42.403268)
			)
			(xy 334.974946 -43.480228) (xy 335.148682 -43.653964) (xy 335.358994 -43.653964) (xy 335.672176 -43.967146)
			(xy 335.672176 -44.480988) (xy 335.555082 -44.598082) (xy 335.540096 -44.598082) (xy 335.50479 -44.633388)
			(xy 335.501996 -44.633388) (xy 335.438496 -44.696888) (xy 335.41208 -44.696888) (xy 335.38414 -44.724828)
			(xy 334.817974 -44.724828) (xy 334.801464 -44.741338) (xy 334.801464 -47.615856) (xy 334.622648 -47.794672)
			(xy 334.622648 -48.19015) (xy 334.740758 -48.30826) (xy 335.145888 -48.30826) (xy 335.341976 -48.504348)
			(xy 336.124296 -48.504348)
		)
		(stroke
			(width 0)
			(type solid)
		)
		(fill yes)
		(layer "B.Cu")
		(net "GND")
	)
	(gr_poly
		(pts
			(arc
				(start 256.189226 -105.66273)
				(mid 256.329061 -105.350094)
				(end 256.64668 -105.22204)
			)
			(arc
				(start 256.64668 -105.22204)
				(mid 256.922839 -105.314737)
				(end 257.087116 -105.555288)
			)
			(xy 257.09753 -105.592372)
			(arc
				(start 257.703574 -105.592372)
				(mid 257.773726 -105.549163)
				(end 257.854704 -105.533952)
			)
			(xy 258.12242 -105.533952) (xy 258.12242 -105.593896)
			(arc
				(start 258.473194 -105.593896)
				(mid 258.616491 -105.499493)
				(end 258.784852 -105.466388)
			)
			(arc
				(start 259.394706 -105.466388)
				(mid 259.628285 -105.532662)
				(end 259.792216 -105.711752)
			)
			(xy 261.1501 -105.711752) (xy 261.331202 -105.53065) (xy 261.331202 -100.314252) (xy 261.331456 -100.313998)
			(xy 261.331456 -100.193348) (xy 260.915404 -99.777296) (xy 259.34543 -99.777296) (xy 259.106924 -100.016056)
			(xy 259.106924 -101.433376) (xy 259.10667 -101.433376) (xy 259.10667 -101.857048) (xy 258.490466 -102.473252)
			(xy 254.741426 -102.473252) (xy 254.606806 -102.607872) (xy 254.606806 -105.528872) (xy 254.789686 -105.711752)
			(xy 256.187448 -105.711752)
		)
		(stroke
			(width 0)
			(type solid)
		)
		(fill yes)
		(layer "B.Cu")
		(net "P3V3_AUX_CLK_GEN_VDDMXCK_CK440")
	)
	(gr_poly
		(pts
			(xy 432.3588 -185.765948) (xy 432.3588 -182.159148) (xy 430.878996 -180.679344) (xy 430.859692 -180.678328)
			(xy 430.829482 -180.676091) (xy 430.769994 -180.664648) (xy 430.712535 -180.645458) (xy 430.658111 -180.618855)
			(xy 430.607671 -180.585305) (xy 430.562098 -180.545394) (xy 430.522189 -180.499821) (xy 430.48864 -180.44938)
			(xy 430.462038 -180.394955) (xy 430.442849 -180.337496) (xy 430.431408 -180.278008) (xy 430.429162 -180.247798)
			(xy 430.428146 -180.228494) (xy 430.0982 -179.898548) (xy 426.5168 -179.898548) (xy 426.3136 -180.101748)
			(xy 426.3136 -184.772808) (xy 431.191922 -184.772808) (xy 431.195993 -184.717186) (xy 431.208119 -184.662749)
			(xy 431.228042 -184.610658) (xy 431.255338 -184.562023) (xy 431.289424 -184.51788) (xy 431.329573 -184.479171)
			(xy 431.374931 -184.44672) (xy 431.424531 -184.421219) (xy 431.477315 -184.403212) (xy 431.532158 -184.393082)
			(xy 431.587892 -184.391045) (xy 431.643329 -184.397145) (xy 431.697286 -184.411251) (xy 431.748615 -184.433063)
			(xy 431.796221 -184.462117) (xy 431.839089 -184.497792) (xy 431.876306 -184.539329) (xy 431.907079 -184.585842)
			(xy 431.930751 -184.636339) (xy 431.946819 -184.689746) (xy 431.954939 -184.744922) (xy 431.955448 -184.772808)
			(xy 431.954939 -184.800694) (xy 431.946819 -184.85587) (xy 431.930751 -184.909277) (xy 431.907079 -184.959774)
			(xy 431.876306 -185.006287) (xy 431.839089 -185.047824) (xy 431.796221 -185.083499) (xy 431.748615 -185.112553)
			(xy 431.697286 -185.134365) (xy 431.643329 -185.148471) (xy 431.587892 -185.154571) (xy 431.532158 -185.152534)
			(xy 431.477315 -185.142404) (xy 431.424531 -185.124397) (xy 431.374931 -185.098896) (xy 431.329573 -185.066445)
			(xy 431.289424 -185.027736) (xy 431.255338 -184.983593) (xy 431.228042 -184.934958) (xy 431.208119 -184.882867)
			(xy 431.195993 -184.82843) (xy 431.191922 -184.772808) (xy 426.3136 -184.772808) (xy 426.3136 -185.816748)
			(xy 426.5168 -186.019948) (xy 432.1048 -186.019948)
		)
		(stroke
			(width 0)
			(type solid)
		)
		(fill yes)
		(layer "B.Cu")
		(net "GND")
	)
	(gr_poly
		(pts
			(xy 380.5682 -79.441548)
			(arc
				(start 380.5682 -72.253856)
				(mid 380.28426 -71.830438)
				(end 380.5682 -71.40702)
			)
			(xy 380.5682 -71.338948) (xy 380.111 -70.881748)
			(arc
				(start 379.75667 -70.881748)
				(mid 379.674839 -70.92313)
				(end 379.659642 -71.013574)
			)
			(arc
				(start 379.659642 -71.013574)
				(mid 379.672562 -71.069563)
				(end 379.676914 -71.126858)
			)
			(arc
				(start 379.676914 -71.126858)
				(mid 379.565173 -71.396625)
				(end 379.295406 -71.508366)
			)
			(arc
				(start 379.295406 -71.508366)
				(mid 379.060282 -71.427299)
				(end 378.925074 -71.218552)
			)
			(arc
				(start 378.925074 -71.218552)
				(mid 378.865959 -71.149572)
				(end 378.775214 -71.155306)
			)
			(xy 378.754132 -71.134224) (xy 377.064016 -71.134224) (xy 376.886216 -71.312024) (xy 376.886216 -81.144364)
			(xy 377.0122 -81.270348) (xy 378.7394 -81.270348)
		)
		(stroke
			(width 0)
			(type solid)
		)
		(fill yes)
		(layer "B.Cu")
		(net "GND")
	)
	(gr_poly
		(pts
			(xy 232.63733 -121.137934) (xy 232.63733 -120.051576) (xy 232.613708 -120.027954) (xy 232.103676 -120.027954)
			(arc
				(start 232.095802 -120.069102)
				(mid 231.964162 -120.291288)
				(end 231.721152 -120.378728)
			)
			(arc
				(start 231.721152 -120.378728)
				(mid 231.586675 -120.354259)
				(end 231.469438 -120.283986)
			)
			(arc
				(start 231.469438 -120.283986)
				(mid 231.372312 -120.263293)
				(end 231.304084 -120.335294)
			)
			(arc
				(start 231.304084 -120.335294)
				(mid 231.168564 -120.54266)
				(end 230.93426 -120.623076)
			)
			(arc
				(start 230.93426 -120.623076)
				(mid 230.699001 -120.541835)
				(end 230.563928 -120.332754)
			)
			(xy 230.560372 -120.319038)
			(arc
				(start 230.259128 -120.01754)
				(mid 230.189928 -119.91407)
				(end 230.165656 -119.791988)
			)
			(xy 230.165656 -119.678704) (xy 229.865682 -119.37873) (xy 229.036118 -119.37873) (xy 228.97211 -119.442738)
			(arc
				(start 228.977952 -119.469916)
				(mid 228.984432 -119.510071)
				(end 228.986588 -119.550688)
			)
			(arc
				(start 228.986588 -119.550688)
				(mid 228.979223 -119.625288)
				(end 228.957378 -119.696992)
			)
			(xy 228.953568 -119.70639) (xy 228.953568 -121.079006) (xy 229.130606 -121.256044) (xy 232.51922 -121.256044)
		)
		(stroke
			(width 0)
			(type solid)
		)
		(fill yes)
		(layer "B.Cu")
		(net "P3V3")
	)
	(gr_poly
		(pts
			(xy 461.920844 -57.575704) (xy 461.920844 -51.218592) (xy 461.5942 -50.891948) (xy 441.879482 -50.891948)
			(xy 440.7916 -51.97983) (xy 440.7916 -52.738528) (xy 448.662552 -52.738528) (xy 448.662552 -51.214528)
			(xy 448.663053 -51.201147) (xy 448.669971 -51.175296) (xy 448.683345 -51.152116) (xy 448.702262 -51.133186)
			(xy 448.725433 -51.119798) (xy 448.75128 -51.112862) (xy 448.76466 -51.11242) (xy 450.28866 -51.11242)
			(xy 450.302051 -51.112825) (xy 450.327922 -51.119749) (xy 450.351118 -51.133136) (xy 450.370057 -51.152072)
			(xy 450.383446 -51.175267) (xy 450.390374 -51.201137) (xy 450.390768 -51.214528) (xy 450.390768 -52.738528)
			(xy 456.170792 -52.738528) (xy 456.170792 -51.214528) (xy 456.171214 -51.201139) (xy 456.178139 -51.175271)
			(xy 456.191524 -51.152078) (xy 456.210456 -51.133141) (xy 456.233645 -51.11975) (xy 456.259511 -51.112818)
			(xy 456.2729 -51.11242) (xy 457.7969 -51.11242) (xy 457.810293 -51.11279) (xy 457.836165 -51.119724)
			(xy 457.859361 -51.133119) (xy 457.878299 -51.152061) (xy 457.891687 -51.175261) (xy 457.898614 -51.201135)
			(xy 457.899008 -51.214528) (xy 457.899008 -52.738528) (xy 457.898596 -52.751914) (xy 457.89166 -52.777774)
			(xy 457.878269 -52.800958) (xy 457.859335 -52.819887) (xy 457.836148 -52.833271) (xy 457.810287 -52.840199)
			(xy 457.7969 -52.840636) (xy 456.2729 -52.840636) (xy 456.259517 -52.840171) (xy 456.233663 -52.833245)
			(xy 456.210482 -52.819864) (xy 456.191553 -52.800941) (xy 456.178166 -52.777763) (xy 456.171232 -52.751911)
			(xy 456.170792 -52.738528) (xy 450.390768 -52.738528) (xy 450.390434 -52.751923) (xy 450.383493 -52.777798)
			(xy 450.370091 -52.800995) (xy 450.351141 -52.819932) (xy 450.327935 -52.833319) (xy 450.302055 -52.840243)
			(xy 450.28866 -52.840636) (xy 448.76466 -52.840636) (xy 448.751275 -52.840206) (xy 448.72542 -52.833271)
			(xy 448.702239 -52.819882) (xy 448.683311 -52.800952) (xy 448.669925 -52.777769) (xy 448.662992 -52.751913)
			(xy 448.662552 -52.738528) (xy 440.7916 -52.738528) (xy 440.7916 -57.775348) (xy 441.1472 -58.130948)
			(xy 461.3656 -58.130948)
		)
		(stroke
			(width 0)
			(type solid)
		)
		(fill yes)
		(layer "B.Cu")
		(net "P3V3_AUX")
	)
	(gr_poly
		(pts
			(xy 239.08258 -252.065028)
			(arc
				(start 239.08258 -251.371608)
				(mid 239.031114 -251.283239)
				(end 238.92891 -251.284486)
			)
			(arc
				(start 238.92891 -251.284486)
				(mid 238.815824 -251.332789)
				(end 238.69396 -251.349256)
			)
			(arc
				(start 238.69396 -251.349256)
				(mid 238.236252 -250.891548)
				(end 238.69396 -250.43384)
			)
			(arc
				(start 238.69396 -250.43384)
				(mid 238.815828 -250.450292)
				(end 238.92891 -250.49861)
			)
			(arc
				(start 238.92891 -250.49861)
				(mid 239.031063 -250.499767)
				(end 239.08258 -250.411488)
			)
			(xy 239.08258 -250.000008) (xy 237.8075 -248.724928) (xy 237.8075 -245.166388) (xy 237.72114 -245.080028)
			(xy 233.5276 -245.080028) (xy 232.791 -245.816628) (xy 232.791 -248.562368) (xy 233.24566 -249.017028)
			(xy 235.53674 -249.017028) (xy 235.63326 -248.920508) (xy 235.63326 -248.476008) (xy 235.6866 -248.422668)
			(xy 236.84484 -248.422668) (xy 237.05058 -248.628408) (xy 237.05058 -250.670568) (xy 237.32236 -250.942348)
			(xy 237.71098 -250.942348) (xy 237.71098 -251.372624) (xy 237.759748 -251.421138) (xy 237.759748 -251.934218)
			(xy 237.71098 -251.982732) (xy 237.71098 -252.128528) (xy 237.44936 -252.390148) (xy 234.56392 -252.390148)
			(xy 234.42422 -252.529848) (xy 234.42422 -253.622048) (xy 234.51058 -253.708408) (xy 237.4392 -253.708408)
		)
		(stroke
			(width 0)
			(type solid)
		)
		(fill yes)
		(layer "B.Cu")
		(net "VFG3P3_CLK_GEN")
	)
	(gr_poly
		(pts
			(xy 342.859868 -51.933602) (xy 342.859868 -51.531266) (xy 342.690196 -51.361594) (xy 342.267286 -51.361594)
			(arc
				(start 342.25484 -51.394614)
				(mid 342.124234 -51.562347)
				(end 341.921338 -51.625754)
			)
			(arc
				(start 341.921338 -51.625754)
				(mid 341.702185 -51.550332)
				(end 341.575898 -51.356006)
			)
			(xy 341.566246 -51.317652) (xy 341.02802 -51.317652) (xy 340.844378 -51.13401) (xy 340.844378 -51.126136)
			(xy 340.749128 -51.03114) (xy 340.749128 -50.831242) (xy 340.748112 -50.829972) (xy 340.748112 -49.394618)
			(xy 341.015066 -49.127664) (xy 341.22868 -49.127664) (xy 341.338916 -49.017428) (xy 341.338916 -48.68291)
			(xy 341.266526 -48.61052) (xy 340.872826 -48.61052)
			(arc
				(start 340.082378 -49.400968)
				(mid 340.052352 -49.472295)
				(end 340.081362 -49.54397)
			)
			(arc
				(start 340.081362 -49.54397)
				(mid 340.156588 -49.658468)
				(end 340.182962 -49.79289)
			)
			(arc
				(start 340.182962 -49.79289)
				(mid 340.07866 -50.044696)
				(end 339.826854 -50.148998)
			)
			(arc
				(start 339.826854 -50.148998)
				(mid 339.742973 -50.13904)
				(end 339.663786 -50.109628)
			)
			(arc
				(start 339.663786 -50.109628)
				(mid 339.564445 -50.113202)
				(end 339.515704 -50.199798)
			)
			(xy 339.515704 -50.618644) (xy 339.667088 -50.76952) (xy 339.846666 -50.76952) (xy 340.1441 -51.067208)
			(xy 340.1441 -51.50358) (xy 340.602062 -51.961542) (xy 341.40267 -51.961542) (xy 341.515954 -52.074826)
			(xy 342.718644 -52.074826)
		)
		(stroke
			(width 0)
			(type solid)
		)
		(fill yes)
		(layer "B.Cu")
		(net "P1V8_PCH_PLL_AUX")
	)
	(gr_poly
		(pts
			(xy 261.025132 -97.187258) (xy 261.028942 -97.176082) (xy 261.038841 -97.148858) (xy 261.065689 -97.09753)
			(xy 261.099987 -97.05085) (xy 261.140946 -97.00989) (xy 261.187626 -96.975592) (xy 261.238954 -96.948743)
			(xy 261.266178 -96.938846) (xy 261.277354 -96.935036) (xy 261.333234 -96.879156) (xy 262.578088 -96.879156)
			(xy 263.58088 -97.881948) (xy 266.319 -97.881948) (xy 266.446 -97.754948) (xy 266.446 -96.230948)
			(xy 266.0904 -95.875348) (xy 264.92708 -95.875348) (xy 264.532618 -95.480886) (xy 264.532618 -94.28861)
			(xy 264.41908 -94.175072) (xy 257.474466 -94.175072) (xy 257.333242 -94.316296) (xy 257.333242 -95.194116)
			(xy 259.893798 -95.194116) (xy 259.893798 -95.13418) (xy 259.901621 -95.074758) (xy 259.917134 -95.016865)
			(xy 259.94007 -94.961492) (xy 259.970037 -94.909586) (xy 260.006524 -94.862036) (xy 260.048904 -94.819656)
			(xy 260.096454 -94.783169) (xy 260.14836 -94.753202) (xy 260.203733 -94.730266) (xy 260.261626 -94.714753)
			(xy 260.321048 -94.70693) (xy 260.380984 -94.70693) (xy 260.440406 -94.714753) (xy 260.498299 -94.730266)
			(xy 260.553672 -94.753202) (xy 260.605578 -94.783169) (xy 260.653128 -94.819656) (xy 260.695508 -94.862036)
			(xy 260.731995 -94.909586) (xy 260.761962 -94.961492) (xy 260.784898 -95.016865) (xy 260.800411 -95.074758)
			(xy 260.808234 -95.13418) (xy 260.808724 -95.164148) (xy 260.808234 -95.194116) (xy 260.800411 -95.253538)
			(xy 260.784898 -95.311431) (xy 260.761962 -95.366804) (xy 260.731995 -95.41871) (xy 260.695508 -95.46626)
			(xy 260.653128 -95.50864) (xy 260.605578 -95.545127) (xy 260.553672 -95.575094) (xy 260.498299 -95.59803)
			(xy 260.440406 -95.613543) (xy 260.380984 -95.621366) (xy 260.321048 -95.621366) (xy 260.261626 -95.613543)
			(xy 260.203733 -95.59803) (xy 260.14836 -95.575094) (xy 260.096454 -95.545127) (xy 260.048904 -95.50864)
			(xy 260.006524 -95.46626) (xy 259.970037 -95.41871) (xy 259.94007 -95.366804) (xy 259.917134 -95.311431)
			(xy 259.901621 -95.253538) (xy 259.893798 -95.194116) (xy 257.333242 -95.194116) (xy 257.333242 -95.748348)
			(xy 257.557016 -95.972122) (xy 257.709162 -95.972122) (xy 257.814318 -95.866712) (xy 258.95173 -95.866712)
			(xy 259.106924 -96.021906) (xy 259.106924 -96.132904) (xy 259.118862 -96.145096) (xy 259.118862 -98.110548)
			(xy 259.398262 -98.389948) (xy 259.822442 -98.389948)
		)
		(stroke
			(width 0)
			(type solid)
		)
		(fill yes)
		(layer "B.Cu")
		(net "P3V3_AUX_CLK_GEN_VDD_CK440")
	)
	(gr_poly
		(pts
			(xy 180.3273 -115.103148) (xy 180.3273 -114.836448) (xy 180.22824 -114.737388) (xy 180.03012 -114.737388)
			(xy 179.96154 -114.668808) (xy 179.96154 -114.483388) (xy 180.01996 -114.424968) (xy 180.231288 -114.424968)
			(xy 180.36794 -114.288316) (xy 180.36794 -114.064288) (xy 180.24094 -113.937288) (xy 180.03012 -113.937288)
			(xy 179.96154 -113.868708) (xy 179.96154 -113.673128) (xy 180.01869 -113.615978) (xy 180.12029 -113.615978)
			(xy 180.1495 -113.586768) (xy 180.1495 -113.175288) (xy 180.10124 -113.127028) (xy 180.01488 -113.127028)
			(xy 179.96154 -113.073688) (xy 179.96154 -112.878108) (xy 180.01996 -112.819688) (xy 180.236622 -112.819688)
			(xy 180.3781 -112.67821) (xy 180.3781 -112.507268) (xy 180.21554 -112.344708) (xy 180.03266 -112.344708)
			(xy 179.96408 -112.276128) (xy 179.96408 -112.070388) (xy 180.01488 -112.019588) (xy 180.236876 -112.019588)
			(xy 180.39842 -111.858044) (xy 180.39842 -111.722408) (xy 180.35016 -111.674148) (xy 179.95392 -111.674148)
			(xy 179.1335 -112.494568) (xy 179.1335 -112.682528) (xy 179.0446 -112.771428) (xy 178.0667 -112.771428)
			(xy 178.0032 -112.707928) (xy 178.0032 -112.522508) (xy 177.05832 -111.577628) (xy 176.85512 -111.577628)
			(xy 176.74844 -111.684308) (xy 176.74844 -111.884968) (xy 176.89068 -112.027208) (xy 177.09388 -112.027208)
			(xy 177.14976 -112.083088) (xy 177.14976 -112.265968) (xy 177.0888 -112.326928) (xy 176.88814 -112.326928)
			(xy 176.75098 -112.464088) (xy 176.75098 -112.69599) (xy 176.882298 -112.827308) (xy 177.09388 -112.827308)
			(xy 177.14976 -112.883188) (xy 177.14976 -113.066068) (xy 177.09134 -113.124488) (xy 176.99482 -113.124488)
			(xy 176.911 -113.208308) (xy 176.911 -113.543588) (xy 176.99228 -113.624868) (xy 177.09134 -113.624868)
			(xy 177.14976 -113.683288) (xy 177.14976 -113.866168) (xy 177.09134 -113.924588) (xy 176.90592 -113.924588)
			(xy 176.76495 -114.065558) (xy 176.76495 -114.306858) (xy 176.8856 -114.427508) (xy 177.09388 -114.427508)
			(xy 177.14976 -114.483388) (xy 177.14976 -114.666268) (xy 177.09134 -114.724688) (xy 176.88306 -114.724688)
			(xy 176.75352 -114.854228) (xy 176.75352 -115.072668) (xy 176.84496 -115.164108) (xy 177.0507 -115.164108)
			(xy 177.99812 -114.216688) (xy 177.99812 -114.041428) (xy 178.05654 -113.983008) (xy 179.05222 -113.983008)
			(xy 179.11318 -114.043968) (xy 179.11318 -114.234468) (xy 180.05806 -115.179348) (xy 180.2511 -115.179348)
		)
		(stroke
			(width 0)
			(type solid)
		)
		(fill yes)
		(layer "B.Cu")
		(net "VCC_PLD_CORE")
	)
	(gr_poly
		(pts
			(xy 303.61128 -375.379996) (xy 303.61128 -363.268768) (xy 303.335436 -362.992924) (xy 298.84243 -362.992924)
			(xy 298.805092 -363.030262) (xy 298.805092 -365.042196) (xy 299.779436 -366.01654) (xy 299.779436 -368.201956)
			(xy 299.103542 -368.87785) (xy 293.82847 -368.87785) (xy 293.030656 -368.080036) (xy 293.030656 -364.957106)
			(xy 293.413688 -364.574074) (xy 293.413688 -363.262926) (xy 293.143686 -362.992924) (xy 289.28949 -362.992924)
			(xy 289.077908 -363.204506) (xy 289.077908 -365.392208) (xy 290.147248 -366.461548) (xy 290.147248 -368.493548)
			(xy 291.770308 -370.116608) (xy 291.770308 -372.49855) (xy 298.442376 -372.49855) (xy 298.442376 -372.413854)
			(xy 298.450427 -372.32954) (xy 298.466456 -372.246374) (xy 298.490317 -372.165107) (xy 298.521796 -372.086477)
			(xy 298.560607 -372.011196) (xy 298.606397 -371.939944) (xy 298.658753 -371.873368) (xy 298.717201 -371.81207)
			(xy 298.781211 -371.756605) (xy 298.850203 -371.707476) (xy 298.923553 -371.665127) (xy 299.000596 -371.629943)
			(xy 299.080635 -371.602241) (xy 299.162944 -371.582273) (xy 299.246779 -371.57022) (xy 299.33138 -371.56619)
			(xy 299.415981 -371.57022) (xy 299.499816 -371.582273) (xy 299.582125 -371.602241) (xy 299.662164 -371.629943)
			(xy 299.739207 -371.665127) (xy 299.812557 -371.707476) (xy 299.881549 -371.756605) (xy 299.945559 -371.81207)
			(xy 300.004007 -371.873368) (xy 300.056363 -371.939944) (xy 300.102153 -372.011196) (xy 300.140964 -372.086477)
			(xy 300.172443 -372.165107) (xy 300.196304 -372.246374) (xy 300.212333 -372.32954) (xy 300.220384 -372.413854)
			(xy 300.220888 -372.456202) (xy 300.220384 -372.49855) (xy 300.212333 -372.582864) (xy 300.196304 -372.66603)
			(xy 300.172443 -372.747297) (xy 300.140964 -372.825927) (xy 300.102153 -372.901208) (xy 300.056363 -372.97246)
			(xy 300.004007 -373.039036) (xy 299.945559 -373.100334) (xy 299.881549 -373.155799) (xy 299.812557 -373.204928)
			(xy 299.739207 -373.247277) (xy 299.662164 -373.282461) (xy 299.582125 -373.310163) (xy 299.499816 -373.330131)
			(xy 299.415981 -373.342184) (xy 299.33138 -373.346215) (xy 299.246779 -373.342184) (xy 299.162944 -373.330131)
			(xy 299.080635 -373.310163) (xy 299.000596 -373.282461) (xy 298.923553 -373.247277) (xy 298.850203 -373.204928)
			(xy 298.781211 -373.155799) (xy 298.717201 -373.100334) (xy 298.658753 -373.039036) (xy 298.606397 -372.97246)
			(xy 298.560607 -372.901208) (xy 298.521796 -372.825927) (xy 298.490317 -372.747297) (xy 298.466456 -372.66603)
			(xy 298.450427 -372.582864) (xy 298.442376 -372.49855) (xy 291.770308 -372.49855) (xy 291.770308 -375.242328)
			(xy 292.202108 -375.674128) (xy 303.317148 -375.674128)
		)
		(stroke
			(width 0)
			(type solid)
		)
		(fill yes)
		(layer "B.Cu")
		(net "SW_P12V_PVCCFA_EHV_FIVRA_CPU0_L")
	)
	(gr_poly
		(pts
			(xy 430.994058 -373.17299) (xy 430.994058 -362.485432) (xy 430.813718 -362.305092) (xy 426.216826 -362.305092)
			(xy 426.179488 -362.34243) (xy 426.179488 -364.354364) (xy 427.153832 -365.328708) (xy 427.153832 -367.514124)
			(xy 426.477938 -368.190018) (xy 421.202866 -368.190018) (xy 420.405052 -367.392204) (xy 420.405052 -364.269274)
			(xy 420.788084 -363.886242) (xy 420.788084 -362.575094) (xy 420.518082 -362.305092) (xy 416.663886 -362.305092)
			(xy 416.452304 -362.516674) (xy 416.452304 -364.666276) (xy 417.526978 -365.74095) (xy 417.526978 -367.65611)
			(xy 419.142418 -369.27155) (xy 419.142418 -371.810718) (xy 425.816772 -371.810718) (xy 425.816772 -371.726022)
			(xy 425.824823 -371.641708) (xy 425.840852 -371.558542) (xy 425.864713 -371.477275) (xy 425.896192 -371.398645)
			(xy 425.935003 -371.323364) (xy 425.980793 -371.252112) (xy 426.033149 -371.185536) (xy 426.091597 -371.124238)
			(xy 426.155607 -371.068773) (xy 426.224599 -371.019644) (xy 426.297949 -370.977295) (xy 426.374992 -370.942111)
			(xy 426.455031 -370.914409) (xy 426.53734 -370.894441) (xy 426.621175 -370.882388) (xy 426.705776 -370.878358)
			(xy 426.790377 -370.882388) (xy 426.874212 -370.894441) (xy 426.956521 -370.914409) (xy 427.03656 -370.942111)
			(xy 427.113603 -370.977295) (xy 427.186953 -371.019644) (xy 427.255945 -371.068773) (xy 427.319955 -371.124238)
			(xy 427.378403 -371.185536) (xy 427.430759 -371.252112) (xy 427.476549 -371.323364) (xy 427.51536 -371.398645)
			(xy 427.546839 -371.477275) (xy 427.5707 -371.558542) (xy 427.586729 -371.641708) (xy 427.59478 -371.726022)
			(xy 427.595284 -371.76837) (xy 427.59478 -371.810718) (xy 427.586729 -371.895032) (xy 427.5707 -371.978198)
			(xy 427.546839 -372.059465) (xy 427.51536 -372.138095) (xy 427.476549 -372.213376) (xy 427.430759 -372.284628)
			(xy 427.378403 -372.351204) (xy 427.319955 -372.412502) (xy 427.255945 -372.467967) (xy 427.186953 -372.517096)
			(xy 427.113603 -372.559445) (xy 427.03656 -372.594629) (xy 426.956521 -372.622331) (xy 426.874212 -372.642299)
			(xy 426.790377 -372.654352) (xy 426.705776 -372.658383) (xy 426.621175 -372.654352) (xy 426.53734 -372.642299)
			(xy 426.455031 -372.622331) (xy 426.374992 -372.594629) (xy 426.297949 -372.559445) (xy 426.224599 -372.517096)
			(xy 426.155607 -372.467967) (xy 426.091597 -372.412502) (xy 426.033149 -372.351204) (xy 425.980793 -372.284628)
			(xy 425.935003 -372.213376) (xy 425.896192 -372.138095) (xy 425.864713 -372.059465) (xy 425.840852 -371.978198)
			(xy 425.824823 -371.895032) (xy 425.816772 -371.810718) (xy 419.142418 -371.810718) (xy 419.142418 -374.57507)
			(xy 419.754558 -375.18721) (xy 428.979838 -375.18721)
		)
		(stroke
			(width 0)
			(type solid)
		)
		(fill yes)
		(layer "B.Cu")
		(net "SW_P12V_PVCCFA_EHV_FIVRA_CPU0_R")
	)
	(gr_poly
		(pts
			(xy 10.35558 -100.975668)
			(arc
				(start 10.35558 -100.736908)
				(mid 10.291661 -100.623706)
				(end 10.269474 -100.495608)
			)
			(arc
				(start 10.269474 -100.495608)
				(mid 10.288907 -100.375144)
				(end 10.34542 -100.267008)
			)
			(xy 10.35558 -100.253546)
			(arc
				(start 10.35558 -100.127816)
				(mid 10.305887 -100.040476)
				(end 10.205466 -100.038662)
			)
			(arc
				(start 10.205466 -100.038662)
				(mid 10.099833 -100.079984)
				(end 9.98728 -100.094034)
			)
			(arc
				(start 9.98728 -100.094034)
				(mid 9.529572 -99.636326)
				(end 9.98728 -99.178618)
			)
			(arc
				(start 9.98728 -99.178618)
				(mid 10.09983 -99.19268)
				(end 10.205466 -99.23399)
			)
			(arc
				(start 10.205466 -99.23399)
				(mid 10.305835 -99.232089)
				(end 10.35558 -99.144836)
			)
			(xy 10.35558 -98.832416)
			(arc
				(start 10.314178 -98.824542)
				(mid 9.941043 -98.374708)
				(end 10.314178 -97.924874)
			)
			(xy 10.35558 -97.917) (xy 10.35558 -97.711768) (xy 9.72566 -97.081848) (xy 6.02742 -97.081848) (xy 5.44576 -97.663508)
			(xy 5.44576 -100.912168) (xy 5.91312 -101.379528) (xy 9.95172 -101.379528)
		)
		(stroke
			(width 0)
			(type solid)
		)
		(fill yes)
		(layer "B.Cu")
		(net "GND")
	)
	(gr_poly
		(pts
			(xy 186.938666 -344.079322) (xy 186.938666 -336.773774) (xy 186.76112 -336.596228) (xy 184.23509 -336.596228)
			(xy 184.23509 -336.65541)
			(arc
				(start 184.237884 -336.663538)
				(mid 184.242013 -336.679693)
				(end 184.243472 -336.696304)
			)
			(arc
				(start 184.243472 -338.271358)
				(mid 184.21355 -338.343469)
				(end 184.141364 -338.373212)
			)
			(arc
				(start 182.561484 -338.373212)
				(mid 182.492766 -338.341742)
				(end 182.464456 -338.271612)
			)
			(arc
				(start 182.464456 -336.696304)
				(mid 182.4659 -336.67969)
				(end 182.470044 -336.663538)
			)
			(xy 182.472838 -336.65541) (xy 182.472838 -336.596228) (xy 178.03749 -336.596228) (xy 178.03749 -336.65541)
			(arc
				(start 178.040284 -336.663538)
				(mid 178.044413 -336.679693)
				(end 178.045872 -336.696304)
			)
			(arc
				(start 178.045872 -338.271358)
				(mid 178.01595 -338.343469)
				(end 177.943764 -338.373212)
			)
			(arc
				(start 176.363884 -338.373212)
				(mid 176.295166 -338.341742)
				(end 176.266856 -338.271612)
			)
			(arc
				(start 176.266856 -336.696304)
				(mid 176.2683 -336.67969)
				(end 176.272444 -336.663538)
			)
			(xy 176.275238 -336.65541) (xy 176.275238 -336.596228)
			(arc
				(start 171.89958 -336.596228)
				(mid 171.858867 -336.616645)
				(end 171.850812 -336.661506)
			)
			(arc
				(start 171.850812 -336.661506)
				(mid 171.853865 -336.675712)
				(end 171.854876 -336.690208)
			)
			(xy 171.854876 -337.371182)
			(arc
				(start 171.85513 -338.265008)
				(mid 171.825313 -338.337119)
				(end 171.753276 -338.367116)
			)
			(arc
				(start 170.178222 -338.367116)
				(mid 170.106111 -338.337194)
				(end 170.076368 -338.265008)
			)
			(arc
				(start 170.076368 -336.690208)
				(mid 170.077369 -336.675711)
				(end 170.080432 -336.661506)
			)
			(arc
				(start 170.080432 -336.661506)
				(mid 170.072434 -336.616603)
				(end 170.031664 -336.596228)
			)
			(xy 166.83228 -336.596228) (xy 166.67734 -336.751168) (xy 166.67734 -344.062558) (xy 167.23487 -344.620088)
			(xy 186.3979 -344.620088)
		)
		(stroke
			(width 0)
			(type solid)
		)
		(fill yes)
		(layer "B.Cu")
		(net "PVCCFA_EHV_FIVRA_CPU1")
	)
	(gr_poly
		(pts
			(arc
				(start 174.886874 -114.01044)
				(mid 174.975363 -114.06675)
				(end 175.066452 -114.014758)
			)
			(arc
				(start 175.066452 -114.014758)
				(mid 175.107877 -113.956263)
				(end 175.16094 -113.908078)
			)
			(xy 175.16094 -113.684812) (xy 175.2219 -113.623852) (xy 175.295052 -113.623852) (xy 175.295052 -113.123472)
			(xy 175.21936 -113.123472) (xy 175.16094 -113.065052)
			(arc
				(start 175.16094 -112.842802)
				(mid 175.060765 -112.725407)
				(end 175.024796 -112.57534)
			)
			(arc
				(start 175.024796 -112.57534)
				(mid 175.060082 -112.426762)
				(end 175.1584 -112.30991)
			)
			(xy 175.1584 -112.085628) (xy 175.00346 -111.930688) (xy 175.00346 -111.609632) (xy 175.15586 -111.457232)
			(xy 175.15586 -111.294672) (xy 175.22444 -111.226092) (xy 175.295052 -111.226092) (xy 175.295052 -111.175038)
			(xy 175.59274 -110.877604) (xy 175.59274 -110.702852) (xy 175.53432 -110.644432) (xy 175.3616 -110.644432)
			(xy 174.32528 -111.680752)
			(arc
				(start 174.32528 -112.16259)
				(mid 174.366662 -112.244421)
				(end 174.457106 -112.259618)
			)
			(arc
				(start 174.457106 -112.259618)
				(mid 174.505687 -112.248391)
				(end 174.555404 -112.244632)
			)
			(arc
				(start 174.555658 -112.244632)
				(mid 174.886366 -112.57534)
				(end 174.555658 -112.906048)
			)
			(arc
				(start 174.555404 -112.906048)
				(mid 174.505693 -112.902252)
				(end 174.457106 -112.891062)
			)
			(arc
				(start 174.457106 -112.891062)
				(mid 174.366646 -112.906237)
				(end 174.32528 -112.98809)
			)
			(arc
				(start 174.32528 -113.448846)
				(mid 174.376205 -113.47964)
				(end 174.421546 -113.518188)
			)
			(arc
				(start 174.817278 -113.91392)
				(mid 174.855985 -113.959361)
				(end 174.886874 -114.01044)
			)
		)
		(stroke
			(width 0)
			(type solid)
		)
		(fill yes)
		(layer "B.Cu")
		(net "P3V3_AUX_FPGA_VCCIO0")
	)
	(gr_poly
		(pts
			(xy 195.969382 -32.595312) (xy 195.969382 -25.404572)
			(arc
				(start 195.49364 -24.929084)
				(mid 195.410945 -24.805323)
				(end 195.38188 -24.659336)
			)
			(xy 195.38188 -21.505164) (xy 194.661028 -20.784312) (xy 193.778378 -20.784312) (xy 193.322448 -21.240242)
			(xy 193.322448 -22.523196)
			(arc
				(start 193.469006 -22.669754)
				(mid 193.551618 -22.79353)
				(end 193.580512 -22.939502)
			)
			(arc
				(start 193.580512 -24.364442)
				(mid 193.551574 -24.510395)
				(end 193.469006 -24.63419)
			)
			(arc
				(start 193.342006 -24.76119)
				(mid 193.21823 -24.843802)
				(end 193.072258 -24.872696)
			)
			(xy 192.835276 -24.872696)
			(arc
				(start 192.835276 -27.960828)
				(mid 192.882056 -28.046624)
				(end 192.979548 -28.053284)
			)
			(arc
				(start 192.979548 -28.053284)
				(mid 193.057406 -28.027117)
				(end 193.13906 -28.018232)
			)
			(arc
				(start 193.13906 -28.018232)
				(mid 193.520568 -28.39974)
				(end 193.13906 -28.781248)
			)
			(arc
				(start 193.13906 -28.781248)
				(mid 193.057408 -28.772352)
				(end 192.979548 -28.746196)
			)
			(arc
				(start 192.979548 -28.746196)
				(mid 192.882057 -28.752858)
				(end 192.835276 -28.838652)
			)
			(arc
				(start 192.835276 -33.373314)
				(mid 192.806338 -33.519267)
				(end 192.72377 -33.643062)
			)
			(arc
				(start 192.310512 -34.056066)
				(mid 192.288476 -34.16685)
				(end 192.382394 -34.229548)
			)
			(xy 194.335146 -34.229548)
		)
		(stroke
			(width 0)
			(type solid)
		)
		(fill yes)
		(layer "B.Cu")
		(net "GND")
	)
	(gr_poly
		(pts
			(arc
				(start 323.851524 -70.672706)
				(mid 323.941823 -70.617675)
				(end 323.934328 -70.512178)
			)
			(arc
				(start 323.934328 -70.512178)
				(mid 323.871225 -70.386075)
				(end 323.849492 -70.246748)
			)
			(arc
				(start 323.849492 -70.246748)
				(mid 324.3072 -69.78904)
				(end 324.764908 -70.246748)
			)
			(arc
				(start 324.764908 -70.246748)
				(mid 324.743186 -70.386079)
				(end 324.680072 -70.512178)
			)
			(arc
				(start 324.680072 -70.512178)
				(mid 324.672549 -70.61769)
				(end 324.762876 -70.672706)
			)
			(xy 326.202548 -70.672706) (xy 326.204326 -70.670928) (xy 326.515222 -70.670928) (xy 326.61987 -70.56628)
			(xy 326.61987 -69.910198) (xy 326.246998 -69.537326) (xy 326.246998 -67.24269) (xy 326.032368 -67.02806)
			(arc
				(start 319.596262 -67.02806)
				(mid 319.510046 -67.075908)
				(end 319.505076 -67.174364)
			)
			(arc
				(start 319.505076 -67.174364)
				(mid 319.761234 -68.925234)
				(end 318.952626 -70.499224)
			)
			(arc
				(start 318.952626 -70.499224)
				(mid 318.93059 -70.610008)
				(end 319.024508 -70.672706)
			)
		)
		(stroke
			(width 0)
			(type solid)
		)
		(fill yes)
		(layer "B.Cu")
		(net "GND")
	)
	(gr_poly
		(pts
			(xy 340.028022 -48.707548) (xy 340.373716 -48.707548) (xy 340.851236 -48.230028) (xy 341.183976 -48.230028)
			(xy 341.394542 -48.019462) (xy 341.394542 -45.766736) (xy 341.15121 -45.523404) (xy 340.684104 -45.523404)
			(xy 340.51875 -45.35805) (xy 340.51875 -44.591224) (xy 340.236048 -44.428156) (xy 339.588348 -44.428156)
			(xy 339.376766 -44.639738) (xy 339.376766 -46.200314) (xy 339.37956 -46.203108) (xy 339.37956 -46.597295)
			(xy 339.935048 -46.597295) (xy 339.935048 -46.543997) (xy 339.942991 -46.491293) (xy 339.958701 -46.440363)
			(xy 339.981827 -46.392342) (xy 340.011851 -46.348305) (xy 340.048103 -46.309234) (xy 340.089774 -46.276003)
			(xy 340.135932 -46.249354) (xy 340.185546 -46.229882) (xy 340.237508 -46.218022) (xy 340.290658 -46.214039)
			(xy 340.343808 -46.218022) (xy 340.39577 -46.229882) (xy 340.445384 -46.249354) (xy 340.491542 -46.276003)
			(xy 340.533213 -46.309234) (xy 340.569465 -46.348305) (xy 340.599489 -46.392342) (xy 340.622615 -46.440363)
			(xy 340.638325 -46.491293) (xy 340.646268 -46.543997) (xy 340.646766 -46.570646) (xy 340.646268 -46.597295)
			(xy 340.638325 -46.649999) (xy 340.622615 -46.700929) (xy 340.599489 -46.74895) (xy 340.569465 -46.792987)
			(xy 340.533213 -46.832058) (xy 340.491542 -46.865289) (xy 340.445384 -46.891938) (xy 340.39577 -46.91141)
			(xy 340.343808 -46.92327) (xy 340.290658 -46.927254) (xy 340.237508 -46.92327) (xy 340.185546 -46.91141)
			(xy 340.135932 -46.891938) (xy 340.089774 -46.865289) (xy 340.048103 -46.832058) (xy 340.011851 -46.792987)
			(xy 339.981827 -46.74895) (xy 339.958701 -46.700929) (xy 339.942991 -46.649999) (xy 339.935048 -46.597295)
			(xy 339.37956 -46.597295) (xy 339.37956 -47.537095) (xy 339.935048 -47.537095) (xy 339.935048 -47.483797)
			(xy 339.942991 -47.431093) (xy 339.958701 -47.380163) (xy 339.981827 -47.332142) (xy 340.011851 -47.288105)
			(xy 340.048103 -47.249034) (xy 340.089774 -47.215803) (xy 340.135932 -47.189154) (xy 340.185546 -47.169682)
			(xy 340.237508 -47.157822) (xy 340.290658 -47.153839) (xy 340.343808 -47.157822) (xy 340.39577 -47.169682)
			(xy 340.445384 -47.189154) (xy 340.491542 -47.215803) (xy 340.533213 -47.249034) (xy 340.569465 -47.288105)
			(xy 340.599489 -47.332142) (xy 340.622615 -47.380163) (xy 340.638325 -47.431093) (xy 340.646268 -47.483797)
			(xy 340.646766 -47.510446) (xy 340.646268 -47.537095) (xy 340.638325 -47.589799) (xy 340.622615 -47.640729)
			(xy 340.599489 -47.68875) (xy 340.569465 -47.732787) (xy 340.533213 -47.771858) (xy 340.491542 -47.805089)
			(xy 340.445384 -47.831738) (xy 340.39577 -47.85121) (xy 340.343808 -47.86307) (xy 340.290658 -47.867054)
			(xy 340.237508 -47.86307) (xy 340.185546 -47.85121) (xy 340.135932 -47.831738) (xy 340.089774 -47.805089)
			(xy 340.048103 -47.771858) (xy 340.011851 -47.732787) (xy 339.981827 -47.68875) (xy 339.958701 -47.640729)
			(xy 339.942991 -47.589799) (xy 339.935048 -47.537095) (xy 339.37956 -47.537095) (xy 339.37956 -48.749966)
			(xy 339.434932 -48.805084) (xy 339.930232 -48.805084)
		)
		(stroke
			(width 0)
			(type solid)
		)
		(fill yes)
		(layer "B.Cu")
		(net "GND")
	)
	(gr_poly
		(pts
			(xy 272.406872 -73.62063) (xy 272.406872 -67.79768) (xy 270.706342 -66.09715) (xy 270.706342 -62.427358)
			(xy 270.64081 -62.361572) (xy 260.35127 -62.361572) (xy 258.85267 -62.982348) (xy 255.46025 -66.374768)
			(xy 263.097754 -66.374768) (xy 263.097754 -66.314832) (xy 263.105577 -66.25541) (xy 263.12109 -66.197517)
			(xy 263.144026 -66.142144) (xy 263.173993 -66.090238) (xy 263.21048 -66.042688) (xy 263.25286 -66.000308)
			(xy 263.30041 -65.963821) (xy 263.352316 -65.933854) (xy 263.407689 -65.910918) (xy 263.465582 -65.895405)
			(xy 263.525004 -65.887582) (xy 263.58494 -65.887582) (xy 263.644362 -65.895405) (xy 263.702255 -65.910918)
			(xy 263.757628 -65.933854) (xy 263.809534 -65.963821) (xy 263.857084 -66.000308) (xy 263.899464 -66.042688)
			(xy 263.935951 -66.090238) (xy 263.965918 -66.142144) (xy 263.988854 -66.197517) (xy 264.004367 -66.25541)
			(xy 264.01219 -66.314832) (xy 264.01268 -66.3448) (xy 264.01219 -66.374768) (xy 264.004367 -66.43419)
			(xy 263.988854 -66.492083) (xy 263.965918 -66.547456) (xy 263.935951 -66.599362) (xy 263.899464 -66.646912)
			(xy 263.857084 -66.689292) (xy 263.809534 -66.725779) (xy 263.757628 -66.755746) (xy 263.702255 -66.778682)
			(xy 263.644362 -66.794195) (xy 263.58494 -66.802018) (xy 263.525004 -66.802018) (xy 263.465582 -66.794195)
			(xy 263.407689 -66.778682) (xy 263.352316 -66.755746) (xy 263.30041 -66.725779) (xy 263.25286 -66.689292)
			(xy 263.21048 -66.646912) (xy 263.173993 -66.599362) (xy 263.144026 -66.547456) (xy 263.12109 -66.492083)
			(xy 263.105577 -66.43419) (xy 263.097754 -66.374768) (xy 255.46025 -66.374768) (xy 254.745998 -67.08902)
			(xy 261.67029 -67.08902) (xy 261.674361 -67.033398) (xy 261.686487 -66.978961) (xy 261.70641 -66.92687)
			(xy 261.733706 -66.878235) (xy 261.767792 -66.834092) (xy 261.807941 -66.795383) (xy 261.853299 -66.762932)
			(xy 261.902899 -66.737431) (xy 261.955683 -66.719424) (xy 262.010526 -66.709294) (xy 262.06626 -66.707257)
			(xy 262.121697 -66.713357) (xy 262.175654 -66.727463) (xy 262.226983 -66.749275) (xy 262.274589 -66.778329)
			(xy 262.317457 -66.814004) (xy 262.354674 -66.855541) (xy 262.385447 -66.902054) (xy 262.409119 -66.952551)
			(xy 262.425187 -67.005958) (xy 262.433307 -67.061134) (xy 262.433816 -67.08902) (xy 262.433307 -67.116906)
			(xy 262.425187 -67.172082) (xy 262.409119 -67.225489) (xy 262.385447 -67.275986) (xy 262.354674 -67.322499)
			(xy 262.317457 -67.364036) (xy 262.274589 -67.399711) (xy 262.226983 -67.428765) (xy 262.175654 -67.450577)
			(xy 262.121697 -67.464683) (xy 262.06626 -67.470783) (xy 262.010526 -67.468746) (xy 261.955683 -67.458616)
			(xy 261.902899 -67.440609) (xy 261.853299 -67.415108) (xy 261.807941 -67.382657) (xy 261.767792 -67.343948)
			(xy 261.733706 -67.299805) (xy 261.70641 -67.25117) (xy 261.686487 -67.199079) (xy 261.674361 -67.144642)
			(xy 261.67029 -67.08902) (xy 254.745998 -67.08902) (xy 253.468886 -68.366132) (xy 253.468886 -69.826378)
			(xy 253.822708 -70.1802) (xy 261.035546 -70.1802) (xy 264.808462 -73.953116) (xy 272.074386 -73.953116)
		)
		(stroke
			(width 0)
			(type solid)
		)
		(fill yes)
		(layer "B.Cu")
		(net "GND")
	)
	(gr_poly
		(pts
			(xy 300.192948 -353.8347) (xy 304.284634 -353.8347) (xy 304.719228 -353.400106) (xy 304.719228 -345.903296)
			(xy 304.46218 -345.646248) (xy 283.7434 -345.646248) (xy 283.49194 -345.897708) (xy 283.49194 -347.487748)
			(xy 286.409892 -347.487748) (xy 286.409892 -345.912948) (xy 286.410331 -345.89956) (xy 286.417252 -345.873693)
			(xy 286.430632 -345.8505) (xy 286.449562 -345.831562) (xy 286.472749 -345.81817) (xy 286.498612 -345.811238)
			(xy 286.512 -345.81084) (xy 288.0868 -345.81084) (xy 288.100194 -345.81119) (xy 288.12607 -345.818126)
			(xy 288.149268 -345.831524) (xy 288.168206 -345.850471) (xy 288.181593 -345.873675) (xy 288.188516 -345.899553)
			(xy 288.188908 -345.912948) (xy 288.188908 -347.487748) (xy 292.607492 -347.487748) (xy 292.607492 -345.912948)
			(xy 292.607931 -345.89956) (xy 292.614852 -345.873693) (xy 292.628232 -345.8505) (xy 292.647162 -345.831562)
			(xy 292.670349 -345.81817) (xy 292.696212 -345.811238) (xy 292.7096 -345.81084) (xy 294.2844 -345.81084)
			(xy 294.297794 -345.81119) (xy 294.32367 -345.818126) (xy 294.346868 -345.831524) (xy 294.365806 -345.850471)
			(xy 294.379193 -345.873675) (xy 294.386116 -345.899553) (xy 294.386508 -345.912948) (xy 294.386508 -347.487748)
			(xy 298.805092 -347.487748) (xy 298.805092 -345.912948) (xy 298.805531 -345.89956) (xy 298.812452 -345.873693)
			(xy 298.825832 -345.8505) (xy 298.844762 -345.831562) (xy 298.867949 -345.81817) (xy 298.893812 -345.811238)
			(xy 298.9072 -345.81084) (xy 300.482 -345.81084) (xy 300.495394 -345.81119) (xy 300.52127 -345.818126)
			(xy 300.544468 -345.831524) (xy 300.563406 -345.850471) (xy 300.576793 -345.873675) (xy 300.583716 -345.899553)
			(xy 300.584108 -345.912948) (xy 300.584108 -347.487748) (xy 300.583713 -347.501135) (xy 300.576773 -347.526996)
			(xy 300.563379 -347.550179) (xy 300.544441 -347.569108) (xy 300.521251 -347.582492) (xy 300.495388 -347.58942)
			(xy 300.482 -347.589856) (xy 298.9072 -347.589856) (xy 298.893819 -347.589372) (xy 298.867968 -347.582447)
			(xy 298.844788 -347.569069) (xy 298.82586 -347.55015) (xy 298.812471 -347.526977) (xy 298.805535 -347.501129)
			(xy 298.805092 -347.487748) (xy 294.386508 -347.487748) (xy 294.386113 -347.501135) (xy 294.379173 -347.526996)
			(xy 294.365779 -347.550179) (xy 294.346841 -347.569108) (xy 294.323651 -347.582492) (xy 294.297788 -347.58942)
			(xy 294.2844 -347.589856) (xy 292.7096 -347.589856) (xy 292.696219 -347.589372) (xy 292.670368 -347.582447)
			(xy 292.647188 -347.569069) (xy 292.62826 -347.55015) (xy 292.614871 -347.526977) (xy 292.607935 -347.501129)
			(xy 292.607492 -347.487748) (xy 288.188908 -347.487748) (xy 288.188513 -347.501135) (xy 288.181573 -347.526996)
			(xy 288.168179 -347.550179) (xy 288.149241 -347.569108) (xy 288.126051 -347.582492) (xy 288.100188 -347.58942)
			(xy 288.0868 -347.589856) (xy 286.512 -347.589856) (xy 286.498619 -347.589372) (xy 286.472768 -347.582447)
			(xy 286.449588 -347.569069) (xy 286.43066 -347.55015) (xy 286.417271 -347.526977) (xy 286.410335 -347.501129)
			(xy 286.409892 -347.487748) (xy 283.49194 -347.487748) (xy 283.49194 -353.710748) (xy 283.615892 -353.8347)
			(xy 287.090612 -353.8347) (xy 287.23844 -353.982528) (xy 290.1696 -353.982528) (xy 290.317428 -353.8347)
			(xy 297.006772 -353.8347) (xy 297.185334 -354.013262) (xy 300.014386 -354.013262)
		)
		(stroke
			(width 0)
			(type solid)
		)
		(fill yes)
		(layer "B.Cu")
		(net "PVCCFA_EHV_FIVRA_CPU0")
	)
	(gr_poly
		(pts
			(xy 342.38311 -50.762154) (xy 342.38565 -50.745644) (xy 342.39045 -50.717827) (xy 342.407681 -50.664075)
			(xy 342.433174 -50.613713) (xy 342.466292 -50.568004) (xy 342.506206 -50.52809) (xy 342.551915 -50.494973)
			(xy 342.602277 -50.46948) (xy 342.656029 -50.45225) (xy 342.683846 -50.447448) (xy 342.700356 -50.444908)
			(xy 342.746076 -50.399188) (xy 342.746076 -50.178462) (xy 343.105486 -49.819052) (xy 343.105486 -49.290478)
			(xy 343.105044 -49.276486) (xy 343.097448 -49.249552) (xy 343.082832 -49.225688) (xy 343.062291 -49.206682)
			(xy 343.037366 -49.19396) (xy 343.009924 -49.188475) (xy 342.982023 -49.190638) (xy 342.955755 -49.200287)
			(xy 342.944196 -49.208182) (xy 342.921255 -49.224142) (xy 342.871446 -49.249478) (xy 342.818291 -49.266725)
			(xy 342.763095 -49.27546) (xy 342.735154 -49.276) (xy 342.707173 -49.275448) (xy 342.651902 -49.266687)
			(xy 342.598682 -49.249388) (xy 342.548823 -49.223977) (xy 342.503552 -49.19108) (xy 342.463985 -49.151507)
			(xy 342.431094 -49.106231) (xy 342.405691 -49.056368) (xy 342.388401 -49.003145) (xy 342.379648 -48.947873)
			(xy 342.379046 -48.919892) (xy 342.379509 -48.894052) (xy 342.386985 -48.842916) (xy 342.401781 -48.793399)
			(xy 342.423583 -48.746543) (xy 342.451934 -48.703334) (xy 342.468708 -48.683672) (xy 342.478486 -48.671796)
			(xy 342.491065 -48.643738) (xy 342.494736 -48.613209) (xy 342.489168 -48.582968) (xy 342.474864 -48.555749)
			(xy 342.46439 -48.54448) (xy 342.117172 -48.197262) (xy 341.771986 -48.197262) (xy 341.637366 -48.331882)
			(xy 341.637366 -49.313084) (xy 341.568532 -49.381918) (xy 341.120476 -49.381918) (xy 341.002366 -49.500028)
			(xy 341.002366 -50.356495) (xy 341.565728 -50.356495) (xy 341.565728 -50.303197) (xy 341.573671 -50.250493)
			(xy 341.589381 -50.199563) (xy 341.612507 -50.151542) (xy 341.642531 -50.107505) (xy 341.678783 -50.068434)
			(xy 341.720454 -50.035203) (xy 341.766612 -50.008554) (xy 341.816226 -49.989082) (xy 341.868188 -49.977222)
			(xy 341.921338 -49.973239) (xy 341.974488 -49.977222) (xy 342.02645 -49.989082) (xy 342.076064 -50.008554)
			(xy 342.122222 -50.035203) (xy 342.163893 -50.068434) (xy 342.200145 -50.107505) (xy 342.230169 -50.151542)
			(xy 342.253295 -50.199563) (xy 342.269005 -50.250493) (xy 342.276948 -50.303197) (xy 342.277446 -50.329846)
			(xy 342.276948 -50.356495) (xy 342.269005 -50.409199) (xy 342.253295 -50.460129) (xy 342.230169 -50.50815)
			(xy 342.200145 -50.552187) (xy 342.163893 -50.591258) (xy 342.122222 -50.624489) (xy 342.076064 -50.651138)
			(xy 342.02645 -50.67061) (xy 341.974488 -50.68247) (xy 341.921338 -50.686454) (xy 341.868188 -50.68247)
			(xy 341.816226 -50.67061) (xy 341.766612 -50.651138) (xy 341.720454 -50.624489) (xy 341.678783 -50.591258)
			(xy 341.642531 -50.552187) (xy 341.612507 -50.50815) (xy 341.589381 -50.460129) (xy 341.573671 -50.409199)
			(xy 341.565728 -50.356495) (xy 341.002366 -50.356495) (xy 341.002366 -50.724562) (xy 341.003636 -50.725832)
			(xy 341.003636 -50.92573) (xy 341.065612 -50.987706) (xy 341.703914 -50.987706) (xy 341.727436 -50.9703)
			(xy 341.77898 -50.942607) (xy 341.834359 -50.923716) (xy 341.892082 -50.914137) (xy 341.921338 -50.913538)
			(xy 341.947154 -50.914) (xy 341.998244 -50.921458) (xy 342.047723 -50.936214) (xy 342.094553 -50.957958)
			(xy 342.11641 -50.971704) (xy 342.150954 -50.99431)
		)
		(stroke
			(width 0)
			(type solid)
		)
		(fill yes)
		(layer "B.Cu")
		(net "GND")
	)
	(gr_poly
		(pts
			(xy 230.38054 -434.93182) (xy 230.41356 -434.8988) (xy 230.41356 -428.09668) (xy 230.41356 -423.3164)
			(xy 230.41356 -422.666668) (xy 230.41356 -422.598088) (xy 232.364788 -420.64686) (xy 232.551732 -420.459916)
			(xy 234.25531 -420.459916) (xy 234.442254 -420.64686) (xy 235.4072 -420.64686) (xy 247.2817 -420.64686)
			(xy 247.60682 -420.32174) (xy 247.60682 -416.94354) (xy 247.608852 -416.941508) (xy 247.608852 -415.923222)
			(xy 248.337832 -415.194496) (xy 253.125732 -415.194496) (xy 254.775462 -413.544512) (xy 265.612118 -413.544512)
			(xy 266.659868 -414.592262) (xy 266.659868 -414.980628) (xy 266.8397 -415.16046) (xy 266.891516 -415.16046)
			(xy 266.89177 -415.159952) (xy 279.961848 -415.159952) (xy 280.19756 -414.92424) (xy 280.19756 -408.29992)
			(xy 279.96896 -408.07132) (xy 239.56772 -408.07132) (xy 237.61446 -406.11806) (xy 235.38942 -406.11806)
			(xy 233.88066 -404.6093) (xy 233.88066 -401.251928) (xy 230.46182 -401.251928) (xy 230.46182 -404.604728)
			(xy 230.256588 -404.80996) (xy 230.256588 -407.522172) (xy 228.0666 -409.71216) (xy 225.575368 -409.71216)
			(xy 223.398588 -407.53538) (xy 223.398588 -404.79218) (xy 223.21774 -404.611332) (xy 223.21774 -401.160488)
			(xy 219.79636 -401.160488) (xy 219.79636 -404.622508) (xy 219.613988 -404.80488) (xy 219.613988 -407.3906)
			(xy 217.404188 -409.6004) (xy 214.66302 -409.6004) (xy 212.71992 -407.6573) (xy 212.71992 -404.79472)
			(xy 212.54212 -404.61692) (xy 212.54212 -401.262088) (xy 209.13598 -401.262088) (xy 209.13598 -404.584408)
			(xy 208.945988 -404.7744) (xy 208.945988 -407.435812) (xy 206.67726 -409.70454) (xy 204.028548 -409.70454)
			(xy 202.062588 -407.73858) (xy 202.062588 -404.779988) (xy 201.87666 -404.59406) (xy 201.87666 -401.124928)
			(xy 198.46798 -401.124928) (xy 198.46798 -404.61946) (xy 197.10146 -405.98598) (xy 190.73876 -405.98598)
			(xy 190.224664 -405.471884)
			(arc
				(start 190.216028 -405.46782)
				(mid 190.077739 -405.373084)
				(end 189.982856 -405.234902)
			)
			(xy 189.979046 -405.226266) (xy 189.362588 -404.609554) (xy 189.362588 -404.177754) (xy 189.337188 -404.152354)
			(xy 188.981588 -404.152354) (xy 188.61786 -403.788626) (xy 188.61786 -401.185888) (xy 185.802016 -401.185888)
			(xy 185.353452 -401.185888) (xy 185.196988 -401.342352) (xy 185.196988 -405.303228)
			(arc
				(start 185.196988 -406.398476)
				(mid 185.638949 -406.592405)
				(end 185.820558 -407.039572)
			)
			(arc
				(start 185.820558 -407.039572)
				(mid 185.742461 -407.34629)
				(end 185.527188 -407.578306)
			)
			(xy 185.527188 -408.419554) (xy 185.323988 -408.622754) (xy 185.323988 -413.045148) (xy 192.87617 -420.59733)
			(xy 197.53453 -420.59733) (xy 206.49184 -429.55464) (xy 206.49184 -435.39156) (xy 207.63484 -436.53456)
			(xy 228.7778 -436.53456)
		)
		(stroke
			(width 0)
			(type solid)
		)
		(fill yes)
		(layer "B.Cu")
		(net "P12V_PSU")
	)
	(gr_poly
		(pts
			(xy 336.964528 -70.796658) (xy 337.05292 -70.708266) (xy 337.263232 -70.200266) (xy 337.263232 -67.446144)
			(xy 337.238825 -67.434383) (xy 337.193581 -67.404585) (xy 337.153373 -67.368278) (xy 337.119127 -67.326299)
			(xy 337.091635 -67.279617) (xy 337.071531 -67.22931) (xy 337.059279 -67.176539) (xy 337.055161 -67.12252)
			(xy 337.059273 -67.068501) (xy 337.071519 -67.015728) (xy 337.091618 -66.965419) (xy 337.119104 -66.918734)
			(xy 337.153345 -66.876751) (xy 337.19355 -66.84044) (xy 337.23879 -66.810636) (xy 337.263232 -66.798952)
			(xy 337.263232 -66.59118) (xy 337.11515 -66.233802) (xy 337.109195 -66.220746) (xy 337.091258 -66.198362)
			(xy 337.067805 -66.181847) (xy 337.040685 -66.172504) (xy 337.012037 -66.171068) (xy 336.984119 -66.177654)
			(xy 336.971386 -66.184272) (xy 336.945446 -66.198462) (xy 336.890695 -66.220786) (xy 336.833526 -66.23588)
			(xy 336.77489 -66.243492) (xy 336.745326 -66.243962) (xy 336.715359 -66.243495) (xy 336.655937 -66.235675)
			(xy 336.598044 -66.220165) (xy 336.542671 -66.197232) (xy 336.490766 -66.167267) (xy 336.443215 -66.130783)
			(xy 336.400834 -66.088404) (xy 336.364348 -66.040856) (xy 336.33438 -65.988952) (xy 336.311443 -65.93358)
			(xy 336.29593 -65.875689) (xy 336.288107 -65.816267) (xy 336.288107 -65.756333) (xy 336.29593 -65.696911)
			(xy 336.311443 -65.63902) (xy 336.33438 -65.583648) (xy 336.364348 -65.531744) (xy 336.400834 -65.484196)
			(xy 336.443215 -65.441817) (xy 336.490766 -65.405333) (xy 336.542671 -65.375368) (xy 336.598044 -65.352435)
			(xy 336.655937 -65.336925) (xy 336.715359 -65.329105) (xy 336.745326 -65.328546) (xy 336.759779 -65.328636)
			(xy 336.788629 -65.330418) (xy 336.802984 -65.332102) (xy 336.806286 -65.33261) (xy 336.860388 -65.33261)
			(xy 336.860388 -65.23482) (xy 336.632296 -65.006728) (xy 334.303116 -65.006728) (xy 333.519022 -65.790822)
			(xy 334.92108 -65.790822) (xy 334.92108 -65.730886) (xy 334.928903 -65.671464) (xy 334.944416 -65.613571)
			(xy 334.967352 -65.558198) (xy 334.997319 -65.506292) (xy 335.033806 -65.458742) (xy 335.076186 -65.416362)
			(xy 335.123736 -65.379875) (xy 335.175642 -65.349908) (xy 335.231015 -65.326972) (xy 335.288908 -65.311459)
			(xy 335.34833 -65.303636) (xy 335.408266 -65.303636) (xy 335.467688 -65.311459) (xy 335.525581 -65.326972)
			(xy 335.580954 -65.349908) (xy 335.63286 -65.379875) (xy 335.68041 -65.416362) (xy 335.72279 -65.458742)
			(xy 335.759277 -65.506292) (xy 335.789244 -65.558198) (xy 335.81218 -65.613571) (xy 335.827693 -65.671464)
			(xy 335.835516 -65.730886) (xy 335.836006 -65.760854) (xy 335.835516 -65.790822) (xy 335.827693 -65.850244)
			(xy 335.81218 -65.908137) (xy 335.789244 -65.96351) (xy 335.759277 -66.015416) (xy 335.72279 -66.062966)
			(xy 335.68041 -66.105346) (xy 335.63286 -66.141833) (xy 335.580954 -66.1718) (xy 335.525581 -66.194736)
			(xy 335.467688 -66.210249) (xy 335.408266 -66.218072) (xy 335.34833 -66.218072) (xy 335.288908 -66.210249)
			(xy 335.231015 -66.194736) (xy 335.175642 -66.1718) (xy 335.123736 -66.141833) (xy 335.076186 -66.105346)
			(xy 335.033806 -66.062966) (xy 334.997319 -66.015416) (xy 334.967352 -65.96351) (xy 334.944416 -65.908137)
			(xy 334.928903 -65.850244) (xy 334.92108 -65.790822) (xy 333.519022 -65.790822) (xy 333.477108 -65.832736)
			(xy 333.477108 -70.794372) (xy 333.550514 -70.867778) (xy 336.792824 -70.867778)
		)
		(stroke
			(width 0)
			(type solid)
		)
		(fill yes)
		(layer "B.Cu")
		(net "GND")
	)
	(gr_poly
		(pts
			(xy 433.981098 -352.35896) (xy 433.981098 -345.53017) (xy 433.409852 -344.958924) (xy 428.289466 -344.958924)
			(xy 428.281084 -344.95867) (xy 426.699172 -344.95867) (xy 426.69079 -344.958924) (xy 422.091866 -344.958924)
			(xy 422.083484 -344.95867) (xy 420.501572 -344.95867) (xy 420.49319 -344.958924) (xy 415.896806 -344.958924)
			(xy 415.887916 -344.95867) (xy 414.315656 -344.95867) (xy 414.306766 -344.958924) (xy 412.383224 -344.958924)
			(xy 411.865064 -345.477084) (xy 411.865064 -346.798392) (xy 414.212532 -346.798392) (xy 414.212532 -345.223592)
			(xy 414.212919 -345.210224) (xy 414.219832 -345.184397) (xy 414.233185 -345.161235) (xy 414.252071 -345.142311)
			(xy 414.275206 -345.128911) (xy 414.301019 -345.121946) (xy 414.314386 -345.121484) (xy 415.889186 -345.121484)
			(xy 415.902567 -345.121858) (xy 415.928414 -345.128794) (xy 415.951578 -345.142194) (xy 415.970476 -345.161143)
			(xy 415.983813 -345.184344) (xy 415.990678 -345.21021) (xy 415.99104 -345.223592) (xy 415.99104 -346.798392)
			(xy 415.990816 -346.804742) (xy 420.40302 -346.804742) (xy 420.40302 -345.229942) (xy 420.403482 -345.216568)
			(xy 420.410405 -345.190731) (xy 420.42379 -345.167573) (xy 420.442721 -345.148677) (xy 420.465904 -345.135334)
			(xy 420.491753 -345.128458) (xy 420.505128 -345.128088) (xy 422.079928 -345.128088) (xy 422.093293 -345.128501)
			(xy 422.119114 -345.135415) (xy 422.142272 -345.148765) (xy 422.161195 -345.167645) (xy 422.174597 -345.190773)
			(xy 422.181568 -345.216578) (xy 422.182036 -345.229942) (xy 422.182036 -346.804742) (xy 426.60062 -346.804742)
			(xy 426.60062 -345.229942) (xy 426.601082 -345.216568) (xy 426.608005 -345.190731) (xy 426.62139 -345.167573)
			(xy 426.640321 -345.148677) (xy 426.663504 -345.135334) (xy 426.689353 -345.128458) (xy 426.702728 -345.128088)
			(xy 428.277528 -345.128088) (xy 428.290893 -345.128501) (xy 428.316714 -345.135415) (xy 428.339872 -345.148765)
			(xy 428.358795 -345.167645) (xy 428.372197 -345.190773) (xy 428.379168 -345.216578) (xy 428.379636 -345.229942)
			(xy 428.379636 -346.804742) (xy 428.379291 -346.818124) (xy 428.372344 -346.84397) (xy 428.358935 -346.867132)
			(xy 428.339982 -346.886027) (xy 428.316778 -346.899365) (xy 428.290911 -346.906232) (xy 428.277528 -346.906596)
			(xy 426.702728 -346.906596) (xy 426.689364 -346.90615) (xy 426.663543 -346.899248) (xy 426.640383 -346.885907)
			(xy 426.621458 -346.867032) (xy 426.608056 -346.843908) (xy 426.601086 -346.818105) (xy 426.60062 -346.804742)
			(xy 422.182036 -346.804742) (xy 422.181691 -346.818124) (xy 422.174744 -346.84397) (xy 422.161335 -346.867132)
			(xy 422.142382 -346.886027) (xy 422.119178 -346.899365) (xy 422.093311 -346.906232) (xy 422.079928 -346.906596)
			(xy 420.505128 -346.906596) (xy 420.491764 -346.90615) (xy 420.465943 -346.899248) (xy 420.442783 -346.885907)
			(xy 420.423858 -346.867032) (xy 420.410456 -346.843908) (xy 420.403486 -346.818105) (xy 420.40302 -346.804742)
			(xy 415.990816 -346.804742) (xy 415.990568 -346.811753) (xy 415.983665 -346.837569) (xy 415.970327 -346.860724)
			(xy 415.951458 -346.879647) (xy 415.928341 -346.893052) (xy 415.902546 -346.900029) (xy 415.889186 -346.9005)
			(xy 414.314386 -346.9005) (xy 414.301011 -346.900068) (xy 414.275175 -346.893132) (xy 414.252019 -346.879739)
			(xy 414.233125 -346.860804) (xy 414.219782 -346.837618) (xy 414.212903 -346.811768) (xy 414.212532 -346.798392)
			(xy 411.865064 -346.798392) (xy 411.865064 -352.73488) (xy 412.060644 -352.93046) (xy 433.409598 -352.93046)
		)
		(stroke
			(width 0)
			(type solid)
		)
		(fill yes)
		(layer "B.Cu")
		(net "PVCCFA_EHV_FIVRA_CPU0")
	)
	(gr_poly
		(pts
			(xy 187.0964 -361.36199) (xy 187.0964 -353.97059) (xy 186.897518 -353.771708) (xy 182.080662 -353.771708)
			(xy 182.043324 -353.809046) (xy 182.043324 -355.82098) (xy 183.002682 -356.780338) (xy 183.009524 -356.787738)
			(xy 183.017248 -356.806336) (xy 183.017668 -356.816406) (xy 183.017668 -358.959658) (xy 183.017234 -358.969723)
			(xy 183.009501 -358.988309) (xy 183.002682 -358.995726) (xy 182.35676 -359.641648) (xy 182.349362 -359.648494)
			(xy 182.330763 -359.656222) (xy 182.320692 -359.656634) (xy 180.505862 -359.656634) (xy 180.450388 -359.682714)
			(xy 180.336501 -359.728088) (xy 180.219758 -359.765509) (xy 180.100716 -359.7948) (xy 179.979939 -359.815822)
			(xy 179.858 -359.828476) (xy 179.73548 -359.8327) (xy 179.61296 -359.828476) (xy 179.491021 -359.815822)
			(xy 179.370244 -359.7948) (xy 179.251202 -359.765509) (xy 179.134459 -359.728088) (xy 179.020572 -359.682714)
			(xy 178.965098 -359.656634) (xy 177.087784 -359.656634) (xy 177.077717 -359.656206) (xy 177.059122 -359.64848)
			(xy 177.051716 -359.641648) (xy 176.283874 -358.873806) (xy 176.277018 -358.866412) (xy 176.26927 -358.847813)
			(xy 176.268888 -358.837738) (xy 176.268888 -355.756972) (xy 176.269316 -355.746904) (xy 176.277036 -355.728305)
			(xy 176.283874 -355.720904) (xy 176.65192 -355.352858) (xy 176.65192 -354.04171) (xy 176.381918 -353.771708)
			(xy 172.527722 -353.771708) (xy 172.31614 -353.98329) (xy 172.31614 -356.02799) (xy 173.181264 -356.893114)
			(xy 173.188112 -356.900512) (xy 173.195847 -356.91911) (xy 173.19625 -356.929182) (xy 173.19625 -359.10774)
			(xy 175.016414 -360.927904) (xy 175.023269 -360.935299) (xy 175.031016 -360.953898) (xy 175.0314 -360.963972)
			(xy 175.0314 -363.155414) (xy 181.645048 -363.155414) (xy 181.645048 -363.070718) (xy 181.653099 -362.986404)
			(xy 181.669128 -362.903238) (xy 181.692989 -362.821971) (xy 181.724468 -362.743341) (xy 181.763279 -362.66806)
			(xy 181.809069 -362.596808) (xy 181.861425 -362.530232) (xy 181.919873 -362.468934) (xy 181.983883 -362.413469)
			(xy 182.052875 -362.36434) (xy 182.126225 -362.321991) (xy 182.203268 -362.286807) (xy 182.283307 -362.259105)
			(xy 182.365616 -362.239137) (xy 182.449451 -362.227084) (xy 182.534052 -362.223054) (xy 182.618653 -362.227084)
			(xy 182.702488 -362.239137) (xy 182.784797 -362.259105) (xy 182.864836 -362.286807) (xy 182.941879 -362.321991)
			(xy 183.015229 -362.36434) (xy 183.084221 -362.413469) (xy 183.148231 -362.468934) (xy 183.206679 -362.530232)
			(xy 183.259035 -362.596808) (xy 183.304825 -362.66806) (xy 183.343636 -362.743341) (xy 183.375115 -362.821971)
			(xy 183.398976 -362.903238) (xy 183.415005 -362.986404) (xy 183.423056 -363.070718) (xy 183.42356 -363.113066)
			(xy 183.423056 -363.155414) (xy 183.415005 -363.239728) (xy 183.398976 -363.322894) (xy 183.375115 -363.404161)
			(xy 183.343636 -363.482791) (xy 183.304825 -363.558072) (xy 183.259035 -363.629324) (xy 183.206679 -363.6959)
			(xy 183.148231 -363.757198) (xy 183.084221 -363.812663) (xy 183.015229 -363.861792) (xy 182.941879 -363.904141)
			(xy 182.864836 -363.939325) (xy 182.784797 -363.967027) (xy 182.702488 -363.986995) (xy 182.618653 -363.999048)
			(xy 182.534052 -364.003079) (xy 182.449451 -363.999048) (xy 182.365616 -363.986995) (xy 182.283307 -363.967027)
			(xy 182.203268 -363.939325) (xy 182.126225 -363.904141) (xy 182.052875 -363.861792) (xy 181.983883 -363.812663)
			(xy 181.919873 -363.757198) (xy 181.861425 -363.6959) (xy 181.809069 -363.629324) (xy 181.763279 -363.558072)
			(xy 181.724468 -363.482791) (xy 181.692989 -363.404161) (xy 181.669128 -363.322894) (xy 181.653099 -363.239728)
			(xy 181.645048 -363.155414) (xy 175.0314 -363.155414) (xy 175.0314 -364.510828) (xy 175.0949 -364.574328)
			(xy 183.882538 -364.574328)
		)
		(stroke
			(width 0)
			(type solid)
		)
		(fill yes)
		(layer "B.Cu")
		(net "SW_P12V_PVCCFA_EHV_FIVRA_CPU1_R")
	)
	(gr_poly
		(pts
			(arc
				(start 179.47894 -26.005028)
				(mid 179.503239 -25.882957)
				(end 179.572412 -25.779476)
			)
			(xy 179.87264 -25.478994) (xy 179.87264 -25.14092)
			(arc
				(start 179.634388 -24.902414)
				(mid 179.565188 -24.798944)
				(end 179.540916 -24.676862)
			)
			(arc
				(start 179.540916 -22.191726)
				(mid 179.487008 -22.102015)
				(end 179.38242 -22.107398)
			)
			(arc
				(start 179.38242 -22.107398)
				(mid 179.280623 -22.156)
				(end 179.16906 -22.172676)
			)
			(arc
				(start 179.16906 -22.172676)
				(mid 178.96791 -22.115339)
				(end 178.827176 -21.960586)
			)
			(arc
				(start 178.827176 -21.960586)
				(mid 178.772958 -21.910837)
				(end 178.699414 -21.910802)
			)
			(arc
				(start 178.699414 -21.910802)
				(mid 178.63189 -21.929955)
				(end 178.562 -21.936456)
			)
			(arc
				(start 178.562 -21.936456)
				(mid 178.309777 -21.841185)
				(end 178.18354 -21.602954)
			)
			(arc
				(start 178.18354 -21.602954)
				(mid 178.171483 -21.574768)
				(end 178.162204 -21.54555)
			)
			(arc
				(start 178.162204 -21.54555)
				(mid 178.119437 -21.486488)
				(end 178.048158 -21.471382)
			)
			(arc
				(start 178.048158 -21.471382)
				(mid 178.018281 -21.474975)
				(end 177.988214 -21.476208)
			)
			(arc
				(start 177.988214 -21.476208)
				(mid 177.606706 -21.0947)
				(end 177.988214 -20.713192)
			)
			(arc
				(start 177.988214 -20.713192)
				(mid 178.012646 -20.713943)
				(end 178.036982 -20.71624)
			)
			(arc
				(start 178.036982 -20.71624)
				(mid 178.116994 -20.691818)
				(end 178.151536 -20.615656)
			)
			(arc
				(start 178.151536 -20.141438)
				(mid 178.175835 -20.019367)
				(end 178.245008 -19.915886)
			)
			(xy 178.311556 -19.849084) (xy 178.311556 -19.785584) (xy 178.3715 -19.785584) (xy 178.3715 -19.442176)
			(arc
				(start 178.03495 -19.442176)
				(mid 177.944493 -19.429083)
				(end 177.861468 -19.390868)
			)
			(arc
				(start 177.861468 -19.390868)
				(mid 177.722177 -19.336797)
				(end 177.614326 -19.233388)
			)
			(xy 176.52238 -19.233388) (xy 175.7807 -19.975068) (xy 175.7807 -27.752548) (xy 176.0601 -28.031948)
			(xy 179.47894 -28.031948)
		)
		(stroke
			(width 0)
			(type solid)
		)
		(fill yes)
		(layer "B.Cu")
		(net "P12V_SCM_R")
	)
	(gr_poly
		(pts
			(arc
				(start 233.775504 -128.216152)
				(mid 233.859754 -128.18408)
				(end 233.94924 -128.173226)
			)
			(arc
				(start 233.94924 -128.173226)
				(mid 234.038714 -128.184128)
				(end 234.122976 -128.216152)
			)
			(xy 234.133898 -128.221994)
			(arc
				(start 234.45216 -128.221994)
				(mid 234.640882 -128.17067)
				(end 234.829604 -128.221994)
			)
			(arc
				(start 235.174028 -128.221994)
				(mid 235.365798 -128.168901)
				(end 235.557568 -128.221994)
			)
			(xy 235.852716 -128.221994)
			(arc
				(start 235.863638 -128.216152)
				(mid 235.947888 -128.18408)
				(end 236.037374 -128.173226)
			)
			(arc
				(start 236.037374 -128.173226)
				(mid 236.126848 -128.184128)
				(end 236.21111 -128.216152)
			)
			(xy 236.222032 -128.221994) (xy 236.269276 -128.221994) (xy 236.447076 -128.044194)
			(arc
				(start 236.447076 -128.02743)
				(mid 236.379856 -127.900339)
				(end 236.356652 -127.758444)
			)
			(arc
				(start 236.356652 -127.758444)
				(mid 236.379814 -127.616535)
				(end 236.447076 -127.489458)
			)
			(xy 236.447076 -126.986538)
			(arc
				(start 236.442758 -126.976632)
				(mid 236.418855 -126.902869)
				(end 236.410754 -126.825756)
			)
			(arc
				(start 236.410754 -126.825756)
				(mid 236.418873 -126.748647)
				(end 236.442758 -126.67488)
			)
			(xy 236.447076 -126.664974) (xy 236.447076 -125.608334) (xy 236.200188 -125.361446)
			(arc
				(start 236.17555 -125.36424)
				(mid 236.15387 -125.366145)
				(end 236.132116 -125.36678)
			)
			(arc
				(start 236.132116 -125.36678)
				(mid 236.038843 -125.354909)
				(end 235.951522 -125.320044)
			)
			(xy 235.940092 -125.313694) (xy 235.88472 -125.313694) (xy 235.709206 -125.489208) (xy 235.193586 -125.489208)
			(xy 235.028232 -125.323854)
			(arc
				(start 234.996736 -125.336808)
				(mid 234.926888 -125.358036)
				(end 234.854242 -125.365256)
			)
			(arc
				(start 234.854242 -125.365256)
				(mid 234.756185 -125.352122)
				(end 234.665012 -125.313694)
			)
			(xy 234.166664 -125.313694)
			(arc
				(start 234.155742 -125.319536)
				(mid 234.071492 -125.351608)
				(end 233.982006 -125.362462)
			)
			(arc
				(start 233.982006 -125.362462)
				(mid 233.892532 -125.35156)
				(end 233.80827 -125.319536)
			)
			(xy 233.797348 -125.313694) (xy 233.7054 -125.313694) (xy 233.554016 -125.465078) (xy 233.554016 -125.687328)
			(arc
				(start 233.555286 -125.692916)
				(mid 233.56443 -125.774958)
				(end 233.555286 -125.857)
			)
			(xy 233.554016 -125.862588) (xy 233.554016 -126.233174)
			(arc
				(start 233.55935 -126.243842)
				(mid 233.598458 -126.409958)
				(end 233.55935 -126.576074)
			)
			(xy 233.554016 -126.586742) (xy 233.554016 -127.020574)
			(arc
				(start 233.55935 -127.031242)
				(mid 233.598458 -127.197358)
				(end 233.55935 -127.363474)
			)
			(xy 233.554016 -127.374142) (xy 233.554016 -127.714248)
			(arc
				(start 233.55681 -127.722376)
				(mid 233.572555 -127.783208)
				(end 233.577892 -127.84582)
			)
			(arc
				(start 233.577892 -127.84582)
				(mid 233.572593 -127.908439)
				(end 233.55681 -127.969264)
			)
			(xy 233.554016 -127.977392) (xy 233.554016 -128.072134) (xy 233.703876 -128.221994) (xy 233.764582 -128.221994)
		)
		(stroke
			(width 0)
			(type solid)
		)
		(fill yes)
		(layer "B.Cu")
		(net "GND")
	)
	(gr_poly
		(pts
			(xy 407.65349 -166.251382) (xy 407.77033 -166.134542) (xy 407.777175 -166.127144) (xy 407.784899 -166.108545)
			(xy 407.785316 -166.098474) (xy 407.785316 -158.134304) (xy 407.7843 -158.112714) (xy 407.77033 -158.098744)
			(xy 407.63952 -157.967934) (xy 407.624534 -157.952948) (xy 401.447508 -157.952948) (xy 401.447508 -159.349948)
			(xy 401.447065 -159.363329) (xy 401.440129 -159.389177) (xy 401.42674 -159.41235) (xy 401.407812 -159.431269)
			(xy 401.384632 -159.444647) (xy 401.358781 -159.451572) (xy 401.3454 -159.452056) (xy 399.7706 -159.452056)
			(xy 399.757212 -159.45162) (xy 399.731349 -159.444692) (xy 399.708159 -159.431308) (xy 399.689221 -159.412379)
			(xy 399.675827 -159.389196) (xy 399.668887 -159.363335) (xy 399.668492 -159.349948) (xy 399.668492 -157.952948)
			(xy 398.408652 -157.952948) (xy 398.393666 -157.967934) (xy 397.562578 -158.799022) (xy 397.547592 -158.814008)
			(xy 397.547592 -162.785552) (xy 399.642589 -162.785552) (xy 399.646611 -162.699832) (xy 399.658642 -162.614864)
			(xy 399.678578 -162.531397) (xy 399.706241 -162.450163) (xy 399.74139 -162.371877) (xy 399.783716 -162.297226)
			(xy 399.832845 -162.226867) (xy 399.888348 -162.161417) (xy 399.949735 -162.101453) (xy 400.016468 -162.0475)
			(xy 400.08796 -162.000033) (xy 400.163582 -161.959469) (xy 400.242671 -161.926165) (xy 400.324531 -161.900413)
			(xy 400.408442 -161.88244) (xy 400.493668 -161.872404) (xy 400.57946 -161.870392) (xy 400.665062 -161.876423)
			(xy 400.749724 -161.890443) (xy 400.832701 -161.912329) (xy 400.913264 -161.94189) (xy 400.990704 -161.978864)
			(xy 401.064343 -162.022928) (xy 401.133531 -162.073694) (xy 401.197662 -162.130715) (xy 401.256171 -162.193491)
			(xy 401.308544 -162.261471) (xy 401.354322 -162.334056) (xy 401.393102 -162.410608) (xy 401.424543 -162.490456)
			(xy 401.448369 -162.572897) (xy 401.46437 -162.657207) (xy 401.472405 -162.742645) (xy 401.472908 -162.785552)
			(xy 401.472405 -162.828459) (xy 401.46437 -162.913897) (xy 401.448369 -162.998207) (xy 401.424543 -163.080648)
			(xy 401.393102 -163.160496) (xy 401.354322 -163.237048) (xy 401.308544 -163.309633) (xy 401.256171 -163.377613)
			(xy 401.197662 -163.440389) (xy 401.133531 -163.49741) (xy 401.064343 -163.548176) (xy 400.990704 -163.59224)
			(xy 400.913264 -163.629214) (xy 400.832701 -163.658775) (xy 400.749724 -163.680661) (xy 400.665062 -163.694681)
			(xy 400.57946 -163.700712) (xy 400.493668 -163.6987) (xy 400.408442 -163.688664) (xy 400.324531 -163.670691)
			(xy 400.242671 -163.644939) (xy 400.163582 -163.611635) (xy 400.08796 -163.571071) (xy 400.016468 -163.523604)
			(xy 399.949735 -163.469651) (xy 399.888348 -163.409687) (xy 399.832845 -163.344237) (xy 399.783716 -163.273878)
			(xy 399.74139 -163.199227) (xy 399.706241 -163.120941) (xy 399.678578 -163.039707) (xy 399.658642 -162.95624)
			(xy 399.646611 -162.871272) (xy 399.642589 -162.785552) (xy 397.547592 -162.785552) (xy 397.547592 -165.572948)
			(xy 399.668492 -165.572948) (xy 399.668492 -163.998148) (xy 399.668931 -163.98476) (xy 399.675852 -163.958893)
			(xy 399.689232 -163.9357) (xy 399.708162 -163.916762) (xy 399.731349 -163.90337) (xy 399.757212 -163.896438)
			(xy 399.7706 -163.89604) (xy 401.3454 -163.89604) (xy 401.358794 -163.89639) (xy 401.38467 -163.903326)
			(xy 401.407868 -163.916724) (xy 401.426806 -163.935671) (xy 401.440193 -163.958875) (xy 401.447116 -163.984753)
			(xy 401.447508 -163.998148) (xy 401.447508 -165.572948) (xy 401.447113 -165.586335) (xy 401.440173 -165.612196)
			(xy 401.426779 -165.635379) (xy 401.407841 -165.654308) (xy 401.384651 -165.667692) (xy 401.358788 -165.67462)
			(xy 401.3454 -165.675056) (xy 399.7706 -165.675056) (xy 399.757219 -165.674572) (xy 399.731368 -165.667647)
			(xy 399.708188 -165.654269) (xy 399.68926 -165.63535) (xy 399.675871 -165.612177) (xy 399.668935 -165.586329)
			(xy 399.668492 -165.572948) (xy 397.547592 -165.572948) (xy 397.547592 -166.044626) (xy 397.562578 -166.059612)
			(xy 397.769334 -166.266368) (xy 407.638504 -166.266368)
		)
		(stroke
			(width 0)
			(type solid)
		)
		(fill yes)
		(layer "B.Cu")
		(net "PVCCD_HV_CPU0")
	)
	(gr_poly
		(pts
			(xy 58.896758 -344.043762) (xy 58.896758 -336.70367) (xy 58.881772 -336.688684) (xy 58.566304 -336.373216)
			(xy 58.551318 -336.35823) (xy 53.142896 -336.35823) (xy 53.136292 -336.360008) (xy 53.096873 -336.370349)
			(xy 53.016665 -336.384811) (xy 52.935488 -336.392072) (xy 52.894738 -336.39252) (xy 52.853988 -336.392059)
			(xy 52.772814 -336.384787) (xy 52.692607 -336.370332) (xy 52.653184 -336.360008) (xy 52.64658 -336.35823)
			(xy 46.945296 -336.35823) (xy 46.938692 -336.360008) (xy 46.899273 -336.370349) (xy 46.819065 -336.384811)
			(xy 46.737888 -336.392072) (xy 46.697138 -336.39252) (xy 46.656388 -336.392059) (xy 46.575214 -336.384787)
			(xy 46.495007 -336.370332) (xy 46.455584 -336.360008) (xy 46.44898 -336.35823) (xy 40.730932 -336.35823)
			(xy 40.724582 -336.359754) (xy 40.688831 -336.368154) (xy 40.616328 -336.379894) (xy 40.543119 -336.38579)
			(xy 40.506396 -336.38617) (xy 40.469672 -336.385807) (xy 40.396461 -336.379917) (xy 40.323959 -336.368169)
			(xy 40.28821 -336.359754) (xy 40.28186 -336.35823) (xy 36.734496 -336.35823) (xy 35.764978 -337.327748)
			(xy 35.764978 -338.258658) (xy 39.616888 -338.258658) (xy 39.616888 -336.683858) (xy 39.617209 -336.670474)
			(xy 39.624158 -336.644625) (xy 39.637571 -336.62146) (xy 39.656529 -336.602564) (xy 39.679739 -336.589228)
			(xy 39.705611 -336.582365) (xy 39.718996 -336.582004) (xy 41.293796 -336.582004) (xy 41.307161 -336.582429)
			(xy 41.332983 -336.589337) (xy 41.356143 -336.602683) (xy 41.375067 -336.621561) (xy 41.388469 -336.644689)
			(xy 41.395438 -336.670494) (xy 41.395904 -336.683858) (xy 41.395904 -338.258658) (xy 41.395721 -338.265008)
			(xy 45.807884 -338.265008) (xy 45.807884 -336.690208) (xy 45.808333 -336.676845) (xy 45.815237 -336.651026)
			(xy 45.828579 -336.627868) (xy 45.847453 -336.608944) (xy 45.870575 -336.595541) (xy 45.896376 -336.588568)
			(xy 45.909738 -336.5881) (xy 47.484538 -336.5881) (xy 47.497914 -336.588511) (xy 47.52375 -336.595452)
			(xy 47.546906 -336.60885) (xy 47.5658 -336.62779) (xy 47.579142 -336.650978) (xy 47.586021 -336.676831)
			(xy 47.586392 -336.690208) (xy 47.586392 -338.265008) (xy 52.005484 -338.265008) (xy 52.005484 -336.690208)
			(xy 52.005933 -336.676845) (xy 52.012837 -336.651026) (xy 52.026179 -336.627868) (xy 52.045053 -336.608944)
			(xy 52.068175 -336.595541) (xy 52.093976 -336.588568) (xy 52.107338 -336.5881) (xy 53.682138 -336.5881)
			(xy 53.695514 -336.588511) (xy 53.72135 -336.595452) (xy 53.744506 -336.60885) (xy 53.7634 -336.62779)
			(xy 53.776742 -336.650978) (xy 53.783621 -336.676831) (xy 53.783992 -336.690208) (xy 53.783992 -338.265008)
			(xy 53.783581 -338.278374) (xy 53.776671 -338.304197) (xy 53.763322 -338.327357) (xy 53.744441 -338.346281)
			(xy 53.72131 -338.359682) (xy 53.695503 -338.366651) (xy 53.682138 -338.367116) (xy 52.107338 -338.367116)
			(xy 52.093958 -338.366721) (xy 52.068112 -338.359791) (xy 52.044948 -338.346395) (xy 52.02605 -338.32745)
			(xy 52.012711 -338.304252) (xy 52.005846 -338.278389) (xy 52.005484 -338.265008) (xy 47.586392 -338.265008)
			(xy 47.585981 -338.278374) (xy 47.579071 -338.304197) (xy 47.565722 -338.327357) (xy 47.546841 -338.346281)
			(xy 47.52371 -338.359682) (xy 47.497903 -338.366651) (xy 47.484538 -338.367116) (xy 45.909738 -338.367116)
			(xy 45.896358 -338.366721) (xy 45.870512 -338.359791) (xy 45.847348 -338.346395) (xy 45.82845 -338.32745)
			(xy 45.815111 -338.304252) (xy 45.808246 -338.278389) (xy 45.807884 -338.265008) (xy 41.395721 -338.265008)
			(xy 41.395518 -338.272039) (xy 41.388587 -338.297886) (xy 41.37519 -338.321052) (xy 41.356243 -338.339951)
			(xy 41.333043 -338.353288) (xy 41.307178 -338.360152) (xy 41.293796 -338.360512) (xy 39.718996 -338.360512)
			(xy 39.705632 -338.360078) (xy 39.679812 -338.35317) (xy 39.656654 -338.339825) (xy 39.63773 -338.320949)
			(xy 39.624328 -338.297824) (xy 39.617356 -338.272021) (xy 39.616888 -338.258658) (xy 35.764978 -338.258658)
			(xy 35.764978 -344.108278) (xy 36.26358 -344.60688) (xy 58.33364 -344.60688)
		)
		(stroke
			(width 0)
			(type solid)
		)
		(fill yes)
		(layer "B.Cu")
		(net "PVCCFA_EHV_FIVRA_CPU1")
	)
	(gr_poly
		(pts
			(arc
				(start 110.987078 -418.69233)
				(mid 111.062238 -418.668233)
				(end 111.140748 -418.660072)
			)
			(arc
				(start 111.140748 -418.660072)
				(mid 111.219268 -418.668186)
				(end 111.294418 -418.69233)
			)
			(xy 111.30407 -418.696648) (xy 112.23625 -418.696648)
			(arc
				(start 112.245902 -418.69233)
				(mid 112.321062 -418.668233)
				(end 112.399572 -418.660072)
			)
			(arc
				(start 112.399572 -418.660072)
				(mid 112.478092 -418.668186)
				(end 112.553242 -418.69233)
			)
			(xy 112.562894 -418.696648) (xy 112.93348 -418.696648) (xy 113.178844 -418.451284)
			(arc
				(start 113.180114 -418.432234)
				(mid 113.300249 -418.179127)
				(end 113.56086 -418.07638)
			)
			(arc
				(start 113.56086 -418.07638)
				(mid 113.623556 -418.081567)
				(end 113.684558 -418.096954)
			)
			(xy 113.692686 -418.099748) (xy 114.11712 -418.099748)
			(arc
				(start 114.12728 -418.095176)
				(mid 114.28476 -418.061133)
				(end 114.44224 -418.095176)
			)
			(xy 114.4524 -418.099748) (xy 114.64798 -418.099748)
			(arc
				(start 114.802158 -417.94557)
				(mid 114.826349 -417.840276)
				(end 114.74196 -417.772596)
			)
			(arc
				(start 114.74196 -417.772596)
				(mid 114.500578 -417.647608)
				(end 114.403632 -417.393628)
			)
			(arc
				(start 114.403632 -417.393628)
				(mid 114.515373 -417.123861)
				(end 114.78514 -417.01212)
			)
			(arc
				(start 114.78514 -417.01212)
				(mid 115.039178 -417.109)
				(end 115.164108 -417.350448)
			)
			(arc
				(start 115.164108 -417.350448)
				(mid 115.231702 -417.435081)
				(end 115.337082 -417.410646)
			)
			(xy 116.32438 -416.423348)
			(arc
				(start 116.32438 -415.53765)
				(mid 116.176289 -415.373032)
				(end 116.122704 -415.158174)
			)
			(arc
				(start 116.122704 -415.158174)
				(mid 116.170606 -414.954322)
				(end 116.304314 -414.793176)
			)
			(xy 116.32438 -414.777936) (xy 116.32438 -414.713928) (xy 116.12372 -414.513268)
			(arc
				(start 116.12372 -414.224724)
				(mid 116.055646 -414.0073)
				(end 116.12372 -413.789876)
			)
			(arc
				(start 116.12372 -412.9659)
				(mid 116.055646 -412.748476)
				(end 116.12372 -412.531052)
			)
			(xy 116.12372 -411.973268) (xy 115.93576 -411.785308) (xy 114.48288 -411.785308) (xy 114.28984 -411.978348)
			(xy 114.28984 -414.157668) (xy 114.1349 -414.312608) (xy 114.1349 -415.735008) (xy 113.54562 -416.324288)
			(xy 113.54562 -417.225988) (xy 113.22304 -417.548568) (xy 112.70234 -417.548568) (xy 112.3061 -417.944808)
			(xy 108.86186 -417.944808) (xy 108.72724 -418.079428) (xy 108.72724 -418.620448) (xy 108.80344 -418.696648)
			(xy 110.977426 -418.696648)
		)
		(stroke
			(width 0)
			(type solid)
		)
		(fill yes)
		(layer "B.Cu")
		(net "P3V3_9ZXL045_VDDR")
	)
	(gr_poly
		(pts
			(xy 327.72477 -66.3575) (xy 327.892156 -66.3575) (xy 333.196946 -61.05271) (xy 335.959196 -61.05271)
			(xy 336.121502 -60.890404) (xy 336.121502 -60.11164) (xy 336.664808 -59.568334) (xy 336.664808 -58.8518)
			(xy 336.583274 -58.770266) (xy 329.001374 -58.770266) (xy 328.67854 -59.0931) (xy 328.67854 -59.237118)
			(xy 328.678021 -59.266189) (xy 328.668965 -59.323621) (xy 328.651032 -59.378928) (xy 328.624664 -59.430747)
			(xy 328.59051 -59.4778) (xy 328.570336 -59.498738) (xy 328.185526 -59.883548) (xy 329.943714 -59.883548)
			(xy 329.944212 -59.856899) (xy 329.952155 -59.804195) (xy 329.967865 -59.753265) (xy 329.990991 -59.705244)
			(xy 330.021015 -59.661207) (xy 330.057267 -59.622136) (xy 330.098938 -59.588905) (xy 330.145096 -59.562256)
			(xy 330.19471 -59.542784) (xy 330.246672 -59.530924) (xy 330.299822 -59.526941) (xy 330.352972 -59.530924)
			(xy 330.404934 -59.542784) (xy 330.454548 -59.562256) (xy 330.500706 -59.588905) (xy 330.542377 -59.622136)
			(xy 330.578629 -59.661207) (xy 330.608653 -59.705244) (xy 330.631779 -59.753265) (xy 330.647489 -59.804195)
			(xy 330.655432 -59.856899) (xy 330.65593 -59.883548) (xy 330.655362 -59.912474) (xy 330.64603 -59.969567)
			(xy 330.627603 -60.024404) (xy 330.600563 -60.075547) (xy 330.58354 -60.09894) (xy 330.575351 -60.110416)
			(xy 330.565113 -60.136675) (xy 330.56244 -60.164732) (xy 330.567535 -60.192452) (xy 330.580011 -60.217725)
			(xy 330.589128 -60.22848) (xy 330.606423 -60.248226) (xy 330.635583 -60.291874) (xy 330.658012 -60.339333)
			(xy 330.673223 -60.389572) (xy 330.680886 -60.441502) (xy 330.68133 -60.467748) (xy 330.680832 -60.494397)
			(xy 330.672889 -60.547101) (xy 330.657179 -60.598031) (xy 330.634053 -60.646052) (xy 330.604029 -60.690089)
			(xy 330.567777 -60.72916) (xy 330.526106 -60.762391) (xy 330.479948 -60.78904) (xy 330.430334 -60.808512)
			(xy 330.378372 -60.820372) (xy 330.325222 -60.824356) (xy 330.272072 -60.820372) (xy 330.22011 -60.808512)
			(xy 330.170496 -60.78904) (xy 330.124338 -60.762391) (xy 330.082667 -60.72916) (xy 330.046415 -60.690089)
			(xy 330.016391 -60.646052) (xy 329.993265 -60.598031) (xy 329.977555 -60.547101) (xy 329.969612 -60.494397)
			(xy 329.969114 -60.467748) (xy 329.969671 -60.438822) (xy 329.979005 -60.381728) (xy 329.997435 -60.32689)
			(xy 330.024479 -60.275748) (xy 330.041504 -60.252356) (xy 330.049703 -60.240886) (xy 330.059947 -60.214625)
			(xy 330.062621 -60.186565) (xy 330.057522 -60.158842) (xy 330.045038 -60.133569) (xy 330.035916 -60.122816)
			(xy 330.018626 -60.103065) (xy 329.989464 -60.05942) (xy 329.967033 -60.011962) (xy 329.951821 -59.961723)
			(xy 329.944158 -59.909794) (xy 329.943714 -59.883548) (xy 328.185526 -59.883548) (xy 328.153014 -59.91606)
			(xy 328.153014 -60.522866) (xy 328.153523 -60.537298) (xy 328.161604 -60.56501) (xy 328.177103 -60.589361)
			(xy 328.198787 -60.608414) (xy 328.224929 -60.620652) (xy 328.25345 -60.625101) (xy 328.267822 -60.623704)
			(xy 328.2828 -60.621813) (xy 328.312924 -60.619779) (xy 328.32802 -60.61964) (xy 328.357984 -60.620131)
			(xy 328.417398 -60.627956) (xy 328.475283 -60.643468) (xy 328.530648 -60.666403) (xy 328.582545 -60.696368)
			(xy 328.630088 -60.732851) (xy 328.672462 -60.775227) (xy 328.708943 -60.822771) (xy 328.738906 -60.87467)
			(xy 328.761838 -60.930036) (xy 328.777348 -60.987922) (xy 328.78517 -61.047336) (xy 328.78517 -61.107264)
			(xy 328.777348 -61.166678) (xy 328.761838 -61.224564) (xy 328.738906 -61.27993) (xy 328.708943 -61.331829)
			(xy 328.672462 -61.379373) (xy 328.630088 -61.421749) (xy 328.582545 -61.458232) (xy 328.530648 -61.488197)
			(xy 328.475283 -61.511132) (xy 328.417398 -61.526644) (xy 328.357984 -61.534469) (xy 328.32802 -61.535056)
			(xy 328.312924 -61.534906) (xy 328.282801 -61.53287) (xy 328.267822 -61.530992) (xy 328.253442 -61.529612)
			(xy 328.224906 -61.534019) (xy 328.198745 -61.546239) (xy 328.177052 -61.565295) (xy 328.161562 -61.589663)
			(xy 328.153513 -61.617392) (xy 328.153014 -61.63183) (xy 328.153014 -62.695328) (xy 328.156824 -62.704726)
			(xy 328.167984 -62.732715) (xy 328.183692 -62.790889) (xy 328.191631 -62.85062) (xy 328.19213 -62.880748)
			(xy 328.191634 -62.910876) (xy 328.183695 -62.970608) (xy 328.167988 -63.028782) (xy 328.156824 -63.05677)
			(xy 328.153014 -63.066168) (xy 328.153014 -63.130176) (xy 326.768968 -64.514222) (xy 326.768968 -64.522604)
			(xy 326.189594 -65.101978) (xy 326.189594 -65.532254) (xy 326.297544 -65.640204) (xy 326.297544 -66.64325)
			(xy 326.380602 -66.726054) (xy 327.356216 -66.726054)
		)
		(stroke
			(width 0)
			(type solid)
		)
		(fill yes)
		(layer "B.Cu")
		(net "GND")
	)
	(gr_poly
		(pts
			(xy 121.18213 -259.85724) (xy 121.18213 -249.764042)
			(arc
				(start 121.17832 -249.754644)
				(mid 121.151895 -249.620024)
				(end 121.17832 -249.485404)
			)
			(xy 121.18213 -249.476006) (xy 121.18213 -248.234454) (xy 121.085356 -248.13768) (xy 120.848628 -248.13768)
			(xy 120.589294 -248.397014) (xy 118.842028 -248.397014) (xy 118.834154 -248.397268) (xy 115.540536 -248.397268)
			(xy 115.540536 -248.39676) (xy 115.26647 -248.39676) (xy 115.167664 -248.49582) (xy 115.167664 -249.43816)
			(xy 115.198144 -249.468894) (xy 115.198144 -249.469148) (xy 115.62461 -249.89536) (xy 117.21211 -249.89536)
			(xy 117.301772 -249.985022) (xy 117.302026 -249.985276) (xy 117.306344 -249.98934) (xy 117.317012 -250.000262)
			(arc
				(start 117.327426 -250.004072)
				(mid 117.49465 -250.134737)
				(end 117.557804 -250.33732)
			)
			(arc
				(start 117.557804 -250.33732)
				(mid 117.555819 -250.374612)
				(end 117.54993 -250.411488)
			)
			(xy 117.544342 -250.438666) (xy 117.633496 -250.52782) (xy 118.57482 -250.52782) (xy 118.634256 -250.468384)
			(xy 118.634256 -250.374658) (xy 118.63451 -250.366784) (xy 118.63451 -250.24842) (xy 118.7196 -250.16333)
			(xy 118.719854 -250.163076) (xy 118.723918 -250.158758) (xy 118.873016 -250.009914) (xy 118.876572 -250.006358)
			(xy 118.876826 -250.006104) (xy 118.96217 -249.92076) (xy 120.421146 -249.92076) (xy 120.51538 -250.014994)
			(xy 120.518428 -250.018042) (xy 120.714516 -250.213876) (xy 120.720358 -250.219718) (xy 120.720612 -250.220226)
			(xy 120.804178 -250.303538) (xy 120.804178 -250.421902) (xy 120.804432 -250.429776) (xy 120.804432 -251.703332)
			(xy 120.804178 -251.71146) (xy 120.804178 -251.862082) (xy 120.657874 -252.008386) (xy 120.507252 -252.008386)
			(xy 120.499124 -252.00864) (xy 115.629944 -252.00864) (xy 115.624864 -252.00356) (xy 115.31727 -252.00356)
			(xy 115.231164 -252.089412) (xy 115.231164 -252.089666) (xy 115.221004 -252.10008) (xy 115.221004 -253.05258)
			(xy 115.37823 -253.21006) (xy 115.74907 -253.5809) (xy 117.21465 -253.5809) (xy 117.301772 -253.668022)
			(xy 117.302026 -253.668276) (xy 117.306344 -253.67234) (xy 117.317012 -253.683262)
			(arc
				(start 117.327426 -253.687072)
				(mid 117.49465 -253.817737)
				(end 117.557804 -254.02032)
			)
			(arc
				(start 117.557804 -254.02032)
				(mid 117.555778 -254.058511)
				(end 117.549676 -254.096266)
			)
			(xy 117.543834 -254.123444) (xy 117.650514 -254.230124) (xy 118.528592 -254.230124) (xy 118.580916 -254.177292)
			(xy 118.581424 -254.177292) (xy 118.662704 -254.096012) (xy 118.707916 -254.0508) (xy 118.707916 -253.920752)
			(xy 118.70817 -253.912624) (xy 118.70817 -253.79426) (xy 118.79326 -253.70917) (xy 118.793514 -253.708916)
			(xy 118.797578 -253.704598) (xy 118.827296 -253.675134) (xy 118.830852 -253.671578) (xy 118.831106 -253.671324)
			(xy 118.91645 -253.58598) (xy 120.524778 -253.58598) (xy 120.781572 -253.842774) (xy 120.781572 -255.528572)
			(xy 120.62206 -255.688084) (xy 115.531392 -255.688084) (xy 115.446048 -255.60274) (xy 115.445794 -255.602486)
			(xy 115.442238 -255.59893) (xy 115.421156 -255.577848) (xy 115.304062 -255.577848) (xy 115.292632 -255.589532)
			(xy 115.261644 -255.620012) (xy 115.261644 -255.620266) (xy 115.205764 -255.6764) (xy 115.205764 -256.42824)
			(xy 115.261644 -256.484374) (xy 115.261644 -256.484628) (xy 115.71605 -256.93878) (xy 115.71605 -257.256026)
			(xy 115.77447 -257.314192) (xy 117.120416 -257.314192) (xy 117.12829 -257.314446) (xy 117.246654 -257.314446)
			(xy 117.278912 -257.346704)
			(arc
				(start 117.28958 -257.350514)
				(mid 117.460272 -257.4808)
				(end 117.525038 -257.68554)
			)
			(arc
				(start 117.525038 -257.68554)
				(mid 117.51418 -257.773061)
				(end 117.482112 -257.855212)
			)
			(xy 117.476016 -257.866642) (xy 117.476016 -257.966464) (xy 117.475762 -257.966464) (xy 117.475762 -258.003548)
			(xy 117.342158 -258.137152) (xy 115.376198 -258.137152) (xy 115.21694 -258.29641) (xy 115.21694 -259.76199)
			(xy 115.293902 -259.838952) (xy 115.43538 -259.838952) (xy 115.696238 -259.578094) (xy 120.496584 -259.578094)
			(xy 120.83923 -259.92074) (xy 121.11863 -259.92074)
		)
		(stroke
			(width 0)
			(type solid)
		)
		(fill yes)
		(layer "B.Cu")
		(net "GND")
	)
	(gr_poly
		(pts
			(xy 461.7466 -50.053748) (xy 461.7466 -47.716948) (xy 461.2894 -47.259748) (xy 443.267338 -47.259748)
			(xy 442.054742 -48.472344) (xy 445.193418 -48.472344) (xy 445.197489 -48.416722) (xy 445.209615 -48.362285)
			(xy 445.229538 -48.310194) (xy 445.256834 -48.261559) (xy 445.29092 -48.217416) (xy 445.331069 -48.178707)
			(xy 445.376427 -48.146256) (xy 445.426027 -48.120755) (xy 445.478811 -48.102748) (xy 445.533654 -48.092618)
			(xy 445.589388 -48.090581) (xy 445.644825 -48.096681) (xy 445.698782 -48.110787) (xy 445.750111 -48.132599)
			(xy 445.797717 -48.161653) (xy 445.840585 -48.197328) (xy 445.877802 -48.238865) (xy 445.908575 -48.285378)
			(xy 445.932247 -48.335875) (xy 445.948315 -48.389282) (xy 445.956435 -48.444458) (xy 445.956944 -48.472344)
			(xy 445.956435 -48.50023) (xy 445.948315 -48.555406) (xy 445.932247 -48.608813) (xy 445.908575 -48.65931)
			(xy 445.877802 -48.705823) (xy 445.840585 -48.74736) (xy 445.797717 -48.783035) (xy 445.750111 -48.812089)
			(xy 445.698782 -48.833901) (xy 445.644825 -48.848007) (xy 445.589388 -48.854107) (xy 445.533654 -48.85207)
			(xy 445.478811 -48.84194) (xy 445.426027 -48.823933) (xy 445.376427 -48.798432) (xy 445.331069 -48.765981)
			(xy 445.29092 -48.727272) (xy 445.256834 -48.683129) (xy 445.229538 -48.634494) (xy 445.209615 -48.582403)
			(xy 445.197489 -48.527966) (xy 445.193418 -48.472344) (xy 442.054742 -48.472344) (xy 441.05068 -49.476406)
			(xy 448.662047 -49.476406) (xy 448.666083 -49.392959) (xy 448.678155 -49.310291) (xy 448.698148 -49.229174)
			(xy 448.725877 -49.150365) (xy 448.761083 -49.0746) (xy 448.803437 -49.002587) (xy 448.852543 -48.934998)
			(xy 448.907944 -48.872464) (xy 448.969121 -48.815569) (xy 449.035504 -48.764843) (xy 449.106472 -48.720762)
			(xy 449.181364 -48.683736) (xy 449.25948 -48.65411) (xy 449.34009 -48.632162) (xy 449.422442 -48.618097)
			(xy 449.505768 -48.612045) (xy 449.589288 -48.614064) (xy 449.672224 -48.624134) (xy 449.7538 -48.642162)
			(xy 449.833256 -48.667979) (xy 449.909849 -48.701344) (xy 449.982865 -48.741945) (xy 450.051621 -48.789404)
			(xy 450.115475 -48.843277) (xy 450.173832 -48.903062) (xy 450.226147 -48.968199) (xy 450.27193 -49.038082)
			(xy 450.310755 -49.112057) (xy 450.34226 -49.189434) (xy 450.366149 -49.269491) (xy 450.3822 -49.351479)
			(xy 450.390263 -49.434634) (xy 450.390768 -49.476406) (xy 456.170287 -49.476406) (xy 456.174323 -49.392959)
			(xy 456.186395 -49.310291) (xy 456.206388 -49.229174) (xy 456.234117 -49.150365) (xy 456.269323 -49.0746)
			(xy 456.311677 -49.002587) (xy 456.360783 -48.934998) (xy 456.416184 -48.872464) (xy 456.477361 -48.815569)
			(xy 456.543744 -48.764843) (xy 456.614712 -48.720762) (xy 456.689604 -48.683736) (xy 456.76772 -48.65411)
			(xy 456.84833 -48.632162) (xy 456.930682 -48.618097) (xy 457.014008 -48.612045) (xy 457.097528 -48.614064)
			(xy 457.180464 -48.624134) (xy 457.26204 -48.642162) (xy 457.341496 -48.667979) (xy 457.418089 -48.701344)
			(xy 457.491105 -48.741945) (xy 457.559861 -48.789404) (xy 457.623715 -48.843277) (xy 457.682072 -48.903062)
			(xy 457.734387 -48.968199) (xy 457.78017 -49.038082) (xy 457.818995 -49.112057) (xy 457.8505 -49.189434)
			(xy 457.874389 -49.269491) (xy 457.89044 -49.351479) (xy 457.898503 -49.434634) (xy 457.899008 -49.476406)
			(xy 457.898503 -49.518178) (xy 457.89044 -49.601333) (xy 457.874389 -49.683321) (xy 457.8505 -49.763378)
			(xy 457.818995 -49.840755) (xy 457.78017 -49.91473) (xy 457.734387 -49.984613) (xy 457.682072 -50.04975)
			(xy 457.623715 -50.109535) (xy 457.559861 -50.163408) (xy 457.491105 -50.210867) (xy 457.418089 -50.251468)
			(xy 457.341496 -50.284833) (xy 457.26204 -50.31065) (xy 457.180464 -50.328678) (xy 457.097528 -50.338748)
			(xy 457.014008 -50.340767) (xy 456.930682 -50.334715) (xy 456.84833 -50.32065) (xy 456.76772 -50.298702)
			(xy 456.689604 -50.269076) (xy 456.614712 -50.23205) (xy 456.543744 -50.187969) (xy 456.477361 -50.137243)
			(xy 456.416184 -50.080348) (xy 456.360783 -50.017814) (xy 456.311677 -49.950225) (xy 456.269323 -49.878212)
			(xy 456.234117 -49.802447) (xy 456.206388 -49.723638) (xy 456.186395 -49.642521) (xy 456.174323 -49.559853)
			(xy 456.170287 -49.476406) (xy 450.390768 -49.476406) (xy 450.390263 -49.518178) (xy 450.3822 -49.601333)
			(xy 450.366149 -49.683321) (xy 450.34226 -49.763378) (xy 450.310755 -49.840755) (xy 450.27193 -49.91473)
			(xy 450.226147 -49.984613) (xy 450.173832 -50.04975) (xy 450.115475 -50.109535) (xy 450.051621 -50.163408)
			(xy 449.982865 -50.210867) (xy 449.909849 -50.251468) (xy 449.833256 -50.284833) (xy 449.7538 -50.31065)
			(xy 449.672224 -50.328678) (xy 449.589288 -50.338748) (xy 449.505768 -50.340767) (xy 449.422442 -50.334715)
			(xy 449.34009 -50.32065) (xy 449.25948 -50.298702) (xy 449.181364 -50.269076) (xy 449.106472 -50.23205)
			(xy 449.035504 -50.187969) (xy 448.969121 -50.137243) (xy 448.907944 -50.080348) (xy 448.852543 -50.017814)
			(xy 448.803437 -49.950225) (xy 448.761083 -49.878212) (xy 448.725877 -49.802447) (xy 448.698148 -49.723638)
			(xy 448.678155 -49.642521) (xy 448.666083 -49.559853) (xy 448.662047 -49.476406) (xy 441.05068 -49.476406)
			(xy 440.8678 -49.659286) (xy 440.8678 -50.307748) (xy 441.1726 -50.612548) (xy 461.1878 -50.612548)
		)
		(stroke
			(width 0)
			(type solid)
		)
		(fill yes)
		(layer "B.Cu")
		(net "GND")
	)
	(gr_poly
		(pts
			(xy 238.712502 -49.377346) (xy 238.726038 -49.376921) (xy 238.752157 -49.3698) (xy 238.775484 -49.356061)
			(xy 238.794376 -49.33667) (xy 238.807503 -49.312993) (xy 238.81394 -49.286697) (xy 238.813234 -49.259633)
			(xy 238.809784 -49.246536) (xy 238.802187 -49.219678) (xy 238.79403 -49.164462) (xy 238.793528 -49.136554)
			(xy 238.794017 -49.109306) (xy 238.801779 -49.055365) (xy 238.817139 -49.003078) (xy 238.839783 -48.953509)
			(xy 238.869251 -48.907667) (xy 238.904943 -48.866485) (xy 238.946133 -48.830802) (xy 238.991981 -48.801344)
			(xy 239.041555 -48.77871) (xy 239.093845 -48.763362) (xy 239.147788 -48.755612) (xy 239.175036 -48.755046)
			(xy 239.203902 -48.755579) (xy 239.260974 -48.764285) (xy 239.316082 -48.781491) (xy 239.367968 -48.806804)
			(xy 239.415447 -48.839648) (xy 239.457435 -48.879271) (xy 239.492972 -48.92477) (xy 239.521247 -48.975103)
			(xy 239.531906 -49.001934) (xy 239.537334 -49.01501) (xy 239.554202 -49.037734) (xy 239.576653 -49.054966)
			(xy 239.602966 -49.065385) (xy 239.631127 -49.068194) (xy 239.658979 -49.063178) (xy 239.67186 -49.057306)
			(xy 239.698091 -49.045058) (xy 239.753332 -49.027751) (xy 239.810556 -49.018997) (xy 239.8395 -49.018444)
			(xy 239.868478 -49.018982) (xy 239.925767 -49.027742) (xy 239.981074 -49.045061) (xy 240.033127 -49.070541)
			(xy 240.080732 -49.103596) (xy 240.122793 -49.143467) (xy 240.140998 -49.166018) (xy 240.150188 -49.177074)
			(xy 240.173425 -49.193982) (xy 240.200457 -49.203734) (xy 240.229136 -49.205557) (xy 240.257185 -49.199305)
			(xy 240.282376 -49.185476) (xy 240.29289 -49.17567) (xy 241.48542 -47.98314) (xy 241.48542 -46.57852)
			(xy 241.36604 -46.45914) (xy 239.380268 -46.45914) (xy 239.365882 -46.459682) (xy 239.338274 -46.467795)
			(xy 239.314023 -46.483283) (xy 239.295051 -46.504919) (xy 239.282863 -46.530985) (xy 239.278426 -46.559417)
			(xy 239.282092 -46.587957) (xy 239.287304 -46.60138) (xy 239.29936 -46.630344) (xy 239.31633 -46.690742)
			(xy 239.324899 -46.752891) (xy 239.325404 -46.78426) (xy 239.324937 -46.814231) (xy 239.317118 -46.87366)
			(xy 239.301608 -46.931559) (xy 239.278673 -46.986939) (xy 239.248706 -47.038852) (xy 239.212218 -47.086408)
			(xy 239.169835 -47.128794) (xy 239.122282 -47.165286) (xy 239.070372 -47.195258) (xy 239.014994 -47.218197)
			(xy 238.957095 -47.233711) (xy 238.897667 -47.241535) (xy 238.867696 -47.241968) (xy 238.838715 -47.241528)
			(xy 238.781214 -47.234223) (xy 238.725096 -47.219718) (xy 238.671258 -47.198244) (xy 238.620561 -47.170147)
			(xy 238.573817 -47.135874) (xy 238.531773 -47.095975) (xy 238.495102 -47.051087) (xy 238.464392 -47.001929)
			(xy 238.451898 -46.975776) (xy 238.44538 -46.962833) (xy 238.426366 -46.940982) (xy 238.401977 -46.925356)
			(xy 238.374179 -46.917215) (xy 238.345213 -46.917215) (xy 238.317415 -46.925356) (xy 238.293026 -46.940982)
			(xy 238.274012 -46.962833) (xy 238.267494 -46.975776) (xy 238.254953 -47.001904) (xy 238.224234 -47.05105)
			(xy 238.187561 -47.09593) (xy 238.145521 -47.135825) (xy 238.098785 -47.170099) (xy 238.048099 -47.198205)
			(xy 237.994272 -47.219693) (xy 237.938165 -47.234221) (xy 237.880674 -47.241555) (xy 237.851696 -47.241968)
			(xy 237.822286 -47.241508) (xy 237.763951 -47.233962) (xy 237.707063 -47.219007) (xy 237.652558 -47.19689)
			(xy 237.601335 -47.167975) (xy 237.554237 -47.132739) (xy 237.512039 -47.091761) (xy 237.475436 -47.045716)
			(xy 237.445031 -46.995363) (xy 237.421325 -46.941531) (xy 237.404708 -46.885106) (xy 237.399576 -46.856142)
			(xy 237.396947 -46.842413) (xy 237.385235 -46.817042) (xy 237.367081 -46.795798) (xy 237.343845 -46.780275)
			(xy 237.317271 -46.771635) (xy 237.289349 -46.770526) (xy 237.262173 -46.777033) (xy 237.23778 -46.790666)
			(xy 237.227618 -46.800262) (xy 236.86008 -47.1678) (xy 236.86008 -47.878746) (xy 236.80928 -47.929546)
			(xy 236.80928 -47.998376) (xy 238.406922 -47.998376) (xy 238.406922 -47.93844) (xy 238.414745 -47.879018)
			(xy 238.430258 -47.821125) (xy 238.453194 -47.765752) (xy 238.483161 -47.713846) (xy 238.519648 -47.666296)
			(xy 238.562028 -47.623916) (xy 238.609578 -47.587429) (xy 238.661484 -47.557462) (xy 238.716857 -47.534526)
			(xy 238.77475 -47.519013) (xy 238.834172 -47.51119) (xy 238.894108 -47.51119) (xy 238.95353 -47.519013)
			(xy 239.011423 -47.534526) (xy 239.066796 -47.557462) (xy 239.118702 -47.587429) (xy 239.166252 -47.623916)
			(xy 239.208632 -47.666296) (xy 239.245119 -47.713846) (xy 239.275086 -47.765752) (xy 239.298022 -47.821125)
			(xy 239.313535 -47.879018) (xy 239.321358 -47.93844) (xy 239.321848 -47.968408) (xy 239.321358 -47.998376)
			(xy 239.313535 -48.057798) (xy 239.298022 -48.115691) (xy 239.275086 -48.171064) (xy 239.245119 -48.22297)
			(xy 239.208632 -48.27052) (xy 239.166252 -48.3129) (xy 239.118702 -48.349387) (xy 239.066796 -48.379354)
			(xy 239.011423 -48.40229) (xy 238.95353 -48.417803) (xy 238.894108 -48.425626) (xy 238.834172 -48.425626)
			(xy 238.77475 -48.417803) (xy 238.716857 -48.40229) (xy 238.661484 -48.379354) (xy 238.609578 -48.349387)
			(xy 238.562028 -48.3129) (xy 238.519648 -48.27052) (xy 238.483161 -48.22297) (xy 238.453194 -48.171064)
			(xy 238.430258 -48.115691) (xy 238.414745 -48.057798) (xy 238.406922 -47.998376) (xy 236.80928 -47.998376)
			(xy 236.80928 -49.301146) (xy 236.88548 -49.377346)
		)
		(stroke
			(width 0)
			(type solid)
		)
		(fill yes)
		(layer "B.Cu")
		(net "P3V3_E1S_0")
	)
	(gr_poly
		(pts
			(xy 369.121944 -259.856986) (xy 369.121944 -249.76328) (xy 369.118134 -249.754136) (xy 369.109853 -249.732759)
			(xy 369.098215 -249.688415) (xy 369.092347 -249.642947) (xy 369.091972 -249.620024) (xy 369.09231 -249.597099)
			(xy 369.098173 -249.551627) (xy 369.109842 -249.507288) (xy 369.118134 -249.485912) (xy 369.121944 -249.476768)
			(xy 369.121944 -248.2342) (xy 369.02517 -248.137426) (xy 368.788442 -248.137426) (xy 368.529108 -248.39676)
			(xy 366.900206 -248.39676) (xy 366.892586 -248.40438) (xy 363.198156 -248.40438) (xy 363.138212 -248.464578)
			(xy 363.138212 -249.46864) (xy 363.564424 -249.895106) (xy 365.151924 -249.895106) (xy 365.156496 -249.899424)
			(xy 365.18596 -249.899424) (xy 365.30915 -250.022868) (xy 365.315246 -250.02617) (xy 365.338582 -250.03978)
			(xy 365.381221 -250.072948) (xy 365.41836 -250.112177) (xy 365.449147 -250.156566) (xy 365.472875 -250.205096)
			(xy 365.488999 -250.256654) (xy 365.49715 -250.310056) (xy 365.497618 -250.337066) (xy 365.49737 -250.355751)
			(xy 365.493429 -250.392914) (xy 365.489744 -250.411234) (xy 365.484156 -250.438412) (xy 365.544862 -250.499372)
			(xy 366.499394 -250.499372) (xy 366.564164 -250.434348) (xy 366.564164 -250.175268) (xy 366.820196 -249.919236)
			(xy 368.378994 -249.919236) (xy 368.807492 -250.347988) (xy 368.807492 -251.798582) (xy 368.550698 -252.055376)
			(xy 363.20476 -252.055376) (xy 363.171232 -252.089158) (xy 363.171232 -252.974856) (xy 363.776768 -253.580646)
			(xy 365.154464 -253.580646) (xy 365.156496 -253.582424) (xy 365.21136 -253.582424) (xy 365.447072 -253.818136)
			(xy 365.447072 -253.836424) (xy 365.453168 -253.847854) (xy 365.467134 -253.874388) (xy 365.486949 -253.930978)
			(xy 365.497001 -253.990087) (xy 365.497618 -254.020066) (xy 365.497379 -254.039203) (xy 365.493308 -254.077259)
			(xy 365.48949 -254.096012) (xy 365.483648 -254.12319) (xy 365.537496 -254.177292) (xy 366.521492 -254.177292)
			(xy 366.602772 -254.096012) (xy 366.602772 -253.829058) (xy 366.847374 -253.584456) (xy 368.461036 -253.584456)
			(xy 368.462306 -253.585726) (xy 368.464592 -253.585726) (xy 368.721386 -253.84252) (xy 368.721386 -253.84506)
			(xy 368.768884 -253.892558) (xy 368.768884 -255.510284) (xy 368.56289 -255.716024) (xy 363.460284 -255.716024)
			(xy 363.333284 -255.589024) (xy 363.232192 -255.589024) (xy 363.201712 -255.619758) (xy 363.201712 -256.48412)
			(xy 363.655864 -256.938526) (xy 363.655864 -257.255772) (xy 363.661452 -257.26136) (xy 365.270034 -257.26136)
			(xy 365.455708 -257.447288) (xy 365.455708 -257.60553) (xy 365.456978 -257.61061) (xy 365.460672 -257.629057)
			(xy 365.46462 -257.666474) (xy 365.464852 -257.685286) (xy 365.464728 -257.6954) (xy 366.682514 -257.6954)
			(xy 366.686497 -257.642249) (xy 366.698359 -257.590286) (xy 366.717833 -257.540672) (xy 366.744484 -257.494514)
			(xy 366.777718 -257.452845) (xy 366.816792 -257.416594) (xy 366.860832 -257.386573) (xy 366.908856 -257.363451)
			(xy 366.959789 -257.347746) (xy 367.012494 -257.339808) (xy 367.039144 -257.339338) (xy 367.063777 -257.339774)
			(xy 367.112574 -257.346559) (xy 367.159969 -257.360007) (xy 367.205057 -257.37986) (xy 367.246978 -257.405741)
			(xy 367.26622 -257.421126) (xy 367.277435 -257.429752) (xy 367.303357 -257.441062) (xy 367.331388 -257.44482)
			(xy 367.359374 -257.440739) (xy 367.385163 -257.429131) (xy 367.396268 -257.420364) (xy 367.415614 -257.404636)
			(xy 367.457866 -257.378168) (xy 367.503401 -257.357861) (xy 367.551325 -257.344113) (xy 367.600701 -257.337195)
			(xy 367.62563 -257.336798) (xy 367.652278 -257.337286) (xy 367.704979 -257.345233) (xy 367.755907 -257.360946)
			(xy 367.803924 -257.384074) (xy 367.847958 -257.414099) (xy 367.887026 -257.450352) (xy 367.920254 -257.492022)
			(xy 367.946901 -257.538179) (xy 367.966372 -257.587792) (xy 367.978231 -257.639752) (xy 367.982214 -257.6929)
			(xy 367.978231 -257.746048) (xy 367.966372 -257.798008) (xy 367.946901 -257.847621) (xy 367.920254 -257.893778)
			(xy 367.887026 -257.935448) (xy 367.847958 -257.971701) (xy 367.803924 -258.001726) (xy 367.755907 -258.024854)
			(xy 367.704979 -258.040567) (xy 367.652278 -258.048514) (xy 367.62563 -258.049014) (xy 367.600997 -258.048581)
			(xy 367.552201 -258.041794) (xy 367.504806 -258.028345) (xy 367.459717 -258.008491) (xy 367.417796 -257.982611)
			(xy 367.398554 -257.967226) (xy 367.387355 -257.958579) (xy 367.361426 -257.947278) (xy 367.333392 -257.943526)
			(xy 367.305404 -257.947612) (xy 367.279612 -257.959221) (xy 367.268506 -257.967988) (xy 367.249175 -257.983735)
			(xy 367.206919 -258.010199) (xy 367.16138 -258.030502) (xy 367.113452 -258.044245) (xy 367.064074 -258.051159)
			(xy 367.039144 -258.051554) (xy 367.012494 -258.050992) (xy 366.959789 -258.043054) (xy 366.908856 -258.027349)
			(xy 366.860832 -258.004227) (xy 366.816792 -257.974206) (xy 366.777718 -257.937955) (xy 366.744484 -257.896286)
			(xy 366.717833 -257.850128) (xy 366.698359 -257.800514) (xy 366.686497 -257.748551) (xy 366.682514 -257.6954)
			(xy 365.464728 -257.6954) (xy 365.464622 -257.704098) (xy 365.460678 -257.741516) (xy 365.456978 -257.759962)
			(xy 365.455708 -257.765042) (xy 365.455708 -257.926078) (xy 365.415576 -257.96621) (xy 365.415576 -258.003294)
			(xy 365.281972 -258.136898) (xy 363.317536 -258.136898) (xy 363.156754 -258.29768) (xy 363.156754 -259.761736)
			(xy 363.233716 -259.838698) (xy 363.375194 -259.838698) (xy 363.636052 -259.57784) (xy 368.436398 -259.57784)
			(xy 368.779044 -259.920486) (xy 369.058444 -259.920486)
		)
		(stroke
			(width 0)
			(type solid)
		)
		(fill yes)
		(layer "B.Cu")
		(net "GND")
	)
	(gr_poly
		(pts
			(xy 182.937658 -404.508462) (xy 182.937658 -404.415244) (xy 182.937404 -404.41499) (xy 182.937404 -402.920454)
			(xy 182.937658 -402.920454) (xy 182.937658 -402.873972) (xy 183.172608 -402.639022) (xy 183.21909 -402.639022)
			(xy 183.21909 -402.638768) (xy 184.556908 -402.638768) (xy 184.785508 -402.410422) (xy 184.785508 -401.051522)
			(xy 184.671208 -400.937222) (xy 181.554628 -400.937222) (xy 181.540318 -400.937716) (xy 181.512825 -400.945672)
			(xy 181.488616 -400.960939) (xy 181.46959 -400.98232) (xy 181.457238 -401.008139) (xy 181.45253 -401.03637)
			(xy 181.455835 -401.064799) (xy 181.460902 -401.078192) (xy 181.472182 -401.103569) (xy 181.488114 -401.15677)
			(xy 181.496181 -401.211715) (xy 181.496716 -401.239482) (xy 181.496254 -401.266736) (xy 181.488499 -401.320689)
			(xy 181.473145 -401.37299) (xy 181.450503 -401.422573) (xy 181.421036 -401.468429) (xy 181.385342 -401.509624)
			(xy 181.344149 -401.54532) (xy 181.298295 -401.574791) (xy 181.248714 -401.597436) (xy 181.196415 -401.612794)
			(xy 181.142462 -401.620552) (xy 181.115208 -401.62099) (xy 181.090265 -401.620561) (xy 181.040809 -401.614021)
			(xy 180.992624 -401.601104) (xy 180.946528 -401.582028) (xy 180.924708 -401.569936) (xy 179.974494 -401.569936)
			(xy 179.464208 -402.080222) (xy 179.464208 -402.49729) (xy 181.63743 -402.49729) (xy 181.641501 -402.441668)
			(xy 181.653627 -402.387231) (xy 181.67355 -402.33514) (xy 181.700846 -402.286505) (xy 181.734932 -402.242362)
			(xy 181.775081 -402.203653) (xy 181.820439 -402.171202) (xy 181.870039 -402.145701) (xy 181.922823 -402.127694)
			(xy 181.977666 -402.117564) (xy 182.0334 -402.115527) (xy 182.088837 -402.121627) (xy 182.142794 -402.135733)
			(xy 182.194123 -402.157545) (xy 182.241729 -402.186599) (xy 182.284597 -402.222274) (xy 182.321814 -402.263811)
			(xy 182.352587 -402.310324) (xy 182.376259 -402.360821) (xy 182.392327 -402.414228) (xy 182.400447 -402.469404)
			(xy 182.400956 -402.49729) (xy 182.400447 -402.525176) (xy 182.392327 -402.580352) (xy 182.376259 -402.633759)
			(xy 182.352587 -402.684256) (xy 182.321814 -402.730769) (xy 182.284597 -402.772306) (xy 182.241729 -402.807981)
			(xy 182.194123 -402.837035) (xy 182.142794 -402.858847) (xy 182.088837 -402.872953) (xy 182.0334 -402.879053)
			(xy 181.977666 -402.877016) (xy 181.922823 -402.866886) (xy 181.870039 -402.848879) (xy 181.820439 -402.823378)
			(xy 181.775081 -402.790927) (xy 181.734932 -402.752218) (xy 181.700846 -402.708075) (xy 181.67355 -402.65944)
			(xy 181.653627 -402.607349) (xy 181.641501 -402.552912) (xy 181.63743 -402.49729) (xy 179.464208 -402.49729)
			(xy 179.464208 -402.954236) (xy 179.615084 -402.954236) (xy 179.615084 -402.894292) (xy 179.882546 -402.894292)
			(xy 179.90325 -402.894759) (xy 179.943965 -402.902299) (xy 179.982629 -402.91712) (xy 180.017953 -402.938726)
			(xy 180.033676 -402.952204) (xy 180.874162 -402.952204) (xy 180.899243 -402.952685) (xy 180.948783 -402.960569)
			(xy 180.996476 -402.976116) (xy 181.041145 -402.998943) (xy 181.081686 -403.028486) (xy 181.099714 -403.04593)
			(xy 181.52999 -403.475952) (xy 181.543706 -403.479508) (xy 181.570964 -403.486717) (xy 181.623147 -403.508069)
			(xy 181.671614 -403.536875) (xy 181.71531 -403.572506) (xy 181.753281 -403.614185) (xy 181.784697 -403.661003)
			(xy 181.808874 -403.711938) (xy 181.825284 -403.765879) (xy 181.833569 -403.821649) (xy 181.834028 -403.84984)
			(xy 181.83354 -403.87709) (xy 181.825778 -403.931034) (xy 181.81042 -403.983325) (xy 181.787777 -404.032899)
			(xy 181.75831 -404.078746) (xy 181.722619 -404.119933) (xy 181.68143 -404.155622) (xy 181.635581 -404.185087)
			(xy 181.586007 -404.207727) (xy 181.533715 -404.223083) (xy 181.47977 -404.230841) (xy 181.45252 -404.231348)
			(xy 181.425115 -404.230875) (xy 181.37087 -404.223029) (xy 181.318307 -404.207495) (xy 181.268511 -404.184595)
			(xy 181.222507 -404.1548) (xy 181.201568 -404.137114) (xy 181.190719 -404.128243) (xy 181.165396 -404.116264)
			(xy 181.137771 -404.111617) (xy 181.109922 -404.11465) (xy 181.083945 -404.125136) (xy 181.061794 -404.142286)
			(xy 181.045137 -404.164809) (xy 181.03977 -404.177754) (xy 181.029075 -404.204558) (xy 181.000779 -404.254852)
			(xy 180.96523 -404.300311) (xy 180.92324 -404.339897) (xy 180.875767 -404.372707) (xy 180.823894 -404.397993)
			(xy 180.768804 -404.415178) (xy 180.711754 -404.42387) (xy 180.6829 -404.424388) (xy 180.655648 -404.423925)
			(xy 180.601698 -404.416168) (xy 180.549401 -404.400811) (xy 180.499822 -404.378169) (xy 180.453971 -404.3487)
			(xy 180.41278 -404.313006) (xy 180.377088 -404.271813) (xy 180.347622 -404.22596) (xy 180.324982 -404.17638)
			(xy 180.309628 -404.124083) (xy 180.301874 -404.070132) (xy 180.301392 -404.04288) (xy 180.301823 -404.017049)
			(xy 180.308801 -403.965859) (xy 180.322627 -403.916081) (xy 180.343048 -403.868625) (xy 180.369689 -403.82436)
			(xy 180.402062 -403.784099) (xy 180.420518 -403.76602) (xy 180.431132 -403.755187) (xy 180.446037 -403.728795)
			(xy 180.452544 -403.699191) (xy 180.45008 -403.66898) (xy 180.438862 -403.640822) (xy 180.419876 -403.617194)
			(xy 180.394794 -403.600175) (xy 180.365823 -403.591263) (xy 180.350668 -403.59076) (xy 180.033676 -403.59076)
			(xy 180.017969 -403.604262) (xy 179.982647 -403.625886) (xy 179.943978 -403.640713) (xy 179.903254 -403.648248)
			(xy 179.882546 -403.648672) (xy 179.615084 -403.648672) (xy 179.615084 -403.588728) (xy 179.46116 -403.588728)
			(xy 179.46116 -404.51024) (xy 179.6288 -404.67788) (xy 182.76824 -404.67788)
		)
		(stroke
			(width 0)
			(type solid)
		)
		(fill yes)
		(layer "B.Cu")
		(net "HSC_VDD_R")
	)
	(gr_poly
		(pts
			(xy 198.43496 -113.538762) (xy 198.434485 -113.5241) (xy 198.426171 -113.495981) (xy 198.41021 -113.471384)
			(xy 198.387918 -113.452334) (xy 198.361132 -113.440404) (xy 198.332061 -113.436575) (xy 198.3031 -113.441165)
			(xy 198.289672 -113.447068) (xy 198.263848 -113.458844) (xy 198.209585 -113.475481) (xy 198.153458 -113.483899)
			(xy 198.12508 -113.484406) (xy 198.09783 -113.483919) (xy 198.043885 -113.47616) (xy 197.991592 -113.460803)
			(xy 197.942018 -113.438161) (xy 197.89617 -113.408694) (xy 197.854983 -113.373003) (xy 197.819294 -113.331814)
			(xy 197.789829 -113.285964) (xy 197.76719 -113.236389) (xy 197.751836 -113.184096) (xy 197.74408 -113.13015)
			(xy 197.74408 -113.07565) (xy 197.751836 -113.021704) (xy 197.76719 -112.969411) (xy 197.789829 -112.919836)
			(xy 197.819294 -112.873986) (xy 197.854983 -112.832797) (xy 197.89617 -112.797106) (xy 197.942018 -112.767639)
			(xy 197.991592 -112.744997) (xy 198.043885 -112.72964) (xy 198.09783 -112.721881) (xy 198.12508 -112.72139)
			(xy 198.153458 -112.72191) (xy 198.209586 -112.730317) (xy 198.26385 -112.746949) (xy 198.289672 -112.758728)
			(xy 198.303113 -112.7646) (xy 198.332072 -112.769183) (xy 198.361141 -112.765354) (xy 198.387926 -112.75343)
			(xy 198.410222 -112.73439) (xy 198.426195 -112.709804) (xy 198.43453 -112.681694) (xy 198.43496 -112.667034)
			(xy 198.43496 -112.560862) (xy 198.434485 -112.5462) (xy 198.426171 -112.518081) (xy 198.41021 -112.493484)
			(xy 198.387918 -112.474434) (xy 198.361132 -112.462504) (xy 198.332061 -112.458675) (xy 198.3031 -112.463265)
			(xy 198.289672 -112.469168) (xy 198.263848 -112.480944) (xy 198.209585 -112.497581) (xy 198.153458 -112.505999)
			(xy 198.12508 -112.506506) (xy 198.09783 -112.506019) (xy 198.043885 -112.49826) (xy 197.991592 -112.482903)
			(xy 197.942018 -112.460261) (xy 197.89617 -112.430794) (xy 197.854983 -112.395103) (xy 197.819294 -112.353914)
			(xy 197.789829 -112.308064) (xy 197.76719 -112.258489) (xy 197.751836 -112.206196) (xy 197.74408 -112.15225)
			(xy 197.74408 -112.09775) (xy 197.751836 -112.043804) (xy 197.76719 -111.991511) (xy 197.789829 -111.941936)
			(xy 197.819294 -111.896086) (xy 197.854983 -111.854897) (xy 197.89617 -111.819206) (xy 197.942018 -111.789739)
			(xy 197.991592 -111.767097) (xy 198.043885 -111.75174) (xy 198.09783 -111.743981) (xy 198.12508 -111.74349)
			(xy 198.153458 -111.74401) (xy 198.209586 -111.752417) (xy 198.26385 -111.769049) (xy 198.289672 -111.780828)
			(xy 198.303113 -111.7867) (xy 198.332072 -111.791283) (xy 198.361141 -111.787454) (xy 198.387926 -111.77553)
			(xy 198.410222 -111.75649) (xy 198.426195 -111.731904) (xy 198.43453 -111.703794) (xy 198.43496 -111.689134)
			(xy 198.43496 -110.922308) (xy 193.381376 -110.922308) (xy 193.367067 -110.922795) (xy 193.339573 -110.930735)
			(xy 193.315358 -110.945985) (xy 193.296319 -110.967351) (xy 193.283949 -110.993157) (xy 193.279219 -111.021381)
			(xy 193.282497 -111.04981) (xy 193.293529 -111.076216) (xy 193.302128 -111.087662) (xy 193.316963 -111.106715)
			(xy 193.341899 -111.148068) (xy 193.361012 -111.192414) (xy 193.373951 -111.238937) (xy 193.380479 -111.286783)
			(xy 193.380868 -111.310928) (xy 193.38035 -111.338136) (xy 193.372067 -111.391917) (xy 193.355696 -111.443812)
			(xy 193.331621 -111.492611) (xy 193.3004 -111.537179) (xy 193.262762 -111.576478) (xy 193.219583 -111.609593)
			(xy 193.195956 -111.623094) (xy 193.16954 -111.637572) (xy 193.16954 -112.048544) (xy 193.213228 -112.05464)
			(xy 193.240149 -112.058967) (xy 193.292471 -112.074307) (xy 193.342077 -112.09694) (xy 193.387955 -112.126404)
			(xy 193.429171 -112.1621) (xy 193.464887 -112.203299) (xy 193.494373 -112.249164) (xy 193.517029 -112.298758)
			(xy 193.532395 -112.351073) (xy 193.540156 -112.405043) (xy 193.540155 -112.459568) (xy 193.532392 -112.513537)
			(xy 193.517025 -112.565852) (xy 193.494367 -112.615446) (xy 193.46488 -112.661309) (xy 193.429164 -112.702508)
			(xy 193.387946 -112.738202) (xy 193.342067 -112.767665) (xy 193.292461 -112.790297) (xy 193.240138 -112.805636)
			(xy 193.213228 -112.810036) (xy 193.16954 -112.816132) (xy 193.16954 -113.514632) (xy 196.46341 -113.514632)
			(xy 196.467481 -113.45901) (xy 196.479607 -113.404573) (xy 196.49953 -113.352482) (xy 196.526826 -113.303847)
			(xy 196.560912 -113.259704) (xy 196.601061 -113.220995) (xy 196.646419 -113.188544) (xy 196.696019 -113.163043)
			(xy 196.748803 -113.145036) (xy 196.803646 -113.134906) (xy 196.85938 -113.132869) (xy 196.914817 -113.138969)
			(xy 196.968774 -113.153075) (xy 197.020103 -113.174887) (xy 197.067709 -113.203941) (xy 197.110577 -113.239616)
			(xy 197.147794 -113.281153) (xy 197.178567 -113.327666) (xy 197.202239 -113.378163) (xy 197.218307 -113.43157)
			(xy 197.226427 -113.486746) (xy 197.226936 -113.514632) (xy 197.226427 -113.542518) (xy 197.218307 -113.597694)
			(xy 197.202239 -113.651101) (xy 197.178567 -113.701598) (xy 197.147794 -113.748111) (xy 197.110577 -113.789648)
			(xy 197.067709 -113.825323) (xy 197.020103 -113.854377) (xy 196.968774 -113.876189) (xy 196.914817 -113.890295)
			(xy 196.85938 -113.896395) (xy 196.803646 -113.894358) (xy 196.748803 -113.884228) (xy 196.696019 -113.866221)
			(xy 196.646419 -113.84072) (xy 196.601061 -113.808269) (xy 196.560912 -113.76956) (xy 196.526826 -113.725417)
			(xy 196.49953 -113.676782) (xy 196.479607 -113.624691) (xy 196.467481 -113.570254) (xy 196.46341 -113.514632)
			(xy 193.16954 -113.514632) (xy 193.16954 -114.303048) (xy 198.43496 -114.303048)
		)
		(stroke
			(width 0)
			(type solid)
		)
		(fill yes)
		(layer "B.Cu")
		(net "GND")
	)
	(gr_poly
		(pts
			(xy 333.806038 -49.14392) (xy 333.806038 -48.393858) (xy 333.805564 -48.379223) (xy 333.797269 -48.351154)
			(xy 333.781345 -48.326595) (xy 333.759102 -48.307569) (xy 333.732373 -48.295642) (xy 333.703357 -48.291797)
			(xy 333.674444 -48.296348) (xy 333.661004 -48.302164) (xy 333.637029 -48.312994) (xy 333.58669 -48.328274)
			(xy 333.534653 -48.335994) (xy 333.50835 -48.336454) (xy 333.4817 -48.335953) (xy 333.428995 -48.328002)
			(xy 333.378064 -48.312285) (xy 333.330044 -48.289154) (xy 333.286008 -48.259125) (xy 333.246938 -48.222869)
			(xy 333.213708 -48.181194) (xy 333.18706 -48.135033) (xy 333.167589 -48.085416) (xy 333.155729 -48.033452)
			(xy 333.151746 -47.9803) (xy 333.155729 -47.927148) (xy 333.167589 -47.875184) (xy 333.18706 -47.825567)
			(xy 333.213708 -47.779406) (xy 333.246938 -47.737731) (xy 333.286008 -47.701475) (xy 333.330044 -47.671446)
			(xy 333.378064 -47.648315) (xy 333.428995 -47.632598) (xy 333.4817 -47.624647) (xy 333.50835 -47.624238)
			(xy 333.536723 -47.624815) (xy 333.592744 -47.633858) (xy 333.646626 -47.65166) (xy 333.697008 -47.677771)
			(xy 333.742619 -47.711533) (xy 333.762858 -47.731426) (xy 333.763112 -47.73168) (xy 333.79918 -47.767748)
			(xy 333.943198 -47.62373) (xy 334.433926 -47.62373) (xy 334.54721 -47.510446) (xy 334.54721 -47.302166)
			(xy 334.546702 -47.29861) (xy 334.545157 -47.286541) (xy 334.543505 -47.262263) (xy 334.5434 -47.250096)
			(xy 334.543491 -47.237928) (xy 334.545141 -47.213649) (xy 334.546702 -47.201582) (xy 334.54721 -47.198026)
			(xy 334.54721 -46.502066) (xy 334.546702 -46.49851) (xy 334.545157 -46.486441) (xy 334.543505 -46.462163)
			(xy 334.5434 -46.449996) (xy 334.543491 -46.437828) (xy 334.545141 -46.413549) (xy 334.546702 -46.401482)
			(xy 334.54721 -46.397926) (xy 334.54721 -44.901866) (xy 334.546702 -44.89831) (xy 334.545157 -44.886241)
			(xy 334.543505 -44.861963) (xy 334.5434 -44.849796) (xy 334.543491 -44.837628) (xy 334.545141 -44.813349)
			(xy 334.546702 -44.801282) (xy 334.54721 -44.797726) (xy 334.54721 -44.635928) (xy 334.712564 -44.470574)
			(xy 335.27873 -44.470574) (xy 335.406238 -44.343066) (xy 335.406238 -44.114466) (xy 335.220056 -43.928284)
			(xy 334.633062 -43.928284) (xy 334.619944 -43.950296) (xy 334.58837 -43.990655) (xy 334.551339 -44.026072)
			(xy 334.509614 -44.055816) (xy 334.464057 -44.079273) (xy 334.415608 -44.09596) (xy 334.365268 -44.10553)
			(xy 334.339692 -44.1071) (xy 334.320134 -44.107862) (xy 333.783178 -44.644564) (xy 333.789528 -44.644564)
			(xy 333.789528 -45.279564) (xy 333.749396 -45.279564) (xy 333.749396 -45.35805) (xy 332.89367 -46.213776)
			(xy 332.909418 -46.246542) (xy 332.924127 -46.278018) (xy 332.944932 -46.344305) (xy 332.955492 -46.412973)
			(xy 332.956154 -46.44771) (xy 332.955648 -46.478578) (xy 332.947349 -46.539753) (xy 332.930903 -46.599257)
			(xy 332.90661 -46.656012) (xy 332.874908 -46.708986) (xy 332.836375 -46.757219) (xy 332.814422 -46.778926)
			(xy 332.814422 -47.067195) (xy 333.153248 -47.067195) (xy 333.153248 -47.013897) (xy 333.161191 -46.961193)
			(xy 333.176901 -46.910263) (xy 333.200027 -46.862242) (xy 333.230051 -46.818205) (xy 333.266303 -46.779134)
			(xy 333.307974 -46.745903) (xy 333.354132 -46.719254) (xy 333.403746 -46.699782) (xy 333.455708 -46.687922)
			(xy 333.508858 -46.683939) (xy 333.562008 -46.687922) (xy 333.61397 -46.699782) (xy 333.663584 -46.719254)
			(xy 333.709742 -46.745903) (xy 333.751413 -46.779134) (xy 333.787665 -46.818205) (xy 333.817689 -46.862242)
			(xy 333.840815 -46.910263) (xy 333.856525 -46.961193) (xy 333.864468 -47.013897) (xy 333.864966 -47.040546)
			(xy 333.864468 -47.067195) (xy 333.856525 -47.119899) (xy 333.840815 -47.170829) (xy 333.817689 -47.21885)
			(xy 333.787665 -47.262887) (xy 333.751413 -47.301958) (xy 333.709742 -47.335189) (xy 333.663584 -47.361838)
			(xy 333.61397 -47.38131) (xy 333.562008 -47.39317) (xy 333.508858 -47.397154) (xy 333.455708 -47.39317)
			(xy 333.403746 -47.38131) (xy 333.354132 -47.361838) (xy 333.307974 -47.335189) (xy 333.266303 -47.301958)
			(xy 333.230051 -47.262887) (xy 333.200027 -47.21885) (xy 333.176901 -47.170829) (xy 333.161191 -47.119899)
			(xy 333.153248 -47.067195) (xy 332.814422 -47.067195) (xy 332.814422 -47.173896) (xy 332.843886 -47.187612)
			(xy 332.86811 -47.199445) (xy 332.912988 -47.229319) (xy 332.952849 -47.265615) (xy 332.986784 -47.307506)
			(xy 333.014017 -47.354033) (xy 333.033925 -47.404134) (xy 333.046053 -47.456662) (xy 333.050125 -47.510419)
			(xy 333.046047 -47.564176) (xy 333.033913 -47.616704) (xy 333.014 -47.666802) (xy 332.986762 -47.713326)
			(xy 332.952822 -47.755213) (xy 332.912957 -47.791505) (xy 332.868076 -47.821374) (xy 332.843886 -47.83328)
			(xy 332.814422 -47.846996) (xy 332.814422 -48.113696) (xy 332.843886 -48.127412) (xy 332.86811 -48.139245)
			(xy 332.912988 -48.169119) (xy 332.952849 -48.205415) (xy 332.986784 -48.247306) (xy 333.014017 -48.293833)
			(xy 333.033925 -48.343934) (xy 333.046053 -48.396462) (xy 333.050125 -48.450219) (xy 333.046047 -48.503976)
			(xy 333.033913 -48.556504) (xy 333.014 -48.606602) (xy 332.986762 -48.653126) (xy 332.952822 -48.695013)
			(xy 332.912957 -48.731305) (xy 332.868076 -48.761174) (xy 332.843886 -48.77308) (xy 332.814422 -48.786796)
			(xy 332.814422 -48.910748) (xy 333.094838 -49.191164) (xy 333.758794 -49.191164)
		)
		(stroke
			(width 0)
			(type solid)
		)
		(fill yes)
		(layer "B.Cu")
		(net "P3V3_AUX")
	)
	(gr_poly
		(pts
			(xy 391.260838 -358.62387) (xy 391.260838 -333.245206) (xy 389.970264 -331.954632) (xy 382.223264 -331.954632)
			(xy 381.693166 -331.424534) (xy 381.693166 -328.889614) (xy 381.486664 -328.683112) (xy 373.23776 -328.683112)
			(xy 372.85549 -328.300842) (xy 372.85549 -325.307198) (xy 372.800118 -325.251826) (xy 342.685878 -325.251826)
			(xy 342.397588 -325.540116) (xy 342.397588 -327.716388) (xy 341.476584 -328.637392) (xy 332.746604 -328.637392)
			(xy 332.69428 -328.689716) (xy 332.69428 -333.872586) (xy 332.545436 -334.02143) (xy 325.997824 -334.02143)
			(xy 325.667624 -333.69123) (xy 324.070218 -333.69123) (xy 323.928232 -333.833216) (xy 323.928232 -342.548972)
			(xy 324.292722 -342.913462) (xy 326.056752 -342.913462) (xy 326.336152 -343.192862) (xy 326.336152 -344.65641)
			(xy 326.894952 -345.21521) (xy 328.574146 -345.21521) (xy 328.610214 -345.200224)
			(arc
				(start 328.656696 -345.153742)
				(mid 328.662599 -345.146598)
				(end 328.66711 -345.138502)
			)
			(xy 328.66711 -342.97874) (xy 328.768202 -342.877648) (xy 332.302866 -342.877648) (xy 332.30566 -342.875108)
			(xy 332.307438 -342.876886) (xy 332.483206 -342.876886) (xy 332.59776 -342.762332) (xy 332.59776 -337.731862)
			(xy 333.18196 -337.147662) (xy 334.235552 -337.147662) (xy 334.464152 -337.376262) (xy 334.464152 -338.840318)
			(xy 334.978502 -339.354668) (xy 334.985868 -339.372194) (xy 335.030064 -339.41639) (xy 335.049622 -339.424518)
			(xy 336.734658 -339.424518) (xy 336.770726 -339.409532)
			(arc
				(start 336.817208 -339.36305)
				(mid 336.823111 -339.355906)
				(end 336.827622 -339.34781)
			)
			(xy 336.827622 -337.188048) (xy 336.928714 -337.086956) (xy 340.463378 -337.086956) (xy 340.466172 -337.084416)
			(xy 340.46795 -337.086194) (xy 340.643718 -337.086194) (xy 340.758272 -336.97164) (xy 340.758272 -334.379062)
			(xy 341.306912 -333.830422) (xy 342.869012 -333.830422) (xy 343.138252 -334.099662) (xy 343.138252 -335.942432)
			(xy 343.153238 -335.9785) (xy 343.174066 -335.999328) (xy 343.210134 -336.014314) (xy 344.89517 -336.014314)
			(xy 344.931238 -335.999328)
			(arc
				(start 344.97772 -335.952846)
				(mid 344.983623 -335.945702)
				(end 344.988134 -335.937606)
			)
			(xy 344.988134 -333.777844) (xy 345.089226 -333.676752) (xy 351.022666 -333.676752) (xy 351.298764 -333.95285)
			(xy 351.298764 -335.939892) (xy 351.373186 -336.014314) (xy 353.055682 -336.014314) (xy 353.09175 -335.999328)
			(arc
				(start 353.138232 -335.952846)
				(mid 353.144135 -335.945702)
				(end 353.148646 -335.937606)
			)
			(xy 353.148646 -333.777844) (xy 353.249738 -333.676752) (xy 356.784402 -333.676752) (xy 356.787196 -333.674212)
			(xy 356.788974 -333.67599) (xy 359.182416 -333.67599) (xy 359.459276 -333.95285) (xy 359.459276 -335.942432)
			(xy 359.474262 -335.9785) (xy 359.49509 -335.999328) (xy 359.531158 -336.014314) (xy 361.216194 -336.014314)
			(xy 361.252262 -335.999328)
			(arc
				(start 361.298744 -335.952846)
				(mid 361.304647 -335.945702)
				(end 361.309158 -335.937606)
			)
			(xy 361.309158 -333.777844) (xy 361.41025 -333.676752) (xy 364.944914 -333.676752) (xy 364.947708 -333.674212)
			(xy 364.949486 -333.67599) (xy 365.239808 -333.67599) (xy 365.519716 -333.396082) (xy 367.06302 -333.396082)
			(xy 367.619788 -333.95285) (xy 367.619788 -335.942432) (xy 367.634774 -335.9785) (xy 367.655602 -335.999328)
			(xy 367.69167 -336.014314) (xy 369.376706 -336.014314) (xy 369.412774 -335.999328)
			(arc
				(start 369.459256 -335.952846)
				(mid 369.465159 -335.945702)
				(end 369.46967 -335.937606)
			)
			(xy 369.46967 -333.777844) (xy 369.570762 -333.676752) (xy 373.105426 -333.676752) (xy 373.10822 -333.674212)
			(xy 373.109998 -333.67599) (xy 373.40032 -333.67599) (xy 373.695468 -333.971138) (xy 373.695468 -337.110578)
			(xy 373.783352 -337.198462) (xy 375.615708 -337.198462) (xy 375.7803 -337.363054) (xy 375.7803 -339.352636)
			(xy 375.795286 -339.388704) (xy 375.816114 -339.409532) (xy 375.852182 -339.424518) (xy 377.537218 -339.424518)
			(xy 377.573286 -339.409532)
			(arc
				(start 377.619768 -339.36305)
				(mid 377.625671 -339.355906)
				(end 377.630182 -339.34781)
			)
			(xy 377.630182 -337.188048) (xy 377.731274 -337.086956) (xy 381.661924 -337.086956) (xy 381.856488 -337.28152)
			(xy 381.856488 -342.53297) (xy 381.920496 -342.596978) (xy 383.384044 -342.596978) (xy 383.940812 -343.153746)
			(xy 383.940812 -345.143328) (xy 383.955798 -345.179396) (xy 383.976626 -345.200224) (xy 384.012694 -345.21521)
			(xy 385.69773 -345.21521) (xy 385.733798 -345.200224)
			(arc
				(start 385.78028 -345.153742)
				(mid 385.786183 -345.146598)
				(end 385.790694 -345.138502)
			)
			(xy 385.790694 -342.97874) (xy 385.891786 -342.877648) (xy 390.040876 -342.877648) (xy 390.387078 -343.22385)
			(xy 390.387078 -349.78975) (xy 388.13994 -352.036888)
			(arc
				(start 388.13994 -352.623374)
				(mid 388.561578 -354.434902)
				(end 388.13994 -356.24643)
			)
			(xy 388.13994 -357.508048) (xy 389.69442 -359.062528) (xy 390.82218 -359.062528)
		)
		(stroke
			(width 0)
			(type solid)
		)
		(fill yes)
		(layer "B.Cu")
		(net "GND")
	)
	(gr_poly
		(pts
			(xy 399.6817 -157.683962) (xy 399.693805 -157.672829) (xy 399.722385 -157.656581) (xy 399.754163 -157.648153)
			(xy 399.7706 -157.64764) (xy 401.3454 -157.64764) (xy 401.361833 -157.648185) (xy 401.393602 -157.656617)
			(xy 401.422183 -157.672848) (xy 401.4343 -157.683962) (xy 401.449286 -157.69844) (xy 408.975052 -157.69844)
			(xy 408.985016 -157.697957) (xy 409.003448 -157.690378) (xy 409.010866 -157.683708) (xy 409.147772 -157.546548)
			(xy 409.147772 -147.41652) (xy 408.9908 -147.259548) (xy 399.288 -147.259548) (xy 398.944592 -147.602956)
			(xy 398.944592 -150.339552) (xy 399.642589 -150.339552) (xy 399.646611 -150.253832) (xy 399.658642 -150.168864)
			(xy 399.678578 -150.085397) (xy 399.706241 -150.004163) (xy 399.74139 -149.925877) (xy 399.783716 -149.851226)
			(xy 399.832845 -149.780867) (xy 399.888348 -149.715417) (xy 399.949735 -149.655453) (xy 400.016468 -149.6015)
			(xy 400.08796 -149.554033) (xy 400.163582 -149.513469) (xy 400.242671 -149.480165) (xy 400.324531 -149.454413)
			(xy 400.408442 -149.43644) (xy 400.493668 -149.426404) (xy 400.57946 -149.424392) (xy 400.665062 -149.430423)
			(xy 400.749724 -149.444443) (xy 400.832701 -149.466329) (xy 400.913264 -149.49589) (xy 400.990704 -149.532864)
			(xy 401.064343 -149.576928) (xy 401.133531 -149.627694) (xy 401.197662 -149.684715) (xy 401.256171 -149.747491)
			(xy 401.308544 -149.815471) (xy 401.354322 -149.888056) (xy 401.393102 -149.964608) (xy 401.424543 -150.044456)
			(xy 401.448369 -150.126897) (xy 401.46437 -150.211207) (xy 401.472405 -150.296645) (xy 401.472908 -150.339552)
			(xy 401.472405 -150.382459) (xy 401.46437 -150.467897) (xy 401.448369 -150.552207) (xy 401.424543 -150.634648)
			(xy 401.393102 -150.714496) (xy 401.354322 -150.791048) (xy 401.308544 -150.863633) (xy 401.256171 -150.931613)
			(xy 401.197662 -150.994389) (xy 401.133531 -151.05141) (xy 401.064343 -151.102176) (xy 400.990704 -151.14624)
			(xy 400.913264 -151.183214) (xy 400.832701 -151.212775) (xy 400.749724 -151.234661) (xy 400.665062 -151.248681)
			(xy 400.57946 -151.254712) (xy 400.493668 -151.2527) (xy 400.408442 -151.242664) (xy 400.324531 -151.224691)
			(xy 400.242671 -151.198939) (xy 400.163582 -151.165635) (xy 400.08796 -151.125071) (xy 400.016468 -151.077604)
			(xy 399.949735 -151.023651) (xy 399.888348 -150.963687) (xy 399.832845 -150.898237) (xy 399.783716 -150.827878)
			(xy 399.74139 -150.753227) (xy 399.706241 -150.674941) (xy 399.678578 -150.593707) (xy 399.658642 -150.51024)
			(xy 399.646611 -150.425272) (xy 399.642589 -150.339552) (xy 398.944592 -150.339552) (xy 398.944592 -153.126948)
			(xy 399.668492 -153.126948) (xy 399.668492 -151.552148) (xy 399.668931 -151.53876) (xy 399.675852 -151.512893)
			(xy 399.689232 -151.4897) (xy 399.708162 -151.470762) (xy 399.731349 -151.45737) (xy 399.757212 -151.450438)
			(xy 399.7706 -151.45004) (xy 401.3454 -151.45004) (xy 401.358794 -151.45039) (xy 401.38467 -151.457326)
			(xy 401.407868 -151.470724) (xy 401.426806 -151.489671) (xy 401.440193 -151.512875) (xy 401.447116 -151.538753)
			(xy 401.447508 -151.552148) (xy 401.447508 -153.126948) (xy 401.447113 -153.140335) (xy 401.440173 -153.166196)
			(xy 401.426779 -153.189379) (xy 401.407841 -153.208308) (xy 401.384651 -153.221692) (xy 401.358788 -153.22862)
			(xy 401.3454 -153.229056) (xy 399.7706 -153.229056) (xy 399.757219 -153.228572) (xy 399.731368 -153.221647)
			(xy 399.708188 -153.208269) (xy 399.68926 -153.18935) (xy 399.675871 -153.166177) (xy 399.668935 -153.140329)
			(xy 399.668492 -153.126948) (xy 398.944592 -153.126948) (xy 398.944592 -156.562552) (xy 399.642589 -156.562552)
			(xy 399.646611 -156.476832) (xy 399.658642 -156.391864) (xy 399.678578 -156.308397) (xy 399.706241 -156.227163)
			(xy 399.74139 -156.148877) (xy 399.783716 -156.074226) (xy 399.832845 -156.003867) (xy 399.888348 -155.938417)
			(xy 399.949735 -155.878453) (xy 400.016468 -155.8245) (xy 400.08796 -155.777033) (xy 400.163582 -155.736469)
			(xy 400.242671 -155.703165) (xy 400.324531 -155.677413) (xy 400.408442 -155.65944) (xy 400.493668 -155.649404)
			(xy 400.57946 -155.647392) (xy 400.665062 -155.653423) (xy 400.749724 -155.667443) (xy 400.832701 -155.689329)
			(xy 400.913264 -155.71889) (xy 400.990704 -155.755864) (xy 401.064343 -155.799928) (xy 401.133531 -155.850694)
			(xy 401.197662 -155.907715) (xy 401.256171 -155.970491) (xy 401.308544 -156.038471) (xy 401.354322 -156.111056)
			(xy 401.393102 -156.187608) (xy 401.424543 -156.267456) (xy 401.448369 -156.349897) (xy 401.46437 -156.434207)
			(xy 401.472405 -156.519645) (xy 401.472908 -156.562552) (xy 401.472405 -156.605459) (xy 401.46437 -156.690897)
			(xy 401.448369 -156.775207) (xy 401.424543 -156.857648) (xy 401.393102 -156.937496) (xy 401.354322 -157.014048)
			(xy 401.308544 -157.086633) (xy 401.256171 -157.154613) (xy 401.197662 -157.217389) (xy 401.133531 -157.27441)
			(xy 401.064343 -157.325176) (xy 400.990704 -157.36924) (xy 400.913264 -157.406214) (xy 400.832701 -157.435775)
			(xy 400.749724 -157.457661) (xy 400.665062 -157.471681) (xy 400.57946 -157.477712) (xy 400.493668 -157.4757)
			(xy 400.408442 -157.465664) (xy 400.324531 -157.447691) (xy 400.242671 -157.421939) (xy 400.163582 -157.388635)
			(xy 400.08796 -157.348071) (xy 400.016468 -157.300604) (xy 399.949735 -157.246651) (xy 399.888348 -157.186687)
			(xy 399.832845 -157.121237) (xy 399.783716 -157.050878) (xy 399.74139 -156.976227) (xy 399.706241 -156.897941)
			(xy 399.678578 -156.816707) (xy 399.658642 -156.73324) (xy 399.646611 -156.648272) (xy 399.642589 -156.562552)
			(xy 398.944592 -156.562552) (xy 398.944592 -157.16504) (xy 399.477992 -157.69844) (xy 399.666714 -157.69844)
		)
		(stroke
			(width 0)
			(type solid)
		)
		(fill yes)
		(layer "B.Cu")
		(net "PVCCFA_EHV_CPU0")
	)
	(gr_poly
		(pts
			(xy 353.168204 -263.390126) (xy 353.168204 -261.825486) (xy 353.110292 -261.767574) (xy 352.213672 -261.767574)
			(xy 352.114104 -261.668006) (xy 352.114104 -261.017766) (xy 352.205544 -260.926326) (xy 352.444304 -260.926326)
			(xy 352.479864 -260.890766) (xy 352.479864 -259.988304) (xy 352.928428 -259.53974) (xy 356.083108 -259.53974)
			(xy 356.312216 -259.768848) (xy 356.456742 -259.768848) (xy 356.558596 -259.666994) (xy 356.558596 -258.679442)
			(xy 356.02291 -258.143756) (xy 354.569014 -258.143756) (xy 354.295456 -257.870198) (xy 354.295456 -257.480816)
			(xy 354.535486 -257.24104) (xy 356.081584 -257.24104) (xy 356.167944 -257.154426) (xy 356.167944 -256.93624)
			(xy 356.17404 -256.930144) (xy 356.17404 -256.922016) (xy 356.566724 -256.529332) (xy 356.566724 -255.668526)
			(xy 356.456488 -255.55829) (xy 356.31628 -255.55829) (xy 356.158546 -255.716024) (xy 353.266248 -255.716024)
			(xy 353.260914 -255.721612) (xy 352.696272 -255.721612) (xy 352.652584 -255.67767) (xy 352.622358 -255.67767)
			(xy 352.482404 -255.537716) (xy 352.482404 -254.48641) (xy 352.44786 -254.451866) (xy 351.819464 -254.451866)
			(xy 351.613724 -254.246126) (xy 351.613724 -253.702566) (xy 351.748344 -253.567946) (xy 351.82556 -253.567946)
			(xy 351.825814 -253.567692) (xy 352.966274 -253.567692) (xy 352.966528 -253.567946) (xy 352.972624 -253.567946)
			(xy 353.201224 -253.796546) (xy 353.201224 -254.108966) (xy 353.271836 -254.179832) (xy 354.105972 -254.179832)
			(xy 354.196904 -254.088646) (xy 354.196904 -253.766066) (xy 354.378514 -253.584456) (xy 356.01656 -253.584456)
			(xy 356.137464 -253.463298) (xy 356.137464 -253.177802) (xy 356.155244 -253.160276) (xy 356.155244 -253.151386)
			(xy 356.561644 -252.744986) (xy 356.561644 -251.975366) (xy 356.485952 -251.89942) (xy 356.343204 -251.89942)
			(xy 356.186232 -252.056646) (xy 351.179384 -252.056646) (xy 351.178368 -252.055376) (xy 351.154238 -252.055376)
			(xy 350.955864 -251.85624) (xy 350.955864 -250.167648) (xy 351.189798 -249.933968) (xy 351.20072 -249.933968)
			(xy 351.203768 -249.930666) (xy 352.947224 -249.930666) (xy 352.950272 -249.933968) (xy 352.95459 -249.933968)
			(xy 353.178872 -250.157996) (xy 353.178872 -250.419616) (xy 353.240594 -250.481592) (xy 354.149152 -250.481592)
			(xy 354.223828 -250.406916) (xy 354.223828 -250.126754) (xy 354.227384 -250.123198) (xy 354.227384 -250.111006)
			(xy 354.425504 -249.912886) (xy 356.043484 -249.912886) (xy 356.091744 -249.864626) (xy 356.091744 -249.610626)
			(xy 356.132892 -249.569732) (xy 356.132892 -249.56262) (xy 356.331012 -249.3645) (xy 356.543356 -249.151648)
			(xy 356.543356 -248.314718) (xy 356.456488 -248.227596) (xy 356.314756 -248.227596) (xy 356.14229 -248.400316)
			(xy 352.765614 -248.400316) (xy 352.69551 -248.47042)
			(arc
				(start 350.54159 -248.47042)
				(mid 350.452229 -248.523676)
				(end 350.4565 -248.627646)
			)
			(arc
				(start 350.4565 -248.627646)
				(mid 350.495931 -248.713081)
				(end 350.509332 -248.806208)
			)
			(arc
				(start 350.509332 -248.806208)
				(mid 350.450829 -248.992906)
				(end 350.296226 -249.112786)
			)
			(xy 350.285812 -249.116596) (xy 350.199198 -249.20321) (xy 349.561658 -249.20321) (xy 349.419418 -249.34545)
			(xy 349.419418 -253.39929) (xy 349.613474 -253.593346) (xy 350.149668 -253.593346)
			(arc
				(start 350.158812 -253.589536)
				(mid 350.224365 -253.570139)
				(end 350.292416 -253.563628)
			)
			(arc
				(start 350.292416 -253.563628)
				(mid 350.544222 -253.66793)
				(end 350.648524 -253.919736)
			)
			(arc
				(start 350.648524 -253.919736)
				(mid 350.56158 -254.152896)
				(end 350.343216 -254.272288)
			)
			(xy 350.299782 -254.278384) (xy 350.299782 -255.188974)
			(arc
				(start 350.343216 -255.19507)
				(mid 350.561645 -255.314406)
				(end 350.648524 -255.547622)
			)
			(arc
				(start 350.648524 -255.547622)
				(mid 350.577814 -255.760603)
				(end 350.393762 -255.888998)
			)
			(xy 350.381316 -255.892808) (xy 350.336358 -255.937766) (xy 350.42729 -256.028698) (xy 350.97847 -256.028698)
			(xy 350.97974 -256.029968) (xy 352.369882 -256.029968) (xy 352.372422 -256.027174) (xy 352.613976 -256.027174)
			(xy 352.927412 -256.34061) (xy 352.927412 -257.38328) (xy 352.928936 -257.384804) (xy 352.927412 -257.386328)
			(xy 352.927412 -259.13461) (xy 352.635312 -259.42671) (xy 352.389694 -259.42671) (xy 352.383344 -259.42036)
			(xy 350.709484 -259.42036) (xy 350.6597 -259.470144) (xy 350.6597 -260.994906)
			(arc
				(start 350.927162 -261.262622)
				(mid 350.974515 -261.322872)
				(end 351.006156 -261.39267)
			)
			(xy 351.009966 -261.404608) (xy 351.021142 -261.415784) (xy 351.021142 -262.340344) (xy 351.715324 -263.034526)
			(xy 351.722944 -263.034526) (xy 352.121724 -263.433306) (xy 353.125024 -263.433306)
		)
		(stroke
			(width 0)
			(type solid)
		)
		(fill yes)
		(layer "B.Cu")
		(net "GND")
	)
	(gr_poly
		(pts
			(xy 67.818 -257.724148) (xy 67.818 -251.374148) (xy 67.6402 -251.196348) (xy 66.286888 -251.196348)
			(xy 66.278252 -251.19965) (xy 66.253944 -251.208367) (xy 66.203518 -251.219499) (xy 66.152014 -251.223235)
			(xy 66.10051 -251.219499) (xy 66.050084 -251.208367) (xy 66.025776 -251.19965) (xy 66.01714 -251.196348)
			(xy 64.077088 -251.196348) (xy 64.068452 -251.19965) (xy 64.048528 -251.206863) (xy 64.007398 -251.217053)
			(xy 63.98641 -251.21997) (xy 63.972382 -251.222208) (xy 63.946273 -251.233373) (xy 63.924246 -251.251294)
			(xy 63.908004 -251.274586) (xy 63.898802 -251.301449) (xy 63.89735 -251.329808) (xy 63.903761 -251.35747)
			(xy 63.91754 -251.382299) (xy 63.927228 -251.39269) (xy 64.167766 -251.633482) (xy 64.185169 -251.651544)
			(xy 64.214694 -251.692088) (xy 64.237517 -251.73675) (xy 64.253076 -251.78443) (xy 64.26099 -251.833957)
			(xy 64.261492 -251.859034) (xy 64.261492 -252.408436) (xy 64.266064 -252.418342) (xy 64.276273 -252.441722)
			(xy 64.290652 -252.490671) (xy 64.297902 -252.541169) (xy 64.298322 -252.566678) (xy 64.297824 -252.593327)
			(xy 64.289881 -252.646031) (xy 64.274171 -252.696961) (xy 64.251045 -252.744982) (xy 64.221021 -252.789019)
			(xy 64.184769 -252.82809) (xy 64.143098 -252.861321) (xy 64.09694 -252.88797) (xy 64.047326 -252.907442)
			(xy 63.995364 -252.919302) (xy 63.942214 -252.923286) (xy 63.889064 -252.919302) (xy 63.837102 -252.907442)
			(xy 63.787488 -252.88797) (xy 63.74133 -252.861321) (xy 63.699659 -252.82809) (xy 63.663407 -252.789019)
			(xy 63.633383 -252.744982) (xy 63.610257 -252.696961) (xy 63.594547 -252.646031) (xy 63.586604 -252.593327)
			(xy 63.586106 -252.566678) (xy 63.586524 -252.541169) (xy 63.593769 -252.490669) (xy 63.608151 -252.441721)
			(xy 63.618364 -252.418342) (xy 63.622936 -252.408436) (xy 63.622936 -251.991114) (xy 63.144908 -251.513086)
			(xy 63.124588 -251.512324) (xy 63.095268 -251.511014) (xy 63.037304 -251.501805) (xy 62.980993 -251.48526)
			(xy 62.927261 -251.461649) (xy 62.876989 -251.431361) (xy 62.831002 -251.394893) (xy 62.790057 -251.352843)
			(xy 62.754826 -251.305903) (xy 62.725886 -251.254843) (xy 62.714378 -251.227844) (xy 62.701424 -251.196348)
			(xy 60.428378 -251.196348) (xy 60.301378 -251.323348) (xy 60.301378 -251.743443) (xy 61.696336 -251.743443)
			(xy 61.696336 -251.690145) (xy 61.704279 -251.637441) (xy 61.719989 -251.586511) (xy 61.743115 -251.53849)
			(xy 61.773139 -251.494453) (xy 61.809391 -251.455382) (xy 61.851062 -251.422151) (xy 61.89722 -251.395502)
			(xy 61.946834 -251.37603) (xy 61.998796 -251.36417) (xy 62.051946 -251.360187) (xy 62.105096 -251.36417)
			(xy 62.157058 -251.37603) (xy 62.206672 -251.395502) (xy 62.25283 -251.422151) (xy 62.294501 -251.455382)
			(xy 62.330753 -251.494453) (xy 62.360777 -251.53849) (xy 62.383903 -251.586511) (xy 62.399613 -251.637441)
			(xy 62.407556 -251.690145) (xy 62.408054 -251.716794) (xy 62.407556 -251.743443) (xy 62.399613 -251.796147)
			(xy 62.383903 -251.847077) (xy 62.360777 -251.895098) (xy 62.330753 -251.939135) (xy 62.294501 -251.978206)
			(xy 62.25283 -252.011437) (xy 62.206672 -252.038086) (xy 62.157058 -252.057558) (xy 62.105096 -252.069418)
			(xy 62.051946 -252.073402) (xy 61.998796 -252.069418) (xy 61.946834 -252.057558) (xy 61.89722 -252.038086)
			(xy 61.851062 -252.011437) (xy 61.809391 -251.978206) (xy 61.773139 -251.939135) (xy 61.743115 -251.895098)
			(xy 61.719989 -251.847077) (xy 61.704279 -251.796147) (xy 61.696336 -251.743443) (xy 60.301378 -251.743443)
			(xy 60.301378 -251.982986) (xy 59.9948 -252.289564) (xy 57.631584 -252.289564) (xy 57.391554 -252.529594)
			(xy 57.391554 -254.24765) (xy 57.380238 -254.258966) (xy 61.460596 -254.258966) (xy 61.460596 -254.174434)
			(xy 61.468395 -254.090264) (xy 61.483928 -254.007172) (xy 61.507061 -253.925867) (xy 61.537596 -253.847044)
			(xy 61.575275 -253.771375) (xy 61.619774 -253.699504) (xy 61.670715 -253.632047) (xy 61.727663 -253.569577)
			(xy 61.790131 -253.512628) (xy 61.857588 -253.461685) (xy 61.929457 -253.417184) (xy 62.005126 -253.379504)
			(xy 62.083948 -253.348967) (xy 62.165252 -253.325832) (xy 62.248344 -253.310298) (xy 62.332514 -253.302497)
			(xy 62.37478 -253.302008) (xy 63.61938 -253.302008) (xy 63.661644 -253.302557) (xy 63.745811 -253.310354)
			(xy 63.8289 -253.325884) (xy 63.910202 -253.349015) (xy 63.989022 -253.379549) (xy 64.064689 -253.417225)
			(xy 64.136557 -253.461722) (xy 64.204012 -253.512661) (xy 64.26648 -253.569606) (xy 64.323426 -253.632072)
			(xy 64.374367 -253.699527) (xy 64.418865 -253.771393) (xy 64.456543 -253.847059) (xy 64.487079 -253.925879)
			(xy 64.510211 -254.00718) (xy 64.525743 -254.090269) (xy 64.533543 -254.174436) (xy 64.533543 -254.258964)
			(xy 64.525743 -254.343131) (xy 64.510211 -254.42622) (xy 64.487079 -254.507521) (xy 64.456543 -254.586341)
			(xy 64.418865 -254.662007) (xy 64.374367 -254.733873) (xy 64.323426 -254.801328) (xy 64.26648 -254.863794)
			(xy 64.204012 -254.920739) (xy 64.136557 -254.971678) (xy 64.064689 -255.016175) (xy 63.989022 -255.053851)
			(xy 63.910202 -255.084385) (xy 63.8289 -255.107516) (xy 63.745811 -255.123046) (xy 63.661644 -255.130843)
			(xy 63.61938 -255.131316) (xy 62.37478 -255.131316) (xy 62.332514 -255.130903) (xy 62.248344 -255.123102)
			(xy 62.165252 -255.107568) (xy 62.083948 -255.084433) (xy 62.005126 -255.053896) (xy 61.929457 -255.016216)
			(xy 61.857588 -254.971715) (xy 61.790131 -254.920772) (xy 61.727663 -254.863823) (xy 61.670715 -254.801353)
			(xy 61.619774 -254.733896) (xy 61.575275 -254.662025) (xy 61.537596 -254.586356) (xy 61.507061 -254.507533)
			(xy 61.483928 -254.426228) (xy 61.468395 -254.343136) (xy 61.460596 -254.258966) (xy 57.380238 -254.258966)
			(xy 56.134 -255.505204) (xy 56.134 -257.927348) (xy 56.328056 -258.121404) (xy 67.420744 -258.121404)
		)
		(stroke
			(width 0)
			(type solid)
		)
		(fill yes)
		(layer "B.Cu")
		(net "PVCCFA_EHV_FIVRA_CPU1")
	)
	(gr_poly
		(pts
			(xy 451.301866 -435.59984) (xy 451.301365 -435.529025) (xy 451.293352 -435.387622) (xy 451.277352 -435.246898)
			(xy 451.253417 -435.107305) (xy 451.221622 -434.96929) (xy 451.18207 -434.833294) (xy 451.134887 -434.699755)
			(xy 451.080225 -434.569098) (xy 451.018259 -434.441743) (xy 450.949186 -434.318098) (xy 450.873229 -434.198559)
			(xy 450.790631 -434.083508) (xy 450.701656 -433.973315) (xy 450.60659 -433.868331) (xy 450.505736 -433.768895)
			(xy 450.399418 -433.675323) (xy 450.287977 -433.587917) (xy 450.171769 -433.506955) (xy 450.051167 -433.432697)
			(xy 449.926556 -433.365381) (xy 449.798337 -433.305223) (xy 449.66692 -433.252416) (xy 449.532726 -433.207127)
			(xy 449.396185 -433.169504) (xy 449.257733 -433.139665) (xy 449.117816 -433.117707) (xy 448.97688 -433.103701)
			(xy 448.835377 -433.09769) (xy 448.693761 -433.099694) (xy 448.552485 -433.109707) (xy 448.412002 -433.127696)
			(xy 448.272762 -433.153605) (xy 448.135211 -433.187349) (xy 447.999788 -433.228822) (xy 447.86693 -433.27789)
			(xy 447.73706 -433.334395) (xy 447.610594 -433.398158) (xy 447.487939 -433.468973) (xy 447.369486 -433.546614)
			(xy 447.255616 -433.630832) (xy 447.146693 -433.721357) (xy 447.043066 -433.8179) (xy 446.945066 -433.92015)
			(xy 446.853009 -434.027782) (xy 446.767188 -434.140449) (xy 446.687878 -434.257791) (xy 446.615335 -434.379432)
			(xy 446.549789 -434.504982) (xy 446.491451 -434.634039) (xy 446.440509 -434.766191) (xy 446.397124 -434.901012)
			(xy 446.361436 -435.038072) (xy 446.33356 -435.176932) (xy 446.313584 -435.317147) (xy 446.301573 -435.458267)
			(xy 446.297565 -435.59984) (xy 446.739528 -435.59984) (xy 446.743513 -435.471743) (xy 446.755455 -435.344142)
			(xy 446.775307 -435.21753) (xy 446.802991 -435.092397) (xy 446.838402 -434.969228) (xy 446.881401 -434.848498)
			(xy 446.931823 -434.730675) (xy 446.989472 -434.616214) (xy 447.054126 -434.505559) (xy 447.125534 -434.399138)
			(xy 447.203421 -434.297362) (xy 447.287484 -434.200625) (xy 447.377398 -434.109301) (xy 447.472816 -434.023744)
			(xy 447.573369 -433.944284) (xy 447.678667 -433.871229) (xy 447.788303 -433.804862) (xy 447.901853 -433.74544)
			(xy 448.018878 -433.693192) (xy 448.138924 -433.64832) (xy 448.261528 -433.610998) (xy 448.386215 -433.581371)
			(xy 448.512503 -433.559553) (xy 448.639903 -433.545628) (xy 448.767922 -433.539651) (xy 448.896066 -433.541644)
			(xy 449.023837 -433.5516) (xy 449.150742 -433.56948) (xy 449.276291 -433.595215) (xy 449.399996 -433.628706)
			(xy 449.52138 -433.669822) (xy 449.639973 -433.718406) (xy 449.755316 -433.774268) (xy 449.866963 -433.837193)
			(xy 449.974482 -433.906938) (xy 450.077458 -433.983232) (xy 450.17549 -434.06578) (xy 450.268201 -434.154263)
			(xy 450.355232 -434.248339) (xy 450.436246 -434.347644) (xy 450.510929 -434.451793) (xy 450.578993 -434.560384)
			(xy 450.640175 -434.672996) (xy 450.694236 -434.789194) (xy 450.74097 -434.908529) (xy 450.780194 -435.030537)
			(xy 450.811756 -435.154749) (xy 450.835536 -435.280682) (xy 450.85144 -435.40785) (xy 450.859408 -435.535761)
			(xy 450.859906 -435.59984) (xy 450.859408 -435.663919) (xy 450.85144 -435.79183) (xy 450.835536 -435.918998)
			(xy 450.811756 -436.044931) (xy 450.780194 -436.169143) (xy 450.74097 -436.291151) (xy 450.694236 -436.410486)
			(xy 450.640175 -436.526684) (xy 450.578993 -436.639296) (xy 450.510929 -436.747887) (xy 450.436246 -436.852036)
			(xy 450.355232 -436.951341) (xy 450.268201 -437.045417) (xy 450.17549 -437.1339) (xy 450.077458 -437.216448)
			(xy 449.974482 -437.292742) (xy 449.866963 -437.362487) (xy 449.755316 -437.425412) (xy 449.639973 -437.481274)
			(xy 449.52138 -437.529858) (xy 449.399996 -437.570974) (xy 449.276291 -437.604465) (xy 449.150742 -437.6302)
			(xy 449.023837 -437.64808) (xy 448.896066 -437.658036) (xy 448.767922 -437.660029) (xy 448.639903 -437.654052)
			(xy 448.512503 -437.640127) (xy 448.386215 -437.618309) (xy 448.261528 -437.588682) (xy 448.138924 -437.55136)
			(xy 448.018878 -437.506488) (xy 447.901853 -437.45424) (xy 447.788303 -437.394818) (xy 447.678667 -437.328451)
			(xy 447.573369 -437.255396) (xy 447.472816 -437.175936) (xy 447.377398 -437.090379) (xy 447.287484 -436.999055)
			(xy 447.203421 -436.902318) (xy 447.125534 -436.800542) (xy 447.054126 -436.694121) (xy 446.989472 -436.583466)
			(xy 446.931823 -436.469005) (xy 446.881401 -436.351182) (xy 446.838402 -436.230452) (xy 446.802991 -436.107283)
			(xy 446.775307 -435.98215) (xy 446.755455 -435.855538) (xy 446.743513 -435.727937) (xy 446.739528 -435.59984)
			(xy 446.297565 -435.59984) (xy 446.301573 -435.741413) (xy 446.313584 -435.882533) (xy 446.33356 -436.022748)
			(xy 446.361436 -436.161608) (xy 446.397124 -436.298668) (xy 446.440509 -436.433489) (xy 446.491451 -436.565641)
			(xy 446.549789 -436.694698) (xy 446.615335 -436.820248) (xy 446.687878 -436.941889) (xy 446.767188 -437.059231)
			(xy 446.853009 -437.171898) (xy 446.945066 -437.27953) (xy 447.043066 -437.38178) (xy 447.146693 -437.478323)
			(xy 447.255616 -437.568848) (xy 447.369486 -437.653066) (xy 447.487939 -437.730707) (xy 447.610594 -437.801522)
			(xy 447.73706 -437.865285) (xy 447.86693 -437.92179) (xy 447.999788 -437.970858) (xy 448.135211 -438.012331)
			(xy 448.272762 -438.046075) (xy 448.412002 -438.071984) (xy 448.552485 -438.089973) (xy 448.693761 -438.099986)
			(xy 448.835377 -438.10199) (xy 448.97688 -438.095979) (xy 449.117816 -438.081973) (xy 449.257733 -438.060015)
			(xy 449.396185 -438.030176) (xy 449.532726 -437.992553) (xy 449.66692 -437.947264) (xy 449.798337 -437.894457)
			(xy 449.926556 -437.834299) (xy 450.051167 -437.766983) (xy 450.171769 -437.692725) (xy 450.287977 -437.611763)
			(xy 450.399418 -437.524357) (xy 450.505736 -437.430785) (xy 450.60659 -437.331349) (xy 450.701656 -437.226365)
			(xy 450.790631 -437.116172) (xy 450.873229 -437.001121) (xy 450.949186 -436.881582) (xy 451.018259 -436.757937)
			(xy 451.080225 -436.630582) (xy 451.134887 -436.499925) (xy 451.18207 -436.366386) (xy 451.221622 -436.23039)
			(xy 451.253417 -436.092375) (xy 451.277352 -435.952782) (xy 451.293352 -435.812058) (xy 451.301365 -435.670655)
		)
		(stroke
			(width 0)
			(type solid)
		)
		(fill yes)
		(layer "B.Cu")
		(net "Net_8631")
	)
	(gr_poly
		(pts
			(xy 415.674556 -185.686192) (xy 415.674556 -183.406288) (xy 415.681405 -183.398891) (xy 415.689142 -183.380292)
			(xy 415.689542 -183.37022) (xy 415.689542 -181.443376) (xy 415.689971 -181.433309) (xy 415.697696 -181.414715)
			(xy 415.704528 -181.407308) (xy 415.827972 -181.283864) (xy 415.835371 -181.277022) (xy 415.85397 -181.269303)
			(xy 415.86404 -181.268878) (xy 418.234876 -181.268878) (xy 418.24494 -181.26844) (xy 418.263522 -181.260704)
			(xy 418.270944 -181.253892) (xy 418.277802 -181.247034) (xy 418.284638 -181.239632) (xy 418.292348 -181.221034)
			(xy 418.292788 -181.210966) (xy 418.292788 -179.501038) (xy 418.292353 -179.490973) (xy 418.284622 -179.472386)
			(xy 418.277802 -179.46497) (xy 418.254434 -179.441602) (xy 418.247032 -179.434766) (xy 418.228434 -179.427055)
			(xy 418.218366 -179.426616) (xy 416.205416 -179.426616) (xy 416.195352 -179.426178) (xy 416.176768 -179.418444)
			(xy 416.169348 -179.41163) (xy 415.918904 -179.161186) (xy 415.91206 -179.153787) (xy 415.90433 -179.135189)
			(xy 415.903918 -179.125118) (xy 415.903918 -176.9872) (xy 415.904342 -176.97713) (xy 415.912058 -176.958527)
			(xy 415.918904 -176.951132) (xy 415.95802 -176.912016) (xy 415.964862 -176.904617) (xy 415.972578 -176.886018)
			(xy 415.973006 -176.875948) (xy 415.973006 -175.059848) (xy 415.972574 -175.049782) (xy 415.964847 -175.03119)
			(xy 415.95802 -175.02378) (xy 415.704528 -174.770288) (xy 415.69768 -174.76289) (xy 415.689946 -174.744292)
			(xy 415.689542 -174.73422) (xy 415.689542 -172.807376) (xy 415.689971 -172.797309) (xy 415.697696 -172.778715)
			(xy 415.704528 -172.771308) (xy 415.827972 -172.647864) (xy 415.835371 -172.641022) (xy 415.85397 -172.633303)
			(xy 415.86404 -172.632878) (xy 418.234876 -172.632878) (xy 418.24494 -172.63244) (xy 418.263522 -172.624704)
			(xy 418.270944 -172.617892) (xy 418.277802 -172.611034) (xy 418.284638 -172.603632) (xy 418.292348 -172.585034)
			(xy 418.292788 -172.574966) (xy 418.292788 -170.865038) (xy 418.292353 -170.854973) (xy 418.284622 -170.836386)
			(xy 418.277802 -170.82897) (xy 418.254434 -170.805602) (xy 418.247032 -170.798766) (xy 418.228434 -170.791055)
			(xy 418.218366 -170.790616) (xy 416.205416 -170.790616) (xy 416.195352 -170.790178) (xy 416.176768 -170.782444)
			(xy 416.169348 -170.77563) (xy 415.918904 -170.525186) (xy 415.91206 -170.517787) (xy 415.90433 -170.499189)
			(xy 415.903918 -170.489118) (xy 415.903918 -168.3512) (xy 415.904342 -168.34113) (xy 415.912058 -168.322527)
			(xy 415.918904 -168.315132) (xy 415.95802 -168.276016) (xy 415.964862 -168.268617) (xy 415.972578 -168.250018)
			(xy 415.973006 -168.239948) (xy 415.973006 -166.93642) (xy 415.972569 -166.926356) (xy 415.964835 -166.907772)
			(xy 415.95802 -166.900352) (xy 415.704528 -166.64686) (xy 415.697685 -166.639461) (xy 415.68996 -166.620862)
			(xy 415.689542 -166.610792) (xy 415.689542 -164.171376) (xy 415.689971 -164.161309) (xy 415.697696 -164.142715)
			(xy 415.704528 -164.135308) (xy 415.827972 -164.011864) (xy 415.835371 -164.005022) (xy 415.85397 -163.997303)
			(xy 415.86404 -163.996878) (xy 418.234876 -163.996878) (xy 418.24494 -163.99644) (xy 418.263522 -163.988704)
			(xy 418.270944 -163.981892) (xy 418.277802 -163.975034) (xy 418.284638 -163.967632) (xy 418.292348 -163.949034)
			(xy 418.292788 -163.938966) (xy 418.292788 -162.229038) (xy 418.292353 -162.218973) (xy 418.284622 -162.200386)
			(xy 418.277802 -162.19297) (xy 418.254434 -162.169602) (xy 418.247032 -162.162766) (xy 418.228434 -162.155055)
			(xy 418.218366 -162.154616) (xy 416.205416 -162.154616) (xy 416.195352 -162.154178) (xy 416.176768 -162.146444)
			(xy 416.169348 -162.13963) (xy 415.918904 -161.889186) (xy 415.91206 -161.881787) (xy 415.90433 -161.863189)
			(xy 415.903918 -161.853118) (xy 415.903918 -157.868366) (xy 415.8869 -157.851348) (xy 416.18408 -157.554168)
			(xy 418.17544 -157.554168) (xy 418.62502 -157.104588) (xy 418.62502 -155.062428) (xy 418.82314 -154.864308)
			(xy 420.01948 -154.864308) (xy 420.4335 -154.450288) (xy 420.4335 -152.837388) (xy 420.23538 -152.639268)
			(xy 418.42436 -152.639268) (xy 418.21862 -152.433528) (xy 418.21862 -149.045168) (xy 418.72916 -148.534628)
			(xy 427.09084 -148.534628) (xy 427.39056 -148.234908) (xy 427.39056 -146.624548) (xy 426.53712 -145.771108)
			(xy 410.06776 -145.771108) (xy 409.40228 -146.436588) (xy 409.40228 -155.529292) (xy 417.448728 -155.529292)
			(xy 417.448728 -155.469324) (xy 417.456556 -155.409868) (xy 417.472077 -155.351943) (xy 417.495026 -155.296539)
			(xy 417.52501 -155.244605) (xy 417.561516 -155.197029) (xy 417.603921 -155.154624) (xy 417.651497 -155.118118)
			(xy 417.703431 -155.088134) (xy 417.758835 -155.065185) (xy 417.81676 -155.049664) (xy 417.876216 -155.041836)
			(xy 417.936184 -155.041836) (xy 417.99564 -155.049664) (xy 418.053565 -155.065185) (xy 418.108969 -155.088134)
			(xy 418.160903 -155.118118) (xy 418.208479 -155.154624) (xy 418.250884 -155.197029) (xy 418.28739 -155.244605)
			(xy 418.317374 -155.296539) (xy 418.340323 -155.351943) (xy 418.355844 -155.409868) (xy 418.363672 -155.469324)
			(xy 418.364162 -155.499308) (xy 418.363672 -155.529292) (xy 418.355844 -155.588748) (xy 418.340323 -155.646673)
			(xy 418.317374 -155.702077) (xy 418.28739 -155.754011) (xy 418.250884 -155.801587) (xy 418.208479 -155.843992)
			(xy 418.160903 -155.880498) (xy 418.108969 -155.910482) (xy 418.053565 -155.933431) (xy 417.99564 -155.948952)
			(xy 417.936184 -155.95678) (xy 417.876216 -155.95678) (xy 417.81676 -155.948952) (xy 417.758835 -155.933431)
			(xy 417.703431 -155.910482) (xy 417.651497 -155.880498) (xy 417.603921 -155.843992) (xy 417.561516 -155.801587)
			(xy 417.52501 -155.754011) (xy 417.495026 -155.702077) (xy 417.472077 -155.646673) (xy 417.456556 -155.588748)
			(xy 417.448728 -155.529292) (xy 409.40228 -155.529292) (xy 409.40228 -157.841188) (xy 409.18892 -158.054548)
			(xy 408.10561 -158.054548) (xy 408.03957 -158.120588) (xy 408.03957 -158.125922) (xy 408.039824 -158.134304)
			(xy 408.039824 -166.098982) (xy 408.03957 -166.106602) (xy 408.03957 -166.64432) (xy 408.039824 -166.644574)
			(xy 408.039824 -184.367932) (xy 408.04592 -184.374028) (xy 408.04592 -185.633868) (xy 408.2542 -185.842148)
			(xy 415.5186 -185.842148)
		)
		(stroke
			(width 0)
			(type solid)
		)
		(fill yes)
		(layer "B.Cu")
		(net "GND")
	)
	(gr_poly
		(pts
			(xy 169.35958 -352.654108) (xy 169.35958 -349.908368) (xy 168.80078 -349.349568) (xy 168.80078 -345.295728)
			(xy 168.402 -344.896948) (xy 166.86784 -344.896948) (xy 166.31158 -344.340688) (xy 166.31158 -336.403188)
			(xy 166.3954 -336.319368)
			(arc
				(start 170.306492 -336.319368)
				(mid 170.400011 -336.257476)
				(end 170.379644 -336.147156)
			)
			(arc
				(start 170.379644 -336.147156)
				(mid 170.155364 -335.845229)
				(end 170.07586 -335.477612)
			)
			(arc
				(start 170.07586 -335.477612)
				(mid 170.965622 -334.58785)
				(end 171.855384 -335.477612)
			)
			(arc
				(start 171.855384 -335.477612)
				(mid 171.775888 -335.845233)
				(end 171.5516 -336.147156)
			)
			(arc
				(start 171.5516 -336.147156)
				(mid 171.531166 -336.257505)
				(end 171.624752 -336.319368)
			)
			(arc
				(start 176.490376 -336.319368)
				(mid 176.583761 -336.257194)
				(end 176.56302 -336.146902)
			)
			(arc
				(start 176.56302 -336.146902)
				(mid 176.344072 -335.84706)
				(end 176.266602 -335.483962)
			)
			(arc
				(start 176.266602 -335.483962)
				(mid 177.156364 -334.5942)
				(end 178.046126 -335.483962)
			)
			(arc
				(start 178.046126 -335.483962)
				(mid 177.968645 -335.847055)
				(end 177.749708 -336.146902)
			)
			(arc
				(start 177.749708 -336.146902)
				(mid 177.728906 -336.25722)
				(end 177.822352 -336.319368)
			)
			(arc
				(start 182.687976 -336.319368)
				(mid 182.781361 -336.257194)
				(end 182.76062 -336.146902)
			)
			(arc
				(start 182.76062 -336.146902)
				(mid 182.541672 -335.84706)
				(end 182.464202 -335.483962)
			)
			(arc
				(start 182.464202 -335.483962)
				(mid 183.353964 -334.5942)
				(end 184.243726 -335.483962)
			)
			(arc
				(start 184.243726 -335.483962)
				(mid 184.166245 -335.847055)
				(end 183.947308 -336.146902)
			)
			(arc
				(start 183.947308 -336.146902)
				(mid 183.926506 -336.25722)
				(end 184.019952 -336.319368)
			)
			(xy 186.625484 -336.319368)
			(arc
				(start 186.796172 -336.14868)
				(mid 186.815695 -336.144779)
				(end 186.83224 -336.133694)
			)
			(arc
				(start 187.05195 -335.913984)
				(mid 187.063061 -335.89745)
				(end 187.066936 -335.877916)
			)
			(xy 187.066936 -334.076548) (xy 164.53104 -334.076548) (xy 163.08324 -335.524348) (xy 163.08324 -352.362008)
			(xy 163.68014 -352.958908) (xy 169.05478 -352.958908)
		)
		(stroke
			(width 0)
			(type solid)
		)
		(fill yes)
		(layer "B.Cu")
		(net "GND")
	)
	(gr_poly
		(pts
			(xy 52.8828 -177.781204) (xy 52.8828 -174.92218) (xy 51.344068 -174.92218) (xy 50.810922 -175.455326)
			(xy 48.07966 -175.455326) (xy 48.069592 -175.454896) (xy 48.050996 -175.447175) (xy 48.043592 -175.44034)
			(xy 46.827186 -174.223934) (xy 46.820341 -174.216536) (xy 46.812617 -174.197937) (xy 46.8122 -174.187866)
			(xy 46.8122 -169.78503) (xy 46.812636 -169.774965) (xy 46.820368 -169.75638) (xy 46.827186 -169.748962)
			(xy 47.483014 -169.093134) (xy 47.490412 -169.086286) (xy 47.50901 -169.078551) (xy 47.519082 -169.078148)
			(xy 54.51348 -169.078148) (xy 54.682136 -168.909492) (xy 54.682136 -165.659562) (xy 54.496208 -165.473634)
			(xy 51.845972 -165.473634) (xy 51.001422 -166.318184) (xy 51.001422 -167.32123) (xy 51.000994 -167.331298)
			(xy 50.993274 -167.349897) (xy 50.986436 -167.357298) (xy 50.77841 -167.565324) (xy 50.771016 -167.57218)
			(xy 50.752417 -167.579931) (xy 50.742342 -167.58031) (xy 49.22901 -167.58031) (xy 49.218939 -167.579889)
			(xy 49.200331 -167.572178) (xy 49.192942 -167.565324) (xy 48.097186 -166.469568) (xy 48.090335 -166.462172)
			(xy 48.082599 -166.443573) (xy 48.0822 -166.4335) (xy 48.0822 -161.85769) (xy 48.082625 -161.847621)
			(xy 48.090342 -161.829019) (xy 48.097186 -161.821622) (xy 49.192942 -160.725866) (xy 49.485296 -160.433512)
			(xy 54.470808 -160.433512) (xy 54.682136 -160.222184) (xy 54.682136 -157.023562) (xy 54.496208 -156.837634)
			(xy 51.845972 -156.837634) (xy 51.001422 -157.682184) (xy 51.001422 -158.68523) (xy 51.000994 -158.695298)
			(xy 50.993274 -158.713897) (xy 50.986436 -158.721298) (xy 50.77841 -158.929324) (xy 50.771016 -158.93618)
			(xy 50.752417 -158.943931) (xy 50.742342 -158.94431) (xy 49.22901 -158.94431) (xy 49.218939 -158.943889)
			(xy 49.200331 -158.936178) (xy 49.192942 -158.929324) (xy 48.097186 -157.833568) (xy 48.090335 -157.826172)
			(xy 48.082599 -157.807573) (xy 48.0822 -157.7975) (xy 48.0822 -153.22169) (xy 48.082625 -153.211621)
			(xy 48.090342 -153.193019) (xy 48.097186 -153.185622) (xy 49.192942 -152.089866) (xy 49.392332 -151.890476)
			(xy 49.525936 -151.756872) (xy 54.546246 -151.756872) (xy 54.682136 -151.620982) (xy 54.682136 -148.387562)
			(xy 54.496208 -148.201634) (xy 51.845972 -148.201634) (xy 51.001422 -149.046184) (xy 51.001422 -150.04923)
			(xy 51.000994 -150.059298) (xy 50.993274 -150.077897) (xy 50.986436 -150.085298) (xy 50.77841 -150.293324)
			(xy 50.771016 -150.30018) (xy 50.752417 -150.307931) (xy 50.742342 -150.30831) (xy 43.736006 -150.30831)
			(xy 43.71467 -150.329646) (xy 43.707272 -150.336493) (xy 43.688674 -150.344225) (xy 43.678602 -150.344632)
			(xy 39.922196 -150.344632) (xy 39.1922 -151.074628) (xy 39.1922 -161.891218) (xy 43.480228 -161.891218)
			(xy 43.480732 -161.848857) (xy 43.488785 -161.76452) (xy 43.504819 -161.68133) (xy 43.528687 -161.60004)
			(xy 43.560175 -161.521388) (xy 43.598997 -161.446085) (xy 43.6448 -161.374813) (xy 43.697171 -161.308217)
			(xy 43.755636 -161.246902) (xy 43.819664 -161.191421) (xy 43.888676 -161.142278) (xy 43.962046 -161.099918)
			(xy 44.039111 -161.064723) (xy 44.119173 -161.037014) (xy 44.201506 -161.01704) (xy 44.285365 -161.004983)
			(xy 44.36999 -161.000952) (xy 44.454615 -161.004983) (xy 44.538474 -161.01704) (xy 44.620807 -161.037014)
			(xy 44.700869 -161.064723) (xy 44.777934 -161.099918) (xy 44.851304 -161.142278) (xy 44.920316 -161.191421)
			(xy 44.984344 -161.246902) (xy 45.042809 -161.308217) (xy 45.09518 -161.374813) (xy 45.140983 -161.446085)
			(xy 45.179805 -161.521388) (xy 45.211293 -161.60004) (xy 45.235161 -161.68133) (xy 45.251195 -161.76452)
			(xy 45.259248 -161.848857) (xy 45.259752 -161.891218) (xy 45.259557 -161.916549) (xy 45.256636 -161.967126)
			(xy 45.25391 -161.99231) (xy 45.251624 -162.01009) (xy 45.245434 -162.052255) (xy 45.226019 -162.135243)
			(xy 45.198757 -162.215994) (xy 45.163897 -162.293767) (xy 45.121759 -162.36785) (xy 45.072728 -162.437563)
			(xy 45.017256 -162.502268) (xy 44.955849 -162.56137) (xy 44.889071 -162.614329) (xy 44.817534 -162.660658)
			(xy 44.741895 -162.699934) (xy 44.662846 -162.731795) (xy 44.581112 -162.75595) (xy 44.497442 -162.772178)
			(xy 44.412604 -162.780329) (xy 44.327376 -162.780329) (xy 44.242538 -162.772178) (xy 44.158868 -162.75595)
			(xy 44.077134 -162.731795) (xy 43.998085 -162.699934) (xy 43.922446 -162.660658) (xy 43.850909 -162.614329)
			(xy 43.784131 -162.56137) (xy 43.722724 -162.502268) (xy 43.667252 -162.437563) (xy 43.618221 -162.36785)
			(xy 43.576083 -162.293767) (xy 43.541223 -162.215994) (xy 43.513961 -162.135243) (xy 43.494546 -162.052255)
			(xy 43.488356 -162.01009) (xy 43.48607 -161.99231) (xy 43.483352 -161.967125) (xy 43.480429 -161.916548)
			(xy 43.480228 -161.891218) (xy 39.1922 -161.891218) (xy 39.1922 -169.844142) (xy 43.406818 -169.844142)
			(xy 43.406818 -169.759446) (xy 43.414869 -169.675132) (xy 43.430898 -169.591966) (xy 43.454759 -169.510699)
			(xy 43.486238 -169.432069) (xy 43.525049 -169.356788) (xy 43.570839 -169.285536) (xy 43.623195 -169.21896)
			(xy 43.681643 -169.157662) (xy 43.745653 -169.102197) (xy 43.814645 -169.053068) (xy 43.887995 -169.010719)
			(xy 43.965038 -168.975535) (xy 44.045077 -168.947833) (xy 44.127386 -168.927865) (xy 44.211221 -168.915812)
			(xy 44.295822 -168.911782) (xy 44.380423 -168.915812) (xy 44.464258 -168.927865) (xy 44.546567 -168.947833)
			(xy 44.626606 -168.975535) (xy 44.703649 -169.010719) (xy 44.776999 -169.053068) (xy 44.845991 -169.102197)
			(xy 44.910001 -169.157662) (xy 44.968449 -169.21896) (xy 45.020805 -169.285536) (xy 45.066595 -169.356788)
			(xy 45.105406 -169.432069) (xy 45.136885 -169.510699) (xy 45.160746 -169.591966) (xy 45.176775 -169.675132)
			(xy 45.184826 -169.759446) (xy 45.18533 -169.801794) (xy 45.184826 -169.844142) (xy 45.176775 -169.928456)
			(xy 45.160746 -170.011622) (xy 45.136885 -170.092889) (xy 45.105406 -170.171519) (xy 45.066595 -170.2468)
			(xy 45.020805 -170.318052) (xy 44.968449 -170.384628) (xy 44.910001 -170.445926) (xy 44.845991 -170.501391)
			(xy 44.776999 -170.55052) (xy 44.703649 -170.592869) (xy 44.626606 -170.628053) (xy 44.546567 -170.655755)
			(xy 44.464258 -170.675723) (xy 44.380423 -170.687776) (xy 44.295822 -170.691807) (xy 44.211221 -170.687776)
			(xy 44.127386 -170.675723) (xy 44.045077 -170.655755) (xy 43.965038 -170.628053) (xy 43.887995 -170.592869)
			(xy 43.814645 -170.55052) (xy 43.745653 -170.501391) (xy 43.681643 -170.445926) (xy 43.623195 -170.384628)
			(xy 43.570839 -170.318052) (xy 43.525049 -170.2468) (xy 43.486238 -170.171519) (xy 43.454759 -170.092889)
			(xy 43.430898 -170.011622) (xy 43.414869 -169.928456) (xy 43.406818 -169.844142) (xy 39.1922 -169.844142)
			(xy 39.1922 -173.175168) (xy 42.291 -176.273968) (xy 44.052236 -178.035204) (xy 44.111164 -178.035204)
			(xy 52.6288 -178.035204)
		)
		(stroke
			(width 0)
			(type solid)
		)
		(fill yes)
		(layer "B.Cu")
		(net "SW_P12V_PVCCINFAON_CPU1_FLT")
	)
	(gr_poly
		(pts
			(xy 419.90772 -178.253644) (xy 419.90772 -177.250598) (xy 419.908144 -177.240528) (xy 419.915861 -177.221926)
			(xy 419.922706 -177.21453) (xy 420.130732 -177.006504) (xy 420.138132 -176.999662) (xy 420.15673 -176.991939)
			(xy 420.1668 -176.991518) (xy 427.431708 -176.991518) (xy 429.1584 -175.264826) (xy 429.1584 -174.539148)
			(xy 429.1584 -161.849308) (xy 430.3014 -160.706308) (xy 431.3555 -159.652208) (xy 431.3555 -149.863048)
			(xy 430.757076 -149.264624) (xy 418.867844 -149.264624) (xy 418.70122 -149.431248) (xy 418.70122 -152.184608)
			(xy 418.89426 -152.377648) (xy 424.339258 -152.377648) (xy 424.349322 -152.378083) (xy 424.367907 -152.385818)
			(xy 424.375326 -152.392634) (xy 424.939714 -152.957022) (xy 424.946566 -152.964418) (xy 424.954306 -152.983017)
			(xy 424.9547 -152.99309) (xy 424.9547 -157.016196) (xy 426.562266 -157.016196) (xy 426.56277 -156.973835)
			(xy 426.570823 -156.889498) (xy 426.586857 -156.806308) (xy 426.610725 -156.725018) (xy 426.642213 -156.646366)
			(xy 426.681035 -156.571063) (xy 426.726838 -156.499791) (xy 426.779209 -156.433195) (xy 426.837674 -156.37188)
			(xy 426.901702 -156.316399) (xy 426.970714 -156.267256) (xy 427.044084 -156.224896) (xy 427.121149 -156.189701)
			(xy 427.201211 -156.161992) (xy 427.283544 -156.142018) (xy 427.367403 -156.129961) (xy 427.452028 -156.12593)
			(xy 427.536653 -156.129961) (xy 427.620512 -156.142018) (xy 427.702845 -156.161992) (xy 427.782907 -156.189701)
			(xy 427.859972 -156.224896) (xy 427.933342 -156.267256) (xy 428.002354 -156.316399) (xy 428.066382 -156.37188)
			(xy 428.124847 -156.433195) (xy 428.177218 -156.499791) (xy 428.223021 -156.571063) (xy 428.261843 -156.646366)
			(xy 428.293331 -156.725018) (xy 428.317199 -156.806308) (xy 428.333233 -156.889498) (xy 428.341286 -156.973835)
			(xy 428.34179 -157.016196) (xy 428.341294 -157.057152) (xy 428.333773 -157.138719) (xy 428.318787 -157.219249)
			(xy 428.296461 -157.29806) (xy 428.266985 -157.374485) (xy 428.230608 -157.447878) (xy 428.187639 -157.517615)
			(xy 428.138441 -157.583107) (xy 428.083431 -157.643799) (xy 428.023075 -157.699178) (xy 427.990762 -157.724348)
			(xy 427.990254 -157.724348) (xy 427.957093 -157.74897) (xy 427.886987 -157.79265) (xy 427.813133 -157.829641)
			(xy 427.736167 -157.859624) (xy 427.656752 -157.88234) (xy 427.575572 -157.897593) (xy 427.493328 -157.905253)
			(xy 427.410728 -157.905253) (xy 427.328484 -157.897593) (xy 427.247304 -157.88234) (xy 427.167889 -157.859624)
			(xy 427.090923 -157.829641) (xy 427.017069 -157.79265) (xy 426.946963 -157.74897) (xy 426.913802 -157.724348)
			(xy 426.913294 -157.724348) (xy 426.880976 -157.699184) (xy 426.820621 -157.643803) (xy 426.765612 -157.583108)
			(xy 426.716414 -157.517615) (xy 426.673444 -157.447877) (xy 426.637065 -157.374485) (xy 426.607585 -157.29806)
			(xy 426.585254 -157.219249) (xy 426.570262 -157.13872) (xy 426.562733 -157.057153) (xy 426.562266 -157.016196)
			(xy 424.9547 -157.016196) (xy 424.9547 -157.348428) (xy 424.1927 -158.110428) (xy 416.422078 -158.110428)
			(xy 416.401758 -158.130748) (xy 416.380676 -158.130748) (xy 416.227006 -158.284418) (xy 416.227006 -161.640266)
			(xy 416.412934 -161.826194) (xy 419.06317 -161.826194) (xy 419.90772 -160.981644) (xy 419.90772 -159.978598)
			(xy 419.908144 -159.968528) (xy 419.915861 -159.949926) (xy 419.922706 -159.94253) (xy 420.130732 -159.734504)
			(xy 420.138132 -159.727662) (xy 420.15673 -159.719939) (xy 420.1668 -159.719518) (xy 421.569388 -159.719518)
			(xy 421.579459 -159.719939) (xy 421.598065 -159.727653) (xy 421.605456 -159.734504) (xy 422.359074 -160.488122)
			(xy 422.36592 -160.49552) (xy 422.37365 -160.514119) (xy 422.37406 -160.52419) (xy 422.37406 -165.716966)
			(xy 422.373624 -165.72703) (xy 422.365888 -165.745613) (xy 422.359074 -165.753034) (xy 421.538146 -166.573962)
			(xy 421.530746 -166.580804) (xy 421.512148 -166.588525) (xy 421.502078 -166.588948) (xy 420.517574 -166.588948)
			(xy 420.265352 -166.84117) (xy 416.306254 -166.84117) (xy 416.227006 -166.920418) (xy 416.227006 -170.276266)
			(xy 416.412934 -170.462194) (xy 419.06317 -170.462194) (xy 419.90772 -169.617644) (xy 419.90772 -168.614598)
			(xy 419.908144 -168.604528) (xy 419.915861 -168.585926) (xy 419.922706 -168.57853) (xy 420.130732 -168.370504)
			(xy 420.138132 -168.363662) (xy 420.15673 -168.355939) (xy 420.1668 -168.355518) (xy 421.891968 -168.355518)
			(xy 421.902032 -168.355954) (xy 421.920617 -168.363688) (xy 421.928036 -168.370504) (xy 422.359074 -168.801542)
			(xy 422.365917 -168.808941) (xy 422.37364 -168.82754) (xy 422.37406 -168.83761) (xy 422.37406 -169.996034)
			(xy 426.563024 -169.996034) (xy 426.563024 -169.911338) (xy 426.571075 -169.827024) (xy 426.587104 -169.743858)
			(xy 426.610965 -169.662591) (xy 426.642444 -169.583961) (xy 426.681255 -169.50868) (xy 426.727045 -169.437428)
			(xy 426.779401 -169.370852) (xy 426.837849 -169.309554) (xy 426.901859 -169.254089) (xy 426.970851 -169.20496)
			(xy 427.044201 -169.162611) (xy 427.121244 -169.127427) (xy 427.201283 -169.099725) (xy 427.283592 -169.079757)
			(xy 427.367427 -169.067704) (xy 427.452028 -169.063674) (xy 427.536629 -169.067704) (xy 427.620464 -169.079757)
			(xy 427.702773 -169.099725) (xy 427.782812 -169.127427) (xy 427.859855 -169.162611) (xy 427.933205 -169.20496)
			(xy 428.002197 -169.254089) (xy 428.066207 -169.309554) (xy 428.124655 -169.370852) (xy 428.177011 -169.437428)
			(xy 428.222801 -169.50868) (xy 428.261612 -169.583961) (xy 428.293091 -169.662591) (xy 428.316952 -169.743858)
			(xy 428.332981 -169.827024) (xy 428.341032 -169.911338) (xy 428.341536 -169.953686) (xy 428.341032 -169.996034)
			(xy 428.332981 -170.080348) (xy 428.316952 -170.163514) (xy 428.293091 -170.244781) (xy 428.261612 -170.323411)
			(xy 428.222801 -170.398692) (xy 428.177011 -170.469944) (xy 428.124655 -170.53652) (xy 428.066207 -170.597818)
			(xy 428.002197 -170.653283) (xy 427.933205 -170.702412) (xy 427.859855 -170.744761) (xy 427.782812 -170.779945)
			(xy 427.702773 -170.807647) (xy 427.620464 -170.827615) (xy 427.536629 -170.839668) (xy 427.452028 -170.843699)
			(xy 427.367427 -170.839668) (xy 427.283592 -170.827615) (xy 427.201283 -170.807647) (xy 427.121244 -170.779945)
			(xy 427.044201 -170.744761) (xy 426.970851 -170.702412) (xy 426.901859 -170.653283) (xy 426.837849 -170.597818)
			(xy 426.779401 -170.53652) (xy 426.727045 -170.469944) (xy 426.681255 -170.398692) (xy 426.642444 -170.323411)
			(xy 426.610965 -170.244781) (xy 426.587104 -170.163514) (xy 426.571075 -170.080348) (xy 426.563024 -169.996034)
			(xy 422.37406 -169.996034) (xy 422.37406 -174.182786) (xy 422.37362 -174.192848) (xy 422.365879 -174.211426)
			(xy 422.359074 -174.218854) (xy 421.367966 -175.209962) (xy 421.360568 -175.216807) (xy 421.341969 -175.224536)
			(xy 421.331898 -175.224948) (xy 420.081964 -175.224948) (xy 419.936422 -175.37049) (xy 419.786308 -175.520604)
			(xy 416.487356 -175.520604) (xy 416.227006 -175.780954) (xy 416.227006 -178.912266) (xy 416.412934 -179.098194)
			(xy 419.06317 -179.098194)
		)
		(stroke
			(width 0)
			(type solid)
		)
		(fill yes)
		(layer "B.Cu")
		(net "SW_P12V_PVCCINFAON_CPU0_FLT")
	)
	(gr_poly
		(pts
			(xy 317.30696 -366.022128) (xy 317.30696 -341.630508) (xy 316.836806 -341.160354) (xy 303.047654 -341.160354)
			(xy 302.992028 -341.104728) (xy 302.206914 -341.104728) (xy 302.202088 -341.109554) (xy 278.175974 -341.109554)
			(xy 277.84552 -341.440008) (xy 277.84552 -361.231688) (xy 278.18842 -361.574588) (xy 283.7434 -361.574588)
			(xy 284.55112 -362.382308) (xy 285.18866 -362.382308) (xy 286.10306 -361.467908) (xy 286.10306 -355.242368)
			(xy 284.957774 -354.097082) (xy 283.509974 -354.097082) (xy 283.12364 -353.710748) (xy 283.12364 -345.773248)
			(xy 283.50718 -345.389708)
			(arc
				(start 286.501332 -345.389708)
				(mid 286.592 -345.333954)
				(end 286.58312 -345.22791)
			)
			(arc
				(start 286.58312 -345.22791)
				(mid 286.454357 -344.97811)
				(end 286.409892 -344.700606)
			)
			(arc
				(start 286.409892 -344.700352)
				(mid 287.2994 -343.810844)
				(end 288.188908 -344.700352)
			)
			(arc
				(start 288.188908 -344.700606)
				(mid 288.144506 -344.978131)
				(end 288.01568 -345.22791)
			)
			(arc
				(start 288.01568 -345.22791)
				(mid 288.006841 -345.333932)
				(end 288.097468 -345.389708)
			)
			(arc
				(start 292.698932 -345.389708)
				(mid 292.7896 -345.333954)
				(end 292.78072 -345.22791)
			)
			(arc
				(start 292.78072 -345.22791)
				(mid 292.651957 -344.97811)
				(end 292.607492 -344.700606)
			)
			(arc
				(start 292.607492 -344.700352)
				(mid 293.497 -343.810844)
				(end 294.386508 -344.700352)
			)
			(arc
				(start 294.386508 -344.700606)
				(mid 294.342106 -344.978131)
				(end 294.21328 -345.22791)
			)
			(arc
				(start 294.21328 -345.22791)
				(mid 294.204441 -345.333932)
				(end 294.295068 -345.389708)
			)
			(arc
				(start 298.896532 -345.389708)
				(mid 298.9872 -345.333954)
				(end 298.97832 -345.22791)
			)
			(arc
				(start 298.97832 -345.22791)
				(mid 298.849557 -344.97811)
				(end 298.805092 -344.700606)
			)
			(arc
				(start 298.805092 -344.700352)
				(mid 299.6946 -343.810844)
				(end 300.584108 -344.700352)
			)
			(arc
				(start 300.584108 -344.700606)
				(mid 300.539706 -344.978131)
				(end 300.41088 -345.22791)
			)
			(arc
				(start 300.41088 -345.22791)
				(mid 300.402041 -345.333932)
				(end 300.492668 -345.389708)
			)
			(xy 304.97272 -345.389708) (xy 305.25974 -345.676728) (xy 305.25974 -353.593908) (xy 304.2793 -354.574348)
			(xy 304.2793 -355.509068) (xy 304.79238 -356.022148) (xy 304.79238 -364.45698)
			(arc
				(start 305.356768 -364.45698)
				(mid 305.44693 -364.494326)
				(end 305.484276 -364.584488)
			)
			(xy 305.484276 -365.779304) (xy 306.578 -366.873028) (xy 316.45606 -366.873028)
		)
		(stroke
			(width 0)
			(type solid)
		)
		(fill yes)
		(layer "B.Cu")
		(net "GND")
	)
	(gr_poly
		(pts
			(xy 75.946 -170.043348) (xy 75.946 -168.906444) (xy 75.95108 -168.884346) (xy 75.95108 -163.167568)
			(xy 75.08494 -162.301428) (xy 75.050396 -162.32378) (xy 75.027134 -162.338272) (xy 74.977336 -162.36116)
			(xy 74.924776 -162.376688) (xy 74.870535 -162.384535) (xy 74.843132 -162.384994) (xy 74.815878 -162.384533)
			(xy 74.761924 -162.376779) (xy 74.709623 -162.361426) (xy 74.66004 -162.338785) (xy 74.614184 -162.309318)
			(xy 74.572989 -162.273624) (xy 74.537293 -162.23243) (xy 74.507823 -162.186576) (xy 74.48518 -162.136993)
			(xy 74.469824 -162.084693) (xy 74.462068 -162.03074) (xy 74.461624 -162.003486) (xy 74.462099 -161.976084)
			(xy 74.469944 -161.921844) (xy 74.485469 -161.869286) (xy 74.508356 -161.81949) (xy 74.522838 -161.796222)
			(xy 74.54519 -161.761678) (xy 73.61936 -160.835848) (xy 72.691752 -160.835848) (xy 71.32066 -162.20694)
			(xy 68.97624 -162.20694) (xy 67.80276 -161.03346) (xy 63.270638 -161.03346) (xy 63.123572 -161.180526)
			(xy 63.123572 -164.634926) (xy 69.007995 -164.634926) (xy 69.012017 -164.549206) (xy 69.024048 -164.464238)
			(xy 69.043984 -164.380771) (xy 69.071647 -164.299537) (xy 69.106796 -164.221251) (xy 69.149122 -164.1466)
			(xy 69.198251 -164.076241) (xy 69.253754 -164.010791) (xy 69.315141 -163.950827) (xy 69.381874 -163.896874)
			(xy 69.453366 -163.849407) (xy 69.528988 -163.808843) (xy 69.608077 -163.775539) (xy 69.689937 -163.749787)
			(xy 69.773848 -163.731814) (xy 69.859074 -163.721778) (xy 69.944866 -163.719766) (xy 70.030468 -163.725797)
			(xy 70.11513 -163.739817) (xy 70.198107 -163.761703) (xy 70.27867 -163.791264) (xy 70.35611 -163.828238)
			(xy 70.429749 -163.872302) (xy 70.498937 -163.923068) (xy 70.563068 -163.980089) (xy 70.621577 -164.042865)
			(xy 70.67395 -164.110845) (xy 70.719728 -164.18343) (xy 70.758508 -164.259982) (xy 70.789949 -164.33983)
			(xy 70.813775 -164.422271) (xy 70.829776 -164.506581) (xy 70.837811 -164.592019) (xy 70.838314 -164.634926)
			(xy 70.837811 -164.677833) (xy 70.829776 -164.763271) (xy 70.813775 -164.847581) (xy 70.789949 -164.930022)
			(xy 70.758508 -165.00987) (xy 70.719728 -165.086422) (xy 70.67395 -165.159007) (xy 70.621577 -165.226987)
			(xy 70.563068 -165.289763) (xy 70.498937 -165.346784) (xy 70.429749 -165.39755) (xy 70.35611 -165.441614)
			(xy 70.27867 -165.478588) (xy 70.198107 -165.508149) (xy 70.11513 -165.530035) (xy 70.030468 -165.544055)
			(xy 69.944866 -165.550086) (xy 69.859074 -165.548074) (xy 69.773848 -165.538038) (xy 69.689937 -165.520065)
			(xy 69.608077 -165.494313) (xy 69.528988 -165.461009) (xy 69.453366 -165.420445) (xy 69.381874 -165.372978)
			(xy 69.315141 -165.319025) (xy 69.253754 -165.259061) (xy 69.198251 -165.193611) (xy 69.149122 -165.123252)
			(xy 69.106796 -165.048601) (xy 69.071647 -164.970315) (xy 69.043984 -164.889081) (xy 69.024048 -164.805614)
			(xy 69.012017 -164.720646) (xy 69.007995 -164.634926) (xy 63.123572 -164.634926) (xy 63.123572 -167.422322)
			(xy 69.034152 -167.422322) (xy 69.034152 -165.847522) (xy 69.034562 -165.834165) (xy 69.041472 -165.808361)
			(xy 69.054825 -165.785226) (xy 69.073713 -165.766335) (xy 69.096847 -165.752978) (xy 69.122649 -165.746064)
			(xy 69.136006 -165.745668) (xy 70.710806 -165.745668) (xy 70.724165 -165.746037) (xy 70.749973 -165.752955)
			(xy 70.77311 -165.766317) (xy 70.792 -165.785212) (xy 70.805356 -165.808353) (xy 70.812266 -165.834163)
			(xy 70.81266 -165.847522) (xy 70.81266 -167.422322) (xy 70.812238 -167.435674) (xy 70.805321 -167.461468)
			(xy 70.791966 -167.484594) (xy 70.773081 -167.503476) (xy 70.749954 -167.516828) (xy 70.724159 -167.52374)
			(xy 70.710806 -167.524176) (xy 69.136006 -167.524176) (xy 69.122656 -167.523713) (xy 69.096866 -167.516805)
			(xy 69.073741 -167.503458) (xy 69.054859 -167.484581) (xy 69.041506 -167.46146) (xy 69.03459 -167.435672)
			(xy 69.034152 -167.422322) (xy 63.123572 -167.422322) (xy 63.123572 -169.185844) (xy 63.284608 -169.34688)
			(xy 64.9986 -169.34688) (xy 67.581272 -171.929552) (xy 67.592249 -171.939733) (xy 67.618667 -171.95379)
			(xy 67.648026 -171.959584) (xy 67.677804 -171.956616) (xy 67.705442 -171.945143) (xy 67.728567 -171.926149)
			(xy 67.745191 -171.901266) (xy 67.753887 -171.872632) (xy 67.7545 -171.85767) (xy 67.7545 -170.98264)
			(xy 67.754893 -170.969246) (xy 67.761818 -170.94337) (xy 67.775206 -170.920169) (xy 67.794144 -170.901225)
			(xy 67.817341 -170.88783) (xy 67.843215 -170.880897) (xy 67.856608 -170.880532) (xy 69.431408 -170.880532)
			(xy 69.444796 -170.880931) (xy 69.470658 -170.887864) (xy 69.493844 -170.901256) (xy 69.512773 -170.920194)
			(xy 69.526154 -170.943386) (xy 69.533076 -170.969252) (xy 69.533516 -170.98264) (xy 69.533516 -171.77004)
			(xy 69.728593 -171.77004) (xy 69.732615 -171.68432) (xy 69.744646 -171.599352) (xy 69.764582 -171.515885)
			(xy 69.792245 -171.434651) (xy 69.827394 -171.356365) (xy 69.86972 -171.281714) (xy 69.918849 -171.211355)
			(xy 69.974352 -171.145905) (xy 70.035739 -171.085941) (xy 70.102472 -171.031988) (xy 70.173964 -170.984521)
			(xy 70.249586 -170.943957) (xy 70.328675 -170.910653) (xy 70.410535 -170.884901) (xy 70.494446 -170.866928)
			(xy 70.579672 -170.856892) (xy 70.665464 -170.85488) (xy 70.751066 -170.860911) (xy 70.835728 -170.874931)
			(xy 70.918705 -170.896817) (xy 70.999268 -170.926378) (xy 71.076708 -170.963352) (xy 71.150347 -171.007416)
			(xy 71.219535 -171.058182) (xy 71.283666 -171.115203) (xy 71.342175 -171.177979) (xy 71.394548 -171.245959)
			(xy 71.440326 -171.318544) (xy 71.479106 -171.395096) (xy 71.510547 -171.474944) (xy 71.534373 -171.557385)
			(xy 71.550374 -171.641695) (xy 71.558409 -171.727133) (xy 71.558912 -171.77004) (xy 71.558409 -171.812947)
			(xy 71.550374 -171.898385) (xy 71.534373 -171.982695) (xy 71.510547 -172.065136) (xy 71.479106 -172.144984)
			(xy 71.440326 -172.221536) (xy 71.394548 -172.294121) (xy 71.342175 -172.362101) (xy 71.283666 -172.424877)
			(xy 71.219535 -172.481898) (xy 71.150347 -172.532664) (xy 71.076708 -172.576728) (xy 70.999268 -172.613702)
			(xy 70.918705 -172.643263) (xy 70.835728 -172.665149) (xy 70.751066 -172.679169) (xy 70.665464 -172.6852)
			(xy 70.579672 -172.683188) (xy 70.494446 -172.673152) (xy 70.410535 -172.655179) (xy 70.328675 -172.629427)
			(xy 70.249586 -172.596123) (xy 70.173964 -172.555559) (xy 70.102472 -172.508092) (xy 70.035739 -172.454139)
			(xy 69.974352 -172.394175) (xy 69.918849 -172.328725) (xy 69.86972 -172.258366) (xy 69.827394 -172.183715)
			(xy 69.792245 -172.105429) (xy 69.764582 -172.024195) (xy 69.744646 -171.940728) (xy 69.732615 -171.85576)
			(xy 69.728593 -171.77004) (xy 69.533516 -171.77004) (xy 69.533516 -172.55744) (xy 69.533074 -172.570822)
			(xy 69.526139 -172.596673) (xy 69.512751 -172.619848) (xy 69.493823 -172.638771) (xy 69.470643 -172.652151)
			(xy 69.44479 -172.659079) (xy 69.431408 -172.659548) (xy 67.82689 -172.659548) (xy 67.82689 -173.34611)
			(xy 68.23202 -173.75124) (xy 72.238108 -173.75124)
		)
		(stroke
			(width 0)
			(type solid)
		)
		(fill yes)
		(layer "B.Cu")
		(net "PVCCD_HV_CPU1")
	)
	(gr_poly
		(pts
			(xy 217.68816 -360.76382) (xy 217.687662 -360.674399) (xy 217.679695 -360.495735) (xy 217.663777 -360.317602)
			(xy 217.63994 -360.140356) (xy 217.60823 -359.964348) (xy 217.568712 -359.789926) (xy 217.521463 -359.617439)
			(xy 217.466576 -359.447227) (xy 217.404162 -359.27963) (xy 217.334344 -359.114979) (xy 217.257261 -358.953602)
			(xy 217.173065 -358.795818) (xy 217.081925 -358.641942) (xy 216.984019 -358.492279) (xy 216.879545 -358.347126)
			(xy 216.768707 -358.206771) (xy 216.651728 -358.071493) (xy 216.528838 -357.94156) (xy 216.400282 -357.81723)
			(xy 216.266315 -357.698751) (xy 216.127204 -357.586357) (xy 215.983223 -357.480271) (xy 215.83466 -357.380705)
			(xy 215.681809 -357.287856) (xy 215.524974 -357.201907) (xy 215.364465 -357.123031) (xy 215.200602 -357.051383)
			(xy 215.03371 -356.987106) (xy 214.864121 -356.930327) (xy 214.69217 -356.881159) (xy 214.5182 -356.8397)
			(xy 214.342556 -356.806032) (xy 214.165586 -356.780221) (xy 213.987642 -356.76232) (xy 213.809078 -356.752363)
			(xy 213.630247 -356.750371) (xy 213.451505 -356.756347) (xy 213.273206 -356.77028) (xy 213.095705 -356.792141)
			(xy 212.919355 -356.821887) (xy 212.744504 -356.85946) (xy 212.571501 -356.904785) (xy 212.400688 -356.957772)
			(xy 212.232406 -357.018315) (xy 212.066987 -357.086294) (xy 211.904761 -357.161575) (xy 211.74605 -357.244008)
			(xy 211.591168 -357.333429) (xy 211.440424 -357.429661) (xy 211.294116 -357.532512) (xy 211.152535 -357.641779)
			(xy 211.015961 -357.757244) (xy 210.884668 -357.878679) (xy 210.758914 -358.005842) (xy 210.638949 -358.13848)
			(xy 210.525012 -358.276331) (xy 210.417329 -358.419121) (xy 210.316114 -358.566565) (xy 210.221568 -358.718373)
			(xy 210.133878 -358.874241) (xy 210.053218 -359.033861) (xy 209.979749 -359.196915) (xy 209.913617 -359.363081)
			(xy 209.854952 -359.532027) (xy 209.803872 -359.703419) (xy 209.760477 -359.876917) (xy 209.724855 -360.052175)
			(xy 209.697074 -360.228846) (xy 209.677192 -360.40658) (xy 209.665246 -360.585022) (xy 209.661262 -360.76382)
			(xy 211.159857 -360.76382) (xy 211.163885 -360.621528) (xy 211.175957 -360.479692) (xy 211.196034 -360.338765)
			(xy 211.224052 -360.199201) (xy 211.259921 -360.061445) (xy 211.303526 -359.925939) (xy 211.354727 -359.793117)
			(xy 211.413361 -359.663404) (xy 211.479239 -359.537217) (xy 211.552151 -359.414958) (xy 211.631863 -359.297021)
			(xy 211.71812 -359.183782) (xy 211.810644 -359.075604) (xy 211.909141 -358.972834) (xy 212.013295 -358.875801)
			(xy 212.122771 -358.784817) (xy 212.237219 -358.700171) (xy 212.356273 -358.622136) (xy 212.479551 -358.550962)
			(xy 212.606658 -358.486875) (xy 212.737187 -358.430083) (xy 212.870721 -358.380766) (xy 213.00683 -358.339083)
			(xy 213.14508 -358.305167) (xy 213.285027 -358.279127) (xy 213.426223 -358.261046) (xy 213.568216 -358.250983)
			(xy 213.710551 -358.248968) (xy 213.852772 -358.25501) (xy 213.994423 -358.269088) (xy 214.135051 -358.291157)
			(xy 214.274205 -358.321147) (xy 214.41144 -358.358962) (xy 214.546315 -358.40448) (xy 214.678399 -358.457556)
			(xy 214.807269 -358.518019) (xy 214.932512 -358.585676) (xy 215.053726 -358.660311) (xy 215.170524 -358.741684)
			(xy 215.282531 -358.829534) (xy 215.389389 -358.923581) (xy 215.490754 -359.023522) (xy 215.586303 -359.129038)
			(xy 215.67573 -359.239791) (xy 215.758748 -359.355425) (xy 215.83509 -359.475572) (xy 215.904513 -359.599844)
			(xy 215.966794 -359.727846) (xy 216.021734 -359.859166) (xy 216.069156 -359.993383) (xy 216.108909 -360.130069)
			(xy 216.140865 -360.268785) (xy 216.164922 -360.409086) (xy 216.181003 -360.550524) (xy 216.189056 -360.692645)
			(xy 216.18956 -360.76382) (xy 216.189056 -360.834995) (xy 216.181003 -360.977116) (xy 216.164922 -361.118554)
			(xy 216.140865 -361.258855) (xy 216.108909 -361.397571) (xy 216.069156 -361.534257) (xy 216.021734 -361.668474)
			(xy 215.966794 -361.799794) (xy 215.904513 -361.927796) (xy 215.83509 -362.052068) (xy 215.758748 -362.172215)
			(xy 215.67573 -362.287849) (xy 215.586303 -362.398602) (xy 215.490754 -362.504118) (xy 215.389389 -362.604059)
			(xy 215.282531 -362.698106) (xy 215.170524 -362.785956) (xy 215.053726 -362.867329) (xy 214.932512 -362.941964)
			(xy 214.807269 -363.009621) (xy 214.678399 -363.070084) (xy 214.546315 -363.12316) (xy 214.41144 -363.168678)
			(xy 214.274205 -363.206493) (xy 214.135051 -363.236483) (xy 213.994423 -363.258552) (xy 213.852772 -363.27263)
			(xy 213.710551 -363.278672) (xy 213.568216 -363.276657) (xy 213.426223 -363.266594) (xy 213.285027 -363.248513)
			(xy 213.14508 -363.222473) (xy 213.00683 -363.188557) (xy 212.870721 -363.146874) (xy 212.737187 -363.097557)
			(xy 212.606658 -363.040765) (xy 212.479551 -362.976678) (xy 212.356273 -362.905504) (xy 212.237219 -362.827469)
			(xy 212.122771 -362.742823) (xy 212.013295 -362.651839) (xy 211.909141 -362.554806) (xy 211.810644 -362.452036)
			(xy 211.71812 -362.343858) (xy 211.631863 -362.230619) (xy 211.552151 -362.112682) (xy 211.479239 -361.990423)
			(xy 211.413361 -361.864236) (xy 211.354727 -361.734523) (xy 211.303526 -361.601701) (xy 211.259921 -361.466195)
			(xy 211.224052 -361.328439) (xy 211.196034 -361.188875) (xy 211.175957 -361.047948) (xy 211.163885 -360.906112)
			(xy 211.159857 -360.76382) (xy 209.661262 -360.76382) (xy 209.665246 -360.942618) (xy 209.677192 -361.12106)
			(xy 209.697074 -361.298794) (xy 209.724855 -361.475465) (xy 209.760477 -361.650723) (xy 209.803872 -361.824221)
			(xy 209.854952 -361.995613) (xy 209.913617 -362.164559) (xy 209.979749 -362.330725) (xy 210.053218 -362.493779)
			(xy 210.133878 -362.653399) (xy 210.221568 -362.809267) (xy 210.316114 -362.961075) (xy 210.417329 -363.108519)
			(xy 210.525012 -363.251309) (xy 210.638949 -363.38916) (xy 210.758914 -363.521798) (xy 210.884668 -363.648961)
			(xy 211.015961 -363.770396) (xy 211.152535 -363.885861) (xy 211.294116 -363.995128) (xy 211.440424 -364.097979)
			(xy 211.591168 -364.194211) (xy 211.74605 -364.283632) (xy 211.904761 -364.366065) (xy 212.066987 -364.441346)
			(xy 212.232406 -364.509325) (xy 212.400688 -364.569868) (xy 212.571501 -364.622855) (xy 212.744504 -364.66818)
			(xy 212.919355 -364.705753) (xy 213.095705 -364.735499) (xy 213.273206 -364.75736) (xy 213.451505 -364.771293)
			(xy 213.630247 -364.777269) (xy 213.809078 -364.775277) (xy 213.987642 -364.76532) (xy 214.165586 -364.747419)
			(xy 214.342556 -364.721608) (xy 214.5182 -364.68794) (xy 214.69217 -364.646481) (xy 214.864121 -364.597313)
			(xy 215.03371 -364.540534) (xy 215.200602 -364.476257) (xy 215.364465 -364.404609) (xy 215.524974 -364.325733)
			(xy 215.681809 -364.239784) (xy 215.83466 -364.146935) (xy 215.983223 -364.047369) (xy 216.127204 -363.941283)
			(xy 216.266315 -363.828889) (xy 216.400282 -363.71041) (xy 216.528838 -363.58608) (xy 216.651728 -363.456147)
			(xy 216.768707 -363.320869) (xy 216.879545 -363.180514) (xy 216.984019 -363.035361) (xy 217.081925 -362.885698)
			(xy 217.173065 -362.731822) (xy 217.257261 -362.574038) (xy 217.334344 -362.412661) (xy 217.404162 -362.24801)
			(xy 217.466576 -362.080413) (xy 217.521463 -361.910201) (xy 217.568712 -361.737714) (xy 217.60823 -361.563292)
			(xy 217.63994 -361.387284) (xy 217.663777 -361.210038) (xy 217.679695 -361.031905) (xy 217.687662 -360.853241)
		)
		(stroke
			(width 0)
			(type solid)
		)
		(fill yes)
		(layer "B.Cu")
		(net "GND")
	)
	(gr_poly
		(pts
			(xy 262.13816 -360.76382) (xy 262.137662 -360.674399) (xy 262.129695 -360.495735) (xy 262.113777 -360.317602)
			(xy 262.08994 -360.140356) (xy 262.05823 -359.964348) (xy 262.018712 -359.789926) (xy 261.971463 -359.617439)
			(xy 261.916576 -359.447227) (xy 261.854162 -359.27963) (xy 261.784344 -359.114979) (xy 261.707261 -358.953602)
			(xy 261.623065 -358.795818) (xy 261.531925 -358.641942) (xy 261.434019 -358.492279) (xy 261.329545 -358.347126)
			(xy 261.218707 -358.206771) (xy 261.101728 -358.071493) (xy 260.978838 -357.94156) (xy 260.850282 -357.81723)
			(xy 260.716315 -357.698751) (xy 260.577204 -357.586357) (xy 260.433223 -357.480271) (xy 260.28466 -357.380705)
			(xy 260.131809 -357.287856) (xy 259.974974 -357.201907) (xy 259.814465 -357.123031) (xy 259.650602 -357.051383)
			(xy 259.48371 -356.987106) (xy 259.314121 -356.930327) (xy 259.14217 -356.881159) (xy 258.9682 -356.8397)
			(xy 258.792556 -356.806032) (xy 258.615586 -356.780221) (xy 258.437642 -356.76232) (xy 258.259078 -356.752363)
			(xy 258.080247 -356.750371) (xy 257.901505 -356.756347) (xy 257.723206 -356.77028) (xy 257.545705 -356.792141)
			(xy 257.369355 -356.821887) (xy 257.194504 -356.85946) (xy 257.021501 -356.904785) (xy 256.850688 -356.957772)
			(xy 256.682406 -357.018315) (xy 256.516987 -357.086294) (xy 256.354761 -357.161575) (xy 256.19605 -357.244008)
			(xy 256.041168 -357.333429) (xy 255.890424 -357.429661) (xy 255.744116 -357.532512) (xy 255.602535 -357.641779)
			(xy 255.465961 -357.757244) (xy 255.334668 -357.878679) (xy 255.208914 -358.005842) (xy 255.088949 -358.13848)
			(xy 254.975012 -358.276331) (xy 254.867329 -358.419121) (xy 254.766114 -358.566565) (xy 254.671568 -358.718373)
			(xy 254.583878 -358.874241) (xy 254.503218 -359.033861) (xy 254.429749 -359.196915) (xy 254.363617 -359.363081)
			(xy 254.304952 -359.532027) (xy 254.253872 -359.703419) (xy 254.210477 -359.876917) (xy 254.174855 -360.052175)
			(xy 254.147074 -360.228846) (xy 254.127192 -360.40658) (xy 254.115246 -360.585022) (xy 254.111262 -360.76382)
			(xy 255.609857 -360.76382) (xy 255.613885 -360.621528) (xy 255.625957 -360.479692) (xy 255.646034 -360.338765)
			(xy 255.674052 -360.199201) (xy 255.709921 -360.061445) (xy 255.753526 -359.925939) (xy 255.804727 -359.793117)
			(xy 255.863361 -359.663404) (xy 255.929239 -359.537217) (xy 256.002151 -359.414958) (xy 256.081863 -359.297021)
			(xy 256.16812 -359.183782) (xy 256.260644 -359.075604) (xy 256.359141 -358.972834) (xy 256.463295 -358.875801)
			(xy 256.572771 -358.784817) (xy 256.687219 -358.700171) (xy 256.806273 -358.622136) (xy 256.929551 -358.550962)
			(xy 257.056658 -358.486875) (xy 257.187187 -358.430083) (xy 257.320721 -358.380766) (xy 257.45683 -358.339083)
			(xy 257.59508 -358.305167) (xy 257.735027 -358.279127) (xy 257.876223 -358.261046) (xy 258.018216 -358.250983)
			(xy 258.160551 -358.248968) (xy 258.302772 -358.25501) (xy 258.444423 -358.269088) (xy 258.585051 -358.291157)
			(xy 258.724205 -358.321147) (xy 258.86144 -358.358962) (xy 258.996315 -358.40448) (xy 259.128399 -358.457556)
			(xy 259.257269 -358.518019) (xy 259.382512 -358.585676) (xy 259.503726 -358.660311) (xy 259.620524 -358.741684)
			(xy 259.732531 -358.829534) (xy 259.839389 -358.923581) (xy 259.940754 -359.023522) (xy 260.036303 -359.129038)
			(xy 260.12573 -359.239791) (xy 260.208748 -359.355425) (xy 260.28509 -359.475572) (xy 260.354513 -359.599844)
			(xy 260.416794 -359.727846) (xy 260.471734 -359.859166) (xy 260.519156 -359.993383) (xy 260.558909 -360.130069)
			(xy 260.590865 -360.268785) (xy 260.614922 -360.409086) (xy 260.631003 -360.550524) (xy 260.639056 -360.692645)
			(xy 260.63956 -360.76382) (xy 260.639056 -360.834995) (xy 260.631003 -360.977116) (xy 260.614922 -361.118554)
			(xy 260.590865 -361.258855) (xy 260.558909 -361.397571) (xy 260.519156 -361.534257) (xy 260.471734 -361.668474)
			(xy 260.416794 -361.799794) (xy 260.354513 -361.927796) (xy 260.28509 -362.052068) (xy 260.208748 -362.172215)
			(xy 260.12573 -362.287849) (xy 260.036303 -362.398602) (xy 259.940754 -362.504118) (xy 259.839389 -362.604059)
			(xy 259.732531 -362.698106) (xy 259.620524 -362.785956) (xy 259.503726 -362.867329) (xy 259.382512 -362.941964)
			(xy 259.257269 -363.009621) (xy 259.128399 -363.070084) (xy 258.996315 -363.12316) (xy 258.86144 -363.168678)
			(xy 258.724205 -363.206493) (xy 258.585051 -363.236483) (xy 258.444423 -363.258552) (xy 258.302772 -363.27263)
			(xy 258.160551 -363.278672) (xy 258.018216 -363.276657) (xy 257.876223 -363.266594) (xy 257.735027 -363.248513)
			(xy 257.59508 -363.222473) (xy 257.45683 -363.188557) (xy 257.320721 -363.146874) (xy 257.187187 -363.097557)
			(xy 257.056658 -363.040765) (xy 256.929551 -362.976678) (xy 256.806273 -362.905504) (xy 256.687219 -362.827469)
			(xy 256.572771 -362.742823) (xy 256.463295 -362.651839) (xy 256.359141 -362.554806) (xy 256.260644 -362.452036)
			(xy 256.16812 -362.343858) (xy 256.081863 -362.230619) (xy 256.002151 -362.112682) (xy 255.929239 -361.990423)
			(xy 255.863361 -361.864236) (xy 255.804727 -361.734523) (xy 255.753526 -361.601701) (xy 255.709921 -361.466195)
			(xy 255.674052 -361.328439) (xy 255.646034 -361.188875) (xy 255.625957 -361.047948) (xy 255.613885 -360.906112)
			(xy 255.609857 -360.76382) (xy 254.111262 -360.76382) (xy 254.115246 -360.942618) (xy 254.127192 -361.12106)
			(xy 254.147074 -361.298794) (xy 254.174855 -361.475465) (xy 254.210477 -361.650723) (xy 254.253872 -361.824221)
			(xy 254.304952 -361.995613) (xy 254.363617 -362.164559) (xy 254.429749 -362.330725) (xy 254.503218 -362.493779)
			(xy 254.583878 -362.653399) (xy 254.671568 -362.809267) (xy 254.766114 -362.961075) (xy 254.867329 -363.108519)
			(xy 254.975012 -363.251309) (xy 255.088949 -363.38916) (xy 255.208914 -363.521798) (xy 255.334668 -363.648961)
			(xy 255.465961 -363.770396) (xy 255.602535 -363.885861) (xy 255.744116 -363.995128) (xy 255.890424 -364.097979)
			(xy 256.041168 -364.194211) (xy 256.19605 -364.283632) (xy 256.354761 -364.366065) (xy 256.516987 -364.441346)
			(xy 256.682406 -364.509325) (xy 256.850688 -364.569868) (xy 257.021501 -364.622855) (xy 257.194504 -364.66818)
			(xy 257.369355 -364.705753) (xy 257.545705 -364.735499) (xy 257.723206 -364.75736) (xy 257.901505 -364.771293)
			(xy 258.080247 -364.777269) (xy 258.259078 -364.775277) (xy 258.437642 -364.76532) (xy 258.615586 -364.747419)
			(xy 258.792556 -364.721608) (xy 258.9682 -364.68794) (xy 259.14217 -364.646481) (xy 259.314121 -364.597313)
			(xy 259.48371 -364.540534) (xy 259.650602 -364.476257) (xy 259.814465 -364.404609) (xy 259.974974 -364.325733)
			(xy 260.131809 -364.239784) (xy 260.28466 -364.146935) (xy 260.433223 -364.047369) (xy 260.577204 -363.941283)
			(xy 260.716315 -363.828889) (xy 260.850282 -363.71041) (xy 260.978838 -363.58608) (xy 261.101728 -363.456147)
			(xy 261.218707 -363.320869) (xy 261.329545 -363.180514) (xy 261.434019 -363.035361) (xy 261.531925 -362.885698)
			(xy 261.623065 -362.731822) (xy 261.707261 -362.574038) (xy 261.784344 -362.412661) (xy 261.854162 -362.24801)
			(xy 261.916576 -362.080413) (xy 261.971463 -361.910201) (xy 262.018712 -361.737714) (xy 262.05823 -361.563292)
			(xy 262.08994 -361.387284) (xy 262.113777 -361.210038) (xy 262.129695 -361.031905) (xy 262.137662 -360.853241)
		)
		(stroke
			(width 0)
			(type solid)
		)
		(fill yes)
		(layer "B.Cu")
		(net "GND")
	)
	(gr_poly
		(pts
			(xy 105.22839 -263.39038) (xy 105.22839 -261.82574) (xy 105.170478 -261.767828) (xy 104.273858 -261.767828)
			(xy 104.17429 -261.66826) (xy 104.17429 -261.01802) (xy 104.26573 -260.92658) (xy 104.50449 -260.92658)
			(xy 104.54005 -260.89102) (xy 104.54005 -260.006338) (xy 105.006394 -259.539994) (xy 108.143294 -259.539994)
			(xy 108.372402 -259.769102) (xy 108.516928 -259.769102) (xy 108.619036 -259.667248) (xy 108.619036 -259.666994)
			(xy 108.639356 -259.64642) (xy 108.639356 -258.69392) (xy 108.276898 -258.331462) (xy 108.272834 -258.327144)
			(xy 108.27258 -258.32689) (xy 108.18749 -258.2418) (xy 108.18749 -258.157726) (xy 108.124244 -258.09448)
			(xy 106.58983 -258.09448) (xy 106.45775 -257.9624) (xy 106.45775 -257.820922)
			(arc
				(start 106.45394 -257.811778)
				(mid 106.426762 -257.67538)
				(end 106.45394 -257.538982)
			)
			(xy 106.45775 -257.529838) (xy 106.45775 -257.39471) (xy 106.57332 -257.27914) (xy 108.103162 -257.27914)
			(xy 108.140754 -257.24104) (xy 108.141516 -257.24104) (xy 108.22813 -257.15468) (xy 108.22813 -256.936494)
			(xy 108.319316 -256.845308) (xy 108.31957 -256.845054) (xy 108.323634 -256.840736) (xy 108.626656 -256.537714)
			(xy 108.626656 -256.529586) (xy 108.62691 -256.529586) (xy 108.62691 -255.66878) (xy 108.516674 -255.558544)
			(xy 108.308394 -255.558544) (xy 108.289344 -255.577848) (xy 108.284518 -255.58242) (xy 108.199428 -255.66751)
			(xy 108.081064 -255.66751) (xy 108.07319 -255.667764) (xy 104.903016 -255.667764) (xy 104.895142 -255.66751)
			(xy 104.776778 -255.66751) (xy 104.691688 -255.58242) (xy 104.691434 -255.582166) (xy 104.687116 -255.578102)
			(xy 104.634284 -255.52527) (xy 104.63022 -255.520952) (xy 104.629966 -255.520698) (xy 104.54259 -255.433322)
			(xy 104.54259 -254.486664) (xy 104.542336 -254.486664) (xy 104.542336 -254.45212) (xy 103.87965 -254.45212)
			(xy 103.67391 -254.24638) (xy 103.67391 -253.70282) (xy 103.80853 -253.5682) (xy 105.03281 -253.5682)
			(xy 105.26141 -253.7968) (xy 105.26141 -254.10922) (xy 105.332276 -254.179832) (xy 105.34523 -254.19304)
			(xy 106.15295 -254.19304) (xy 106.25709 -254.0889) (xy 106.25709 -253.76632) (xy 106.4387 -253.58471)
			(xy 108.076746 -253.58471) (xy 108.091732 -253.569724) (xy 108.091986 -253.569724) (xy 108.215176 -253.44628)
			(xy 108.215176 -253.286768) (xy 108.21543 -253.278894) (xy 108.21543 -253.15164) (xy 108.62183 -252.74524)
			(xy 108.62183 -251.97562) (xy 108.512864 -251.866654) (xy 108.436664 -251.866654) (xy 108.246418 -252.0569)
			(xy 103.23957 -252.0569) (xy 103.2383 -252.055884) (xy 103.157782 -251.975366) (xy 103.153718 -251.971048)
			(xy 103.153464 -251.970794) (xy 103.068374 -251.885704) (xy 103.068374 -251.76734) (xy 103.06812 -251.759466)
			(xy 103.06812 -250.252738) (xy 103.068374 -250.244864) (xy 103.068374 -250.1265) (xy 103.153464 -250.04141)
			(xy 103.153718 -250.041156) (xy 103.157782 -250.036838) (xy 103.17099 -250.02363) (xy 103.175308 -250.019566)
			(xy 103.175562 -250.019312) (xy 103.263954 -249.93092) (xy 105.00741 -249.93092) (xy 105.095802 -250.019312)
			(xy 105.096056 -250.019566) (xy 105.100374 -250.02363) (xy 105.131362 -250.054618) (xy 105.135426 -250.058936)
			(xy 105.13568 -250.05919) (xy 105.22077 -250.14428) (xy 105.22077 -250.262644) (xy 105.221024 -250.270518)
			(xy 105.221024 -250.43384) (xy 105.312972 -250.525788) (xy 106.164888 -250.525788) (xy 106.28376 -250.406916)
			(xy 106.287316 -250.40336) (xy 106.287316 -250.24969) (xy 106.28757 -250.241816) (xy 106.28757 -250.11126)
			(xy 106.48569 -249.91314) (xy 108.10367 -249.91314) (xy 108.15193 -249.86488) (xy 108.15193 -249.61088)
			(xy 108.278168 -249.484642) (xy 108.278422 -249.484388) (xy 108.282486 -249.48007) (xy 108.619036 -249.14352)
			(xy 108.619036 -248.33072) (xy 108.51642 -248.228104) (xy 108.506768 -248.218452) (xy 108.384848 -248.218452)
			(xy 108.202476 -248.40057) (xy 104.8258 -248.40057) (xy 104.755696 -248.470928)
			(arc
				(start 102.601522 -248.470928)
				(mid 102.512211 -248.524091)
				(end 102.516432 -248.6279)
			)
			(arc
				(start 102.516432 -248.6279)
				(mid 102.555827 -248.713213)
				(end 102.569264 -248.806208)
			)
			(arc
				(start 102.569264 -248.806208)
				(mid 102.510514 -248.993436)
				(end 102.355142 -249.113294)
			)
			(xy 102.344474 -249.117104) (xy 102.21849 -249.243342) (xy 101.559106 -249.243342) (xy 101.423978 -249.37847)
			(xy 101.423978 -253.20371) (xy 101.813868 -253.5936) (xy 102.209092 -253.5936)
			(arc
				(start 102.218236 -253.58979)
				(mid 102.284027 -253.570237)
				(end 102.352348 -253.563628)
			)
			(arc
				(start 102.352348 -253.563628)
				(mid 102.604154 -253.66793)
				(end 102.708456 -253.919736)
			)
			(arc
				(start 102.708456 -253.919736)
				(mid 102.621586 -254.152716)
				(end 102.403402 -254.272034)
			)
			(xy 102.359968 -254.278384) (xy 102.359968 -255.188974)
			(arc
				(start 102.403402 -255.195324)
				(mid 102.621653 -255.314585)
				(end 102.708456 -255.547622)
			)
			(arc
				(start 102.708456 -255.547622)
				(mid 102.637746 -255.760603)
				(end 102.453694 -255.888998)
			)
			(xy 102.441248 -255.892808) (xy 102.39629 -255.937766) (xy 102.487476 -256.028952) (xy 103.038656 -256.028952)
			(xy 103.039926 -256.030222) (xy 104.430068 -256.030222) (xy 104.43464 -256.02565) (xy 104.601518 -256.02565)
			(xy 104.987598 -256.41173) (xy 104.987598 -257.383534) (xy 104.989122 -257.385058) (xy 104.987598 -257.386582)
			(xy 104.987598 -259.12445) (xy 104.692958 -259.41909) (xy 104.377998 -259.41909) (xy 104.376474 -259.420614)
			(xy 102.76967 -259.420614) (xy 102.719886 -259.470398) (xy 102.719886 -261.023862)
			(arc
				(start 102.97287 -261.276846)
				(mid 103.006783 -261.317365)
				(end 103.033068 -261.363206)
			)
			(xy 103.036878 -261.371588) (xy 103.081328 -261.416038) (xy 103.081328 -262.340598) (xy 103.77551 -263.03478)
			(xy 103.78313 -263.03478) (xy 104.18191 -263.43356) (xy 105.18521 -263.43356)
		)
		(stroke
			(width 0)
			(type solid)
		)
		(fill yes)
		(layer "B.Cu")
		(net "GND")
	)
	(gr_poly
		(pts
			(xy 326.04329 -66.612008) (xy 326.04329 -65.745614) (xy 326.009508 -65.711832) (xy 324.89267 -65.711832)
			(xy 324.697852 -65.517014) (xy 324.697852 -65.045844) (xy 324.792086 -64.95161) (xy 324.792086 -64.67475)
			(xy 324.65391 -64.536574) (xy 324.65391 -63.889636) (xy 325.24319 -63.300356) (xy 325.24319 -62.803278)
			(xy 325.466202 -62.580266) (xy 325.466202 -62.173358) (xy 325.308976 -62.016132) (xy 323.519038 -62.016132)
			(xy 322.514468 -61.011308) (xy 322.509642 -61.011308) (xy 322.156582 -60.658248) (xy 322.156582 -59.629548)
			(xy 322.042282 -59.515248) (xy 319.908682 -59.515248) (xy 319.456562 -59.063128) (xy 318.961262 -59.063128)
			(xy 318.715644 -59.308746) (xy 318.705374 -59.319768) (xy 318.691199 -59.346334) (xy 318.685388 -59.375879)
			(xy 318.688446 -59.405835) (xy 318.700107 -59.433596) (xy 318.719357 -59.45675) (xy 318.731646 -59.465464)
			(xy 318.758406 -59.483688) (xy 318.806994 -59.526477) (xy 318.849063 -59.57569) (xy 318.88377 -59.630344)
			(xy 318.910424 -59.689347) (xy 318.92849 -59.751518) (xy 318.937608 -59.815616) (xy 318.938148 -59.847988)
			(xy 318.937712 -59.876807) (xy 318.930476 -59.93399) (xy 318.916117 -59.989812) (xy 318.894862 -60.043389)
			(xy 318.867048 -60.093873) (xy 318.833115 -60.140464) (xy 318.7936 -60.182427) (xy 318.749129 -60.219095)
			(xy 318.700406 -60.249889) (xy 318.674496 -60.262516) (xy 318.645286 -60.276232) (xy 318.645286 -60.832238)
			(xy 318.68745 -60.839604) (xy 318.717465 -60.845272) (xy 318.775757 -60.863524) (xy 318.831103 -60.889367)
			(xy 318.88252 -60.922342) (xy 318.929094 -60.961863) (xy 318.969998 -61.007228) (xy 319.004504 -61.05763)
			(xy 319.032 -61.112174) (xy 319.051996 -61.169891) (xy 319.064137 -61.229755) (xy 319.068209 -61.290701)
			(xy 319.064137 -61.351648) (xy 319.051995 -61.411512) (xy 319.031998 -61.469228) (xy 319.004503 -61.523772)
			(xy 318.969996 -61.574174) (xy 318.929092 -61.619539) (xy 318.882518 -61.65906) (xy 318.831101 -61.692035)
			(xy 318.775754 -61.717877) (xy 318.717462 -61.736129) (xy 318.68745 -61.741812) (xy 318.645286 -61.749178)
			(xy 318.645286 -62.181736) (xy 321.288392 -62.181736) (xy 321.288392 -62.1218) (xy 321.296215 -62.062378)
			(xy 321.311728 -62.004485) (xy 321.334664 -61.949112) (xy 321.364631 -61.897206) (xy 321.401118 -61.849656)
			(xy 321.443498 -61.807276) (xy 321.491048 -61.770789) (xy 321.542954 -61.740822) (xy 321.598327 -61.717886)
			(xy 321.65622 -61.702373) (xy 321.715642 -61.69455) (xy 321.775578 -61.69455) (xy 321.835 -61.702373)
			(xy 321.892893 -61.717886) (xy 321.948266 -61.740822) (xy 322.000172 -61.770789) (xy 322.047722 -61.807276)
			(xy 322.090102 -61.849656) (xy 322.126589 -61.897206) (xy 322.156556 -61.949112) (xy 322.179492 -62.004485)
			(xy 322.195005 -62.062378) (xy 322.202828 -62.1218) (xy 322.203318 -62.151768) (xy 322.202828 -62.181736)
			(xy 322.195005 -62.241158) (xy 322.179492 -62.299051) (xy 322.156556 -62.354424) (xy 322.126589 -62.40633)
			(xy 322.090102 -62.45388) (xy 322.047722 -62.49626) (xy 322.000172 -62.532747) (xy 321.948266 -62.562714)
			(xy 321.892893 -62.58565) (xy 321.835 -62.601163) (xy 321.775578 -62.608986) (xy 321.715642 -62.608986)
			(xy 321.65622 -62.601163) (xy 321.598327 -62.58565) (xy 321.542954 -62.562714) (xy 321.491048 -62.532747)
			(xy 321.443498 -62.49626) (xy 321.401118 -62.45388) (xy 321.364631 -62.40633) (xy 321.334664 -62.354424)
			(xy 321.311728 -62.299051) (xy 321.296215 -62.241158) (xy 321.288392 -62.181736) (xy 318.645286 -62.181736)
			(xy 318.645286 -62.223396) (xy 318.676782 -62.23635) (xy 318.704432 -62.248173) (xy 318.756631 -62.278033)
			(xy 318.804468 -62.314475) (xy 318.847118 -62.35687) (xy 318.883845 -62.404488) (xy 318.914018 -62.456507)
			(xy 318.937115 -62.512031) (xy 318.952738 -62.570102) (xy 318.960618 -62.62972) (xy 318.96062 -62.689856)
			(xy 318.952743 -62.749474) (xy 318.937122 -62.807546) (xy 318.914028 -62.863071) (xy 318.883859 -62.915092)
			(xy 318.847134 -62.962711) (xy 318.804486 -63.005109) (xy 318.756651 -63.041553) (xy 318.704454 -63.071417)
			(xy 318.676782 -63.083186) (xy 318.645286 -63.09614) (xy 318.645286 -63.371222) (xy 318.491112 -63.525396)
			(xy 320.869292 -63.525396) (xy 320.869292 -63.46546) (xy 320.877115 -63.406038) (xy 320.892628 -63.348145)
			(xy 320.915564 -63.292772) (xy 320.945531 -63.240866) (xy 320.982018 -63.193316) (xy 321.024398 -63.150936)
			(xy 321.071948 -63.114449) (xy 321.123854 -63.084482) (xy 321.179227 -63.061546) (xy 321.23712 -63.046033)
			(xy 321.296542 -63.03821) (xy 321.356478 -63.03821) (xy 321.4159 -63.046033) (xy 321.473793 -63.061546)
			(xy 321.529166 -63.084482) (xy 321.581072 -63.114449) (xy 321.628622 -63.150936) (xy 321.671002 -63.193316)
			(xy 321.707489 -63.240866) (xy 321.737456 -63.292772) (xy 321.760392 -63.348145) (xy 321.775905 -63.406038)
			(xy 321.783728 -63.46546) (xy 321.784218 -63.495428) (xy 321.783728 -63.525396) (xy 321.775905 -63.584818)
			(xy 321.760392 -63.642711) (xy 321.737456 -63.698084) (xy 321.707489 -63.74999) (xy 321.671002 -63.79754)
			(xy 321.628622 -63.83992) (xy 321.581072 -63.876407) (xy 321.529166 -63.906374) (xy 321.473793 -63.92931)
			(xy 321.4159 -63.944823) (xy 321.356478 -63.952646) (xy 321.296542 -63.952646) (xy 321.23712 -63.944823)
			(xy 321.179227 -63.92931) (xy 321.123854 -63.906374) (xy 321.071948 -63.876407) (xy 321.024398 -63.83992)
			(xy 320.982018 -63.79754) (xy 320.945531 -63.74999) (xy 320.915564 -63.698084) (xy 320.892628 -63.642711)
			(xy 320.877115 -63.584818) (xy 320.869292 -63.525396) (xy 318.491112 -63.525396) (xy 318.421258 -63.59525)
			(xy 318.421258 -64.038988) (xy 318.757298 -64.038988) (xy 318.761369 -63.983366) (xy 318.773495 -63.928929)
			(xy 318.793418 -63.876838) (xy 318.820714 -63.828203) (xy 318.8548 -63.78406) (xy 318.894949 -63.745351)
			(xy 318.940307 -63.7129) (xy 318.989907 -63.687399) (xy 319.042691 -63.669392) (xy 319.097534 -63.659262)
			(xy 319.153268 -63.657225) (xy 319.208705 -63.663325) (xy 319.262662 -63.677431) (xy 319.313991 -63.699243)
			(xy 319.361597 -63.728297) (xy 319.404465 -63.763972) (xy 319.441682 -63.805509) (xy 319.472455 -63.852022)
			(xy 319.496127 -63.902519) (xy 319.512195 -63.955926) (xy 319.520315 -64.011102) (xy 319.520824 -64.038988)
			(xy 319.520315 -64.066874) (xy 319.512195 -64.12205) (xy 319.496127 -64.175457) (xy 319.472455 -64.225954)
			(xy 319.441682 -64.272467) (xy 319.404465 -64.314004) (xy 319.361597 -64.349679) (xy 319.313991 -64.378733)
			(xy 319.262662 -64.400545) (xy 319.208705 -64.414651) (xy 319.153268 -64.420751) (xy 319.097534 -64.418714)
			(xy 319.042691 -64.408584) (xy 318.989907 -64.390577) (xy 318.940307 -64.365076) (xy 318.894949 -64.332625)
			(xy 318.8548 -64.293916) (xy 318.820714 -64.249773) (xy 318.793418 -64.201138) (xy 318.773495 -64.149047)
			(xy 318.761369 -64.09461) (xy 318.757298 -64.038988) (xy 318.421258 -64.038988) (xy 318.421258 -65.98031)
			(xy 318.484055 -66.019542) (xy 318.606016 -66.103534) (xy 318.723534 -66.193639) (xy 318.836303 -66.289621)
			(xy 318.944029 -66.391231) (xy 319.04643 -66.498204) (xy 319.143242 -66.610262) (xy 319.1891 -66.668396)
			(xy 325.986902 -66.668396)
		)
		(stroke
			(width 0)
			(type solid)
		)
		(fill yes)
		(layer "B.Cu")
		(net "P3V3_AUX")
	)
	(gr_poly
		(pts
			(xy 316.484 -257.647948) (xy 316.484 -251.440188) (xy 316.2046 -251.160788) (xy 314.292742 -251.160788)
			(xy 314.270455 -251.17543) (xy 314.222423 -251.198592) (xy 314.171472 -251.214327) (xy 314.118744 -251.222284)
			(xy 314.06542 -251.222284) (xy 314.012692 -251.214327) (xy 313.961741 -251.198592) (xy 313.913709 -251.17543)
			(xy 313.891422 -251.160788) (xy 312.082942 -251.160788) (xy 312.060654 -251.175429) (xy 312.012622 -251.198587)
			(xy 311.961671 -251.21432) (xy 311.908944 -251.222273) (xy 311.882282 -251.222764) (xy 311.857366 -251.22235)
			(xy 311.808023 -251.215398) (xy 311.760135 -251.201618) (xy 311.714642 -251.181282) (xy 311.693306 -251.168408)
			(xy 311.681114 -251.160788) (xy 311.611772 -251.160788) (xy 311.601782 -251.161278) (xy 311.58332 -251.16892)
			(xy 311.569177 -251.183035) (xy 311.561498 -251.201482) (xy 311.561447 -251.221463) (xy 311.569032 -251.239948)
			(xy 311.575704 -251.247402) (xy 312.107834 -251.779786) (xy 312.125239 -251.797848) (xy 312.154766 -251.838391)
			(xy 312.17759 -251.883052) (xy 312.193151 -251.930733) (xy 312.201065 -251.980261) (xy 312.20156 -252.005338)
			(xy 312.20156 -252.408436) (xy 312.206132 -252.418342) (xy 312.216342 -252.441722) (xy 312.230722 -252.49067)
			(xy 312.237973 -252.541169) (xy 312.23839 -252.566678) (xy 312.237892 -252.593327) (xy 312.229949 -252.646031)
			(xy 312.214239 -252.696961) (xy 312.191113 -252.744982) (xy 312.161089 -252.789019) (xy 312.124837 -252.82809)
			(xy 312.083166 -252.861321) (xy 312.037008 -252.88797) (xy 311.987394 -252.907442) (xy 311.935432 -252.919302)
			(xy 311.882282 -252.923286) (xy 311.829132 -252.919302) (xy 311.77717 -252.907442) (xy 311.727556 -252.88797)
			(xy 311.681398 -252.861321) (xy 311.639727 -252.82809) (xy 311.603475 -252.789019) (xy 311.573451 -252.744982)
			(xy 311.550325 -252.696961) (xy 311.534615 -252.646031) (xy 311.526672 -252.593327) (xy 311.526174 -252.566678)
			(xy 311.526592 -252.541169) (xy 311.533837 -252.490669) (xy 311.548218 -252.44172) (xy 311.558432 -252.418342)
			(xy 311.563004 -252.408436) (xy 311.563004 -252.137418) (xy 310.910732 -251.485146) (xy 310.890412 -251.484384)
			(xy 310.860683 -251.483031) (xy 310.801925 -251.473581) (xy 310.744888 -251.456596) (xy 310.690533 -251.43236)
			(xy 310.639779 -251.401284) (xy 310.59348 -251.363891) (xy 310.552419 -251.320812) (xy 310.517288 -251.272775)
			(xy 310.48868 -251.220589) (xy 310.477408 -251.193046) (xy 310.464708 -251.160788) (xy 306.87264 -251.160788)
			(xy 306.289985 -251.743443) (xy 307.426604 -251.743443) (xy 307.426604 -251.690145) (xy 307.434547 -251.637441)
			(xy 307.450257 -251.586511) (xy 307.473383 -251.53849) (xy 307.503407 -251.494453) (xy 307.539659 -251.455382)
			(xy 307.58133 -251.422151) (xy 307.627488 -251.395502) (xy 307.677102 -251.37603) (xy 307.729064 -251.36417)
			(xy 307.782214 -251.360187) (xy 307.835364 -251.36417) (xy 307.887326 -251.37603) (xy 307.93694 -251.395502)
			(xy 307.983098 -251.422151) (xy 308.024769 -251.455382) (xy 308.061021 -251.494453) (xy 308.091045 -251.53849)
			(xy 308.114171 -251.586511) (xy 308.129881 -251.637441) (xy 308.137824 -251.690145) (xy 308.138322 -251.716794)
			(xy 308.137824 -251.743443) (xy 309.636404 -251.743443) (xy 309.636404 -251.690145) (xy 309.644347 -251.637441)
			(xy 309.660057 -251.586511) (xy 309.683183 -251.53849) (xy 309.713207 -251.494453) (xy 309.749459 -251.455382)
			(xy 309.79113 -251.422151) (xy 309.837288 -251.395502) (xy 309.886902 -251.37603) (xy 309.938864 -251.36417)
			(xy 309.992014 -251.360187) (xy 310.045164 -251.36417) (xy 310.097126 -251.37603) (xy 310.14674 -251.395502)
			(xy 310.192898 -251.422151) (xy 310.234569 -251.455382) (xy 310.270821 -251.494453) (xy 310.300845 -251.53849)
			(xy 310.323971 -251.586511) (xy 310.339681 -251.637441) (xy 310.347624 -251.690145) (xy 310.348122 -251.716794)
			(xy 310.347624 -251.743443) (xy 310.339681 -251.796147) (xy 310.323971 -251.847077) (xy 310.300845 -251.895098)
			(xy 310.270821 -251.939135) (xy 310.234569 -251.978206) (xy 310.192898 -252.011437) (xy 310.14674 -252.038086)
			(xy 310.097126 -252.057558) (xy 310.045164 -252.069418) (xy 309.992014 -252.073402) (xy 309.938864 -252.069418)
			(xy 309.886902 -252.057558) (xy 309.837288 -252.038086) (xy 309.79113 -252.011437) (xy 309.749459 -251.978206)
			(xy 309.713207 -251.939135) (xy 309.683183 -251.895098) (xy 309.660057 -251.847077) (xy 309.644347 -251.796147)
			(xy 309.636404 -251.743443) (xy 308.137824 -251.743443) (xy 308.129881 -251.796147) (xy 308.114171 -251.847077)
			(xy 308.091045 -251.895098) (xy 308.061021 -251.939135) (xy 308.024769 -251.978206) (xy 307.983098 -252.011437)
			(xy 307.93694 -252.038086) (xy 307.887326 -252.057558) (xy 307.835364 -252.069418) (xy 307.782214 -252.073402)
			(xy 307.729064 -252.069418) (xy 307.677102 -252.057558) (xy 307.627488 -252.038086) (xy 307.58133 -252.011437)
			(xy 307.539659 -251.978206) (xy 307.503407 -251.939135) (xy 307.473383 -251.895098) (xy 307.450257 -251.847077)
			(xy 307.434547 -251.796147) (xy 307.426604 -251.743443) (xy 306.289985 -251.743443) (xy 305.055778 -252.97765)
			(xy 305.055778 -254.258968) (xy 309.400582 -254.258968) (xy 309.400582 -254.174432) (xy 309.408382 -254.090256)
			(xy 309.423916 -254.007159) (xy 309.447051 -253.92585) (xy 309.47759 -253.847022) (xy 309.515273 -253.771348)
			(xy 309.559777 -253.699475) (xy 309.610723 -253.632014) (xy 309.667676 -253.569542) (xy 309.730151 -253.512592)
			(xy 309.797614 -253.46165) (xy 309.86949 -253.417149) (xy 309.945166 -253.379471) (xy 310.023995 -253.348936)
			(xy 310.105305 -253.325805) (xy 310.188403 -253.310275) (xy 310.27258 -253.302479) (xy 310.314848 -253.302008)
			(xy 311.559448 -253.302008) (xy 311.601709 -253.302574) (xy 311.685871 -253.310377) (xy 311.768954 -253.325912)
			(xy 311.850249 -253.349046) (xy 311.929062 -253.379582) (xy 312.004722 -253.41726) (xy 312.076583 -253.461758)
			(xy 312.144032 -253.512696) (xy 312.206494 -253.56964) (xy 312.263435 -253.632105) (xy 312.314369 -253.699556)
			(xy 312.358863 -253.77142) (xy 312.396537 -253.847082) (xy 312.427069 -253.925897) (xy 312.450199 -254.007193)
			(xy 312.46573 -254.090277) (xy 312.473528 -254.174439) (xy 312.473528 -254.258961) (xy 312.46573 -254.343123)
			(xy 312.450199 -254.426207) (xy 312.427069 -254.507503) (xy 312.396537 -254.586318) (xy 312.358863 -254.66198)
			(xy 312.314369 -254.733844) (xy 312.263435 -254.801295) (xy 312.206494 -254.86376) (xy 312.144032 -254.920704)
			(xy 312.076583 -254.971642) (xy 312.004722 -255.01614) (xy 311.929062 -255.053818) (xy 311.850249 -255.084354)
			(xy 311.768954 -255.107488) (xy 311.685871 -255.123023) (xy 311.601709 -255.130826) (xy 311.559448 -255.131316)
			(xy 310.314848 -255.131316) (xy 310.27258 -255.130921) (xy 310.188403 -255.123125) (xy 310.105305 -255.107595)
			(xy 310.023995 -255.084464) (xy 309.945166 -255.053929) (xy 309.86949 -255.016251) (xy 309.797614 -254.97175)
			(xy 309.730151 -254.920808) (xy 309.667676 -254.863858) (xy 309.610723 -254.801386) (xy 309.559777 -254.733925)
			(xy 309.515273 -254.662052) (xy 309.47759 -254.586378) (xy 309.447051 -254.50755) (xy 309.423916 -254.426241)
			(xy 309.408382 -254.343144) (xy 309.400582 -254.258968) (xy 305.055778 -254.258968) (xy 305.055778 -255.005078)
			(xy 304.336196 -255.72466) (xy 304.336196 -257.099308) (xy 304.327814 -257.10769) (xy 304.327814 -257.795776)
			(xy 304.55362 -258.021328) (xy 316.11062 -258.021328)
		)
		(stroke
			(width 0)
			(type solid)
		)
		(fill yes)
		(layer "B.Cu")
		(net "PVCCFA_EHV_FIVRA_CPU0")
	)
	(gr_poly
		(pts
			(xy 252.083824 -98.672904) (xy 252.083824 -96.850708) (xy 251.880624 -96.647508) (xy 250.661424 -96.647508)
			(xy 250.413012 -96.399096) (xy 250.413012 -95.339408) (xy 250.412541 -95.325515) (xy 250.405051 -95.298758)
			(xy 250.390624 -95.275011) (xy 250.370328 -95.256034) (xy 250.345666 -95.243233) (xy 250.318467 -95.237555)
			(xy 250.290744 -95.239422) (xy 250.264551 -95.248695) (xy 250.241829 -95.264687) (xy 250.232672 -95.275146)
			(xy 250.213997 -95.29739) (xy 250.171939 -95.337447) (xy 250.125151 -95.371862) (xy 250.074386 -95.400081)
			(xy 250.020459 -95.421652) (xy 249.964236 -95.436226) (xy 249.906621 -95.443572) (xy 249.87758 -95.444056)
			(xy 249.847612 -95.443565) (xy 249.788189 -95.43574) (xy 249.730296 -95.420226) (xy 249.674922 -95.397289)
			(xy 249.623016 -95.367322) (xy 249.575465 -95.330836) (xy 249.533083 -95.288456) (xy 249.496594 -95.240907)
			(xy 249.466623 -95.189003) (xy 249.443683 -95.133631) (xy 249.428166 -95.075738) (xy 249.420337 -95.016316)
			(xy 249.419872 -94.986348) (xy 249.420354 -94.956551) (xy 249.428095 -94.897462) (xy 249.443439 -94.839878)
			(xy 249.466126 -94.784772) (xy 249.495773 -94.733076) (xy 249.531879 -94.685665) (xy 249.573832 -94.643341)
			(xy 249.620923 -94.606819) (xy 249.672356 -94.576718) (xy 249.72726 -94.553546) (xy 249.784707 -94.537696)
			(xy 249.843725 -94.529435) (xy 249.873516 -94.52864) (xy 249.888444 -94.527968) (xy 249.916949 -94.519049)
			(xy 249.941658 -94.502272) (xy 249.960464 -94.479068) (xy 249.97176 -94.451419) (xy 249.974581 -94.421685)
			(xy 249.968687 -94.392405) (xy 249.954581 -94.366078) (xy 249.944382 -94.355158) (xy 249.63882 -94.049596)
			(xy 246.143272 -94.049596) (xy 245.696486 -94.496382) (xy 240.079022 -94.496382) (xy 239.812576 -94.762828)
			(xy 248.380502 -94.762828) (xy 248.384573 -94.707206) (xy 248.396699 -94.652769) (xy 248.416622 -94.600678)
			(xy 248.443918 -94.552043) (xy 248.478004 -94.5079) (xy 248.518153 -94.469191) (xy 248.563511 -94.43674)
			(xy 248.613111 -94.411239) (xy 248.665895 -94.393232) (xy 248.720738 -94.383102) (xy 248.776472 -94.381065)
			(xy 248.831909 -94.387165) (xy 248.885866 -94.401271) (xy 248.937195 -94.423083) (xy 248.984801 -94.452137)
			(xy 249.027669 -94.487812) (xy 249.064886 -94.529349) (xy 249.095659 -94.575862) (xy 249.119331 -94.626359)
			(xy 249.135399 -94.679766) (xy 249.143519 -94.734942) (xy 249.144028 -94.762828) (xy 249.143519 -94.790714)
			(xy 249.135399 -94.84589) (xy 249.119331 -94.899297) (xy 249.095659 -94.949794) (xy 249.064886 -94.996307)
			(xy 249.027669 -95.037844) (xy 248.984801 -95.073519) (xy 248.937195 -95.102573) (xy 248.885866 -95.124385)
			(xy 248.831909 -95.138491) (xy 248.776472 -95.144591) (xy 248.720738 -95.142554) (xy 248.665895 -95.132424)
			(xy 248.613111 -95.114417) (xy 248.563511 -95.088916) (xy 248.518153 -95.056465) (xy 248.478004 -95.017756)
			(xy 248.443918 -94.973613) (xy 248.416622 -94.924978) (xy 248.396699 -94.872887) (xy 248.384573 -94.81845)
			(xy 248.380502 -94.762828) (xy 239.812576 -94.762828) (xy 239.465358 -95.110046) (xy 239.465358 -97.59188)
			(xy 239.61217 -97.738692) (xy 240.559336 -97.738692) (xy 240.95964 -97.338388) (xy 243.241322 -97.338388)
			(xy 243.521484 -97.058226) (xy 244.735858 -97.058226) (xy 244.89918 -97.221548) (xy 246.065802 -97.221548)
			(xy 246.080153 -97.221057) (xy 246.107723 -97.213073) (xy 246.131985 -97.197736) (xy 246.151023 -97.176255)
			(xy 246.163335 -97.150327) (xy 246.167949 -97.121998) (xy 246.164502 -97.093503) (xy 246.153265 -97.067091)
			(xy 246.144542 -97.055686) (xy 246.132535 -97.040294) (xy 246.113444 -97.006247) (xy 246.100476 -96.969429)
			(xy 246.094016 -96.930933) (xy 246.093742 -96.911414) (xy 246.093996 -96.911414) (xy 246.093996 -96.612202)
			(xy 246.093742 -96.612202) (xy 246.094055 -96.59225) (xy 246.100826 -96.552928) (xy 246.114372 -96.515397)
			(xy 246.123968 -96.497902) (xy 246.130572 -96.486218) (xy 246.130572 -96.095058) (xy 246.131064 -96.070228)
			(xy 246.138799 -96.021174) (xy 246.154043 -95.973912) (xy 246.176429 -95.929583) (xy 246.190516 -95.90913)
			(xy 246.195839 -95.883238) (xy 246.21268 -95.833132) (xy 246.236276 -95.785831) (xy 246.266176 -95.74224)
			(xy 246.301807 -95.703193) (xy 246.342486 -95.669439) (xy 246.387436 -95.641624) (xy 246.435795 -95.620279)
			(xy 246.486638 -95.605815) (xy 246.53899 -95.598507) (xy 246.56542 -95.59798) (xy 246.592671 -95.598467)
			(xy 246.646617 -95.606226) (xy 246.69891 -95.621583) (xy 246.748485 -95.644225) (xy 246.794334 -95.673691)
			(xy 246.835523 -95.709383) (xy 246.871213 -95.750572) (xy 246.900679 -95.796422) (xy 246.92332 -95.845998)
			(xy 246.938676 -95.898291) (xy 246.94133 -95.916746) (xy 248.403346 -95.916746) (xy 248.403346 -95.85681)
			(xy 248.411169 -95.797388) (xy 248.426682 -95.739495) (xy 248.449618 -95.684122) (xy 248.479585 -95.632216)
			(xy 248.516072 -95.584666) (xy 248.558452 -95.542286) (xy 248.606002 -95.505799) (xy 248.657908 -95.475832)
			(xy 248.713281 -95.452896) (xy 248.771174 -95.437383) (xy 248.830596 -95.42956) (xy 248.890532 -95.42956)
			(xy 248.949954 -95.437383) (xy 249.007847 -95.452896) (xy 249.06322 -95.475832) (xy 249.115126 -95.505799)
			(xy 249.162676 -95.542286) (xy 249.205056 -95.584666) (xy 249.241543 -95.632216) (xy 249.27151 -95.684122)
			(xy 249.294446 -95.739495) (xy 249.309959 -95.797388) (xy 249.317782 -95.85681) (xy 249.318272 -95.886778)
			(xy 249.317782 -95.916746) (xy 249.309959 -95.976168) (xy 249.294446 -96.034061) (xy 249.27151 -96.089434)
			(xy 249.241543 -96.14134) (xy 249.205056 -96.18889) (xy 249.162676 -96.23127) (xy 249.115126 -96.267757)
			(xy 249.06322 -96.297724) (xy 249.007847 -96.32066) (xy 248.949954 -96.336173) (xy 248.890532 -96.343996)
			(xy 248.830596 -96.343996) (xy 248.771174 -96.336173) (xy 248.713281 -96.32066) (xy 248.657908 -96.297724)
			(xy 248.606002 -96.267757) (xy 248.558452 -96.23127) (xy 248.516072 -96.18889) (xy 248.479585 -96.14134)
			(xy 248.449618 -96.089434) (xy 248.426682 -96.034061) (xy 248.411169 -95.976168) (xy 248.403346 -95.916746)
			(xy 246.94133 -95.916746) (xy 246.946433 -95.952237) (xy 246.946928 -95.979488) (xy 246.946451 -96.006958)
			(xy 246.938572 -96.061329) (xy 246.922976 -96.114008) (xy 246.899986 -96.163906) (xy 246.870076 -96.20999)
			(xy 246.833866 -96.251308) (xy 246.792104 -96.287004) (xy 246.769128 -96.302068) (xy 246.769128 -96.444308)
			(xy 247.112536 -96.444308) (xy 247.112536 -96.384364) (xy 247.379998 -96.384364) (xy 247.402323 -96.384883)
			(xy 247.446107 -96.393637) (xy 247.487324 -96.410806) (xy 247.524375 -96.435723) (xy 247.555821 -96.467421)
			(xy 247.580442 -96.504669) (xy 247.597282 -96.546022) (xy 247.605687 -96.589873) (xy 247.606058 -96.612202)
			(xy 247.605804 -96.612202) (xy 247.605804 -96.911414) (xy 247.606058 -96.911414) (xy 247.605743 -96.931366)
			(xy 247.59897 -96.970686) (xy 247.585422 -97.008216) (xy 247.575832 -97.025714) (xy 247.569228 -97.037398)
			(xy 247.569228 -97.221548) (xy 248.12498 -97.221548) (xy 248.14879 -97.204299) (xy 248.19999 -97.175396)
			(xy 248.254472 -97.153291) (xy 248.311337 -97.138349) (xy 248.369648 -97.130815) (xy 248.428444 -97.130815)
			(xy 248.486755 -97.138349) (xy 248.54362 -97.153291) (xy 248.598102 -97.175396) (xy 248.649302 -97.204299)
			(xy 248.673112 -97.221548) (xy 249.45848 -97.221548) (xy 250.95708 -98.720148) (xy 252.03658 -98.720148)
		)
		(stroke
			(width 0)
			(type solid)
		)
		(fill yes)
		(layer "B.Cu")
		(net "P3V3_AUX_CLK_GEN_VDDXTAL_CK440")
	)
	(gr_poly
		(pts
			(xy 240.899696 -81.699862) (xy 240.899195 -81.599808) (xy 240.891189 -81.399861) (xy 240.87519 -81.200394)
			(xy 240.851222 -81.001726) (xy 240.819325 -80.804177) (xy 240.77955 -80.608062) (xy 240.73196 -80.413696)
			(xy 240.676632 -80.221389) (xy 240.613654 -80.03145) (xy 240.543127 -79.844183) (xy 240.465164 -79.659887)
			(xy 240.37989 -79.478858) (xy 240.287441 -79.301386) (xy 240.187966 -79.127755) (xy 240.081623 -78.958243)
			(xy 239.968584 -78.793122) (xy 239.849028 -78.632655) (xy 239.723148 -78.4771) (xy 239.591145 -78.326706)
			(xy 239.453231 -78.181714) (xy 239.309626 -78.042356) (xy 239.16056 -77.908855) (xy 239.006272 -77.781425)
			(xy 238.84701 -77.66027) (xy 238.683027 -77.545584) (xy 238.514588 -77.437551) (xy 238.341961 -77.336343)
			(xy 238.165422 -77.242123) (xy 237.985256 -77.155042) (xy 237.801749 -77.075239) (xy 237.615197 -77.002842)
			(xy 237.425898 -76.937967) (xy 237.234154 -76.880717) (xy 237.040273 -76.831185) (xy 236.844566 -76.78945)
			(xy 236.647346 -76.755578) (xy 236.448929 -76.729625) (xy 236.249632 -76.71163) (xy 236.049774 -76.701624)
			(xy 235.849677 -76.699622) (xy 235.649659 -76.705627) (xy 235.450042 -76.71963) (xy 235.251145 -76.741609)
			(xy 235.053286 -76.771528) (xy 234.856783 -76.809339) (xy 234.66195 -76.854982) (xy 234.4691 -76.908383)
			(xy 234.27854 -76.969458) (xy 234.090577 -77.038107) (xy 233.90551 -77.114223) (xy 233.723637 -77.197681)
			(xy 233.545249 -77.28835) (xy 233.370632 -77.386083) (xy 233.200064 -77.490724) (xy 233.03382 -77.602106)
			(xy 232.872165 -77.72005) (xy 232.715358 -77.844368) (xy 232.563651 -77.974859) (xy 232.417287 -78.111316)
			(xy 232.276499 -78.25352) (xy 232.141513 -78.401243) (xy 232.012546 -78.554248) (xy 231.889803 -78.71229)
			(xy 231.773483 -78.875117) (xy 231.66377 -79.042467) (xy 231.56084 -79.214073) (xy 231.464859 -79.38966)
			(xy 231.375979 -79.568946) (xy 231.294344 -79.751645) (xy 231.220085 -79.937464) (xy 231.153319 -80.126105)
			(xy 231.094154 -80.317266) (xy 231.042684 -80.510641) (xy 230.998993 -80.705921) (xy 230.96315 -80.902792)
			(xy 230.935212 -81.10094) (xy 230.915225 -81.300047) (xy 230.903219 -81.499794) (xy 230.899389 -81.691235)
			(xy 232.138513 -81.691235) (xy 232.142937 -81.517286) (xy 232.155401 -81.343727) (xy 232.17588 -81.170931)
			(xy 232.204328 -80.999267) (xy 232.240686 -80.829102) (xy 232.284875 -80.660801) (xy 232.336801 -80.494724)
			(xy 232.396352 -80.331227) (xy 232.463402 -80.170658) (xy 232.537806 -80.013363) (xy 232.619406 -79.859677)
			(xy 232.708027 -79.709929) (xy 232.803478 -79.564441) (xy 232.905557 -79.423523) (xy 233.014043 -79.287477)
			(xy 233.128706 -79.156594) (xy 233.2493 -79.031155) (xy 233.375566 -78.911427) (xy 233.507235 -78.797668)
			(xy 233.644024 -78.69012) (xy 233.714544 -78.639162) (xy 238.084868 -78.639162) (xy 238.155388 -78.69012)
			(xy 238.292177 -78.797668) (xy 238.423846 -78.911427) (xy 238.550112 -79.031155) (xy 238.670706 -79.156594)
			(xy 238.785369 -79.287477) (xy 238.893855 -79.423523) (xy 238.995934 -79.564441) (xy 239.091385 -79.709929)
			(xy 239.180006 -79.859677) (xy 239.261606 -80.013363) (xy 239.33601 -80.170658) (xy 239.40306 -80.331227)
			(xy 239.462611 -80.494724) (xy 239.514537 -80.660801) (xy 239.558726 -80.829102) (xy 239.595084 -80.999267)
			(xy 239.623532 -81.170931) (xy 239.644011 -81.343727) (xy 239.656475 -81.517286) (xy 239.660899 -81.691235)
			(xy 239.657273 -81.865202) (xy 239.645605 -82.038816) (xy 239.62592 -82.211704) (xy 239.598259 -82.383497)
			(xy 239.562682 -82.553827) (xy 239.519266 -82.722329) (xy 239.468102 -82.888642) (xy 239.409301 -83.052411)
			(xy 239.342989 -83.213286) (xy 239.269307 -83.370921) (xy 239.188413 -83.52498) (xy 239.100481 -83.675132)
			(xy 239.005697 -83.821057) (xy 238.904267 -83.962441) (xy 238.796405 -84.098984) (xy 238.682344 -84.230391)
			(xy 238.562327 -84.356382) (xy 238.436611 -84.476688) (xy 238.305466 -84.59105) (xy 238.169171 -84.699225)
			(xy 238.028019 -84.80098) (xy 237.882313 -84.896097) (xy 237.732362 -84.984374) (xy 237.57849 -85.065621)
			(xy 237.421024 -85.139665) (xy 237.260302 -85.206346) (xy 237.096668 -85.265522) (xy 236.930472 -85.317067)
			(xy 236.762071 -85.36087) (xy 236.591823 -85.396837) (xy 236.420094 -85.424892) (xy 236.247251 -85.444974)
			(xy 236.073665 -85.45704) (xy 235.899706 -85.461065) (xy 235.725747 -85.45704) (xy 235.552161 -85.444974)
			(xy 235.379318 -85.424892) (xy 235.207589 -85.396837) (xy 235.037341 -85.36087) (xy 234.86894 -85.317067)
			(xy 234.702744 -85.265522) (xy 234.53911 -85.206346) (xy 234.378388 -85.139665) (xy 234.220922 -85.065621)
			(xy 234.06705 -84.984374) (xy 233.917099 -84.896097) (xy 233.771393 -84.80098) (xy 233.630241 -84.699225)
			(xy 233.493946 -84.59105) (xy 233.362801 -84.476688) (xy 233.237085 -84.356382) (xy 233.117068 -84.230391)
			(xy 233.003007 -84.098984) (xy 232.895145 -83.962441) (xy 232.793715 -83.821057) (xy 232.698931 -83.675132)
			(xy 232.610999 -83.52498) (xy 232.530105 -83.370921) (xy 232.456423 -83.213286) (xy 232.390111 -83.052411)
			(xy 232.33131 -82.888642) (xy 232.280146 -82.722329) (xy 232.23673 -82.553827) (xy 232.201153 -82.383497)
			(xy 232.173492 -82.211704) (xy 232.153807 -82.038816) (xy 232.142139 -81.865202) (xy 232.138513 -81.691235)
			(xy 230.899389 -81.691235) (xy 230.899216 -81.699862) (xy 230.903219 -81.89993) (xy 230.915225 -82.099677)
			(xy 230.935212 -82.298784) (xy 230.96315 -82.496932) (xy 230.998993 -82.693803) (xy 231.042684 -82.889083)
			(xy 231.094154 -83.082458) (xy 231.153319 -83.273619) (xy 231.220085 -83.46226) (xy 231.294344 -83.648079)
			(xy 231.375979 -83.830778) (xy 231.464859 -84.010064) (xy 231.56084 -84.185651) (xy 231.66377 -84.357257)
			(xy 231.773483 -84.524607) (xy 231.889803 -84.687434) (xy 232.012546 -84.845476) (xy 232.141513 -84.998481)
			(xy 232.276499 -85.146204) (xy 232.417287 -85.288408) (xy 232.563651 -85.424865) (xy 232.715358 -85.555356)
			(xy 232.872165 -85.679674) (xy 233.03382 -85.797618) (xy 233.200064 -85.909) (xy 233.370632 -86.013641)
			(xy 233.545249 -86.111374) (xy 233.723637 -86.202043) (xy 233.90551 -86.285501) (xy 234.090577 -86.361617)
			(xy 234.27854 -86.430266) (xy 234.4691 -86.491341) (xy 234.66195 -86.544742) (xy 234.856783 -86.590385)
			(xy 235.053286 -86.628196) (xy 235.251145 -86.658115) (xy 235.450042 -86.680094) (xy 235.649659 -86.694097)
			(xy 235.849677 -86.700102) (xy 236.049774 -86.6981) (xy 236.249632 -86.688094) (xy 236.448929 -86.670099)
			(xy 236.647346 -86.644146) (xy 236.844566 -86.610274) (xy 237.040273 -86.568539) (xy 237.234154 -86.519007)
			(xy 237.425898 -86.461757) (xy 237.615197 -86.396882) (xy 237.801749 -86.324485) (xy 237.985256 -86.244682)
			(xy 238.165422 -86.157601) (xy 238.341961 -86.063381) (xy 238.514588 -85.962173) (xy 238.683027 -85.85414)
			(xy 238.84701 -85.739454) (xy 239.006272 -85.618299) (xy 239.16056 -85.490869) (xy 239.309626 -85.357368)
			(xy 239.453231 -85.21801) (xy 239.591145 -85.073018) (xy 239.723148 -84.922624) (xy 239.849028 -84.767069)
			(xy 239.968584 -84.606602) (xy 240.081623 -84.441481) (xy 240.187966 -84.271969) (xy 240.287441 -84.098338)
			(xy 240.37989 -83.920866) (xy 240.465164 -83.739837) (xy 240.543127 -83.555541) (xy 240.613654 -83.368274)
			(xy 240.676632 -83.178335) (xy 240.73196 -82.986028) (xy 240.77955 -82.791662) (xy 240.819325 -82.595547)
			(xy 240.851222 -82.397998) (xy 240.87519 -82.19933) (xy 240.891189 -81.999863) (xy 240.899195 -81.799916)
		)
		(stroke
			(width 0)
			(type solid)
		)
		(fill yes)
		(layer "B.Cu")
		(net "GND")
	)
	(gr_poly
		(pts
			(xy 74.1807 -23.851108) (xy 74.1807 -21.976842) (xy 74.177652 -21.96846) (xy 74.167205 -21.937297)
			(xy 74.155965 -21.872543) (xy 74.1553 -21.839682) (xy 74.15599 -21.806823) (xy 74.167232 -21.742074)
			(xy 74.177652 -21.710904) (xy 74.1807 -21.702522) (xy 74.1807 -21.267928) (xy 74.24674 -21.201888)
			(xy 74.22261 -21.16709) (xy 74.206718 -21.143092) (xy 74.181562 -21.091324) (xy 74.164469 -21.036364)
			(xy 74.155825 -20.97946) (xy 74.1553 -20.950682) (xy 74.155787 -20.923432) (xy 74.163546 -20.869486)
			(xy 74.178902 -20.817194) (xy 74.201545 -20.76762) (xy 74.231012 -20.721772) (xy 74.266703 -20.680585)
			(xy 74.307893 -20.644896) (xy 74.353743 -20.615432) (xy 74.403319 -20.592793) (xy 74.455612 -20.57744)
			(xy 74.509558 -20.569685) (xy 74.536808 -20.569174) (xy 74.565586 -20.569698) (xy 74.622489 -20.578345)
			(xy 74.677447 -20.595441) (xy 74.729214 -20.620598) (xy 74.753216 -20.636484) (xy 74.788014 -20.660614)
			(xy 74.97826 -20.470368) (xy 74.97826 -20.29968) (xy 74.97774 -20.284705) (xy 74.969067 -20.256038)
			(xy 74.952444 -20.231125) (xy 74.929303 -20.212112) (xy 74.901639 -20.200637) (xy 74.871835 -20.197688)
			(xy 74.842459 -20.20352) (xy 74.816041 -20.21763) (xy 74.805032 -20.227798) (xy 74.783414 -20.248507)
			(xy 74.734926 -20.283612) (xy 74.681552 -20.310717) (xy 74.624601 -20.329155) (xy 74.565469 -20.338476)
			(xy 74.535538 -20.33905) (xy 74.50828 -20.33859) (xy 74.454319 -20.330836) (xy 74.402011 -20.315482)
			(xy 74.352421 -20.292839) (xy 74.306558 -20.263369) (xy 74.265356 -20.227671) (xy 74.229654 -20.186473)
			(xy 74.200179 -20.140613) (xy 74.177532 -20.091025) (xy 74.162172 -20.038718) (xy 74.154413 -19.984758)
			(xy 74.154413 -19.930242) (xy 74.162172 -19.876282) (xy 74.177532 -19.823975) (xy 74.200179 -19.774387)
			(xy 74.229654 -19.728527) (xy 74.265356 -19.687329) (xy 74.306558 -19.651631) (xy 74.352421 -19.622161)
			(xy 74.402011 -19.599518) (xy 74.454319 -19.584164) (xy 74.50828 -19.57641) (xy 74.535538 -19.576034)
			(xy 74.56547 -19.576599) (xy 74.624605 -19.585911) (xy 74.681558 -19.60435) (xy 74.734931 -19.63146)
			(xy 74.783413 -19.666577) (xy 74.805032 -19.687286) (xy 74.816013 -19.697472) (xy 74.84244 -19.711536)
			(xy 74.87181 -19.717335) (xy 74.9016 -19.714371) (xy 74.929251 -19.702898) (xy 74.952389 -19.683902)
			(xy 74.969027 -19.659014) (xy 74.977734 -19.630372) (xy 74.97826 -19.615404) (xy 74.97826 -18.529808)
			(xy 75.90282 -17.605248) (xy 78.08214 -17.605248) (xy 79.07274 -18.595848) (xy 80.17002 -18.595848)
			(xy 80.47228 -18.293588) (xy 80.47228 -15.664688) (xy 80.13192 -15.324328) (xy 73.47839 -15.324328)
			(xy 73.467976 -15.361158) (xy 73.459945 -15.387332) (xy 73.437428 -15.437236) (xy 73.408012 -15.48341)
			(xy 73.372301 -15.524908) (xy 73.331026 -15.560878) (xy 73.285036 -15.590582) (xy 73.235274 -15.61341)
			(xy 73.182761 -15.628894) (xy 73.128574 -15.636716) (xy 73.073826 -15.636716) (xy 73.019639 -15.628894)
			(xy 72.967126 -15.61341) (xy 72.917364 -15.590582) (xy 72.871374 -15.560878) (xy 72.830099 -15.524908)
			(xy 72.794388 -15.48341) (xy 72.764972 -15.437236) (xy 72.742455 -15.387332) (xy 72.734424 -15.361158)
			(xy 72.72401 -15.324328) (xy 72.20966 -15.324328) (xy 68.38188 -11.496548) (xy 63.22568 -11.496548)
			(xy 62.51448 -12.207748) (xy 62.51448 -13.096748) (xy 63.02248 -13.604748) (xy 66.07048 -13.604748)
			(xy 66.32194 -13.856208) (xy 66.32194 -17.148302) (xy 74.02525 -17.148302) (xy 74.029321 -17.09268)
			(xy 74.041447 -17.038243) (xy 74.06137 -16.986152) (xy 74.088666 -16.937517) (xy 74.122752 -16.893374)
			(xy 74.162901 -16.854665) (xy 74.208259 -16.822214) (xy 74.257859 -16.796713) (xy 74.310643 -16.778706)
			(xy 74.365486 -16.768576) (xy 74.42122 -16.766539) (xy 74.476657 -16.772639) (xy 74.530614 -16.786745)
			(xy 74.581943 -16.808557) (xy 74.629549 -16.837611) (xy 74.672417 -16.873286) (xy 74.709634 -16.914823)
			(xy 74.740407 -16.961336) (xy 74.764079 -17.011833) (xy 74.780147 -17.06524) (xy 74.788267 -17.120416)
			(xy 74.788776 -17.148302) (xy 74.788267 -17.176188) (xy 74.780147 -17.231364) (xy 74.764079 -17.284771)
			(xy 74.740407 -17.335268) (xy 74.709634 -17.381781) (xy 74.672417 -17.423318) (xy 74.629549 -17.458993)
			(xy 74.581943 -17.488047) (xy 74.530614 -17.509859) (xy 74.476657 -17.523965) (xy 74.42122 -17.530065)
			(xy 74.365486 -17.528028) (xy 74.310643 -17.517898) (xy 74.257859 -17.499891) (xy 74.208259 -17.47439)
			(xy 74.162901 -17.441939) (xy 74.122752 -17.40323) (xy 74.088666 -17.359087) (xy 74.06137 -17.310452)
			(xy 74.041447 -17.258361) (xy 74.029321 -17.203924) (xy 74.02525 -17.148302) (xy 66.32194 -17.148302)
			(xy 66.32194 -18.160746) (xy 74.02525 -18.160746) (xy 74.029321 -18.105124) (xy 74.041447 -18.050687)
			(xy 74.06137 -17.998596) (xy 74.088666 -17.949961) (xy 74.122752 -17.905818) (xy 74.162901 -17.867109)
			(xy 74.208259 -17.834658) (xy 74.257859 -17.809157) (xy 74.310643 -17.79115) (xy 74.365486 -17.78102)
			(xy 74.42122 -17.778983) (xy 74.476657 -17.785083) (xy 74.530614 -17.799189) (xy 74.581943 -17.821001)
			(xy 74.629549 -17.850055) (xy 74.672417 -17.88573) (xy 74.709634 -17.927267) (xy 74.740407 -17.97378)
			(xy 74.764079 -18.024277) (xy 74.780147 -18.077684) (xy 74.788267 -18.13286) (xy 74.788776 -18.160746)
			(xy 74.788267 -18.188632) (xy 74.780147 -18.243808) (xy 74.764079 -18.297215) (xy 74.740407 -18.347712)
			(xy 74.709634 -18.394225) (xy 74.672417 -18.435762) (xy 74.629549 -18.471437) (xy 74.581943 -18.500491)
			(xy 74.530614 -18.522303) (xy 74.476657 -18.536409) (xy 74.42122 -18.542509) (xy 74.365486 -18.540472)
			(xy 74.310643 -18.530342) (xy 74.257859 -18.512335) (xy 74.208259 -18.486834) (xy 74.162901 -18.454383)
			(xy 74.122752 -18.415674) (xy 74.088666 -18.371531) (xy 74.06137 -18.322896) (xy 74.041447 -18.270805)
			(xy 74.029321 -18.216368) (xy 74.02525 -18.160746) (xy 66.32194 -18.160746) (xy 66.32194 -20.892008)
			(xy 66.36258 -20.932648) (xy 65.71488 -21.580348) (xy 65.71488 -25.192482) (xy 70.55434 -25.192482)
			(xy 70.558411 -25.13686) (xy 70.570537 -25.082423) (xy 70.59046 -25.030332) (xy 70.617756 -24.981697)
			(xy 70.651842 -24.937554) (xy 70.691991 -24.898845) (xy 70.737349 -24.866394) (xy 70.786949 -24.840893)
			(xy 70.839733 -24.822886) (xy 70.894576 -24.812756) (xy 70.95031 -24.810719) (xy 71.005747 -24.816819)
			(xy 71.059704 -24.830925) (xy 71.111033 -24.852737) (xy 71.158639 -24.881791) (xy 71.201507 -24.917466)
			(xy 71.238724 -24.959003) (xy 71.269497 -25.005516) (xy 71.293169 -25.056013) (xy 71.309237 -25.10942)
			(xy 71.317357 -25.164596) (xy 71.317866 -25.192482) (xy 71.317357 -25.220368) (xy 71.309237 -25.275544)
			(xy 71.293169 -25.328951) (xy 71.269497 -25.379448) (xy 71.238724 -25.425961) (xy 71.201507 -25.467498)
			(xy 71.158639 -25.503173) (xy 71.111033 -25.532227) (xy 71.059704 -25.554039) (xy 71.005747 -25.568145)
			(xy 70.95031 -25.574245) (xy 70.894576 -25.572208) (xy 70.839733 -25.562078) (xy 70.786949 -25.544071)
			(xy 70.737349 -25.51857) (xy 70.691991 -25.486119) (xy 70.651842 -25.44741) (xy 70.617756 -25.403267)
			(xy 70.59046 -25.354632) (xy 70.570537 -25.302541) (xy 70.558411 -25.248104) (xy 70.55434 -25.192482)
			(xy 65.71488 -25.192482) (xy 65.71488 -25.466548) (xy 66.27368 -26.025348) (xy 72.00646 -26.025348)
		)
		(stroke
			(width 0)
			(type solid)
		)
		(fill yes)
		(layer "B.Cu")
		(net "P12V_OCP_V3_2")
	)
	(gr_poly
		(pts
			(xy 209.64525 -51.999896) (xy 209.644749 -51.899842) (xy 209.636743 -51.699895) (xy 209.620744 -51.500428)
			(xy 209.596776 -51.30176) (xy 209.564879 -51.104211) (xy 209.525104 -50.908096) (xy 209.477514 -50.71373)
			(xy 209.422186 -50.521423) (xy 209.359208 -50.331484) (xy 209.288681 -50.144217) (xy 209.210718 -49.959921)
			(xy 209.125444 -49.778892) (xy 209.032995 -49.60142) (xy 208.93352 -49.427789) (xy 208.827177 -49.258277)
			(xy 208.714138 -49.093156) (xy 208.594582 -48.932689) (xy 208.468702 -48.777134) (xy 208.336699 -48.62674)
			(xy 208.198785 -48.481748) (xy 208.05518 -48.34239) (xy 207.906114 -48.208889) (xy 207.751826 -48.081459)
			(xy 207.592564 -47.960304) (xy 207.428581 -47.845618) (xy 207.260142 -47.737585) (xy 207.087515 -47.636377)
			(xy 206.910976 -47.542157) (xy 206.73081 -47.455076) (xy 206.547303 -47.375273) (xy 206.360751 -47.302876)
			(xy 206.171452 -47.238001) (xy 205.979708 -47.180751) (xy 205.785827 -47.131219) (xy 205.59012 -47.089484)
			(xy 205.3929 -47.055612) (xy 205.194483 -47.029659) (xy 204.995186 -47.011664) (xy 204.795328 -47.001658)
			(xy 204.595231 -46.999656) (xy 204.395213 -47.005661) (xy 204.195596 -47.019664) (xy 203.996699 -47.041643)
			(xy 203.79884 -47.071562) (xy 203.602337 -47.109373) (xy 203.407504 -47.155016) (xy 203.214654 -47.208417)
			(xy 203.024094 -47.269492) (xy 202.836131 -47.338141) (xy 202.651064 -47.414257) (xy 202.469191 -47.497715)
			(xy 202.290803 -47.588384) (xy 202.116186 -47.686117) (xy 201.945618 -47.790758) (xy 201.779374 -47.90214)
			(xy 201.617719 -48.020084) (xy 201.460912 -48.144402) (xy 201.309205 -48.274893) (xy 201.162841 -48.41135)
			(xy 201.022053 -48.553554) (xy 200.887067 -48.701277) (xy 200.7581 -48.854282) (xy 200.635357 -49.012324)
			(xy 200.519037 -49.175151) (xy 200.409324 -49.342501) (xy 200.306394 -49.514107) (xy 200.210413 -49.689694)
			(xy 200.121533 -49.86898) (xy 200.039898 -50.051679) (xy 199.965639 -50.237498) (xy 199.898873 -50.426139)
			(xy 199.839708 -50.6173) (xy 199.788238 -50.810675) (xy 199.744547 -51.005955) (xy 199.708704 -51.202826)
			(xy 199.680766 -51.400974) (xy 199.660779 -51.600081) (xy 199.648773 -51.799828) (xy 199.64477 -51.999896)
			(xy 201.365618 -51.999896) (xy 201.369631 -51.837706) (xy 201.38166 -51.675912) (xy 201.401675 -51.514911)
			(xy 201.429628 -51.355097) (xy 201.465451 -51.196861) (xy 201.509055 -51.04059) (xy 201.560333 -50.886667)
			(xy 201.619161 -50.735468) (xy 201.685395 -50.587364) (xy 201.758871 -50.442716) (xy 201.839411 -50.301878)
			(xy 201.926818 -50.165196) (xy 202.020877 -50.033004) (xy 202.121358 -49.905625) (xy 202.228016 -49.783371)
			(xy 202.340589 -49.666542) (xy 202.458802 -49.555422) (xy 202.582365 -49.450285) (xy 202.710977 -49.351387)
			(xy 202.844323 -49.25897) (xy 202.982075 -49.173261) (xy 203.123898 -49.094468) (xy 203.269444 -49.022786)
			(xy 203.418356 -48.95839) (xy 203.570271 -48.901437) (xy 203.724817 -48.852066) (xy 203.881615 -48.810398)
			(xy 204.040282 -48.776535) (xy 204.200429 -48.750561) (xy 204.361665 -48.732538) (xy 204.523595 -48.722511)
			(xy 204.685823 -48.720505) (xy 204.847952 -48.726523) (xy 205.009584 -48.740553) (xy 205.170325 -48.762558)
			(xy 205.329781 -48.792485) (xy 205.487562 -48.830262) (xy 205.643281 -48.875795) (xy 205.796558 -48.928974)
			(xy 205.947018 -48.989667) (xy 206.094293 -49.057727) (xy 206.238021 -49.132987) (xy 206.377851 -49.215263)
			(xy 206.513442 -49.304354) (xy 206.64446 -49.40004) (xy 206.770587 -49.502089) (xy 206.891512 -49.610251)
			(xy 207.00694 -49.72426) (xy 207.116589 -49.843839) (xy 207.22019 -49.968693) (xy 207.31749 -50.098518)
			(xy 207.408251 -50.232997) (xy 207.49225 -50.371799) (xy 207.569282 -50.514585) (xy 207.639158 -50.661006)
			(xy 207.701708 -50.810704) (xy 207.756778 -50.963312) (xy 207.804234 -51.118456) (xy 207.843959 -51.275758)
			(xy 207.875856 -51.434831) (xy 207.899848 -51.595288) (xy 207.915875 -51.756734) (xy 207.923899 -51.918776)
			(xy 207.9244 -51.999896) (xy 207.923899 -52.081016) (xy 207.915875 -52.243058) (xy 207.899848 -52.404504)
			(xy 207.875856 -52.564961) (xy 207.843959 -52.724034) (xy 207.804234 -52.881336) (xy 207.756778 -53.03648)
			(xy 207.701708 -53.189088) (xy 207.639158 -53.338786) (xy 207.569282 -53.485207) (xy 207.49225 -53.627993)
			(xy 207.408251 -53.766795) (xy 207.31749 -53.901274) (xy 207.22019 -54.031099) (xy 207.116589 -54.155953)
			(xy 207.00694 -54.275532) (xy 206.891512 -54.389541) (xy 206.770587 -54.497703) (xy 206.64446 -54.599752)
			(xy 206.513442 -54.695438) (xy 206.377851 -54.784529) (xy 206.238021 -54.866805) (xy 206.094293 -54.942065)
			(xy 205.947018 -55.010125) (xy 205.796558 -55.070818) (xy 205.643281 -55.123997) (xy 205.487562 -55.16953)
			(xy 205.329781 -55.207307) (xy 205.170325 -55.237234) (xy 205.009584 -55.259239) (xy 204.847952 -55.273269)
			(xy 204.685823 -55.279287) (xy 204.523595 -55.277281) (xy 204.361665 -55.267254) (xy 204.200429 -55.249231)
			(xy 204.040282 -55.223257) (xy 203.881615 -55.189394) (xy 203.724817 -55.147726) (xy 203.570271 -55.098355)
			(xy 203.418356 -55.041402) (xy 203.269444 -54.977006) (xy 203.123898 -54.905324) (xy 202.982075 -54.826531)
			(xy 202.844323 -54.740822) (xy 202.710977 -54.648405) (xy 202.582365 -54.549507) (xy 202.458802 -54.44437)
			(xy 202.340589 -54.33325) (xy 202.228016 -54.216421) (xy 202.121358 -54.094167) (xy 202.020877 -53.966788)
			(xy 201.926818 -53.834596) (xy 201.839411 -53.697914) (xy 201.758871 -53.557076) (xy 201.685395 -53.412428)
			(xy 201.619161 -53.264324) (xy 201.560333 -53.113125) (xy 201.509055 -52.959202) (xy 201.465451 -52.802931)
			(xy 201.429628 -52.644695) (xy 201.401675 -52.484881) (xy 201.38166 -52.32388) (xy 201.369631 -52.162086)
			(xy 201.365618 -51.999896) (xy 199.64477 -51.999896) (xy 199.648773 -52.199964) (xy 199.660779 -52.399711)
			(xy 199.680766 -52.598818) (xy 199.708704 -52.796966) (xy 199.744547 -52.993837) (xy 199.788238 -53.189117)
			(xy 199.839708 -53.382492) (xy 199.898873 -53.573653) (xy 199.965639 -53.762294) (xy 200.039898 -53.948113)
			(xy 200.121533 -54.130812) (xy 200.210413 -54.310098) (xy 200.306394 -54.485685) (xy 200.409324 -54.657291)
			(xy 200.519037 -54.824641) (xy 200.635357 -54.987468) (xy 200.7581 -55.14551) (xy 200.887067 -55.298515)
			(xy 201.022053 -55.446238) (xy 201.162841 -55.588442) (xy 201.309205 -55.724899) (xy 201.460912 -55.85539)
			(xy 201.617719 -55.979708) (xy 201.779374 -56.097652) (xy 201.945618 -56.209034) (xy 202.116186 -56.313675)
			(xy 202.290803 -56.411408) (xy 202.469191 -56.502077) (xy 202.651064 -56.585535) (xy 202.836131 -56.661651)
			(xy 203.024094 -56.7303) (xy 203.214654 -56.791375) (xy 203.407504 -56.844776) (xy 203.602337 -56.890419)
			(xy 203.79884 -56.92823) (xy 203.996699 -56.958149) (xy 204.195596 -56.980128) (xy 204.395213 -56.994131)
			(xy 204.595231 -57.000136) (xy 204.795328 -56.998134) (xy 204.995186 -56.988128) (xy 205.194483 -56.970133)
			(xy 205.3929 -56.94418) (xy 205.59012 -56.910308) (xy 205.785827 -56.868573) (xy 205.979708 -56.819041)
			(xy 206.171452 -56.761791) (xy 206.360751 -56.696916) (xy 206.547303 -56.624519) (xy 206.73081 -56.544716)
			(xy 206.910976 -56.457635) (xy 207.087515 -56.363415) (xy 207.260142 -56.262207) (xy 207.428581 -56.154174)
			(xy 207.592564 -56.039488) (xy 207.751826 -55.918333) (xy 207.906114 -55.790903) (xy 208.05518 -55.657402)
			(xy 208.198785 -55.518044) (xy 208.336699 -55.373052) (xy 208.468702 -55.222658) (xy 208.594582 -55.067103)
			(xy 208.714138 -54.906636) (xy 208.827177 -54.741515) (xy 208.93352 -54.572003) (xy 209.032995 -54.398372)
			(xy 209.125444 -54.2209) (xy 209.210718 -54.039871) (xy 209.288681 -53.855575) (xy 209.359208 -53.668308)
			(xy 209.422186 -53.478369) (xy 209.477514 -53.286062) (xy 209.525104 -53.091696) (xy 209.564879 -52.895581)
			(xy 209.596776 -52.698032) (xy 209.620744 -52.499364) (xy 209.636743 -52.299897) (xy 209.644749 -52.09995)
		)
		(stroke
			(width 0)
			(type solid)
		)
		(fill yes)
		(layer "B.Cu")
		(net "GND")
	)
	(gr_poly
		(pts
			(xy 273.645122 -51.999896) (xy 273.644621 -51.899842) (xy 273.636615 -51.699895) (xy 273.620616 -51.500428)
			(xy 273.596648 -51.30176) (xy 273.564751 -51.104211) (xy 273.524976 -50.908096) (xy 273.477386 -50.71373)
			(xy 273.422058 -50.521423) (xy 273.35908 -50.331484) (xy 273.288553 -50.144217) (xy 273.21059 -49.959921)
			(xy 273.125316 -49.778892) (xy 273.032867 -49.60142) (xy 272.933392 -49.427789) (xy 272.827049 -49.258277)
			(xy 272.71401 -49.093156) (xy 272.594454 -48.932689) (xy 272.468574 -48.777134) (xy 272.336571 -48.62674)
			(xy 272.198657 -48.481748) (xy 272.055052 -48.34239) (xy 271.905986 -48.208889) (xy 271.751698 -48.081459)
			(xy 271.592436 -47.960304) (xy 271.428453 -47.845618) (xy 271.260014 -47.737585) (xy 271.087387 -47.636377)
			(xy 270.910848 -47.542157) (xy 270.730682 -47.455076) (xy 270.547175 -47.375273) (xy 270.360623 -47.302876)
			(xy 270.171324 -47.238001) (xy 269.97958 -47.180751) (xy 269.785699 -47.131219) (xy 269.589992 -47.089484)
			(xy 269.392772 -47.055612) (xy 269.194355 -47.029659) (xy 268.995058 -47.011664) (xy 268.7952 -47.001658)
			(xy 268.595103 -46.999656) (xy 268.395085 -47.005661) (xy 268.195468 -47.019664) (xy 267.996571 -47.041643)
			(xy 267.798712 -47.071562) (xy 267.602209 -47.109373) (xy 267.407376 -47.155016) (xy 267.214526 -47.208417)
			(xy 267.023966 -47.269492) (xy 266.836003 -47.338141) (xy 266.650936 -47.414257) (xy 266.469063 -47.497715)
			(xy 266.290675 -47.588384) (xy 266.116058 -47.686117) (xy 265.94549 -47.790758) (xy 265.779246 -47.90214)
			(xy 265.617591 -48.020084) (xy 265.460784 -48.144402) (xy 265.309077 -48.274893) (xy 265.162713 -48.41135)
			(xy 265.021925 -48.553554) (xy 264.886939 -48.701277) (xy 264.757972 -48.854282) (xy 264.635229 -49.012324)
			(xy 264.518909 -49.175151) (xy 264.409196 -49.342501) (xy 264.306266 -49.514107) (xy 264.210285 -49.689694)
			(xy 264.121405 -49.86898) (xy 264.03977 -50.051679) (xy 263.965511 -50.237498) (xy 263.898745 -50.426139)
			(xy 263.83958 -50.6173) (xy 263.78811 -50.810675) (xy 263.744419 -51.005955) (xy 263.708576 -51.202826)
			(xy 263.680638 -51.400974) (xy 263.660651 -51.600081) (xy 263.648645 -51.799828) (xy 263.644642 -51.999896)
			(xy 265.36549 -51.999896) (xy 265.369503 -51.837706) (xy 265.381532 -51.675912) (xy 265.401547 -51.514911)
			(xy 265.4295 -51.355097) (xy 265.465323 -51.196861) (xy 265.508927 -51.04059) (xy 265.560205 -50.886667)
			(xy 265.619033 -50.735468) (xy 265.685267 -50.587364) (xy 265.758743 -50.442716) (xy 265.839283 -50.301878)
			(xy 265.92669 -50.165196) (xy 266.020749 -50.033004) (xy 266.12123 -49.905625) (xy 266.227888 -49.783371)
			(xy 266.340461 -49.666542) (xy 266.458674 -49.555422) (xy 266.582237 -49.450285) (xy 266.710849 -49.351387)
			(xy 266.844195 -49.25897) (xy 266.981947 -49.173261) (xy 267.12377 -49.094468) (xy 267.269316 -49.022786)
			(xy 267.418228 -48.95839) (xy 267.570143 -48.901437) (xy 267.724689 -48.852066) (xy 267.881487 -48.810398)
			(xy 268.040154 -48.776535) (xy 268.200301 -48.750561) (xy 268.361537 -48.732538) (xy 268.523467 -48.722511)
			(xy 268.685695 -48.720505) (xy 268.847824 -48.726523) (xy 269.009456 -48.740553) (xy 269.170197 -48.762558)
			(xy 269.329653 -48.792485) (xy 269.487434 -48.830262) (xy 269.643153 -48.875795) (xy 269.79643 -48.928974)
			(xy 269.94689 -48.989667) (xy 270.094165 -49.057727) (xy 270.237893 -49.132987) (xy 270.377723 -49.215263)
			(xy 270.513314 -49.304354) (xy 270.644332 -49.40004) (xy 270.770459 -49.502089) (xy 270.891384 -49.610251)
			(xy 271.006812 -49.72426) (xy 271.116461 -49.843839) (xy 271.220062 -49.968693) (xy 271.317362 -50.098518)
			(xy 271.408123 -50.232997) (xy 271.492122 -50.371799) (xy 271.569154 -50.514585) (xy 271.63903 -50.661006)
			(xy 271.70158 -50.810704) (xy 271.75665 -50.963312) (xy 271.804106 -51.118456) (xy 271.843831 -51.275758)
			(xy 271.875728 -51.434831) (xy 271.89972 -51.595288) (xy 271.915747 -51.756734) (xy 271.923771 -51.918776)
			(xy 271.924272 -51.999896) (xy 271.923771 -52.081016) (xy 271.915747 -52.243058) (xy 271.89972 -52.404504)
			(xy 271.875728 -52.564961) (xy 271.843831 -52.724034) (xy 271.804106 -52.881336) (xy 271.75665 -53.03648)
			(xy 271.70158 -53.189088) (xy 271.63903 -53.338786) (xy 271.569154 -53.485207) (xy 271.492122 -53.627993)
			(xy 271.408123 -53.766795) (xy 271.317362 -53.901274) (xy 271.220062 -54.031099) (xy 271.116461 -54.155953)
			(xy 271.006812 -54.275532) (xy 270.891384 -54.389541) (xy 270.770459 -54.497703) (xy 270.644332 -54.599752)
			(xy 270.513314 -54.695438) (xy 270.377723 -54.784529) (xy 270.237893 -54.866805) (xy 270.094165 -54.942065)
			(xy 269.94689 -55.010125) (xy 269.79643 -55.070818) (xy 269.643153 -55.123997) (xy 269.487434 -55.16953)
			(xy 269.329653 -55.207307) (xy 269.170197 -55.237234) (xy 269.009456 -55.259239) (xy 268.847824 -55.273269)
			(xy 268.685695 -55.279287) (xy 268.523467 -55.277281) (xy 268.361537 -55.267254) (xy 268.200301 -55.249231)
			(xy 268.040154 -55.223257) (xy 267.881487 -55.189394) (xy 267.724689 -55.147726) (xy 267.570143 -55.098355)
			(xy 267.418228 -55.041402) (xy 267.269316 -54.977006) (xy 267.12377 -54.905324) (xy 266.981947 -54.826531)
			(xy 266.844195 -54.740822) (xy 266.710849 -54.648405) (xy 266.582237 -54.549507) (xy 266.458674 -54.44437)
			(xy 266.340461 -54.33325) (xy 266.227888 -54.216421) (xy 266.12123 -54.094167) (xy 266.020749 -53.966788)
			(xy 265.92669 -53.834596) (xy 265.839283 -53.697914) (xy 265.758743 -53.557076) (xy 265.685267 -53.412428)
			(xy 265.619033 -53.264324) (xy 265.560205 -53.113125) (xy 265.508927 -52.959202) (xy 265.465323 -52.802931)
			(xy 265.4295 -52.644695) (xy 265.401547 -52.484881) (xy 265.381532 -52.32388) (xy 265.369503 -52.162086)
			(xy 265.36549 -51.999896) (xy 263.644642 -51.999896) (xy 263.648645 -52.199964) (xy 263.660651 -52.399711)
			(xy 263.680638 -52.598818) (xy 263.708576 -52.796966) (xy 263.744419 -52.993837) (xy 263.78811 -53.189117)
			(xy 263.83958 -53.382492) (xy 263.898745 -53.573653) (xy 263.965511 -53.762294) (xy 264.03977 -53.948113)
			(xy 264.121405 -54.130812) (xy 264.210285 -54.310098) (xy 264.306266 -54.485685) (xy 264.409196 -54.657291)
			(xy 264.518909 -54.824641) (xy 264.635229 -54.987468) (xy 264.757972 -55.14551) (xy 264.886939 -55.298515)
			(xy 265.021925 -55.446238) (xy 265.162713 -55.588442) (xy 265.309077 -55.724899) (xy 265.460784 -55.85539)
			(xy 265.617591 -55.979708) (xy 265.779246 -56.097652) (xy 265.94549 -56.209034) (xy 266.116058 -56.313675)
			(xy 266.290675 -56.411408) (xy 266.469063 -56.502077) (xy 266.650936 -56.585535) (xy 266.836003 -56.661651)
			(xy 267.023966 -56.7303) (xy 267.214526 -56.791375) (xy 267.407376 -56.844776) (xy 267.602209 -56.890419)
			(xy 267.798712 -56.92823) (xy 267.996571 -56.958149) (xy 268.195468 -56.980128) (xy 268.395085 -56.994131)
			(xy 268.595103 -57.000136) (xy 268.7952 -56.998134) (xy 268.995058 -56.988128) (xy 269.194355 -56.970133)
			(xy 269.392772 -56.94418) (xy 269.589992 -56.910308) (xy 269.785699 -56.868573) (xy 269.97958 -56.819041)
			(xy 270.171324 -56.761791) (xy 270.360623 -56.696916) (xy 270.547175 -56.624519) (xy 270.730682 -56.544716)
			(xy 270.910848 -56.457635) (xy 271.087387 -56.363415) (xy 271.260014 -56.262207) (xy 271.428453 -56.154174)
			(xy 271.592436 -56.039488) (xy 271.751698 -55.918333) (xy 271.905986 -55.790903) (xy 272.055052 -55.657402)
			(xy 272.198657 -55.518044) (xy 272.336571 -55.373052) (xy 272.468574 -55.222658) (xy 272.594454 -55.067103)
			(xy 272.71401 -54.906636) (xy 272.827049 -54.741515) (xy 272.933392 -54.572003) (xy 273.032867 -54.398372)
			(xy 273.125316 -54.2209) (xy 273.21059 -54.039871) (xy 273.288553 -53.855575) (xy 273.35908 -53.668308)
			(xy 273.422058 -53.478369) (xy 273.477386 -53.286062) (xy 273.524976 -53.091696) (xy 273.564751 -52.895581)
			(xy 273.596648 -52.698032) (xy 273.620616 -52.499364) (xy 273.636615 -52.299897) (xy 273.644621 -52.09995)
		)
		(stroke
			(width 0)
			(type solid)
		)
		(fill yes)
		(layer "B.Cu")
		(net "GND")
	)
	(gr_poly
		(pts
			(xy 176.35855 -115.71224) (xy 176.409096 -115.71224) (xy 176.409096 -115.674902) (xy 176.46777 -115.584224)
			(xy 176.643538 -115.584224) (xy 176.702212 -115.674902) (xy 176.702212 -115.71224) (xy 176.75225 -115.71224)
			(xy 176.91481 -115.8748) (xy 176.98847 -115.8748) (xy 177.15103 -115.71224) (xy 177.209196 -115.71224)
			(xy 177.209196 -115.674902) (xy 177.26787 -115.584224) (xy 177.443638 -115.584224) (xy 177.502312 -115.674902)
			(xy 177.502312 -115.71224) (xy 177.55235 -115.71224) (xy 177.71491 -115.8748) (xy 177.78857 -115.8748)
			(xy 177.95113 -115.71224) (xy 178.008788 -115.71224) (xy 178.008788 -115.674902) (xy 178.067716 -115.584224)
			(xy 178.243484 -115.584224) (xy 178.301904 -115.674902) (xy 178.301904 -115.71224) (xy 178.808888 -115.71224)
			(xy 178.808888 -115.674902) (xy 178.867816 -115.584224) (xy 179.043584 -115.584224) (xy 179.102004 -115.674902)
			(xy 179.102004 -115.71224) (xy 179.15763 -115.71224) (xy 179.32273 -115.87734) (xy 179.38623 -115.87734)
			(xy 179.55133 -115.71224) (xy 179.608988 -115.71224) (xy 179.608988 -115.674902) (xy 179.667662 -115.584224)
			(xy 179.84343 -115.584224) (xy 179.902104 -115.674902) (xy 179.902104 -115.71224) (xy 179.95011 -115.71224)
			(xy 180.11267 -115.8748) (xy 180.19903 -115.8748) (xy 180.36159 -115.71224) (xy 180.409088 -115.71224)
			(xy 180.409088 -115.674902) (xy 180.467762 -115.584224) (xy 180.64353 -115.584224) (xy 180.702204 -115.674902)
			(xy 180.702204 -115.71224) (xy 180.74513 -115.71224) (xy 181.019704 -115.987068) (xy 181.03342 -115.987068)
			(xy 181.264052 -115.756436) (xy 181.264052 -115.756182) (xy 181.437534 -115.582954) (xy 181.50332 -115.517168)
			(xy 181.5592 -115.461288) (xy 181.5592 -115.241324) (xy 181.538779 -115.225615) (xy 181.502603 -115.188935)
			(xy 181.472553 -115.147088) (xy 181.449355 -115.101088) (xy 181.433572 -115.052046) (xy 181.425584 -115.001151)
			(xy 181.425585 -114.949632) (xy 181.433576 -114.898737) (xy 181.449362 -114.849697) (xy 181.472562 -114.803698)
			(xy 181.502614 -114.761853) (xy 181.538792 -114.725174) (xy 181.5592 -114.709448) (xy 181.5592 -114.441478)
			(xy 181.538775 -114.425769) (xy 181.502591 -114.389087) (xy 181.472532 -114.347238) (xy 181.449327 -114.301234)
			(xy 181.433537 -114.252188) (xy 181.425543 -114.201286) (xy 181.42554 -114.149761) (xy 181.433526 -114.098859)
			(xy 181.449309 -114.04981) (xy 181.472508 -114.003803) (xy 181.50256 -113.961949) (xy 181.538739 -113.925262)
			(xy 181.5592 -113.909602) (xy 181.5592 -112.841278) (xy 181.538775 -112.825569) (xy 181.502591 -112.788887)
			(xy 181.472532 -112.747038) (xy 181.449327 -112.701034) (xy 181.433537 -112.651988) (xy 181.425543 -112.601086)
			(xy 181.42554 -112.549561) (xy 181.433526 -112.498659) (xy 181.449309 -112.44961) (xy 181.472508 -112.403603)
			(xy 181.50256 -112.361749) (xy 181.538739 -112.325062) (xy 181.5592 -112.309402) (xy 181.5592 -112.041432)
			(xy 181.538778 -112.025723) (xy 181.502601 -111.989042) (xy 181.47255 -111.947195) (xy 181.449351 -111.901195)
			(xy 181.433567 -111.852153) (xy 181.425578 -111.801256) (xy 181.425579 -111.749737) (xy 181.433568 -111.69884)
			(xy 181.449354 -111.649799) (xy 181.472554 -111.603798) (xy 181.502606 -111.561952) (xy 181.538784 -111.525272)
			(xy 181.5592 -111.509556) (xy 181.5592 -111.288068) (xy 181.50332 -111.232188) (xy 181.437534 -111.166402)
			(xy 181.264052 -110.993174) (xy 181.264052 -110.99292) (xy 181.07914 -110.808008) (xy 180.984144 -110.808008)
			(xy 180.75529 -111.037116) (xy 180.702204 -111.037116) (xy 180.702204 -111.075978) (xy 180.64353 -111.166656)
			(xy 180.467762 -111.166656) (xy 180.409088 -111.075978) (xy 180.409088 -111.037116) (xy 180.36413 -111.037116)
			(xy 180.20665 -110.879636) (xy 180.10505 -110.879636) (xy 179.94757 -111.037116) (xy 179.902104 -111.037116)
			(xy 179.902104 -111.075978) (xy 179.84343 -111.166656) (xy 179.667662 -111.166656) (xy 179.608988 -111.075978)
			(xy 179.608988 -111.037116) (xy 179.54879 -111.037116) (xy 179.3621 -110.850172) (xy 179.17541 -111.037116)
			(xy 179.102512 -111.037116) (xy 179.102512 -111.075978) (xy 179.043584 -111.166656) (xy 178.867816 -111.166656)
			(xy 178.809396 -111.075978) (xy 178.809396 -111.037116) (xy 178.302412 -111.037116) (xy 178.302412 -111.075978)
			(xy 178.243484 -111.166656) (xy 178.067716 -111.166656) (xy 178.009296 -111.075978) (xy 178.009296 -111.037116)
			(xy 177.93335 -111.037116) (xy 177.74031 -110.843822) (xy 177.55235 -111.032036) (xy 177.502312 -111.032036)
			(xy 177.502312 -111.075978) (xy 177.443638 -111.166656) (xy 177.26787 -111.166656) (xy 177.209196 -111.075978)
			(xy 177.209196 -111.032036) (xy 177.15103 -111.032036) (xy 176.99355 -110.874556) (xy 176.91481 -110.874556)
			(xy 176.75733 -111.032036) (xy 176.702212 -111.032036) (xy 176.702212 -111.075978) (xy 176.643538 -111.166656)
			(xy 176.46777 -111.166656) (xy 176.409096 -111.075978) (xy 176.409096 -111.032036) (xy 176.34331 -111.032036)
			(xy 176.119536 -110.808008) (xy 176.022 -110.808008) (xy 175.54956 -111.280448) (xy 175.54956 -111.507778)
			(xy 175.570355 -111.523429) (xy 175.607211 -111.560173) (xy 175.637854 -111.602239) (xy 175.661524 -111.648588)
			(xy 175.677637 -111.698075) (xy 175.685794 -111.749475) (xy 175.685795 -111.801518) (xy 175.677638 -111.852919)
			(xy 175.661526 -111.902405) (xy 175.637857 -111.948755) (xy 175.607539 -111.990378) (xy 176.493932 -111.990378)
			(xy 176.493932 -111.578898) (xy 176.74971 -111.32312) (xy 177.16373 -111.32312) (xy 178.224688 -112.384332)
			(xy 178.243484 -112.384332) (xy 178.301904 -112.474756) (xy 178.301904 -112.51692) (xy 178.808888 -112.51692)
			(xy 178.808888 -112.474756) (xy 178.867816 -112.384332) (xy 178.884072 -112.384332) (xy 179.84851 -111.41964)
			(xy 180.45557 -111.41964) (xy 180.652928 -111.616998) (xy 180.652928 -112.018318) (xy 180.450744 -112.220248)
			(xy 180.632608 -112.401858) (xy 180.632608 -112.793018) (xy 180.379624 -113.045748) (xy 180.404008 -113.069878)
			(xy 180.404008 -113.692178) (xy 180.379624 -113.716308) (xy 180.622448 -113.958878) (xy 180.622448 -114.413538)
			(xy 180.443124 -114.592608) (xy 180.581808 -114.731038) (xy 180.581808 -115.208558) (xy 180.35651 -115.433856)
			(xy 179.95265 -115.433856) (xy 178.885596 -114.366548) (xy 178.867816 -114.366548) (xy 178.809396 -114.276124)
			(xy 178.809396 -114.237516) (xy 178.302412 -114.237516) (xy 178.302412 -114.276124) (xy 178.243484 -114.366548)
			(xy 178.207924 -114.366548) (xy 177.15611 -115.418616) (xy 176.73955 -115.418616) (xy 176.499012 -115.178078)
			(xy 176.499012 -114.748818) (xy 176.673256 -114.574828) (xy 176.510696 -114.412268) (xy 176.510696 -113.960148)
			(xy 176.739296 -113.731548) (xy 176.656492 -113.648998) (xy 176.656492 -113.102898) (xy 176.716436 -113.043208)
			(xy 176.496472 -112.823498) (xy 176.496472 -112.358678) (xy 176.679606 -112.175798) (xy 176.493932 -111.990378)
			(xy 175.607539 -111.990378) (xy 175.607216 -111.990822) (xy 175.57036 -112.027567) (xy 175.54956 -112.04321)
			(xy 175.54956 -112.307624) (xy 175.570351 -112.323275) (xy 175.607201 -112.360017) (xy 175.637836 -112.402082)
			(xy 175.6615 -112.448427) (xy 175.677607 -112.49791) (xy 175.685759 -112.549305) (xy 175.685756 -112.601342)
			(xy 175.677596 -112.652736) (xy 175.661482 -112.702216) (xy 175.637811 -112.748558) (xy 175.60717 -112.790618)
			(xy 175.570315 -112.827356) (xy 175.54956 -112.843056) (xy 175.54956 -113.907824) (xy 175.570351 -113.923475)
			(xy 175.607201 -113.960217) (xy 175.637836 -114.002282) (xy 175.6615 -114.048627) (xy 175.677607 -114.09811)
			(xy 175.685759 -114.149505) (xy 175.685756 -114.201542) (xy 175.677596 -114.252936) (xy 175.661482 -114.302416)
			(xy 175.637811 -114.348758) (xy 175.60717 -114.390818) (xy 175.570315 -114.427556) (xy 175.54956 -114.443256)
			(xy 175.54956 -114.70767) (xy 175.570355 -114.723321) (xy 175.607213 -114.760065) (xy 175.637857 -114.802132)
			(xy 175.661528 -114.848481) (xy 175.677642 -114.897968) (xy 175.6858 -114.94937) (xy 175.685802 -115.001414)
			(xy 175.677646 -115.052816) (xy 175.661534 -115.102303) (xy 175.637865 -115.148654) (xy 175.607224 -115.190723)
			(xy 175.570368 -115.227468) (xy 175.54956 -115.243102) (xy 175.54956 -115.489228) (xy 176.0474 -115.987068)
			(xy 176.083976 -115.987068)
		)
		(stroke
			(width 0)
			(type solid)
		)
		(fill yes)
		(layer "B.Cu")
		(net "GND")
	)
	(gr_poly
		(pts
			(xy 54.324758 -365.592106) (xy 54.324758 -363.77499) (xy 56.338978 -361.76077) (xy 56.338978 -353.83724)
			(xy 56.338543 -353.827175) (xy 56.330811 -353.808589) (xy 56.323992 -353.801172) (xy 56.303164 -353.780344)
			(xy 56.295766 -353.773499) (xy 56.277167 -353.76577) (xy 56.267096 -353.765358) (xy 51.642518 -353.765358)
			(xy 51.632456 -353.765798) (xy 51.613878 -353.77354) (xy 51.60645 -353.780344) (xy 51.599084 -353.78771)
			(xy 51.59223 -353.795105) (xy 51.584486 -353.813704) (xy 51.584098 -353.823778) (xy 51.584098 -355.244146)
			(xy 55.43499 -355.244146) (xy 55.439061 -355.188524) (xy 55.451187 -355.134087) (xy 55.47111 -355.081996)
			(xy 55.498406 -355.033361) (xy 55.532492 -354.989218) (xy 55.572641 -354.950509) (xy 55.617999 -354.918058)
			(xy 55.667599 -354.892557) (xy 55.720383 -354.87455) (xy 55.775226 -354.86442) (xy 55.83096 -354.862383)
			(xy 55.886397 -354.868483) (xy 55.940354 -354.882589) (xy 55.991683 -354.904401) (xy 56.039289 -354.933455)
			(xy 56.082157 -354.96913) (xy 56.119374 -355.010667) (xy 56.150147 -355.05718) (xy 56.173819 -355.107677)
			(xy 56.189887 -355.161084) (xy 56.198007 -355.21626) (xy 56.198516 -355.244146) (xy 56.198007 -355.272032)
			(xy 56.189887 -355.327208) (xy 56.173819 -355.380615) (xy 56.150147 -355.431112) (xy 56.119374 -355.477625)
			(xy 56.082157 -355.519162) (xy 56.039289 -355.554837) (xy 55.991683 -355.583891) (xy 55.940354 -355.605703)
			(xy 55.886397 -355.619809) (xy 55.83096 -355.625909) (xy 55.775226 -355.623872) (xy 55.720383 -355.613742)
			(xy 55.667599 -355.595735) (xy 55.617999 -355.570234) (xy 55.572641 -355.537783) (xy 55.532492 -355.499074)
			(xy 55.498406 -355.454931) (xy 55.47111 -355.406296) (xy 55.451187 -355.354205) (xy 55.439061 -355.299768)
			(xy 55.43499 -355.244146) (xy 51.584098 -355.244146) (xy 51.584098 -355.793548) (xy 51.58453 -355.803614)
			(xy 51.592256 -355.822206) (xy 51.599084 -355.829616) (xy 51.877214 -356.107746) (xy 55.434736 -356.107746)
			(xy 55.438809 -356.052087) (xy 55.450944 -355.997614) (xy 55.47088 -355.945488) (xy 55.498194 -355.89682)
			(xy 55.532302 -355.852648) (xy 55.572479 -355.813913) (xy 55.617867 -355.781441) (xy 55.667499 -355.755923)
			(xy 55.720319 -355.737904) (xy 55.775198 -355.727767) (xy 55.830969 -355.725729) (xy 55.886443 -355.731832)
			(xy 55.940436 -355.745948) (xy 55.991799 -355.767775) (xy 56.039437 -355.796848) (xy 56.082333 -355.832547)
			(xy 56.119575 -355.874111) (xy 56.150369 -355.920655) (xy 56.174057 -355.971186) (xy 56.190135 -356.024628)
			(xy 56.198261 -356.079842) (xy 56.19877 -356.107746) (xy 56.198261 -356.13565) (xy 56.190135 -356.190864)
			(xy 56.174057 -356.244306) (xy 56.150369 -356.294837) (xy 56.119575 -356.341381) (xy 56.082333 -356.382945)
			(xy 56.039437 -356.418644) (xy 55.991799 -356.447717) (xy 55.940436 -356.469544) (xy 55.886443 -356.48366)
			(xy 55.830969 -356.489763) (xy 55.775198 -356.487725) (xy 55.720319 -356.477588) (xy 55.667499 -356.459569)
			(xy 55.617867 -356.434051) (xy 55.572479 -356.401579) (xy 55.532302 -356.362844) (xy 55.498194 -356.318672)
			(xy 55.47088 -356.270004) (xy 55.450944 -356.217878) (xy 55.438809 -356.163405) (xy 55.434736 -356.107746)
			(xy 51.877214 -356.107746) (xy 52.543456 -356.773988) (xy 52.550309 -356.781384) (xy 52.558055 -356.799982)
			(xy 52.558442 -356.810056) (xy 52.558442 -356.996746) (xy 55.434736 -356.996746) (xy 55.438809 -356.941087)
			(xy 55.450944 -356.886614) (xy 55.47088 -356.834488) (xy 55.498194 -356.78582) (xy 55.532302 -356.741648)
			(xy 55.572479 -356.702913) (xy 55.617867 -356.670441) (xy 55.667499 -356.644923) (xy 55.720319 -356.626904)
			(xy 55.775198 -356.616767) (xy 55.830969 -356.614729) (xy 55.886443 -356.620832) (xy 55.940436 -356.634948)
			(xy 55.991799 -356.656775) (xy 56.039437 -356.685848) (xy 56.082333 -356.721547) (xy 56.119575 -356.763111)
			(xy 56.150369 -356.809655) (xy 56.174057 -356.860186) (xy 56.190135 -356.913628) (xy 56.198261 -356.968842)
			(xy 56.19877 -356.996746) (xy 56.198261 -357.02465) (xy 56.190135 -357.079864) (xy 56.174057 -357.133306)
			(xy 56.150369 -357.183837) (xy 56.119575 -357.230381) (xy 56.082333 -357.271945) (xy 56.039437 -357.307644)
			(xy 55.991799 -357.336717) (xy 55.940436 -357.358544) (xy 55.886443 -357.37266) (xy 55.830969 -357.378763)
			(xy 55.775198 -357.376725) (xy 55.720319 -357.366588) (xy 55.667499 -357.348569) (xy 55.617867 -357.323051)
			(xy 55.572479 -357.290579) (xy 55.532302 -357.251844) (xy 55.498194 -357.207672) (xy 55.47088 -357.159004)
			(xy 55.450944 -357.106878) (xy 55.438809 -357.052405) (xy 55.434736 -356.996746) (xy 52.558442 -356.996746)
			(xy 52.558442 -358.953308) (xy 52.558016 -358.963376) (xy 52.550293 -358.981973) (xy 52.543456 -358.989376)
			(xy 51.897534 -359.635298) (xy 51.890132 -359.642134) (xy 51.871534 -359.649845) (xy 51.861466 -359.650284)
			(xy 46.628558 -359.650284) (xy 46.618492 -359.649853) (xy 46.5999 -359.642126) (xy 46.59249 -359.635298)
			(xy 45.824648 -358.867456) (xy 45.817803 -358.860057) (xy 45.810077 -358.841459) (xy 45.809662 -358.831388)
			(xy 45.809662 -355.750622) (xy 45.810101 -355.740559) (xy 45.817842 -355.721981) (xy 45.824648 -355.714554)
			(xy 46.177708 -355.361494) (xy 46.184553 -355.354095) (xy 46.192284 -355.335497) (xy 46.192694 -355.325426)
			(xy 46.192694 -354.056442) (xy 46.19226 -354.046377) (xy 46.18453 -354.027788) (xy 46.177708 -354.020374)
			(xy 45.937678 -353.780344) (xy 45.930281 -353.773496) (xy 45.911682 -353.765763) (xy 45.90161 -353.765358)
			(xy 42.089578 -353.765358) (xy 42.079511 -353.765787) (xy 42.060918 -353.773513) (xy 42.05351 -353.780344)
			(xy 41.8719 -353.961954) (xy 41.865062 -353.969355) (xy 41.857347 -353.987954) (xy 41.856914 -353.998022)
			(xy 41.856914 -356.029768) (xy 41.85735 -356.039832) (xy 41.865083 -356.058418) (xy 41.8719 -356.065836)
			(xy 42.635932 -356.829868) (xy 42.642775 -356.837267) (xy 42.650496 -356.855866) (xy 42.650918 -356.865936)
			(xy 42.650918 -363.187519) (xy 51.221321 -363.187519) (xy 51.228907 -363.105659) (xy 51.244016 -363.024849)
			(xy 51.26652 -362.945778) (xy 51.296226 -362.869122) (xy 51.33288 -362.795535) (xy 51.37617 -362.725646)
			(xy 51.425727 -362.66005) (xy 51.481126 -362.599309) (xy 51.5112 -362.571284) (xy 51.5112 -362.570776)
			(xy 51.54191 -362.543471) (xy 51.607519 -362.493982) (xy 51.677411 -362.450752) (xy 51.750991 -362.41415)
			(xy 51.827632 -362.384486) (xy 51.906681 -362.362014) (xy 51.987465 -362.346925) (xy 52.069295 -362.339348)
			(xy 52.110386 -362.338874) (xy 52.152749 -362.33929) (xy 52.237093 -362.347342) (xy 52.320289 -362.363376)
			(xy 52.401584 -362.387245) (xy 52.480242 -362.418734) (xy 52.555551 -362.457557) (xy 52.626828 -362.503363)
			(xy 52.693429 -362.555738) (xy 52.754749 -362.614205) (xy 52.810234 -362.678237) (xy 52.85938 -362.747253)
			(xy 52.901744 -362.820629) (xy 52.936941 -362.897699) (xy 52.964653 -362.977766) (xy 52.984628 -363.060105)
			(xy 52.996686 -363.143969) (xy 53.000718 -363.2286) (xy 52.996686 -363.313231) (xy 52.984628 -363.397095)
			(xy 52.964653 -363.479434) (xy 52.936941 -363.559501) (xy 52.901744 -363.636571) (xy 52.85938 -363.709947)
			(xy 52.810234 -363.778963) (xy 52.754749 -363.842995) (xy 52.693429 -363.901462) (xy 52.626828 -363.953837)
			(xy 52.555551 -363.999643) (xy 52.480242 -364.038466) (xy 52.401584 -364.069955) (xy 52.320289 -364.093824)
			(xy 52.237093 -364.109858) (xy 52.152749 -364.11791) (xy 52.110386 -364.118398) (xy 52.069295 -364.117944)
			(xy 51.987462 -364.110366) (xy 51.906677 -364.095276) (xy 51.827627 -364.072803) (xy 51.750985 -364.043138)
			(xy 51.677404 -364.006534) (xy 51.607512 -363.963302) (xy 51.541902 -363.913811) (xy 51.5112 -363.886496)
			(xy 51.5112 -363.885988) (xy 51.48116 -363.857925) (xy 51.425758 -363.797187) (xy 51.376198 -363.731594)
			(xy 51.332904 -363.661707) (xy 51.296245 -363.588122) (xy 51.266535 -363.511468) (xy 51.244027 -363.432398)
			(xy 51.228914 -363.351589) (xy 51.221323 -363.26973) (xy 51.221321 -363.187519) (xy 42.650918 -363.187519)
			(xy 42.650918 -363.941868) (xy 44.6024 -365.89335) (xy 54.02326 -365.89335)
		)
		(stroke
			(width 0)
			(type solid)
		)
		(fill yes)
		(layer "B.Cu")
		(net "SW_P12V_PVCCFA_EHV_FIVRA_CPU1_L")
	)
	(gr_poly
		(pts
			(xy 411.508956 -257.846576) (xy 411.508956 -257.07975) (xy 411.79623 -256.792222) (xy 413.935926 -256.792222)
			(xy 414.1978 -256.530348) (xy 414.1978 -251.348748) (xy 414.019492 -251.17044) (xy 412.14421 -251.17044)
			(xy 412.123137 -251.182869) (xy 412.078306 -251.202457) (xy 412.031211 -251.215711) (xy 411.982744 -251.222379)
			(xy 411.958282 -251.222764) (xy 411.933823 -251.222353) (xy 411.885366 -251.215656) (xy 411.838277 -251.202402)
			(xy 411.79344 -251.182841) (xy 411.772354 -251.17044) (xy 409.93441 -251.17044) (xy 409.913337 -251.182869)
			(xy 409.868506 -251.202457) (xy 409.821411 -251.215711) (xy 409.772944 -251.222379) (xy 409.748482 -251.222764)
			(xy 409.724023 -251.222353) (xy 409.675566 -251.215656) (xy 409.628477 -251.202402) (xy 409.58364 -251.182841)
			(xy 409.562554 -251.17044) (xy 405.205692 -251.17044) (xy 405.082756 -251.293376) (xy 405.082756 -251.743443)
			(xy 405.292804 -251.743443) (xy 405.292804 -251.690145) (xy 405.300747 -251.637441) (xy 405.316457 -251.586511)
			(xy 405.339583 -251.53849) (xy 405.369607 -251.494453) (xy 405.405859 -251.455382) (xy 405.44753 -251.422151)
			(xy 405.493688 -251.395502) (xy 405.543302 -251.37603) (xy 405.595264 -251.36417) (xy 405.648414 -251.360187)
			(xy 405.701564 -251.36417) (xy 405.753526 -251.37603) (xy 405.80314 -251.395502) (xy 405.849298 -251.422151)
			(xy 405.890969 -251.455382) (xy 405.927221 -251.494453) (xy 405.957245 -251.53849) (xy 405.980371 -251.586511)
			(xy 405.996081 -251.637441) (xy 406.004024 -251.690145) (xy 406.004522 -251.716794) (xy 406.004024 -251.743443)
			(xy 407.502604 -251.743443) (xy 407.502604 -251.690145) (xy 407.510547 -251.637441) (xy 407.526257 -251.586511)
			(xy 407.549383 -251.53849) (xy 407.579407 -251.494453) (xy 407.615659 -251.455382) (xy 407.65733 -251.422151)
			(xy 407.703488 -251.395502) (xy 407.753102 -251.37603) (xy 407.805064 -251.36417) (xy 407.858214 -251.360187)
			(xy 407.911364 -251.36417) (xy 407.963326 -251.37603) (xy 408.01294 -251.395502) (xy 408.059098 -251.422151)
			(xy 408.100769 -251.455382) (xy 408.137021 -251.494453) (xy 408.167045 -251.53849) (xy 408.190171 -251.586511)
			(xy 408.205881 -251.637441) (xy 408.213824 -251.690145) (xy 408.214322 -251.716794) (xy 408.213824 -251.743443)
			(xy 412.836604 -251.743443) (xy 412.836604 -251.690145) (xy 412.844547 -251.637441) (xy 412.860257 -251.586511)
			(xy 412.883383 -251.53849) (xy 412.913407 -251.494453) (xy 412.949659 -251.455382) (xy 412.99133 -251.422151)
			(xy 413.037488 -251.395502) (xy 413.087102 -251.37603) (xy 413.139064 -251.36417) (xy 413.192214 -251.360187)
			(xy 413.245364 -251.36417) (xy 413.297326 -251.37603) (xy 413.34694 -251.395502) (xy 413.393098 -251.422151)
			(xy 413.434769 -251.455382) (xy 413.471021 -251.494453) (xy 413.501045 -251.53849) (xy 413.524171 -251.586511)
			(xy 413.539881 -251.637441) (xy 413.547824 -251.690145) (xy 413.548322 -251.716794) (xy 413.547824 -251.743443)
			(xy 413.539881 -251.796147) (xy 413.524171 -251.847077) (xy 413.501045 -251.895098) (xy 413.471021 -251.939135)
			(xy 413.434769 -251.978206) (xy 413.393098 -252.011437) (xy 413.34694 -252.038086) (xy 413.297326 -252.057558)
			(xy 413.245364 -252.069418) (xy 413.192214 -252.073402) (xy 413.139064 -252.069418) (xy 413.087102 -252.057558)
			(xy 413.037488 -252.038086) (xy 412.99133 -252.011437) (xy 412.949659 -251.978206) (xy 412.913407 -251.939135)
			(xy 412.883383 -251.895098) (xy 412.860257 -251.847077) (xy 412.844547 -251.796147) (xy 412.836604 -251.743443)
			(xy 408.213824 -251.743443) (xy 408.205881 -251.796147) (xy 408.190171 -251.847077) (xy 408.167045 -251.895098)
			(xy 408.137021 -251.939135) (xy 408.100769 -251.978206) (xy 408.059098 -252.011437) (xy 408.01294 -252.038086)
			(xy 407.963326 -252.057558) (xy 407.911364 -252.069418) (xy 407.858214 -252.073402) (xy 407.805064 -252.069418)
			(xy 407.753102 -252.057558) (xy 407.703488 -252.038086) (xy 407.65733 -252.011437) (xy 407.615659 -251.978206)
			(xy 407.579407 -251.939135) (xy 407.549383 -251.895098) (xy 407.526257 -251.847077) (xy 407.510547 -251.796147)
			(xy 407.502604 -251.743443) (xy 406.004024 -251.743443) (xy 405.996081 -251.796147) (xy 405.980371 -251.847077)
			(xy 405.957245 -251.895098) (xy 405.927221 -251.939135) (xy 405.890969 -251.978206) (xy 405.849298 -252.011437)
			(xy 405.80314 -252.038086) (xy 405.753526 -252.057558) (xy 405.701564 -252.069418) (xy 405.648414 -252.073402)
			(xy 405.595264 -252.069418) (xy 405.543302 -252.057558) (xy 405.493688 -252.038086) (xy 405.44753 -252.011437)
			(xy 405.405859 -251.978206) (xy 405.369607 -251.939135) (xy 405.339583 -251.895098) (xy 405.316457 -251.847077)
			(xy 405.300747 -251.796147) (xy 405.292804 -251.743443) (xy 405.082756 -251.743443) (xy 405.082756 -254.258968)
			(xy 407.266782 -254.258968) (xy 407.266782 -254.174432) (xy 407.274582 -254.090256) (xy 407.290116 -254.007159)
			(xy 407.313251 -253.92585) (xy 407.34379 -253.847022) (xy 407.381473 -253.771348) (xy 407.425977 -253.699475)
			(xy 407.476923 -253.632014) (xy 407.533876 -253.569542) (xy 407.596351 -253.512592) (xy 407.663814 -253.46165)
			(xy 407.73569 -253.417149) (xy 407.811366 -253.379471) (xy 407.890195 -253.348936) (xy 407.971505 -253.325805)
			(xy 408.054603 -253.310275) (xy 408.13878 -253.302479) (xy 408.181048 -253.302008) (xy 409.425648 -253.302008)
			(xy 409.467909 -253.302574) (xy 409.552071 -253.310377) (xy 409.635154 -253.325912) (xy 409.716449 -253.349046)
			(xy 409.795262 -253.379582) (xy 409.870922 -253.41726) (xy 409.942783 -253.461758) (xy 410.010232 -253.512696)
			(xy 410.072694 -253.56964) (xy 410.129635 -253.632105) (xy 410.180569 -253.699556) (xy 410.225063 -253.77142)
			(xy 410.262737 -253.847082) (xy 410.293269 -253.925897) (xy 410.316399 -254.007193) (xy 410.330486 -254.08255)
			(xy 411.225238 -254.08255) (xy 411.225744 -254.055504) (xy 411.233919 -254.002033) (xy 411.250087 -253.950414)
			(xy 411.273877 -253.901835) (xy 411.304742 -253.857413) (xy 411.341971 -253.81817) (xy 411.384707 -253.785011)
			(xy 411.431967 -253.758697) (xy 411.45714 -253.748794) (xy 411.467554 -253.744984) (xy 411.97276 -253.239778)
			(xy 411.973522 -253.219458) (xy 411.974818 -253.190076) (xy 411.984051 -253.13199) (xy 412.000651 -253.075566)
			(xy 412.024344 -253.021734) (xy 412.054739 -252.971382) (xy 412.091335 -252.925339) (xy 412.133529 -252.884365)
			(xy 412.180625 -252.849135) (xy 412.231847 -252.82023) (xy 412.286351 -252.798126) (xy 412.343237 -252.783187)
			(xy 412.401568 -252.775661) (xy 412.430976 -252.775212) (xy 412.460945 -252.775684) (xy 412.520371 -252.783504)
			(xy 412.578268 -252.799016) (xy 412.633645 -252.821952) (xy 412.685554 -252.85192) (xy 412.733107 -252.888407)
			(xy 412.77549 -252.93079) (xy 412.811978 -252.978343) (xy 412.841947 -253.030252) (xy 412.864883 -253.085628)
			(xy 412.880395 -253.143525) (xy 412.888216 -253.202951) (xy 412.888684 -253.23292) (xy 412.888213 -253.262323)
			(xy 412.880667 -253.320644) (xy 412.865715 -253.377518) (xy 412.843602 -253.432009) (xy 412.814693 -253.48322)
			(xy 412.779464 -253.530306) (xy 412.738495 -253.572494) (xy 412.692461 -253.609088) (xy 412.64212 -253.639485)
			(xy 412.588301 -253.663186) (xy 412.53189 -253.679799) (xy 412.473815 -253.689051) (xy 412.444438 -253.690374)
			(xy 412.424118 -253.691136) (xy 411.918912 -254.196342) (xy 411.915102 -254.206756) (xy 411.905177 -254.231919)
			(xy 411.87886 -254.279173) (xy 411.8457 -254.321905) (xy 411.80646 -254.359131) (xy 411.762043 -254.389997)
			(xy 411.713469 -254.413791) (xy 411.661856 -254.429966) (xy 411.60839 -254.438152) (xy 411.581346 -254.438658)
			(xy 411.553367 -254.438017) (xy 411.498096 -254.42927) (xy 411.444874 -254.411985) (xy 411.395011 -254.386587)
			(xy 411.349735 -254.353701) (xy 411.310161 -254.314138) (xy 411.277263 -254.268871) (xy 411.251852 -254.219015)
			(xy 411.234552 -254.165798) (xy 411.225791 -254.110529) (xy 411.225238 -254.08255) (xy 410.330486 -254.08255)
			(xy 410.33193 -254.090277) (xy 410.339728 -254.174439) (xy 410.339728 -254.258961) (xy 410.33193 -254.343123)
			(xy 410.316399 -254.426207) (xy 410.293269 -254.507503) (xy 410.262737 -254.586318) (xy 410.225063 -254.66198)
			(xy 410.180569 -254.733844) (xy 410.129635 -254.801295) (xy 410.072694 -254.86376) (xy 410.010232 -254.920704)
			(xy 409.942783 -254.971642) (xy 409.870922 -255.01614) (xy 409.795262 -255.053818) (xy 409.716449 -255.084354)
			(xy 409.635154 -255.107488) (xy 409.552071 -255.123023) (xy 409.467909 -255.130826) (xy 409.425648 -255.131316)
			(xy 408.181048 -255.131316) (xy 408.13878 -255.130921) (xy 408.054603 -255.123125) (xy 407.971505 -255.107595)
			(xy 407.890195 -255.084464) (xy 407.811366 -255.053929) (xy 407.73569 -255.016251) (xy 407.663814 -254.97175)
			(xy 407.596351 -254.920808) (xy 407.533876 -254.863858) (xy 407.476923 -254.801386) (xy 407.425977 -254.733925)
			(xy 407.381473 -254.662052) (xy 407.34379 -254.586378) (xy 407.313251 -254.50755) (xy 407.290116 -254.426241)
			(xy 407.274582 -254.343144) (xy 407.266782 -254.258968) (xy 405.082756 -254.258968) (xy 405.082756 -257.744468)
			(xy 405.337264 -257.998976) (xy 411.356556 -257.998976)
		)
		(stroke
			(width 0)
			(type solid)
		)
		(fill yes)
		(layer "B.Cu")
		(net "PVCCFA_EHV_FIVRA_CPU0")
	)
	(gr_poly
		(pts
			(xy 407.610056 -184.561734) (xy 407.646378 -184.546494) (xy 407.785316 -184.407556) (xy 407.785316 -166.74973)
			(xy 407.624534 -166.588948) (xy 399.54962 -166.588948) (xy 398.8689 -167.269668) (xy 398.8689 -168.983152)
			(xy 399.642589 -168.983152) (xy 399.646611 -168.897432) (xy 399.658642 -168.812464) (xy 399.678578 -168.728997)
			(xy 399.706241 -168.647763) (xy 399.74139 -168.569477) (xy 399.783716 -168.494826) (xy 399.832845 -168.424467)
			(xy 399.888348 -168.359017) (xy 399.949735 -168.299053) (xy 400.016468 -168.2451) (xy 400.08796 -168.197633)
			(xy 400.163582 -168.157069) (xy 400.242671 -168.123765) (xy 400.324531 -168.098013) (xy 400.408442 -168.08004)
			(xy 400.493668 -168.070004) (xy 400.57946 -168.067992) (xy 400.665062 -168.074023) (xy 400.749724 -168.088043)
			(xy 400.832701 -168.109929) (xy 400.913264 -168.13949) (xy 400.990704 -168.176464) (xy 401.064343 -168.220528)
			(xy 401.133531 -168.271294) (xy 401.197662 -168.328315) (xy 401.256171 -168.391091) (xy 401.308544 -168.459071)
			(xy 401.354322 -168.531656) (xy 401.393102 -168.608208) (xy 401.424543 -168.688056) (xy 401.448369 -168.770497)
			(xy 401.46437 -168.854807) (xy 401.472405 -168.940245) (xy 401.472908 -168.983152) (xy 401.472405 -169.026059)
			(xy 401.46437 -169.111497) (xy 401.448369 -169.195807) (xy 401.424543 -169.278248) (xy 401.393102 -169.358096)
			(xy 401.354322 -169.434648) (xy 401.308544 -169.507233) (xy 401.256171 -169.575213) (xy 401.197662 -169.637989)
			(xy 401.133531 -169.69501) (xy 401.064343 -169.745776) (xy 400.990704 -169.78984) (xy 400.913264 -169.826814)
			(xy 400.832701 -169.856375) (xy 400.749724 -169.878261) (xy 400.665062 -169.892281) (xy 400.57946 -169.898312)
			(xy 400.493668 -169.8963) (xy 400.408442 -169.886264) (xy 400.324531 -169.868291) (xy 400.242671 -169.842539)
			(xy 400.163582 -169.809235) (xy 400.08796 -169.768671) (xy 400.016468 -169.721204) (xy 399.949735 -169.667251)
			(xy 399.888348 -169.607287) (xy 399.832845 -169.541837) (xy 399.783716 -169.471478) (xy 399.74139 -169.396827)
			(xy 399.706241 -169.318541) (xy 399.678578 -169.237307) (xy 399.658642 -169.15384) (xy 399.646611 -169.068872)
			(xy 399.642589 -168.983152) (xy 398.8689 -168.983152) (xy 398.8689 -171.770548) (xy 399.668492 -171.770548)
			(xy 399.668492 -170.195748) (xy 399.668931 -170.18236) (xy 399.675852 -170.156493) (xy 399.689232 -170.1333)
			(xy 399.708162 -170.114362) (xy 399.731349 -170.10097) (xy 399.757212 -170.094038) (xy 399.7706 -170.09364)
			(xy 401.3454 -170.09364) (xy 401.358794 -170.09399) (xy 401.38467 -170.100926) (xy 401.407868 -170.114324)
			(xy 401.426806 -170.133271) (xy 401.440193 -170.156475) (xy 401.447116 -170.182353) (xy 401.447508 -170.195748)
			(xy 401.447508 -171.770548) (xy 401.447113 -171.783935) (xy 401.440173 -171.809796) (xy 401.426779 -171.832979)
			(xy 401.407841 -171.851908) (xy 401.384651 -171.865292) (xy 401.358788 -171.87222) (xy 401.3454 -171.872656)
			(xy 399.7706 -171.872656) (xy 399.757219 -171.872172) (xy 399.731368 -171.865247) (xy 399.708188 -171.851869)
			(xy 399.68926 -171.83295) (xy 399.675871 -171.809777) (xy 399.668935 -171.783929) (xy 399.668492 -171.770548)
			(xy 398.8689 -171.770548) (xy 398.8689 -175.206152) (xy 399.642589 -175.206152) (xy 399.646611 -175.120432)
			(xy 399.658642 -175.035464) (xy 399.678578 -174.951997) (xy 399.706241 -174.870763) (xy 399.74139 -174.792477)
			(xy 399.783716 -174.717826) (xy 399.832845 -174.647467) (xy 399.888348 -174.582017) (xy 399.949735 -174.522053)
			(xy 400.016468 -174.4681) (xy 400.08796 -174.420633) (xy 400.163582 -174.380069) (xy 400.242671 -174.346765)
			(xy 400.324531 -174.321013) (xy 400.408442 -174.30304) (xy 400.493668 -174.293004) (xy 400.57946 -174.290992)
			(xy 400.665062 -174.297023) (xy 400.749724 -174.311043) (xy 400.832701 -174.332929) (xy 400.913264 -174.36249)
			(xy 400.990704 -174.399464) (xy 401.064343 -174.443528) (xy 401.133531 -174.494294) (xy 401.197662 -174.551315)
			(xy 401.256171 -174.614091) (xy 401.308544 -174.682071) (xy 401.354322 -174.754656) (xy 401.393102 -174.831208)
			(xy 401.424543 -174.911056) (xy 401.448369 -174.993497) (xy 401.46437 -175.077807) (xy 401.472405 -175.163245)
			(xy 401.472908 -175.206152) (xy 401.472405 -175.249059) (xy 401.46437 -175.334497) (xy 401.448369 -175.418807)
			(xy 401.424543 -175.501248) (xy 401.393102 -175.581096) (xy 401.354322 -175.657648) (xy 401.308544 -175.730233)
			(xy 401.256171 -175.798213) (xy 401.197662 -175.860989) (xy 401.133531 -175.91801) (xy 401.064343 -175.968776)
			(xy 400.990704 -176.01284) (xy 400.913264 -176.049814) (xy 400.832701 -176.079375) (xy 400.749724 -176.101261)
			(xy 400.665062 -176.115281) (xy 400.57946 -176.121312) (xy 400.493668 -176.1193) (xy 400.408442 -176.109264)
			(xy 400.324531 -176.091291) (xy 400.242671 -176.065539) (xy 400.163582 -176.032235) (xy 400.08796 -175.991671)
			(xy 400.016468 -175.944204) (xy 399.949735 -175.890251) (xy 399.888348 -175.830287) (xy 399.832845 -175.764837)
			(xy 399.783716 -175.694478) (xy 399.74139 -175.619827) (xy 399.706241 -175.541541) (xy 399.678578 -175.460307)
			(xy 399.658642 -175.37684) (xy 399.646611 -175.291872) (xy 399.642589 -175.206152) (xy 398.8689 -175.206152)
			(xy 398.8689 -177.993548) (xy 399.668492 -177.993548) (xy 399.668492 -176.418748) (xy 399.668931 -176.40536)
			(xy 399.675852 -176.379493) (xy 399.689232 -176.3563) (xy 399.708162 -176.337362) (xy 399.731349 -176.32397)
			(xy 399.757212 -176.317038) (xy 399.7706 -176.31664) (xy 401.3454 -176.31664) (xy 401.358794 -176.31699)
			(xy 401.38467 -176.323926) (xy 401.407868 -176.337324) (xy 401.426806 -176.356271) (xy 401.440193 -176.379475)
			(xy 401.447116 -176.405353) (xy 401.447508 -176.418748) (xy 401.447508 -177.993548) (xy 401.447113 -178.006935)
			(xy 401.440173 -178.032796) (xy 401.426779 -178.055979) (xy 401.407841 -178.074908) (xy 401.384651 -178.088292)
			(xy 401.358788 -178.09522) (xy 401.3454 -178.095656) (xy 399.7706 -178.095656) (xy 399.757219 -178.095172)
			(xy 399.731368 -178.088247) (xy 399.708188 -178.074869) (xy 399.68926 -178.05595) (xy 399.675871 -178.032777)
			(xy 399.668935 -178.006929) (xy 399.668492 -177.993548) (xy 398.8689 -177.993548) (xy 398.8689 -181.429152)
			(xy 399.642589 -181.429152) (xy 399.646611 -181.343432) (xy 399.658642 -181.258464) (xy 399.678578 -181.174997)
			(xy 399.706241 -181.093763) (xy 399.74139 -181.015477) (xy 399.783716 -180.940826) (xy 399.832845 -180.870467)
			(xy 399.888348 -180.805017) (xy 399.949735 -180.745053) (xy 400.016468 -180.6911) (xy 400.08796 -180.643633)
			(xy 400.163582 -180.603069) (xy 400.242671 -180.569765) (xy 400.324531 -180.544013) (xy 400.408442 -180.52604)
			(xy 400.493668 -180.516004) (xy 400.57946 -180.513992) (xy 400.665062 -180.520023) (xy 400.749724 -180.534043)
			(xy 400.832701 -180.555929) (xy 400.913264 -180.58549) (xy 400.990704 -180.622464) (xy 401.064343 -180.666528)
			(xy 401.133531 -180.717294) (xy 401.197662 -180.774315) (xy 401.256171 -180.837091) (xy 401.308544 -180.905071)
			(xy 401.354322 -180.977656) (xy 401.393102 -181.054208) (xy 401.424543 -181.134056) (xy 401.448369 -181.216497)
			(xy 401.46437 -181.300807) (xy 401.472405 -181.386245) (xy 401.472908 -181.429152) (xy 401.472405 -181.472059)
			(xy 401.46437 -181.557497) (xy 401.448369 -181.641807) (xy 401.424543 -181.724248) (xy 401.393102 -181.804096)
			(xy 401.354322 -181.880648) (xy 401.308544 -181.953233) (xy 401.256171 -182.021213) (xy 401.197662 -182.083989)
			(xy 401.133531 -182.14101) (xy 401.064343 -182.191776) (xy 400.990704 -182.23584) (xy 400.913264 -182.272814)
			(xy 400.832701 -182.302375) (xy 400.749724 -182.324261) (xy 400.665062 -182.338281) (xy 400.57946 -182.344312)
			(xy 400.493668 -182.3423) (xy 400.408442 -182.332264) (xy 400.324531 -182.314291) (xy 400.242671 -182.288539)
			(xy 400.163582 -182.255235) (xy 400.08796 -182.214671) (xy 400.016468 -182.167204) (xy 399.949735 -182.113251)
			(xy 399.888348 -182.053287) (xy 399.832845 -181.987837) (xy 399.783716 -181.917478) (xy 399.74139 -181.842827)
			(xy 399.706241 -181.764541) (xy 399.678578 -181.683307) (xy 399.658642 -181.59984) (xy 399.646611 -181.514872)
			(xy 399.642589 -181.429152) (xy 398.8689 -181.429152) (xy 398.8689 -183.909208) (xy 399.17624 -184.216548)
			(xy 399.668492 -184.216548) (xy 399.668492 -182.641748) (xy 399.668931 -182.62836) (xy 399.675852 -182.602493)
			(xy 399.689232 -182.5793) (xy 399.708162 -182.560362) (xy 399.731349 -182.54697) (xy 399.757212 -182.540038)
			(xy 399.7706 -182.53964) (xy 401.3454 -182.53964) (xy 401.358794 -182.53999) (xy 401.38467 -182.546926)
			(xy 401.407868 -182.560324) (xy 401.426806 -182.579271) (xy 401.440193 -182.602475) (xy 401.447116 -182.628353)
			(xy 401.447508 -182.641748) (xy 401.447508 -184.216548) (xy 401.447113 -184.229935) (xy 401.440173 -184.255796)
			(xy 401.426779 -184.278979) (xy 401.407841 -184.297908) (xy 401.384651 -184.311292) (xy 401.358788 -184.31822)
			(xy 401.3454 -184.318656) (xy 399.7706 -184.318656) (xy 399.757219 -184.318172) (xy 399.731368 -184.311247)
			(xy 399.708188 -184.297869) (xy 399.68926 -184.27895) (xy 399.675871 -184.255777) (xy 399.668935 -184.229929)
			(xy 399.668492 -184.216548) (xy 399.17624 -184.216548) (xy 399.99158 -185.031888) (xy 407.139902 -185.031888)
		)
		(stroke
			(width 0)
			(type solid)
		)
		(fill yes)
		(layer "B.Cu")
		(net "PVCCINFAON_CPU0")
	)
	(gr_poly
		(pts
			(xy 0.65786 -18.185384)
			(arc
				(start 0.669544 -18.177256)
				(mid 0.829138 -18.072187)
				(end 0.992632 -17.973294)
			)
			(xy 1.017524 -17.930114)
			(arc
				(start 1.017524 -13.780008)
				(mid 1.305283 -13.085295)
				(end 1.999996 -12.797536)
			)
			(arc
				(start 11.102594 -12.797536)
				(mid 13.236139 -11.913635)
				(end 14.11986 -9.780016)
			)
			(xy 14.11986 -3.945382)
			(arc
				(start 14.10081 -3.90779)
				(mid 13.825764 -3.583504)
				(end 13.726922 -3.16992)
			)
			(arc
				(start 13.726922 -3.16992)
				(mid 13.825371 -2.757062)
				(end 14.09954 -2.433066)
			)
			(xy 14.11986 -2.392934) (xy 14.11986 -1.016) (xy 80.684116 -1.016) (xy 80.684116 -2.39141)
			(arc
				(start 80.704944 -2.43205)
				(mid 81.07796 -3.169158)
				(end 80.704944 -3.906266)
			)
			(xy 80.684116 -3.946906)
			(arc
				(start 80.684116 -9.780016)
				(mid 80.769304 -10.491732)
				(end 81.019904 -11.1633)
			)
			(xy 81.02727 -11.172698) (xy 81.19872 -11.344148) (xy 81.20634 -11.350498)
			(arc
				(start 83.329526 -12.769342)
				(mid 83.337224 -12.773574)
				(end 83.345528 -12.776454)
			)
			(arc
				(start 83.345528 -12.776454)
				(mid 83.523143 -12.792257)
				(end 83.701382 -12.797536)
			)
			(arc
				(start 124.102622 -12.797536)
				(mid 126.236167 -11.913635)
				(end 127.119888 -9.780016)
			)
			(arc
				(start 127.119888 -9.223756)
				(mid 127.113727 -9.202804)
				(end 127.099314 -9.186418)
			)
			(arc
				(start 127.099314 -9.186418)
				(mid 126.839825 -8.890054)
				(end 126.728982 -8.512048)
			)
			(xy 126.700534 -8.46963) (xy 126.687326 -8.463026)
			(arc
				(start 126.66345 -8.457184)
				(mid 126.627619 -8.471973)
				(end 126.61265 -8.50773)
			)
			(arc
				(start 126.61265 -9.780016)
				(mid 125.877331 -11.555233)
				(end 124.102114 -12.290552)
			)
			(arc
				(start 83.70189 -12.290552)
				(mid 81.926673 -11.555233)
				(end 81.191354 -9.780016)
			)
			(xy 81.191354 -1.28524) (xy 81.19364 -1.28524)
			(arc
				(start 81.19364 -0.999998)
				(mid 81.049612 -0.652282)
				(end 80.701896 -0.508254)
			)
			(arc
				(start 14.10208 -0.508254)
				(mid 13.754364 -0.652282)
				(end 13.610336 -0.999998)
			)
			(xy 13.610336 -1.28524) (xy 13.612622 -1.28524)
			(arc
				(start 13.612622 -9.780016)
				(mid 12.877303 -11.555233)
				(end 11.102086 -12.290552)
			)
			(arc
				(start 1.999996 -12.290552)
				(mid 0.946792 -12.726804)
				(end 0.51054 -13.780008)
			)
			(arc
				(start 0.51054 -18.093436)
				(mid 0.51786 -18.119707)
				(end 0.537718 -18.138394)
			)
			(xy 0.62992 -18.187162)
		)
		(stroke
			(width 0)
			(type solid)
		)
		(fill yes)
		(layer "B.Cu")
		(net "GND")
	)
	(gr_poly
		(pts
			(xy 460.267812 -24.651462) (xy 460.221363 -24.560844) (xy 460.134852 -24.376477) (xy 460.055761 -24.188807)
			(xy 459.984214 -23.998133) (xy 459.920326 -23.804758) (xy 459.864198 -23.60899) (xy 459.81592 -23.41114)
			(xy 459.775568 -23.211523) (xy 459.743207 -23.010455) (xy 459.718887 -22.808257) (xy 459.702648 -22.60525)
			(xy 459.694516 -22.401758) (xy 459.694026 -22.29993) (xy 459.694528 -22.198102) (xy 459.702645 -21.994607)
			(xy 459.718871 -21.791599) (xy 459.74318 -21.589398) (xy 459.775534 -21.388328) (xy 459.815881 -21.188709)
			(xy 459.864157 -20.990857) (xy 459.920285 -20.795088) (xy 459.984175 -20.601713) (xy 460.055727 -20.41104)
			(xy 460.134827 -20.223372) (xy 460.221347 -20.039008) (xy 460.267812 -19.948398) (xy 460.267812 -13.896594)
			(xy 456.818492 -13.896594) (xy 456.134216 -13.212318) (xy 454.879456 -13.212318) (xy 454.75271 -13.339064)
			(xy 454.75271 -19.111722) (xy 454.46569 -19.398742) (xy 454.456353 -19.408767) (xy 454.442905 -19.432622)
			(xy 454.436279 -19.459193) (xy 454.43695 -19.48657) (xy 454.444871 -19.512784) (xy 454.459472 -19.535951)
			(xy 454.469246 -19.545554) (xy 454.488525 -19.563711) (xy 454.522386 -19.604429) (xy 454.550286 -19.649442)
			(xy 454.57169 -19.697882) (xy 454.586185 -19.748817) (xy 454.593492 -19.801269) (xy 454.59396 -19.827748)
			(xy 454.59347 -19.854996) (xy 454.585708 -19.908936) (xy 454.570348 -19.961222) (xy 454.547704 -20.01079)
			(xy 454.518236 -20.056631) (xy 454.482543 -20.097811) (xy 454.441354 -20.133493) (xy 454.395506 -20.16295)
			(xy 454.345932 -20.185582) (xy 454.293642 -20.200929) (xy 454.2397 -20.208677) (xy 454.212452 -20.209256)
			(xy 454.185861 -20.208792) (xy 454.133194 -20.2014) (xy 454.082065 -20.186765) (xy 454.033463 -20.165171)
			(xy 453.988331 -20.137037) (xy 453.947544 -20.102907) (xy 453.911892 -20.063444) (xy 453.882065 -20.019413)
			(xy 453.858643 -19.971665) (xy 453.842079 -19.921128) (xy 453.832693 -19.86878) (xy 453.831198 -19.842226)
			(xy 453.82942 -19.793458) (xy 450.895212 -19.793458) (xy 450.641212 -20.047458) (xy 450.641212 -21.623528)
			(xy 453.640952 -21.623528) (xy 453.641409 -21.594782) (xy 453.648613 -21.537743) (xy 453.662898 -21.482055)
			(xy 453.68404 -21.428591) (xy 453.711707 -21.378194) (xy 453.745463 -21.331655) (xy 453.784778 -21.289707)
			(xy 453.829033 -21.253009) (xy 453.853042 -21.237194) (xy 453.863949 -21.229874) (xy 453.881826 -21.210635)
			(xy 453.89418 -21.18746) (xy 453.900189 -21.161895) (xy 453.899452 -21.135643) (xy 453.892018 -21.110455)
			(xy 453.885554 -21.099018) (xy 453.872585 -21.076638) (xy 453.852139 -21.029127) (xy 453.83831 -20.979285)
			(xy 453.831355 -20.928031) (xy 453.830944 -20.902168) (xy 453.83143 -20.874917) (xy 453.839186 -20.820969)
			(xy 453.854541 -20.768674) (xy 453.877183 -20.719097) (xy 453.906649 -20.673247) (xy 453.94234 -20.632056)
			(xy 453.983531 -20.596365) (xy 454.029381 -20.566899) (xy 454.078958 -20.544257) (xy 454.131253 -20.528902)
			(xy 454.185201 -20.521146) (xy 454.239703 -20.521146) (xy 454.293651 -20.528902) (xy 454.345946 -20.544257)
			(xy 454.395523 -20.566899) (xy 454.441373 -20.596365) (xy 454.482564 -20.632056) (xy 454.518255 -20.673247)
			(xy 454.547721 -20.719097) (xy 454.570363 -20.768674) (xy 454.585718 -20.820969) (xy 454.593474 -20.874917)
			(xy 454.59396 -20.902168) (xy 454.593486 -20.929382) (xy 454.585754 -20.983259) (xy 454.570443 -21.035489)
			(xy 454.547863 -21.085013) (xy 454.518474 -21.130824) (xy 454.482871 -21.171993) (xy 454.462642 -21.190204)
			(xy 454.45116 -21.200989) (xy 454.434886 -21.227942) (xy 454.427564 -21.258565) (xy 454.429885 -21.289965)
			(xy 454.44163 -21.319177) (xy 454.451212 -21.331682) (xy 454.470975 -21.356423) (xy 454.504253 -21.410295)
			(xy 454.529786 -21.46824) (xy 454.547088 -21.529152) (xy 454.555827 -21.591867) (xy 454.556368 -21.623528)
			(xy 454.555878 -21.653496) (xy 454.548055 -21.712918) (xy 454.532542 -21.770811) (xy 454.509606 -21.826184)
			(xy 454.479639 -21.87809) (xy 454.443152 -21.92564) (xy 454.400772 -21.96802) (xy 454.353222 -22.004507)
			(xy 454.301316 -22.034474) (xy 454.245943 -22.05741) (xy 454.18805 -22.072923) (xy 454.128628 -22.080746)
			(xy 454.068692 -22.080746) (xy 454.00927 -22.072923) (xy 453.951377 -22.05741) (xy 453.896004 -22.034474)
			(xy 453.844098 -22.004507) (xy 453.796548 -21.96802) (xy 453.754168 -21.92564) (xy 453.717681 -21.87809)
			(xy 453.687714 -21.826184) (xy 453.664778 -21.770811) (xy 453.649265 -21.712918) (xy 453.641442 -21.653496)
			(xy 453.640952 -21.623528) (xy 450.641212 -21.623528) (xy 450.641212 -21.990558) (xy 450.672454 -22.003512)
			(xy 450.699936 -22.01545) (xy 450.751807 -22.045446) (xy 450.799321 -22.081951) (xy 450.841668 -22.124343)
			(xy 450.878123 -22.171896) (xy 450.908064 -22.223798) (xy 450.930979 -22.279162) (xy 450.946476 -22.337042)
			(xy 450.954291 -22.396449) (xy 450.95429 -22.430736) (xy 452.039972 -22.430736) (xy 452.039972 -22.3708)
			(xy 452.047795 -22.311378) (xy 452.063308 -22.253485) (xy 452.086244 -22.198112) (xy 452.116211 -22.146206)
			(xy 452.152698 -22.098656) (xy 452.195078 -22.056276) (xy 452.242628 -22.019789) (xy 452.294534 -21.989822)
			(xy 452.349907 -21.966886) (xy 452.4078 -21.951373) (xy 452.467222 -21.94355) (xy 452.527158 -21.94355)
			(xy 452.58658 -21.951373) (xy 452.644473 -21.966886) (xy 452.699846 -21.989822) (xy 452.751752 -22.019789)
			(xy 452.799302 -22.056276) (xy 452.841682 -22.098656) (xy 452.878169 -22.146206) (xy 452.908136 -22.198112)
			(xy 452.931072 -22.253485) (xy 452.946585 -22.311378) (xy 452.954408 -22.3708) (xy 452.954898 -22.400768)
			(xy 452.954408 -22.430736) (xy 452.946585 -22.490158) (xy 452.931072 -22.548051) (xy 452.908136 -22.603424)
			(xy 452.878169 -22.65533) (xy 452.841682 -22.70288) (xy 452.799302 -22.74526) (xy 452.751752 -22.781747)
			(xy 452.699846 -22.811714) (xy 452.644473 -22.83465) (xy 452.58658 -22.850163) (xy 452.527158 -22.857986)
			(xy 452.467222 -22.857986) (xy 452.4078 -22.850163) (xy 452.349907 -22.83465) (xy 452.294534 -22.811714)
			(xy 452.242628 -22.781747) (xy 452.195078 -22.74526) (xy 452.152698 -22.70288) (xy 452.116211 -22.65533)
			(xy 452.086244 -22.603424) (xy 452.063308 -22.548051) (xy 452.047795 -22.490158) (xy 452.039972 -22.430736)
			(xy 450.95429 -22.430736) (xy 450.95429 -22.456368) (xy 450.946473 -22.515775) (xy 450.930973 -22.573654)
			(xy 450.908056 -22.629017) (xy 450.878114 -22.680918) (xy 450.841657 -22.72847) (xy 450.799308 -22.77086)
			(xy 450.751793 -22.807363) (xy 450.699921 -22.837357) (xy 450.672454 -22.849332) (xy 450.641212 -22.862286)
			(xy 450.641212 -23.019258) (xy 451.351394 -23.019258) (xy 451.355465 -22.963636) (xy 451.367591 -22.909199)
			(xy 451.387514 -22.857108) (xy 451.41481 -22.808473) (xy 451.448896 -22.76433) (xy 451.489045 -22.725621)
			(xy 451.534403 -22.69317) (xy 451.584003 -22.667669) (xy 451.636787 -22.649662) (xy 451.69163 -22.639532)
			(xy 451.747364 -22.637495) (xy 451.802801 -22.643595) (xy 451.856758 -22.657701) (xy 451.908087 -22.679513)
			(xy 451.955693 -22.708567) (xy 451.998561 -22.744242) (xy 452.035778 -22.785779) (xy 452.066551 -22.832292)
			(xy 452.090223 -22.882789) (xy 452.106291 -22.936196) (xy 452.114411 -22.991372) (xy 452.11492 -23.019258)
			(xy 452.114411 -23.047144) (xy 452.106291 -23.10232) (xy 452.090223 -23.155727) (xy 452.066551 -23.206224)
			(xy 452.035778 -23.252737) (xy 451.998561 -23.294274) (xy 451.955693 -23.329949) (xy 451.908087 -23.359003)
			(xy 451.856758 -23.380815) (xy 451.802801 -23.394921) (xy 451.747364 -23.401021) (xy 451.69163 -23.398984)
			(xy 451.636787 -23.388854) (xy 451.584003 -23.370847) (xy 451.534403 -23.345346) (xy 451.489045 -23.312895)
			(xy 451.448896 -23.274186) (xy 451.41481 -23.230043) (xy 451.387514 -23.181408) (xy 451.367591 -23.129317)
			(xy 451.355465 -23.07488) (xy 451.351394 -23.019258) (xy 450.641212 -23.019258) (xy 450.641212 -23.508208)
			(xy 450.647054 -23.51913) (xy 450.658683 -23.542242) (xy 450.675126 -23.591295) (xy 450.68343 -23.64236)
			(xy 450.683884 -23.668228) (xy 450.683884 -24.108664) (xy 451.272656 -24.697182) (xy 451.283936 -24.70767)
			(xy 451.311228 -24.721917) (xy 451.341525 -24.727383) (xy 451.372075 -24.723571) (xy 451.4001 -24.710828)
			(xy 451.423054 -24.690311) (xy 451.431406 -24.67737) (xy 451.446296 -24.653513) (xy 451.481979 -24.61005)
			(xy 451.523653 -24.572292) (xy 451.570415 -24.541056) (xy 451.621253 -24.517018) (xy 451.675068 -24.500699)
			(xy 451.730695 -24.492451) (xy 451.758812 -24.49195) (xy 451.786064 -24.492437) (xy 451.840012 -24.500194)
			(xy 451.892308 -24.51555) (xy 451.941887 -24.538191) (xy 451.987738 -24.567657) (xy 452.028931 -24.603348)
			(xy 452.064625 -24.644537) (xy 452.094094 -24.690387) (xy 452.11674 -24.739964) (xy 452.132099 -24.792258)
			(xy 452.139861 -24.846206) (xy 452.14032 -24.873458) (xy 452.139823 -24.901578) (xy 452.13158 -24.957209)
			(xy 452.115265 -25.011029) (xy 452.091232 -25.061875) (xy 452.060001 -25.108645) (xy 452.022247 -25.150327)
			(xy 451.978787 -25.186021) (xy 451.9549 -25.200864) (xy 451.941951 -25.209215) (xy 451.921413 -25.232167)
			(xy 451.908653 -25.260198) (xy 451.904832 -25.290759) (xy 451.910298 -25.321069) (xy 451.924554 -25.348371)
			(xy 451.935088 -25.359614) (xy 454.507092 -27.931618) (xy 460.267812 -27.931618)
		)
		(stroke
			(width 0)
			(type solid)
		)
		(fill yes)
		(layer "B.Cu")
		(net "GND")
	)
	(gr_poly
		(pts
			(xy 381.317754 -366.605312) (xy 381.332576 -366.604781) (xy 381.360958 -366.59622) (xy 381.385684 -366.579866)
			(xy 381.404668 -366.557097) (xy 381.41631 -366.529833) (xy 381.419628 -366.500374) (xy 381.414342 -366.471204)
			(xy 381.400897 -366.444783) (xy 381.380428 -366.423338) (xy 381.367792 -366.415574) (xy 381.332097 -366.397413)
			(xy 381.263898 -366.355413) (xy 381.199875 -366.307287) (xy 381.140576 -366.253446) (xy 381.086511 -366.194352)
			(xy 381.038142 -366.130512) (xy 380.995884 -366.062473) (xy 380.960098 -365.990818) (xy 380.931093 -365.91616)
			(xy 380.909116 -365.83914) (xy 380.894355 -365.760417) (xy 380.886937 -365.680667) (xy 380.886462 -365.64062)
			(xy 380.886952 -365.599469) (xy 380.894775 -365.517539) (xy 380.910351 -365.436723) (xy 380.933538 -365.357755)
			(xy 380.964127 -365.281347) (xy 381.00184 -365.208194) (xy 381.046336 -365.138957) (xy 381.097212 -365.074262)
			(xy 381.154008 -365.014697) (xy 381.216208 -364.9608) (xy 381.28325 -364.91306) (xy 381.354526 -364.871909)
			(xy 381.429391 -364.837719) (xy 381.507167 -364.810801) (xy 381.58715 -364.791397) (xy 381.668615 -364.779684)
			(xy 381.750824 -364.775768) (xy 381.833033 -364.779684) (xy 381.914498 -364.791397) (xy 381.994481 -364.810801)
			(xy 382.072257 -364.837719) (xy 382.147122 -364.871909) (xy 382.218398 -364.91306) (xy 382.28544 -364.9608)
			(xy 382.34764 -365.014697) (xy 382.404436 -365.074262) (xy 382.455312 -365.138957) (xy 382.499808 -365.208194)
			(xy 382.537521 -365.281347) (xy 382.56811 -365.357755) (xy 382.591297 -365.436723) (xy 382.606873 -365.517539)
			(xy 382.614696 -365.599469) (xy 382.615186 -365.64062) (xy 382.614737 -365.68067) (xy 382.607334 -365.760426)
			(xy 382.592584 -365.839155) (xy 382.570614 -365.916182) (xy 382.541612 -365.990846) (xy 382.505826 -366.062506)
			(xy 382.463565 -366.130549) (xy 382.415189 -366.19439) (xy 382.361115 -366.253481) (xy 382.301806 -366.307317)
			(xy 382.237771 -366.355434) (xy 382.169558 -366.397421) (xy 382.133856 -366.415574) (xy 382.121238 -366.423357)
			(xy 382.100799 -366.444813) (xy 382.087378 -366.471233) (xy 382.082104 -366.500394) (xy 382.085422 -366.529841)
			(xy 382.097052 -366.557096) (xy 382.116016 -366.579867) (xy 382.140718 -366.596236) (xy 382.169079 -366.604827)
			(xy 382.183894 -366.605312) (xy 383.307336 -366.605312) (xy 389.635238 -360.27741) (xy 389.635238 -360.253788)
			(xy 390.92886 -358.960166) (xy 390.92886 -350.848168) (xy 390.51484 -350.434148) (xy 374.7262 -350.434148)
			(xy 374.5992 -350.561148) (xy 374.5992 -359.46842) (xy 374.88368 -359.7529) (xy 374.891089 -359.759587)
			(xy 374.909525 -359.767177) (xy 374.919494 -359.767632) (xy 376.990864 -359.767632) (xy 376.990864 -359.770172)
			(xy 377.642882 -359.770172) (xy 377.652932 -359.770678) (xy 377.671493 -359.7784) (xy 377.67895 -359.785158)
			(xy 377.920758 -360.026966) (xy 377.927599 -360.034366) (xy 377.935316 -360.052965) (xy 377.935744 -360.063034)
			(xy 377.935744 -361.734652) (xy 382.553685 -361.734652) (xy 382.553685 -361.680148) (xy 382.561442 -361.6262)
			(xy 382.576798 -361.573905) (xy 382.59944 -361.524328) (xy 382.628907 -361.478477) (xy 382.6646 -361.437287)
			(xy 382.705792 -361.401596) (xy 382.751643 -361.372131) (xy 382.801222 -361.349492) (xy 382.853518 -361.334138)
			(xy 382.907466 -361.326384) (xy 382.934718 -361.325922) (xy 382.961166 -361.326377) (xy 383.013558 -361.333666)
			(xy 383.064438 -361.348129) (xy 383.11283 -361.369489) (xy 383.157804 -361.397336) (xy 383.198495 -361.431133)
			(xy 383.234122 -361.470232) (xy 383.264 -361.513882) (xy 383.287556 -361.561244) (xy 383.304336 -361.611408)
			(xy 383.309622 -361.637326) (xy 383.312552 -361.650749) (xy 383.324676 -361.675393) (xy 383.343002 -361.695848)
			(xy 383.366171 -361.710597) (xy 383.392461 -361.718543) (xy 383.419919 -361.719096) (xy 383.43332 -361.716066)
			(xy 383.461107 -361.709436) (xy 383.517787 -361.7023) (xy 383.54635 -361.701842) (xy 383.546858 -361.701842)
			(xy 383.576823 -361.702421) (xy 383.63624 -361.710238) (xy 383.694128 -361.725743) (xy 383.749498 -361.748672)
			(xy 383.801401 -361.778631) (xy 383.84895 -361.815109) (xy 383.89133 -361.857481) (xy 383.927817 -361.905022)
			(xy 383.957787 -361.95692) (xy 383.980727 -362.012284) (xy 383.996244 -362.07017) (xy 384.004073 -362.129585)
			(xy 384.004566 -362.15955) (xy 384.004312 -362.17479) (xy 384.004362 -362.188018) (xy 384.01039 -362.213761)
			(xy 384.022902 -362.237051) (xy 384.04104 -362.256289) (xy 384.063554 -362.270149) (xy 384.088897 -362.277681)
			(xy 384.102102 -362.278422) (xy 384.128919 -362.279557) (xy 384.181865 -362.28837) (xy 384.233054 -362.304514)
			(xy 384.281476 -362.327671) (xy 384.326176 -362.357383) (xy 384.366272 -362.393065) (xy 384.400973 -362.434012)
			(xy 384.429596 -362.479418) (xy 384.451574 -362.528386) (xy 384.466475 -362.57995) (xy 384.474005 -362.633093)
			(xy 384.474466 -362.65993) (xy 384.474319 -362.676783) (xy 384.471389 -362.710361) (xy 384.468624 -362.726986)
			(xy 384.466385 -362.742337) (xy 384.47046 -362.773079) (xy 384.483676 -362.801133) (xy 384.504784 -362.823851)
			(xy 384.531793 -362.839089) (xy 384.546856 -362.84281) (xy 384.575095 -362.849184) (xy 384.629329 -362.869433)
			(xy 384.679879 -362.897645) (xy 384.725586 -362.933174) (xy 384.765397 -362.975201) (xy 384.7984 -363.022763)
			(xy 384.823836 -363.074767) (xy 384.84112 -363.130017) (xy 384.849855 -363.187245) (xy 384.850386 -363.21619)
			(xy 384.850386 -363.22254) (xy 384.850578 -363.235886) (xy 384.857101 -363.261756) (xy 384.870183 -363.285008)
			(xy 384.888909 -363.304013) (xy 384.911965 -363.317437) (xy 384.937737 -363.324341) (xy 384.964416 -363.324241)
			(xy 384.977386 -363.321092) (xy 385.007148 -363.313398) (xy 385.068062 -363.305115) (xy 385.098798 -363.304582)
			(xy 385.128767 -363.305059) (xy 385.188193 -363.312882) (xy 385.24609 -363.328395) (xy 385.301466 -363.351333)
			(xy 385.353374 -363.381302) (xy 385.400927 -363.41779) (xy 385.44331 -363.460173) (xy 385.479798 -363.507726)
			(xy 385.509767 -363.559634) (xy 385.532705 -363.61501) (xy 385.548218 -363.672907) (xy 385.556041 -363.732333)
			(xy 385.556041 -363.792271) (xy 385.548217 -363.851697) (xy 385.532703 -363.909593) (xy 385.509765 -363.964969)
			(xy 385.479796 -364.016877) (xy 385.443307 -364.06443) (xy 385.400924 -364.106812) (xy 385.353371 -364.1433)
			(xy 385.301462 -364.173269) (xy 385.246086 -364.196206) (xy 385.188189 -364.211718) (xy 385.128763 -364.219541)
			(xy 385.068825 -364.219541) (xy 385.009399 -364.211716) (xy 384.951503 -364.196202) (xy 384.896127 -364.173264)
			(xy 384.844219 -364.143293) (xy 384.796667 -364.106804) (xy 384.754285 -364.064421) (xy 384.717798 -364.016867)
			(xy 384.687829 -363.964958) (xy 384.664893 -363.909582) (xy 384.649381 -363.851685) (xy 384.641558 -363.792259)
			(xy 384.64109 -363.76229) (xy 384.641182 -363.747837) (xy 384.642962 -363.718987) (xy 384.644646 -363.704632)
			(xy 384.645829 -363.691364) (xy 384.642148 -363.664996) (xy 384.631694 -363.640512) (xy 384.615196 -363.619616)
			(xy 384.593804 -363.603767) (xy 384.56901 -363.59407) (xy 384.542542 -363.591199) (xy 384.52933 -363.592872)
			(xy 384.514319 -363.595134) (xy 384.484057 -363.597551) (xy 384.468878 -363.597698) (xy 384.441626 -363.597243)
			(xy 384.387676 -363.589483) (xy 384.33538 -363.574124) (xy 384.285803 -363.55148) (xy 384.239952 -363.522011)
			(xy 384.198762 -363.486316) (xy 384.16307 -363.445123) (xy 384.133605 -363.399269) (xy 384.110964 -363.349689)
			(xy 384.09561 -363.297392) (xy 384.087855 -363.243442) (xy 384.08737 -363.21619) (xy 384.087521 -363.199337)
			(xy 384.090448 -363.165759) (xy 384.093212 -363.149134) (xy 384.095402 -363.133779) (xy 384.091334 -363.103045)
			(xy 384.078129 -363.074996) (xy 384.057033 -363.052278) (xy 384.030038 -363.037035) (xy 384.01498 -363.03331)
			(xy 383.989044 -363.027461) (xy 383.939001 -363.009507) (xy 383.891938 -362.984773) (xy 383.848769 -362.95374)
			(xy 383.810331 -362.917009) (xy 383.77737 -362.875292) (xy 383.750525 -362.829401) (xy 383.730318 -362.780224)
			(xy 383.717141 -362.728716) (xy 383.713736 -362.702348) (xy 383.711844 -362.689243) (xy 383.702187 -362.664603)
			(xy 383.686435 -362.643335) (xy 383.665681 -362.626912) (xy 383.64136 -362.616473) (xy 383.615159 -362.612741)
			(xy 383.601976 -362.613956) (xy 383.588376 -362.615495) (xy 383.561053 -362.61715) (xy 383.547366 -362.617258)
			(xy 383.546858 -362.617258) (xy 383.5178 -362.616813) (xy 383.46015 -362.609463) (xy 383.403895 -362.594874)
			(xy 383.349939 -362.57328) (xy 383.299151 -362.545029) (xy 383.252349 -362.510575) (xy 383.210284 -362.470474)
			(xy 383.173636 -362.425369) (xy 383.142992 -362.375989) (xy 383.118846 -362.323125) (xy 383.101587 -362.267631)
			(xy 383.091493 -362.210398) (xy 383.089658 -362.181394) (xy 383.088491 -362.167737) (xy 383.079868 -362.141734)
			(xy 383.064567 -362.11901) (xy 383.043718 -362.101239) (xy 383.018857 -362.089732) (xy 382.991816 -362.085337)
			(xy 382.978152 -362.086398) (xy 382.967332 -362.087575) (xy 382.945602 -362.088846) (xy 382.934718 -362.088938)
			(xy 382.907466 -362.088416) (xy 382.853518 -362.080662) (xy 382.801222 -362.065308) (xy 382.751643 -362.042669)
			(xy 382.705792 -362.013204) (xy 382.6646 -361.977513) (xy 382.628907 -361.936323) (xy 382.59944 -361.890472)
			(xy 382.576798 -361.840895) (xy 382.561442 -361.7886) (xy 382.553685 -361.734652) (xy 377.935744 -361.734652)
			(xy 377.935744 -362.16717) (xy 377.935307 -362.177233) (xy 377.927568 -362.195814) (xy 377.920758 -362.203238)
			(xy 377.12523 -362.998766) (xy 377.117829 -363.005605) (xy 377.099231 -363.013319) (xy 377.089162 -363.013752)
			(xy 368.831876 -363.013752) (xy 368.398298 -363.44733) (xy 368.398298 -366.31499) (xy 368.68862 -366.605312)
		)
		(stroke
			(width 0)
			(type solid)
		)
		(fill yes)
		(layer "B.Cu")
		(net "GND")
	)
	(gr_poly
		(pts
			(xy 470.24544 -77.216508) (xy 470.24544 -60.77204) (xy 469.99906 -60.52566) (xy 462.76768 -60.52566)
			(xy 462.407 -60.16498) (xy 462.407 -58.765948) (xy 462.116424 -58.475372) (xy 441.107576 -58.475372)
			(xy 440.817 -58.765948) (xy 440.817 -71.069196) (xy 443.149718 -71.069196) (xy 443.149718 -71.00926)
			(xy 443.157541 -70.949838) (xy 443.173054 -70.891945) (xy 443.19599 -70.836572) (xy 443.225957 -70.784666)
			(xy 443.262444 -70.737116) (xy 443.304824 -70.694736) (xy 443.352374 -70.658249) (xy 443.40428 -70.628282)
			(xy 443.459653 -70.605346) (xy 443.517546 -70.589833) (xy 443.576968 -70.58201) (xy 443.636904 -70.58201)
			(xy 443.696326 -70.589833) (xy 443.754219 -70.605346) (xy 443.809592 -70.628282) (xy 443.861498 -70.658249)
			(xy 443.909048 -70.694736) (xy 443.951428 -70.737116) (xy 443.987915 -70.784666) (xy 444.017882 -70.836572)
			(xy 444.040818 -70.891945) (xy 444.056331 -70.949838) (xy 444.064154 -71.00926) (xy 444.064644 -71.039228)
			(xy 444.064154 -71.069196) (xy 444.056331 -71.128618) (xy 444.040818 -71.186511) (xy 444.017882 -71.241884)
			(xy 443.987915 -71.29379) (xy 443.951428 -71.34134) (xy 443.909048 -71.38372) (xy 443.861498 -71.420207)
			(xy 443.809592 -71.450174) (xy 443.754219 -71.47311) (xy 443.696326 -71.488623) (xy 443.636904 -71.496446)
			(xy 443.576968 -71.496446) (xy 443.517546 -71.488623) (xy 443.459653 -71.47311) (xy 443.40428 -71.450174)
			(xy 443.352374 -71.420207) (xy 443.304824 -71.38372) (xy 443.262444 -71.34134) (xy 443.225957 -71.29379)
			(xy 443.19599 -71.241884) (xy 443.173054 -71.186511) (xy 443.157541 -71.128618) (xy 443.149718 -71.069196)
			(xy 440.817 -71.069196) (xy 440.817 -73.53554) (xy 452.08444 -73.53554) (xy 452.08444 -71.05904)
			(xy 452.24192 -70.90156) (xy 455.676 -70.90156) (xy 456.58786 -69.9897) (xy 461.22844 -69.9897) (xy 461.3529 -69.86524)
			(xy 461.3529 -66.38544) (xy 461.8736 -65.86474) (xy 465.03844 -65.86474) (xy 465.38642 -66.21272)
			(xy 465.38642 -68.519802) (xy 465.542379 -68.519802) (xy 465.546415 -68.436355) (xy 465.558487 -68.353687)
			(xy 465.57848 -68.27257) (xy 465.606209 -68.193761) (xy 465.641415 -68.117996) (xy 465.683769 -68.045983)
			(xy 465.732875 -67.978394) (xy 465.788276 -67.91586) (xy 465.849453 -67.858965) (xy 465.915836 -67.808239)
			(xy 465.986804 -67.764158) (xy 466.061696 -67.727132) (xy 466.139812 -67.697506) (xy 466.220422 -67.675558)
			(xy 466.302774 -67.661493) (xy 466.3861 -67.655441) (xy 466.46962 -67.65746) (xy 466.552556 -67.66753)
			(xy 466.634132 -67.685558) (xy 466.713588 -67.711375) (xy 466.790181 -67.74474) (xy 466.863197 -67.785341)
			(xy 466.931953 -67.8328) (xy 466.995807 -67.886673) (xy 467.054164 -67.946458) (xy 467.106479 -68.011595)
			(xy 467.152262 -68.081478) (xy 467.191087 -68.155453) (xy 467.222592 -68.23283) (xy 467.246481 -68.312887)
			(xy 467.262532 -68.394875) (xy 467.270595 -68.47803) (xy 467.2711 -68.519802) (xy 467.270595 -68.561574)
			(xy 467.262532 -68.644729) (xy 467.246481 -68.726717) (xy 467.222592 -68.806774) (xy 467.191087 -68.884151)
			(xy 467.152262 -68.958126) (xy 467.106479 -69.028009) (xy 467.054164 -69.093146) (xy 466.995807 -69.152931)
			(xy 466.931953 -69.206804) (xy 466.863197 -69.254263) (xy 466.790181 -69.294864) (xy 466.713588 -69.328229)
			(xy 466.634132 -69.354046) (xy 466.552556 -69.372074) (xy 466.46962 -69.382144) (xy 466.3861 -69.384163)
			(xy 466.302774 -69.378111) (xy 466.220422 -69.364046) (xy 466.139812 -69.342098) (xy 466.061696 -69.312472)
			(xy 465.986804 -69.275446) (xy 465.915836 -69.231365) (xy 465.849453 -69.180639) (xy 465.788276 -69.123744)
			(xy 465.732875 -69.06121) (xy 465.683769 -68.993621) (xy 465.641415 -68.921608) (xy 465.606209 -68.845843)
			(xy 465.57848 -68.767034) (xy 465.558487 -68.685917) (xy 465.546415 -68.603249) (xy 465.542379 -68.519802)
			(xy 465.38642 -68.519802) (xy 465.38642 -75.960224) (xy 465.542379 -75.960224) (xy 465.546415 -75.876777)
			(xy 465.558487 -75.794109) (xy 465.57848 -75.712992) (xy 465.606209 -75.634183) (xy 465.641415 -75.558418)
			(xy 465.683769 -75.486405) (xy 465.732875 -75.418816) (xy 465.788276 -75.356282) (xy 465.849453 -75.299387)
			(xy 465.915836 -75.248661) (xy 465.986804 -75.20458) (xy 466.061696 -75.167554) (xy 466.139812 -75.137928)
			(xy 466.220422 -75.11598) (xy 466.302774 -75.101915) (xy 466.3861 -75.095863) (xy 466.46962 -75.097882)
			(xy 466.552556 -75.107952) (xy 466.634132 -75.12598) (xy 466.713588 -75.151797) (xy 466.790181 -75.185162)
			(xy 466.863197 -75.225763) (xy 466.931953 -75.273222) (xy 466.995807 -75.327095) (xy 467.054164 -75.38688)
			(xy 467.106479 -75.452017) (xy 467.152262 -75.5219) (xy 467.191087 -75.595875) (xy 467.222592 -75.673252)
			(xy 467.246481 -75.753309) (xy 467.262532 -75.835297) (xy 467.270595 -75.918452) (xy 467.2711 -75.960224)
			(xy 467.270595 -76.001996) (xy 467.262532 -76.085151) (xy 467.246481 -76.167139) (xy 467.222592 -76.247196)
			(xy 467.191087 -76.324573) (xy 467.152262 -76.398548) (xy 467.106479 -76.468431) (xy 467.054164 -76.533568)
			(xy 466.995807 -76.593353) (xy 466.931953 -76.647226) (xy 466.863197 -76.694685) (xy 466.790181 -76.735286)
			(xy 466.713588 -76.768651) (xy 466.634132 -76.794468) (xy 466.552556 -76.812496) (xy 466.46962 -76.822566)
			(xy 466.3861 -76.824585) (xy 466.302774 -76.818533) (xy 466.220422 -76.804468) (xy 466.139812 -76.78252)
			(xy 466.061696 -76.752894) (xy 465.986804 -76.715868) (xy 465.915836 -76.671787) (xy 465.849453 -76.621061)
			(xy 465.788276 -76.564166) (xy 465.732875 -76.501632) (xy 465.683769 -76.434043) (xy 465.641415 -76.36203)
			(xy 465.606209 -76.286265) (xy 465.57848 -76.207456) (xy 465.558487 -76.126339) (xy 465.546415 -76.043671)
			(xy 465.542379 -75.960224) (xy 465.38642 -75.960224) (xy 465.38642 -77.38872) (xy 465.14512 -77.63002)
			(xy 461.31226 -77.63002) (xy 460.66964 -76.9874) (xy 454.23328 -76.9874) (xy 453.81418 -76.5683)
			(xy 453.81418 -75.26528) (xy 452.08444 -73.53554) (xy 440.817 -73.53554) (xy 440.817 -74.640948)
			(xy 443.978282 -74.640948) (xy 443.982353 -74.585326) (xy 443.994479 -74.530889) (xy 444.014402 -74.478798)
			(xy 444.041698 -74.430163) (xy 444.075784 -74.38602) (xy 444.115933 -74.347311) (xy 444.161291 -74.31486)
			(xy 444.210891 -74.289359) (xy 444.263675 -74.271352) (xy 444.318518 -74.261222) (xy 444.374252 -74.259185)
			(xy 444.429689 -74.265285) (xy 444.483646 -74.279391) (xy 444.534975 -74.301203) (xy 444.582581 -74.330257)
			(xy 444.625449 -74.365932) (xy 444.662666 -74.407469) (xy 444.693439 -74.453982) (xy 444.717111 -74.504479)
			(xy 444.733179 -74.557886) (xy 444.741299 -74.613062) (xy 444.741808 -74.640948) (xy 444.741299 -74.668834)
			(xy 444.733179 -74.72401) (xy 444.717111 -74.777417) (xy 444.693439 -74.827914) (xy 444.662666 -74.874427)
			(xy 444.625449 -74.915964) (xy 444.582581 -74.951639) (xy 444.534975 -74.980693) (xy 444.483646 -75.002505)
			(xy 444.429689 -75.016611) (xy 444.374252 -75.022711) (xy 444.318518 -75.020674) (xy 444.263675 -75.010544)
			(xy 444.210891 -74.992537) (xy 444.161291 -74.967036) (xy 444.115933 -74.934585) (xy 444.075784 -74.895876)
			(xy 444.041698 -74.851733) (xy 444.014402 -74.803098) (xy 443.994479 -74.751007) (xy 443.982353 -74.69657)
			(xy 443.978282 -74.640948) (xy 440.817 -74.640948) (xy 440.817 -75.555348) (xy 441.1472 -75.885548)
			(xy 443.009274 -75.885548) (xy 443.033009 -75.867552) (xy 443.085229 -75.83891) (xy 443.14149 -75.819365)
			(xy 443.20022 -75.809462) (xy 443.23 -75.80884) (xy 443.257784 -75.809372) (xy 443.312677 -75.818)
			(xy 443.365566 -75.835045) (xy 443.415166 -75.860096) (xy 443.438026 -75.875896) (xy 443.451488 -75.885548)
			(xy 443.555882 -75.885548) (xy 443.597538 -75.843892) (xy 448.591178 -75.843892) (xy 449.161916 -76.41463)
			(xy 451.01637 -76.41463) (xy 451.18782 -76.24318) (xy 451.18782 -76.208636) (xy 451.173938 -76.188285)
			(xy 451.151937 -76.144211) (xy 451.136963 -76.097281) (xy 451.129373 -76.048608) (xy 451.128892 -76.023978)
			(xy 451.128892 -75.613768) (xy 450.919342 -75.404218) (xy 450.919342 -74.708258) (xy 451.1167 -74.5109)
			(xy 451.78218 -74.5109) (xy 452.3613 -75.09002) (xy 452.3613 -76.639166) (xy 452.5043 -76.639166)
			(xy 452.508373 -76.583507) (xy 452.520508 -76.529034) (xy 452.540444 -76.476908) (xy 452.567758 -76.42824)
			(xy 452.601866 -76.384068) (xy 452.642043 -76.345333) (xy 452.687431 -76.312861) (xy 452.737063 -76.287343)
			(xy 452.789883 -76.269324) (xy 452.844762 -76.259187) (xy 452.900533 -76.257149) (xy 452.956007 -76.263252)
			(xy 453.01 -76.277368) (xy 453.061363 -76.299195) (xy 453.109001 -76.328268) (xy 453.151897 -76.363967)
			(xy 453.189139 -76.405531) (xy 453.219933 -76.452075) (xy 453.243621 -76.502606) (xy 453.259699 -76.556048)
			(xy 453.267825 -76.611262) (xy 453.268334 -76.639166) (xy 453.267825 -76.66707) (xy 453.259699 -76.722284)
			(xy 453.243621 -76.775726) (xy 453.219933 -76.826257) (xy 453.189139 -76.872801) (xy 453.151897 -76.914365)
			(xy 453.109001 -76.950064) (xy 453.061363 -76.979137) (xy 453.01 -77.000964) (xy 452.956007 -77.01508)
			(xy 452.900533 -77.021183) (xy 452.844762 -77.019145) (xy 452.789883 -77.009008) (xy 452.737063 -76.990989)
			(xy 452.687431 -76.965471) (xy 452.642043 -76.932999) (xy 452.601866 -76.894264) (xy 452.567758 -76.850092)
			(xy 452.540444 -76.801424) (xy 452.520508 -76.749298) (xy 452.508373 -76.694825) (xy 452.5043 -76.639166)
			(xy 452.3613 -76.639166) (xy 452.3613 -77.015848) (xy 456.0316 -80.686148) (xy 466.7758 -80.686148)
		)
		(stroke
			(width 0)
			(type solid)
		)
		(fill yes)
		(layer "B.Cu")
		(net "GND")
	)
	(gr_poly
		(pts
			(xy 21.296376 -183.640984) (xy 21.288756 -183.628792) (xy 21.275441 -183.606221) (xy 21.25445 -183.558206)
			(xy 21.240234 -183.507768) (xy 21.233061 -183.455858) (xy 21.232622 -183.429656) (xy 21.233108 -183.402405)
			(xy 21.240864 -183.348457) (xy 21.256219 -183.296162) (xy 21.278861 -183.246585) (xy 21.308327 -183.200735)
			(xy 21.344018 -183.159544) (xy 21.385209 -183.123853) (xy 21.431059 -183.094387) (xy 21.480636 -183.071745)
			(xy 21.532931 -183.05639) (xy 21.586879 -183.048634) (xy 21.641381 -183.048634) (xy 21.695329 -183.05639)
			(xy 21.747624 -183.071745) (xy 21.797201 -183.094387) (xy 21.843051 -183.123853) (xy 21.884242 -183.159544)
			(xy 21.919933 -183.200735) (xy 21.949399 -183.246585) (xy 21.972041 -183.296162) (xy 21.987396 -183.348457)
			(xy 21.995152 -183.402405) (xy 21.995638 -183.429656) (xy 21.9952 -183.455857) (xy 21.988017 -183.507764)
			(xy 21.973795 -183.558199) (xy 21.9528 -183.606211) (xy 21.939504 -183.628792) (xy 21.931884 -183.640984)
			(xy 21.931884 -183.803798) (xy 22.314916 -183.803798) (xy 22.327362 -183.771032) (xy 22.33565 -183.750174)
			(xy 22.357254 -183.710835) (xy 22.384181 -183.674928) (xy 22.399752 -183.658764) (xy 22.894544 -183.163972)
			(xy 22.8981 -183.150002) (xy 22.905198 -183.122597) (xy 22.926386 -183.070103) (xy 22.955107 -183.021322)
			(xy 22.990729 -182.977325) (xy 23.032466 -182.939082) (xy 23.079402 -182.907434) (xy 23.130502 -182.883077)
			(xy 23.184644 -182.866548) (xy 23.240635 -182.858209) (xy 23.26894 -182.857648) (xy 23.296191 -182.858136)
			(xy 23.350136 -182.865897) (xy 23.402429 -182.881256) (xy 23.452004 -182.903898) (xy 23.497852 -182.933365)
			(xy 23.539041 -182.969056) (xy 23.574733 -183.010245) (xy 23.6042 -183.056093) (xy 23.626843 -183.105668)
			(xy 23.642202 -183.15796) (xy 23.649963 -183.211905) (xy 23.650448 -183.239156) (xy 23.649929 -183.267458)
			(xy 23.641556 -183.32344) (xy 23.625001 -183.37757) (xy 23.60063 -183.42866) (xy 23.568975 -183.475586)
			(xy 23.530734 -183.51732) (xy 23.486745 -183.552944) (xy 23.437975 -183.581676) (xy 23.385494 -183.602886)
			(xy 23.358094 -183.609996) (xy 23.344124 -183.613552) (xy 23.32736 -183.630316) (xy 23.317136 -183.641284)
			(xy 23.302994 -183.667708) (xy 23.297125 -183.697097) (xy 23.300034 -183.726926) (xy 23.31147 -183.754628)
			(xy 23.330449 -183.777822) (xy 23.355341 -183.794513) (xy 23.384004 -183.803266) (xy 23.398988 -183.803798)
			(xy 25.00884 -183.803798) (xy 26.101548 -182.71109) (xy 26.101548 -179.06238) (xy 26.101062 -179.048091)
			(xy 26.093134 -179.020634) (xy 26.077905 -178.996452) (xy 26.056569 -178.97744) (xy 26.030798 -178.965087)
			(xy 26.002613 -178.960363) (xy 25.974223 -178.963639) (xy 25.960832 -178.968654) (xy 25.932727 -178.979887)
			(xy 25.874305 -178.9957) (xy 25.81431 -179.003692) (xy 25.784048 -179.004214) (xy 25.752417 -179.003677)
			(xy 25.689758 -178.994959) (xy 25.628897 -178.977698) (xy 25.570991 -178.952221) (xy 25.517145 -178.919014)
			(xy 25.468384 -178.878709) (xy 25.425637 -178.832075) (xy 25.389718 -178.779999) (xy 25.361311 -178.723473)
			(xy 25.340957 -178.663575) (xy 25.334468 -178.632612) (xy 25.331674 -178.617118) (xy 25.08377 -178.369468)
			(xy 25.065309 -178.350356) (xy 25.033496 -178.307795) (xy 25.008091 -178.261124) (xy 24.998426 -178.236372)
			(xy 24.993427 -178.224091) (xy 24.978135 -178.202442) (xy 24.957779 -178.185465) (xy 24.933736 -178.174308)
			(xy 24.90763 -178.169725) (xy 24.881224 -178.172025) (xy 24.868632 -178.176174) (xy 24.843594 -178.184813)
			(xy 24.792031 -178.196926) (xy 24.739414 -178.202996) (xy 24.71293 -178.203352) (xy 24.682962 -178.202862)
			(xy 24.623539 -178.195039) (xy 24.565645 -178.179526) (xy 24.510272 -178.15659) (xy 24.458366 -178.126622)
			(xy 24.410816 -178.090135) (xy 24.368435 -178.047754) (xy 24.331948 -178.000204) (xy 24.30198 -177.948298)
			(xy 24.279044 -177.892925) (xy 24.263531 -177.835031) (xy 24.255708 -177.775608) (xy 24.255708 -177.715672)
			(xy 24.263531 -177.656249) (xy 24.279044 -177.598355) (xy 24.30198 -177.542982) (xy 24.331948 -177.491076)
			(xy 24.368435 -177.443526) (xy 24.410816 -177.401145) (xy 24.458366 -177.364658) (xy 24.510272 -177.33469)
			(xy 24.565645 -177.311754) (xy 24.623539 -177.296241) (xy 24.682962 -177.288418) (xy 24.71293 -177.287936)
			(xy 24.746308 -177.288542) (xy 24.812356 -177.298236) (xy 24.844502 -177.30724) (xy 24.85759 -177.310723)
			(xy 24.884655 -177.311413) (xy 24.91095 -177.304965) (xy 24.934626 -177.291832) (xy 24.954018 -177.272939)
			(xy 24.967763 -177.249613) (xy 24.974893 -177.223495) (xy 24.975312 -177.209958) (xy 24.975312 -176.747932)
			(xy 24.816816 -176.589436) (xy 24.352504 -176.589436) (xy 24.325326 -176.588674) (xy 24.323294 -176.58842)
			(xy 24.06396 -176.58842) (xy 23.8633 -176.38776) (xy 22.68474 -176.38776) (xy 22.634702 -176.437798)
			(xy 21.714968 -176.437798) (xy 21.714968 -177.097944) (xy 21.716238 -177.103786) (xy 21.720992 -177.125381)
			(xy 21.726084 -177.169306) (xy 21.726398 -177.191416) (xy 21.725912 -177.218667) (xy 21.718156 -177.272615)
			(xy 21.702801 -177.32491) (xy 21.680159 -177.374487) (xy 21.650693 -177.420337) (xy 21.615002 -177.461528)
			(xy 21.573811 -177.497219) (xy 21.527961 -177.526685) (xy 21.478384 -177.549327) (xy 21.426089 -177.564682)
			(xy 21.372141 -177.572438) (xy 21.317639 -177.572438) (xy 21.263691 -177.564682) (xy 21.211396 -177.549327)
			(xy 21.161819 -177.526685) (xy 21.115969 -177.497219) (xy 21.074778 -177.461528) (xy 21.039087 -177.420337)
			(xy 21.009621 -177.374487) (xy 20.986979 -177.32491) (xy 20.971624 -177.272615) (xy 20.963868 -177.218667)
			(xy 20.963382 -177.191416) (xy 20.963685 -177.169306) (xy 20.968779 -177.12538) (xy 20.973542 -177.103786)
			(xy 20.974812 -177.097944) (xy 20.974812 -176.437798) (xy 19.80184 -176.437798) (xy 18.931128 -177.308256)
			(xy 18.931128 -177.74539) (xy 19.133312 -177.94732) (xy 19.621246 -177.94732) (xy 19.644824 -177.932275)
			(xy 19.695455 -177.908509) (xy 19.749015 -177.892396) (xy 19.804354 -177.884284) (xy 19.83232 -177.88382)
			(xy 19.859568 -177.884308) (xy 19.91351 -177.892066) (xy 19.965798 -177.907422) (xy 20.015369 -177.930062)
			(xy 20.061214 -177.959527) (xy 20.102399 -177.995216) (xy 20.138085 -178.036402) (xy 20.167547 -178.082248)
			(xy 20.190185 -178.13182) (xy 20.205538 -178.18411) (xy 20.213294 -178.238052) (xy 20.213294 -178.292548)
			(xy 20.205538 -178.34649) (xy 20.190185 -178.39878) (xy 20.167547 -178.448352) (xy 20.138085 -178.494198)
			(xy 20.102399 -178.535384) (xy 20.061214 -178.571073) (xy 20.015369 -178.600538) (xy 19.965798 -178.623178)
			(xy 19.91351 -178.638534) (xy 19.859568 -178.646292) (xy 19.83232 -178.646836) (xy 19.804355 -178.646364)
			(xy 19.749019 -178.638239) (xy 19.695459 -178.622131) (xy 19.644822 -178.598384) (xy 19.621246 -178.583336)
			(xy 19.00174 -178.583336) (xy 18.976758 -178.582821) (xy 18.927414 -178.574963) (xy 18.879901 -178.559498)
			(xy 18.835387 -178.536804) (xy 18.794961 -178.507437) (xy 18.77695 -178.490118) (xy 18.388584 -178.101752)
			(xy 18.372249 -178.084824) (xy 18.344246 -178.047025) (xy 18.322129 -178.005507) (xy 18.306379 -177.961181)
			(xy 18.301462 -177.938176) (xy 18.293334 -177.897282) (xy 16.293084 -177.897282) (xy 15.81023 -178.380136)
			(xy 15.81023 -179.135782) (xy 20.625798 -179.135782) (xy 20.625798 -179.075846) (xy 20.633621 -179.016424)
			(xy 20.649134 -178.958531) (xy 20.67207 -178.903158) (xy 20.702037 -178.851252) (xy 20.738524 -178.803702)
			(xy 20.780904 -178.761322) (xy 20.828454 -178.724835) (xy 20.88036 -178.694868) (xy 20.935733 -178.671932)
			(xy 20.993626 -178.656419) (xy 21.053048 -178.648596) (xy 21.112984 -178.648596) (xy 21.172406 -178.656419)
			(xy 21.230299 -178.671932) (xy 21.285672 -178.694868) (xy 21.337578 -178.724835) (xy 21.385128 -178.761322)
			(xy 21.427508 -178.803702) (xy 21.463995 -178.851252) (xy 21.493962 -178.903158) (xy 21.516898 -178.958531)
			(xy 21.532411 -179.016424) (xy 21.540234 -179.075846) (xy 21.540724 -179.105814) (xy 21.540234 -179.135782)
			(xy 21.532411 -179.195204) (xy 21.516898 -179.253097) (xy 21.493962 -179.30847) (xy 21.463995 -179.360376)
			(xy 21.427508 -179.407926) (xy 21.385128 -179.450306) (xy 21.337578 -179.486793) (xy 21.285672 -179.51676)
			(xy 21.230299 -179.539696) (xy 21.172406 -179.555209) (xy 21.112984 -179.563032) (xy 21.053048 -179.563032)
			(xy 20.993626 -179.555209) (xy 20.935733 -179.539696) (xy 20.88036 -179.51676) (xy 20.828454 -179.486793)
			(xy 20.780904 -179.450306) (xy 20.738524 -179.407926) (xy 20.702037 -179.360376) (xy 20.67207 -179.30847)
			(xy 20.649134 -179.253097) (xy 20.633621 -179.195204) (xy 20.625798 -179.135782) (xy 15.81023 -179.135782)
			(xy 15.81023 -181.954932) (xy 23.963628 -181.954932) (xy 23.967699 -181.89931) (xy 23.979825 -181.844873)
			(xy 23.999748 -181.792782) (xy 24.027044 -181.744147) (xy 24.06113 -181.700004) (xy 24.101279 -181.661295)
			(xy 24.146637 -181.628844) (xy 24.196237 -181.603343) (xy 24.249021 -181.585336) (xy 24.303864 -181.575206)
			(xy 24.359598 -181.573169) (xy 24.415035 -181.579269) (xy 24.468992 -181.593375) (xy 24.520321 -181.615187)
			(xy 24.567927 -181.644241) (xy 24.610795 -181.679916) (xy 24.648012 -181.721453) (xy 24.678785 -181.767966)
			(xy 24.702457 -181.818463) (xy 24.718525 -181.87187) (xy 24.726645 -181.927046) (xy 24.727154 -181.954932)
			(xy 24.726645 -181.982818) (xy 24.718525 -182.037994) (xy 24.702457 -182.091401) (xy 24.678785 -182.141898)
			(xy 24.648012 -182.188411) (xy 24.610795 -182.229948) (xy 24.567927 -182.265623) (xy 24.520321 -182.294677)
			(xy 24.468992 -182.316489) (xy 24.415035 -182.330595) (xy 24.359598 -182.336695) (xy 24.303864 -182.334658)
			(xy 24.249021 -182.324528) (xy 24.196237 -182.306521) (xy 24.146637 -182.28102) (xy 24.101279 -182.248569)
			(xy 24.06113 -182.20986) (xy 24.027044 -182.165717) (xy 23.999748 -182.117082) (xy 23.979825 -182.064991)
			(xy 23.967699 -182.010554) (xy 23.963628 -181.954932) (xy 15.81023 -181.954932) (xy 15.81023 -182.262018)
			(xy 17.35201 -183.803798) (xy 21.296376 -183.803798)
		)
		(stroke
			(width 0)
			(type solid)
		)
		(fill yes)
		(layer "B.Cu")
		(net "GND")
	)
	(gr_poly
		(pts
			(arc
				(start 63.340996 -360.27233)
				(mid 63.360519 -360.268429)
				(end 63.377064 -360.257344)
			)
			(arc
				(start 63.830454 -359.803954)
				(mid 63.841565 -359.78742)
				(end 63.84544 -359.767886)
			)
			(arc
				(start 63.84544 -334.71993)
				(mid 63.841539 -334.700407)
				(end 63.830454 -334.683862)
			)
			(arc
				(start 62.882526 -333.735934)
				(mid 62.865992 -333.724823)
				(end 62.846458 -333.720948)
			)
			(arc
				(start 39.111682 -333.720948)
				(mid 39.092159 -333.724849)
				(end 39.075614 -333.735934)
			)
			(arc
				(start 37.505386 -335.306162)
				(mid 37.494275 -335.322696)
				(end 37.4904 -335.34223)
			)
			(arc
				(start 37.4904 -335.909158)
				(mid 37.494301 -335.928681)
				(end 37.505386 -335.945226)
			)
			(arc
				(start 37.602414 -336.042254)
				(mid 37.618948 -336.053365)
				(end 37.638482 -336.05724)
			)
			(xy 39.111682 -336.05724) (xy 39.111682 -336.060288)
			(arc
				(start 39.643558 -336.060288)
				(mid 39.73133 -336.009861)
				(end 39.73195 -335.90865)
			)
			(arc
				(start 39.73195 -335.90865)
				(mid 39.646136 -335.697393)
				(end 39.616888 -335.471262)
			)
			(arc
				(start 39.616888 -335.471262)
				(mid 40.506396 -334.581754)
				(end 41.395904 -335.471262)
			)
			(arc
				(start 41.395904 -335.471262)
				(mid 41.366616 -335.697383)
				(end 41.280842 -335.90865)
			)
			(arc
				(start 41.280842 -335.90865)
				(mid 41.281486 -336.009847)
				(end 41.369234 -336.060288)
			)
			(arc
				(start 45.830744 -336.060288)
				(mid 45.918096 -336.010145)
				(end 45.91939 -335.909412)
			)
			(arc
				(start 45.91939 -335.909412)
				(mid 45.836065 -335.70075)
				(end 45.80763 -335.477866)
			)
			(arc
				(start 45.80763 -335.477612)
				(mid 46.697138 -334.588104)
				(end 47.586646 -335.477612)
			)
			(arc
				(start 47.586646 -335.477866)
				(mid 47.558266 -335.700764)
				(end 47.474886 -335.909412)
			)
			(arc
				(start 47.474886 -335.909412)
				(mid 47.476143 -336.010167)
				(end 47.563532 -336.060288)
			)
			(arc
				(start 52.028344 -336.060288)
				(mid 52.115696 -336.010145)
				(end 52.11699 -335.909412)
			)
			(arc
				(start 52.11699 -335.909412)
				(mid 52.033665 -335.70075)
				(end 52.00523 -335.477866)
			)
			(arc
				(start 52.00523 -335.477612)
				(mid 52.894738 -334.588104)
				(end 53.784246 -335.477612)
			)
			(arc
				(start 53.784246 -335.477866)
				(mid 53.755866 -335.700764)
				(end 53.672486 -335.909412)
			)
			(arc
				(start 53.672486 -335.909412)
				(mid 53.673743 -336.010167)
				(end 53.761132 -336.060288)
			)
			(arc
				(start 58.927238 -336.060288)
				(mid 58.946761 -336.064189)
				(end 58.963306 -336.075274)
			)
			(arc
				(start 59.360054 -336.472022)
				(mid 59.371165 -336.488556)
				(end 59.37504 -336.50809)
			)
			(xy 59.37504 -344.276426) (xy 58.78322 -344.868246) (xy 35.91052 -344.868246) (xy 35.451034 -344.868246)
			(xy 35.25266 -345.06662) (xy 35.25266 -352.58756) (xy 35.3949 -352.7298) (xy 36.848288 -352.7298)
			(arc
				(start 37.645594 -353.527106)
				(mid 37.662128 -353.538217)
				(end 37.681662 -353.542092)
			)
			(arc
				(start 39.424356 -353.542092)
				(mid 39.443879 -353.545993)
				(end 39.460424 -353.557078)
			)
			(arc
				(start 39.760906 -353.85756)
				(mid 39.772017 -353.874094)
				(end 39.775892 -353.893628)
			)
			(arc
				(start 39.775892 -355.707188)
				(mid 39.779793 -355.726711)
				(end 39.790878 -355.743256)
			)
			(arc
				(start 39.878762 -355.83114)
				(mid 39.895296 -355.842251)
				(end 39.91483 -355.846126)
			)
			(arc
				(start 41.51249 -355.846126)
				(mid 41.522458 -355.845189)
				(end 41.532048 -355.842316)
			)
			(arc
				(start 41.54932 -355.83495)
				(mid 41.558103 -355.83029)
				(end 41.56583 -355.824028)
			)
			(arc
				(start 41.600628 -355.78923)
				(mid 41.611739 -355.772696)
				(end 41.615614 -355.753162)
			)
			(arc
				(start 41.615614 -353.630738)
				(mid 41.619515 -353.611215)
				(end 41.6306 -353.59467)
			)
			(arc
				(start 41.70172 -353.52355)
				(mid 41.718254 -353.512439)
				(end 41.737788 -353.508564)
			)
			(arc
				(start 46.229016 -353.508564)
				(mid 46.248539 -353.512465)
				(end 46.265084 -353.52355)
			)
			(arc
				(start 46.469808 -353.728274)
				(mid 46.480919 -353.744808)
				(end 46.484794 -353.764342)
			)
			(arc
				(start 46.484794 -355.873558)
				(mid 46.480893 -355.893081)
				(end 46.469808 -355.909626)
			)
			(arc
				(start 46.13656 -356.242874)
				(mid 46.125449 -356.259408)
				(end 46.121574 -356.278942)
			)
			(arc
				(start 46.121574 -358.692958)
				(mid 46.125475 -358.712481)
				(end 46.13656 -358.729026)
			)
			(arc
				(start 46.787308 -359.379774)
				(mid 46.803842 -359.390885)
				(end 46.823376 -359.39476)
			)
			(arc
				(start 47.309532 -359.39476)
				(mid 47.329055 -359.390859)
				(end 47.3456 -359.379774)
			)
			(arc
				(start 47.473108 -359.252266)
				(mid 47.484219 -359.235732)
				(end 47.488094 -359.216198)
			)
			(arc
				(start 47.488094 -359.011982)
				(mid 47.484193 -358.992459)
				(end 47.473108 -358.975914)
			)
			(arc
				(start 47.19828 -358.701086)
				(mid 47.187169 -358.684552)
				(end 47.183294 -358.665018)
			)
			(arc
				(start 47.183294 -353.745038)
				(mid 47.187195 -353.725515)
				(end 47.19828 -353.70897)
			)
			(xy 47.318422 -353.588828)
			(arc
				(start 47.384208 -353.522788)
				(mid 47.400742 -353.511677)
				(end 47.420276 -353.507802)
			)
			(arc
				(start 48.806354 -353.507802)
				(mid 48.825877 -353.511703)
				(end 48.842422 -353.522788)
			)
			(arc
				(start 49.225708 -353.906074)
				(mid 49.236819 -353.922608)
				(end 49.240694 -353.942142)
			)
			(arc
				(start 49.240694 -355.652578)
				(mid 49.244595 -355.672101)
				(end 49.25568 -355.688646)
			)
			(arc
				(start 49.397666 -355.830632)
				(mid 49.4142 -355.841743)
				(end 49.433734 -355.845618)
			)
			(arc
				(start 51.152044 -355.845618)
				(mid 51.171567 -355.841717)
				(end 51.188112 -355.830632)
			)
			(arc
				(start 51.298348 -355.720396)
				(mid 51.309459 -355.703862)
				(end 51.313334 -355.684328)
			)
			(arc
				(start 51.313334 -353.784662)
				(mid 51.317235 -353.765139)
				(end 51.32832 -353.748594)
			)
			(arc
				(start 51.553364 -353.52355)
				(mid 51.569898 -353.512439)
				(end 51.589432 -353.508564)
			)
			(arc
				(start 56.42229 -353.508564)
				(mid 56.441813 -353.512465)
				(end 56.458358 -353.52355)
			)
			(arc
				(start 56.626252 -353.691444)
				(mid 56.637363 -353.707978)
				(end 56.641238 -353.727512)
			)
			(arc
				(start 56.641238 -360.048048)
				(mid 56.645139 -360.067571)
				(end 56.656224 -360.084116)
			)
			(arc
				(start 56.829452 -360.257344)
				(mid 56.845986 -360.268455)
				(end 56.86552 -360.27233)
			)
		)
		(stroke
			(width 0)
			(type solid)
		)
		(fill yes)
		(layer "B.Cu")
		(net "GND")
	)
	(gr_poly
		(pts
			(xy 163.713922 -257.783838) (xy 163.713922 -256.668778) (xy 163.985194 -256.397506) (xy 165.939216 -256.397506)
			(xy 166.0271 -256.309368) (xy 166.0271 -254.715772) (xy 166.026647 -254.702046) (xy 166.019324 -254.675589)
			(xy 166.005215 -254.65204) (xy 165.985341 -254.633103) (xy 165.96114 -254.620146) (xy 165.93436 -254.614108)
			(xy 165.90694 -254.615424) (xy 165.89375 -254.619252) (xy 165.859902 -254.629687) (xy 165.789971 -254.640915)
			(xy 165.754558 -254.641604) (xy 165.72544 -254.641146) (xy 165.667703 -254.633539) (xy 165.611453 -254.618461)
			(xy 165.557653 -254.596169) (xy 165.507222 -254.567046) (xy 165.461024 -254.53159) (xy 165.419849 -254.490407)
			(xy 165.384402 -254.444202) (xy 165.35529 -254.393765) (xy 165.33301 -254.33996) (xy 165.317943 -254.283706)
			(xy 165.310348 -254.225968) (xy 165.309804 -254.19685) (xy 165.309804 -252.471936) (xy 164.903658 -252.06579)
			(xy 164.903658 -251.7902) (xy 164.902642 -251.785374) (xy 164.89953 -251.768401) (xy 164.89622 -251.734049)
			(xy 164.896038 -251.716794) (xy 164.896236 -251.699539) (xy 164.899543 -251.665189) (xy 164.902642 -251.648214)
			(xy 164.903658 -251.643388) (xy 164.903658 -250.843796) (xy 164.581078 -250.521216) (xy 164.405564 -250.521216)
			(xy 164.392001 -250.521647) (xy 164.365832 -250.528796) (xy 164.342468 -250.542579) (xy 164.323555 -250.562026)
			(xy 164.310426 -250.585765) (xy 164.304008 -250.612122) (xy 164.304753 -250.639239) (xy 164.312608 -250.665204)
			(xy 164.319458 -250.676918) (xy 164.332454 -250.698313) (xy 164.352967 -250.743976) (xy 164.366874 -250.792064)
			(xy 164.3739 -250.841627) (xy 164.374322 -250.866656) (xy 164.373824 -250.893305) (xy 164.365881 -250.946009)
			(xy 164.350171 -250.996939) (xy 164.327045 -251.04496) (xy 164.297021 -251.088997) (xy 164.260769 -251.128068)
			(xy 164.219098 -251.161299) (xy 164.17294 -251.187948) (xy 164.123326 -251.20742) (xy 164.071364 -251.21928)
			(xy 164.018214 -251.223264) (xy 163.965064 -251.21928) (xy 163.913102 -251.20742) (xy 163.863488 -251.187948)
			(xy 163.81733 -251.161299) (xy 163.775659 -251.128068) (xy 163.739407 -251.088997) (xy 163.709383 -251.04496)
			(xy 163.686257 -250.996939) (xy 163.670547 -250.946009) (xy 163.662604 -250.893305) (xy 163.662106 -250.866656)
			(xy 163.662553 -250.841629) (xy 163.669598 -250.792074) (xy 163.683503 -250.74399) (xy 163.703993 -250.698322)
			(xy 163.71697 -250.676918) (xy 163.723837 -250.665204) (xy 163.731731 -250.639233) (xy 163.7325 -250.612099)
			(xy 163.72609 -250.585723) (xy 163.712954 -250.561969) (xy 163.694021 -250.542518) (xy 163.67063 -250.528745)
			(xy 163.644437 -250.521625) (xy 163.630864 -250.521216) (xy 162.195764 -250.521216) (xy 162.182201 -250.521647)
			(xy 162.156032 -250.528796) (xy 162.132668 -250.542579) (xy 162.113755 -250.562026) (xy 162.100626 -250.585765)
			(xy 162.094208 -250.612122) (xy 162.094953 -250.639239) (xy 162.102808 -250.665204) (xy 162.109658 -250.676918)
			(xy 162.122654 -250.698313) (xy 162.143167 -250.743976) (xy 162.157074 -250.792064) (xy 162.1641 -250.841627)
			(xy 162.164522 -250.866656) (xy 162.164024 -250.893305) (xy 162.156081 -250.946009) (xy 162.140371 -250.996939)
			(xy 162.117245 -251.04496) (xy 162.087221 -251.088997) (xy 162.050969 -251.128068) (xy 162.009298 -251.161299)
			(xy 161.96314 -251.187948) (xy 161.913526 -251.20742) (xy 161.861564 -251.21928) (xy 161.808414 -251.223264)
			(xy 161.755264 -251.21928) (xy 161.703302 -251.20742) (xy 161.653688 -251.187948) (xy 161.60753 -251.161299)
			(xy 161.565859 -251.128068) (xy 161.529607 -251.088997) (xy 161.499583 -251.04496) (xy 161.476457 -250.996939)
			(xy 161.460747 -250.946009) (xy 161.452804 -250.893305) (xy 161.452306 -250.866656) (xy 161.452753 -250.841629)
			(xy 161.459798 -250.792074) (xy 161.473703 -250.74399) (xy 161.494193 -250.698322) (xy 161.50717 -250.676918)
			(xy 161.514037 -250.665204) (xy 161.521931 -250.639233) (xy 161.5227 -250.612099) (xy 161.51629 -250.585723)
			(xy 161.503154 -250.561969) (xy 161.484221 -250.542518) (xy 161.46083 -250.528745) (xy 161.434637 -250.521625)
			(xy 161.421064 -250.521216) (xy 157.802072 -250.521216) (xy 157.796738 -250.52655) (xy 156.735018 -250.52655)
			(xy 155.6512 -251.610368) (xy 155.6512 -251.743443) (xy 157.352736 -251.743443) (xy 157.352736 -251.690145)
			(xy 157.360679 -251.637441) (xy 157.376389 -251.586511) (xy 157.399515 -251.53849) (xy 157.429539 -251.494453)
			(xy 157.465791 -251.455382) (xy 157.507462 -251.422151) (xy 157.55362 -251.395502) (xy 157.603234 -251.37603)
			(xy 157.655196 -251.36417) (xy 157.708346 -251.360187) (xy 157.761496 -251.36417) (xy 157.813458 -251.37603)
			(xy 157.863072 -251.395502) (xy 157.90923 -251.422151) (xy 157.950901 -251.455382) (xy 157.987153 -251.494453)
			(xy 158.017177 -251.53849) (xy 158.040303 -251.586511) (xy 158.056013 -251.637441) (xy 158.063956 -251.690145)
			(xy 158.064454 -251.716794) (xy 158.063956 -251.743443) (xy 159.562536 -251.743443) (xy 159.562536 -251.690145)
			(xy 159.570479 -251.637441) (xy 159.586189 -251.586511) (xy 159.609315 -251.53849) (xy 159.639339 -251.494453)
			(xy 159.675591 -251.455382) (xy 159.717262 -251.422151) (xy 159.76342 -251.395502) (xy 159.813034 -251.37603)
			(xy 159.864996 -251.36417) (xy 159.918146 -251.360187) (xy 159.971296 -251.36417) (xy 160.023258 -251.37603)
			(xy 160.072872 -251.395502) (xy 160.11903 -251.422151) (xy 160.160701 -251.455382) (xy 160.196953 -251.494453)
			(xy 160.226977 -251.53849) (xy 160.250103 -251.586511) (xy 160.265813 -251.637441) (xy 160.273756 -251.690145)
			(xy 160.274254 -251.716794) (xy 160.273756 -251.743443) (xy 160.265813 -251.796147) (xy 160.250103 -251.847077)
			(xy 160.226977 -251.895098) (xy 160.196953 -251.939135) (xy 160.160701 -251.978206) (xy 160.11903 -252.011437)
			(xy 160.072872 -252.038086) (xy 160.023258 -252.057558) (xy 159.971296 -252.069418) (xy 159.918146 -252.073402)
			(xy 159.864996 -252.069418) (xy 159.813034 -252.057558) (xy 159.76342 -252.038086) (xy 159.717262 -252.011437)
			(xy 159.675591 -251.978206) (xy 159.639339 -251.939135) (xy 159.609315 -251.895098) (xy 159.586189 -251.847077)
			(xy 159.570479 -251.796147) (xy 159.562536 -251.743443) (xy 158.063956 -251.743443) (xy 158.056013 -251.796147)
			(xy 158.040303 -251.847077) (xy 158.017177 -251.895098) (xy 157.987153 -251.939135) (xy 157.950901 -251.978206)
			(xy 157.90923 -252.011437) (xy 157.863072 -252.038086) (xy 157.813458 -252.057558) (xy 157.761496 -252.069418)
			(xy 157.708346 -252.073402) (xy 157.655196 -252.069418) (xy 157.603234 -252.057558) (xy 157.55362 -252.038086)
			(xy 157.507462 -252.011437) (xy 157.465791 -251.978206) (xy 157.429539 -251.939135) (xy 157.399515 -251.895098)
			(xy 157.376389 -251.847077) (xy 157.360679 -251.796147) (xy 157.352736 -251.743443) (xy 155.6512 -251.743443)
			(xy 155.6512 -254.258966) (xy 159.326796 -254.258966) (xy 159.326796 -254.174434) (xy 159.334595 -254.090264)
			(xy 159.350128 -254.007172) (xy 159.373261 -253.925867) (xy 159.403796 -253.847044) (xy 159.441475 -253.771375)
			(xy 159.485974 -253.699504) (xy 159.536915 -253.632047) (xy 159.593863 -253.569577) (xy 159.656331 -253.512628)
			(xy 159.723788 -253.461685) (xy 159.795657 -253.417184) (xy 159.871326 -253.379504) (xy 159.950148 -253.348967)
			(xy 160.031452 -253.325832) (xy 160.114544 -253.310298) (xy 160.198714 -253.302497) (xy 160.24098 -253.302008)
			(xy 161.48558 -253.302008) (xy 161.527844 -253.302557) (xy 161.612011 -253.310354) (xy 161.6951 -253.325884)
			(xy 161.776402 -253.349015) (xy 161.855222 -253.379549) (xy 161.930889 -253.417225) (xy 162.002757 -253.461722)
			(xy 162.070212 -253.512661) (xy 162.13268 -253.569606) (xy 162.189626 -253.632072) (xy 162.240567 -253.699527)
			(xy 162.285065 -253.771393) (xy 162.322743 -253.847059) (xy 162.353279 -253.925879) (xy 162.376411 -254.00718)
			(xy 162.3905 -254.08255) (xy 163.28517 -254.08255) (xy 163.28572 -254.055506) (xy 163.293893 -254.002039)
			(xy 163.310057 -253.950424) (xy 163.333843 -253.901847) (xy 163.364701 -253.857425) (xy 163.401922 -253.818182)
			(xy 163.444651 -253.785019) (xy 163.491903 -253.7587) (xy 163.517072 -253.748794) (xy 163.527486 -253.744984)
			(xy 164.06495 -253.20752) (xy 164.068252 -253.193804) (xy 164.075931 -253.164272) (xy 164.098069 -253.10741)
			(xy 164.127568 -253.053995) (xy 164.163903 -253.004973) (xy 164.20643 -252.961214) (xy 164.254395 -252.923495)
			(xy 164.306946 -252.892484) (xy 164.363153 -252.868731) (xy 164.422018 -252.852658) (xy 164.482496 -252.844551)
			(xy 164.513006 -252.844046) (xy 164.54297 -252.844628) (xy 164.602386 -252.852451) (xy 164.660273 -252.867963)
			(xy 164.71564 -252.890897) (xy 164.767539 -252.920862) (xy 164.815084 -252.957344) (xy 164.857459 -252.999721)
			(xy 164.893942 -253.047266) (xy 164.923906 -253.099166) (xy 164.946839 -253.154533) (xy 164.96235 -253.21242)
			(xy 164.970172 -253.271836) (xy 164.970172 -253.331764) (xy 164.96235 -253.39118) (xy 164.946839 -253.449067)
			(xy 164.923906 -253.504434) (xy 164.893942 -253.556334) (xy 164.857459 -253.603879) (xy 164.815084 -253.646256)
			(xy 164.767539 -253.682738) (xy 164.71564 -253.712703) (xy 164.660273 -253.735637) (xy 164.602386 -253.751149)
			(xy 164.54297 -253.758972) (xy 164.513006 -253.759462) (xy 164.496948 -253.759308) (xy 164.464915 -253.757017)
			(xy 164.448998 -253.75489) (xy 164.423852 -253.751334) (xy 163.978844 -254.196342) (xy 163.975034 -254.206756)
			(xy 163.965166 -254.231943) (xy 163.938842 -254.2792) (xy 163.905675 -254.321933) (xy 163.866427 -254.359159)
			(xy 163.822001 -254.390021) (xy 163.773419 -254.413811) (xy 163.721798 -254.42998) (xy 163.668325 -254.438157)
			(xy 163.641278 -254.438658) (xy 163.613297 -254.43808) (xy 163.558024 -254.429323) (xy 163.504801 -254.412028)
			(xy 163.454938 -254.386622) (xy 163.409662 -254.353729) (xy 163.370089 -254.314159) (xy 163.337193 -254.268886)
			(xy 163.311782 -254.219025) (xy 163.294484 -254.165804) (xy 163.285723 -254.110531) (xy 163.28517 -254.08255)
			(xy 162.3905 -254.08255) (xy 162.391943 -254.090269) (xy 162.399743 -254.174436) (xy 162.399743 -254.258964)
			(xy 162.391943 -254.343131) (xy 162.376411 -254.42622) (xy 162.353279 -254.507521) (xy 162.322743 -254.586341)
			(xy 162.285065 -254.662007) (xy 162.240567 -254.733873) (xy 162.189626 -254.801328) (xy 162.13268 -254.863794)
			(xy 162.070212 -254.920739) (xy 162.002757 -254.971678) (xy 161.930889 -255.016175) (xy 161.855222 -255.053851)
			(xy 161.776402 -255.084385) (xy 161.6951 -255.107516) (xy 161.612011 -255.123046) (xy 161.527844 -255.130843)
			(xy 161.48558 -255.131316) (xy 160.24098 -255.131316) (xy 160.198714 -255.130903) (xy 160.114544 -255.123102)
			(xy 160.031452 -255.107568) (xy 159.950148 -255.084433) (xy 159.871326 -255.053896) (xy 159.795657 -255.016216)
			(xy 159.723788 -254.971715) (xy 159.656331 -254.920772) (xy 159.593863 -254.863823) (xy 159.536915 -254.801353)
			(xy 159.485974 -254.733896) (xy 159.441475 -254.662025) (xy 159.403796 -254.586356) (xy 159.373261 -254.507533)
			(xy 159.350128 -254.426228) (xy 159.334595 -254.343136) (xy 159.326796 -254.258966) (xy 155.6512 -254.258966)
			(xy 155.6512 -257.673348) (xy 155.833064 -257.855212) (xy 159.990536 -257.855212) (xy 160.154112 -258.019042)
			(xy 163.478718 -258.019042)
		)
		(stroke
			(width 0)
			(type solid)
		)
		(fill yes)
		(layer "B.Cu")
		(net "PVCCFA_EHV_FIVRA_CPU1")
	)
	(gr_poly
		(pts
			(xy 337.500976 -51.369468) (xy 337.500976 -50.973228) (xy 337.384136 -50.856388) (xy 337.384136 -50.856134)
			(xy 337.383671 -50.845576) (xy 337.375283 -50.826205) (xy 337.359794 -50.811864) (xy 337.339835 -50.804991)
			(xy 337.329272 -50.805334) (xy 337.299808 -50.806604) (xy 337.273157 -50.806131) (xy 337.220449 -50.798188)
			(xy 337.169515 -50.782478) (xy 337.121491 -50.759352) (xy 337.07745 -50.729326) (xy 337.038376 -50.693071)
			(xy 337.005142 -50.651398) (xy 336.97849 -50.605237) (xy 336.959016 -50.555619) (xy 336.947155 -50.503653)
			(xy 336.943172 -50.4505) (xy 336.947155 -50.397347) (xy 336.959016 -50.345381) (xy 336.97849 -50.295763)
			(xy 337.005142 -50.249602) (xy 337.038376 -50.207929) (xy 337.07745 -50.171674) (xy 337.121491 -50.141648)
			(xy 337.169515 -50.118522) (xy 337.220449 -50.102812) (xy 337.273157 -50.094869) (xy 337.299808 -50.094388)
			(xy 337.322502 -50.094747) (xy 337.367525 -50.100508) (xy 337.411455 -50.111922) (xy 337.43265 -50.120042)
			(xy 337.445998 -50.124893) (xy 337.474238 -50.127806) (xy 337.502189 -50.122836) (xy 337.527693 -50.110367)
			(xy 337.548782 -50.091362) (xy 337.563828 -50.067287) (xy 337.571668 -50.040002) (xy 337.572096 -50.025808)
			(xy 337.572096 -49.682908) (xy 337.806538 -49.448466) (xy 337.809078 -49.44491) (xy 337.827087 -49.420484)
			(xy 337.869997 -49.377576) (xy 337.894422 -49.359566) (xy 337.897978 -49.357026) (xy 337.91271 -49.342294)
			(xy 337.920838 -49.342294) (xy 337.932014 -49.336198) (xy 337.958006 -49.322987) (xy 338.013227 -49.304286)
			(xy 338.070757 -49.294834) (xy 338.099908 -49.294288) (xy 338.129057 -49.294854) (xy 338.186582 -49.304313)
			(xy 338.2418 -49.323011) (xy 338.267802 -49.336198) (xy 338.278978 -49.342294) (xy 338.720938 -49.342294)
			(xy 338.732114 -49.336198) (xy 338.752807 -49.325603) (xy 338.79633 -49.309268) (xy 338.841607 -49.298724)
			(xy 338.864702 -49.296066) (xy 338.882736 -49.294288) (xy 339.125306 -49.051718) (xy 339.125306 -46.308518)
			(xy 338.984336 -46.167548) (xy 338.511896 -46.167548) (xy 338.511896 -46.012608) (xy 338.351876 -45.852588)
			(xy 338.351876 -45.527468) (xy 338.242656 -45.418248) (xy 337.965796 -45.418248) (xy 337.83016 -45.554138)
			(xy 337.83016 -46.671738) (xy 337.528662 -46.972982) (xy 337.561682 -47.008796) (xy 337.579292 -47.028636)
			(xy 337.609047 -47.072553) (xy 337.631958 -47.120398) (xy 337.64752 -47.171111) (xy 337.655389 -47.223572)
			(xy 337.655916 -47.250096) (xy 337.655411 -47.277157) (xy 337.647218 -47.330654) (xy 337.631019 -47.382295)
			(xy 337.607189 -47.430888) (xy 337.576276 -47.475312) (xy 337.538994 -47.514545) (xy 337.496202 -47.54768)
			(xy 337.472782 -47.561246) (xy 337.461147 -47.56819) (xy 337.441753 -47.5871) (xy 337.428015 -47.610444)
			(xy 337.420898 -47.636579) (xy 337.420904 -47.663666) (xy 337.428032 -47.689797) (xy 337.441781 -47.713135)
			(xy 337.461183 -47.732037) (xy 337.472782 -47.739046) (xy 337.496195 -47.752622) (xy 337.538987 -47.785753)
			(xy 337.576268 -47.824983) (xy 337.607177 -47.869407) (xy 337.631002 -47.917999) (xy 337.647192 -47.96964)
			(xy 337.655374 -48.023136) (xy 337.655916 -48.050196) (xy 337.655418 -48.076845) (xy 337.647475 -48.129549)
			(xy 337.631765 -48.180479) (xy 337.608639 -48.2285) (xy 337.578615 -48.272537) (xy 337.542363 -48.311608)
			(xy 337.500692 -48.344839) (xy 337.454534 -48.371488) (xy 337.40492 -48.39096) (xy 337.352958 -48.40282)
			(xy 337.299808 -48.406804) (xy 337.246658 -48.40282) (xy 337.194696 -48.39096) (xy 337.145082 -48.371488)
			(xy 337.098924 -48.344839) (xy 337.057253 -48.311608) (xy 337.021001 -48.272537) (xy 336.990977 -48.2285)
			(xy 336.967851 -48.180479) (xy 336.952141 -48.129549) (xy 336.944198 -48.076845) (xy 336.9437 -48.050196)
			(xy 336.944206 -48.023136) (xy 336.9524 -47.969639) (xy 336.9686 -47.918) (xy 336.992432 -47.869409)
			(xy 337.023345 -47.824987) (xy 337.060628 -47.785757) (xy 337.103421 -47.752624) (xy 337.126834 -47.739046)
			(xy 337.13849 -47.732108) (xy 337.157922 -47.713196) (xy 337.171694 -47.689838) (xy 337.178834 -47.66368)
			(xy 337.17884 -47.636564) (xy 337.171711 -47.610403) (xy 337.15795 -47.587039) (xy 337.138526 -47.568119)
			(xy 337.126834 -47.561246) (xy 337.103416 -47.547672) (xy 337.060613 -47.514545) (xy 337.02332 -47.475318)
			(xy 336.992399 -47.430895) (xy 336.968561 -47.382302) (xy 336.952357 -47.330659) (xy 336.944161 -47.277159)
			(xy 336.9437 -47.250096) (xy 336.944172 -47.222733) (xy 336.952496 -47.168644) (xy 336.969009 -47.116468)
			(xy 336.99332 -47.067439) (xy 337.024855 -47.022713) (xy 337.043522 -47.0027) (xy 337.052333 -46.992932)
			(xy 337.065104 -46.969947) (xy 337.07159 -46.944463) (xy 337.071361 -46.918169) (xy 337.064432 -46.892803)
			(xy 337.051261 -46.870043) (xy 337.042252 -46.86046) (xy 336.792824 -46.610778) (xy 336.792824 -45.215556)
			(xy 337.014566 -44.99356) (xy 337.50885 -44.99356) (xy 337.577176 -44.925488) (xy 337.577176 -44.808648)
			(xy 338.055712 -44.330112) (xy 338.049362 -44.302426) (xy 338.044964 -44.282395) (xy 338.040256 -44.241653)
			(xy 338.039964 -44.221146) (xy 338.040481 -44.193157) (xy 338.04923 -44.137869) (xy 338.066522 -44.084629)
			(xy 338.091929 -44.034751) (xy 338.124827 -43.989461) (xy 338.164404 -43.949875) (xy 338.209687 -43.916968)
			(xy 338.259561 -43.89155) (xy 338.312797 -43.874248) (xy 338.368084 -43.865486) (xy 338.396072 -43.865038)
			(xy 338.416579 -43.865325) (xy 338.457322 -43.870031) (xy 338.477352 -43.874436) (xy 338.505038 -43.880786)
			(xy 338.702396 -43.683428) (xy 338.702396 -42.855388) (xy 338.567776 -42.720768) (xy 338.410296 -42.720768)
			(xy 338.38769 -42.698162) (xy 338.368894 -42.696638) (xy 338.34239 -42.69411) (xy 338.290503 -42.682183)
			(xy 338.24097 -42.662665) (xy 338.194895 -42.635988) (xy 338.153306 -42.602749) (xy 338.11713 -42.563689)
			(xy 338.087172 -42.519677) (xy 338.064102 -42.471695) (xy 338.048432 -42.420814) (xy 338.040513 -42.368166)
			(xy 338.039964 -42.341546) (xy 338.041488 -42.309288) (xy 338.04352 -42.285412) (xy 337.858862 -42.100754)
			(xy 337.822794 -42.133774) (xy 337.802966 -42.151346) (xy 337.759085 -42.181033) (xy 337.711289 -42.203888)
			(xy 337.660634 -42.219409) (xy 337.608238 -42.227252) (xy 337.581748 -42.227754) (xy 337.555776 -42.227286)
			(xy 337.504384 -42.219743) (xy 337.454634 -42.204811) (xy 337.407582 -42.182807) (xy 337.364228 -42.154197)
			(xy 337.325492 -42.11959) (xy 337.292198 -42.079721) (xy 337.278218 -42.057828) (xy 336.472276 -42.057828)
			(xy 336.32648 -42.203878) (xy 336.32648 -42.838095) (xy 337.226138 -42.838095) (xy 337.226138 -42.784797)
			(xy 337.234081 -42.732093) (xy 337.249791 -42.681163) (xy 337.272917 -42.633142) (xy 337.302941 -42.589105)
			(xy 337.339193 -42.550034) (xy 337.380864 -42.516803) (xy 337.427022 -42.490154) (xy 337.476636 -42.470682)
			(xy 337.528598 -42.458822) (xy 337.581748 -42.454839) (xy 337.634898 -42.458822) (xy 337.68686 -42.470682)
			(xy 337.736474 -42.490154) (xy 337.782632 -42.516803) (xy 337.824303 -42.550034) (xy 337.860555 -42.589105)
			(xy 337.890579 -42.633142) (xy 337.913705 -42.681163) (xy 337.929415 -42.732093) (xy 337.937358 -42.784797)
			(xy 337.937856 -42.811446) (xy 337.937358 -42.838095) (xy 337.929415 -42.890799) (xy 337.913705 -42.941729)
			(xy 337.890579 -42.98975) (xy 337.860555 -43.033787) (xy 337.824303 -43.072858) (xy 337.782632 -43.106089)
			(xy 337.736474 -43.132738) (xy 337.68686 -43.15221) (xy 337.634898 -43.16407) (xy 337.581748 -43.168054)
			(xy 337.528598 -43.16407) (xy 337.476636 -43.15221) (xy 337.427022 -43.132738) (xy 337.380864 -43.106089)
			(xy 337.339193 -43.072858) (xy 337.302941 -43.033787) (xy 337.272917 -42.98975) (xy 337.249791 -42.941729)
			(xy 337.234081 -42.890799) (xy 337.226138 -42.838095) (xy 336.32648 -42.838095) (xy 336.32648 -43.777895)
			(xy 337.226138 -43.777895) (xy 337.226138 -43.724597) (xy 337.234081 -43.671893) (xy 337.249791 -43.620963)
			(xy 337.272917 -43.572942) (xy 337.302941 -43.528905) (xy 337.339193 -43.489834) (xy 337.380864 -43.456603)
			(xy 337.427022 -43.429954) (xy 337.476636 -43.410482) (xy 337.528598 -43.398622) (xy 337.581748 -43.394639)
			(xy 337.634898 -43.398622) (xy 337.68686 -43.410482) (xy 337.736474 -43.429954) (xy 337.782632 -43.456603)
			(xy 337.824303 -43.489834) (xy 337.860555 -43.528905) (xy 337.890579 -43.572942) (xy 337.913705 -43.620963)
			(xy 337.929415 -43.671893) (xy 337.937358 -43.724597) (xy 337.937856 -43.751246) (xy 337.937358 -43.777895)
			(xy 337.929415 -43.830599) (xy 337.913705 -43.881529) (xy 337.890579 -43.92955) (xy 337.860555 -43.973587)
			(xy 337.824303 -44.012658) (xy 337.782632 -44.045889) (xy 337.736474 -44.072538) (xy 337.68686 -44.09201)
			(xy 337.634898 -44.10387) (xy 337.581748 -44.107854) (xy 337.528598 -44.10387) (xy 337.476636 -44.09201)
			(xy 337.427022 -44.072538) (xy 337.380864 -44.045889) (xy 337.339193 -44.012658) (xy 337.302941 -43.973587)
			(xy 337.272917 -43.92955) (xy 337.249791 -43.881529) (xy 337.234081 -43.830599) (xy 337.226138 -43.777895)
			(xy 336.32648 -43.777895) (xy 336.32648 -43.801538) (xy 336.350356 -43.825668) (xy 336.350356 -44.334684)
			(xy 336.416904 -44.400978) (xy 336.416904 -45.046138) (xy 336.350356 -45.112432) (xy 336.350356 -45.149008)
			(xy 336.243676 -45.255688) (xy 336.2071 -45.255688) (xy 336.195162 -45.26788) (xy 335.685638 -45.26788)
			(xy 335.606136 -45.347128) (xy 335.606136 -46.6852) (xy 335.629758 -46.708568) (xy 336.194654 -46.708568)
			(xy 336.419444 -46.933358) (xy 336.419444 -48.569118) (xy 336.286856 -48.701452) (xy 336.286856 -48.712628)
			(xy 336.241136 -48.758348) (xy 336.22996 -48.758348) (xy 336.229706 -48.758856) (xy 335.236566 -48.758856)
			(xy 335.081372 -48.603408) (xy 334.620362 -48.603408) (xy 334.592422 -48.631348) (xy 334.592422 -48.705008)
			(xy 334.59928 -48.705008) (xy 334.59928 -49.407064) (xy 334.694276 -49.502314) (xy 334.694276 -49.772316)
			(xy 335.205832 -49.772316) (xy 335.24571 -49.812448) (xy 335.443322 -49.812448) (xy 335.532222 -49.901348)
			(xy 335.532222 -49.997614) (xy 335.53274 -50.012152) (xy 335.540932 -50.040051) (xy 335.55665 -50.064514)
			(xy 335.57862 -50.08356) (xy 335.605064 -50.095649) (xy 335.633843 -50.099801) (xy 335.6483 -50.098198)
			(xy 335.661053 -50.096428) (xy 335.686733 -50.094523) (xy 335.699608 -50.094388) (xy 335.726257 -50.094886)
			(xy 335.77896 -50.102831) (xy 335.82989 -50.118542) (xy 335.87791 -50.141668) (xy 335.921947 -50.171693)
			(xy 335.961017 -50.207945) (xy 335.994248 -50.249616) (xy 336.020897 -50.295774) (xy 336.040369 -50.345388)
			(xy 336.052229 -50.397351) (xy 336.056212 -50.4505) (xy 336.052229 -50.503649) (xy 336.040369 -50.555612)
			(xy 336.020897 -50.605226) (xy 335.994248 -50.651384) (xy 335.961017 -50.693055) (xy 335.921947 -50.729307)
			(xy 335.87791 -50.759332) (xy 335.82989 -50.782458) (xy 335.77896 -50.798169) (xy 335.726257 -50.806114)
			(xy 335.699608 -50.806604) (xy 335.686146 -50.80635) (xy 335.672494 -50.806273) (xy 335.645925 -50.812507)
			(xy 335.621959 -50.825563) (xy 335.602314 -50.844505) (xy 335.588394 -50.867979) (xy 335.581197 -50.894304)
			(xy 335.580736 -50.90795) (xy 335.580736 -51.502818) (xy 335.586578 -51.508914) (xy 337.36153 -51.508914)
		)
		(stroke
			(width 0)
			(type solid)
		)
		(fill yes)
		(layer "B.Cu")
		(net "P1V05_PCH_AUX")
	)
	(gr_poly
		(pts
			(xy 215.06434 -398.8689) (xy 217.95486 -398.8689) (xy 219.22994 -400.14398) (xy 224.51568 -400.14398)
			(xy 225.61804 -399.04162) (xy 228.76256 -399.04162) (xy 229.95636 -400.23542) (xy 238.74222 -400.23542)
			(xy 239.02416 -399.95348) (xy 239.02416 -397.9037) (xy 239.57788 -397.34998) (xy 243.27866 -397.34998)
			(xy 243.35994 -397.2687) (xy 243.35994 -396.376144) (xy 243.354352 -396.37081) (xy 243.354352 -395.72057)
			(xy 243.35994 -395.715236) (xy 243.35994 -393.57046) (xy 243.54536 -393.38504) (xy 245.71706 -393.38504)
			(xy 245.9101 -393.57808) (xy 245.9101 -394.572236) (xy 245.918228 -394.58011) (xy 245.918228 -395.983968)
			(xy 246.15394 -396.21968) (xy 249.145806 -396.21968) (xy 249.2756 -396.089886) (xy 249.2756 -393.55014)
			(xy 249.43308 -393.39266) (xy 251.71146 -393.39266) (xy 251.84862 -393.52982) (xy 251.84862 -396.30096)
			(xy 251.9172 -396.36954) (xy 255.17602 -396.36954) (xy 255.2319 -396.31366) (xy 255.2319 -393.49934)
			(xy 255.35128 -393.37996) (xy 257.63474 -393.37996) (xy 257.82778 -393.573) (xy 257.82778 -396.29842)
			(xy 257.8989 -396.36954) (xy 261.10438 -396.36954) (xy 261.17296 -396.30096) (xy 261.17296 -393.5603)
			(xy 261.4168 -393.31646) (xy 263.43102 -393.31646) (xy 263.72312 -393.60856) (xy 263.72312 -396.24254)
			(xy 263.85012 -396.36954) (xy 267.04036 -396.36954) (xy 267.10386 -396.30604) (xy 267.10386 -393.49172)
			(xy 267.34262 -393.25296) (xy 269.33144 -393.25296) (xy 269.64132 -393.56284) (xy 269.64132 -396.30096)
			(xy 269.7099 -396.36954) (xy 272.9484 -396.36954) (xy 273.00174 -396.3162) (xy 273.00174 -393.53744)
			(xy 273.2913 -393.24788) (xy 275.2979 -393.24788) (xy 275.54936 -393.49934) (xy 275.54936 -396.2527)
			(xy 275.6662 -396.36954) (xy 278.72182 -396.36954) (xy 278.94026 -396.1511) (xy 278.94026 -391.4521)
			(xy 277.42134 -389.93318) (xy 269.1511 -389.93318) (xy 260.11378 -380.89586) (xy 189.99962 -380.89586)
			(xy 185.14568 -385.7498) (xy 185.14568 -388.01294) (xy 233.776012 -388.01294) (xy 233.776499 -387.98557)
			(xy 233.784311 -387.931392) (xy 233.799795 -387.878889) (xy 233.822632 -387.829142) (xy 233.852353 -387.783174)
			(xy 233.869992 -387.762242) (xy 233.879191 -387.750886) (xy 233.891374 -387.724339) (xy 233.895555 -387.69543)
			(xy 233.891391 -387.666519) (xy 233.879224 -387.639965) (xy 233.869992 -387.628638) (xy 233.852356 -387.607703)
			(xy 233.822644 -387.561731) (xy 233.799808 -387.511984) (xy 233.784316 -387.459484) (xy 233.776487 -387.405309)
			(xy 233.776012 -387.37794) (xy 233.776493 -387.350687) (xy 233.784245 -387.296736) (xy 233.799597 -387.244437)
			(xy 233.822236 -387.194856) (xy 233.851702 -387.149002) (xy 233.887394 -387.107808) (xy 233.928585 -387.072114)
			(xy 233.974438 -387.042645) (xy 234.024018 -387.020004) (xy 234.076316 -387.004649) (xy 234.130267 -386.996894)
			(xy 234.15752 -386.996432) (xy 234.184891 -386.996879) (xy 234.239071 -387.0047) (xy 234.291575 -387.020193)
			(xy 234.341321 -387.043039) (xy 234.387287 -387.072769) (xy 234.408218 -387.090412) (xy 234.419546 -387.099648)
			(xy 234.446103 -387.111824) (xy 234.47502 -387.115997) (xy 234.503937 -387.111824) (xy 234.530494 -387.099648)
			(xy 234.541822 -387.090412) (xy 234.562755 -387.072771) (xy 234.608723 -387.043047) (xy 234.658469 -387.020201)
			(xy 234.710971 -387.004705) (xy 234.765149 -386.996876) (xy 234.819891 -386.996876) (xy 234.874069 -387.004705)
			(xy 234.926571 -387.020201) (xy 234.976317 -387.043047) (xy 235.022285 -387.072771) (xy 235.043218 -387.090412)
			(xy 235.054546 -387.099648) (xy 235.081103 -387.111824) (xy 235.11002 -387.115997) (xy 235.138937 -387.111824)
			(xy 235.165494 -387.099648) (xy 235.176822 -387.090412) (xy 235.197755 -387.072771) (xy 235.243723 -387.043047)
			(xy 235.293469 -387.020201) (xy 235.345971 -387.004705) (xy 235.400149 -386.996876) (xy 235.454891 -386.996876)
			(xy 235.509069 -387.004705) (xy 235.561571 -387.020201) (xy 235.611317 -387.043047) (xy 235.657285 -387.072771)
			(xy 235.678218 -387.090412) (xy 235.689546 -387.099648) (xy 235.716103 -387.111824) (xy 235.74502 -387.115997)
			(xy 235.773937 -387.111824) (xy 235.800494 -387.099648) (xy 235.811822 -387.090412) (xy 235.832755 -387.072771)
			(xy 235.878723 -387.043047) (xy 235.928469 -387.020201) (xy 235.980971 -387.004705) (xy 236.035149 -386.996876)
			(xy 236.089891 -386.996876) (xy 236.144069 -387.004705) (xy 236.196571 -387.020201) (xy 236.246317 -387.043047)
			(xy 236.292285 -387.072771) (xy 236.313218 -387.090412) (xy 236.324546 -387.099648) (xy 236.351103 -387.111824)
			(xy 236.38002 -387.115997) (xy 236.408937 -387.111824) (xy 236.435494 -387.099648) (xy 236.446822 -387.090412)
			(xy 236.467755 -387.072771) (xy 236.513723 -387.043047) (xy 236.563469 -387.020201) (xy 236.615971 -387.004705)
			(xy 236.670149 -386.996876) (xy 236.724891 -386.996876) (xy 236.779069 -387.004705) (xy 236.831571 -387.020201)
			(xy 236.881317 -387.043047) (xy 236.927285 -387.072771) (xy 236.948218 -387.090412) (xy 236.959546 -387.099648)
			(xy 236.986103 -387.111824) (xy 237.01502 -387.115997) (xy 237.043937 -387.111824) (xy 237.070494 -387.099648)
			(xy 237.081822 -387.090412) (xy 237.102755 -387.072771) (xy 237.148723 -387.043047) (xy 237.198469 -387.020201)
			(xy 237.250971 -387.004705) (xy 237.305149 -386.996876) (xy 237.359891 -386.996876) (xy 237.414069 -387.004705)
			(xy 237.466571 -387.020201) (xy 237.516317 -387.043047) (xy 237.562285 -387.072771) (xy 237.583218 -387.090412)
			(xy 237.594546 -387.099648) (xy 237.621103 -387.111824) (xy 237.65002 -387.115997) (xy 237.678937 -387.111824)
			(xy 237.705494 -387.099648) (xy 237.716822 -387.090412) (xy 237.737755 -387.072771) (xy 237.783723 -387.043047)
			(xy 237.833469 -387.020201) (xy 237.885971 -387.004705) (xy 237.940149 -386.996876) (xy 237.994891 -386.996876)
			(xy 238.049069 -387.004705) (xy 238.101571 -387.020201) (xy 238.151317 -387.043047) (xy 238.197285 -387.072771)
			(xy 238.218218 -387.090412) (xy 238.229546 -387.099648) (xy 238.256103 -387.111824) (xy 238.28502 -387.115997)
			(xy 238.313937 -387.111824) (xy 238.340494 -387.099648) (xy 238.351822 -387.090412) (xy 238.372774 -387.072798)
			(xy 238.418741 -387.043082) (xy 238.468484 -387.020241) (xy 238.52098 -387.004744) (xy 238.575152 -386.996909)
			(xy 238.60252 -386.996432) (xy 238.629775 -386.996836) (xy 238.68373 -387.004597) (xy 238.736032 -387.019958)
			(xy 238.785615 -387.042605) (xy 238.83147 -387.072079) (xy 238.872663 -387.107779) (xy 238.908357 -387.148978)
			(xy 238.937823 -387.194838) (xy 238.960463 -387.244424) (xy 238.975816 -387.296728) (xy 238.983568 -387.350685)
			(xy 238.984028 -387.37794) (xy 238.983544 -387.40531) (xy 238.975733 -387.459489) (xy 238.960249 -387.511992)
			(xy 238.937411 -387.56174) (xy 238.907689 -387.607707) (xy 238.890048 -387.628638) (xy 238.880776 -387.639938)
			(xy 238.86861 -387.666507) (xy 238.864447 -387.69543) (xy 238.868627 -387.724352) (xy 238.880809 -387.750913)
			(xy 238.890048 -387.762242) (xy 238.907665 -387.783192) (xy 238.937382 -387.829159) (xy 238.960223 -387.878902)
			(xy 238.975719 -387.931399) (xy 238.983552 -387.985572) (xy 238.984028 -388.01294) (xy 238.983559 -388.040191)
			(xy 238.975798 -388.094139) (xy 238.960439 -388.146432) (xy 238.937794 -388.196009) (xy 238.908326 -388.241858)
			(xy 238.872633 -388.283047) (xy 238.831442 -388.318738) (xy 238.785591 -388.348204) (xy 238.736014 -388.370846)
			(xy 238.683719 -388.386202) (xy 238.629771 -388.393961) (xy 238.60252 -388.394448) (xy 238.57515 -388.393983)
			(xy 238.52097 -388.386167) (xy 238.468466 -388.370678) (xy 238.418719 -388.347836) (xy 238.372753 -388.31811)
			(xy 238.351822 -388.300468) (xy 238.340494 -388.291232) (xy 238.313937 -388.279056) (xy 238.28502 -388.274883)
			(xy 238.256103 -388.279056) (xy 238.229546 -388.291232) (xy 238.218218 -388.300468) (xy 238.197285 -388.318109)
			(xy 238.151317 -388.347833) (xy 238.101571 -388.370679) (xy 238.049069 -388.386175) (xy 237.994891 -388.394004)
			(xy 237.940149 -388.394004) (xy 237.885971 -388.386175) (xy 237.833469 -388.370679) (xy 237.783723 -388.347833)
			(xy 237.737755 -388.318109) (xy 237.716822 -388.300468) (xy 237.705494 -388.291232) (xy 237.678937 -388.279056)
			(xy 237.65002 -388.274883) (xy 237.621103 -388.279056) (xy 237.594546 -388.291232) (xy 237.583218 -388.300468)
			(xy 237.562285 -388.318109) (xy 237.516317 -388.347833) (xy 237.466571 -388.370679) (xy 237.414069 -388.386175)
			(xy 237.359891 -388.394004) (xy 237.305149 -388.394004) (xy 237.250971 -388.386175) (xy 237.198469 -388.370679)
			(xy 237.148723 -388.347833) (xy 237.102755 -388.318109) (xy 237.081822 -388.300468) (xy 237.070494 -388.291232)
			(xy 237.043937 -388.279056) (xy 237.01502 -388.274883) (xy 236.986103 -388.279056) (xy 236.959546 -388.291232)
			(xy 236.948218 -388.300468) (xy 236.927285 -388.318109) (xy 236.881317 -388.347833) (xy 236.831571 -388.370679)
			(xy 236.779069 -388.386175) (xy 236.724891 -388.394004) (xy 236.670149 -388.394004) (xy 236.615971 -388.386175)
			(xy 236.563469 -388.370679) (xy 236.513723 -388.347833) (xy 236.467755 -388.318109) (xy 236.446822 -388.300468)
			(xy 236.435494 -388.291232) (xy 236.408937 -388.279056) (xy 236.38002 -388.274883) (xy 236.351103 -388.279056)
			(xy 236.324546 -388.291232) (xy 236.313218 -388.300468) (xy 236.292285 -388.318109) (xy 236.246317 -388.347833)
			(xy 236.196571 -388.370679) (xy 236.144069 -388.386175) (xy 236.089891 -388.394004) (xy 236.035149 -388.394004)
			(xy 235.980971 -388.386175) (xy 235.928469 -388.370679) (xy 235.878723 -388.347833) (xy 235.832755 -388.318109)
			(xy 235.811822 -388.300468) (xy 235.800494 -388.291232) (xy 235.773937 -388.279056) (xy 235.74502 -388.274883)
			(xy 235.716103 -388.279056) (xy 235.689546 -388.291232) (xy 235.678218 -388.300468) (xy 235.657285 -388.318109)
			(xy 235.611317 -388.347833) (xy 235.561571 -388.370679) (xy 235.509069 -388.386175) (xy 235.454891 -388.394004)
			(xy 235.400149 -388.394004) (xy 235.345971 -388.386175) (xy 235.293469 -388.370679) (xy 235.243723 -388.347833)
			(xy 235.197755 -388.318109) (xy 235.176822 -388.300468) (xy 235.165494 -388.291232) (xy 235.138937 -388.279056)
			(xy 235.11002 -388.274883) (xy 235.081103 -388.279056) (xy 235.054546 -388.291232) (xy 235.043218 -388.300468)
			(xy 235.022285 -388.318109) (xy 234.976317 -388.347833) (xy 234.926571 -388.370679) (xy 234.874069 -388.386175)
			(xy 234.819891 -388.394004) (xy 234.765149 -388.394004) (xy 234.710971 -388.386175) (xy 234.658469 -388.370679)
			(xy 234.608723 -388.347833) (xy 234.562755 -388.318109) (xy 234.541822 -388.300468) (xy 234.530494 -388.291232)
			(xy 234.503937 -388.279056) (xy 234.47502 -388.274883) (xy 234.446103 -388.279056) (xy 234.419546 -388.291232)
			(xy 234.408218 -388.300468) (xy 234.387286 -388.318107) (xy 234.341314 -388.34782) (xy 234.291566 -388.370657)
			(xy 234.239065 -388.386147) (xy 234.184889 -388.393975) (xy 234.15752 -388.394448) (xy 234.130271 -388.393903)
			(xy 234.076328 -388.386151) (xy 234.024036 -388.3708) (xy 233.974462 -388.348164) (xy 233.928614 -388.318704)
			(xy 233.887424 -388.283018) (xy 233.851732 -388.241835) (xy 233.822265 -388.195991) (xy 233.799621 -388.14642)
			(xy 233.784262 -388.094131) (xy 233.776501 -388.040189) (xy 233.776012 -388.01294) (xy 185.14568 -388.01294)
			(xy 185.14568 -397.71828) (xy 185.82386 -398.39646) (xy 185.82386 -399.8595) (xy 186.13374 -400.16938)
			(xy 192.58788 -400.16938) (xy 194.3481 -398.40916) (xy 196.67474 -398.40916) (xy 198.374 -400.10842)
			(xy 203.1619 -400.10842) (xy 204.30998 -398.96034) (xy 207.30464 -398.96034) (xy 208.58988 -400.24558)
			(xy 213.68766 -400.24558)
		)
		(stroke
			(width 0)
			(type solid)
		)
		(fill yes)
		(layer "B.Cu")
		(net "P12V_AUX")
	)
	(gr_poly
		(pts
			(xy 435.69128 -368.323368) (xy 438.360058 -368.323368) (xy 438.378854 -368.315748) (xy 438.385966 -368.308382)
			(xy 439.123074 -367.571274) (xy 439.129919 -367.563875) (xy 439.137648 -367.545277) (xy 439.13806 -367.535206)
			(xy 439.13806 -341.00389) (xy 439.13044 -340.985094) (xy 439.123074 -340.977982) (xy 438.5818 -340.436708)
			(xy 438.574402 -340.429861) (xy 438.555804 -340.422125) (xy 438.545732 -340.421722) (xy 411.752288 -340.421722)
			(xy 411.733492 -340.429342) (xy 411.72638 -340.436708) (xy 409.526486 -342.636602) (xy 409.519631 -342.643997)
			(xy 409.511883 -342.662595) (xy 409.5115 -342.67267) (xy 409.5115 -352.762566) (xy 411.51048 -352.762566)
			(xy 411.51048 -345.23807) (xy 411.510868 -345.227996) (xy 411.518613 -345.209397) (xy 411.525466 -345.202002)
			(xy 412.000192 -344.727276) (xy 412.007598 -344.720443) (xy 412.026193 -344.71272) (xy 412.03626 -344.71229)
			(xy 412.26994 -344.71229) (xy 412.279592 -344.708226) (xy 412.284221 -344.706455) (xy 412.293942 -344.704535)
			(xy 412.298896 -344.704416) (xy 414.306766 -344.704416) (xy 414.320837 -344.703968) (xy 414.347912 -344.696297)
			(xy 414.371867 -344.681529) (xy 414.390882 -344.660785) (xy 414.403514 -344.635638) (xy 414.408805 -344.607999)
			(xy 414.406352 -344.579965) (xy 414.396342 -344.553665) (xy 414.3883 -344.54211) (xy 414.364371 -344.509229)
			(xy 414.321959 -344.439835) (xy 414.286061 -344.366858) (xy 414.256976 -344.290909) (xy 414.234947 -344.212621)
			(xy 414.220158 -344.132649) (xy 414.212732 -344.05166) (xy 414.212278 -344.010996) (xy 414.212782 -343.968648)
			(xy 414.220833 -343.884334) (xy 414.236862 -343.801168) (xy 414.260723 -343.719901) (xy 414.292202 -343.641271)
			(xy 414.331013 -343.56599) (xy 414.376803 -343.494738) (xy 414.429159 -343.428162) (xy 414.487607 -343.366864)
			(xy 414.551617 -343.311399) (xy 414.620609 -343.26227) (xy 414.693959 -343.219921) (xy 414.771002 -343.184737)
			(xy 414.851041 -343.157035) (xy 414.93335 -343.137067) (xy 415.017185 -343.125014) (xy 415.101786 -343.120984)
			(xy 415.186387 -343.125014) (xy 415.270222 -343.137067) (xy 415.352531 -343.157035) (xy 415.43257 -343.184737)
			(xy 415.509613 -343.219921) (xy 415.582963 -343.26227) (xy 415.651955 -343.311399) (xy 415.715965 -343.366864)
			(xy 415.774413 -343.428162) (xy 415.826769 -343.494738) (xy 415.872559 -343.56599) (xy 415.91137 -343.641271)
			(xy 415.942849 -343.719901) (xy 415.96671 -343.801168) (xy 415.982739 -343.884334) (xy 415.99079 -343.968648)
			(xy 415.991294 -344.010996) (xy 415.990854 -344.05166) (xy 415.983428 -344.132649) (xy 415.968637 -344.212622)
			(xy 415.946604 -344.290909) (xy 415.917515 -344.366858) (xy 415.881612 -344.439833) (xy 415.839195 -344.509224)
			(xy 415.815272 -344.54211) (xy 415.80725 -344.553676) (xy 415.797245 -344.579973) (xy 415.794794 -344.608002)
			(xy 415.800084 -344.635636) (xy 415.812712 -344.660779) (xy 415.831722 -344.681522) (xy 415.855669 -344.696291)
			(xy 415.882738 -344.703966) (xy 415.896806 -344.704416) (xy 420.492936 -344.704416) (xy 420.506959 -344.703922)
			(xy 420.533944 -344.696281) (xy 420.557831 -344.681586) (xy 420.576819 -344.660946) (xy 420.589474 -344.635917)
			(xy 420.594842 -344.60839) (xy 420.592516 -344.58044) (xy 420.582674 -344.554178) (xy 420.574724 -344.542618)
			(xy 420.551381 -344.509955) (xy 420.509991 -344.441157) (xy 420.474971 -344.368908) (xy 420.446606 -344.293797)
			(xy 420.425127 -344.216435) (xy 420.410708 -344.137452) (xy 420.403467 -344.05749) (xy 420.40302 -344.017346)
			(xy 420.403524 -343.974998) (xy 420.411575 -343.890684) (xy 420.427604 -343.807518) (xy 420.451465 -343.726251)
			(xy 420.482944 -343.647621) (xy 420.521755 -343.57234) (xy 420.567545 -343.501088) (xy 420.619901 -343.434512)
			(xy 420.678349 -343.373214) (xy 420.742359 -343.317749) (xy 420.811351 -343.26862) (xy 420.884701 -343.226271)
			(xy 420.961744 -343.191087) (xy 421.041783 -343.163385) (xy 421.124092 -343.143417) (xy 421.207927 -343.131364)
			(xy 421.292528 -343.127334) (xy 421.377129 -343.131364) (xy 421.460964 -343.143417) (xy 421.543273 -343.163385)
			(xy 421.623312 -343.191087) (xy 421.700355 -343.226271) (xy 421.773705 -343.26862) (xy 421.842697 -343.317749)
			(xy 421.906707 -343.373214) (xy 421.965155 -343.434512) (xy 422.017511 -343.501088) (xy 422.063301 -343.57234)
			(xy 422.102112 -343.647621) (xy 422.133591 -343.726251) (xy 422.157452 -343.807518) (xy 422.173481 -343.890684)
			(xy 422.181532 -343.974998) (xy 422.182036 -344.017346) (xy 422.181593 -344.057491) (xy 422.174359 -344.137454)
			(xy 422.159944 -344.21644) (xy 422.138467 -344.293804) (xy 422.110102 -344.368916) (xy 422.07508 -344.441165)
			(xy 422.033687 -344.509963) (xy 422.010332 -344.542618) (xy 422.002482 -344.554226) (xy 421.992706 -344.580472)
			(xy 421.990419 -344.608386) (xy 421.995792 -344.635873) (xy 422.008422 -344.660871) (xy 422.027362 -344.681504)
			(xy 422.05119 -344.696222) (xy 422.078118 -344.703923) (xy 422.09212 -344.704416) (xy 426.690536 -344.704416)
			(xy 426.704559 -344.703922) (xy 426.731544 -344.696281) (xy 426.755431 -344.681586) (xy 426.774419 -344.660946)
			(xy 426.787074 -344.635917) (xy 426.792442 -344.60839) (xy 426.790116 -344.58044) (xy 426.780274 -344.554178)
			(xy 426.772324 -344.542618) (xy 426.748981 -344.509955) (xy 426.707591 -344.441157) (xy 426.672571 -344.368908)
			(xy 426.644206 -344.293797) (xy 426.622727 -344.216435) (xy 426.608308 -344.137452) (xy 426.601067 -344.05749)
			(xy 426.60062 -344.017346) (xy 426.601124 -343.974998) (xy 426.609175 -343.890684) (xy 426.625204 -343.807518)
			(xy 426.649065 -343.726251) (xy 426.680544 -343.647621) (xy 426.719355 -343.57234) (xy 426.765145 -343.501088)
			(xy 426.817501 -343.434512) (xy 426.875949 -343.373214) (xy 426.939959 -343.317749) (xy 427.008951 -343.26862)
			(xy 427.082301 -343.226271) (xy 427.159344 -343.191087) (xy 427.239383 -343.163385) (xy 427.321692 -343.143417)
			(xy 427.405527 -343.131364) (xy 427.490128 -343.127334) (xy 427.574729 -343.131364) (xy 427.658564 -343.143417)
			(xy 427.740873 -343.163385) (xy 427.820912 -343.191087) (xy 427.897955 -343.226271) (xy 427.971305 -343.26862)
			(xy 428.040297 -343.317749) (xy 428.104307 -343.373214) (xy 428.162755 -343.434512) (xy 428.215111 -343.501088)
			(xy 428.260901 -343.57234) (xy 428.299712 -343.647621) (xy 428.331191 -343.726251) (xy 428.355052 -343.807518)
			(xy 428.371081 -343.890684) (xy 428.379132 -343.974998) (xy 428.379636 -344.017346) (xy 428.379193 -344.057491)
			(xy 428.371959 -344.137454) (xy 428.357544 -344.21644) (xy 428.336067 -344.293804) (xy 428.307702 -344.368916)
			(xy 428.27268 -344.441165) (xy 428.231287 -344.509963) (xy 428.207932 -344.542618) (xy 428.200082 -344.554226)
			(xy 428.190306 -344.580472) (xy 428.188019 -344.608386) (xy 428.193392 -344.635873) (xy 428.206022 -344.660871)
			(xy 428.224962 -344.681504) (xy 428.24879 -344.696222) (xy 428.275718 -344.703923) (xy 428.28972 -344.704416)
			(xy 433.504086 -344.704416) (xy 433.513992 -344.70848) (xy 433.518621 -344.710251) (xy 433.528342 -344.712171)
			(xy 433.533296 -344.71229) (xy 433.705 -344.71229) (xy 433.715072 -344.712692) (xy 433.733671 -344.720426)
			(xy 433.741068 -344.727276) (xy 434.352954 -345.339162) (xy 434.359763 -345.346586) (xy 434.367502 -345.365167)
			(xy 434.36794 -345.37523) (xy 434.36794 -352.549206) (xy 434.367534 -352.559278) (xy 434.359802 -352.577876)
			(xy 434.352954 -352.585274) (xy 433.761134 -353.177094) (xy 433.753716 -353.183911) (xy 433.73513 -353.191644)
			(xy 433.725066 -353.19208) (xy 411.934406 -353.19208) (xy 411.92704 -353.199446) (xy 411.922214 -353.195382)
			(xy 411.525466 -352.798634) (xy 411.518644 -352.79122) (xy 411.510915 -352.772631) (xy 411.51048 -352.762566)
			(xy 409.5115 -352.762566) (xy 409.5115 -356.201726) (xy 409.51912 -356.220522) (xy 409.526486 -356.227634)
			(xy 411.068774 -357.769922) (xy 411.07562 -357.77732) (xy 411.08335 -357.795919) (xy 411.08376 -357.80599)
			(xy 411.08376 -361.627166) (xy 411.09138 -361.645962) (xy 411.098746 -361.653074) (xy 411.515814 -362.070142)
			(xy 411.52321 -362.076993) (xy 411.541809 -362.084731) (xy 411.551882 -362.085128) (xy 412.476696 -362.085128)
			(xy 412.485332 -362.081826) (xy 414.019746 -362.081826) (xy 414.029812 -362.082258) (xy 414.048402 -362.089987)
			(xy 414.055814 -362.096812) (xy 414.356296 -362.397294) (xy 414.363144 -362.404692) (xy 414.370881 -362.42329)
			(xy 414.371282 -362.433362) (xy 414.371282 -364.246922) (xy 414.371709 -364.256991) (xy 414.379427 -364.275591)
			(xy 414.386268 -364.28299) (xy 414.474152 -364.370874) (xy 414.481552 -364.377715) (xy 414.500151 -364.385434)
			(xy 414.51022 -364.38586) (xy 416.118294 -364.38586) (xy 416.145472 -364.37443) (xy 416.14991 -364.372402)
			(xy 416.157962 -364.366896) (xy 416.161474 -364.363508) (xy 416.196018 -364.328964) (xy 416.202868 -364.321568)
			(xy 416.210602 -364.302968) (xy 416.211004 -364.292896) (xy 416.211004 -362.170472) (xy 416.211432 -362.160404)
			(xy 416.219154 -362.141808) (xy 416.22599 -362.134404) (xy 416.29711 -362.063284) (xy 416.304505 -362.05643)
			(xy 416.323104 -362.048686) (xy 416.333178 -362.048298) (xy 420.824406 -362.048298) (xy 420.834476 -362.048722)
			(xy 420.853079 -362.056438) (xy 420.860474 -362.063284) (xy 421.065198 -362.268008) (xy 421.072043 -362.275407)
			(xy 421.079775 -362.294005) (xy 421.080184 -362.304076) (xy 421.080184 -364.413292) (xy 421.079762 -364.423363)
			(xy 421.072048 -364.441968) (xy 421.065198 -364.44936) (xy 420.73195 -364.782608) (xy 420.724584 -364.78972)
			(xy 420.716964 -364.808516) (xy 420.716964 -367.232692) (xy 420.717387 -367.242761) (xy 420.725107 -367.261362)
			(xy 420.73195 -367.26876) (xy 421.382698 -367.919508) (xy 421.390097 -367.926354) (xy 421.408695 -367.934088)
			(xy 421.418766 -367.934494) (xy 421.904922 -367.934494) (xy 421.91499 -367.934067) (xy 421.933588 -367.926346)
			(xy 421.94099 -367.919508) (xy 422.068498 -367.792) (xy 422.075345 -367.784602) (xy 422.08308 -367.766004)
			(xy 422.083484 -367.755932) (xy 422.083484 -367.551716) (xy 422.083045 -367.541653) (xy 422.075307 -367.523072)
			(xy 422.068498 -367.515648) (xy 421.79367 -367.24082) (xy 421.786829 -367.23342) (xy 421.779112 -367.214821)
			(xy 421.778684 -367.204752) (xy 421.778684 -362.284772) (xy 421.779112 -362.274704) (xy 421.786831 -362.256105)
			(xy 421.79367 -362.248704) (xy 421.913812 -362.128562) (xy 421.979598 -362.062522) (xy 421.986995 -362.055673)
			(xy 422.005594 -362.047934) (xy 422.015666 -362.047536) (xy 423.401744 -362.047536) (xy 423.41181 -362.047968)
			(xy 423.430399 -362.055698) (xy 423.437812 -362.062522) (xy 423.821098 -362.445808) (xy 423.827943 -362.453207)
			(xy 423.835675 -362.471805) (xy 423.836084 -362.481876) (xy 423.836084 -364.192312) (xy 423.836509 -364.202382)
			(xy 423.844224 -364.220984) (xy 423.85107 -364.22838) (xy 423.993056 -364.370366) (xy 424.000456 -364.377207)
			(xy 424.019054 -364.384927) (xy 424.029124 -364.385352) (xy 425.747434 -364.385352) (xy 425.7575 -364.384921)
			(xy 425.776091 -364.377193) (xy 425.783502 -364.370366) (xy 425.893738 -364.26013) (xy 425.90058 -364.252731)
			(xy 425.908299 -364.234132) (xy 425.908724 -364.224062) (xy 425.908724 -362.324396) (xy 425.909148 -362.314327)
			(xy 425.916867 -362.295725) (xy 425.92371 -362.288328) (xy 426.148754 -362.063284) (xy 426.156151 -362.056437)
			(xy 426.174751 -362.048709) (xy 426.184822 -362.048298) (xy 431.042064 -362.048298) (xy 431.052129 -362.048733)
			(xy 431.070717 -362.056463) (xy 431.078132 -362.063284) (xy 431.413412 -362.398564) (xy 431.420258 -362.405962)
			(xy 431.427983 -362.424561) (xy 431.428398 -362.434632) (xy 431.428398 -367.947448) (xy 431.42883 -367.957514)
			(xy 431.436556 -367.976106) (xy 431.443384 -367.983516) (xy 431.774092 -368.314224) (xy 431.781486 -368.32108)
			(xy 431.800085 -368.32883) (xy 431.81016 -368.32921) (xy 435.685438 -368.32921)
		)
		(stroke
			(width 0)
			(type solid)
		)
		(fill yes)
		(layer "B.Cu")
		(net "GND")
	)
	(gr_poly
		(pts
			(xy 383.273808 -79.562452) (xy 383.274023 -79.547675) (xy 383.277851 -79.518371) (xy 383.281428 -79.504032)
			(xy 383.283105 -79.476587) (xy 383.293553 -79.422605) (xy 383.311863 -79.370759) (xy 383.337634 -79.322189)
			(xy 383.3703 -79.277961) (xy 383.389378 -79.25816) (xy 383.78257 -78.864968) (xy 383.801105 -78.847068)
			(xy 383.842246 -78.816043) (xy 383.88729 -78.791021) (xy 383.935367 -78.772485) (xy 383.98555 -78.760792)
			(xy 384.01117 -78.758034) (xy 384.035421 -78.751973) (xy 384.084983 -78.745472) (xy 384.109976 -78.74508)
			(xy 384.13771 -78.745575) (xy 384.192593 -78.7536) (xy 384.245737 -78.769483) (xy 384.296023 -78.792891)
			(xy 384.342392 -78.82333) (xy 384.383867 -78.86016) (xy 384.419575 -78.902604) (xy 384.434588 -78.925928)
			(xy 384.437636 -78.931008) (xy 384.562096 -79.055468) (xy 384.586226 -79.052928) (xy 384.610102 -79.051404)
			(xy 384.877564 -79.051404) (xy 384.877564 -79.083916) (xy 384.905758 -79.09814) (xy 384.930142 -79.111348)
			(xy 385.14274 -79.111348) (xy 385.14274 -79.704184) (xy 390.38784 -79.704184) (xy 390.773666 -79.318358)
			(xy 390.773666 -71.428356) (xy 390.242806 -70.897496) (xy 385.54787 -70.897496) (xy 385.534237 -70.920736)
			(xy 385.501058 -70.963188) (xy 385.461863 -71.000156) (xy 385.417546 -71.030798) (xy 385.369118 -71.054413)
			(xy 385.317685 -71.070462) (xy 385.264421 -71.078579) (xy 385.210543 -71.078579) (xy 385.157279 -71.070462)
			(xy 385.105846 -71.054413) (xy 385.057418 -71.030798) (xy 385.013101 -71.000156) (xy 384.973906 -70.963188)
			(xy 384.940727 -70.920736) (xy 384.927094 -70.897496) (xy 383.50825 -70.897496) (xy 383.494772 -70.897919)
			(xy 383.468758 -70.904988) (xy 383.445502 -70.91862) (xy 383.426625 -70.937864) (xy 383.413444 -70.961378)
			(xy 383.406877 -70.987523) (xy 383.407383 -71.014476) (xy 383.410714 -71.027544) (xy 383.417821 -71.05364)
			(xy 383.425465 -71.107182) (xy 383.425954 -71.134224) (xy 383.425468 -71.161475) (xy 383.417712 -71.215423)
			(xy 383.402357 -71.267718) (xy 383.379715 -71.317295) (xy 383.350249 -71.363145) (xy 383.314558 -71.404336)
			(xy 383.273367 -71.440027) (xy 383.227517 -71.469493) (xy 383.17794 -71.492135) (xy 383.125645 -71.50749)
			(xy 383.071697 -71.515246) (xy 383.017195 -71.515246) (xy 382.963247 -71.50749) (xy 382.910952 -71.492135)
			(xy 382.861375 -71.469493) (xy 382.815525 -71.440027) (xy 382.774334 -71.404336) (xy 382.738643 -71.363145)
			(xy 382.709177 -71.317295) (xy 382.686535 -71.267718) (xy 382.67118 -71.215423) (xy 382.663424 -71.161475)
			(xy 382.662938 -71.134224) (xy 382.663404 -71.10718) (xy 382.671047 -71.053635) (xy 382.678178 -71.027544)
			(xy 382.681552 -71.014482) (xy 382.682058 -70.987519) (xy 382.675489 -70.961364) (xy 382.662302 -70.93784)
			(xy 382.643416 -70.918589) (xy 382.62015 -70.904953) (xy 382.594126 -70.897883) (xy 382.580642 -70.897496)
			(xy 379.761242 -70.897496) (xy 379.747868 -70.897882) (xy 379.722032 -70.904808) (xy 379.698889 -70.918219)
			(xy 379.680034 -70.937191) (xy 379.666767 -70.960416) (xy 379.660002 -70.986295) (xy 379.660206 -71.013042)
			(xy 379.663452 -71.02602) (xy 379.669789 -71.050745) (xy 379.676542 -71.101337) (xy 379.676914 -71.126858)
			(xy 379.676371 -71.15583) (xy 379.6676 -71.213106) (xy 379.650269 -71.268398) (xy 379.624775 -71.320433)
			(xy 379.591707 -71.368014) (xy 379.551823 -71.410047) (xy 379.506042 -71.445566) (xy 379.455416 -71.473753)
			(xy 379.401109 -71.493961) (xy 379.344372 -71.505724) (xy 379.315472 -71.507858) (xy 379.30581 -71.508771)
			(xy 379.288192 -71.51687) (xy 379.274849 -71.530939) (xy 379.267695 -71.548961) (xy 379.267212 -71.558658)
			(xy 379.267212 -71.860406) (xy 380.284718 -71.860406) (xy 380.284718 -71.80047) (xy 380.292541 -71.741048)
			(xy 380.308054 -71.683155) (xy 380.33099 -71.627782) (xy 380.360957 -71.575876) (xy 380.397444 -71.528326)
			(xy 380.439824 -71.485946) (xy 380.487374 -71.449459) (xy 380.53928 -71.419492) (xy 380.594653 -71.396556)
			(xy 380.652546 -71.381043) (xy 380.711968 -71.37322) (xy 380.771904 -71.37322) (xy 380.831326 -71.381043)
			(xy 380.889219 -71.396556) (xy 380.944592 -71.419492) (xy 380.996498 -71.449459) (xy 381.044048 -71.485946)
			(xy 381.086428 -71.528326) (xy 381.122915 -71.575876) (xy 381.152882 -71.627782) (xy 381.175818 -71.683155)
			(xy 381.191331 -71.741048) (xy 381.199154 -71.80047) (xy 381.199644 -71.830438) (xy 381.199154 -71.860406)
			(xy 381.191331 -71.919828) (xy 381.175818 -71.977721) (xy 381.152882 -72.033094) (xy 381.122915 -72.085)
			(xy 381.086428 -72.13255) (xy 381.044048 -72.17493) (xy 380.996498 -72.211417) (xy 380.944592 -72.241384)
			(xy 380.889219 -72.26432) (xy 380.831326 -72.279833) (xy 380.771904 -72.287656) (xy 380.711968 -72.287656)
			(xy 380.652546 -72.279833) (xy 380.594653 -72.26432) (xy 380.53928 -72.241384) (xy 380.487374 -72.211417)
			(xy 380.439824 -72.17493) (xy 380.397444 -72.13255) (xy 380.360957 -72.085) (xy 380.33099 -72.033094)
			(xy 380.308054 -71.977721) (xy 380.292541 -71.919828) (xy 380.284718 -71.860406) (xy 379.267212 -71.860406)
			(xy 379.267212 -73.394824) (xy 386.271514 -73.394824) (xy 386.275585 -73.339202) (xy 386.287711 -73.284765)
			(xy 386.307634 -73.232674) (xy 386.33493 -73.184039) (xy 386.369016 -73.139896) (xy 386.409165 -73.101187)
			(xy 386.454523 -73.068736) (xy 386.504123 -73.043235) (xy 386.556907 -73.025228) (xy 386.61175 -73.015098)
			(xy 386.667484 -73.013061) (xy 386.722921 -73.019161) (xy 386.776878 -73.033267) (xy 386.828207 -73.055079)
			(xy 386.875813 -73.084133) (xy 386.918681 -73.119808) (xy 386.955898 -73.161345) (xy 386.986671 -73.207858)
			(xy 387.010343 -73.258355) (xy 387.026411 -73.311762) (xy 387.034531 -73.366938) (xy 387.03504 -73.394824)
			(xy 387.034531 -73.42271) (xy 387.026411 -73.477886) (xy 387.010343 -73.531293) (xy 386.986671 -73.58179)
			(xy 386.955898 -73.628303) (xy 386.918681 -73.66984) (xy 386.875813 -73.705515) (xy 386.828207 -73.734569)
			(xy 386.776878 -73.756381) (xy 386.722921 -73.770487) (xy 386.667484 -73.776587) (xy 386.61175 -73.77455)
			(xy 386.556907 -73.76442) (xy 386.504123 -73.746413) (xy 386.454523 -73.720912) (xy 386.409165 -73.688461)
			(xy 386.369016 -73.649752) (xy 386.33493 -73.605609) (xy 386.307634 -73.556974) (xy 386.287711 -73.504883)
			(xy 386.275585 -73.450446) (xy 386.271514 -73.394824) (xy 379.267212 -73.394824) (xy 379.267212 -75.757278)
			(xy 382.792224 -75.757278) (xy 382.792224 -73.95845) (xy 382.79271 -73.931199) (xy 382.800466 -73.877251)
			(xy 382.815821 -73.824956) (xy 382.838463 -73.775379) (xy 382.867929 -73.729529) (xy 382.90362 -73.688338)
			(xy 382.944811 -73.652647) (xy 382.990661 -73.623181) (xy 383.040238 -73.600539) (xy 383.092533 -73.585184)
			(xy 383.146481 -73.577428) (xy 383.200983 -73.577428) (xy 383.254931 -73.585184) (xy 383.307226 -73.600539)
			(xy 383.356803 -73.623181) (xy 383.402653 -73.652647) (xy 383.443844 -73.688338) (xy 383.479535 -73.729529)
			(xy 383.509001 -73.775379) (xy 383.531643 -73.824956) (xy 383.546998 -73.877251) (xy 383.554754 -73.931199)
			(xy 383.55524 -73.95845) (xy 383.55524 -74.075032) (xy 385.030708 -74.075032) (xy 385.030708 -74.015096)
			(xy 385.038531 -73.955674) (xy 385.054044 -73.897781) (xy 385.07698 -73.842408) (xy 385.106947 -73.790502)
			(xy 385.143434 -73.742952) (xy 385.185814 -73.700572) (xy 385.233364 -73.664085) (xy 385.28527 -73.634118)
			(xy 385.340643 -73.611182) (xy 385.398536 -73.595669) (xy 385.457958 -73.587846) (xy 385.517894 -73.587846)
			(xy 385.577316 -73.595669) (xy 385.635209 -73.611182) (xy 385.690582 -73.634118) (xy 385.742488 -73.664085)
			(xy 385.790038 -73.700572) (xy 385.832418 -73.742952) (xy 385.868905 -73.790502) (xy 385.898872 -73.842408)
			(xy 385.921808 -73.897781) (xy 385.937321 -73.955674) (xy 385.945144 -74.015096) (xy 385.945634 -74.045064)
			(xy 385.945144 -74.075032) (xy 385.937321 -74.134454) (xy 385.921808 -74.192347) (xy 385.898872 -74.24772)
			(xy 385.868905 -74.299626) (xy 385.832418 -74.347176) (xy 385.790038 -74.389556) (xy 385.742488 -74.426043)
			(xy 385.690582 -74.45601) (xy 385.635209 -74.478946) (xy 385.577316 -74.494459) (xy 385.517894 -74.502282)
			(xy 385.457958 -74.502282) (xy 385.398536 -74.494459) (xy 385.340643 -74.478946) (xy 385.28527 -74.45601)
			(xy 385.233364 -74.426043) (xy 385.185814 -74.389556) (xy 385.143434 -74.347176) (xy 385.106947 -74.299626)
			(xy 385.07698 -74.24772) (xy 385.054044 -74.192347) (xy 385.038531 -74.134454) (xy 385.030708 -74.075032)
			(xy 383.55524 -74.075032) (xy 383.55524 -75.59929) (xy 383.917698 -75.961748) (xy 383.938461 -75.983364)
			(xy 383.973646 -76.031885) (xy 384.000813 -76.08531) (xy 384.019293 -76.142325) (xy 384.028633 -76.201528)
			(xy 384.029204 -76.231496) (xy 384.029204 -77.769466) (xy 384.028672 -77.799438) (xy 384.019353 -77.858653)
			(xy 384.000876 -77.915678) (xy 383.973698 -77.969105) (xy 383.938488 -78.017618) (xy 383.917698 -78.039214)
			(xy 383.80416 -78.152498) (xy 383.80416 -78.350618) (xy 383.803674 -78.377851) (xy 383.795923 -78.431763)
			(xy 383.780578 -78.484023) (xy 383.757952 -78.533567) (xy 383.728505 -78.579387) (xy 383.692838 -78.62055)
			(xy 383.651675 -78.656217) (xy 383.605855 -78.685664) (xy 383.556311 -78.70829) (xy 383.504051 -78.723635)
			(xy 383.450139 -78.731386) (xy 383.395673 -78.731386) (xy 383.341761 -78.723635) (xy 383.289501 -78.70829)
			(xy 383.239957 -78.685664) (xy 383.194137 -78.656217) (xy 383.152974 -78.62055) (xy 383.117307 -78.579387)
			(xy 383.08786 -78.533567) (xy 383.065234 -78.484023) (xy 383.049889 -78.431763) (xy 383.042138 -78.377851)
			(xy 383.041652 -78.350618) (xy 383.041652 -77.99451) (xy 383.042152 -77.964536) (xy 383.051477 -77.90532)
			(xy 383.06996 -77.848294) (xy 383.097146 -77.794866) (xy 383.132364 -77.746356) (xy 383.153158 -77.724762)
			(xy 383.266696 -77.611478) (xy 383.266696 -76.389484) (xy 382.903984 -76.027026) (xy 382.883172 -76.005439)
			(xy 382.847919 -75.956933) (xy 382.820692 -75.90351) (xy 382.80216 -75.846483) (xy 382.79278 -75.787259)
			(xy 382.792224 -75.757278) (xy 379.267212 -75.757278) (xy 379.267212 -77.39405) (xy 382.04697 -77.39405)
			(xy 382.04697 -77.334114) (xy 382.054793 -77.274692) (xy 382.070306 -77.216799) (xy 382.093242 -77.161426)
			(xy 382.123209 -77.10952) (xy 382.159696 -77.06197) (xy 382.202076 -77.01959) (xy 382.249626 -76.983103)
			(xy 382.301532 -76.953136) (xy 382.356905 -76.9302) (xy 382.414798 -76.914687) (xy 382.47422 -76.906864)
			(xy 382.534156 -76.906864) (xy 382.593578 -76.914687) (xy 382.651471 -76.9302) (xy 382.706844 -76.953136)
			(xy 382.75875 -76.983103) (xy 382.8063 -77.01959) (xy 382.84868 -77.06197) (xy 382.885167 -77.10952)
			(xy 382.915134 -77.161426) (xy 382.93807 -77.216799) (xy 382.953583 -77.274692) (xy 382.961406 -77.334114)
			(xy 382.961896 -77.364082) (xy 382.961406 -77.39405) (xy 382.953583 -77.453472) (xy 382.93807 -77.511365)
			(xy 382.915134 -77.566738) (xy 382.885167 -77.618644) (xy 382.84868 -77.666194) (xy 382.8063 -77.708574)
			(xy 382.75875 -77.745061) (xy 382.706844 -77.775028) (xy 382.651471 -77.797964) (xy 382.593578 -77.813477)
			(xy 382.534156 -77.8213) (xy 382.47422 -77.8213) (xy 382.414798 -77.813477) (xy 382.356905 -77.797964)
			(xy 382.301532 -77.775028) (xy 382.249626 -77.745061) (xy 382.202076 -77.708574) (xy 382.159696 -77.666194)
			(xy 382.123209 -77.618644) (xy 382.093242 -77.566738) (xy 382.070306 -77.511365) (xy 382.054793 -77.453472)
			(xy 382.04697 -77.39405) (xy 379.267212 -77.39405) (xy 379.267212 -79.048864) (xy 379.922532 -79.704184)
			(xy 383.273808 -79.704184)
		)
		(stroke
			(width 0)
			(type solid)
		)
		(fill yes)
		(layer "B.Cu")
		(net "GND")
	)
	(gr_poly
		(pts
			(xy 72.21474 -160.74644) (xy 72.21474 -160.32226) (xy 72.285352 -160.251648) (xy 72.40905 -160.251648)
			(xy 72.41032 -160.210246) (xy 72.410944 -160.18309) (xy 72.418934 -160.129362) (xy 72.434465 -160.07731)
			(xy 72.457221 -160.027988) (xy 72.486743 -159.982392) (xy 72.522433 -159.941444) (xy 72.56357 -159.905972)
			(xy 72.609323 -159.876694) (xy 72.658766 -159.854201) (xy 72.710899 -159.838948) (xy 72.764669 -159.831244)
			(xy 72.818987 -159.831244) (xy 72.872757 -159.838948) (xy 72.92489 -159.854201) (xy 72.974333 -159.876694)
			(xy 73.020086 -159.905972) (xy 73.061223 -159.941444) (xy 73.096913 -159.982392) (xy 73.126435 -160.027988)
			(xy 73.149191 -160.07731) (xy 73.164722 -160.129362) (xy 73.172712 -160.18309) (xy 73.173336 -160.210246)
			(xy 73.174606 -160.251648) (xy 73.64476 -160.251648) (xy 75.95108 -157.945328) (xy 75.95108 -149.860762)
			(xy 75.950645 -149.847472) (xy 75.943775 -149.821793) (xy 75.930511 -149.798758) (xy 75.911751 -149.779926)
			(xy 75.888767 -149.766574) (xy 75.863115 -149.759607) (xy 75.836534 -149.759495) (xy 75.823572 -149.762464)
			(xy 75.791428 -149.771478) (xy 75.725379 -149.781174) (xy 75.692 -149.781768) (xy 75.662035 -149.781278)
			(xy 75.602618 -149.773456) (xy 75.54473 -149.757945) (xy 75.489361 -149.73501) (xy 75.43746 -149.705045)
			(xy 75.389915 -149.668562) (xy 75.347538 -149.626185) (xy 75.311055 -149.57864) (xy 75.28109 -149.526739)
			(xy 75.258155 -149.47137) (xy 75.242644 -149.413482) (xy 75.234822 -149.354065) (xy 75.234822 -149.294135)
			(xy 75.242644 -149.234718) (xy 75.258155 -149.17683) (xy 75.28109 -149.121461) (xy 75.311055 -149.06956)
			(xy 75.347538 -149.022015) (xy 75.389915 -148.979638) (xy 75.43746 -148.943155) (xy 75.489361 -148.91319)
			(xy 75.54473 -148.890255) (xy 75.602618 -148.874744) (xy 75.662035 -148.866922) (xy 75.692 -148.866352)
			(xy 75.725378 -148.866956) (xy 75.791427 -148.876646) (xy 75.823572 -148.885656) (xy 75.836539 -148.888632)
			(xy 75.863132 -148.888543) (xy 75.8888 -148.881588) (xy 75.911799 -148.868237) (xy 75.930569 -148.849397)
			(xy 75.943834 -148.826348) (xy 75.950693 -148.800655) (xy 75.95108 -148.787358) (xy 75.95108 -145.216118)
			(xy 75.912472 -145.17751) (xy 75.153774 -145.17751) (xy 75.123346 -145.20589) (xy 75.057346 -145.256566)
			(xy 74.986221 -145.299754) (xy 74.910815 -145.334938) (xy 74.832025 -145.361702) (xy 74.75079 -145.379725)
			(xy 74.668075 -145.388795) (xy 74.62647 -145.389346) (xy 74.586536 -145.388822) (xy 74.507107 -145.380471)
			(xy 74.428985 -145.363863) (xy 74.353027 -145.339181) (xy 74.280065 -145.306695) (xy 74.210899 -145.266761)
			(xy 74.146285 -145.219816) (xy 74.086932 -145.166374) (xy 74.033489 -145.107022) (xy 73.986544 -145.042408)
			(xy 73.946609 -144.973242) (xy 73.914122 -144.90028) (xy 73.889439 -144.824323) (xy 73.872831 -144.746201)
			(xy 73.864479 -144.666772) (xy 73.863962 -144.626838) (xy 73.864414 -144.589203) (xy 73.871823 -144.514299)
			(xy 73.886574 -144.440489) (xy 73.908523 -144.36849) (xy 73.937456 -144.299004) (xy 73.954894 -144.26565)
			(xy 73.932188 -144.234573) (xy 73.89192 -144.168976) (xy 73.857831 -144.099965) (xy 73.830209 -144.028121)
			(xy 73.809286 -143.954049) (xy 73.795237 -143.87837) (xy 73.788181 -143.801723) (xy 73.787762 -143.763238)
			(xy 73.788249 -143.722057) (xy 73.796318 -143.640092) (xy 73.812383 -143.559312) (xy 73.836288 -143.480496)
			(xy 73.867803 -143.404402) (xy 73.906625 -143.331764) (xy 73.952379 -143.263281) (xy 74.004626 -143.199613)
			(xy 74.062862 -143.141372) (xy 74.126527 -143.08912) (xy 74.195006 -143.04336) (xy 74.267641 -143.004532)
			(xy 74.343732 -142.97301) (xy 74.422546 -142.949099) (xy 74.503325 -142.933028) (xy 74.585289 -142.924952)
			(xy 74.62647 -142.92453) (xy 74.667531 -142.925028) (xy 74.749261 -142.933051) (xy 74.829816 -142.949023)
			(xy 74.908423 -142.972792) (xy 74.984332 -143.004129) (xy 75.056814 -143.042735) (xy 75.125177 -143.08824)
			(xy 75.188764 -143.140209) (xy 75.246969 -143.198143) (xy 75.299233 -143.261488) (xy 75.345055 -143.329638)
			(xy 75.383998 -143.40194) (xy 75.415688 -143.477702) (xy 75.439822 -143.556198) (xy 75.456169 -143.636677)
			(xy 75.464572 -143.718369) (xy 75.465178 -143.759428) (xy 75.465178 -143.763746) (xy 75.464591 -143.807967)
			(xy 75.455259 -143.895917) (xy 75.436734 -143.982398) (xy 75.423522 -144.024604) (xy 75.420399 -144.037596)
			(xy 75.420308 -144.064308) (xy 75.427146 -144.09013) (xy 75.440446 -144.113295) (xy 75.459299 -144.132219)
			(xy 75.482414 -144.145607) (xy 75.50821 -144.152543) (xy 75.521566 -144.152874) (xy 75.912472 -144.152874)
			(xy 75.95108 -144.114266) (xy 75.95108 -142.514828) (xy 75.5142 -142.077948) (xy 63.3222 -142.077948)
			(xy 63.123572 -142.276576) (xy 63.123572 -144.665192) (xy 71.87641 -144.665192) (xy 71.880481 -144.60957)
			(xy 71.892607 -144.555133) (xy 71.91253 -144.503042) (xy 71.939826 -144.454407) (xy 71.973912 -144.410264)
			(xy 72.014061 -144.371555) (xy 72.059419 -144.339104) (xy 72.109019 -144.313603) (xy 72.161803 -144.295596)
			(xy 72.216646 -144.285466) (xy 72.27238 -144.283429) (xy 72.327817 -144.289529) (xy 72.381774 -144.303635)
			(xy 72.433103 -144.325447) (xy 72.480709 -144.354501) (xy 72.523577 -144.390176) (xy 72.560794 -144.431713)
			(xy 72.591567 -144.478226) (xy 72.615239 -144.528723) (xy 72.631307 -144.58213) (xy 72.639427 -144.637306)
			(xy 72.639936 -144.665192) (xy 72.639427 -144.693078) (xy 72.631307 -144.748254) (xy 72.615239 -144.801661)
			(xy 72.591567 -144.852158) (xy 72.560794 -144.898671) (xy 72.523577 -144.940208) (xy 72.480709 -144.975883)
			(xy 72.433103 -145.004937) (xy 72.381774 -145.026749) (xy 72.327817 -145.040855) (xy 72.27238 -145.046955)
			(xy 72.216646 -145.044918) (xy 72.161803 -145.034788) (xy 72.109019 -145.016781) (xy 72.059419 -144.99128)
			(xy 72.014061 -144.958829) (xy 71.973912 -144.92012) (xy 71.939826 -144.875977) (xy 71.91253 -144.827342)
			(xy 71.892607 -144.775251) (xy 71.880481 -144.720814) (xy 71.87641 -144.665192) (xy 63.123572 -144.665192)
			(xy 63.123572 -146.228308) (xy 69.007995 -146.228308) (xy 69.012017 -146.142588) (xy 69.024048 -146.05762)
			(xy 69.043984 -145.974153) (xy 69.071647 -145.892919) (xy 69.106796 -145.814633) (xy 69.149122 -145.739982)
			(xy 69.198251 -145.669623) (xy 69.253754 -145.604173) (xy 69.315141 -145.544209) (xy 69.381874 -145.490256)
			(xy 69.453366 -145.442789) (xy 69.528988 -145.402225) (xy 69.608077 -145.368921) (xy 69.689937 -145.343169)
			(xy 69.773848 -145.325196) (xy 69.859074 -145.31516) (xy 69.944866 -145.313148) (xy 70.030468 -145.319179)
			(xy 70.11513 -145.333199) (xy 70.198107 -145.355085) (xy 70.27867 -145.384646) (xy 70.35611 -145.42162)
			(xy 70.429749 -145.465684) (xy 70.498937 -145.51645) (xy 70.563068 -145.573471) (xy 70.621577 -145.636247)
			(xy 70.67395 -145.704227) (xy 70.719728 -145.776812) (xy 70.758508 -145.853364) (xy 70.789949 -145.933212)
			(xy 70.813775 -146.015653) (xy 70.829776 -146.099963) (xy 70.837811 -146.185401) (xy 70.838314 -146.228308)
			(xy 70.837811 -146.271215) (xy 70.829776 -146.356653) (xy 70.813775 -146.440963) (xy 70.789949 -146.523404)
			(xy 70.758508 -146.603252) (xy 70.719728 -146.679804) (xy 70.67395 -146.752389) (xy 70.621577 -146.820369)
			(xy 70.563068 -146.883145) (xy 70.498937 -146.940166) (xy 70.429749 -146.990932) (xy 70.35611 -147.034996)
			(xy 70.27867 -147.07197) (xy 70.198107 -147.101531) (xy 70.11513 -147.123417) (xy 70.030468 -147.137437)
			(xy 69.944866 -147.143468) (xy 69.859074 -147.141456) (xy 69.773848 -147.13142) (xy 69.689937 -147.113447)
			(xy 69.608077 -147.087695) (xy 69.528988 -147.054391) (xy 69.453366 -147.013827) (xy 69.381874 -146.96636)
			(xy 69.315141 -146.912407) (xy 69.253754 -146.852443) (xy 69.198251 -146.786993) (xy 69.149122 -146.716634)
			(xy 69.106796 -146.641983) (xy 69.071647 -146.563697) (xy 69.043984 -146.482463) (xy 69.024048 -146.398996)
			(xy 69.012017 -146.314028) (xy 69.007995 -146.228308) (xy 63.123572 -146.228308) (xy 63.123572 -149.015704)
			(xy 69.034152 -149.015704) (xy 69.034152 -147.440904) (xy 69.034629 -147.427543) (xy 69.041531 -147.401729)
			(xy 69.054869 -147.378574) (xy 69.073737 -147.359652) (xy 69.096852 -147.346246) (xy 69.122647 -147.339268)
			(xy 69.136006 -147.338796) (xy 70.710806 -147.338796) (xy 70.724189 -147.33914) (xy 70.750038 -147.346082)
			(xy 70.773204 -147.359488) (xy 70.792101 -147.378443) (xy 70.805437 -147.40165) (xy 70.8123 -147.42752)
			(xy 70.81266 -147.440904) (xy 70.81266 -149.015704) (xy 70.812277 -149.029072) (xy 70.805365 -149.0549)
			(xy 70.792012 -149.078064) (xy 70.773125 -149.096988) (xy 70.749988 -149.110387) (xy 70.724173 -149.11735)
			(xy 70.710806 -149.117812) (xy 69.136006 -149.117812) (xy 69.122625 -149.117449) (xy 69.096776 -149.110511)
			(xy 69.073612 -149.097108) (xy 69.054714 -149.078157) (xy 69.041377 -149.054954) (xy 69.034513 -149.029087)
			(xy 69.034152 -149.015704) (xy 63.123572 -149.015704) (xy 63.123572 -152.364694) (xy 69.007995 -152.364694)
			(xy 69.012017 -152.278974) (xy 69.024048 -152.194006) (xy 69.043984 -152.110539) (xy 69.071647 -152.029305)
			(xy 69.106796 -151.951019) (xy 69.149122 -151.876368) (xy 69.198251 -151.806009) (xy 69.253754 -151.740559)
			(xy 69.315141 -151.680595) (xy 69.381874 -151.626642) (xy 69.453366 -151.579175) (xy 69.528988 -151.538611)
			(xy 69.608077 -151.505307) (xy 69.689937 -151.479555) (xy 69.773848 -151.461582) (xy 69.859074 -151.451546)
			(xy 69.944866 -151.449534) (xy 70.030468 -151.455565) (xy 70.11513 -151.469585) (xy 70.198107 -151.491471)
			(xy 70.27867 -151.521032) (xy 70.35611 -151.558006) (xy 70.429749 -151.60207) (xy 70.498937 -151.652836)
			(xy 70.563068 -151.709857) (xy 70.621577 -151.772633) (xy 70.67395 -151.840613) (xy 70.719728 -151.913198)
			(xy 70.758508 -151.98975) (xy 70.789949 -152.069598) (xy 70.813775 -152.152039) (xy 70.829776 -152.236349)
			(xy 70.837811 -152.321787) (xy 70.838314 -152.364694) (xy 70.837811 -152.407601) (xy 70.829776 -152.493039)
			(xy 70.813775 -152.577349) (xy 70.789949 -152.65979) (xy 70.758508 -152.739638) (xy 70.719728 -152.81619)
			(xy 70.67395 -152.888775) (xy 70.621577 -152.956755) (xy 70.563068 -153.019531) (xy 70.498937 -153.076552)
			(xy 70.429749 -153.127318) (xy 70.35611 -153.171382) (xy 70.27867 -153.208356) (xy 70.198107 -153.237917)
			(xy 70.11513 -153.259803) (xy 70.030468 -153.273823) (xy 69.944866 -153.279854) (xy 69.859074 -153.277842)
			(xy 69.773848 -153.267806) (xy 69.689937 -153.249833) (xy 69.608077 -153.224081) (xy 69.528988 -153.190777)
			(xy 69.453366 -153.150213) (xy 69.381874 -153.102746) (xy 69.315141 -153.048793) (xy 69.253754 -152.988829)
			(xy 69.198251 -152.923379) (xy 69.149122 -152.85302) (xy 69.106796 -152.778369) (xy 69.071647 -152.700083)
			(xy 69.043984 -152.618849) (xy 69.024048 -152.535382) (xy 69.012017 -152.450414) (xy 69.007995 -152.364694)
			(xy 63.123572 -152.364694) (xy 63.123572 -155.15209) (xy 69.034152 -155.15209) (xy 69.034152 -153.57729)
			(xy 69.034573 -153.563937) (xy 69.041487 -153.538142) (xy 69.054842 -153.515015) (xy 69.073728 -153.496132)
			(xy 69.096857 -153.482781) (xy 69.122653 -153.475871) (xy 69.136006 -153.475436) (xy 70.710806 -153.475436)
			(xy 70.724157 -153.475876) (xy 70.74995 -153.482788) (xy 70.773075 -153.49614) (xy 70.791958 -153.515021)
			(xy 70.80531 -153.538146) (xy 70.812223 -153.563939) (xy 70.81266 -153.57729) (xy 70.81266 -155.15209)
			(xy 70.812248 -155.165446) (xy 70.805337 -155.191249) (xy 70.791983 -155.214383) (xy 70.773096 -155.233273)
			(xy 70.749964 -155.246631) (xy 70.724162 -155.253546) (xy 70.710806 -155.253944) (xy 69.136006 -155.253944)
			(xy 69.122648 -155.253552) (xy 69.096843 -155.246639) (xy 69.073707 -155.233281) (xy 69.054816 -155.21439)
			(xy 69.04146 -155.191253) (xy 69.034547 -155.165448) (xy 69.034152 -155.15209) (xy 63.123572 -155.15209)
			(xy 63.123572 -158.49981) (xy 69.007995 -158.49981) (xy 69.012017 -158.41409) (xy 69.024048 -158.329122)
			(xy 69.043984 -158.245655) (xy 69.071647 -158.164421) (xy 69.106796 -158.086135) (xy 69.149122 -158.011484)
			(xy 69.198251 -157.941125) (xy 69.253754 -157.875675) (xy 69.315141 -157.815711) (xy 69.381874 -157.761758)
			(xy 69.453366 -157.714291) (xy 69.528988 -157.673727) (xy 69.608077 -157.640423) (xy 69.689937 -157.614671)
			(xy 69.773848 -157.596698) (xy 69.859074 -157.586662) (xy 69.944866 -157.58465) (xy 70.030468 -157.590681)
			(xy 70.11513 -157.604701) (xy 70.198107 -157.626587) (xy 70.27867 -157.656148) (xy 70.35611 -157.693122)
			(xy 70.429749 -157.737186) (xy 70.498937 -157.787952) (xy 70.563068 -157.844973) (xy 70.621577 -157.907749)
			(xy 70.67395 -157.975729) (xy 70.719728 -158.048314) (xy 70.758508 -158.124866) (xy 70.789949 -158.204714)
			(xy 70.813775 -158.287155) (xy 70.829776 -158.371465) (xy 70.837811 -158.456903) (xy 70.838314 -158.49981)
			(xy 70.837811 -158.542717) (xy 70.829776 -158.628155) (xy 70.813775 -158.712465) (xy 70.789949 -158.794906)
			(xy 70.758508 -158.874754) (xy 70.719728 -158.951306) (xy 70.67395 -159.023891) (xy 70.621577 -159.091871)
			(xy 70.563068 -159.154647) (xy 70.498937 -159.211668) (xy 70.429749 -159.262434) (xy 70.35611 -159.306498)
			(xy 70.27867 -159.343472) (xy 70.198107 -159.373033) (xy 70.11513 -159.394919) (xy 70.030468 -159.408939)
			(xy 69.944866 -159.41497) (xy 69.859074 -159.412958) (xy 69.773848 -159.402922) (xy 69.689937 -159.384949)
			(xy 69.608077 -159.359197) (xy 69.528988 -159.325893) (xy 69.453366 -159.285329) (xy 69.381874 -159.237862)
			(xy 69.315141 -159.183909) (xy 69.253754 -159.123945) (xy 69.198251 -159.058495) (xy 69.149122 -158.988136)
			(xy 69.106796 -158.913485) (xy 69.071647 -158.835199) (xy 69.043984 -158.753965) (xy 69.024048 -158.670498)
			(xy 69.012017 -158.58553) (xy 69.007995 -158.49981) (xy 63.123572 -158.49981) (xy 63.123572 -160.549844)
			(xy 63.284608 -160.71088) (xy 67.92214 -160.71088) (xy 68.498466 -161.287206) (xy 69.034152 -161.287206)
			(xy 69.034152 -159.712406) (xy 69.034548 -159.699049) (xy 69.041461 -159.673244) (xy 69.054818 -159.650108)
			(xy 69.073708 -159.631218) (xy 69.096844 -159.617861) (xy 69.122649 -159.610948) (xy 69.136006 -159.610552)
			(xy 70.710806 -159.610552) (xy 70.724159 -159.610976) (xy 70.749954 -159.61789) (xy 70.773081 -159.631244)
			(xy 70.791963 -159.650129) (xy 70.805315 -159.673257) (xy 70.812225 -159.699053) (xy 70.81266 -159.712406)
			(xy 70.81266 -161.287206) (xy 70.812224 -161.300558) (xy 70.805311 -161.326351) (xy 70.791959 -161.349477)
			(xy 70.773077 -161.368359) (xy 70.749951 -161.381711) (xy 70.724158 -161.388624) (xy 70.710806 -161.38906)
			(xy 69.136006 -161.38906) (xy 69.122655 -161.388613) (xy 69.096862 -161.381704) (xy 69.073736 -161.368354)
			(xy 69.054854 -161.349473) (xy 69.041501 -161.326349) (xy 69.034588 -161.300557) (xy 69.034152 -161.287206)
			(xy 68.498466 -161.287206) (xy 69.08546 -161.8742) (xy 71.08698 -161.8742)
		)
		(stroke
			(width 0)
			(type solid)
		)
		(fill yes)
		(layer "B.Cu")
		(net "PVCCINFAON_CPU1")
	)
	(gr_poly
		(pts
			(arc
				(start 256.800096 -36.291012)
				(mid 258.932727 -35.407647)
				(end 259.816092 -33.275016)
			)
			(xy 259.817616 -32.293306) (xy 259.817616 -32.275018)
			(arc
				(start 259.817616 -13.780008)
				(mid 260.105375 -13.085295)
				(end 260.800088 -12.797536)
			)
			(arc
				(start 385.601972 -12.797536)
				(mid 387.735681 -11.913725)
				(end 388.619492 -9.780016)
			)
			(xy 388.619492 -3.928364)
			(arc
				(start 388.614158 -3.917442)
				(mid 388.329377 -3.590886)
				(end 388.226808 -3.16992)
			)
			(arc
				(start 388.226808 -3.16992)
				(mid 388.275543 -2.875216)
				(end 388.416546 -2.611882)
			)
			(arc
				(start 388.416546 -2.611882)
				(mid 388.501545 -2.513276)
				(end 388.59968 -2.427732)
			)
			(xy 388.619492 -2.388108) (xy 388.619492 -1.016) (xy 455.184256 -1.016) (xy 455.184256 -2.375154)
			(arc
				(start 455.205338 -2.416048)
				(mid 455.573689 -3.012402)
				(end 455.41184 -3.69443)
			)
			(arc
				(start 455.41184 -3.69443)
				(mid 455.315091 -3.810755)
				(end 455.200512 -3.909568)
			)
			(xy 455.184256 -3.941318)
			(arc
				(start 455.184256 -9.780016)
				(mid 456.068231 -11.91374)
				(end 458.20203 -12.797536)
			)
			(arc
				(start 469.799924 -12.797536)
				(mid 470.494637 -13.085295)
				(end 470.782396 -13.780008)
			)
			(xy 470.782396 -17.930114)
			(arc
				(start 470.807288 -17.973294)
				(mid 470.970786 -18.072311)
				(end 471.130376 -18.17751)
			)
			(xy 471.141806 -18.185384) (xy 471.170254 -18.187162)
			(arc
				(start 471.262202 -18.138648)
				(mid 471.282048 -18.119954)
				(end 471.28938 -18.09369)
			)
			(arc
				(start 471.28938 -13.780008)
				(mid 470.853128 -12.726804)
				(end 469.799924 -12.290552)
			)
			(arc
				(start 458.20203 -12.290552)
				(mid 456.426813 -11.555233)
				(end 455.691494 -9.780016)
			)
			(xy 455.691494 -1.30556) (xy 455.69378 -1.30556)
			(arc
				(start 455.69378 -0.999998)
				(mid 455.549752 -0.652282)
				(end 455.202036 -0.508254)
			)
			(arc
				(start 388.601966 -0.508254)
				(mid 388.25425 -0.652282)
				(end 388.110222 -0.999998)
			)
			(xy 388.110222 -1.30556) (xy 388.112508 -1.30556)
			(arc
				(start 388.112508 -9.780016)
				(mid 387.377189 -11.555233)
				(end 385.601972 -12.290552)
			)
			(arc
				(start 260.800088 -12.290552)
				(mid 259.746884 -12.726804)
				(end 259.310632 -13.780008)
			)
			(arc
				(start 259.310632 -32.275018)
				(mid 259.308727 -32.775015)
				(end 259.308092 -33.275016)
			)
			(arc
				(start 259.308092 -33.275016)
				(mid 258.573517 -35.048437)
				(end 256.800096 -35.783012)
			)
			(arc
				(start 225.300032 -35.783012)
				(mid 223.526611 -35.048437)
				(end 222.792036 -33.275016)
			)
			(arc
				(start 222.792036 -33.275016)
				(mid 222.790131 -32.775019)
				(end 222.789496 -32.275018)
			)
			(arc
				(start 222.789496 -13.780008)
				(mid 222.353244 -12.726804)
				(end 221.30004 -12.290552)
			)
			(arc
				(start 196.701918 -12.290552)
				(mid 194.926701 -11.555233)
				(end 194.191382 -9.780016)
			)
			(xy 194.191382 -6.53796) (xy 194.193668 -6.53796)
			(arc
				(start 194.193668 -6.279896)
				(mid 194.04964 -5.93218)
				(end 193.701924 -5.788152)
			)
			(arc
				(start 127.102108 -5.788152)
				(mid 126.754392 -5.93218)
				(end 126.610364 -6.279896)
			)
			(xy 126.610364 -6.53796) (xy 126.61265 -6.53796)
			(arc
				(start 126.61265 -7.744206)
				(mid 126.627618 -7.779963)
				(end 126.66345 -7.794752)
			)
			(arc
				(start 126.687326 -7.78891)
				(mid 126.774244 -7.75555)
				(end 126.86665 -7.744206)
			)
			(arc
				(start 126.86665 -7.744206)
				(mid 126.931475 -7.749794)
				(end 126.994412 -7.766304)
			)
			(arc
				(start 126.994412 -7.766304)
				(mid 127.020815 -7.768359)
				(end 127.044704 -7.756906)
			)
			(arc
				(start 127.044704 -7.756906)
				(mid 127.071589 -7.734537)
				(end 127.099314 -7.713218)
			)
			(xy 127.119888 -7.672832) (xy 127.119888 -6.295898) (xy 193.684144 -6.295898) (xy 193.684144 -7.673086)
			(arc
				(start 193.704718 -7.713472)
				(mid 194.076604 -8.449818)
				(end 193.704718 -9.186164)
			)
			(xy 193.684144 -9.22655)
			(arc
				(start 193.684144 -9.780016)
				(mid 194.568119 -11.91374)
				(end 196.701918 -12.797536)
			)
			(arc
				(start 221.30004 -12.797536)
				(mid 221.994753 -13.085295)
				(end 222.282512 -13.780008)
			)
			(xy 222.282512 -32.275018)
			(arc
				(start 222.284036 -33.275016)
				(mid 223.167401 -35.407647)
				(end 225.300032 -36.291012)
			)
		)
		(stroke
			(width 0)
			(type solid)
		)
		(fill yes)
		(layer "B.Cu")
		(net "GND")
	)
	(gr_poly
		(pts
			(xy 445.28867 -25.933908) (xy 445.302206 -25.933488) (xy 445.328329 -25.92638) (xy 445.351665 -25.912655)
			(xy 445.370572 -25.893279) (xy 445.383722 -25.869614) (xy 445.390188 -25.843325) (xy 445.389518 -25.816261)
			(xy 445.381757 -25.790325) (xy 445.367451 -25.767341) (xy 445.357758 -25.757886) (xy 445.338844 -25.739757)
			(xy 445.30566 -25.699215) (xy 445.278329 -25.654517) (xy 445.257367 -25.606502) (xy 445.243166 -25.556072)
			(xy 445.235992 -25.504174) (xy 445.235584 -25.477978) (xy 445.23607 -25.450727) (xy 445.243826 -25.396779)
			(xy 445.259181 -25.344484) (xy 445.281823 -25.294907) (xy 445.311289 -25.249057) (xy 445.34698 -25.207866)
			(xy 445.388171 -25.172175) (xy 445.434021 -25.142709) (xy 445.483598 -25.120067) (xy 445.535893 -25.104712)
			(xy 445.589841 -25.096956) (xy 445.644343 -25.096956) (xy 445.698291 -25.104712) (xy 445.750586 -25.120067)
			(xy 445.800163 -25.142709) (xy 445.846013 -25.172175) (xy 445.887204 -25.207866) (xy 445.922895 -25.249057)
			(xy 445.952361 -25.294907) (xy 445.975003 -25.344484) (xy 445.990358 -25.396779) (xy 445.998114 -25.450727)
			(xy 445.9986 -25.477978) (xy 445.998169 -25.504174) (xy 445.991006 -25.556073) (xy 445.976813 -25.606504)
			(xy 445.955856 -25.654521) (xy 445.928529 -25.69922) (xy 445.895345 -25.739762) (xy 445.876426 -25.757886)
			(xy 445.866808 -25.767403) (xy 445.85253 -25.790375) (xy 445.844786 -25.816291) (xy 445.844121 -25.843331)
			(xy 445.850581 -25.869597) (xy 445.863712 -25.893243) (xy 445.882593 -25.912611) (xy 445.905898 -25.92634)
			(xy 445.93199 -25.933466) (xy 445.945514 -25.933908) (xy 446.65646 -25.933908) (xy 448.380612 -24.209756)
			(xy 448.389997 -24.199757) (xy 448.403542 -24.175926) (xy 448.410251 -24.149348) (xy 448.409639 -24.121943)
			(xy 448.401751 -24.09569) (xy 448.387157 -24.072487) (xy 448.37731 -24.062944) (xy 448.358108 -24.044795)
			(xy 448.324391 -24.004117) (xy 448.29661 -23.959176) (xy 448.275296 -23.91083) (xy 448.260859 -23.860006)
			(xy 448.253573 -23.807676) (xy 448.253104 -23.781258) (xy 448.253619 -23.752652) (xy 448.262173 -23.696083)
			(xy 448.279083 -23.641427) (xy 448.303968 -23.589911) (xy 448.336272 -23.542691) (xy 448.375267 -23.500827)
			(xy 448.42008 -23.46526) (xy 448.44462 -23.45055) (xy 448.44462 -23.186136) (xy 447.48958 -23.186136)
			(xy 447.467944 -23.207636) (xy 447.419967 -23.245303) (xy 447.367415 -23.276266) (xy 447.311217 -23.299979)
			(xy 447.252368 -23.31602) (xy 447.19191 -23.324106) (xy 447.161412 -23.324566) (xy 447.131443 -23.324098)
			(xy 447.072019 -23.316275) (xy 447.014124 -23.300763) (xy 446.95875 -23.277826) (xy 446.906843 -23.247856)
			(xy 446.859293 -23.211368) (xy 446.816912 -23.168985) (xy 446.780427 -23.121432) (xy 446.750461 -23.069523)
			(xy 446.727528 -23.014147) (xy 446.712019 -22.956251) (xy 446.7042 -22.896827) (xy 446.703704 -22.866858)
			(xy 446.704097 -22.839324) (xy 446.710668 -22.78465) (xy 446.723746 -22.731158) (xy 446.743143 -22.67962)
			(xy 446.75552 -22.655022) (xy 446.761909 -22.641747) (xy 446.767541 -22.612842) (xy 446.764677 -22.583532)
			(xy 446.753555 -22.556264) (xy 446.735104 -22.533313) (xy 446.710862 -22.516592) (xy 446.682853 -22.507497)
			(xy 446.668144 -22.506686) (xy 446.641334 -22.505571) (xy 446.588407 -22.49675) (xy 446.537238 -22.480597)
			(xy 446.488839 -22.457432) (xy 446.444163 -22.427712) (xy 446.404095 -22.392023) (xy 446.369424 -22.351071)
			(xy 446.340835 -22.305664) (xy 446.318893 -22.256698) (xy 446.30403 -22.20514) (xy 446.29654 -22.152007)
			(xy 446.296034 -22.125178) (xy 446.29652 -22.097927) (xy 446.304276 -22.043979) (xy 446.319631 -21.991684)
			(xy 446.342273 -21.942107) (xy 446.371739 -21.896257) (xy 446.40743 -21.855066) (xy 446.448621 -21.819375)
			(xy 446.494471 -21.789909) (xy 446.544048 -21.767267) (xy 446.596343 -21.751912) (xy 446.650291 -21.744156)
			(xy 446.704793 -21.744156) (xy 446.758741 -21.751912) (xy 446.811036 -21.767267) (xy 446.860613 -21.789909)
			(xy 446.906463 -21.819375) (xy 446.947654 -21.855066) (xy 446.983345 -21.896257) (xy 447.012811 -21.942107)
			(xy 447.035453 -21.991684) (xy 447.050808 -22.043979) (xy 447.058564 -22.097927) (xy 447.05905 -22.125178)
			(xy 447.058632 -22.149984) (xy 447.052171 -22.199174) (xy 447.039407 -22.247116) (xy 447.030348 -22.270212)
			(xy 447.025205 -22.284042) (xy 447.022262 -22.313388) (xy 447.027826 -22.342351) (xy 447.041435 -22.368517)
			(xy 447.061952 -22.389705) (xy 447.087668 -22.404146) (xy 447.116437 -22.410638) (xy 447.131186 -22.410166)
			(xy 447.161412 -22.40915) (xy 447.19191 -22.409635) (xy 447.252369 -22.417703) (xy 447.31122 -22.433734)
			(xy 447.367419 -22.457444) (xy 447.419968 -22.488411) (xy 447.467936 -22.526088) (xy 447.48958 -22.54758)
			(xy 448.44462 -22.54758) (xy 448.44462 -21.42617) (xy 448.440556 -21.416518) (xy 448.428828 -21.387916)
			(xy 448.412315 -21.328343) (xy 448.403991 -21.267087) (xy 448.403472 -21.236178) (xy 448.403999 -21.20527)
			(xy 448.412342 -21.144018) (xy 448.428833 -21.084441) (xy 448.440556 -21.055838) (xy 448.44462 -21.046186)
			(xy 448.44462 -20.903692) (xy 448.444188 -20.890089) (xy 448.437007 -20.863847) (xy 448.423158 -20.84043)
			(xy 448.403621 -20.821496) (xy 448.37978 -20.808388) (xy 448.353326 -20.802035) (xy 448.339718 -20.802092)
			(xy 448.327272 -20.802346) (xy 448.300019 -20.801858) (xy 448.246069 -20.794098) (xy 448.193773 -20.778739)
			(xy 448.144194 -20.756094) (xy 448.098343 -20.726624) (xy 448.057152 -20.690929) (xy 448.02146 -20.649735)
			(xy 447.991993 -20.603881) (xy 447.969352 -20.554301) (xy 447.953996 -20.502003) (xy 447.94624 -20.448053)
			(xy 447.94624 -20.393547) (xy 447.953996 -20.339597) (xy 447.969352 -20.287299) (xy 447.991993 -20.237719)
			(xy 448.02146 -20.191865) (xy 448.057152 -20.150671) (xy 448.098343 -20.114976) (xy 448.144194 -20.085506)
			(xy 448.193773 -20.062861) (xy 448.246069 -20.047502) (xy 448.300019 -20.039742) (xy 448.327272 -20.03933)
			(xy 448.339718 -20.039584) (xy 448.353331 -20.039603) (xy 448.379801 -20.033288) (xy 448.403659 -20.020199)
			(xy 448.423209 -20.001269) (xy 448.437058 -19.977844) (xy 448.444222 -19.951591) (xy 448.44462 -19.937984)
			(xy 448.44462 -17.437608) (xy 448.7037 -17.178528) (xy 450.82206 -17.178528) (xy 451.5358 -17.892268)
			(xy 451.5358 -18.816828) (xy 451.94474 -19.225768) (xy 452.54926 -19.225768) (xy 452.82866 -18.946368)
			(xy 452.82866 -17.912588) (xy 454.47712 -16.264128) (xy 454.47712 -14.262608) (xy 454.20788 -13.993368)
			(xy 452.916798 -13.993368) (xy 452.904991 -14.017811) (xy 452.875485 -14.063374) (xy 452.839816 -14.104293)
			(xy 452.798704 -14.139739) (xy 452.752981 -14.168996) (xy 452.70357 -14.191472) (xy 452.651471 -14.206714)
			(xy 452.597737 -14.214412) (xy 452.543455 -14.214412) (xy 452.489721 -14.206714) (xy 452.437622 -14.191472)
			(xy 452.388211 -14.168996) (xy 452.342488 -14.139739) (xy 452.301376 -14.104293) (xy 452.265707 -14.063374)
			(xy 452.236201 -14.017811) (xy 452.224394 -13.993368) (xy 451.940422 -13.993368) (xy 451.919856 -14.027107)
			(xy 451.87277 -14.090566) (xy 451.819373 -14.148815) (xy 451.760238 -14.201228) (xy 451.695998 -14.247244)
			(xy 451.627345 -14.286369) (xy 451.555012 -14.318184) (xy 451.479777 -14.342347) (xy 451.402447 -14.358599)
			(xy 451.32385 -14.366766) (xy 451.28434 -14.367256) (xy 451.24623 -14.366791) (xy 451.170391 -14.359183)
			(xy 451.095689 -14.344049) (xy 451.022868 -14.32154) (xy 450.952656 -14.29188) (xy 450.885753 -14.255365)
			(xy 450.822824 -14.212359) (xy 450.793358 -14.188186) (xy 450.781025 -14.178579) (xy 450.752141 -14.166657)
			(xy 450.721007 -14.164008) (xy 450.690525 -14.170878) (xy 450.663536 -14.186626) (xy 450.652642 -14.197838)
			(xy 450.626194 -14.22642) (xy 450.568823 -14.279085) (xy 450.506817 -14.326204) (xy 450.440709 -14.367371)
			(xy 450.37107 -14.402231) (xy 450.298498 -14.430485) (xy 450.223619 -14.451889) (xy 450.147078 -14.466258)
			(xy 450.069535 -14.473469) (xy 450.030596 -14.473936) (xy 449.991111 -14.473482) (xy 449.91249 -14.46606)
			(xy 449.834915 -14.451281) (xy 449.759072 -14.429276) (xy 449.685633 -14.400241) (xy 449.615248 -14.364433)
			(xy 449.54854 -14.322167) (xy 449.486099 -14.273819) (xy 449.428479 -14.219817) (xy 449.376189 -14.160638)
			(xy 449.329693 -14.096807) (xy 449.289402 -14.028888) (xy 449.272152 -13.993368) (xy 447.74866 -13.993368)
			(xy 447.657474 -13.902182) (xy 447.643758 -13.89888) (xy 447.615167 -13.891224) (xy 447.560604 -13.868294)
			(xy 447.510236 -13.837214) (xy 447.46527 -13.79873) (xy 447.426786 -13.753764) (xy 447.395706 -13.703396)
			(xy 447.372776 -13.648833) (xy 447.36512 -13.620242) (xy 447.361818 -13.606526) (xy 447.29908 -13.543788)
			(xy 445.34328 -13.543788) (xy 445.0588 -13.259308) (xy 445.0588 -12.605004) (xy 445.042619 -12.582813)
			(xy 445.016119 -12.534711) (xy 444.996789 -12.483306) (xy 444.98503 -12.429661) (xy 444.981085 -12.374884)
			(xy 444.985035 -12.320107) (xy 444.996798 -12.266463) (xy 445.016132 -12.21506) (xy 445.042637 -12.16696)
			(xy 445.0588 -12.144756) (xy 445.0588 -11.567668) (xy 443.25794 -9.766808) (xy 442.301884 -9.766808)
			(xy 442.290708 -9.77265) (xy 442.267719 -9.784096) (xy 442.218994 -9.800304) (xy 442.168302 -9.808499)
			(xy 442.142626 -9.808972) (xy 437.775096 -9.808972) (xy 437.24068 -10.343388) (xy 437.24068 -12.845288)
			(xy 438.15508 -13.759688) (xy 440.00928 -13.759688) (xy 440.46394 -14.214348) (xy 440.46394 -14.522704)
			(xy 440.466988 -14.525498) (xy 440.466988 -14.646148) (xy 446.581782 -14.646148) (xy 446.585853 -14.590526)
			(xy 446.597979 -14.536089) (xy 446.617902 -14.483998) (xy 446.645198 -14.435363) (xy 446.679284 -14.39122)
			(xy 446.719433 -14.352511) (xy 446.764791 -14.32006) (xy 446.814391 -14.294559) (xy 446.867175 -14.276552)
			(xy 446.922018 -14.266422) (xy 446.977752 -14.264385) (xy 447.033189 -14.270485) (xy 447.087146 -14.284591)
			(xy 447.138475 -14.306403) (xy 447.186081 -14.335457) (xy 447.228949 -14.371132) (xy 447.266166 -14.412669)
			(xy 447.296939 -14.459182) (xy 447.320611 -14.509679) (xy 447.336679 -14.563086) (xy 447.341427 -14.595348)
			(xy 447.775582 -14.595348) (xy 447.779653 -14.539726) (xy 447.791779 -14.485289) (xy 447.811702 -14.433198)
			(xy 447.838998 -14.384563) (xy 447.873084 -14.34042) (xy 447.913233 -14.301711) (xy 447.958591 -14.26926)
			(xy 448.008191 -14.243759) (xy 448.060975 -14.225752) (xy 448.115818 -14.215622) (xy 448.171552 -14.213585)
			(xy 448.226989 -14.219685) (xy 448.280946 -14.233791) (xy 448.332275 -14.255603) (xy 448.379881 -14.284657)
			(xy 448.422749 -14.320332) (xy 448.459966 -14.361869) (xy 448.490739 -14.408382) (xy 448.514411 -14.458879)
			(xy 448.530479 -14.512286) (xy 448.538599 -14.567462) (xy 448.539108 -14.595348) (xy 448.538599 -14.623234)
			(xy 448.530479 -14.67841) (xy 448.514411 -14.731817) (xy 448.490739 -14.782314) (xy 448.459966 -14.828827)
			(xy 448.422749 -14.870364) (xy 448.379881 -14.906039) (xy 448.332275 -14.935093) (xy 448.280946 -14.956905)
			(xy 448.226989 -14.971011) (xy 448.171552 -14.977111) (xy 448.115818 -14.975074) (xy 448.060975 -14.964944)
			(xy 448.008191 -14.946937) (xy 447.958591 -14.921436) (xy 447.913233 -14.888985) (xy 447.873084 -14.850276)
			(xy 447.838998 -14.806133) (xy 447.811702 -14.757498) (xy 447.791779 -14.705407) (xy 447.779653 -14.65097)
			(xy 447.775582 -14.595348) (xy 447.341427 -14.595348) (xy 447.344799 -14.618262) (xy 447.345308 -14.646148)
			(xy 447.344799 -14.674034) (xy 447.336679 -14.72921) (xy 447.320611 -14.782617) (xy 447.296939 -14.833114)
			(xy 447.266166 -14.879627) (xy 447.228949 -14.921164) (xy 447.186081 -14.956839) (xy 447.138475 -14.985893)
			(xy 447.087146 -15.007705) (xy 447.033189 -15.021811) (xy 446.977752 -15.027911) (xy 446.922018 -15.025874)
			(xy 446.867175 -15.015744) (xy 446.814391 -14.997737) (xy 446.764791 -14.972236) (xy 446.719433 -14.939785)
			(xy 446.679284 -14.901076) (xy 446.645198 -14.856933) (xy 446.617902 -14.808298) (xy 446.597979 -14.756207)
			(xy 446.585853 -14.70177) (xy 446.581782 -14.646148) (xy 440.466988 -14.646148) (xy 440.466988 -17.433798)
			(xy 446.165984 -17.433798) (xy 446.170055 -17.378176) (xy 446.182181 -17.323739) (xy 446.202104 -17.271648)
			(xy 446.2294 -17.223013) (xy 446.263486 -17.17887) (xy 446.303635 -17.140161) (xy 446.348993 -17.10771)
			(xy 446.398593 -17.082209) (xy 446.451377 -17.064202) (xy 446.50622 -17.054072) (xy 446.561954 -17.052035)
			(xy 446.617391 -17.058135) (xy 446.671348 -17.072241) (xy 446.722677 -17.094053) (xy 446.770283 -17.123107)
			(xy 446.813151 -17.158782) (xy 446.850368 -17.200319) (xy 446.881141 -17.246832) (xy 446.904813 -17.297329)
			(xy 446.920881 -17.350736) (xy 446.929001 -17.405912) (xy 446.92951 -17.433798) (xy 446.929001 -17.461684)
			(xy 446.920881 -17.51686) (xy 446.904813 -17.570267) (xy 446.881141 -17.620764) (xy 446.850368 -17.667277)
			(xy 446.813151 -17.708814) (xy 446.770283 -17.744489) (xy 446.722677 -17.773543) (xy 446.671348 -17.795355)
			(xy 446.617391 -17.809461) (xy 446.561954 -17.815561) (xy 446.50622 -17.813524) (xy 446.451377 -17.803394)
			(xy 446.398593 -17.785387) (xy 446.348993 -17.759886) (xy 446.303635 -17.727435) (xy 446.263486 -17.688726)
			(xy 446.2294 -17.644583) (xy 446.202104 -17.595948) (xy 446.182181 -17.543857) (xy 446.170055 -17.48942)
			(xy 446.165984 -17.433798) (xy 440.466988 -17.433798) (xy 440.466988 -18.446242) (xy 446.165984 -18.446242)
			(xy 446.170055 -18.39062) (xy 446.182181 -18.336183) (xy 446.202104 -18.284092) (xy 446.2294 -18.235457)
			(xy 446.263486 -18.191314) (xy 446.303635 -18.152605) (xy 446.348993 -18.120154) (xy 446.398593 -18.094653)
			(xy 446.451377 -18.076646) (xy 446.50622 -18.066516) (xy 446.561954 -18.064479) (xy 446.617391 -18.070579)
			(xy 446.671348 -18.084685) (xy 446.722677 -18.106497) (xy 446.770283 -18.135551) (xy 446.813151 -18.171226)
			(xy 446.850368 -18.212763) (xy 446.881141 -18.259276) (xy 446.904813 -18.309773) (xy 446.920881 -18.36318)
			(xy 446.929001 -18.418356) (xy 446.92951 -18.446242) (xy 446.929001 -18.474128) (xy 446.920881 -18.529304)
			(xy 446.904813 -18.582711) (xy 446.881141 -18.633208) (xy 446.850368 -18.679721) (xy 446.813151 -18.721258)
			(xy 446.770283 -18.756933) (xy 446.722677 -18.785987) (xy 446.671348 -18.807799) (xy 446.617391 -18.821905)
			(xy 446.561954 -18.828005) (xy 446.50622 -18.825968) (xy 446.451377 -18.815838) (xy 446.398593 -18.797831)
			(xy 446.348993 -18.77233) (xy 446.303635 -18.739879) (xy 446.263486 -18.70117) (xy 446.2294 -18.657027)
			(xy 446.202104 -18.608392) (xy 446.182181 -18.556301) (xy 446.170055 -18.501864) (xy 446.165984 -18.446242)
			(xy 440.466988 -18.446242) (xy 440.466988 -20.243038) (xy 446.294254 -20.243038) (xy 446.298325 -20.187416)
			(xy 446.310451 -20.132979) (xy 446.330374 -20.080888) (xy 446.35767 -20.032253) (xy 446.391756 -19.98811)
			(xy 446.431905 -19.949401) (xy 446.477263 -19.91695) (xy 446.526863 -19.891449) (xy 446.579647 -19.873442)
			(xy 446.63449 -19.863312) (xy 446.690224 -19.861275) (xy 446.745661 -19.867375) (xy 446.799618 -19.881481)
			(xy 446.850947 -19.903293) (xy 446.898553 -19.932347) (xy 446.941421 -19.968022) (xy 446.978638 -20.009559)
			(xy 447.009411 -20.056072) (xy 447.033083 -20.106569) (xy 447.049151 -20.159976) (xy 447.057271 -20.215152)
			(xy 447.05778 -20.243038) (xy 447.057271 -20.270924) (xy 447.049151 -20.3261) (xy 447.033083 -20.379507)
			(xy 447.009411 -20.430004) (xy 446.978638 -20.476517) (xy 446.941421 -20.518054) (xy 446.898553 -20.553729)
			(xy 446.850947 -20.582783) (xy 446.799618 -20.604595) (xy 446.745661 -20.618701) (xy 446.690224 -20.624801)
			(xy 446.63449 -20.622764) (xy 446.579647 -20.612634) (xy 446.526863 -20.594627) (xy 446.477263 -20.569126)
			(xy 446.431905 -20.536675) (xy 446.391756 -20.497966) (xy 446.35767 -20.453823) (xy 446.330374 -20.405188)
			(xy 446.310451 -20.353097) (xy 446.298325 -20.29866) (xy 446.294254 -20.243038) (xy 440.466988 -20.243038)
			(xy 440.466988 -21.228558) (xy 440.46394 -21.231352) (xy 440.46394 -21.236178) (xy 446.295524 -21.236178)
			(xy 446.299595 -21.180556) (xy 446.311721 -21.126119) (xy 446.331644 -21.074028) (xy 446.35894 -21.025393)
			(xy 446.393026 -20.98125) (xy 446.433175 -20.942541) (xy 446.478533 -20.91009) (xy 446.528133 -20.884589)
			(xy 446.580917 -20.866582) (xy 446.63576 -20.856452) (xy 446.691494 -20.854415) (xy 446.746931 -20.860515)
			(xy 446.800888 -20.874621) (xy 446.852217 -20.896433) (xy 446.899823 -20.925487) (xy 446.942691 -20.961162)
			(xy 446.979908 -21.002699) (xy 447.010681 -21.049212) (xy 447.034353 -21.099709) (xy 447.050421 -21.153116)
			(xy 447.058541 -21.208292) (xy 447.05905 -21.236178) (xy 447.058541 -21.264064) (xy 447.050421 -21.31924)
			(xy 447.034353 -21.372647) (xy 447.010681 -21.423144) (xy 446.979908 -21.469657) (xy 446.942691 -21.511194)
			(xy 446.899823 -21.546869) (xy 446.852217 -21.575923) (xy 446.800888 -21.597735) (xy 446.746931 -21.611841)
			(xy 446.691494 -21.617941) (xy 446.63576 -21.615904) (xy 446.580917 -21.605774) (xy 446.528133 -21.587767)
			(xy 446.478533 -21.562266) (xy 446.433175 -21.529815) (xy 446.393026 -21.491106) (xy 446.35894 -21.446963)
			(xy 446.331644 -21.398328) (xy 446.311721 -21.346237) (xy 446.299595 -21.2918) (xy 446.295524 -21.236178)
			(xy 440.46394 -21.236178) (xy 440.46394 -23.528528) (xy 442.86932 -25.933908)
		)
		(stroke
			(width 0)
			(type solid)
		)
		(fill yes)
		(layer "B.Cu")
		(net "P12V_OCP_SFF")
	)
	(gr_poly
		(pts
			(arc
				(start 364.363 -217.357706)
				(mid 364.449366 -217.309617)
				(end 364.453932 -217.210894)
			)
			(arc
				(start 364.453932 -217.210894)
				(mid 364.428204 -217.139611)
				(end 364.419388 -217.064336)
			)
			(arc
				(start 364.419388 -217.064336)
				(mid 364.74908 -216.734644)
				(end 365.078772 -217.064336)
			)
			(arc
				(start 365.078772 -217.064336)
				(mid 365.074064 -217.119346)
				(end 365.06023 -217.172794)
			)
			(xy 365.05261 -217.194892) (xy 365.14659 -217.357706) (xy 365.618522 -217.357706) (xy 365.927894 -217.048334)
			(xy 365.927894 -216.586562) (xy 365.371634 -216.030302) (xy 364.385606 -216.030302) (xy 364.107476 -215.752172)
			(xy 364.107476 -214.513414) (xy 365.852202 -212.768688) (xy 365.852202 -209.377788) (xy 366.282732 -208.947258)
			(xy 369.142772 -208.947258) (xy 369.568476 -209.372962) (xy 369.568476 -213.249002) (xy 369.20805 -213.609428)
			(xy 369.20805 -213.811612) (xy 369.50523 -214.108792) (xy 373.259604 -214.108792) (xy 373.267224 -214.101426)
			(xy 374.151144 -214.101426) (xy 374.450864 -213.801706) (xy 374.450864 -199.119236) (xy 373.882158 -198.55053)
			(xy 356.401878 -198.55053) (xy 356.127812 -198.824596) (xy 356.127812 -212.615018) (xy 355.770688 -212.972142)
			(xy 352.626168 -212.972142) (xy 352.343974 -212.689948) (xy 352.343974 -209.588608) (xy 352.23323 -209.477864)
			(xy 349.59036 -209.477864) (xy 349.472504 -209.595466) (xy 349.472504 -212.593428) (xy 348.394528 -213.671404)
			(xy 348.394528 -214.304372)
			(arc
				(start 348.426278 -214.317326)
				(mid 348.575658 -214.438605)
				(end 348.631764 -214.622634)
			)
			(arc
				(start 348.631764 -214.622634)
				(mid 348.625332 -214.687923)
				(end 348.60611 -214.75065)
			)
			(xy 348.592648 -214.782146) (xy 348.73819 -214.927688) (xy 348.838266 -214.927688) (xy 348.93885 -214.753444)
			(arc
				(start 348.930976 -214.7316)
				(mid 348.917237 -214.677889)
				(end 348.912688 -214.622634)
			)
			(arc
				(start 348.912688 -214.622634)
				(mid 349.242126 -214.293196)
				(end 349.571564 -214.622634)
			)
			(arc
				(start 349.571564 -214.622634)
				(mid 349.561735 -214.702759)
				(end 349.532702 -214.778082)
			)
			(arc
				(start 349.532702 -214.778082)
				(mid 349.535111 -214.878344)
				(end 349.622364 -214.927688)
			)
			(arc
				(start 349.801688 -214.927688)
				(mid 349.888851 -214.87829)
				(end 349.89135 -214.778082)
			)
			(arc
				(start 349.89135 -214.778082)
				(mid 349.862331 -214.702756)
				(end 349.852488 -214.622634)
			)
			(arc
				(start 349.852488 -214.622634)
				(mid 349.859561 -214.554226)
				(end 349.880682 -214.488776)
			)
			(xy 349.890588 -214.466424) (xy 349.676974 -214.061294)
			(arc
				(start 349.652844 -214.056722)
				(mid 349.459416 -213.943425)
				(end 349.383096 -213.732618)
			)
			(arc
				(start 349.383096 -213.732618)
				(mid 349.712534 -213.40318)
				(end 350.041972 -213.732618)
			)
			(arc
				(start 350.041972 -213.732618)
				(mid 350.034899 -213.801026)
				(end 350.013778 -213.866476)
			)
			(xy 350.003872 -213.888828) (xy 350.217486 -214.293958)
			(arc
				(start 350.241616 -214.29853)
				(mid 350.435044 -214.411827)
				(end 350.511364 -214.622634)
			)
			(arc
				(start 350.511364 -214.622634)
				(mid 350.501535 -214.702759)
				(end 350.472502 -214.778082)
			)
			(arc
				(start 350.472502 -214.778082)
				(mid 350.474911 -214.878344)
				(end 350.562164 -214.927688)
			)
			(xy 350.717866 -214.927688) (xy 350.81845 -214.753444)
			(arc
				(start 350.810576 -214.7316)
				(mid 350.796837 -214.677889)
				(end 350.792288 -214.622634)
			)
			(arc
				(start 350.792288 -214.622634)
				(mid 351.121726 -214.293196)
				(end 351.451164 -214.622634)
			)
			(arc
				(start 351.451164 -214.622634)
				(mid 351.441335 -214.702759)
				(end 351.412302 -214.778082)
			)
			(arc
				(start 351.412302 -214.778082)
				(mid 351.414711 -214.878344)
				(end 351.501964 -214.927688)
			)
			(arc
				(start 351.681288 -214.927688)
				(mid 351.768451 -214.87829)
				(end 351.77095 -214.778082)
			)
			(arc
				(start 351.77095 -214.778082)
				(mid 351.741931 -214.702756)
				(end 351.732088 -214.622634)
			)
			(arc
				(start 351.732088 -214.622634)
				(mid 351.739161 -214.554226)
				(end 351.760282 -214.488776)
			)
			(xy 351.770188 -214.466424) (xy 351.556574 -214.061294)
			(arc
				(start 351.532444 -214.056722)
				(mid 351.339016 -213.943425)
				(end 351.262696 -213.732618)
			)
			(arc
				(start 351.262696 -213.732618)
				(mid 351.592134 -213.40318)
				(end 351.921572 -213.732618)
			)
			(arc
				(start 351.921572 -213.732618)
				(mid 351.914499 -213.801026)
				(end 351.893378 -213.866476)
			)
			(xy 351.883472 -213.888828) (xy 352.097086 -214.293958)
			(arc
				(start 352.121216 -214.29853)
				(mid 352.314644 -214.411827)
				(end 352.390964 -214.622634)
			)
			(arc
				(start 352.390964 -214.622634)
				(mid 352.381135 -214.702759)
				(end 352.352102 -214.778082)
			)
			(arc
				(start 352.352102 -214.778082)
				(mid 352.354511 -214.878344)
				(end 352.441764 -214.927688)
			)
			(xy 352.597466 -214.927688) (xy 352.69805 -214.753444)
			(arc
				(start 352.690176 -214.7316)
				(mid 352.676437 -214.677889)
				(end 352.671888 -214.622634)
			)
			(arc
				(start 352.671888 -214.622634)
				(mid 353.001326 -214.293196)
				(end 353.330764 -214.622634)
			)
			(arc
				(start 353.330764 -214.622634)
				(mid 353.320935 -214.702759)
				(end 353.291902 -214.778082)
			)
			(arc
				(start 353.291902 -214.778082)
				(mid 353.294311 -214.878344)
				(end 353.381564 -214.927688)
			)
			(arc
				(start 353.560888 -214.927688)
				(mid 353.648051 -214.87829)
				(end 353.65055 -214.778082)
			)
			(arc
				(start 353.65055 -214.778082)
				(mid 353.621531 -214.702756)
				(end 353.611688 -214.622634)
			)
			(arc
				(start 353.611688 -214.622634)
				(mid 353.618761 -214.554226)
				(end 353.639882 -214.488776)
			)
			(xy 353.649788 -214.466424) (xy 353.436174 -214.061294)
			(arc
				(start 353.412044 -214.056722)
				(mid 353.218616 -213.943425)
				(end 353.142296 -213.732618)
			)
			(arc
				(start 353.142296 -213.732618)
				(mid 353.471734 -213.40318)
				(end 353.801172 -213.732618)
			)
			(arc
				(start 353.801172 -213.732618)
				(mid 353.794099 -213.801026)
				(end 353.772978 -213.866476)
			)
			(xy 353.763072 -213.888828) (xy 353.976686 -214.293958)
			(arc
				(start 354.000816 -214.29853)
				(mid 354.194244 -214.411827)
				(end 354.270564 -214.622634)
			)
			(arc
				(start 354.270564 -214.622634)
				(mid 354.260735 -214.702759)
				(end 354.231702 -214.778082)
			)
			(arc
				(start 354.231702 -214.778082)
				(mid 354.234111 -214.878344)
				(end 354.321364 -214.927688)
			)
			(xy 354.477066 -214.927688) (xy 354.57765 -214.753444)
			(arc
				(start 354.569776 -214.7316)
				(mid 354.556037 -214.677889)
				(end 354.551488 -214.622634)
			)
			(arc
				(start 354.551488 -214.622634)
				(mid 354.880926 -214.293196)
				(end 355.210364 -214.622634)
			)
			(arc
				(start 355.210364 -214.622634)
				(mid 355.200535 -214.702759)
				(end 355.171502 -214.778082)
			)
			(arc
				(start 355.171502 -214.778082)
				(mid 355.173911 -214.878344)
				(end 355.261164 -214.927688)
			)
			(arc
				(start 355.440488 -214.927688)
				(mid 355.527651 -214.87829)
				(end 355.53015 -214.778082)
			)
			(arc
				(start 355.53015 -214.778082)
				(mid 355.501131 -214.702756)
				(end 355.491288 -214.622634)
			)
			(arc
				(start 355.491288 -214.622634)
				(mid 355.498361 -214.554226)
				(end 355.519482 -214.488776)
			)
			(xy 355.529388 -214.466424) (xy 355.315774 -214.061294)
			(arc
				(start 355.291644 -214.056722)
				(mid 355.098216 -213.943425)
				(end 355.021896 -213.732618)
			)
			(arc
				(start 355.021896 -213.732618)
				(mid 355.351334 -213.40318)
				(end 355.680772 -213.732618)
			)
			(arc
				(start 355.680772 -213.732618)
				(mid 355.673699 -213.801026)
				(end 355.652578 -213.866476)
			)
			(xy 355.642672 -213.888828) (xy 355.856286 -214.293958)
			(arc
				(start 355.880416 -214.29853)
				(mid 356.073844 -214.411827)
				(end 356.150164 -214.622634)
			)
			(arc
				(start 356.150164 -214.622634)
				(mid 356.140335 -214.702759)
				(end 356.111302 -214.778082)
			)
			(arc
				(start 356.111302 -214.778082)
				(mid 356.113711 -214.878344)
				(end 356.200964 -214.927688)
			)
			(xy 356.356666 -214.927688) (xy 356.45725 -214.753444)
			(arc
				(start 356.449376 -214.7316)
				(mid 356.435637 -214.677889)
				(end 356.431088 -214.622634)
			)
			(arc
				(start 356.431088 -214.622634)
				(mid 356.760526 -214.293196)
				(end 357.089964 -214.622634)
			)
			(arc
				(start 357.089964 -214.622634)
				(mid 357.080135 -214.702759)
				(end 357.051102 -214.778082)
			)
			(arc
				(start 357.051102 -214.778082)
				(mid 357.053511 -214.878344)
				(end 357.140764 -214.927688)
			)
			(arc
				(start 358.259888 -214.927688)
				(mid 358.347051 -214.87829)
				(end 358.34955 -214.778082)
			)
			(arc
				(start 358.34955 -214.778082)
				(mid 358.320531 -214.702756)
				(end 358.310688 -214.622634)
			)
			(arc
				(start 358.310688 -214.622634)
				(mid 358.640126 -214.293196)
				(end 358.969564 -214.622634)
			)
			(arc
				(start 358.969564 -214.622634)
				(mid 358.964984 -214.677633)
				(end 358.951276 -214.731092)
			)
			(xy 358.943656 -214.75319) (xy 359.044494 -214.927688) (xy 359.569258 -214.927688) (xy 359.88752 -214.609426)
			(xy 359.88752 -214.503508) (xy 359.114344 -213.730332) (xy 359.114344 -209.430366) (xy 359.714038 -208.830926)
			(xy 362.23067 -208.830926) (xy 362.906564 -209.50682) (xy 362.906564 -214.374222) (xy 362.527342 -214.753444)
			(xy 362.527342 -215.943942)
			(arc
				(start 362.55452 -215.958166)
				(mid 362.683173 -216.079881)
				(end 362.730542 -216.25052)
			)
			(arc
				(start 362.730542 -216.25052)
				(mid 362.719382 -216.335707)
				(end 362.6866 -216.415112)
			)
			(xy 362.667296 -216.44864) (xy 362.96854 -216.749884)
			(arc
				(start 362.979208 -216.753694)
				(mid 363.102438 -216.831378)
				(end 363.180122 -216.954608)
			)
			(xy 363.183932 -216.965276) (xy 363.576362 -217.357706)
		)
		(stroke
			(width 0)
			(type solid)
		)
		(fill yes)
		(layer "B.Cu")
		(net "GND")
	)
	(gr_poly
		(pts
			(xy 465.31657 -395.99616) (xy 467.047834 -394.264642) (xy 467.047834 -368.257582) (xy 466.4456 -367.655348)
			(xy 443.7888 -367.655348) (xy 443.5348 -367.909348) (xy 443.5348 -371.405912) (xy 443.554371 -371.427298)
			(xy 443.587476 -371.474885) (xy 443.612994 -371.526935) (xy 443.630338 -371.582249) (xy 443.639109 -371.63955)
			(xy 443.639104 -371.697519) (xy 443.630323 -371.754819) (xy 443.612968 -371.81013) (xy 443.58744 -371.862175)
			(xy 443.554327 -371.909756) (xy 443.5348 -371.931184) (xy 443.5348 -372.92534) (xy 441.8203 -374.63984)
			(xy 435.09692 -374.63984) (xy 435.08168 -374.6246) (xy 433.15636 -374.6246) (xy 432.652678 -375.128282)
			(xy 432.652678 -378.526548) (xy 438.052462 -378.526548) (xy 438.056533 -378.470926) (xy 438.068659 -378.416489)
			(xy 438.088582 -378.364398) (xy 438.115878 -378.315763) (xy 438.149964 -378.27162) (xy 438.190113 -378.232911)
			(xy 438.235471 -378.20046) (xy 438.285071 -378.174959) (xy 438.337855 -378.156952) (xy 438.392698 -378.146822)
			(xy 438.448432 -378.144785) (xy 438.503869 -378.150885) (xy 438.557826 -378.164991) (xy 438.609155 -378.186803)
			(xy 438.656761 -378.215857) (xy 438.699629 -378.251532) (xy 438.736846 -378.293069) (xy 438.767619 -378.339582)
			(xy 438.791291 -378.390079) (xy 438.807359 -378.443486) (xy 438.815479 -378.498662) (xy 438.815988 -378.526548)
			(xy 438.815479 -378.554434) (xy 438.807359 -378.60961) (xy 438.791291 -378.663017) (xy 438.767619 -378.713514)
			(xy 438.736846 -378.760027) (xy 438.699629 -378.801564) (xy 438.656761 -378.837239) (xy 438.609155 -378.866293)
			(xy 438.557826 -378.888105) (xy 438.503869 -378.902211) (xy 438.448432 -378.908311) (xy 438.392698 -378.906274)
			(xy 438.337855 -378.896144) (xy 438.285071 -378.878137) (xy 438.235471 -378.852636) (xy 438.190113 -378.820185)
			(xy 438.149964 -378.781476) (xy 438.115878 -378.737333) (xy 438.088582 -378.688698) (xy 438.068659 -378.636607)
			(xy 438.056533 -378.58217) (xy 438.052462 -378.526548) (xy 432.652678 -378.526548) (xy 432.652678 -379.070108)
			(xy 432.645058 -379.088904) (xy 432.645058 -380.807468) (xy 432.645509 -380.820935) (xy 432.652627 -380.846914)
			(xy 432.666297 -380.870124) (xy 432.685564 -380.888948) (xy 432.709086 -380.902072) (xy 432.735224 -380.908584)
			(xy 432.762155 -380.908027) (xy 432.788001 -380.900442) (xy 432.799744 -380.893828) (xy 432.822391 -380.880439)
			(xy 432.870583 -380.859333) (xy 432.921218 -380.845052) (xy 432.973336 -380.837866) (xy 432.999642 -380.83744)
			(xy 433.026888 -380.837929) (xy 433.080824 -380.845689) (xy 433.133107 -380.861046) (xy 433.182673 -380.883687)
			(xy 433.228512 -380.913151) (xy 433.269692 -380.948838) (xy 433.305375 -380.990021) (xy 433.334833 -381.035864)
			(xy 433.357468 -381.085432) (xy 433.37282 -381.137717) (xy 433.380574 -381.191654) (xy 433.380574 -381.246146)
			(xy 433.37282 -381.300083) (xy 433.357468 -381.352368) (xy 433.334833 -381.401936) (xy 433.305375 -381.447779)
			(xy 433.269692 -381.488962) (xy 433.228512 -381.524649) (xy 433.182673 -381.554113) (xy 433.133107 -381.576754)
			(xy 433.080824 -381.592111) (xy 433.026888 -381.599871) (xy 432.999642 -381.600456) (xy 432.973336 -381.600032)
			(xy 432.921219 -381.592841) (xy 432.870583 -381.578561) (xy 432.822388 -381.557463) (xy 432.799744 -381.544068)
			(xy 432.788042 -381.537389) (xy 432.762191 -381.529824) (xy 432.735261 -381.529284) (xy 432.709128 -381.535809)
			(xy 432.685612 -381.548943) (xy 432.666351 -381.567772) (xy 432.652686 -381.590983) (xy 432.64557 -381.616962)
			(xy 432.645058 -381.630428) (xy 432.645058 -385.760468) (xy 432.645509 -385.773935) (xy 432.652627 -385.799914)
			(xy 432.666297 -385.823124) (xy 432.685564 -385.841948) (xy 432.709086 -385.855072) (xy 432.735224 -385.861584)
			(xy 432.762155 -385.861027) (xy 432.788001 -385.853442) (xy 432.799744 -385.846828) (xy 432.822391 -385.833439)
			(xy 432.870583 -385.812333) (xy 432.921218 -385.798052) (xy 432.973336 -385.790866) (xy 432.999642 -385.79044)
			(xy 433.026888 -385.790929) (xy 433.080824 -385.798689) (xy 433.133107 -385.814046) (xy 433.182673 -385.836687)
			(xy 433.228512 -385.866151) (xy 433.269692 -385.901838) (xy 433.305375 -385.943021) (xy 433.334833 -385.988864)
			(xy 433.357468 -386.038432) (xy 433.37282 -386.090717) (xy 433.380574 -386.144654) (xy 433.380574 -386.199146)
			(xy 433.37282 -386.253083) (xy 433.357468 -386.305368) (xy 433.334833 -386.354936) (xy 433.305375 -386.400779)
			(xy 433.269692 -386.441962) (xy 433.228512 -386.477649) (xy 433.182673 -386.507113) (xy 433.133107 -386.529754)
			(xy 433.080824 -386.545111) (xy 433.026888 -386.552871) (xy 432.999642 -386.553456) (xy 432.973336 -386.553032)
			(xy 432.921219 -386.545841) (xy 432.870583 -386.531561) (xy 432.822388 -386.510463) (xy 432.799744 -386.497068)
			(xy 432.788042 -386.490389) (xy 432.762191 -386.482824) (xy 432.735261 -386.482284) (xy 432.709128 -386.488809)
			(xy 432.685612 -386.501943) (xy 432.666351 -386.520772) (xy 432.652686 -386.543983) (xy 432.64557 -386.569962)
			(xy 432.645058 -386.583428) (xy 432.645058 -390.926066) (xy 437.298592 -390.926066) (xy 437.298592 -379.7554)
			(xy 437.299038 -379.731403) (xy 437.306505 -379.683995) (xy 437.321317 -379.638345) (xy 437.343106 -379.595584)
			(xy 437.371334 -379.556771) (xy 437.388 -379.5395) (xy 437.423052 -379.504448) (xy 437.44037 -379.48784)
			(xy 437.479194 -379.45965) (xy 437.521946 -379.437871) (xy 437.567576 -379.42304) (xy 437.614963 -379.415521)
			(xy 437.638952 -379.41504) (xy 446.142618 -379.41504) (xy 446.166615 -379.41549) (xy 446.214022 -379.422958)
			(xy 446.259671 -379.43777) (xy 446.302432 -379.459558) (xy 446.341246 -379.487784) (xy 446.358518 -379.504448)
			(xy 446.523618 -379.669548) (xy 460.297782 -379.669548) (xy 460.301853 -379.613926) (xy 460.313979 -379.559489)
			(xy 460.333902 -379.507398) (xy 460.361198 -379.458763) (xy 460.395284 -379.41462) (xy 460.435433 -379.375911)
			(xy 460.480791 -379.34346) (xy 460.530391 -379.317959) (xy 460.583175 -379.299952) (xy 460.638018 -379.289822)
			(xy 460.693752 -379.287785) (xy 460.749189 -379.293885) (xy 460.803146 -379.307991) (xy 460.854475 -379.329803)
			(xy 460.902081 -379.358857) (xy 460.944949 -379.394532) (xy 460.982166 -379.436069) (xy 461.012939 -379.482582)
			(xy 461.036611 -379.533079) (xy 461.052679 -379.586486) (xy 461.060799 -379.641662) (xy 461.061308 -379.669548)
			(xy 461.060799 -379.697434) (xy 461.052679 -379.75261) (xy 461.036611 -379.806017) (xy 461.012939 -379.856514)
			(xy 460.982166 -379.903027) (xy 460.944949 -379.944564) (xy 460.902081 -379.980239) (xy 460.854475 -380.009293)
			(xy 460.803146 -380.031105) (xy 460.749189 -380.045211) (xy 460.693752 -380.051311) (xy 460.638018 -380.049274)
			(xy 460.583175 -380.039144) (xy 460.530391 -380.021137) (xy 460.480791 -379.995636) (xy 460.435433 -379.963185)
			(xy 460.395284 -379.924476) (xy 460.361198 -379.880333) (xy 460.333902 -379.831698) (xy 460.313979 -379.779607)
			(xy 460.301853 -379.72517) (xy 460.297782 -379.669548) (xy 446.523618 -379.669548) (xy 446.626488 -379.772418)
			(xy 446.643134 -379.789702) (xy 446.671318 -379.828536) (xy 446.693089 -379.871297) (xy 446.707911 -379.916934)
			(xy 446.715421 -379.964326) (xy 446.715896 -379.988318) (xy 446.715896 -381.404114) (xy 461.463388 -381.404114)
			(xy 461.467459 -381.348492) (xy 461.479585 -381.294055) (xy 461.499508 -381.241964) (xy 461.526804 -381.193329)
			(xy 461.56089 -381.149186) (xy 461.601039 -381.110477) (xy 461.646397 -381.078026) (xy 461.695997 -381.052525)
			(xy 461.748781 -381.034518) (xy 461.803624 -381.024388) (xy 461.859358 -381.022351) (xy 461.914795 -381.028451)
			(xy 461.968752 -381.042557) (xy 462.020081 -381.064369) (xy 462.067687 -381.093423) (xy 462.110555 -381.129098)
			(xy 462.147772 -381.170635) (xy 462.178545 -381.217148) (xy 462.202217 -381.267645) (xy 462.218285 -381.321052)
			(xy 462.226405 -381.376228) (xy 462.226914 -381.404114) (xy 462.226405 -381.432) (xy 462.218285 -381.487176)
			(xy 462.202217 -381.540583) (xy 462.193558 -381.559054) (xy 463.166712 -381.559054) (xy 463.170783 -381.503432)
			(xy 463.182909 -381.448995) (xy 463.202832 -381.396904) (xy 463.230128 -381.348269) (xy 463.264214 -381.304126)
			(xy 463.304363 -381.265417) (xy 463.349721 -381.232966) (xy 463.399321 -381.207465) (xy 463.452105 -381.189458)
			(xy 463.506948 -381.179328) (xy 463.562682 -381.177291) (xy 463.618119 -381.183391) (xy 463.672076 -381.197497)
			(xy 463.689681 -381.204978) (xy 464.315048 -381.204978) (xy 464.315541 -381.17613) (xy 464.324227 -381.119091)
			(xy 464.341412 -381.064014) (xy 464.366703 -381.012157) (xy 464.399522 -380.964704) (xy 464.418934 -380.943358)
			(xy 464.429105 -380.931769) (xy 464.442652 -380.904088) (xy 464.447314 -380.873626) (xy 464.442667 -380.843161)
			(xy 464.429135 -380.815473) (xy 464.418934 -380.803912) (xy 464.399513 -380.782577) (xy 464.366716 -380.735113)
			(xy 464.341441 -380.683251) (xy 464.324264 -380.628174) (xy 464.315577 -380.571139) (xy 464.315048 -380.542292)
			(xy 464.31557 -380.515043) (xy 464.323327 -380.461098) (xy 464.338681 -380.408807) (xy 464.361319 -380.359233)
			(xy 464.390782 -380.313384) (xy 464.42647 -380.272195) (xy 464.467656 -380.236504) (xy 464.513501 -380.207037)
			(xy 464.563073 -380.184393) (xy 464.615363 -380.169034) (xy 464.669307 -380.161273) (xy 464.696556 -380.160784)
			(xy 464.725296 -380.161278) (xy 464.782124 -380.169908) (xy 464.837015 -380.186966) (xy 464.888727 -380.212064)
			(xy 464.936088 -380.244635) (xy 464.957414 -380.263908) (xy 464.968948 -380.27398) (xy 464.996494 -380.287322)
			(xy 465.026756 -380.291907) (xy 465.057018 -380.287322) (xy 465.084564 -380.27398) (xy 465.096098 -380.263908)
			(xy 465.117398 -380.244606) (xy 465.164768 -380.212045) (xy 465.216486 -380.186959) (xy 465.271383 -380.169916)
			(xy 465.328215 -380.161301) (xy 465.356956 -380.160784) (xy 465.384207 -380.161296) (xy 465.438156 -380.169047)
			(xy 465.490453 -380.184397) (xy 465.540032 -380.207034) (xy 465.585885 -380.236496) (xy 465.627078 -380.272185)
			(xy 465.662772 -380.313373) (xy 465.692241 -380.359222) (xy 465.714885 -380.408799) (xy 465.730242 -380.461093)
			(xy 465.738 -380.515041) (xy 465.738464 -380.542292) (xy 465.737949 -380.571139) (xy 465.729268 -380.628177)
			(xy 465.712088 -380.683254) (xy 465.686802 -380.735112) (xy 465.653988 -380.782565) (xy 465.634578 -380.803912)
			(xy 465.624387 -380.815468) (xy 465.610927 -380.843173) (xy 465.606307 -380.873626) (xy 465.610943 -380.904076)
			(xy 465.624416 -380.931774) (xy 465.634578 -380.943358) (xy 465.653987 -380.964704) (xy 465.686785 -381.012165)
			(xy 465.712063 -381.064025) (xy 465.729243 -381.119099) (xy 465.737933 -381.176132) (xy 465.738464 -381.204978)
			(xy 465.738024 -381.232232) (xy 465.730269 -381.286186) (xy 465.714913 -381.338487) (xy 465.69227 -381.38807)
			(xy 465.662801 -381.433926) (xy 465.627104 -381.47512) (xy 465.585908 -381.510814) (xy 465.540051 -381.540281)
			(xy 465.490467 -381.562921) (xy 465.438165 -381.578274) (xy 465.38421 -381.586026) (xy 465.356956 -381.586486)
			(xy 465.328217 -381.585966) (xy 465.271391 -381.577339) (xy 465.216501 -381.560287) (xy 465.164789 -381.535195)
			(xy 465.117426 -381.502631) (xy 465.096098 -381.483362) (xy 465.084564 -381.47329) (xy 465.057018 -381.459948)
			(xy 465.026756 -381.455363) (xy 464.996494 -381.459948) (xy 464.968948 -381.47329) (xy 464.957414 -381.483362)
			(xy 464.936105 -381.502654) (xy 464.888738 -381.535217) (xy 464.837022 -381.560305) (xy 464.782127 -381.577351)
			(xy 464.725296 -381.585968) (xy 464.696556 -381.586486) (xy 464.669303 -381.586063) (xy 464.615352 -381.5783)
			(xy 464.563054 -381.562938) (xy 464.513475 -381.54029) (xy 464.467624 -381.510817) (xy 464.426434 -381.475119)
			(xy 464.390743 -381.433923) (xy 464.361278 -381.388067) (xy 464.338639 -381.338484) (xy 464.323286 -381.286184)
			(xy 464.315532 -381.232231) (xy 464.315048 -381.204978) (xy 463.689681 -381.204978) (xy 463.723405 -381.219309)
			(xy 463.771011 -381.248363) (xy 463.813879 -381.284038) (xy 463.851096 -381.325575) (xy 463.881869 -381.372088)
			(xy 463.905541 -381.422585) (xy 463.921609 -381.475992) (xy 463.929729 -381.531168) (xy 463.930238 -381.559054)
			(xy 463.929729 -381.58694) (xy 463.921609 -381.642116) (xy 463.905541 -381.695523) (xy 463.881869 -381.74602)
			(xy 463.851096 -381.792533) (xy 463.813879 -381.83407) (xy 463.771011 -381.869745) (xy 463.723405 -381.898799)
			(xy 463.672076 -381.920611) (xy 463.618119 -381.934717) (xy 463.562682 -381.940817) (xy 463.506948 -381.93878)
			(xy 463.452105 -381.92865) (xy 463.399321 -381.910643) (xy 463.349721 -381.885142) (xy 463.304363 -381.852691)
			(xy 463.264214 -381.813982) (xy 463.230128 -381.769839) (xy 463.202832 -381.721204) (xy 463.182909 -381.669113)
			(xy 463.170783 -381.614676) (xy 463.166712 -381.559054) (xy 462.193558 -381.559054) (xy 462.178545 -381.59108)
			(xy 462.147772 -381.637593) (xy 462.110555 -381.67913) (xy 462.067687 -381.714805) (xy 462.020081 -381.743859)
			(xy 461.968752 -381.765671) (xy 461.914795 -381.779777) (xy 461.859358 -381.785877) (xy 461.803624 -381.78384)
			(xy 461.748781 -381.77371) (xy 461.695997 -381.755703) (xy 461.646397 -381.730202) (xy 461.601039 -381.697751)
			(xy 461.56089 -381.659042) (xy 461.526804 -381.614899) (xy 461.499508 -381.566264) (xy 461.479585 -381.514173)
			(xy 461.467459 -381.459736) (xy 461.463388 -381.404114) (xy 446.715896 -381.404114) (xy 446.715896 -382.753108)
			(xy 455.66584 -382.753108) (xy 455.66584 -382.118108) (xy 455.856848 -382.118108) (xy 455.867823 -382.111023)
			(xy 455.890575 -382.098185) (xy 455.902314 -382.092454) (xy 455.931016 -382.078484) (xy 455.931016 -382.058164)
			(xy 456.012804 -382.058164) (xy 456.01636 -382.05791) (xy 456.02931 -382.056185) (xy 456.055367 -382.054275)
			(xy 456.06843 -382.0541) (xy 456.081493 -382.054273) (xy 456.107551 -382.056176) (xy 456.1205 -382.05791)
			(xy 456.124056 -382.058164) (xy 456.198478 -382.058164) (xy 456.221553 -382.058725) (xy 456.266737 -382.068129)
			(xy 456.309079 -382.086488) (xy 456.328272 -382.099312) (xy 456.34148 -382.108456) (xy 456.912726 -382.108456)
			(xy 456.927871 -382.081844) (xy 456.964216 -382.032565) (xy 457.006801 -381.988566) (xy 457.054869 -381.950634)
			(xy 457.107561 -381.919443) (xy 457.163939 -381.89555) (xy 457.222998 -381.87938) (xy 457.283684 -381.871223)
			(xy 457.3143 -381.870712) (xy 457.34427 -381.871161) (xy 457.403697 -381.878985) (xy 457.461594 -381.894499)
			(xy 457.516971 -381.917438) (xy 457.56888 -381.947408) (xy 457.616432 -381.983898) (xy 457.658815 -382.026283)
			(xy 457.695303 -382.073837) (xy 457.725271 -382.125747) (xy 457.748207 -382.181125) (xy 457.763719 -382.239023)
			(xy 457.77154 -382.29845) (xy 457.772008 -382.32842) (xy 457.771521 -382.359896) (xy 457.762911 -382.422255)
			(xy 457.749051 -382.471418) (xy 458.558882 -382.471418) (xy 458.558882 -382.411482) (xy 458.566705 -382.35206)
			(xy 458.582218 -382.294167) (xy 458.605154 -382.238794) (xy 458.635121 -382.186888) (xy 458.671608 -382.139338)
			(xy 458.713988 -382.096958) (xy 458.761538 -382.060471) (xy 458.813444 -382.030504) (xy 458.868817 -382.007568)
			(xy 458.92671 -381.992055) (xy 458.986132 -381.984232) (xy 459.046068 -381.984232) (xy 459.10549 -381.992055)
			(xy 459.163383 -382.007568) (xy 459.218756 -382.030504) (xy 459.270662 -382.060471) (xy 459.318212 -382.096958)
			(xy 459.360592 -382.139338) (xy 459.397079 -382.186888) (xy 459.427046 -382.238794) (xy 459.449982 -382.294167)
			(xy 459.465495 -382.35206) (xy 459.466362 -382.358646) (xy 459.737458 -382.358646) (xy 459.741529 -382.303024)
			(xy 459.753655 -382.248587) (xy 459.773578 -382.196496) (xy 459.800874 -382.147861) (xy 459.83496 -382.103718)
			(xy 459.875109 -382.065009) (xy 459.920467 -382.032558) (xy 459.970067 -382.007057) (xy 460.022851 -381.98905)
			(xy 460.077694 -381.97892) (xy 460.133428 -381.976883) (xy 460.188865 -381.982983) (xy 460.242822 -381.997089)
			(xy 460.294151 -382.018901) (xy 460.341757 -382.047955) (xy 460.384625 -382.08363) (xy 460.421842 -382.125167)
			(xy 460.452615 -382.17168) (xy 460.476287 -382.222177) (xy 460.492355 -382.275584) (xy 460.500475 -382.33076)
			(xy 460.500984 -382.358646) (xy 460.500475 -382.386532) (xy 460.492355 -382.441708) (xy 460.476287 -382.495115)
			(xy 460.452615 -382.545612) (xy 460.421842 -382.592125) (xy 460.384625 -382.633662) (xy 460.341757 -382.669337)
			(xy 460.294151 -382.698391) (xy 460.242822 -382.720203) (xy 460.188865 -382.734309) (xy 460.133428 -382.740409)
			(xy 460.077694 -382.738372) (xy 460.022851 -382.728242) (xy 459.970067 -382.710235) (xy 459.920467 -382.684734)
			(xy 459.875109 -382.652283) (xy 459.83496 -382.613574) (xy 459.800874 -382.569431) (xy 459.773578 -382.520796)
			(xy 459.753655 -382.468705) (xy 459.741529 -382.414268) (xy 459.737458 -382.358646) (xy 459.466362 -382.358646)
			(xy 459.473318 -382.411482) (xy 459.473808 -382.44145) (xy 459.473318 -382.471418) (xy 459.465495 -382.53084)
			(xy 459.449982 -382.588733) (xy 459.427046 -382.644106) (xy 459.397079 -382.696012) (xy 459.360592 -382.743562)
			(xy 459.318212 -382.785942) (xy 459.270662 -382.822429) (xy 459.218756 -382.852396) (xy 459.163383 -382.875332)
			(xy 459.10549 -382.890845) (xy 459.046068 -382.898668) (xy 458.986132 -382.898668) (xy 458.92671 -382.890845)
			(xy 458.868817 -382.875332) (xy 458.813444 -382.852396) (xy 458.761538 -382.822429) (xy 458.713988 -382.785942)
			(xy 458.671608 -382.743562) (xy 458.635121 -382.696012) (xy 458.605154 -382.644106) (xy 458.582218 -382.588733)
			(xy 458.566705 -382.53084) (xy 458.558882 -382.471418) (xy 457.749051 -382.471418) (xy 457.74583 -382.482844)
			(xy 457.720601 -382.540518) (xy 457.687699 -382.594186) (xy 457.647748 -382.642835) (xy 457.601502 -382.685544)
			(xy 457.549835 -382.721507) (xy 457.493724 -382.750044) (xy 457.434229 -382.770615) (xy 457.403454 -382.777238)
			(xy 457.382542 -382.794918) (xy 457.336586 -382.824696) (xy 457.28684 -382.847589) (xy 457.23433 -382.863126)
			(xy 457.180136 -382.870987) (xy 457.152756 -382.871472) (xy 456.122786 -382.871472) (xy 456.097047 -382.871004)
			(xy 456.046036 -382.864076) (xy 455.996421 -382.850349) (xy 455.949104 -382.830072) (xy 455.904945 -382.803613)
			(xy 455.864747 -382.771454) (xy 455.846688 -382.753108) (xy 455.66584 -382.753108) (xy 446.715896 -382.753108)
			(xy 446.715896 -387.281166) (xy 455.614786 -387.281166) (xy 455.615383 -387.247637) (xy 455.625214 -387.181301)
			(xy 455.644617 -387.11711) (xy 455.673176 -387.056436) (xy 455.69124 -387.028182) (xy 455.69124 -385.264914)
			(xy 455.691746 -385.234941) (xy 455.70107 -385.175724) (xy 455.719552 -385.118699) (xy 455.746736 -385.065271)
			(xy 455.781952 -385.01676) (xy 455.802746 -384.995166) (xy 457.416662 -383.38125) (xy 457.43828 -383.360488)
			(xy 457.4868 -383.325301) (xy 457.540224 -383.298134) (xy 457.597239 -383.279653) (xy 457.656442 -383.270314)
			(xy 457.68641 -383.269744) (xy 459.675738 -383.269744) (xy 459.688798 -383.269844) (xy 459.714856 -383.271623)
			(xy 459.727808 -383.2733) (xy 459.731364 -383.273808) (xy 459.813152 -383.273808) (xy 459.813152 -383.293874)
			(xy 459.841854 -383.307844) (xy 459.853604 -383.313624) (xy 459.876355 -383.326593) (xy 459.88732 -383.333752)
			(xy 460.285846 -383.333752) (xy 460.31023 -383.32029) (xy 460.338424 -383.306066) (xy 460.338424 -383.266696)
			(xy 460.350515 -383.2615) (xy 460.371748 -383.245971) (xy 460.388296 -383.225523) (xy 460.399057 -383.201519)
			(xy 460.403312 -383.17556) (xy 460.400778 -383.149377) (xy 460.39659 -383.136902) (xy 460.385535 -383.104878)
			(xy 460.373653 -383.038186) (xy 460.372968 -383.004314) (xy 460.373491 -382.977064) (xy 460.381245 -382.923119)
			(xy 460.396597 -382.870827) (xy 460.419235 -382.821251) (xy 460.448698 -382.775402) (xy 460.484385 -382.734212)
			(xy 460.525571 -382.69852) (xy 460.571418 -382.669053) (xy 460.620991 -382.646411) (xy 460.673282 -382.631053)
			(xy 460.727226 -382.623294) (xy 460.754476 -382.622806) (xy 460.776586 -382.623122) (xy 460.820511 -382.628213)
			(xy 460.842106 -382.632966) (xy 460.847948 -382.634236) (xy 461.231996 -382.634236) (xy 461.261076 -382.634774)
			(xy 461.318518 -382.643889) (xy 461.373826 -382.661879) (xy 461.425639 -382.688302) (xy 461.472679 -382.722505)
			(xy 461.493616 -382.742694) (xy 461.843628 -383.09296) (xy 461.859122 -383.095754) (xy 461.888635 -383.101828)
			(xy 461.945817 -383.120831) (xy 462.000011 -383.147173) (xy 462.050281 -383.180397) (xy 462.095758 -383.219929)
			(xy 462.135655 -383.265085) (xy 462.169283 -383.315085) (xy 462.196061 -383.369066) (xy 462.215525 -383.426092)
			(xy 462.22734 -383.48518) (xy 462.2313 -383.545306) (xy 462.227338 -383.605433) (xy 462.215522 -383.66452)
			(xy 462.196056 -383.721546) (xy 462.169277 -383.775526) (xy 462.135647 -383.825525) (xy 462.095749 -383.870681)
			(xy 462.050271 -383.910211) (xy 462 -383.943434) (xy 461.945805 -383.969773) (xy 461.888622 -383.988776)
			(xy 461.859122 -383.994914) (xy 461.843628 -383.997708) (xy 461.615536 -384.226054) (xy 461.594586 -384.246229)
			(xy 461.547554 -384.280443) (xy 461.495745 -384.30687) (xy 461.440438 -384.32486) (xy 461.382996 -384.333969)
			(xy 461.353916 -384.334512) (xy 460.789274 -384.334512) (xy 460.760195 -384.333944) (xy 460.702754 -384.324839)
			(xy 460.647445 -384.306856) (xy 460.595632 -384.28044) (xy 460.548592 -384.246241) (xy 460.527654 -384.226054)
			(xy 460.270098 -383.968244) (xy 459.88732 -383.968244) (xy 459.876353 -383.975398) (xy 459.8536 -383.988364)
			(xy 459.841854 -383.994152) (xy 459.813152 -384.008122) (xy 459.813152 -384.028188) (xy 459.731364 -384.028188)
			(xy 459.727808 -384.028696) (xy 459.714854 -384.030357) (xy 459.688797 -384.032138) (xy 459.675738 -384.032252)
			(xy 457.844398 -384.032252) (xy 456.453748 -385.422902) (xy 456.453748 -387.028182) (xy 456.471809 -387.056438)
			(xy 456.500373 -387.11711) (xy 456.519775 -387.181301) (xy 456.529598 -387.247637) (xy 456.530202 -387.281166)
			(xy 456.529712 -387.311134) (xy 456.521889 -387.370556) (xy 456.506376 -387.428449) (xy 456.48344 -387.483822)
			(xy 456.453473 -387.535728) (xy 456.416986 -387.583278) (xy 456.374606 -387.625658) (xy 456.327056 -387.662145)
			(xy 456.27515 -387.692112) (xy 456.219777 -387.715048) (xy 456.161884 -387.730561) (xy 456.102462 -387.738384)
			(xy 456.042526 -387.738384) (xy 455.983104 -387.730561) (xy 455.925211 -387.715048) (xy 455.869838 -387.692112)
			(xy 455.817932 -387.662145) (xy 455.770382 -387.625658) (xy 455.728002 -387.583278) (xy 455.691515 -387.535728)
			(xy 455.661548 -387.483822) (xy 455.638612 -387.428449) (xy 455.623099 -387.370556) (xy 455.615276 -387.311134)
			(xy 455.614786 -387.281166) (xy 446.715896 -387.281166) (xy 446.715896 -390.926066) (xy 446.715495 -390.950065)
			(xy 446.708017 -390.997475) (xy 446.693195 -391.043126) (xy 446.671396 -391.085886) (xy 446.643158 -391.124697)
			(xy 446.626488 -391.141966) (xy 446.127378 -391.641076) (xy 446.127378 -391.64133) (xy 446.110098 -391.657995)
			(xy 446.071284 -391.686244) (xy 446.02853 -391.708074) (xy 445.982887 -391.722948) (xy 445.93548 -391.7305)
			(xy 445.911478 -391.730992) (xy 438.10301 -391.730992) (xy 438.079005 -391.730539) (xy 438.031591 -391.722993)
			(xy 437.985943 -391.708116) (xy 437.943188 -391.686275) (xy 437.904379 -391.65801) (xy 437.88711 -391.64133)
			(xy 437.88711 -391.641076) (xy 437.388 -391.141966) (xy 437.371392 -391.124648) (xy 437.343204 -391.085823)
			(xy 437.321426 -391.04307) (xy 437.306595 -390.997441) (xy 437.299074 -390.950055) (xy 437.298592 -390.926066)
			(xy 432.645058 -390.926066) (xy 432.645058 -391.094468) (xy 432.645509 -391.107935) (xy 432.652627 -391.133914)
			(xy 432.666297 -391.157124) (xy 432.685564 -391.175948) (xy 432.709086 -391.189072) (xy 432.735224 -391.195584)
			(xy 432.762155 -391.195027) (xy 432.788001 -391.187442) (xy 432.799744 -391.180828) (xy 432.822391 -391.167439)
			(xy 432.870583 -391.146333) (xy 432.921218 -391.132052) (xy 432.973336 -391.124866) (xy 432.999642 -391.12444)
			(xy 433.026888 -391.124929) (xy 433.080824 -391.132689) (xy 433.133107 -391.148046) (xy 433.182673 -391.170687)
			(xy 433.228512 -391.200151) (xy 433.269692 -391.235838) (xy 433.305375 -391.277021) (xy 433.334833 -391.322864)
			(xy 433.357468 -391.372432) (xy 433.37282 -391.424717) (xy 433.380574 -391.478654) (xy 433.380574 -391.533146)
			(xy 433.37282 -391.587083) (xy 433.357468 -391.639368) (xy 433.334833 -391.688936) (xy 433.305375 -391.734779)
			(xy 433.269692 -391.775962) (xy 433.228512 -391.811649) (xy 433.182673 -391.841113) (xy 433.133107 -391.863754)
			(xy 433.080824 -391.879111) (xy 433.026888 -391.886871) (xy 432.999642 -391.887456) (xy 432.973336 -391.887032)
			(xy 432.921219 -391.879841) (xy 432.870583 -391.865561) (xy 432.822388 -391.844463) (xy 432.799744 -391.831068)
			(xy 432.788042 -391.824389) (xy 432.762191 -391.816824) (xy 432.735261 -391.816284) (xy 432.709128 -391.822809)
			(xy 432.685612 -391.835943) (xy 432.666351 -391.854772) (xy 432.652686 -391.877983) (xy 432.64557 -391.903962)
			(xy 432.645058 -391.917428) (xy 432.645058 -393.671044) (xy 432.660044 -393.68603) (xy 434.98516 -396.011146)
			(xy 465.301584 -396.011146)
		)
		(stroke
			(width 0)
			(type solid)
		)
		(fill yes)
		(layer "B.Cu")
		(net "GND")
	)
	(gr_poly
		(pts
			(arc
				(start 116.422932 -217.35796)
				(mid 116.509298 -217.309871)
				(end 116.513864 -217.211148)
			)
			(arc
				(start 116.513864 -217.211148)
				(mid 116.488107 -217.139741)
				(end 116.47932 -217.064336)
			)
			(arc
				(start 116.47932 -217.064336)
				(mid 116.809012 -216.734644)
				(end 117.138704 -217.064336)
			)
			(arc
				(start 117.138704 -217.064336)
				(mid 117.133996 -217.119346)
				(end 117.120162 -217.172794)
			)
			(xy 117.112542 -217.194892) (xy 117.206776 -217.35796) (xy 117.817138 -217.35796) (xy 117.98808 -217.187018)
			(xy 117.98808 -216.586816) (xy 117.43182 -216.030556) (xy 116.445792 -216.030556) (xy 116.167662 -215.752426)
			(arc
				(start 116.167662 -215.725502)
				(mid 116.138114 -215.679361)
				(end 116.083842 -215.686894)
			)
			(arc
				(start 116.083842 -215.686894)
				(mid 115.983654 -215.745887)
				(end 115.869212 -215.766396)
			)
			(arc
				(start 115.869212 -215.766396)
				(mid 115.636085 -215.669831)
				(end 115.53952 -215.436704)
			)
			(arc
				(start 115.53952 -215.436704)
				(mid 115.615277 -215.226433)
				(end 115.807744 -215.112854)
			)
			(xy 115.830604 -215.108536) (xy 116.035582 -214.753444)
			(arc
				(start 116.027708 -214.7316)
				(mid 116.013969 -214.677889)
				(end 116.00942 -214.622634)
			)
			(arc
				(start 116.00942 -214.622634)
				(mid 116.10591 -214.389686)
				(end 116.338858 -214.293196)
			)
			(xy 116.36248 -214.293958) (xy 116.385848 -214.295482)
			(arc
				(start 116.574062 -214.107268)
				(mid 116.603836 -214.035745)
				(end 116.57457 -213.964012)
			)
			(arc
				(start 116.57457 -213.964012)
				(mid 116.504408 -213.85765)
				(end 116.479828 -213.732618)
			)
			(arc
				(start 116.479828 -213.732618)
				(mid 116.576318 -213.49967)
				(end 116.809266 -213.40318)
			)
			(arc
				(start 116.809266 -213.40318)
				(mid 116.93431 -213.42773)
				(end 117.04066 -213.497922)
			)
			(arc
				(start 117.04066 -213.497922)
				(mid 117.112393 -213.52719)
				(end 117.183916 -213.497414)
			)
			(xy 117.912388 -212.768942) (xy 117.912388 -209.396838) (xy 118.405656 -208.90357) (xy 121.159016 -208.90357)
			(xy 121.628662 -209.373216) (xy 121.628662 -213.249256) (xy 121.268236 -213.609682) (xy 121.268236 -213.811866)
			(xy 121.565416 -214.109046)
			(arc
				(start 122.115834 -214.109046)
				(mid 122.207773 -214.050687)
				(end 122.194066 -213.942676)
			)
			(arc
				(start 122.194066 -213.942676)
				(mid 122.138013 -213.844231)
				(end 122.118628 -213.732618)
			)
			(arc
				(start 122.118628 -213.732618)
				(mid 122.448066 -213.40318)
				(end 122.777504 -213.732618)
			)
			(arc
				(start 122.777504 -213.732618)
				(mid 122.770431 -213.801026)
				(end 122.74931 -213.866476)
			)
			(xy 122.739404 -213.888828) (xy 122.855482 -214.109046)
			(arc
				(start 123.99518 -214.109046)
				(mid 124.087119 -214.050687)
				(end 124.073412 -213.942676)
			)
			(arc
				(start 124.073412 -213.942676)
				(mid 124.017283 -213.844243)
				(end 123.99772 -213.732618)
			)
			(arc
				(start 123.99772 -213.732618)
				(mid 124.327412 -213.402926)
				(end 124.657104 -213.732618)
			)
			(arc
				(start 124.657104 -213.732618)
				(mid 124.649068 -213.804992)
				(end 124.625354 -213.873842)
			)
			(xy 124.614432 -213.896448) (xy 124.724668 -214.109046) (xy 125.74778 -214.109046) (xy 125.910086 -213.94674)
			(xy 125.910086 -213.876128)
			(arc
				(start 125.905768 -213.866222)
				(mid 125.884572 -213.800907)
				(end 125.87732 -213.732618)
			)
			(arc
				(start 125.87732 -213.732618)
				(mid 125.884526 -213.664319)
				(end 125.905768 -213.599014)
			)
			(xy 125.910086 -213.589108) (xy 125.910086 -199.66178) (xy 125.353826 -199.10552) (xy 108.709206 -199.10552)
			(xy 108.187998 -199.626728) (xy 108.187998 -212.723984) (xy 107.7849 -213.127082) (xy 104.84104 -213.127082)
			(xy 104.40416 -212.690202) (xy 104.40416 -212.511132) (xy 104.396032 -212.503258) (xy 104.396032 -209.580988)
			(xy 104.293416 -209.478118) (xy 101.650546 -209.478118) (xy 101.53269 -209.59572) (xy 101.53269 -212.593682)
			(xy 100.534216 -213.592156)
			(arc
				(start 100.534216 -214.341456)
				(mid 100.649667 -214.461489)
				(end 100.691696 -214.622634)
			)
			(arc
				(start 100.691696 -214.622634)
				(mid 100.685264 -214.687923)
				(end 100.666042 -214.75065)
			)
			(xy 100.65258 -214.782146) (xy 100.798376 -214.927942) (xy 100.897944 -214.927942) (xy 100.998782 -214.753444)
			(arc
				(start 100.990908 -214.7316)
				(mid 100.977169 -214.677889)
				(end 100.97262 -214.622634)
			)
			(arc
				(start 100.97262 -214.622634)
				(mid 101.302058 -214.293196)
				(end 101.631496 -214.622634)
			)
			(arc
				(start 101.631496 -214.622634)
				(mid 101.621698 -214.70289)
				(end 101.592634 -214.778336)
			)
			(arc
				(start 101.592634 -214.778336)
				(mid 101.59495 -214.878432)
				(end 101.682042 -214.927942)
			)
			(arc
				(start 101.861874 -214.927942)
				(mid 101.949068 -214.878493)
				(end 101.951282 -214.778336)
			)
			(arc
				(start 101.951282 -214.778336)
				(mid 101.922233 -214.702887)
				(end 101.91242 -214.622634)
			)
			(arc
				(start 101.91242 -214.622634)
				(mid 101.919493 -214.554226)
				(end 101.940614 -214.488776)
			)
			(xy 101.95052 -214.466424) (xy 101.736906 -214.061294)
			(arc
				(start 101.712776 -214.056722)
				(mid 101.519348 -213.943425)
				(end 101.443028 -213.732618)
			)
			(arc
				(start 101.443028 -213.732618)
				(mid 101.772466 -213.40318)
				(end 102.101904 -213.732618)
			)
			(arc
				(start 102.101904 -213.732618)
				(mid 102.094831 -213.801026)
				(end 102.07371 -213.866476)
			)
			(xy 102.063804 -213.888828) (xy 102.277418 -214.293958)
			(arc
				(start 102.301548 -214.29853)
				(mid 102.494976 -214.411827)
				(end 102.571296 -214.622634)
			)
			(arc
				(start 102.571296 -214.622634)
				(mid 102.561498 -214.70289)
				(end 102.532434 -214.778336)
			)
			(arc
				(start 102.532434 -214.778336)
				(mid 102.53475 -214.878432)
				(end 102.621842 -214.927942)
			)
			(xy 102.777544 -214.927942) (xy 102.878382 -214.753444)
			(arc
				(start 102.870508 -214.7316)
				(mid 102.856769 -214.677889)
				(end 102.85222 -214.622634)
			)
			(arc
				(start 102.85222 -214.622634)
				(mid 103.181658 -214.293196)
				(end 103.511096 -214.622634)
			)
			(arc
				(start 103.511096 -214.622634)
				(mid 103.501298 -214.70289)
				(end 103.472234 -214.778336)
			)
			(arc
				(start 103.472234 -214.778336)
				(mid 103.47455 -214.878432)
				(end 103.561642 -214.927942)
			)
			(arc
				(start 103.741474 -214.927942)
				(mid 103.828668 -214.878493)
				(end 103.830882 -214.778336)
			)
			(arc
				(start 103.830882 -214.778336)
				(mid 103.801833 -214.702887)
				(end 103.79202 -214.622634)
			)
			(arc
				(start 103.79202 -214.622634)
				(mid 103.799093 -214.554226)
				(end 103.820214 -214.488776)
			)
			(xy 103.83012 -214.466424) (xy 103.616506 -214.061294)
			(arc
				(start 103.592376 -214.056722)
				(mid 103.398948 -213.943425)
				(end 103.322628 -213.732618)
			)
			(arc
				(start 103.322628 -213.732618)
				(mid 103.652066 -213.40318)
				(end 103.981504 -213.732618)
			)
			(arc
				(start 103.981504 -213.732618)
				(mid 103.974431 -213.801026)
				(end 103.95331 -213.866476)
			)
			(xy 103.943404 -213.888828) (xy 104.157018 -214.293958)
			(arc
				(start 104.181148 -214.29853)
				(mid 104.374576 -214.411827)
				(end 104.450896 -214.622634)
			)
			(arc
				(start 104.450896 -214.622634)
				(mid 104.441098 -214.70289)
				(end 104.412034 -214.778336)
			)
			(arc
				(start 104.412034 -214.778336)
				(mid 104.41435 -214.878432)
				(end 104.501442 -214.927942)
			)
			(xy 104.657144 -214.927942) (xy 104.757982 -214.753444)
			(arc
				(start 104.750108 -214.7316)
				(mid 104.736369 -214.677889)
				(end 104.73182 -214.622634)
			)
			(arc
				(start 104.73182 -214.622634)
				(mid 105.061258 -214.293196)
				(end 105.390696 -214.622634)
			)
			(arc
				(start 105.390696 -214.622634)
				(mid 105.380898 -214.70289)
				(end 105.351834 -214.778336)
			)
			(arc
				(start 105.351834 -214.778336)
				(mid 105.35415 -214.878432)
				(end 105.441242 -214.927942)
			)
			(arc
				(start 105.621074 -214.927942)
				(mid 105.708268 -214.878493)
				(end 105.710482 -214.778336)
			)
			(arc
				(start 105.710482 -214.778336)
				(mid 105.681433 -214.702887)
				(end 105.67162 -214.622634)
			)
			(arc
				(start 105.67162 -214.622634)
				(mid 105.678693 -214.554226)
				(end 105.699814 -214.488776)
			)
			(xy 105.70972 -214.466424) (xy 105.496106 -214.061294)
			(arc
				(start 105.471976 -214.056722)
				(mid 105.278548 -213.943425)
				(end 105.202228 -213.732618)
			)
			(arc
				(start 105.202228 -213.732618)
				(mid 105.531666 -213.40318)
				(end 105.861104 -213.732618)
			)
			(arc
				(start 105.861104 -213.732618)
				(mid 105.854031 -213.801026)
				(end 105.83291 -213.866476)
			)
			(xy 105.823004 -213.888828) (xy 106.036618 -214.293958)
			(arc
				(start 106.060748 -214.29853)
				(mid 106.254176 -214.411827)
				(end 106.330496 -214.622634)
			)
			(arc
				(start 106.330496 -214.622634)
				(mid 106.320698 -214.70289)
				(end 106.291634 -214.778336)
			)
			(arc
				(start 106.291634 -214.778336)
				(mid 106.29395 -214.878432)
				(end 106.381042 -214.927942)
			)
			(xy 106.536744 -214.927942) (xy 106.637582 -214.753444)
			(arc
				(start 106.629708 -214.7316)
				(mid 106.615969 -214.677889)
				(end 106.61142 -214.622634)
			)
			(arc
				(start 106.61142 -214.622634)
				(mid 106.940858 -214.293196)
				(end 107.270296 -214.622634)
			)
			(arc
				(start 107.270296 -214.622634)
				(mid 107.260498 -214.70289)
				(end 107.231434 -214.778336)
			)
			(arc
				(start 107.231434 -214.778336)
				(mid 107.23375 -214.878432)
				(end 107.320842 -214.927942)
			)
			(arc
				(start 107.500674 -214.927942)
				(mid 107.587868 -214.878493)
				(end 107.590082 -214.778336)
			)
			(arc
				(start 107.590082 -214.778336)
				(mid 107.561033 -214.702887)
				(end 107.55122 -214.622634)
			)
			(arc
				(start 107.55122 -214.622634)
				(mid 107.558293 -214.554226)
				(end 107.579414 -214.488776)
			)
			(xy 107.58932 -214.466424) (xy 107.375706 -214.061294)
			(arc
				(start 107.351576 -214.056722)
				(mid 107.158148 -213.943425)
				(end 107.081828 -213.732618)
			)
			(arc
				(start 107.081828 -213.732618)
				(mid 107.411266 -213.40318)
				(end 107.740704 -213.732618)
			)
			(arc
				(start 107.740704 -213.732618)
				(mid 107.733631 -213.801026)
				(end 107.71251 -213.866476)
			)
			(xy 107.702604 -213.888828) (xy 107.916218 -214.293958)
			(arc
				(start 107.940348 -214.29853)
				(mid 108.133776 -214.411827)
				(end 108.210096 -214.622634)
			)
			(arc
				(start 108.210096 -214.622634)
				(mid 108.200298 -214.70289)
				(end 108.171234 -214.778336)
			)
			(arc
				(start 108.171234 -214.778336)
				(mid 108.17355 -214.878432)
				(end 108.260642 -214.927942)
			)
			(xy 108.416344 -214.927942) (xy 108.517182 -214.753444)
			(arc
				(start 108.509308 -214.7316)
				(mid 108.495569 -214.677889)
				(end 108.49102 -214.622634)
			)
			(arc
				(start 108.49102 -214.622634)
				(mid 108.820458 -214.293196)
				(end 109.149896 -214.622634)
			)
			(arc
				(start 109.149896 -214.622634)
				(mid 109.140098 -214.70289)
				(end 109.111034 -214.778336)
			)
			(arc
				(start 109.111034 -214.778336)
				(mid 109.11335 -214.878432)
				(end 109.200442 -214.927942)
			)
			(xy 110.080044 -214.927942) (xy 110.271306 -214.73668) (xy 110.271306 -214.266018) (xy 111.040164 -213.49716)
			(xy 111.040164 -209.56524) (xy 111.774224 -208.83118) (xy 114.290856 -208.83118) (xy 114.96675 -209.507074)
			(xy 114.96675 -213.402672)
			(arc
				(start 115.005866 -213.41207)
				(mid 115.188185 -213.52835)
				(end 115.259104 -213.732618)
			)
			(arc
				(start 115.259104 -213.732618)
				(mid 115.252031 -213.801026)
				(end 115.23091 -213.866476)
			)
			(xy 115.221004 -213.888828) (xy 115.434618 -214.293958)
			(arc
				(start 115.458748 -214.29853)
				(mid 115.652176 -214.411827)
				(end 115.728496 -214.622634)
			)
			(arc
				(start 115.728496 -214.622634)
				(mid 115.399058 -214.952072)
				(end 115.06962 -214.622634)
			)
			(arc
				(start 115.06962 -214.622634)
				(mid 115.076693 -214.554226)
				(end 115.097814 -214.488776)
			)
			(xy 115.10772 -214.466424)
			(arc
				(start 115.091718 -214.43569)
				(mid 115.016969 -214.382635)
				(end 114.92992 -214.411306)
			)
			(xy 114.783616 -214.55761)
			(arc
				(start 114.786664 -214.582248)
				(mid 114.788557 -214.602402)
				(end 114.789204 -214.622634)
			)
			(arc
				(start 114.789204 -214.622634)
				(mid 114.742161 -214.792289)
				(end 114.614452 -214.913464)
			)
			(xy 114.587528 -214.927942) (xy 114.587528 -215.943942)
			(arc
				(start 114.614452 -215.958166)
				(mid 114.743105 -216.079881)
				(end 114.790474 -216.25052)
			)
			(arc
				(start 114.790474 -216.25052)
				(mid 114.779314 -216.335707)
				(end 114.746532 -216.415112)
			)
			(xy 114.727228 -216.44864) (xy 115.028472 -216.749884)
			(arc
				(start 115.03914 -216.753694)
				(mid 115.16237 -216.831378)
				(end 115.240054 -216.954608)
			)
			(xy 115.243864 -216.965276) (xy 115.636548 -217.35796)
		)
		(stroke
			(width 0)
			(type solid)
		)
		(fill yes)
		(layer "B.Cu")
		(net "GND")
	)
	(gr_poly
		(pts
			(arc
				(start 99.892612 -218.793314)
				(mid 99.918782 -218.789936)
				(end 99.943158 -218.779852)
			)
			(arc
				(start 99.943158 -218.779852)
				(mid 100.140885 -218.697158)
				(end 100.353114 -218.66733)
			)
			(arc
				(start 100.353114 -218.66733)
				(mid 100.424139 -218.637127)
				(end 100.453444 -218.56573)
			)
			(xy 100.453444 -218.430348) (xy 100.324158 -218.206574)
			(arc
				(start 100.301298 -218.202256)
				(mid 100.109015 -218.088573)
				(end 100.033328 -217.878406)
			)
			(arc
				(start 100.033328 -217.878406)
				(mid 100.070053 -217.726995)
				(end 100.172266 -217.60942)
			)
			(arc
				(start 100.172266 -217.60942)
				(mid 100.214715 -217.535178)
				(end 100.185474 -217.454734)
			)
			(xy 100.073206 -217.342466)
			(arc
				(start 100.04044 -217.358976)
				(mid 99.998276 -217.376587)
				(end 99.95408 -217.388186)
			)
			(xy 99.93122 -217.392504) (xy 99.726242 -217.747596)
			(arc
				(start 99.734116 -217.76944)
				(mid 99.747855 -217.823151)
				(end 99.752404 -217.878406)
			)
			(arc
				(start 99.752404 -217.878406)
				(mid 99.422966 -218.207844)
				(end 99.093528 -217.878406)
			)
			(arc
				(start 99.093528 -217.878406)
				(mid 99.169205 -217.668231)
				(end 99.361498 -217.554556)
			)
			(xy 99.384358 -217.550238)
			(arc
				(start 99.465892 -217.409014)
				(mid 99.465931 -217.307482)
				(end 99.378008 -217.256614)
			)
			(arc
				(start 99.252786 -217.256614)
				(mid 98.953066 -217.42043)
				(end 98.653346 -217.256614)
			)
			(arc
				(start 98.280728 -217.256614)
				(mid 98.190258 -217.342232)
				(end 98.07448 -217.388186)
			)
			(xy 98.05162 -217.392504) (xy 97.846642 -217.747596)
			(arc
				(start 97.854516 -217.76944)
				(mid 97.868255 -217.823151)
				(end 97.872804 -217.878406)
			)
			(arc
				(start 97.872804 -217.878406)
				(mid 97.543366 -218.207844)
				(end 97.213928 -217.878406)
			)
			(arc
				(start 97.213928 -217.878406)
				(mid 97.289605 -217.668231)
				(end 97.481898 -217.554556)
			)
			(xy 97.504758 -217.550238)
			(arc
				(start 97.586292 -217.409014)
				(mid 97.586331 -217.307482)
				(end 97.498408 -217.256614)
			)
			(arc
				(start 97.373186 -217.256614)
				(mid 97.073466 -217.42043)
				(end 96.773746 -217.256614)
			)
			(arc
				(start 96.401128 -217.256614)
				(mid 96.310658 -217.342232)
				(end 96.19488 -217.388186)
			)
			(xy 96.17202 -217.392504) (xy 95.967042 -217.747596)
			(arc
				(start 95.974916 -217.76944)
				(mid 95.988655 -217.823151)
				(end 95.993204 -217.878406)
			)
			(arc
				(start 95.993204 -217.878406)
				(mid 95.663766 -218.207844)
				(end 95.334328 -217.878406)
			)
			(arc
				(start 95.334328 -217.878406)
				(mid 95.410005 -217.668231)
				(end 95.602298 -217.554556)
			)
			(xy 95.625158 -217.550238)
			(arc
				(start 95.706692 -217.409014)
				(mid 95.706731 -217.307482)
				(end 95.618808 -217.256614)
			)
			(arc
				(start 95.493586 -217.256614)
				(mid 95.193866 -217.42043)
				(end 94.894146 -217.256614)
			)
			(arc
				(start 94.521528 -217.256614)
				(mid 94.431058 -217.342232)
				(end 94.31528 -217.388186)
			)
			(xy 94.29242 -217.392504) (xy 94.087442 -217.747596)
			(arc
				(start 94.095316 -217.76944)
				(mid 94.109055 -217.823151)
				(end 94.113604 -217.878406)
			)
			(arc
				(start 94.113604 -217.878406)
				(mid 93.784166 -218.207844)
				(end 93.454728 -217.878406)
			)
			(arc
				(start 93.454728 -217.878406)
				(mid 93.530405 -217.668231)
				(end 93.722698 -217.554556)
			)
			(xy 93.745558 -217.550238)
			(arc
				(start 93.827092 -217.409014)
				(mid 93.827131 -217.307482)
				(end 93.739208 -217.256614)
			)
			(arc
				(start 93.613986 -217.256614)
				(mid 93.314266 -217.42043)
				(end 93.014546 -217.256614)
			)
			(arc
				(start 92.641928 -217.256614)
				(mid 92.551458 -217.342232)
				(end 92.43568 -217.388186)
			)
			(xy 92.41282 -217.392504) (xy 92.207842 -217.747596)
			(arc
				(start 92.215716 -217.76944)
				(mid 92.229455 -217.823151)
				(end 92.234004 -217.878406)
			)
			(arc
				(start 92.234004 -217.878406)
				(mid 91.904566 -218.207844)
				(end 91.575128 -217.878406)
			)
			(arc
				(start 91.575128 -217.878406)
				(mid 91.650805 -217.668231)
				(end 91.843098 -217.554556)
			)
			(xy 91.865958 -217.550238)
			(arc
				(start 91.947492 -217.409014)
				(mid 91.947531 -217.307482)
				(end 91.859608 -217.256614)
			)
			(arc
				(start 91.734386 -217.256614)
				(mid 91.434666 -217.42043)
				(end 91.134946 -217.256614)
			)
			(arc
				(start 90.762328 -217.256614)
				(mid 90.671858 -217.342232)
				(end 90.55608 -217.388186)
			)
			(xy 90.53322 -217.392504) (xy 90.328242 -217.747596)
			(arc
				(start 90.336116 -217.76944)
				(mid 90.349855 -217.823151)
				(end 90.354404 -217.878406)
			)
			(arc
				(start 90.354404 -217.878406)
				(mid 90.024966 -218.207844)
				(end 89.695528 -217.878406)
			)
			(arc
				(start 89.695528 -217.878406)
				(mid 89.771205 -217.668231)
				(end 89.963498 -217.554556)
			)
			(xy 89.986358 -217.550238)
			(arc
				(start 90.067892 -217.409014)
				(mid 90.067931 -217.307482)
				(end 89.980008 -217.256614)
			)
			(arc
				(start 89.854786 -217.256614)
				(mid 89.75238 -217.360765)
				(end 89.616788 -217.41511)
			)
			(xy 89.60104 -217.417904) (xy 89.346024 -217.67292)
			(arc
				(start 89.366598 -217.70721)
				(mid 89.402383 -217.789505)
				(end 89.414604 -217.878406)
			)
			(arc
				(start 89.414604 -217.878406)
				(mid 89.410045 -217.933534)
				(end 89.396316 -217.987118)
			)
			(xy 89.388442 -218.009216) (xy 89.59342 -218.364054)
			(arc
				(start 89.61628 -218.368372)
				(mid 89.787985 -218.459225)
				(end 89.878662 -218.631008)
			)
			(arc
				(start 89.878662 -218.631008)
				(mid 89.898295 -218.662447)
				(end 89.934034 -218.672156)
			)
			(arc
				(start 89.934034 -218.672156)
				(mid 90.185206 -218.68266)
				(end 90.421968 -218.767152)
			)
			(xy 90.430858 -218.771978)
			(arc
				(start 90.444574 -218.780106)
				(mid 90.468735 -218.78996)
				(end 90.494612 -218.793314)
			)
			(arc
				(start 90.494612 -218.793314)
				(mid 90.520782 -218.789936)
				(end 90.545158 -218.779852)
			)
			(arc
				(start 90.545158 -218.779852)
				(mid 90.791597 -218.685411)
				(end 91.05519 -218.672156)
			)
			(arc
				(start 91.05519 -218.672156)
				(mid 91.090878 -218.662378)
				(end 91.110562 -218.631008)
			)
			(arc
				(start 91.110562 -218.631008)
				(mid 91.11603 -218.607023)
				(end 91.123262 -218.58351)
			)
			(xy 91.131136 -218.561412) (xy 90.926158 -218.206574)
			(arc
				(start 90.903298 -218.202256)
				(mid 90.711015 -218.088573)
				(end 90.635328 -217.878406)
			)
			(arc
				(start 90.635328 -217.878406)
				(mid 90.964766 -217.548968)
				(end 91.294204 -217.878406)
			)
			(arc
				(start 91.294204 -217.878406)
				(mid 91.289645 -217.933534)
				(end 91.275916 -217.987118)
			)
			(xy 91.268042 -218.009216) (xy 91.47302 -218.364054)
			(arc
				(start 91.49588 -218.368372)
				(mid 91.667585 -218.459225)
				(end 91.758262 -218.631008)
			)
			(arc
				(start 91.758262 -218.631008)
				(mid 91.777895 -218.662447)
				(end 91.813634 -218.672156)
			)
			(arc
				(start 91.813634 -218.672156)
				(mid 92.064806 -218.68266)
				(end 92.301568 -218.767152)
			)
			(xy 92.310458 -218.771978)
			(arc
				(start 92.324174 -218.780106)
				(mid 92.348335 -218.78996)
				(end 92.374212 -218.793314)
			)
			(arc
				(start 92.374212 -218.793314)
				(mid 92.400382 -218.789936)
				(end 92.424758 -218.779852)
			)
			(arc
				(start 92.424758 -218.779852)
				(mid 92.671197 -218.685411)
				(end 92.93479 -218.672156)
			)
			(arc
				(start 92.93479 -218.672156)
				(mid 92.970478 -218.662378)
				(end 92.990162 -218.631008)
			)
			(arc
				(start 92.990162 -218.631008)
				(mid 92.99563 -218.607023)
				(end 93.002862 -218.58351)
			)
			(xy 93.010736 -218.561412) (xy 92.805758 -218.206574)
			(arc
				(start 92.782898 -218.202256)
				(mid 92.590615 -218.088573)
				(end 92.514928 -217.878406)
			)
			(arc
				(start 92.514928 -217.878406)
				(mid 92.844366 -217.548968)
				(end 93.173804 -217.878406)
			)
			(arc
				(start 93.173804 -217.878406)
				(mid 93.169245 -217.933534)
				(end 93.155516 -217.987118)
			)
			(xy 93.147642 -218.009216) (xy 93.35262 -218.364054)
			(arc
				(start 93.37548 -218.368372)
				(mid 93.547185 -218.459225)
				(end 93.637862 -218.631008)
			)
			(arc
				(start 93.637862 -218.631008)
				(mid 93.657495 -218.662447)
				(end 93.693234 -218.672156)
			)
			(arc
				(start 93.693234 -218.672156)
				(mid 93.944406 -218.68266)
				(end 94.181168 -218.767152)
			)
			(xy 94.190058 -218.771978)
			(arc
				(start 94.203774 -218.780106)
				(mid 94.227935 -218.78996)
				(end 94.253812 -218.793314)
			)
			(arc
				(start 94.253812 -218.793314)
				(mid 94.279982 -218.789936)
				(end 94.304358 -218.779852)
			)
			(arc
				(start 94.304358 -218.779852)
				(mid 94.550797 -218.685411)
				(end 94.81439 -218.672156)
			)
			(arc
				(start 94.81439 -218.672156)
				(mid 94.850078 -218.662378)
				(end 94.869762 -218.631008)
			)
			(arc
				(start 94.869762 -218.631008)
				(mid 94.87523 -218.607023)
				(end 94.882462 -218.58351)
			)
			(xy 94.890336 -218.561412) (xy 94.685358 -218.206574)
			(arc
				(start 94.662498 -218.202256)
				(mid 94.470215 -218.088573)
				(end 94.394528 -217.878406)
			)
			(arc
				(start 94.394528 -217.878406)
				(mid 94.723966 -217.548968)
				(end 95.053404 -217.878406)
			)
			(arc
				(start 95.053404 -217.878406)
				(mid 95.048845 -217.933534)
				(end 95.035116 -217.987118)
			)
			(xy 95.027242 -218.009216) (xy 95.23222 -218.364054)
			(arc
				(start 95.25508 -218.368372)
				(mid 95.426785 -218.459225)
				(end 95.517462 -218.631008)
			)
			(arc
				(start 95.517462 -218.631008)
				(mid 95.537095 -218.662447)
				(end 95.572834 -218.672156)
			)
			(arc
				(start 95.572834 -218.672156)
				(mid 95.824006 -218.68266)
				(end 96.060768 -218.767152)
			)
			(xy 96.069658 -218.771978)
			(arc
				(start 96.083374 -218.780106)
				(mid 96.107535 -218.78996)
				(end 96.133412 -218.793314)
			)
			(arc
				(start 96.133412 -218.793314)
				(mid 96.159582 -218.789936)
				(end 96.183958 -218.779852)
			)
			(arc
				(start 96.183958 -218.779852)
				(mid 96.430397 -218.685411)
				(end 96.69399 -218.672156)
			)
			(arc
				(start 96.69399 -218.672156)
				(mid 96.729678 -218.662378)
				(end 96.749362 -218.631008)
			)
			(arc
				(start 96.749362 -218.631008)
				(mid 96.75483 -218.607023)
				(end 96.762062 -218.58351)
			)
			(xy 96.769936 -218.561412) (xy 96.564958 -218.206574)
			(arc
				(start 96.542098 -218.202256)
				(mid 96.349815 -218.088573)
				(end 96.274128 -217.878406)
			)
			(arc
				(start 96.274128 -217.878406)
				(mid 96.603566 -217.548968)
				(end 96.933004 -217.878406)
			)
			(arc
				(start 96.933004 -217.878406)
				(mid 96.928445 -217.933534)
				(end 96.914716 -217.987118)
			)
			(xy 96.906842 -218.009216) (xy 97.11182 -218.364054)
			(arc
				(start 97.13468 -218.368372)
				(mid 97.306385 -218.459225)
				(end 97.397062 -218.631008)
			)
			(arc
				(start 97.397062 -218.631008)
				(mid 97.416695 -218.662447)
				(end 97.452434 -218.672156)
			)
			(arc
				(start 97.452434 -218.672156)
				(mid 97.703606 -218.68266)
				(end 97.940368 -218.767152)
			)
			(xy 97.949258 -218.771978)
			(arc
				(start 97.962974 -218.780106)
				(mid 97.987135 -218.78996)
				(end 98.013012 -218.793314)
			)
			(arc
				(start 98.013012 -218.793314)
				(mid 98.039182 -218.789936)
				(end 98.063558 -218.779852)
			)
			(arc
				(start 98.063558 -218.779852)
				(mid 98.309997 -218.685411)
				(end 98.57359 -218.672156)
			)
			(arc
				(start 98.57359 -218.672156)
				(mid 98.609278 -218.662378)
				(end 98.628962 -218.631008)
			)
			(arc
				(start 98.628962 -218.631008)
				(mid 98.63443 -218.607023)
				(end 98.641662 -218.58351)
			)
			(xy 98.649536 -218.561412) (xy 98.444558 -218.206574)
			(arc
				(start 98.421698 -218.202256)
				(mid 98.229415 -218.088573)
				(end 98.153728 -217.878406)
			)
			(arc
				(start 98.153728 -217.878406)
				(mid 98.483166 -217.548968)
				(end 98.812604 -217.878406)
			)
			(arc
				(start 98.812604 -217.878406)
				(mid 98.808045 -217.933534)
				(end 98.794316 -217.987118)
			)
			(xy 98.786442 -218.009216) (xy 98.99142 -218.364054)
			(arc
				(start 99.01428 -218.368372)
				(mid 99.185985 -218.459225)
				(end 99.276662 -218.631008)
			)
			(arc
				(start 99.276662 -218.631008)
				(mid 99.296295 -218.662447)
				(end 99.332034 -218.672156)
			)
			(arc
				(start 99.332034 -218.672156)
				(mid 99.583206 -218.68266)
				(end 99.819968 -218.767152)
			)
			(xy 99.828858 -218.771978)
			(arc
				(start 99.842574 -218.780106)
				(mid 99.866735 -218.78996)
				(end 99.892612 -218.793314)
			)
		)
		(stroke
			(width 0)
			(type solid)
		)
		(fill yes)
		(layer "B.Cu")
		(net "PVCCFA_EHV_FIVRA_CPU1")
	)
	(gr_poly
		(pts
			(xy 96.257618 -353.493832) (xy 101.145594 -348.605856) (xy 101.152989 -348.599003) (xy 101.171588 -348.591257)
			(xy 101.181662 -348.59087) (xy 112.405922 -348.59087) (xy 115.0112 -351.196148) (xy 115.620292 -351.196148)
			(xy 115.620292 -349.672148) (xy 115.620731 -349.65876) (xy 115.627652 -349.632893) (xy 115.641032 -349.6097)
			(xy 115.659962 -349.590762) (xy 115.683149 -349.57737) (xy 115.709012 -349.570438) (xy 115.7224 -349.57004)
			(xy 117.2464 -349.57004) (xy 117.259794 -349.57039) (xy 117.28567 -349.577326) (xy 117.308868 -349.590724)
			(xy 117.327806 -349.609671) (xy 117.341193 -349.632875) (xy 117.348116 -349.658753) (xy 117.348508 -349.672148)
			(xy 117.348508 -350.4341) (xy 118.09452 -350.4341) (xy 118.09855 -350.349501) (xy 118.110604 -350.265668)
			(xy 118.130572 -350.18336) (xy 118.158273 -350.103323) (xy 118.193457 -350.026282) (xy 118.235806 -349.952934)
			(xy 118.284934 -349.883944) (xy 118.340399 -349.819936) (xy 118.401696 -349.76149) (xy 118.468272 -349.709136)
			(xy 118.539523 -349.663347) (xy 118.614804 -349.624539) (xy 118.693432 -349.593062) (xy 118.774697 -349.569203)
			(xy 118.857862 -349.553176) (xy 118.942174 -349.545127) (xy 118.984522 -349.54464) (xy 119.02703 -349.545106)
			(xy 119.111658 -349.553211) (xy 119.195127 -349.569355) (xy 119.276675 -349.59339) (xy 119.355557 -349.625097)
			(xy 119.431053 -349.664186) (xy 119.502475 -349.710302) (xy 119.56917 -349.763022) (xy 119.63053 -349.821866)
			(xy 119.658638 -349.853758) (xy 119.66321 -349.858838) (xy 119.691688 -349.893292) (xy 119.742369 -349.966931)
			(xy 119.78541 -350.045281) (xy 119.820376 -350.127552) (xy 119.846915 -350.212915) (xy 119.86476 -350.300509)
			(xy 119.87373 -350.389451) (xy 119.874284 -350.434148) (xy 119.873772 -350.47889) (xy 119.864819 -350.567924)
			(xy 119.846967 -350.655609) (xy 119.820397 -350.741057) (xy 119.785378 -350.823404) (xy 119.742264 -350.901816)
			(xy 119.691492 -350.975501) (xy 119.662956 -351.009966) (xy 119.658638 -351.014538) (xy 119.630526 -351.046425)
			(xy 119.569159 -351.105257) (xy 119.502461 -351.157968) (xy 119.431038 -351.204076) (xy 119.355542 -351.243161)
			(xy 119.276663 -351.274865) (xy 119.195118 -351.298901) (xy 119.111653 -351.315048) (xy 119.027028 -351.32316)
			(xy 118.984522 -351.323656) (xy 118.942174 -351.323073) (xy 118.857862 -351.315024) (xy 118.774697 -351.298997)
			(xy 118.693432 -351.275138) (xy 118.614804 -351.243661) (xy 118.539523 -351.204853) (xy 118.468272 -351.159064)
			(xy 118.401696 -351.10671) (xy 118.340399 -351.048264) (xy 118.284934 -350.984256) (xy 118.235806 -350.915266)
			(xy 118.193457 -350.841918) (xy 118.158273 -350.764877) (xy 118.130572 -350.68484) (xy 118.110604 -350.602532)
			(xy 118.09855 -350.518699) (xy 118.09452 -350.4341) (xy 117.348508 -350.4341) (xy 117.348508 -351.196148)
			(xy 117.348113 -351.209535) (xy 117.341173 -351.235396) (xy 117.327779 -351.258579) (xy 117.308841 -351.277508)
			(xy 117.285651 -351.290892) (xy 117.259788 -351.29782) (xy 117.2464 -351.298256) (xy 115.7224 -351.298256)
			(xy 115.709019 -351.297772) (xy 115.683168 -351.290847) (xy 115.659988 -351.277469) (xy 115.64106 -351.25855)
			(xy 115.627671 -351.235377) (xy 115.620735 -351.209529) (xy 115.620292 -351.196148) (xy 115.0112 -351.196148)
			(xy 115.4176 -351.602548) (xy 123.19 -351.602548) (xy 124.7648 -350.027748) (xy 142.19174 -350.027748)
			(xy 142.41526 -349.804228) (xy 142.41526 -343.428828) (xy 142.11808 -343.131648) (xy 141.76502 -343.131648)
			(xy 141.7574 -343.139268) (xy 141.14272 -343.139268) (xy 141.13764 -343.134442) (xy 138.189462 -343.134442)
			(xy 138.1633 -343.139522) (xy 138.131042 -343.17178) (xy 138.131042 -346.394532) (xy 138.136122 -346.420694)
			(xy 138.51509 -346.799662) (xy 139.706858 -346.799662) (xy 139.716922 -346.800097) (xy 139.735505 -346.807834)
			(xy 139.742926 -346.814648) (xy 140.001752 -347.073474) (xy 140.008592 -347.080874) (xy 140.016307 -347.099473)
			(xy 140.016738 -347.109542) (xy 140.016738 -348.27845) (xy 140.016304 -348.288515) (xy 140.00857 -348.3071)
			(xy 140.001752 -348.314518) (xy 139.520676 -348.795848) (xy 139.513279 -348.802696) (xy 139.49468 -348.81043)
			(xy 139.484608 -348.810834) (xy 133.961632 -348.810834) (xy 133.951569 -348.810397) (xy 133.932988 -348.802658)
			(xy 133.925564 -348.795848) (xy 133.595872 -348.46641) (xy 133.589016 -348.459016) (xy 133.581267 -348.440417)
			(xy 133.580886 -348.430342) (xy 133.580886 -338.60867) (xy 133.580378 -338.608416) (xy 133.580378 -338.489798)
			(xy 133.580886 -338.48929) (xy 133.580886 -337.440016) (xy 133.566662 -337.40344) (xy 133.506972 -337.34375)
			(xy 130.02895 -337.34375) (xy 130.002788 -337.34883) (xy 129.97053 -337.381088) (xy 129.97053 -340.60384)
			(xy 129.97561 -340.630002) (xy 130.180842 -340.835234) (xy 131.147058 -340.835234) (xy 131.157123 -340.835668)
			(xy 131.175709 -340.843401) (xy 131.183126 -340.85022) (xy 131.842002 -341.509096) (xy 131.848849 -341.516494)
			(xy 131.856585 -341.535092) (xy 131.856988 -341.545164) (xy 131.856988 -342.958166) (xy 131.856552 -342.968231)
			(xy 131.84882 -342.986817) (xy 131.842002 -342.994234) (xy 131.55676 -343.279476) (xy 131.549361 -343.286319)
			(xy 131.530762 -343.294043) (xy 131.520692 -343.294462) (xy 126.60122 -343.294462) (xy 126.591157 -343.294023)
			(xy 126.572577 -343.286284) (xy 126.565152 -343.279476) (xy 125.43536 -342.149684) (xy 125.42851 -342.142287)
			(xy 125.420772 -342.123689) (xy 125.420374 -342.113616) (xy 125.420374 -341.527892) (xy 125.39853 -341.507064)
			(xy 125.377748 -341.485451) (xy 125.342504 -341.436947) (xy 125.315278 -341.383528) (xy 125.29674 -341.32651)
			(xy 125.287347 -341.267294) (xy 125.28677 -341.237316) (xy 125.28677 -340.586822) (xy 125.287326 -340.556841)
			(xy 125.296707 -340.497618) (xy 125.315241 -340.440593) (xy 125.342471 -340.387171) (xy 125.377726 -340.338669)
			(xy 125.39853 -340.317074) (xy 125.420374 -340.295992) (xy 125.420374 -335.198466) (xy 125.419866 -335.198212)
			(xy 125.419866 -335.079594) (xy 125.420374 -335.079086) (xy 125.420374 -334.029812) (xy 125.40615 -333.993236)
			(xy 125.34646 -333.933546) (xy 121.868438 -333.933546) (xy 121.842276 -333.938626) (xy 121.810018 -333.970884)
			(xy 121.810018 -337.193636) (xy 121.815098 -337.219798) (xy 122.105166 -337.509866) (xy 123.095512 -337.509866)
			(xy 123.10558 -337.510293) (xy 123.124175 -337.518018) (xy 123.13158 -337.524852) (xy 123.328684 -337.721956)
			(xy 123.484386 -337.721956) (xy 123.494448 -337.722396) (xy 123.513024 -337.730139) (xy 123.520454 -337.736942)
			(xy 123.740926 -337.957414) (xy 123.747778 -337.96481) (xy 123.755519 -337.983409) (xy 123.755912 -337.993482)
			(xy 123.755912 -338.149184) (xy 123.760738 -338.15401) (xy 123.760738 -339.577172) (xy 123.7603 -339.587235)
			(xy 123.75256 -339.605815) (xy 123.745752 -339.61324) (xy 123.728734 -339.630258) (xy 123.457462 -339.901276)
			(xy 123.450063 -339.908119) (xy 123.431464 -339.915844) (xy 123.421394 -339.916262) (xy 118.140988 -339.916262)
			(xy 118.13092 -339.915836) (xy 118.112322 -339.908114) (xy 118.10492 -339.901276) (xy 117.577108 -339.373464)
			(xy 117.570266 -339.366064) (xy 117.562544 -339.347466) (xy 117.562122 -339.337396) (xy 117.562122 -338.031328)
			(xy 117.557042 -338.005166) (xy 117.274848 -337.722972) (xy 117.268001 -337.715574) (xy 117.260269 -337.696976)
			(xy 117.259862 -337.686904) (xy 117.259862 -335.198466) (xy 117.259354 -335.198212) (xy 117.259354 -335.079594)
			(xy 117.259862 -335.079086) (xy 117.259862 -334.029812) (xy 117.245638 -333.993236) (xy 117.185948 -333.933546)
			(xy 113.707926 -333.933546) (xy 113.681764 -333.938626) (xy 113.649506 -333.970884) (xy 113.649506 -336.863944)
			(xy 113.654586 -336.890106) (xy 114.37874 -337.61426) (xy 115.526058 -337.61426) (xy 115.536122 -337.614695)
			(xy 115.554706 -337.622431) (xy 115.562126 -337.629246) (xy 115.770152 -337.837272) (xy 115.776992 -337.844672)
			(xy 115.784708 -337.863271) (xy 115.785138 -337.87334) (xy 115.785138 -339.5853) (xy 115.784713 -339.595369)
			(xy 115.776992 -339.613967) (xy 115.770152 -339.621368) (xy 115.556284 -339.835236) (xy 115.548888 -339.842087)
			(xy 115.530289 -339.849825) (xy 115.520216 -339.850222) (xy 109.50702 -339.850222) (xy 109.49697 -339.849716)
			(xy 109.478409 -339.841994) (xy 109.470952 -339.835236) (xy 109.114336 -339.47862) (xy 109.107498 -339.471219)
			(xy 109.099787 -339.45262) (xy 109.09935 -339.442552) (xy 109.09935 -335.198466) (xy 109.098842 -335.198212)
			(xy 109.098842 -335.079594) (xy 109.09935 -335.079086) (xy 109.09935 -334.029812) (xy 109.085126 -333.993236)
			(xy 109.025436 -333.933546) (xy 105.547414 -333.933546) (xy 105.521252 -333.938626) (xy 105.488994 -333.970884)
			(xy 105.488994 -336.827114) (xy 105.494074 -336.853276) (xy 106.22026 -337.579462) (xy 107.41914 -337.579462)
			(xy 107.429206 -337.579894) (xy 107.447794 -337.587626) (xy 107.455208 -337.594448) (xy 107.704636 -337.843876)
			(xy 107.711477 -337.851276) (xy 107.719194 -337.869875) (xy 107.719622 -337.879944) (xy 107.719622 -339.591142)
			(xy 107.719192 -339.601209) (xy 107.711469 -339.619805) (xy 107.704636 -339.62721) (xy 107.592368 -339.739478)
			(xy 107.580938 -339.739478) (xy 107.46994 -339.850476) (xy 107.462539 -339.857315) (xy 107.443941 -339.865032)
			(xy 107.433872 -339.865462) (xy 101.55682 -339.865462) (xy 101.546757 -339.865023) (xy 101.528177 -339.857284)
			(xy 101.520752 -339.850476) (xy 100.953824 -339.283548) (xy 100.946983 -339.276148) (xy 100.939264 -339.257549)
			(xy 100.938838 -339.24748) (xy 100.938838 -335.198466) (xy 100.93833 -335.198212) (xy 100.93833 -335.079594)
			(xy 100.938838 -335.079086) (xy 100.938838 -334.029812) (xy 100.924614 -333.993236) (xy 100.864924 -333.933546)
			(xy 97.386902 -333.933546) (xy 97.36074 -333.938626) (xy 97.328482 -333.970884) (xy 97.328482 -336.967068)
			(xy 97.333562 -336.99323) (xy 97.954338 -337.614006) (xy 99.314 -337.614006) (xy 99.32407 -337.614429)
			(xy 99.342674 -337.622144) (xy 99.350068 -337.628992) (xy 99.490276 -337.7692) (xy 99.497125 -337.776597)
			(xy 99.504863 -337.795196) (xy 99.505262 -337.805268) (xy 99.505262 -339.18398) (xy 99.504823 -339.194043)
			(xy 99.497084 -339.212623) (xy 99.490276 -339.220048) (xy 99.303586 -339.406738) (xy 99.29619 -339.413589)
			(xy 99.277591 -339.421328) (xy 99.267518 -339.421724) (xy 94.93758 -339.421724) (xy 94.911418 -339.426804)
			(xy 94.530164 -339.808058) (xy 94.522765 -339.814903) (xy 94.504167 -339.822631) (xy 94.494096 -339.823044)
			(xy 93.91015 -339.823044) (xy 93.900085 -339.82261) (xy 93.881499 -339.814877) (xy 93.874082 -339.808058)
			(xy 92.793312 -338.727288) (xy 92.786466 -338.719889) (xy 92.778734 -338.701291) (xy 92.778326 -338.69122)
			(xy 92.778326 -338.60867) (xy 92.777818 -338.608416) (xy 92.777818 -338.489798) (xy 92.778326 -338.48929)
			(xy 92.778326 -337.428332) (xy 92.773246 -337.40217) (xy 92.714826 -337.34375) (xy 89.22639 -337.34375)
			(xy 89.200228 -337.34883) (xy 89.16797 -337.381088) (xy 89.16797 -340.31936) (xy 89.17305 -340.345522)
			(xy 89.851738 -341.02421) (xy 91.045538 -341.02421) (xy 91.050492 -341.024332) (xy 91.06021 -341.026258)
			(xy 91.064842 -341.02802) (xy 91.167966 -341.071708) (xy 91.17076 -341.07247) (xy 91.176732 -341.074429)
			(xy 91.187533 -341.080848) (xy 91.192096 -341.08517) (xy 91.295474 -341.188548) (xy 91.299761 -341.193137)
			(xy 91.306179 -341.203929) (xy 91.308174 -341.209884) (xy 91.308936 -341.212678) (xy 91.352624 -341.315802)
			(xy 91.354398 -341.32043) (xy 91.356318 -341.330151) (xy 91.356434 -341.335106) (xy 91.356434 -342.733884)
			(xy 91.355994 -342.743946) (xy 91.348251 -342.762522) (xy 91.341448 -342.769952) (xy 90.933524 -343.177876)
			(xy 90.926123 -343.184713) (xy 90.907524 -343.192424) (xy 90.897456 -343.192862) (xy 86.576916 -343.192862)
			(xy 86.550754 -343.197942) (xy 86.271354 -343.477342) (xy 86.263956 -343.484187) (xy 86.245357 -343.491914)
			(xy 86.235286 -343.492328) (xy 85.83295 -343.492328) (xy 85.822883 -343.491897) (xy 85.804289 -343.484173)
			(xy 85.796882 -343.477342) (xy 85.512402 -343.192862) (xy 81.18094 -343.192862) (xy 81.154778 -343.197942)
			(xy 81.007458 -343.345262) (xy 81.007458 -344.791284) (xy 96.474788 -344.791284) (xy 96.474788 -343.267284)
			(xy 96.475215 -343.253898) (xy 96.482147 -343.22804) (xy 96.495535 -343.204857) (xy 96.514466 -343.185927)
			(xy 96.537651 -343.172542) (xy 96.56351 -343.165613) (xy 96.576896 -343.165176) (xy 98.100896 -343.165176)
			(xy 98.11428 -343.165632) (xy 98.140136 -343.172559) (xy 98.163318 -343.18594) (xy 98.182247 -343.204866)
			(xy 98.195634 -343.228046) (xy 98.202565 -343.2539) (xy 98.203004 -343.267284) (xy 98.203004 -344.071632)
			(xy 98.950014 -344.071632) (xy 98.950014 -343.986936) (xy 98.958065 -343.902622) (xy 98.974094 -343.819456)
			(xy 98.997955 -343.738189) (xy 99.029434 -343.659559) (xy 99.068245 -343.584278) (xy 99.114035 -343.513026)
			(xy 99.166391 -343.44645) (xy 99.224839 -343.385152) (xy 99.288849 -343.329687) (xy 99.357841 -343.280558)
			(xy 99.431191 -343.238209) (xy 99.508234 -343.203025) (xy 99.588273 -343.175323) (xy 99.670582 -343.155355)
			(xy 99.754417 -343.143302) (xy 99.839018 -343.139272) (xy 99.923619 -343.143302) (xy 100.007454 -343.155355)
			(xy 100.089763 -343.175323) (xy 100.169802 -343.203025) (xy 100.246845 -343.238209) (xy 100.320195 -343.280558)
			(xy 100.389187 -343.329687) (xy 100.453197 -343.385152) (xy 100.511645 -343.44645) (xy 100.564001 -343.513026)
			(xy 100.609791 -343.584278) (xy 100.648602 -343.659559) (xy 100.680081 -343.738189) (xy 100.703942 -343.819456)
			(xy 100.719971 -343.902622) (xy 100.728022 -343.986936) (xy 100.728526 -344.029284) (xy 100.728022 -344.071632)
			(xy 100.719971 -344.155946) (xy 100.703942 -344.239112) (xy 100.680081 -344.320379) (xy 100.648602 -344.399009)
			(xy 100.609791 -344.47429) (xy 100.564001 -344.545542) (xy 100.511645 -344.612118) (xy 100.453197 -344.673416)
			(xy 100.389187 -344.728881) (xy 100.320195 -344.77801) (xy 100.297204 -344.791284) (xy 104.035352 -344.791284)
			(xy 104.035352 -343.267284) (xy 104.035814 -343.253901) (xy 104.042744 -343.228048) (xy 104.056126 -343.204869)
			(xy 104.075049 -343.18594) (xy 104.098226 -343.172553) (xy 104.124077 -343.165618) (xy 104.13746 -343.165176)
			(xy 105.66146 -343.165176) (xy 105.674847 -343.165624) (xy 105.700712 -343.172545) (xy 105.723903 -343.185925)
			(xy 105.742841 -343.204852) (xy 105.756234 -343.228036) (xy 105.763168 -343.253897) (xy 105.763568 -343.267284)
			(xy 105.763568 -344.071632) (xy 106.510578 -344.071632) (xy 106.510578 -343.986936) (xy 106.518629 -343.902622)
			(xy 106.534658 -343.819456) (xy 106.558519 -343.738189) (xy 106.589998 -343.659559) (xy 106.628809 -343.584278)
			(xy 106.674599 -343.513026) (xy 106.726955 -343.44645) (xy 106.785403 -343.385152) (xy 106.849413 -343.329687)
			(xy 106.918405 -343.280558) (xy 106.991755 -343.238209) (xy 107.068798 -343.203025) (xy 107.148837 -343.175323)
			(xy 107.231146 -343.155355) (xy 107.314981 -343.143302) (xy 107.399582 -343.139272) (xy 107.484183 -343.143302)
			(xy 107.568018 -343.155355) (xy 107.650327 -343.175323) (xy 107.730366 -343.203025) (xy 107.807409 -343.238209)
			(xy 107.880759 -343.280558) (xy 107.949751 -343.329687) (xy 108.013761 -343.385152) (xy 108.072209 -343.44645)
			(xy 108.124565 -343.513026) (xy 108.170355 -343.584278) (xy 108.209166 -343.659559) (xy 108.240645 -343.738189)
			(xy 108.264506 -343.819456) (xy 108.280535 -343.902622) (xy 108.288586 -343.986936) (xy 108.28909 -344.029284)
			(xy 108.288586 -344.071632) (xy 108.280535 -344.155946) (xy 108.264506 -344.239112) (xy 108.240645 -344.320379)
			(xy 108.209166 -344.399009) (xy 108.170355 -344.47429) (xy 108.124565 -344.545542) (xy 108.072209 -344.612118)
			(xy 108.013761 -344.673416) (xy 107.949751 -344.728881) (xy 107.880759 -344.77801) (xy 107.857768 -344.791284)
			(xy 111.740696 -344.791284) (xy 111.740696 -343.267284) (xy 111.741115 -343.253898) (xy 111.748048 -343.228038)
			(xy 111.761437 -343.204854) (xy 111.78037 -343.185925) (xy 111.803557 -343.17254) (xy 111.829418 -343.165612)
			(xy 111.842804 -343.165176) (xy 113.366804 -343.165176) (xy 113.380188 -343.165625) (xy 113.406044 -343.172553)
			(xy 113.429227 -343.185937) (xy 113.448156 -343.204864) (xy 113.461542 -343.228045) (xy 113.468473 -343.2539)
			(xy 113.468912 -343.267284) (xy 113.468912 -344.071632) (xy 114.215922 -344.071632) (xy 114.215922 -343.986936)
			(xy 114.223973 -343.902622) (xy 114.240002 -343.819456) (xy 114.263863 -343.738189) (xy 114.295342 -343.659559)
			(xy 114.334153 -343.584278) (xy 114.379943 -343.513026) (xy 114.432299 -343.44645) (xy 114.490747 -343.385152)
			(xy 114.554757 -343.329687) (xy 114.623749 -343.280558) (xy 114.697099 -343.238209) (xy 114.774142 -343.203025)
			(xy 114.854181 -343.175323) (xy 114.93649 -343.155355) (xy 115.020325 -343.143302) (xy 115.104926 -343.139272)
			(xy 115.189527 -343.143302) (xy 115.273362 -343.155355) (xy 115.355671 -343.175323) (xy 115.43571 -343.203025)
			(xy 115.512753 -343.238209) (xy 115.586103 -343.280558) (xy 115.655095 -343.329687) (xy 115.719105 -343.385152)
			(xy 115.777553 -343.44645) (xy 115.829909 -343.513026) (xy 115.875699 -343.584278) (xy 115.91451 -343.659559)
			(xy 115.945989 -343.738189) (xy 115.96985 -343.819456) (xy 115.985879 -343.902622) (xy 115.99393 -343.986936)
			(xy 115.994434 -344.029284) (xy 115.99393 -344.071632) (xy 115.985879 -344.155946) (xy 115.96985 -344.239112)
			(xy 115.945989 -344.320379) (xy 115.91451 -344.399009) (xy 115.875699 -344.47429) (xy 115.829909 -344.545542)
			(xy 115.777553 -344.612118) (xy 115.723937 -344.668348) (xy 119.201692 -344.668348) (xy 119.201692 -343.144348)
			(xy 119.202131 -343.13096) (xy 119.209052 -343.105093) (xy 119.222432 -343.0819) (xy 119.241362 -343.062962)
			(xy 119.264549 -343.04957) (xy 119.290412 -343.042638) (xy 119.3038 -343.04224) (xy 120.8278 -343.04224)
			(xy 120.841194 -343.04259) (xy 120.86707 -343.049526) (xy 120.890268 -343.062924) (xy 120.909206 -343.081871)
			(xy 120.922593 -343.105075) (xy 120.929516 -343.130953) (xy 120.929908 -343.144348) (xy 120.929908 -343.9063)
			(xy 121.67592 -343.9063) (xy 121.67995 -343.821701) (xy 121.692004 -343.737868) (xy 121.711972 -343.65556)
			(xy 121.739673 -343.575523) (xy 121.774857 -343.498482) (xy 121.817206 -343.425134) (xy 121.866334 -343.356144)
			(xy 121.921799 -343.292136) (xy 121.983096 -343.23369) (xy 122.049672 -343.181336) (xy 122.120923 -343.135547)
			(xy 122.196204 -343.096739) (xy 122.274832 -343.065262) (xy 122.356097 -343.041403) (xy 122.439262 -343.025376)
			(xy 122.523574 -343.017327) (xy 122.565922 -343.01684) (xy 122.566176 -343.01684) (xy 122.592209 -343.01703)
			(xy 122.644185 -343.020083) (xy 122.670062 -343.022936) (xy 122.676666 -343.023444) (xy 122.71918 -343.0292)
			(xy 122.80289 -343.048026) (xy 122.884398 -343.074821) (xy 122.96295 -343.109337) (xy 123.037814 -343.151253)
			(xy 123.108297 -343.20018) (xy 123.173743 -343.255665) (xy 123.233544 -343.31719) (xy 123.287146 -343.384186)
			(xy 123.334051 -343.456031) (xy 123.373824 -343.532056) (xy 123.406094 -343.611556) (xy 123.430562 -343.693794)
			(xy 123.447001 -343.778004) (xy 123.455259 -343.863406) (xy 123.455258 -343.949206) (xy 123.446999 -344.034608)
			(xy 123.430559 -344.118818) (xy 123.40609 -344.201055) (xy 123.373819 -344.280555) (xy 123.334045 -344.35658)
			(xy 123.287139 -344.428423) (xy 123.233536 -344.495419) (xy 123.173734 -344.556944) (xy 123.108287 -344.612427)
			(xy 123.037804 -344.661353) (xy 122.962939 -344.703269) (xy 122.884387 -344.737784) (xy 122.802878 -344.764578)
			(xy 122.719168 -344.783402) (xy 122.676666 -344.789252) (xy 122.670062 -344.78976) (xy 122.644186 -344.792621)
			(xy 122.592209 -344.795669) (xy 122.566176 -344.795856) (xy 122.565922 -344.795856) (xy 122.523574 -344.795273)
			(xy 122.439262 -344.787224) (xy 122.356097 -344.771197) (xy 122.274832 -344.747338) (xy 122.196204 -344.715861)
			(xy 122.120923 -344.677053) (xy 122.049672 -344.631264) (xy 121.983096 -344.57891) (xy 121.921799 -344.520464)
			(xy 121.866334 -344.456456) (xy 121.817206 -344.387466) (xy 121.774857 -344.314118) (xy 121.739673 -344.237077)
			(xy 121.711972 -344.15704) (xy 121.692004 -344.074732) (xy 121.67995 -343.990899) (xy 121.67592 -343.9063)
			(xy 120.929908 -343.9063) (xy 120.929908 -344.668348) (xy 120.929513 -344.681735) (xy 120.922573 -344.707596)
			(xy 120.909179 -344.730779) (xy 120.890241 -344.749708) (xy 120.867051 -344.763092) (xy 120.841188 -344.77002)
			(xy 120.8278 -344.770456) (xy 119.3038 -344.770456) (xy 119.290419 -344.769972) (xy 119.264568 -344.763047)
			(xy 119.241388 -344.749669) (xy 119.22246 -344.73075) (xy 119.209071 -344.707577) (xy 119.202135 -344.681729)
			(xy 119.201692 -344.668348) (xy 115.723937 -344.668348) (xy 115.719105 -344.673416) (xy 115.655095 -344.728881)
			(xy 115.586103 -344.77801) (xy 115.512753 -344.820359) (xy 115.43571 -344.855543) (xy 115.355671 -344.883245)
			(xy 115.273362 -344.903213) (xy 115.189527 -344.915266) (xy 115.104926 -344.919297) (xy 115.020325 -344.915266)
			(xy 114.93649 -344.903213) (xy 114.854181 -344.883245) (xy 114.774142 -344.855543) (xy 114.697099 -344.820359)
			(xy 114.623749 -344.77801) (xy 114.554757 -344.728881) (xy 114.490747 -344.673416) (xy 114.432299 -344.612118)
			(xy 114.379943 -344.545542) (xy 114.334153 -344.47429) (xy 114.295342 -344.399009) (xy 114.263863 -344.320379)
			(xy 114.240002 -344.239112) (xy 114.223973 -344.155946) (xy 114.215922 -344.071632) (xy 113.468912 -344.071632)
			(xy 113.468912 -344.791284) (xy 113.468496 -344.804673) (xy 113.461569 -344.830541) (xy 113.448183 -344.853733)
			(xy 113.429249 -344.87267) (xy 113.406059 -344.886061) (xy 113.380193 -344.892994) (xy 113.366804 -344.893392)
			(xy 111.842804 -344.893392) (xy 111.829412 -344.893007) (xy 111.803542 -344.886075) (xy 111.780347 -344.872683)
			(xy 111.76141 -344.853743) (xy 111.748021 -344.830547) (xy 111.741092 -344.804676) (xy 111.740696 -344.791284)
			(xy 107.857768 -344.791284) (xy 107.807409 -344.820359) (xy 107.730366 -344.855543) (xy 107.650327 -344.883245)
			(xy 107.568018 -344.903213) (xy 107.484183 -344.915266) (xy 107.399582 -344.919297) (xy 107.314981 -344.915266)
			(xy 107.231146 -344.903213) (xy 107.148837 -344.883245) (xy 107.068798 -344.855543) (xy 106.991755 -344.820359)
			(xy 106.918405 -344.77801) (xy 106.849413 -344.728881) (xy 106.785403 -344.673416) (xy 106.726955 -344.612118)
			(xy 106.674599 -344.545542) (xy 106.628809 -344.47429) (xy 106.589998 -344.399009) (xy 106.558519 -344.320379)
			(xy 106.534658 -344.239112) (xy 106.518629 -344.155946) (xy 106.510578 -344.071632) (xy 105.763568 -344.071632)
			(xy 105.763568 -344.791284) (xy 105.763196 -344.804677) (xy 105.756265 -344.830551) (xy 105.742871 -344.853748)
			(xy 105.723929 -344.872686) (xy 105.700728 -344.886074) (xy 105.674853 -344.892999) (xy 105.66146 -344.893392)
			(xy 104.13746 -344.893392) (xy 104.124072 -344.893006) (xy 104.09821 -344.886066) (xy 104.075024 -344.872671)
			(xy 104.056095 -344.853731) (xy 104.042712 -344.830539) (xy 104.035787 -344.804673) (xy 104.035352 -344.791284)
			(xy 100.297204 -344.791284) (xy 100.246845 -344.820359) (xy 100.169802 -344.855543) (xy 100.089763 -344.883245)
			(xy 100.007454 -344.903213) (xy 99.923619 -344.915266) (xy 99.839018 -344.919297) (xy 99.754417 -344.915266)
			(xy 99.670582 -344.903213) (xy 99.588273 -344.883245) (xy 99.508234 -344.855543) (xy 99.431191 -344.820359)
			(xy 99.357841 -344.77801) (xy 99.288849 -344.728881) (xy 99.224839 -344.673416) (xy 99.166391 -344.612118)
			(xy 99.114035 -344.545542) (xy 99.068245 -344.47429) (xy 99.029434 -344.399009) (xy 98.997955 -344.320379)
			(xy 98.974094 -344.239112) (xy 98.958065 -344.155946) (xy 98.950014 -344.071632) (xy 98.203004 -344.071632)
			(xy 98.203004 -344.791284) (xy 98.202596 -344.804674) (xy 98.195668 -344.830542) (xy 98.182281 -344.853736)
			(xy 98.163345 -344.872673) (xy 98.140154 -344.886064) (xy 98.114286 -344.892995) (xy 98.100896 -344.893392)
			(xy 96.576896 -344.893392) (xy 96.563504 -344.893014) (xy 96.537633 -344.88608) (xy 96.514439 -344.872686)
			(xy 96.495502 -344.853745) (xy 96.482112 -344.830548) (xy 96.475184 -344.804676) (xy 96.474788 -344.791284)
			(xy 81.007458 -344.791284) (xy 81.007458 -346.02674) (xy 81.012538 -346.052902) (xy 81.774538 -346.814902)
			(xy 82.88528 -346.814902) (xy 82.889562 -346.815031) (xy 82.897988 -346.816571) (xy 82.902044 -346.81795)
			(xy 82.910172 -346.820744) (xy 83.095338 -346.820744) (xy 83.105404 -346.821175) (xy 83.123994 -346.828904)
			(xy 83.131406 -346.83573) (xy 83.207352 -346.911676) (xy 83.214192 -346.919076) (xy 83.221906 -346.937675)
			(xy 83.222338 -346.947744) (xy 83.222338 -348.246446) (xy 83.260692 -348.259146) (xy 83.26247 -348.259654)
			(xy 83.363493 -348.286022) (xy 83.563649 -348.345525) (xy 83.761371 -348.412673) (xy 83.956368 -348.487366)
			(xy 84.148352 -348.569493) (xy 84.33704 -348.658934) (xy 84.522154 -348.755557) (xy 84.703419 -348.859219)
			(xy 84.880569 -348.969767) (xy 85.053342 -349.087037) (xy 85.221483 -349.210858) (xy 85.384744 -349.341045)
			(xy 85.542884 -349.477407) (xy 85.695669 -349.619743) (xy 85.842875 -349.767843) (xy 85.984283 -349.921487)
			(xy 86.119685 -350.08045) (xy 86.248882 -350.244496) (xy 86.371682 -350.413383) (xy 86.487904 -350.586863)
			(xy 86.597377 -350.764679) (xy 86.69994 -350.946569) (xy 86.79544 -351.132263) (xy 86.883737 -351.321489)
			(xy 86.964701 -351.513967) (xy 87.038212 -351.709413) (xy 87.104161 -351.907538) (xy 87.162452 -352.10805)
			(xy 87.212997 -352.310654) (xy 87.255724 -352.515049) (xy 87.290568 -352.720934) (xy 87.317478 -352.928006)
			(xy 87.336414 -353.135958) (xy 87.347349 -353.344485) (xy 87.34933 -353.448874) (xy 87.350092 -353.498912)
			(xy 96.231456 -353.498912)
		)
		(stroke
			(width 0)
			(type solid)
		)
		(fill yes)
		(layer "B.Cu")
		(net "SW_P12V_PVCCIN_CPU1_FLT")
	)
	(gr_poly
		(pts
			(xy 133.228588 -366.677448) (xy 133.243307 -366.676957) (xy 133.271522 -366.668563) (xy 133.29617 -366.65247)
			(xy 133.315205 -366.630015) (xy 133.327043 -366.603063) (xy 133.330701 -366.573854) (xy 133.325876 -366.544815)
			(xy 133.312967 -366.518359) (xy 133.293049 -366.496684) (xy 133.280658 -366.488726) (xy 133.246199 -366.467493)
			(xy 133.180996 -366.419528) (xy 133.120564 -366.365675) (xy 133.065434 -366.306406) (xy 133.01609 -366.24224)
			(xy 132.972963 -366.173741) (xy 132.936432 -366.101508) (xy 132.906817 -366.026175) (xy 132.884378 -365.948402)
			(xy 132.869311 -365.868872) (xy 132.861749 -365.788281) (xy 132.861304 -365.747808) (xy 132.861793 -365.706669)
			(xy 132.869614 -365.624763) (xy 132.885186 -365.543971) (xy 132.908366 -365.465026) (xy 132.938946 -365.388641)
			(xy 132.976648 -365.315509) (xy 133.021131 -365.246292) (xy 133.071992 -365.181617) (xy 133.128771 -365.122069)
			(xy 133.190953 -365.068188) (xy 133.257975 -365.020462) (xy 133.32923 -364.979323) (xy 133.404073 -364.945143)
			(xy 133.481827 -364.918232) (xy 133.561786 -364.898834) (xy 133.643227 -364.887125) (xy 133.725412 -364.88321)
			(xy 133.807597 -364.887125) (xy 133.889038 -364.898834) (xy 133.968997 -364.918232) (xy 134.046751 -364.945143)
			(xy 134.121594 -364.979323) (xy 134.192849 -365.020462) (xy 134.259871 -365.068188) (xy 134.322053 -365.122069)
			(xy 134.378832 -365.181617) (xy 134.429693 -365.246292) (xy 134.474176 -365.315509) (xy 134.511878 -365.388641)
			(xy 134.542458 -365.465026) (xy 134.565638 -365.543971) (xy 134.58121 -365.624763) (xy 134.589031 -365.706669)
			(xy 134.58952 -365.747808) (xy 134.589048 -365.78828) (xy 134.581479 -365.868869) (xy 134.566409 -365.948397)
			(xy 134.543969 -366.026168) (xy 134.514356 -366.1015) (xy 134.47783 -366.173734) (xy 134.43471 -366.242236)
			(xy 134.385374 -366.306407) (xy 134.330255 -366.365683) (xy 134.269835 -366.419547) (xy 134.204643 -366.467526)
			(xy 134.170166 -366.488726) (xy 134.15779 -366.496701) (xy 134.137888 -366.518379) (xy 134.124992 -366.544832)
			(xy 134.120173 -366.573864) (xy 134.123831 -366.603065) (xy 134.135662 -366.630011) (xy 134.154685 -366.652465)
			(xy 134.179319 -366.668565) (xy 134.207522 -366.676973) (xy 134.222236 -366.677448) (xy 136.483598 -366.677448)
			(xy 146.07667 -357.084376) (xy 146.07667 -342.12022) (xy 146.076232 -342.110157) (xy 146.068493 -342.091576)
			(xy 146.061684 -342.084152) (xy 143.648176 -339.670644) (xy 143.64133 -339.663246) (xy 143.633604 -339.644647)
			(xy 143.63319 -339.634576) (xy 143.63319 -339.005926) (xy 143.638716 -339.000102) (xy 143.646113 -338.985861)
			(xy 143.647668 -338.977986) (xy 143.648176 -338.969858) (xy 143.648176 -334.051656) (xy 143.647765 -334.042887)
			(xy 143.641797 -334.026391) (xy 143.636492 -334.019398) (xy 143.634968 -334.01762) (xy 143.547084 -333.929736)
			(xy 143.539972 -333.92237) (xy 143.521176 -333.91475) (xy 134.116064 -333.91475) (xy 134.105998 -333.914319)
			(xy 134.087408 -333.90659) (xy 134.079996 -333.899764) (xy 133.768338 -333.588106) (xy 133.761487 -333.58071)
			(xy 133.753744 -333.562111) (xy 133.753352 -333.552038) (xy 133.753352 -328.70902) (xy 133.752935 -328.699)
			(xy 133.745267 -328.680484) (xy 133.731092 -328.666317) (xy 133.712573 -328.658659) (xy 133.702552 -328.65822)
			(xy 125.558042 -328.65822) (xy 125.548051 -328.657691) (xy 125.529606 -328.64999) (xy 125.522228 -328.643234)
			(xy 125.229112 -328.350118) (xy 125.222459 -328.342763) (xy 125.214871 -328.324462) (xy 125.21438 -328.314558)
			(xy 125.21438 -325.395844) (xy 125.21406 -325.388034) (xy 125.209283 -325.37316) (xy 125.204982 -325.366634)
			(xy 125.202442 -325.362824) (xy 125.081284 -325.241666) (xy 125.073888 -325.234815) (xy 125.055289 -325.227076)
			(xy 125.045216 -325.22668) (xy 94.665038 -325.22668) (xy 94.654972 -325.227114) (xy 94.636382 -325.234842)
			(xy 94.62897 -325.241666) (xy 94.37751 -325.493126) (xy 94.371922 -325.49973) (xy 94.371922 -325.499984)
			(xy 94.367621 -325.506512) (xy 94.362831 -325.521383) (xy 94.362524 -325.529194) (xy 94.362524 -327.662794)
			(xy 94.362006 -327.672694) (xy 94.35443 -327.690992) (xy 94.347792 -327.698354) (xy 93.433392 -328.612754)
			(xy 93.426049 -328.619568) (xy 93.407586 -328.627305) (xy 93.397578 -328.62774) (xy 84.805266 -328.62774)
			(xy 84.795252 -328.628166) (xy 84.776754 -328.635844) (xy 84.762602 -328.650016) (xy 84.754952 -328.668525)
			(xy 84.754466 -328.67854) (xy 84.754466 -331.68971) (xy 84.75404 -331.699779) (xy 84.74632 -331.718377)
			(xy 84.73948 -331.725778) (xy 84.617052 -331.848206) (xy 84.609432 -331.857858) (xy 84.603336 -331.867764)
			(xy 84.59597 -331.877416) (xy 84.540344 -331.933042) (xy 84.532945 -331.939886) (xy 84.514346 -331.947609)
			(xy 84.504276 -331.948028) (xy 79.256382 -331.948028) (xy 79.246314 -331.948455) (xy 79.227717 -331.956177)
			(xy 79.220314 -331.963014) (xy 79.135986 -332.047342) (xy 79.129137 -332.054738) (xy 79.121404 -332.073338)
			(xy 79.121 -332.08341) (xy 79.121 -332.950058) (xy 79.120566 -332.960123) (xy 79.112837 -332.978713)
			(xy 79.106014 -332.986126) (xy 78.780386 -333.311754) (xy 78.772974 -333.318438) (xy 78.754541 -333.326035)
			(xy 78.734603 -333.326035) (xy 78.71617 -333.318438) (xy 78.708758 -333.311754) (xy 78.708758 -333.3115)
			(xy 77.740764 -334.279494) (xy 77.733364 -334.286335) (xy 77.714766 -334.294058) (xy 77.704696 -334.29448)
			(xy 77.183742 -334.29448) (xy 77.173676 -334.294913) (xy 77.155085 -334.30264) (xy 77.147674 -334.309466)
			(xy 76.707238 -334.749902) (xy 76.699836 -334.756739) (xy 76.681238 -334.76445) (xy 76.67117 -334.764888)
			(xy 76.133452 -334.764888) (xy 76.123385 -334.765319) (xy 76.104792 -334.773045) (xy 76.097384 -334.779874)
			(xy 75.901296 -334.975962) (xy 75.89393 -334.983074) (xy 75.88631 -335.00187) (xy 75.88631 -342.688672)
			(xy 75.88678 -342.698545) (xy 75.894238 -342.716828) (xy 75.900788 -342.724232) (xy 76.075032 -342.898476)
			(xy 76.07554 -342.898984) (xy 76.082922 -342.905565) (xy 76.10122 -342.913016) (xy 76.1111 -342.913462)
			(xy 78.095856 -342.913462) (xy 78.10592 -342.913897) (xy 78.124504 -342.921633) (xy 78.131924 -342.928448)
			(xy 78.381352 -343.177876) (xy 78.388192 -343.185276) (xy 78.395906 -343.203875) (xy 78.396338 -343.213944)
			(xy 78.396338 -344.635328) (xy 78.396798 -344.645206) (xy 78.404237 -344.663507) (xy 78.410816 -344.670888)
			(xy 78.940152 -345.200224) (xy 78.94066 -345.200732) (xy 78.94804 -345.207316) (xy 78.96634 -345.214767)
			(xy 78.97622 -345.21521) (xy 80.634586 -345.21521) (xy 80.661764 -345.20378) (xy 80.666203 -345.201754)
			(xy 80.674261 -345.196253) (xy 80.677766 -345.192858) (xy 80.71231 -345.158314) (xy 80.712818 -345.157806)
			(xy 80.719398 -345.150424) (xy 80.726839 -345.132125) (xy 80.727296 -345.122246) (xy 80.727296 -342.999822)
			(xy 80.727733 -342.989758) (xy 80.735467 -342.971174) (xy 80.742282 -342.963754) (xy 80.813402 -342.892634)
			(xy 80.820799 -342.885784) (xy 80.839397 -342.878045) (xy 80.84947 -342.877648) (xy 84.363052 -342.877648)
			(xy 84.365846 -342.875108) (xy 84.367624 -342.876886) (xy 84.52231 -342.876886) (xy 84.532187 -342.876427)
			(xy 84.550487 -342.868984) (xy 84.55787 -342.862408) (xy 84.64296 -342.777318) (xy 84.643468 -342.77681)
			(xy 84.650043 -342.769426) (xy 84.657478 -342.751127) (xy 84.657946 -342.74125) (xy 84.657946 -337.752944)
			(xy 84.658381 -337.742879) (xy 84.666115 -337.724294) (xy 84.672932 -337.716876) (xy 85.22716 -337.162648)
			(xy 85.234559 -337.155806) (xy 85.253158 -337.148086) (xy 85.263228 -337.147662) (xy 86.274656 -337.147662)
			(xy 86.28472 -337.148097) (xy 86.303304 -337.155833) (xy 86.310724 -337.162648) (xy 86.509352 -337.361276)
			(xy 86.516192 -337.368676) (xy 86.523906 -337.387275) (xy 86.524338 -337.397344) (xy 86.524338 -338.819236)
			(xy 86.5248 -338.829113) (xy 86.532241 -338.847412) (xy 86.538816 -338.854796) (xy 87.031576 -339.347556)
			(xy 87.034862 -339.351037) (xy 87.040227 -339.358963) (xy 87.042244 -339.363304) (xy 87.046054 -339.372194)
			(xy 87.082884 -339.409024) (xy 87.086407 -339.412397) (xy 87.094464 -339.417888) (xy 87.098886 -339.419946)
			(xy 87.10041 -339.420454) (xy 87.105149 -339.422325) (xy 87.115129 -339.42437) (xy 87.120222 -339.424518)
			(xy 88.795098 -339.424518) (xy 88.822276 -339.413088) (xy 88.826715 -339.411062) (xy 88.834772 -339.40556)
			(xy 88.838278 -339.402166) (xy 88.872822 -339.367622) (xy 88.87333 -339.367114) (xy 88.87991 -339.359732)
			(xy 88.887352 -339.341433) (xy 88.887808 -339.331554) (xy 88.887808 -337.20913) (xy 88.888244 -337.199066)
			(xy 88.895977 -337.18048) (xy 88.902794 -337.173062) (xy 88.973914 -337.101942) (xy 88.981311 -337.095093)
			(xy 88.99991 -337.087357) (xy 89.009982 -337.086956) (xy 92.523564 -337.086956) (xy 92.526358 -337.084416)
			(xy 92.528136 -337.086194) (xy 92.682822 -337.086194) (xy 92.692699 -337.085733) (xy 92.710996 -337.078288)
			(xy 92.718382 -337.071716) (xy 92.803472 -336.986626) (xy 92.80398 -336.986118) (xy 92.810555 -336.978734)
			(xy 92.817991 -336.960435) (xy 92.818458 -336.950558) (xy 92.818458 -334.400144) (xy 92.818893 -334.39008)
			(xy 92.826628 -334.371495) (xy 92.833444 -334.364076) (xy 93.352112 -333.845408) (xy 93.359511 -333.838563)
			(xy 93.378109 -333.830831) (xy 93.38818 -333.830422) (xy 94.908116 -333.830422) (xy 94.918184 -333.830849)
			(xy 94.936783 -333.83857) (xy 94.944184 -333.845408) (xy 95.183452 -334.084676) (xy 95.190292 -334.092076)
			(xy 95.198006 -334.110675) (xy 95.198438 -334.120744) (xy 95.198438 -335.942686) (xy 95.209868 -335.969864)
			(xy 95.211895 -335.974302) (xy 95.2174 -335.982356) (xy 95.22079 -335.985866) (xy 95.226886 -335.991962)
			(xy 95.230407 -335.995338) (xy 95.238462 -336.000835) (xy 95.242888 -336.002884) (xy 95.270066 -336.014314)
			(xy 96.95561 -336.014314) (xy 96.982788 -336.002884) (xy 96.987231 -336.000864) (xy 96.995298 -335.995371)
			(xy 96.99879 -335.991962) (xy 97.033334 -335.957418) (xy 97.033842 -335.95691) (xy 97.04042 -335.949527)
			(xy 97.047858 -335.931228) (xy 97.04832 -335.92135) (xy 97.04832 -333.798926) (xy 97.048757 -333.788862)
			(xy 97.056493 -333.770279) (xy 97.063306 -333.762858) (xy 97.134426 -333.691738) (xy 97.141824 -333.684891)
			(xy 97.160423 -333.67716) (xy 97.170494 -333.676752) (xy 103.06177 -333.676752) (xy 103.071833 -333.677189)
			(xy 103.090414 -333.684927) (xy 103.097838 -333.691738) (xy 103.343964 -333.937864) (xy 103.350804 -333.945264)
			(xy 103.358521 -333.963863) (xy 103.35895 -333.973932) (xy 103.35895 -334.195166) (xy 103.359103 -334.201033)
			(xy 103.361801 -334.212453) (xy 103.364284 -334.217772) (xy 103.377112 -334.244312) (xy 103.397249 -334.299715)
			(xy 103.410833 -334.357078) (xy 103.417683 -334.415628) (xy 103.418132 -334.445102) (xy 103.417676 -334.474575)
			(xy 103.410802 -334.533119) (xy 103.397215 -334.590479) (xy 103.377098 -334.645886) (xy 103.364284 -334.672432)
			(xy 103.35895 -334.6831) (xy 103.35895 -335.942686) (xy 103.37038 -335.969864) (xy 103.372408 -335.974302)
			(xy 103.377914 -335.982355) (xy 103.381302 -335.985866) (xy 103.387398 -335.991962) (xy 103.390919 -335.995337)
			(xy 103.398975 -336.000833) (xy 103.4034 -336.002884) (xy 103.430578 -336.014314) (xy 105.116122 -336.014314)
			(xy 105.1433 -336.002884) (xy 105.147743 -336.000863) (xy 105.155808 -335.995369) (xy 105.159302 -335.991962)
			(xy 105.193846 -335.957418) (xy 105.194354 -335.95691) (xy 105.20093 -335.949527) (xy 105.208367 -335.931228)
			(xy 105.208832 -335.92135) (xy 105.208832 -333.798926) (xy 105.209269 -333.788862) (xy 105.217006 -333.77028)
			(xy 105.223818 -333.762858) (xy 105.294938 -333.691738) (xy 105.302337 -333.684894) (xy 105.320935 -333.677167)
			(xy 105.331006 -333.676752) (xy 108.844588 -333.676752) (xy 108.847382 -333.674212) (xy 108.84916 -333.67599)
			(xy 111.22152 -333.67599) (xy 111.231589 -333.676416) (xy 111.250189 -333.684135) (xy 111.257588 -333.690976)
			(xy 111.504476 -333.937864) (xy 111.511315 -333.945265) (xy 111.51903 -333.963863) (xy 111.519462 -333.973932)
			(xy 111.519462 -335.942686) (xy 111.52886 -335.965038) (xy 111.530871 -335.969543) (xy 111.536371 -335.97773)
			(xy 111.539782 -335.981294) (xy 111.552482 -335.993994) (xy 111.556053 -335.997395) (xy 111.564241 -336.002891)
			(xy 111.568738 -336.004916) (xy 111.59109 -336.014314) (xy 113.276634 -336.014314) (xy 113.303812 -336.002884)
			(xy 113.308254 -336.000862) (xy 113.316318 -335.995367) (xy 113.319814 -335.991962) (xy 113.354358 -335.957418)
			(xy 113.354866 -335.95691) (xy 113.361441 -335.949526) (xy 113.368877 -335.931227) (xy 113.369344 -335.92135)
			(xy 113.369344 -333.798926) (xy 113.369782 -333.788863) (xy 113.37752 -333.770282) (xy 113.38433 -333.762858)
			(xy 113.45545 -333.691738) (xy 113.462849 -333.684895) (xy 113.481448 -333.677173) (xy 113.491518 -333.676752)
			(xy 117.0051 -333.676752) (xy 117.007894 -333.674212) (xy 117.009672 -333.67599) (xy 117.278912 -333.67599)
			(xy 117.288789 -333.675531) (xy 117.307089 -333.668088) (xy 117.314472 -333.661512) (xy 117.564916 -333.411068)
			(xy 117.572312 -333.404217) (xy 117.590911 -333.396477) (xy 117.600984 -333.396082) (xy 119.102124 -333.396082)
			(xy 119.112193 -333.396509) (xy 119.130793 -333.404227) (xy 119.138192 -333.411068) (xy 119.664988 -333.937864)
			(xy 119.671825 -333.945266) (xy 119.679538 -333.963864) (xy 119.679974 -333.973932) (xy 119.679974 -335.92135)
			(xy 119.680406 -335.931417) (xy 119.68813 -335.95001) (xy 119.69496 -335.957418) (xy 119.73687 -335.999328)
			(xy 119.744269 -336.006171) (xy 119.762868 -336.013891) (xy 119.772938 -336.014314) (xy 121.437146 -336.014314)
			(xy 121.464324 -336.002884) (xy 121.468765 -336.000861) (xy 121.476828 -335.995365) (xy 121.480326 -335.991962)
			(xy 121.51487 -335.957418) (xy 121.515378 -335.95691) (xy 121.521952 -335.949526) (xy 121.529385 -335.931227)
			(xy 121.529856 -335.92135) (xy 121.529856 -333.798926) (xy 121.530294 -333.788863) (xy 121.538034 -333.770283)
			(xy 121.544842 -333.762858) (xy 121.615962 -333.691738) (xy 121.623362 -333.684897) (xy 121.641961 -333.677179)
			(xy 121.65203 -333.676752) (xy 125.165612 -333.676752) (xy 125.168406 -333.674212) (xy 125.170184 -333.67599)
			(xy 125.439424 -333.67599) (xy 125.449493 -333.676417) (xy 125.468092 -333.684136) (xy 125.475492 -333.690976)
			(xy 125.740668 -333.956152) (xy 125.74751 -333.963552) (xy 125.75523 -333.98215) (xy 125.755654 -333.99222)
			(xy 125.755654 -337.089496) (xy 125.756109 -337.099376) (xy 125.763542 -337.117684) (xy 125.770132 -337.125056)
			(xy 125.828552 -337.183476) (xy 125.82906 -337.183984) (xy 125.836443 -337.190562) (xy 125.854742 -337.198005)
			(xy 125.86462 -337.198462) (xy 126.22784 -337.198462) (xy 126.232158 -337.1977) (xy 126.253395 -337.194326)
			(xy 126.296253 -337.190765) (xy 126.317756 -337.190588) (xy 127.257302 -337.190588) (xy 127.278804 -337.190781)
			(xy 127.321661 -337.19434) (xy 127.3429 -337.1977) (xy 127.347218 -337.198462) (xy 127.654812 -337.198462)
			(xy 127.66488 -337.198889) (xy 127.683475 -337.206613) (xy 127.69088 -337.213448) (xy 127.8255 -337.348068)
			(xy 127.832336 -337.35547) (xy 127.840046 -337.374068) (xy 127.840486 -337.384136) (xy 127.840486 -339.281262)
			(xy 127.84092 -339.291328) (xy 127.848649 -339.309917) (xy 127.855472 -339.31733) (xy 127.880618 -339.342476)
			(xy 127.893826 -339.349334) (xy 127.9017 -339.350858) (xy 127.929713 -339.356541) (xy 127.984152 -339.373963)
			(xy 128.035993 -339.39804) (xy 128.06045 -339.412834) (xy 128.066292 -339.41639) (xy 128.086358 -339.422486)
			(xy 128.089899 -339.423452) (xy 128.097166 -339.424474) (xy 128.100836 -339.424518) (xy 129.597658 -339.424518)
			(xy 129.624836 -339.413088) (xy 129.629277 -339.411065) (xy 129.637338 -339.405567) (xy 129.640838 -339.402166)
			(xy 129.675382 -339.367622) (xy 129.67589 -339.367114) (xy 129.682463 -339.359729) (xy 129.689896 -339.341431)
			(xy 129.690368 -339.331554) (xy 129.690368 -337.20913) (xy 129.690872 -337.199079) (xy 129.69859 -337.180515)
			(xy 129.705354 -337.173062) (xy 129.776474 -337.101942) (xy 129.783874 -337.095103) (xy 129.802473 -337.087388)
			(xy 129.812542 -337.086956) (xy 133.701028 -337.086956) (xy 133.711095 -337.087386) (xy 133.729686 -337.095114)
			(xy 133.737096 -337.101942) (xy 133.901688 -337.266534) (xy 133.90853 -337.273934) (xy 133.916254 -337.292532)
			(xy 133.916674 -337.302602) (xy 133.916674 -342.511888) (xy 133.917146 -342.52176) (xy 133.924604 -342.540043)
			(xy 133.931152 -342.547448) (xy 133.965696 -342.581992) (xy 133.966204 -342.5825) (xy 133.973585 -342.58908)
			(xy 133.991885 -342.59652) (xy 134.001764 -342.596978) (xy 134.813802 -342.596978) (xy 134.82368 -342.59652)
			(xy 134.841981 -342.589079) (xy 134.849362 -342.5825) (xy 134.853172 -342.57869) (xy 134.856474 -342.581992)
			(xy 134.863876 -342.588827) (xy 134.882474 -342.596536) (xy 134.892542 -342.596978) (xy 135.423148 -342.596978)
			(xy 135.433215 -342.597409) (xy 135.451809 -342.605133) (xy 135.459216 -342.611964) (xy 135.986012 -343.13876)
			(xy 135.992858 -343.146158) (xy 136.000585 -343.164757) (xy 136.000998 -343.174828) (xy 136.000998 -345.143582)
			(xy 136.012428 -345.17076) (xy 136.014454 -345.175199) (xy 136.019955 -345.183257) (xy 136.02335 -345.186762)
			(xy 136.029446 -345.192858) (xy 136.032968 -345.196231) (xy 136.041025 -345.201725) (xy 136.045448 -345.20378)
			(xy 136.072626 -345.21521) (xy 137.75817 -345.21521) (xy 137.785348 -345.20378) (xy 137.789788 -345.201755)
			(xy 137.797848 -345.196256) (xy 137.80135 -345.192858) (xy 137.835894 -345.158314) (xy 137.836402 -345.157806)
			(xy 137.842984 -345.150425) (xy 137.850427 -345.132125) (xy 137.85088 -345.122246) (xy 137.85088 -342.999822)
			(xy 137.851317 -342.989758) (xy 137.859049 -342.971172) (xy 137.865866 -342.963754) (xy 137.936986 -342.892634)
			(xy 137.944387 -342.885797) (xy 137.962986 -342.878089) (xy 137.973054 -342.877648) (xy 142.363698 -342.877648)
			(xy 142.373767 -342.878072) (xy 142.392368 -342.885791) (xy 142.399766 -342.892634) (xy 142.783814 -343.276682)
			(xy 142.790657 -343.284081) (xy 142.798375 -343.30268) (xy 142.7988 -343.31275) (xy 142.7988 -343.493102)
			(xy 143.436068 -343.493102) (xy 143.436068 -343.433134) (xy 143.443896 -343.373678) (xy 143.459417 -343.315753)
			(xy 143.482366 -343.260349) (xy 143.51235 -343.208415) (xy 143.548856 -343.160839) (xy 143.591261 -343.118434)
			(xy 143.638837 -343.081928) (xy 143.690771 -343.051944) (xy 143.746175 -343.028995) (xy 143.8041 -343.013474)
			(xy 143.863556 -343.005646) (xy 143.923524 -343.005646) (xy 143.98298 -343.013474) (xy 144.040905 -343.028995)
			(xy 144.096309 -343.051944) (xy 144.148243 -343.081928) (xy 144.195819 -343.118434) (xy 144.238224 -343.160839)
			(xy 144.27473 -343.208415) (xy 144.304714 -343.260349) (xy 144.327663 -343.315753) (xy 144.343184 -343.373678)
			(xy 144.351012 -343.433134) (xy 144.351502 -343.463118) (xy 144.351012 -343.493102) (xy 144.34593 -343.531698)
			(xy 144.792698 -343.531698) (xy 144.796771 -343.476039) (xy 144.808906 -343.421566) (xy 144.828842 -343.36944)
			(xy 144.856156 -343.320772) (xy 144.890264 -343.2766) (xy 144.930441 -343.237865) (xy 144.975829 -343.205393)
			(xy 145.025461 -343.179875) (xy 145.078281 -343.161856) (xy 145.13316 -343.151719) (xy 145.188931 -343.149681)
			(xy 145.244405 -343.155784) (xy 145.298398 -343.1699) (xy 145.349761 -343.191727) (xy 145.397399 -343.2208)
			(xy 145.440295 -343.256499) (xy 145.477537 -343.298063) (xy 145.508331 -343.344607) (xy 145.532019 -343.395138)
			(xy 145.548097 -343.44858) (xy 145.556223 -343.503794) (xy 145.556732 -343.531698) (xy 145.556223 -343.559602)
			(xy 145.548097 -343.614816) (xy 145.532019 -343.668258) (xy 145.508331 -343.718789) (xy 145.477537 -343.765333)
			(xy 145.440295 -343.806897) (xy 145.397399 -343.842596) (xy 145.349761 -343.871669) (xy 145.298398 -343.893496)
			(xy 145.244405 -343.907612) (xy 145.188931 -343.913715) (xy 145.13316 -343.911677) (xy 145.078281 -343.90154)
			(xy 145.025461 -343.883521) (xy 144.975829 -343.858003) (xy 144.930441 -343.825531) (xy 144.890264 -343.786796)
			(xy 144.856156 -343.742624) (xy 144.828842 -343.693956) (xy 144.808906 -343.64183) (xy 144.796771 -343.587357)
			(xy 144.792698 -343.531698) (xy 144.34593 -343.531698) (xy 144.343184 -343.552558) (xy 144.327663 -343.610483)
			(xy 144.304714 -343.665887) (xy 144.27473 -343.717821) (xy 144.238224 -343.765397) (xy 144.195819 -343.807802)
			(xy 144.148243 -343.844308) (xy 144.096309 -343.874292) (xy 144.040905 -343.897241) (xy 143.98298 -343.912762)
			(xy 143.923524 -343.92059) (xy 143.863556 -343.92059) (xy 143.8041 -343.912762) (xy 143.746175 -343.897241)
			(xy 143.690771 -343.874292) (xy 143.638837 -343.844308) (xy 143.591261 -343.807802) (xy 143.548856 -343.765397)
			(xy 143.51235 -343.717821) (xy 143.482366 -343.665887) (xy 143.459417 -343.610483) (xy 143.443896 -343.552558)
			(xy 143.436068 -343.493102) (xy 142.7988 -343.493102) (xy 142.7988 -345.784932) (xy 144.561558 -345.784932)
			(xy 144.565631 -345.729273) (xy 144.577766 -345.6748) (xy 144.597702 -345.622674) (xy 144.625016 -345.574006)
			(xy 144.659124 -345.529834) (xy 144.699301 -345.491099) (xy 144.744689 -345.458627) (xy 144.794321 -345.433109)
			(xy 144.847141 -345.41509) (xy 144.90202 -345.404953) (xy 144.957791 -345.402915) (xy 145.013265 -345.409018)
			(xy 145.067258 -345.423134) (xy 145.118621 -345.444961) (xy 145.166259 -345.474034) (xy 145.209155 -345.509733)
			(xy 145.246397 -345.551297) (xy 145.277191 -345.597841) (xy 145.300879 -345.648372) (xy 145.316957 -345.701814)
			(xy 145.325083 -345.757028) (xy 145.325592 -345.784932) (xy 145.325083 -345.812836) (xy 145.316957 -345.86805)
			(xy 145.300879 -345.921492) (xy 145.277191 -345.972023) (xy 145.246397 -346.018567) (xy 145.209155 -346.060131)
			(xy 145.166259 -346.09583) (xy 145.118621 -346.124903) (xy 145.067258 -346.14673) (xy 145.013265 -346.160846)
			(xy 144.957791 -346.166949) (xy 144.90202 -346.164911) (xy 144.847141 -346.154774) (xy 144.794321 -346.136755)
			(xy 144.744689 -346.111237) (xy 144.699301 -346.078765) (xy 144.659124 -346.04003) (xy 144.625016 -345.995858)
			(xy 144.597702 -345.94719) (xy 144.577766 -345.895064) (xy 144.565631 -345.840591) (xy 144.561558 -345.784932)
			(xy 142.7988 -345.784932) (xy 142.7988 -350.016826) (xy 142.798372 -350.026894) (xy 142.790651 -350.045492)
			(xy 142.783814 -350.052894) (xy 142.442946 -350.393762) (xy 142.435546 -350.400604) (xy 142.416948 -350.408325)
			(xy 142.406878 -350.408748) (xy 127.407162 -350.408748) (xy 127.397096 -350.409179) (xy 127.378506 -350.416909)
			(xy 127.371094 -350.423734) (xy 127.36576 -350.429068) (xy 127.347218 -350.436688) (xy 126.205742 -350.436688)
			(xy 126.195676 -350.437121) (xy 126.177086 -350.444849) (xy 126.169674 -350.451674) (xy 125.440186 -351.181162)
			(xy 125.43334 -351.18856) (xy 125.425615 -351.207159) (xy 125.4252 -351.21723) (xy 125.4252 -360.680508)
			(xy 128.966466 -360.680508) (xy 128.970537 -360.624886) (xy 128.982663 -360.570449) (xy 129.002586 -360.518358)
			(xy 129.029882 -360.469723) (xy 129.063968 -360.42558) (xy 129.104117 -360.386871) (xy 129.149475 -360.35442)
			(xy 129.199075 -360.328919) (xy 129.251859 -360.310912) (xy 129.306702 -360.300782) (xy 129.362436 -360.298745)
			(xy 129.417873 -360.304845) (xy 129.47183 -360.318951) (xy 129.523159 -360.340763) (xy 129.570765 -360.369817)
			(xy 129.613633 -360.405492) (xy 129.65085 -360.447029) (xy 129.681623 -360.493542) (xy 129.705295 -360.544039)
			(xy 129.721363 -360.597446) (xy 129.729483 -360.652622) (xy 129.729992 -360.680508) (xy 129.729483 -360.708394)
			(xy 129.721363 -360.76357) (xy 129.705295 -360.816977) (xy 129.681623 -360.867474) (xy 129.65085 -360.913987)
			(xy 129.613633 -360.955524) (xy 129.570765 -360.991199) (xy 129.523159 -361.020253) (xy 129.47183 -361.042065)
			(xy 129.417873 -361.056171) (xy 129.362436 -361.062271) (xy 129.306702 -361.060234) (xy 129.251859 -361.050104)
			(xy 129.199075 -361.032097) (xy 129.149475 -361.006596) (xy 129.104117 -360.974145) (xy 129.063968 -360.935436)
			(xy 129.029882 -360.891293) (xy 129.002586 -360.842658) (xy 128.982663 -360.790567) (xy 128.970537 -360.73613)
			(xy 128.966466 -360.680508) (xy 125.4252 -360.680508) (xy 125.4252 -361.589066) (xy 125.424765 -361.599131)
			(xy 125.417033 -361.617718) (xy 125.410214 -361.625134) (xy 124.908298 -362.12705) (xy 128.009886 -362.12705)
			(xy 128.009886 -362.067082) (xy 128.017714 -362.007626) (xy 128.033235 -361.949701) (xy 128.056184 -361.894297)
			(xy 128.086168 -361.842363) (xy 128.122674 -361.794787) (xy 128.165079 -361.752382) (xy 128.212655 -361.715876)
			(xy 128.264589 -361.685892) (xy 128.319993 -361.662943) (xy 128.377918 -361.647422) (xy 128.437374 -361.639594)
			(xy 128.497342 -361.639594) (xy 128.556798 -361.647422) (xy 128.614723 -361.662943) (xy 128.670127 -361.685892)
			(xy 128.722061 -361.715876) (xy 128.769637 -361.752382) (xy 128.812042 -361.794787) (xy 128.848548 -361.842363)
			(xy 128.878532 -361.894297) (xy 128.901481 -361.949701) (xy 128.917002 -362.007626) (xy 128.92483 -362.067082)
			(xy 128.92532 -362.097066) (xy 128.92483 -362.12705) (xy 128.917002 -362.186506) (xy 128.901481 -362.244431)
			(xy 128.878532 -362.299835) (xy 128.848548 -362.351769) (xy 128.812042 -362.399345) (xy 128.769637 -362.44175)
			(xy 128.722061 -362.478256) (xy 128.670127 -362.50824) (xy 128.614723 -362.531189) (xy 128.556798 -362.54671)
			(xy 128.497342 -362.554538) (xy 128.437374 -362.554538) (xy 128.377918 -362.54671) (xy 128.319993 -362.531189)
			(xy 128.264589 -362.50824) (xy 128.212655 -362.478256) (xy 128.165079 -362.44175) (xy 128.122674 -362.399345)
			(xy 128.086168 -362.351769) (xy 128.056184 -362.299835) (xy 128.033235 -362.244431) (xy 128.017714 -362.186506)
			(xy 128.009886 -362.12705) (xy 124.908298 -362.12705) (xy 124.255022 -362.780326) (xy 124.247623 -362.787168)
			(xy 124.229024 -362.794886) (xy 124.218954 -362.795312) (xy 120.794018 -362.795312) (xy 120.783955 -362.79575)
			(xy 120.765373 -362.803487) (xy 120.75795 -362.810298) (xy 120.336564 -363.231684) (xy 120.329724 -363.239084)
			(xy 120.32201 -363.257683) (xy 120.321578 -363.267752) (xy 120.321578 -366.154208) (xy 120.322002 -366.164278)
			(xy 120.329716 -366.182883) (xy 120.336564 -366.190276) (xy 120.823736 -366.677448)
		)
		(stroke
			(width 0)
			(type solid)
		)
		(fill yes)
		(layer "B.Cu")
		(net "GND")
	)
	(gr_poly
		(pts
			(xy 192.072768 -33.215326) (xy 192.072768 -25.158192) (xy 192.072258 -25.143352) (xy 192.063731 -25.114922)
			(xy 192.047397 -25.090139) (xy 192.024633 -25.071093) (xy 191.997357 -25.059387) (xy 191.967869 -25.056009)
			(xy 191.938653 -25.061243) (xy 191.925194 -25.067514) (xy 191.901165 -25.079202) (xy 191.850972 -25.097536)
			(xy 191.798988 -25.109911) (xy 191.745918 -25.116158) (xy 191.7192 -25.116536) (xy 191.689231 -25.116046)
			(xy 191.629804 -25.108222) (xy 191.571908 -25.092709) (xy 191.516531 -25.069771) (xy 191.464623 -25.039802)
			(xy 191.41707 -25.003313) (xy 191.374687 -24.96093) (xy 191.338198 -24.913377) (xy 191.308229 -24.861469)
			(xy 191.285291 -24.806092) (xy 191.269778 -24.748196) (xy 191.261954 -24.688769) (xy 191.261954 -24.628831)
			(xy 191.269778 -24.569404) (xy 191.285291 -24.511508) (xy 191.308229 -24.456131) (xy 191.338198 -24.404223)
			(xy 191.374687 -24.35667) (xy 191.41707 -24.314287) (xy 191.464623 -24.277798) (xy 191.516531 -24.247829)
			(xy 191.571908 -24.224891) (xy 191.629804 -24.209378) (xy 191.689231 -24.201554) (xy 191.7192 -24.20112)
			(xy 191.749045 -24.201621) (xy 191.808224 -24.209417) (xy 191.865889 -24.224836) (xy 191.921061 -24.247618)
			(xy 191.972804 -24.277376) (xy 191.996822 -24.2951) (xy 192.007964 -24.303006) (xy 192.033314 -24.313164)
			(xy 192.060449 -24.316244) (xy 192.087431 -24.312025) (xy 192.112331 -24.30081) (xy 192.133371 -24.283399)
			(xy 192.141602 -24.272494) (xy 192.156971 -24.251332) (xy 192.192575 -24.21302) (xy 192.233083 -24.179938)
			(xy 192.277736 -24.152706) (xy 192.325693 -24.131837) (xy 192.376053 -24.117722) (xy 192.427871 -24.110627)
			(xy 192.454022 -24.110188) (xy 192.818004 -24.110188) (xy 192.818004 -23.945342) (xy 192.817483 -23.931025)
			(xy 192.80947 -23.903532) (xy 192.794146 -23.87934) (xy 192.772714 -23.860348) (xy 192.746854 -23.848045)
			(xy 192.718597 -23.843398) (xy 192.690159 -23.846771) (xy 192.663773 -23.8579) (xy 192.652396 -23.866602)
			(xy 192.627835 -23.885785) (xy 192.574507 -23.918036) (xy 192.517299 -23.942759) (xy 192.457267 -23.959496)
			(xy 192.395521 -23.967941) (xy 192.36436 -23.968456) (xy 192.334391 -23.967963) (xy 192.274966 -23.960135)
			(xy 192.217071 -23.944618) (xy 192.161697 -23.921677) (xy 192.109791 -23.891705) (xy 192.06224 -23.855214)
			(xy 192.01986 -23.812829) (xy 191.983373 -23.765276) (xy 191.953406 -23.713367) (xy 191.930469 -23.657991)
			(xy 191.914957 -23.600095) (xy 191.907134 -23.540669) (xy 191.907134 -23.480731) (xy 191.914957 -23.421305)
			(xy 191.930469 -23.363409) (xy 191.953406 -23.308033) (xy 191.983373 -23.256124) (xy 192.01986 -23.208571)
			(xy 192.06224 -23.166186) (xy 192.109791 -23.129695) (xy 192.161697 -23.099723) (xy 192.217071 -23.076782)
			(xy 192.274966 -23.061265) (xy 192.334391 -23.053437) (xy 192.36436 -23.05304) (xy 192.394253 -23.053529)
			(xy 192.45353 -23.061322) (xy 192.511287 -23.076768) (xy 192.566541 -23.099603) (xy 192.618351 -23.129438)
			(xy 192.665835 -23.165766) (xy 192.708184 -23.207968) (xy 192.726818 -23.231348) (xy 192.742058 -23.25116)
			(xy 192.818004 -23.25116) (xy 192.818004 -23.09749) (xy 192.671192 -22.950932) (xy 192.650414 -22.929317)
			(xy 192.615177 -22.880811) (xy 192.587959 -22.827392) (xy 192.569428 -22.770375) (xy 192.56004 -22.711161)
			(xy 192.559432 -22.681184) (xy 192.559432 -21.082254) (xy 192.559986 -21.052272) (xy 192.569361 -20.993046)
			(xy 192.58789 -20.936016) (xy 192.615115 -20.882589) (xy 192.650366 -20.834081) (xy 192.671192 -20.812506)
			(xy 193.152522 -20.33143) (xy 193.162747 -20.320452) (xy 193.176882 -20.294007) (xy 193.182728 -20.264597)
			(xy 193.179784 -20.234757) (xy 193.168302 -20.207057) (xy 193.149271 -20.183885) (xy 193.124332 -20.167236)
			(xy 193.095633 -20.158547) (xy 193.08064 -20.157948) (xy 192.96634 -20.157948) (xy 192.946321 -20.174765)
			(xy 192.901901 -20.202333) (xy 192.877948 -20.212812) (xy 191.839088 -20.643342) (xy 191.765682 -20.716748)
			(xy 191.765682 -21.580348) (xy 190.770256 -22.575774) (xy 190.800228 -22.611334) (xy 190.817088 -22.632044)
			(xy 190.845459 -22.677288) (xy 190.867239 -22.726048) (xy 190.882003 -22.77737) (xy 190.889461 -22.83025)
			(xy 190.88989 -22.856952) (xy 190.889407 -22.884527) (xy 190.88147 -22.939103) (xy 190.865755 -22.991967)
			(xy 190.84259 -23.042017) (xy 190.812458 -23.088208) (xy 190.775987 -23.129577) (xy 190.75527 -23.147782)
			(xy 190.744369 -23.157682) (xy 190.728288 -23.182337) (xy 190.719896 -23.210551) (xy 190.719887 -23.239987)
			(xy 190.728262 -23.268206) (xy 190.744327 -23.292871) (xy 190.75527 -23.302722) (xy 190.775975 -23.320939)
			(xy 190.812437 -23.362311) (xy 190.842564 -23.408501) (xy 190.865728 -23.458548) (xy 190.881447 -23.511407)
			(xy 190.889392 -23.565979) (xy 190.88989 -23.593552) (xy 190.889404 -23.620803) (xy 190.881648 -23.674751)
			(xy 190.866293 -23.727046) (xy 190.843651 -23.776623) (xy 190.814185 -23.822473) (xy 190.778494 -23.863664)
			(xy 190.737303 -23.899355) (xy 190.691453 -23.928821) (xy 190.641876 -23.951463) (xy 190.589581 -23.966818)
			(xy 190.535633 -23.974574) (xy 190.481131 -23.974574) (xy 190.427183 -23.966818) (xy 190.374888 -23.951463)
			(xy 190.325311 -23.928821) (xy 190.279461 -23.899355) (xy 190.23827 -23.863664) (xy 190.202579 -23.822473)
			(xy 190.173113 -23.776623) (xy 190.150471 -23.727046) (xy 190.135116 -23.674751) (xy 190.12736 -23.620803)
			(xy 190.126874 -23.593552) (xy 190.127357 -23.565976) (xy 190.135293 -23.511399) (xy 190.151006 -23.458534)
			(xy 190.174169 -23.408483) (xy 190.204299 -23.362289) (xy 190.240768 -23.320917) (xy 190.261494 -23.302722)
			(xy 190.272385 -23.292824) (xy 190.288444 -23.268178) (xy 190.296817 -23.239977) (xy 190.296808 -23.210561)
			(xy 190.288418 -23.182366) (xy 190.272343 -23.157729) (xy 190.261494 -23.147782) (xy 190.243812 -23.13233)
			(xy 190.211967 -23.09782) (xy 190.197994 -23.078948) (xy 188.373004 -23.078948) (xy 188.37275 -23.129494)
			(xy 188.372117 -23.159364) (xy 188.364047 -23.218562) (xy 188.348344 -23.276207) (xy 188.325274 -23.331319)
			(xy 188.295229 -23.382961) (xy 188.25872 -23.430254) (xy 188.216368 -23.472395) (xy 188.168893 -23.508667)
			(xy 188.117102 -23.538454) (xy 188.061876 -23.561249) (xy 188.004153 -23.576664) (xy 187.944915 -23.584438)
			(xy 187.885169 -23.584438) (xy 187.825931 -23.576664) (xy 187.768208 -23.561249) (xy 187.712982 -23.538454)
			(xy 187.661191 -23.508667) (xy 187.613716 -23.472395) (xy 187.571364 -23.430254) (xy 187.534855 -23.382961)
			(xy 187.50481 -23.331319) (xy 187.48174 -23.276207) (xy 187.466037 -23.218562) (xy 187.457967 -23.159364)
			(xy 187.457334 -23.129494) (xy 187.45708 -23.078948) (xy 185.172858 -23.078948) (xy 185.170572 -23.127462)
			(xy 185.168898 -23.153858) (xy 185.159177 -23.205847) (xy 185.142369 -23.255995) (xy 185.118796 -23.303341)
			(xy 185.08891 -23.346978) (xy 185.053284 -23.38607) (xy 185.012601 -23.419867) (xy 184.96764 -23.447721)
			(xy 184.919263 -23.469099) (xy 184.868397 -23.483591) (xy 184.816017 -23.490919) (xy 184.789572 -23.491444)
			(xy 184.761048 -23.490911) (xy 184.704636 -23.482412) (xy 184.650118 -23.465609) (xy 184.59871 -23.440876)
			(xy 184.551558 -23.408765) (xy 184.509712 -23.36999) (xy 184.474106 -23.325417) (xy 184.445533 -23.27604)
			(xy 184.424631 -23.222959) (xy 184.417716 -23.19528) (xy 184.415363 -23.186518) (xy 184.405456 -23.171334)
			(xy 184.39087 -23.160565) (xy 184.373442 -23.155569) (xy 184.364376 -23.15591) (xy 184.3405 -23.156672)
			(xy 182.77078 -23.156672) (xy 182.485284 -23.442168) (xy 182.485284 -24.15692) (xy 186.428362 -24.15692)
			(xy 186.428362 -24.096984) (xy 186.436185 -24.037562) (xy 186.451698 -23.979669) (xy 186.474634 -23.924296)
			(xy 186.504601 -23.87239) (xy 186.541088 -23.82484) (xy 186.583468 -23.78246) (xy 186.631018 -23.745973)
			(xy 186.682924 -23.716006) (xy 186.738297 -23.69307) (xy 186.79619 -23.677557) (xy 186.855612 -23.669734)
			(xy 186.915548 -23.669734) (xy 186.97497 -23.677557) (xy 187.032863 -23.69307) (xy 187.088236 -23.716006)
			(xy 187.140142 -23.745973) (xy 187.187692 -23.78246) (xy 187.230072 -23.82484) (xy 187.266559 -23.87239)
			(xy 187.296526 -23.924296) (xy 187.319462 -23.979669) (xy 187.334975 -24.037562) (xy 187.338784 -24.066496)
			(xy 188.781672 -24.066496) (xy 188.781672 -24.00656) (xy 188.789495 -23.947138) (xy 188.805008 -23.889245)
			(xy 188.827944 -23.833872) (xy 188.857911 -23.781966) (xy 188.894398 -23.734416) (xy 188.936778 -23.692036)
			(xy 188.984328 -23.655549) (xy 189.036234 -23.625582) (xy 189.091607 -23.602646) (xy 189.1495 -23.587133)
			(xy 189.208922 -23.57931) (xy 189.268858 -23.57931) (xy 189.32828 -23.587133) (xy 189.386173 -23.602646)
			(xy 189.441546 -23.625582) (xy 189.493452 -23.655549) (xy 189.541002 -23.692036) (xy 189.583382 -23.734416)
			(xy 189.619869 -23.781966) (xy 189.649836 -23.833872) (xy 189.672772 -23.889245) (xy 189.688285 -23.947138)
			(xy 189.696108 -24.00656) (xy 189.696598 -24.036528) (xy 189.696108 -24.066496) (xy 189.688285 -24.125918)
			(xy 189.672772 -24.183811) (xy 189.649836 -24.239184) (xy 189.619869 -24.29109) (xy 189.583382 -24.33864)
			(xy 189.541002 -24.38102) (xy 189.493452 -24.417507) (xy 189.441546 -24.447474) (xy 189.386173 -24.47041)
			(xy 189.32828 -24.485923) (xy 189.268858 -24.493746) (xy 189.208922 -24.493746) (xy 189.1495 -24.485923)
			(xy 189.091607 -24.47041) (xy 189.036234 -24.447474) (xy 188.984328 -24.417507) (xy 188.936778 -24.38102)
			(xy 188.894398 -24.33864) (xy 188.857911 -24.29109) (xy 188.827944 -24.239184) (xy 188.805008 -24.183811)
			(xy 188.789495 -24.125918) (xy 188.781672 -24.066496) (xy 187.338784 -24.066496) (xy 187.342798 -24.096984)
			(xy 187.343288 -24.126952) (xy 187.342798 -24.15692) (xy 187.334975 -24.216342) (xy 187.319462 -24.274235)
			(xy 187.296526 -24.329608) (xy 187.266559 -24.381514) (xy 187.230072 -24.429064) (xy 187.187692 -24.471444)
			(xy 187.140142 -24.507931) (xy 187.088236 -24.537898) (xy 187.032863 -24.560834) (xy 186.97497 -24.576347)
			(xy 186.915548 -24.58417) (xy 186.855612 -24.58417) (xy 186.79619 -24.576347) (xy 186.738297 -24.560834)
			(xy 186.682924 -24.537898) (xy 186.631018 -24.507931) (xy 186.583468 -24.471444) (xy 186.541088 -24.429064)
			(xy 186.504601 -24.381514) (xy 186.474634 -24.329608) (xy 186.451698 -24.274235) (xy 186.436185 -24.216342)
			(xy 186.428362 -24.15692) (xy 182.485284 -24.15692) (xy 182.485284 -25.852116) (xy 186.669662 -25.852116)
			(xy 186.669662 -25.79218) (xy 186.677485 -25.732758) (xy 186.692998 -25.674865) (xy 186.715934 -25.619492)
			(xy 186.745901 -25.567586) (xy 186.782388 -25.520036) (xy 186.824768 -25.477656) (xy 186.872318 -25.441169)
			(xy 186.924224 -25.411202) (xy 186.979597 -25.388266) (xy 187.03749 -25.372753) (xy 187.096912 -25.36493)
			(xy 187.156848 -25.36493) (xy 187.21627 -25.372753) (xy 187.274163 -25.388266) (xy 187.329536 -25.411202)
			(xy 187.381442 -25.441169) (xy 187.428992 -25.477656) (xy 187.471372 -25.520036) (xy 187.507859 -25.567586)
			(xy 187.537826 -25.619492) (xy 187.560762 -25.674865) (xy 187.576275 -25.732758) (xy 187.584098 -25.79218)
			(xy 187.584588 -25.822148) (xy 187.584098 -25.852116) (xy 187.576275 -25.911538) (xy 187.560762 -25.969431)
			(xy 187.537826 -26.024804) (xy 187.507859 -26.07671) (xy 187.471372 -26.12426) (xy 187.428992 -26.16664)
			(xy 187.381442 -26.203127) (xy 187.329536 -26.233094) (xy 187.274163 -26.25603) (xy 187.21627 -26.271543)
			(xy 187.156848 -26.279366) (xy 187.096912 -26.279366) (xy 187.03749 -26.271543) (xy 186.979597 -26.25603)
			(xy 186.924224 -26.233094) (xy 186.872318 -26.203127) (xy 186.824768 -26.16664) (xy 186.782388 -26.12426)
			(xy 186.745901 -26.07671) (xy 186.715934 -26.024804) (xy 186.692998 -25.969431) (xy 186.677485 -25.911538)
			(xy 186.669662 -25.852116) (xy 182.485284 -25.852116) (xy 182.485284 -27.013916) (xy 182.484817 -27.038986)
			(xy 182.47697 -27.088509) (xy 182.461472 -27.136194) (xy 182.438704 -27.180868) (xy 182.409228 -27.221429)
			(xy 182.391812 -27.239468) (xy 182.070822 -27.56052) (xy 184.945764 -27.56052) (xy 184.945764 -27.500584)
			(xy 184.953587 -27.441162) (xy 184.9691 -27.383269) (xy 184.992036 -27.327896) (xy 185.022003 -27.27599)
			(xy 185.05849 -27.22844) (xy 185.10087 -27.18606) (xy 185.14842 -27.149573) (xy 185.200326 -27.119606)
			(xy 185.255699 -27.09667) (xy 185.313592 -27.081157) (xy 185.373014 -27.073334) (xy 185.43295 -27.073334)
			(xy 185.492372 -27.081157) (xy 185.550265 -27.09667) (xy 185.599433 -27.117036) (xy 190.220582 -27.117036)
			(xy 190.220582 -27.0571) (xy 190.228405 -26.997678) (xy 190.243918 -26.939785) (xy 190.266854 -26.884412)
			(xy 190.296821 -26.832506) (xy 190.333308 -26.784956) (xy 190.375688 -26.742576) (xy 190.423238 -26.706089)
			(xy 190.475144 -26.676122) (xy 190.530517 -26.653186) (xy 190.58841 -26.637673) (xy 190.647832 -26.62985)
			(xy 190.707768 -26.62985) (xy 190.76719 -26.637673) (xy 190.825083 -26.653186) (xy 190.880456 -26.676122)
			(xy 190.932362 -26.706089) (xy 190.979912 -26.742576) (xy 191.022292 -26.784956) (xy 191.058779 -26.832506)
			(xy 191.088746 -26.884412) (xy 191.111682 -26.939785) (xy 191.127195 -26.997678) (xy 191.135018 -27.0571)
			(xy 191.135508 -27.087068) (xy 191.135018 -27.117036) (xy 191.127195 -27.176458) (xy 191.111682 -27.234351)
			(xy 191.088746 -27.289724) (xy 191.058779 -27.34163) (xy 191.022292 -27.38918) (xy 190.979912 -27.43156)
			(xy 190.932362 -27.468047) (xy 190.880456 -27.498014) (xy 190.825083 -27.52095) (xy 190.76719 -27.536463)
			(xy 190.707768 -27.544286) (xy 190.647832 -27.544286) (xy 190.58841 -27.536463) (xy 190.530517 -27.52095)
			(xy 190.475144 -27.498014) (xy 190.423238 -27.468047) (xy 190.375688 -27.43156) (xy 190.333308 -27.38918)
			(xy 190.296821 -27.34163) (xy 190.266854 -27.289724) (xy 190.243918 -27.234351) (xy 190.228405 -27.176458)
			(xy 190.220582 -27.117036) (xy 185.599433 -27.117036) (xy 185.605638 -27.119606) (xy 185.657544 -27.149573)
			(xy 185.705094 -27.18606) (xy 185.747474 -27.22844) (xy 185.783961 -27.27599) (xy 185.813928 -27.327896)
			(xy 185.836864 -27.383269) (xy 185.852377 -27.441162) (xy 185.8602 -27.500584) (xy 185.86069 -27.530552)
			(xy 185.8602 -27.56052) (xy 185.852377 -27.619942) (xy 185.844206 -27.650436) (xy 187.835014 -27.650436)
			(xy 187.835014 -27.5905) (xy 187.842837 -27.531078) (xy 187.85835 -27.473185) (xy 187.881286 -27.417812)
			(xy 187.911253 -27.365906) (xy 187.94774 -27.318356) (xy 187.99012 -27.275976) (xy 188.03767 -27.239489)
			(xy 188.089576 -27.209522) (xy 188.144949 -27.186586) (xy 188.202842 -27.171073) (xy 188.262264 -27.16325)
			(xy 188.3222 -27.16325) (xy 188.381622 -27.171073) (xy 188.439515 -27.186586) (xy 188.494888 -27.209522)
			(xy 188.546794 -27.239489) (xy 188.594344 -27.275976) (xy 188.636724 -27.318356) (xy 188.673211 -27.365906)
			(xy 188.703178 -27.417812) (xy 188.726114 -27.473185) (xy 188.741627 -27.531078) (xy 188.747711 -27.577288)
			(xy 189.414402 -27.577288) (xy 189.418473 -27.521666) (xy 189.430599 -27.467229) (xy 189.450522 -27.415138)
			(xy 189.477818 -27.366503) (xy 189.511904 -27.32236) (xy 189.552053 -27.283651) (xy 189.597411 -27.2512)
			(xy 189.647011 -27.225699) (xy 189.699795 -27.207692) (xy 189.754638 -27.197562) (xy 189.810372 -27.195525)
			(xy 189.865809 -27.201625) (xy 189.919766 -27.215731) (xy 189.971095 -27.237543) (xy 190.018701 -27.266597)
			(xy 190.061569 -27.302272) (xy 190.098786 -27.343809) (xy 190.129559 -27.390322) (xy 190.153231 -27.440819)
			(xy 190.169299 -27.494226) (xy 190.177419 -27.549402) (xy 190.177928 -27.577288) (xy 190.177419 -27.605174)
			(xy 190.169299 -27.66035) (xy 190.153231 -27.713757) (xy 190.129559 -27.764254) (xy 190.098786 -27.810767)
			(xy 190.061569 -27.852304) (xy 190.018701 -27.887979) (xy 189.971095 -27.917033) (xy 189.919766 -27.938845)
			(xy 189.865809 -27.952951) (xy 189.810372 -27.959051) (xy 189.754638 -27.957014) (xy 189.699795 -27.946884)
			(xy 189.647011 -27.928877) (xy 189.597411 -27.903376) (xy 189.552053 -27.870925) (xy 189.511904 -27.832216)
			(xy 189.477818 -27.788073) (xy 189.450522 -27.739438) (xy 189.430599 -27.687347) (xy 189.418473 -27.63291)
			(xy 189.414402 -27.577288) (xy 188.747711 -27.577288) (xy 188.74945 -27.5905) (xy 188.74994 -27.620468)
			(xy 188.74945 -27.650436) (xy 188.741627 -27.709858) (xy 188.726114 -27.767751) (xy 188.703178 -27.823124)
			(xy 188.673211 -27.87503) (xy 188.636724 -27.92258) (xy 188.594344 -27.96496) (xy 188.546794 -28.001447)
			(xy 188.494888 -28.031414) (xy 188.439515 -28.05435) (xy 188.381622 -28.069863) (xy 188.3222 -28.077686)
			(xy 188.262264 -28.077686) (xy 188.202842 -28.069863) (xy 188.144949 -28.05435) (xy 188.089576 -28.031414)
			(xy 188.03767 -28.001447) (xy 187.99012 -27.96496) (xy 187.94774 -27.92258) (xy 187.911253 -27.87503)
			(xy 187.881286 -27.823124) (xy 187.85835 -27.767751) (xy 187.842837 -27.709858) (xy 187.835014 -27.650436)
			(xy 185.844206 -27.650436) (xy 185.836864 -27.677835) (xy 185.813928 -27.733208) (xy 185.783961 -27.785114)
			(xy 185.747474 -27.832664) (xy 185.705094 -27.875044) (xy 185.657544 -27.911531) (xy 185.605638 -27.941498)
			(xy 185.550265 -27.964434) (xy 185.492372 -27.979947) (xy 185.43295 -27.98777) (xy 185.373014 -27.98777)
			(xy 185.313592 -27.979947) (xy 185.255699 -27.964434) (xy 185.200326 -27.941498) (xy 185.14842 -27.911531)
			(xy 185.10087 -27.875044) (xy 185.05849 -27.832664) (xy 185.022003 -27.785114) (xy 184.992036 -27.733208)
			(xy 184.9691 -27.677835) (xy 184.953587 -27.619942) (xy 184.945764 -27.56052) (xy 182.070822 -27.56052)
			(xy 181.069234 -28.5623) (xy 181.059938 -28.572196) (xy 181.046473 -28.595761) (xy 181.03969 -28.622041)
			(xy 181.040069 -28.64918) (xy 181.047581 -28.67526) (xy 181.061697 -28.698441) (xy 181.081421 -28.717086)
			(xy 181.105358 -28.729878) (xy 181.11851 -28.733242) (xy 181.14731 -28.740352) (xy 181.202433 -28.762263)
			(xy 181.253505 -28.792434) (xy 181.299299 -28.830138) (xy 181.338713 -28.874468) (xy 181.355238 -28.899104)
			(xy 181.363519 -28.911031) (xy 181.385455 -28.930035) (xy 181.411855 -28.94209) (xy 181.440582 -28.94622)
			(xy 181.469309 -28.94209) (xy 181.495709 -28.930035) (xy 181.517645 -28.911031) (xy 181.525926 -28.899104)
			(xy 181.541081 -28.876442) (xy 181.576794 -28.835252) (xy 181.618002 -28.79956) (xy 181.663868 -28.770091)
			(xy 181.713458 -28.747445) (xy 181.765764 -28.73208) (xy 181.819724 -28.724311) (xy 181.846982 -28.723844)
			(xy 181.874235 -28.724329) (xy 181.928188 -28.732083) (xy 181.980487 -28.747436) (xy 182.03007 -28.770075)
			(xy 182.075926 -28.79954) (xy 182.117122 -28.835231) (xy 182.15282 -28.876421) (xy 182.182293 -28.922272)
			(xy 182.204941 -28.971851) (xy 182.220303 -29.024148) (xy 182.228067 -29.078099) (xy 182.22849 -29.105352)
			(xy 182.228007 -29.132927) (xy 182.22007 -29.187503) (xy 182.204355 -29.240367) (xy 182.18119 -29.290417)
			(xy 182.151058 -29.336608) (xy 182.114587 -29.377977) (xy 182.09387 -29.396182) (xy 182.082969 -29.406082)
			(xy 182.066888 -29.430737) (xy 182.058496 -29.458951) (xy 182.058487 -29.488387) (xy 182.066862 -29.516606)
			(xy 182.080244 -29.537152) (xy 189.618364 -29.537152) (xy 189.622435 -29.48153) (xy 189.634561 -29.427093)
			(xy 189.654484 -29.375002) (xy 189.68178 -29.326367) (xy 189.715866 -29.282224) (xy 189.756015 -29.243515)
			(xy 189.801373 -29.211064) (xy 189.850973 -29.185563) (xy 189.903757 -29.167556) (xy 189.9586 -29.157426)
			(xy 190.014334 -29.155389) (xy 190.069771 -29.161489) (xy 190.123728 -29.175595) (xy 190.175057 -29.197407)
			(xy 190.222663 -29.226461) (xy 190.265531 -29.262136) (xy 190.302748 -29.303673) (xy 190.333521 -29.350186)
			(xy 190.357193 -29.400683) (xy 190.373261 -29.45409) (xy 190.381381 -29.509266) (xy 190.38189 -29.537152)
			(xy 190.381381 -29.565038) (xy 190.373261 -29.620214) (xy 190.357193 -29.673621) (xy 190.333521 -29.724118)
			(xy 190.302748 -29.770631) (xy 190.265531 -29.812168) (xy 190.222663 -29.847843) (xy 190.175057 -29.876897)
			(xy 190.123728 -29.898709) (xy 190.069771 -29.912815) (xy 190.014334 -29.918915) (xy 189.9586 -29.916878)
			(xy 189.903757 -29.906748) (xy 189.850973 -29.888741) (xy 189.801373 -29.86324) (xy 189.756015 -29.830789)
			(xy 189.715866 -29.79208) (xy 189.68178 -29.747937) (xy 189.654484 -29.699302) (xy 189.634561 -29.647211)
			(xy 189.622435 -29.592774) (xy 189.618364 -29.537152) (xy 182.080244 -29.537152) (xy 182.082927 -29.541271)
			(xy 182.09387 -29.551122) (xy 182.114575 -29.569339) (xy 182.151037 -29.610711) (xy 182.181164 -29.656901)
			(xy 182.204328 -29.706948) (xy 182.220047 -29.759807) (xy 182.227992 -29.814379) (xy 182.22849 -29.841952)
			(xy 182.22803 -29.869207) (xy 182.220278 -29.923162) (xy 182.204926 -29.975464) (xy 182.182286 -30.025049)
			(xy 182.152819 -30.070907) (xy 182.117125 -30.112104) (xy 182.075931 -30.147801) (xy 182.030076 -30.177272)
			(xy 181.980493 -30.199916) (xy 181.928191 -30.215272) (xy 181.874237 -30.223028) (xy 181.846982 -30.22346)
			(xy 181.819725 -30.222973) (xy 181.765765 -30.215213) (xy 181.713459 -30.199855) (xy 181.66387 -30.17721)
			(xy 181.618008 -30.14774) (xy 181.576805 -30.112044) (xy 181.541102 -30.070848) (xy 181.525926 -30.0482)
			(xy 181.517645 -30.036273) (xy 181.495709 -30.017269) (xy 181.469309 -30.005214) (xy 181.440582 -30.001084)
			(xy 181.411855 -30.005214) (xy 181.385455 -30.017269) (xy 181.363519 -30.036273) (xy 181.355238 -30.0482)
			(xy 181.340083 -30.070861) (xy 181.304368 -30.112046) (xy 181.263159 -30.147734) (xy 181.217293 -30.177198)
			(xy 181.167703 -30.19984) (xy 181.115397 -30.215199) (xy 181.061439 -30.222964) (xy 181.034182 -30.22346)
			(xy 181.007 -30.222977) (xy 180.953186 -30.215256) (xy 180.901013 -30.199973) (xy 180.851539 -30.177438)
			(xy 180.805766 -30.148107) (xy 180.76462 -30.112574) (xy 180.7464 -30.092396) (xy 180.737053 -30.082333)
			(xy 180.71417 -30.067165) (xy 180.688073 -30.05864) (xy 180.660649 -30.057376) (xy 180.633878 -30.063463)
			(xy 180.609696 -30.076461) (xy 180.589851 -30.095431) (xy 180.575775 -30.119002) (xy 180.568488 -30.145471)
			(xy 180.568092 -30.159198) (xy 180.568092 -30.25775) (xy 181.957596 -31.647254) (xy 182.48193 -31.647254)
			(xy 182.48193 -31.592746) (xy 182.489687 -31.538793) (xy 182.505043 -31.486493) (xy 182.527686 -31.436911)
			(xy 182.557154 -31.391056) (xy 182.592848 -31.349861) (xy 182.634041 -31.314165) (xy 182.679895 -31.284694)
			(xy 182.729476 -31.262049) (xy 182.781776 -31.246691) (xy 182.835728 -31.238931) (xy 182.862982 -31.238444)
			(xy 182.890239 -31.238938) (xy 182.944198 -31.246703) (xy 182.996504 -31.262062) (xy 183.046093 -31.284705)
			(xy 183.091959 -31.314169) (xy 183.133168 -31.349857) (xy 183.168883 -31.391043) (xy 183.184038 -31.413704)
			(xy 183.192319 -31.425631) (xy 183.214255 -31.444635) (xy 183.240655 -31.45669) (xy 183.269382 -31.46082)
			(xy 183.298109 -31.45669) (xy 183.324509 -31.444635) (xy 183.346445 -31.425631) (xy 183.354726 -31.413704)
			(xy 183.369903 -31.391057) (xy 183.405606 -31.349861) (xy 183.446808 -31.314165) (xy 183.49267 -31.284694)
			(xy 183.542259 -31.262049) (xy 183.594565 -31.246691) (xy 183.648525 -31.238931) (xy 183.675782 -31.238444)
			(xy 183.703032 -31.239002) (xy 183.756978 -31.246756) (xy 183.809272 -31.262108) (xy 183.858848 -31.284747)
			(xy 183.904698 -31.314211) (xy 183.945887 -31.3499) (xy 183.981578 -31.391088) (xy 184.011044 -31.436936)
			(xy 184.033685 -31.486511) (xy 184.04904 -31.538804) (xy 184.056797 -31.59275) (xy 184.056797 -31.64725)
			(xy 184.04904 -31.701196) (xy 184.033685 -31.753489) (xy 184.011044 -31.803064) (xy 183.981578 -31.848912)
			(xy 183.945887 -31.8901) (xy 183.904698 -31.925789) (xy 183.858848 -31.955253) (xy 183.809272 -31.977892)
			(xy 183.756978 -31.993244) (xy 183.703032 -32.000998) (xy 183.675782 -32.00146) (xy 183.648524 -32.000991)
			(xy 183.594564 -31.993222) (xy 183.542258 -31.977858) (xy 183.492668 -31.955211) (xy 183.446803 -31.925743)
			(xy 183.405595 -31.890051) (xy 183.369881 -31.848862) (xy 183.354726 -31.8262) (xy 183.346445 -31.814273)
			(xy 183.324509 -31.795269) (xy 183.298109 -31.783214) (xy 183.269382 -31.779084) (xy 183.240655 -31.783214)
			(xy 183.214255 -31.795269) (xy 183.192319 -31.814273) (xy 183.184038 -31.8262) (xy 183.168886 -31.848864)
			(xy 183.133178 -31.89006) (xy 183.091972 -31.925755) (xy 183.046106 -31.955224) (xy 182.996513 -31.977866)
			(xy 182.944203 -31.99322) (xy 182.890241 -32.000975) (xy 182.862982 -32.00146) (xy 182.835728 -32.001069)
			(xy 182.781776 -31.993309) (xy 182.729476 -31.977951) (xy 182.679895 -31.955306) (xy 182.634041 -31.925835)
			(xy 182.592848 -31.890139) (xy 182.557154 -31.848944) (xy 182.527686 -31.803089) (xy 182.505043 -31.753507)
			(xy 182.489687 -31.701207) (xy 182.48193 -31.647254) (xy 181.957596 -31.647254) (xy 183.37403 -33.063688)
			(xy 183.606948 -33.063688) (xy 183.632017 -33.064158) (xy 183.681535 -33.072011) (xy 183.729215 -33.087516)
			(xy 183.773882 -33.11029) (xy 183.814435 -33.139773) (xy 183.8325 -33.15716) (xy 184.225785 -33.550352)
			(xy 184.716674 -33.550352) (xy 184.717124 -33.524036) (xy 184.724346 -33.471902) (xy 184.73866 -33.421254)
			(xy 184.759795 -33.373052) (xy 184.787351 -33.328211) (xy 184.820804 -33.287578) (xy 184.839864 -33.269428)
			(xy 184.849935 -33.259663) (xy 184.864636 -33.235778) (xy 184.87227 -33.208791) (xy 184.872261 -33.180745)
			(xy 184.864609 -33.153762) (xy 184.849894 -33.129887) (xy 184.839864 -33.120076) (xy 184.820785 -33.10194)
			(xy 184.787305 -33.061322) (xy 184.759732 -33.016482) (xy 184.738593 -32.968274) (xy 184.72429 -32.917616)
			(xy 184.717093 -32.865472) (xy 184.716674 -32.839152) (xy 184.717185 -32.811579) (xy 184.725129 -32.757009)
			(xy 184.740846 -32.70415) (xy 184.764008 -32.654104) (xy 184.794132 -32.607913) (xy 184.830591 -32.56654)
			(xy 184.851294 -32.548322) (xy 184.862239 -32.538472) (xy 184.878311 -32.513808) (xy 184.886689 -32.485588)
			(xy 184.88668 -32.45615) (xy 184.878284 -32.427935) (xy 184.862198 -32.403281) (xy 184.851294 -32.393382)
			(xy 184.83057 -32.375185) (xy 184.794101 -32.333813) (xy 184.76397 -32.28762) (xy 184.740807 -32.23757)
			(xy 184.725093 -32.184704) (xy 184.717157 -32.130128) (xy 184.716674 -32.102552) (xy 184.71716 -32.075301)
			(xy 184.724916 -32.021353) (xy 184.740271 -31.969058) (xy 184.762913 -31.919481) (xy 184.792379 -31.873631)
			(xy 184.82807 -31.83244) (xy 184.869261 -31.796749) (xy 184.915111 -31.767283) (xy 184.964688 -31.744641)
			(xy 185.016983 -31.729286) (xy 185.070931 -31.72153) (xy 185.125433 -31.72153) (xy 185.179381 -31.729286)
			(xy 185.231676 -31.744641) (xy 185.281253 -31.767283) (xy 185.327103 -31.796749) (xy 185.368294 -31.83244)
			(xy 185.403985 -31.873631) (xy 185.433451 -31.919481) (xy 185.456093 -31.969058) (xy 185.471448 -32.021353)
			(xy 185.479204 -32.075301) (xy 185.47969 -32.102552) (xy 185.479195 -32.130126) (xy 185.471249 -32.184697)
			(xy 185.45553 -32.237557) (xy 185.432365 -32.287603) (xy 185.402238 -32.333793) (xy 185.365775 -32.375165)
			(xy 185.34507 -32.393382) (xy 185.334224 -32.403331) (xy 185.318155 -32.427968) (xy 185.309769 -32.456162)
			(xy 185.30976 -32.485576) (xy 185.318129 -32.513775) (xy 185.334183 -32.538422) (xy 185.34507 -32.548322)
			(xy 185.365789 -32.566525) (xy 185.40226 -32.607895) (xy 185.432392 -32.654086) (xy 185.455557 -32.704136)
			(xy 185.471271 -32.757) (xy 185.479207 -32.811577) (xy 185.47969 -32.839152) (xy 185.479255 -32.865469)
			(xy 185.472031 -32.917604) (xy 185.457715 -32.968252) (xy 185.436577 -33.016454) (xy 185.409019 -33.061296)
			(xy 185.375562 -33.101927) (xy 185.3565 -33.120076) (xy 185.346528 -33.129934) (xy 185.331828 -33.153793)
			(xy 185.324184 -33.180755) (xy 185.324175 -33.20878) (xy 185.331802 -33.235747) (xy 185.346487 -33.259616)
			(xy 185.3565 -33.269428) (xy 185.375593 -33.287549) (xy 185.40907 -33.328172) (xy 185.436638 -33.373016)
			(xy 185.457775 -33.421226) (xy 185.472076 -33.471886) (xy 185.479271 -33.524032) (xy 185.47969 -33.550352)
			(xy 185.479204 -33.577603) (xy 185.471448 -33.631551) (xy 185.456093 -33.683846) (xy 185.433451 -33.733423)
			(xy 185.403985 -33.779273) (xy 185.368294 -33.820464) (xy 185.327103 -33.856155) (xy 185.281253 -33.885621)
			(xy 185.231676 -33.908263) (xy 185.179381 -33.923618) (xy 185.125433 -33.931374) (xy 185.070931 -33.931374)
			(xy 185.016983 -33.923618) (xy 184.964688 -33.908263) (xy 184.915111 -33.885621) (xy 184.869261 -33.856155)
			(xy 184.82807 -33.820464) (xy 184.792379 -33.779273) (xy 184.762913 -33.733423) (xy 184.740271 -33.683846)
			(xy 184.724916 -33.631551) (xy 184.71716 -33.577603) (xy 184.716674 -33.550352) (xy 184.225785 -33.550352)
			(xy 184.905142 -34.229548) (xy 191.058546 -34.229548)
		)
		(stroke
			(width 0)
			(type solid)
		)
		(fill yes)
		(layer "B.Cu")
		(net "GND")
	)
	(gr_poly
		(pts
			(xy 337.270852 -57.761124) (xy 337.2739 -57.74563) (xy 337.280006 -57.716128) (xy 337.298946 -57.658936)
			(xy 337.325229 -57.604725) (xy 337.358401 -57.554433) (xy 337.397887 -57.508931) (xy 337.443004 -57.469005)
			(xy 337.467702 -57.451752) (xy 337.467702 -57.247536) (xy 337.437476 -57.234074) (xy 337.412603 -57.222522)
			(xy 337.366442 -57.192915) (xy 337.325366 -57.156582) (xy 337.290345 -57.11438) (xy 337.262209 -57.067309)
			(xy 337.241621 -57.01648) (xy 337.22907 -56.963096) (xy 337.224851 -56.908419) (xy 337.229064 -56.853741)
			(xy 337.24161 -56.800356) (xy 337.262192 -56.749525) (xy 337.290324 -56.70245) (xy 337.32534 -56.660245)
			(xy 337.366412 -56.623907) (xy 337.41257 -56.594296) (xy 337.437476 -56.582818) (xy 337.467702 -56.569356)
			(xy 337.467702 -56.307736) (xy 337.437476 -56.294274) (xy 337.412614 -56.282712) (xy 337.366476 -56.253091)
			(xy 337.325423 -56.21675) (xy 337.290423 -56.174547) (xy 337.262304 -56.127479) (xy 337.241729 -56.076658)
			(xy 337.229186 -56.023284) (xy 337.22497 -55.968619) (xy 337.22918 -55.913953) (xy 337.241718 -55.860578)
			(xy 337.262287 -55.809754) (xy 337.290401 -55.762683) (xy 337.325397 -55.720477) (xy 337.366447 -55.684131)
			(xy 337.412581 -55.654505) (xy 337.437476 -55.643018) (xy 337.467702 -55.629556) (xy 337.467702 -55.367936)
			(xy 337.437476 -55.354474) (xy 337.412614 -55.342912) (xy 337.366476 -55.313291) (xy 337.325423 -55.27695)
			(xy 337.290423 -55.234747) (xy 337.262304 -55.187679) (xy 337.241729 -55.136858) (xy 337.229186 -55.083484)
			(xy 337.22497 -55.028819) (xy 337.22918 -54.974153) (xy 337.241718 -54.920778) (xy 337.262287 -54.869954)
			(xy 337.290401 -54.822883) (xy 337.325397 -54.780677) (xy 337.366447 -54.744331) (xy 337.412581 -54.714705)
			(xy 337.437476 -54.703218) (xy 337.467702 -54.689756) (xy 337.467702 -54.428136) (xy 337.437476 -54.414674)
			(xy 337.412614 -54.403112) (xy 337.366476 -54.373491) (xy 337.325423 -54.33715) (xy 337.290423 -54.294947)
			(xy 337.262304 -54.247879) (xy 337.241729 -54.197058) (xy 337.229186 -54.143684) (xy 337.22497 -54.089019)
			(xy 337.22918 -54.034353) (xy 337.241718 -53.980978) (xy 337.262287 -53.930154) (xy 337.290401 -53.883083)
			(xy 337.325397 -53.840877) (xy 337.366447 -53.804531) (xy 337.412581 -53.774905) (xy 337.437476 -53.763418)
			(xy 337.467702 -53.749956) (xy 337.467702 -53.488336) (xy 337.437476 -53.474874) (xy 337.412614 -53.463312)
			(xy 337.366476 -53.433691) (xy 337.325423 -53.39735) (xy 337.290423 -53.355147) (xy 337.262304 -53.308079)
			(xy 337.241729 -53.257258) (xy 337.229186 -53.203884) (xy 337.22497 -53.149219) (xy 337.22918 -53.094553)
			(xy 337.241718 -53.041178) (xy 337.262287 -52.990354) (xy 337.290401 -52.943283) (xy 337.325397 -52.901077)
			(xy 337.366447 -52.864731) (xy 337.412581 -52.835105) (xy 337.437476 -52.823618) (xy 337.467702 -52.810156)
			(xy 337.467702 -52.710842) (xy 337.545172 -52.633372) (xy 337.545172 -51.94046) (xy 337.439 -51.834288)
			(xy 335.552288 -51.834288) (xy 335.326228 -51.608228) (xy 335.326228 -50.25263) (xy 335.100422 -50.026824)
			(xy 334.83804 -50.026824) (xy 334.760824 -50.10404) (xy 334.760824 -51.667918) (xy 334.750156 -51.678332)
			(xy 334.750156 -51.732688) (xy 334.616044 -51.8668) (xy 334.561688 -51.8668) (xy 334.55737 -51.871372)
			(xy 333.915258 -51.871372) (xy 333.91094 -51.8668) (xy 333.842868 -51.8668) (xy 333.829152 -51.895248)
			(xy 333.816207 -51.920604) (xy 333.783493 -51.967194) (xy 333.743783 -52.007985) (xy 333.698088 -52.041938)
			(xy 333.647574 -52.068188) (xy 333.593526 -52.086066) (xy 333.537322 -52.095117) (xy 333.508858 -52.095654)
			(xy 333.492765 -52.095465) (xy 333.460711 -52.092543) (xy 333.44485 -52.089812) (xy 333.418688 -52.084986)
			(xy 332.96987 -52.533804) (xy 332.96606 -52.544726) (xy 332.955622 -52.573084) (xy 332.928333 -52.627)
			(xy 332.894192 -52.676861) (xy 332.874366 -52.699666) (xy 332.869041 -52.705995) (xy 334.782658 -52.705995)
			(xy 334.782658 -52.652697) (xy 334.790601 -52.599993) (xy 334.806311 -52.549063) (xy 334.829437 -52.501042)
			(xy 334.859461 -52.457005) (xy 334.895713 -52.417934) (xy 334.937384 -52.384703) (xy 334.983542 -52.358054)
			(xy 335.033156 -52.338582) (xy 335.085118 -52.326722) (xy 335.138268 -52.322739) (xy 335.191418 -52.326722)
			(xy 335.24338 -52.338582) (xy 335.292994 -52.358054) (xy 335.339152 -52.384703) (xy 335.380823 -52.417934)
			(xy 335.417075 -52.457005) (xy 335.447099 -52.501042) (xy 335.470225 -52.549063) (xy 335.485935 -52.599993)
			(xy 335.493878 -52.652697) (xy 335.494376 -52.679346) (xy 335.493878 -52.705995) (xy 335.485935 -52.758699)
			(xy 335.470225 -52.809629) (xy 335.447099 -52.85765) (xy 335.417075 -52.901687) (xy 335.380823 -52.940758)
			(xy 335.339152 -52.973989) (xy 335.292994 -53.000638) (xy 335.24338 -53.02011) (xy 335.191418 -53.03197)
			(xy 335.138268 -53.035954) (xy 335.085118 -53.03197) (xy 335.033156 -53.02011) (xy 334.983542 -53.000638)
			(xy 334.937384 -52.973989) (xy 334.895713 -52.940758) (xy 334.859461 -52.901687) (xy 334.829437 -52.85765)
			(xy 334.806311 -52.809629) (xy 334.790601 -52.758699) (xy 334.782658 -52.705995) (xy 332.869041 -52.705995)
			(xy 332.86497 -52.710833) (xy 332.852399 -52.737159) (xy 332.847775 -52.765963) (xy 332.851474 -52.7949)
			(xy 332.863196 -52.821614) (xy 332.881984 -52.843931) (xy 332.893924 -52.85232) (xy 332.914604 -52.866531)
			(xy 332.952135 -52.899837) (xy 332.984618 -52.938081) (xy 333.011411 -52.980507) (xy 333.031982 -53.026274)
			(xy 333.045925 -53.074475) (xy 333.052963 -53.124157) (xy 333.053436 -53.149246) (xy 333.05291 -53.175895)
			(xy 333.969858 -53.175895) (xy 333.969858 -53.122597) (xy 333.977801 -53.069893) (xy 333.993511 -53.018963)
			(xy 334.016637 -52.970942) (xy 334.046661 -52.926905) (xy 334.082913 -52.887834) (xy 334.124584 -52.854603)
			(xy 334.170742 -52.827954) (xy 334.220356 -52.808482) (xy 334.272318 -52.796622) (xy 334.325468 -52.792639)
			(xy 334.378618 -52.796622) (xy 334.43058 -52.808482) (xy 334.480194 -52.827954) (xy 334.526352 -52.854603)
			(xy 334.568023 -52.887834) (xy 334.604275 -52.926905) (xy 334.634299 -52.970942) (xy 334.657425 -53.018963)
			(xy 334.673135 -53.069893) (xy 334.681078 -53.122597) (xy 334.681576 -53.149246) (xy 334.681078 -53.175895)
			(xy 335.597998 -53.175895) (xy 335.597998 -53.122597) (xy 335.605941 -53.069893) (xy 335.621651 -53.018963)
			(xy 335.644777 -52.970942) (xy 335.674801 -52.926905) (xy 335.711053 -52.887834) (xy 335.752724 -52.854603)
			(xy 335.798882 -52.827954) (xy 335.848496 -52.808482) (xy 335.900458 -52.796622) (xy 335.953608 -52.792639)
			(xy 336.006758 -52.796622) (xy 336.05872 -52.808482) (xy 336.108334 -52.827954) (xy 336.154492 -52.854603)
			(xy 336.196163 -52.887834) (xy 336.232415 -52.926905) (xy 336.262439 -52.970942) (xy 336.285565 -53.018963)
			(xy 336.301275 -53.069893) (xy 336.309218 -53.122597) (xy 336.309716 -53.149246) (xy 336.309218 -53.175895)
			(xy 336.301275 -53.228599) (xy 336.285565 -53.279529) (xy 336.262439 -53.32755) (xy 336.232415 -53.371587)
			(xy 336.196163 -53.410658) (xy 336.154492 -53.443889) (xy 336.108334 -53.470538) (xy 336.05872 -53.49001)
			(xy 336.006758 -53.50187) (xy 335.953608 -53.505854) (xy 335.900458 -53.50187) (xy 335.848496 -53.49001)
			(xy 335.798882 -53.470538) (xy 335.752724 -53.443889) (xy 335.711053 -53.410658) (xy 335.674801 -53.371587)
			(xy 335.644777 -53.32755) (xy 335.621651 -53.279529) (xy 335.605941 -53.228599) (xy 335.597998 -53.175895)
			(xy 334.681078 -53.175895) (xy 334.673135 -53.228599) (xy 334.657425 -53.279529) (xy 334.634299 -53.32755)
			(xy 334.604275 -53.371587) (xy 334.568023 -53.410658) (xy 334.526352 -53.443889) (xy 334.480194 -53.470538)
			(xy 334.43058 -53.49001) (xy 334.378618 -53.50187) (xy 334.325468 -53.505854) (xy 334.272318 -53.50187)
			(xy 334.220356 -53.49001) (xy 334.170742 -53.470538) (xy 334.124584 -53.443889) (xy 334.082913 -53.410658)
			(xy 334.046661 -53.371587) (xy 334.016637 -53.32755) (xy 333.993511 -53.279529) (xy 333.977801 -53.228599)
			(xy 333.969858 -53.175895) (xy 333.05291 -53.175895) (xy 333.052884 -53.177228) (xy 333.044123 -53.232501)
			(xy 333.026825 -53.285723) (xy 333.001415 -53.335585) (xy 332.968518 -53.380859) (xy 332.928945 -53.42043)
			(xy 332.88367 -53.453324) (xy 332.833807 -53.478732) (xy 332.780583 -53.496027) (xy 332.72531 -53.504785)
			(xy 332.697328 -53.505354) (xy 332.672085 -53.504915) (xy 332.622106 -53.497786) (xy 332.573636 -53.483667)
			(xy 332.527647 -53.46284) (xy 332.485061 -53.435725) (xy 332.446735 -53.402864) (xy 332.413436 -53.364918)
			(xy 332.385832 -53.322648) (xy 332.364478 -53.276901) (xy 332.356714 -53.252878) (xy 332.352904 -53.240686)
			(xy 332.307946 -53.195728) (xy 332.200504 -53.30317) (xy 332.209648 -53.33238) (xy 332.219171 -53.365346)
			(xy 332.229372 -53.433199) (xy 332.229968 -53.467508) (xy 332.229476 -53.498148) (xy 332.221298 -53.55888)
			(xy 332.205089 -53.617977) (xy 332.193277 -53.645795) (xy 336.410798 -53.645795) (xy 336.410798 -53.592497)
			(xy 336.418741 -53.539793) (xy 336.434451 -53.488863) (xy 336.457577 -53.440842) (xy 336.487601 -53.396805)
			(xy 336.523853 -53.357734) (xy 336.565524 -53.324503) (xy 336.611682 -53.297854) (xy 336.661296 -53.278382)
			(xy 336.713258 -53.266522) (xy 336.766408 -53.262539) (xy 336.819558 -53.266522) (xy 336.87152 -53.278382)
			(xy 336.921134 -53.297854) (xy 336.967292 -53.324503) (xy 337.008963 -53.357734) (xy 337.045215 -53.396805)
			(xy 337.075239 -53.440842) (xy 337.098365 -53.488863) (xy 337.114075 -53.539793) (xy 337.122018 -53.592497)
			(xy 337.122516 -53.619146) (xy 337.122018 -53.645795) (xy 337.114075 -53.698499) (xy 337.098365 -53.749429)
			(xy 337.075239 -53.79745) (xy 337.045215 -53.841487) (xy 337.008963 -53.880558) (xy 336.967292 -53.913789)
			(xy 336.921134 -53.940438) (xy 336.87152 -53.95991) (xy 336.819558 -53.97177) (xy 336.766408 -53.975754)
			(xy 336.713258 -53.97177) (xy 336.661296 -53.95991) (xy 336.611682 -53.940438) (xy 336.565524 -53.913789)
			(xy 336.523853 -53.880558) (xy 336.487601 -53.841487) (xy 336.457577 -53.79745) (xy 336.434451 -53.749429)
			(xy 336.418741 -53.698499) (xy 336.410798 -53.645795) (xy 332.193277 -53.645795) (xy 332.181138 -53.674383)
			(xy 332.149875 -53.727089) (xy 332.111859 -53.775151) (xy 332.067769 -53.817711) (xy 332.018394 -53.854006)
			(xy 331.991716 -53.869082) (xy 331.991716 -54.218078) (xy 332.022704 -54.231286) (xy 332.046456 -54.241912)
			(xy 332.090857 -54.269041) (xy 332.130837 -54.302342) (xy 332.165547 -54.341106) (xy 332.194247 -54.384508)
			(xy 332.216326 -54.431624) (xy 332.231315 -54.481452) (xy 332.238893 -54.53293) (xy 332.239366 -54.558946)
			(xy 332.23893 -54.584391) (xy 332.238757 -54.585595) (xy 333.154518 -54.585595) (xy 333.154518 -54.532297)
			(xy 333.162461 -54.479593) (xy 333.178171 -54.428663) (xy 333.201297 -54.380642) (xy 333.231321 -54.336605)
			(xy 333.267573 -54.297534) (xy 333.309244 -54.264303) (xy 333.355402 -54.237654) (xy 333.405016 -54.218182)
			(xy 333.456978 -54.206322) (xy 333.510128 -54.202339) (xy 333.563278 -54.206322) (xy 333.61524 -54.218182)
			(xy 333.664854 -54.237654) (xy 333.711012 -54.264303) (xy 333.752683 -54.297534) (xy 333.788935 -54.336605)
			(xy 333.818959 -54.380642) (xy 333.842085 -54.428663) (xy 333.857795 -54.479593) (xy 333.865738 -54.532297)
			(xy 333.866236 -54.558946) (xy 333.865738 -54.585595) (xy 336.410798 -54.585595) (xy 336.410798 -54.532297)
			(xy 336.418741 -54.479593) (xy 336.434451 -54.428663) (xy 336.457577 -54.380642) (xy 336.487601 -54.336605)
			(xy 336.523853 -54.297534) (xy 336.565524 -54.264303) (xy 336.611682 -54.237654) (xy 336.661296 -54.218182)
			(xy 336.713258 -54.206322) (xy 336.766408 -54.202339) (xy 336.819558 -54.206322) (xy 336.87152 -54.218182)
			(xy 336.921134 -54.237654) (xy 336.967292 -54.264303) (xy 337.008963 -54.297534) (xy 337.045215 -54.336605)
			(xy 337.075239 -54.380642) (xy 337.098365 -54.428663) (xy 337.114075 -54.479593) (xy 337.122018 -54.532297)
			(xy 337.122516 -54.558946) (xy 337.122018 -54.585595) (xy 337.114075 -54.638299) (xy 337.098365 -54.689229)
			(xy 337.075239 -54.73725) (xy 337.045215 -54.781287) (xy 337.008963 -54.820358) (xy 336.967292 -54.853589)
			(xy 336.921134 -54.880238) (xy 336.87152 -54.89971) (xy 336.819558 -54.91157) (xy 336.766408 -54.915554)
			(xy 336.713258 -54.91157) (xy 336.661296 -54.89971) (xy 336.611682 -54.880238) (xy 336.565524 -54.853589)
			(xy 336.523853 -54.820358) (xy 336.487601 -54.781287) (xy 336.457577 -54.73725) (xy 336.434451 -54.689229)
			(xy 336.418741 -54.638299) (xy 336.410798 -54.585595) (xy 333.865738 -54.585595) (xy 333.857795 -54.638299)
			(xy 333.842085 -54.689229) (xy 333.818959 -54.73725) (xy 333.788935 -54.781287) (xy 333.752683 -54.820358)
			(xy 333.711012 -54.853589) (xy 333.664854 -54.880238) (xy 333.61524 -54.89971) (xy 333.563278 -54.91157)
			(xy 333.510128 -54.915554) (xy 333.456978 -54.91157) (xy 333.405016 -54.89971) (xy 333.355402 -54.880238)
			(xy 333.309244 -54.853589) (xy 333.267573 -54.820358) (xy 333.231321 -54.781287) (xy 333.201297 -54.73725)
			(xy 333.178171 -54.689229) (xy 333.162461 -54.638299) (xy 333.154518 -54.585595) (xy 332.238757 -54.585595)
			(xy 332.231681 -54.634761) (xy 332.217336 -54.683587) (xy 332.196188 -54.729875) (xy 332.168667 -54.772681)
			(xy 332.135334 -54.811134) (xy 332.096868 -54.844452) (xy 332.05405 -54.871956) (xy 332.007755 -54.893086)
			(xy 331.958923 -54.907411) (xy 331.933804 -54.911498) (xy 331.91704 -54.913784) (xy 331.775329 -55.055495)
			(xy 335.597998 -55.055495) (xy 335.597998 -55.002197) (xy 335.605941 -54.949493) (xy 335.621651 -54.898563)
			(xy 335.644777 -54.850542) (xy 335.674801 -54.806505) (xy 335.711053 -54.767434) (xy 335.752724 -54.734203)
			(xy 335.798882 -54.707554) (xy 335.848496 -54.688082) (xy 335.900458 -54.676222) (xy 335.953608 -54.672239)
			(xy 336.006758 -54.676222) (xy 336.05872 -54.688082) (xy 336.108334 -54.707554) (xy 336.154492 -54.734203)
			(xy 336.196163 -54.767434) (xy 336.232415 -54.806505) (xy 336.262439 -54.850542) (xy 336.285565 -54.898563)
			(xy 336.301275 -54.949493) (xy 336.309218 -55.002197) (xy 336.309716 -55.028846) (xy 336.309218 -55.055495)
			(xy 336.301275 -55.108199) (xy 336.285565 -55.159129) (xy 336.262439 -55.20715) (xy 336.232415 -55.251187)
			(xy 336.196163 -55.290258) (xy 336.154492 -55.323489) (xy 336.108334 -55.350138) (xy 336.05872 -55.36961)
			(xy 336.006758 -55.38147) (xy 335.953608 -55.385454) (xy 335.900458 -55.38147) (xy 335.848496 -55.36961)
			(xy 335.798882 -55.350138) (xy 335.752724 -55.323489) (xy 335.711053 -55.290258) (xy 335.674801 -55.251187)
			(xy 335.644777 -55.20715) (xy 335.621651 -55.159129) (xy 335.605941 -55.108199) (xy 335.597998 -55.055495)
			(xy 331.775329 -55.055495) (xy 331.773022 -55.057802) (xy 331.773022 -55.146702) (xy 331.827378 -55.146702)
			(xy 331.831188 -55.146194) (xy 331.843819 -55.144504) (xy 331.869244 -55.142725) (xy 331.881988 -55.142638)
			(xy 331.908636 -55.14311) (xy 331.961338 -55.151052) (xy 332.012267 -55.16676) (xy 332.060286 -55.189883)
			(xy 332.104322 -55.219906) (xy 332.143392 -55.256156) (xy 332.176623 -55.297824) (xy 332.203271 -55.34398)
			(xy 332.222743 -55.393592) (xy 332.234603 -55.445552) (xy 332.238586 -55.4987) (xy 332.234603 -55.551848)
			(xy 332.222743 -55.603808) (xy 332.203271 -55.65342) (xy 332.176623 -55.699576) (xy 332.143392 -55.741244)
			(xy 332.104322 -55.777494) (xy 332.060286 -55.807517) (xy 332.012267 -55.83064) (xy 331.961338 -55.846348)
			(xy 331.908636 -55.85429) (xy 331.881988 -55.854854) (xy 331.876146 -55.854854) (xy 331.86269 -55.855062)
			(xy 331.836619 -55.861697) (xy 331.813188 -55.874915) (xy 331.794026 -55.893798) (xy 331.780465 -55.917032)
			(xy 331.773448 -55.943003) (xy 331.773022 -55.956454) (xy 331.773022 -55.980838) (xy 331.773439 -55.994284)
			(xy 331.773713 -55.995295) (xy 332.341972 -55.995295) (xy 332.341972 -55.941997) (xy 332.349915 -55.889293)
			(xy 332.365625 -55.838363) (xy 332.388751 -55.790342) (xy 332.418775 -55.746305) (xy 332.455027 -55.707234)
			(xy 332.496698 -55.674003) (xy 332.542856 -55.647354) (xy 332.59247 -55.627882) (xy 332.644432 -55.616022)
			(xy 332.697582 -55.612039) (xy 332.750732 -55.616022) (xy 332.802694 -55.627882) (xy 332.852308 -55.647354)
			(xy 332.898466 -55.674003) (xy 332.940137 -55.707234) (xy 332.976389 -55.746305) (xy 333.006413 -55.790342)
			(xy 333.029539 -55.838363) (xy 333.045249 -55.889293) (xy 333.053192 -55.941997) (xy 333.05369 -55.968646)
			(xy 333.053192 -55.995295) (xy 333.045249 -56.047999) (xy 333.029539 -56.098929) (xy 333.006413 -56.14695)
			(xy 332.976389 -56.190987) (xy 332.940137 -56.230058) (xy 332.898466 -56.263289) (xy 332.852308 -56.289938)
			(xy 332.802694 -56.30941) (xy 332.750732 -56.32127) (xy 332.697582 -56.325254) (xy 332.644432 -56.32127)
			(xy 332.59247 -56.30941) (xy 332.542856 -56.289938) (xy 332.496698 -56.263289) (xy 332.455027 -56.230058)
			(xy 332.418775 -56.190987) (xy 332.388751 -56.14695) (xy 332.365625 -56.098929) (xy 332.349915 -56.047999)
			(xy 332.341972 -55.995295) (xy 331.773713 -55.995295) (xy 331.780473 -56.02024) (xy 331.794043 -56.043457)
			(xy 331.813206 -56.062324) (xy 331.836632 -56.07553) (xy 331.862694 -56.082159) (xy 331.876146 -56.082438)
			(xy 331.881988 -56.082438) (xy 331.908636 -56.08291) (xy 331.961338 -56.090852) (xy 332.012267 -56.10656)
			(xy 332.060286 -56.129683) (xy 332.104322 -56.159706) (xy 332.143392 -56.195956) (xy 332.176623 -56.237624)
			(xy 332.203271 -56.28378) (xy 332.222743 -56.333392) (xy 332.234603 -56.385352) (xy 332.238586 -56.4385)
			(xy 332.238583 -56.438546) (xy 333.154274 -56.438546) (xy 333.154764 -56.411139) (xy 333.163143 -56.356968)
			(xy 333.179726 -56.304723) (xy 333.20412 -56.255636) (xy 333.23575 -56.210867) (xy 333.273867 -56.171476)
			(xy 333.317571 -56.138392) (xy 333.36583 -56.112398) (xy 333.417503 -56.094107) (xy 333.444342 -56.088534)
			(xy 333.459836 -56.08574) (xy 333.570072 -55.975504) (xy 333.561944 -55.946802) (xy 333.553857 -55.91626)
			(xy 333.545186 -55.853678) (xy 333.544672 -55.822088) (xy 333.545174 -55.79212) (xy 333.552999 -55.732696)
			(xy 333.568513 -55.674802) (xy 333.591451 -55.619428) (xy 333.621421 -55.567522) (xy 333.65791 -55.519973)
			(xy 333.700293 -55.477592) (xy 333.747845 -55.441106) (xy 333.799752 -55.41114) (xy 333.855127 -55.388204)
			(xy 333.913022 -55.372694) (xy 333.972446 -55.364872) (xy 334.032383 -55.364874) (xy 334.091807 -55.372699)
			(xy 334.149701 -55.388214) (xy 334.205074 -55.411153) (xy 334.25698 -55.441123) (xy 334.304529 -55.477611)
			(xy 334.34691 -55.519995) (xy 334.351053 -55.525395) (xy 334.782658 -55.525395) (xy 334.782658 -55.472097)
			(xy 334.790601 -55.419393) (xy 334.806311 -55.368463) (xy 334.829437 -55.320442) (xy 334.859461 -55.276405)
			(xy 334.895713 -55.237334) (xy 334.937384 -55.204103) (xy 334.983542 -55.177454) (xy 335.033156 -55.157982)
			(xy 335.085118 -55.146122) (xy 335.138268 -55.142139) (xy 335.191418 -55.146122) (xy 335.24338 -55.157982)
			(xy 335.292994 -55.177454) (xy 335.339152 -55.204103) (xy 335.380823 -55.237334) (xy 335.417075 -55.276405)
			(xy 335.447099 -55.320442) (xy 335.470225 -55.368463) (xy 335.485935 -55.419393) (xy 335.493878 -55.472097)
			(xy 335.494376 -55.498746) (xy 335.493878 -55.525395) (xy 336.412068 -55.525395) (xy 336.412068 -55.472097)
			(xy 336.420011 -55.419393) (xy 336.435721 -55.368463) (xy 336.458847 -55.320442) (xy 336.488871 -55.276405)
			(xy 336.525123 -55.237334) (xy 336.566794 -55.204103) (xy 336.612952 -55.177454) (xy 336.662566 -55.157982)
			(xy 336.714528 -55.146122) (xy 336.767678 -55.142139) (xy 336.820828 -55.146122) (xy 336.87279 -55.157982)
			(xy 336.922404 -55.177454) (xy 336.968562 -55.204103) (xy 337.010233 -55.237334) (xy 337.046485 -55.276405)
			(xy 337.076509 -55.320442) (xy 337.099635 -55.368463) (xy 337.115345 -55.419393) (xy 337.123288 -55.472097)
			(xy 337.123786 -55.498746) (xy 337.123288 -55.525395) (xy 337.115345 -55.578099) (xy 337.099635 -55.629029)
			(xy 337.076509 -55.67705) (xy 337.046485 -55.721087) (xy 337.010233 -55.760158) (xy 336.968562 -55.793389)
			(xy 336.922404 -55.820038) (xy 336.87279 -55.83951) (xy 336.820828 -55.85137) (xy 336.767678 -55.855354)
			(xy 336.714528 -55.85137) (xy 336.662566 -55.83951) (xy 336.612952 -55.820038) (xy 336.566794 -55.793389)
			(xy 336.525123 -55.760158) (xy 336.488871 -55.721087) (xy 336.458847 -55.67705) (xy 336.435721 -55.629029)
			(xy 336.420011 -55.578099) (xy 336.412068 -55.525395) (xy 335.493878 -55.525395) (xy 335.485935 -55.578099)
			(xy 335.470225 -55.629029) (xy 335.447099 -55.67705) (xy 335.417075 -55.721087) (xy 335.380823 -55.760158)
			(xy 335.339152 -55.793389) (xy 335.292994 -55.820038) (xy 335.24338 -55.83951) (xy 335.191418 -55.85137)
			(xy 335.138268 -55.855354) (xy 335.085118 -55.85137) (xy 335.033156 -55.83951) (xy 334.983542 -55.820038)
			(xy 334.937384 -55.793389) (xy 334.895713 -55.760158) (xy 334.859461 -55.721087) (xy 334.829437 -55.67705)
			(xy 334.806311 -55.629029) (xy 334.790601 -55.578099) (xy 334.782658 -55.525395) (xy 334.351053 -55.525395)
			(xy 334.383395 -55.567547) (xy 334.413362 -55.619455) (xy 334.436296 -55.67483) (xy 334.451807 -55.732725)
			(xy 334.459628 -55.792149) (xy 334.459626 -55.852086) (xy 334.4518 -55.911509) (xy 334.436285 -55.969403)
			(xy 334.425559 -55.995295) (xy 335.597998 -55.995295) (xy 335.597998 -55.941997) (xy 335.605941 -55.889293)
			(xy 335.621651 -55.838363) (xy 335.644777 -55.790342) (xy 335.674801 -55.746305) (xy 335.711053 -55.707234)
			(xy 335.752724 -55.674003) (xy 335.798882 -55.647354) (xy 335.848496 -55.627882) (xy 335.900458 -55.616022)
			(xy 335.953608 -55.612039) (xy 336.006758 -55.616022) (xy 336.05872 -55.627882) (xy 336.108334 -55.647354)
			(xy 336.154492 -55.674003) (xy 336.196163 -55.707234) (xy 336.232415 -55.746305) (xy 336.262439 -55.790342)
			(xy 336.285565 -55.838363) (xy 336.301275 -55.889293) (xy 336.309218 -55.941997) (xy 336.309716 -55.968646)
			(xy 336.309218 -55.995295) (xy 336.301275 -56.047999) (xy 336.285565 -56.098929) (xy 336.262439 -56.14695)
			(xy 336.232415 -56.190987) (xy 336.196163 -56.230058) (xy 336.154492 -56.263289) (xy 336.108334 -56.289938)
			(xy 336.05872 -56.30941) (xy 336.006758 -56.32127) (xy 335.953608 -56.325254) (xy 335.900458 -56.32127)
			(xy 335.848496 -56.30941) (xy 335.798882 -56.289938) (xy 335.752724 -56.263289) (xy 335.711053 -56.230058)
			(xy 335.674801 -56.190987) (xy 335.644777 -56.14695) (xy 335.621651 -56.098929) (xy 335.605941 -56.047999)
			(xy 335.597998 -55.995295) (xy 334.425559 -55.995295) (xy 334.413346 -56.024776) (xy 334.383376 -56.076682)
			(xy 334.346887 -56.124231) (xy 334.304503 -56.166611) (xy 334.256951 -56.203097) (xy 334.205043 -56.233063)
			(xy 334.149668 -56.255997) (xy 334.091773 -56.271508) (xy 334.032348 -56.279328) (xy 334.00238 -56.279796)
			(xy 333.971138 -56.27878) (xy 333.956172 -56.278342) (xy 333.927025 -56.285121) (xy 333.901091 -56.300053)
			(xy 333.880594 -56.321856) (xy 333.867291 -56.348661) (xy 333.862323 -56.378171) (xy 333.863696 -56.39308)
			(xy 333.865032 -56.404399) (xy 333.866433 -56.427149) (xy 333.86649 -56.438546) (xy 333.865992 -56.465195)
			(xy 334.782658 -56.465195) (xy 334.782658 -56.411897) (xy 334.790601 -56.359193) (xy 334.806311 -56.308263)
			(xy 334.829437 -56.260242) (xy 334.859461 -56.216205) (xy 334.895713 -56.177134) (xy 334.937384 -56.143903)
			(xy 334.983542 -56.117254) (xy 335.033156 -56.097782) (xy 335.085118 -56.085922) (xy 335.138268 -56.081939)
			(xy 335.191418 -56.085922) (xy 335.24338 -56.097782) (xy 335.292994 -56.117254) (xy 335.339152 -56.143903)
			(xy 335.380823 -56.177134) (xy 335.417075 -56.216205) (xy 335.447099 -56.260242) (xy 335.470225 -56.308263)
			(xy 335.485935 -56.359193) (xy 335.493878 -56.411897) (xy 335.494376 -56.438546) (xy 335.493878 -56.465195)
			(xy 336.411814 -56.465195) (xy 336.411814 -56.411897) (xy 336.419757 -56.359193) (xy 336.435467 -56.308263)
			(xy 336.458593 -56.260242) (xy 336.488617 -56.216205) (xy 336.524869 -56.177134) (xy 336.56654 -56.143903)
			(xy 336.612698 -56.117254) (xy 336.662312 -56.097782) (xy 336.714274 -56.085922) (xy 336.767424 -56.081939)
			(xy 336.820574 -56.085922) (xy 336.872536 -56.097782) (xy 336.92215 -56.117254) (xy 336.968308 -56.143903)
			(xy 337.009979 -56.177134) (xy 337.046231 -56.216205) (xy 337.076255 -56.260242) (xy 337.099381 -56.308263)
			(xy 337.115091 -56.359193) (xy 337.123034 -56.411897) (xy 337.123532 -56.438546) (xy 337.123034 -56.465195)
			(xy 337.115091 -56.517899) (xy 337.099381 -56.568829) (xy 337.076255 -56.61685) (xy 337.046231 -56.660887)
			(xy 337.009979 -56.699958) (xy 336.968308 -56.733189) (xy 336.92215 -56.759838) (xy 336.872536 -56.77931)
			(xy 336.820574 -56.79117) (xy 336.767424 -56.795154) (xy 336.714274 -56.79117) (xy 336.662312 -56.77931)
			(xy 336.612698 -56.759838) (xy 336.56654 -56.733189) (xy 336.524869 -56.699958) (xy 336.488617 -56.660887)
			(xy 336.458593 -56.61685) (xy 336.435467 -56.568829) (xy 336.419757 -56.517899) (xy 336.411814 -56.465195)
			(xy 335.493878 -56.465195) (xy 335.485935 -56.517899) (xy 335.470225 -56.568829) (xy 335.447099 -56.61685)
			(xy 335.417075 -56.660887) (xy 335.380823 -56.699958) (xy 335.339152 -56.733189) (xy 335.292994 -56.759838)
			(xy 335.24338 -56.77931) (xy 335.191418 -56.79117) (xy 335.138268 -56.795154) (xy 335.085118 -56.79117)
			(xy 335.033156 -56.77931) (xy 334.983542 -56.759838) (xy 334.937384 -56.733189) (xy 334.895713 -56.699958)
			(xy 334.859461 -56.660887) (xy 334.829437 -56.61685) (xy 334.806311 -56.568829) (xy 334.790601 -56.517899)
			(xy 334.782658 -56.465195) (xy 333.865992 -56.465195) (xy 333.858049 -56.517899) (xy 333.842339 -56.568829)
			(xy 333.819213 -56.61685) (xy 333.789189 -56.660887) (xy 333.752937 -56.699958) (xy 333.711266 -56.733189)
			(xy 333.665108 -56.759838) (xy 333.615494 -56.77931) (xy 333.563532 -56.79117) (xy 333.510382 -56.795154)
			(xy 333.457232 -56.79117) (xy 333.40527 -56.77931) (xy 333.355656 -56.759838) (xy 333.309498 -56.733189)
			(xy 333.267827 -56.699958) (xy 333.231575 -56.660887) (xy 333.201551 -56.61685) (xy 333.178425 -56.568829)
			(xy 333.162715 -56.517899) (xy 333.154772 -56.465195) (xy 333.154274 -56.438546) (xy 332.238583 -56.438546)
			(xy 332.234603 -56.491648) (xy 332.222743 -56.543608) (xy 332.203271 -56.59322) (xy 332.176623 -56.639376)
			(xy 332.143392 -56.681044) (xy 332.104322 -56.717294) (xy 332.060286 -56.747317) (xy 332.012267 -56.77044)
			(xy 331.961338 -56.786148) (xy 331.908636 -56.79409) (xy 331.881988 -56.794654) (xy 331.876146 -56.794654)
			(xy 331.86269 -56.794862) (xy 331.836619 -56.801497) (xy 331.813188 -56.814715) (xy 331.794026 -56.833598)
			(xy 331.780465 -56.856832) (xy 331.773448 -56.882803) (xy 331.773022 -56.896254) (xy 331.773022 -56.935095)
			(xy 332.340702 -56.935095) (xy 332.340702 -56.881797) (xy 332.348645 -56.829093) (xy 332.364355 -56.778163)
			(xy 332.387481 -56.730142) (xy 332.417505 -56.686105) (xy 332.453757 -56.647034) (xy 332.495428 -56.613803)
			(xy 332.541586 -56.587154) (xy 332.5912 -56.567682) (xy 332.643162 -56.555822) (xy 332.696312 -56.551839)
			(xy 332.749462 -56.555822) (xy 332.801424 -56.567682) (xy 332.851038 -56.587154) (xy 332.897196 -56.613803)
			(xy 332.938867 -56.647034) (xy 332.975119 -56.686105) (xy 333.005143 -56.730142) (xy 333.028269 -56.778163)
			(xy 333.043979 -56.829093) (xy 333.051922 -56.881797) (xy 333.05242 -56.908446) (xy 333.051922 -56.935095)
			(xy 335.597998 -56.935095) (xy 335.597998 -56.881797) (xy 335.605941 -56.829093) (xy 335.621651 -56.778163)
			(xy 335.644777 -56.730142) (xy 335.674801 -56.686105) (xy 335.711053 -56.647034) (xy 335.752724 -56.613803)
			(xy 335.798882 -56.587154) (xy 335.848496 -56.567682) (xy 335.900458 -56.555822) (xy 335.953608 -56.551839)
			(xy 336.006758 -56.555822) (xy 336.05872 -56.567682) (xy 336.108334 -56.587154) (xy 336.154492 -56.613803)
			(xy 336.196163 -56.647034) (xy 336.232415 -56.686105) (xy 336.262439 -56.730142) (xy 336.285565 -56.778163)
			(xy 336.301275 -56.829093) (xy 336.309218 -56.881797) (xy 336.309716 -56.908446) (xy 336.309218 -56.935095)
			(xy 336.301275 -56.987799) (xy 336.285565 -57.038729) (xy 336.262439 -57.08675) (xy 336.232415 -57.130787)
			(xy 336.196163 -57.169858) (xy 336.154492 -57.203089) (xy 336.108334 -57.229738) (xy 336.05872 -57.24921)
			(xy 336.006758 -57.26107) (xy 335.953608 -57.265054) (xy 335.900458 -57.26107) (xy 335.848496 -57.24921)
			(xy 335.798882 -57.229738) (xy 335.752724 -57.203089) (xy 335.711053 -57.169858) (xy 335.674801 -57.130787)
			(xy 335.644777 -57.08675) (xy 335.621651 -57.038729) (xy 335.605941 -56.987799) (xy 335.597998 -56.935095)
			(xy 333.051922 -56.935095) (xy 333.043979 -56.987799) (xy 333.028269 -57.038729) (xy 333.005143 -57.08675)
			(xy 332.975119 -57.130787) (xy 332.938867 -57.169858) (xy 332.897196 -57.203089) (xy 332.851038 -57.229738)
			(xy 332.801424 -57.24921) (xy 332.749462 -57.26107) (xy 332.696312 -57.265054) (xy 332.643162 -57.26107)
			(xy 332.5912 -57.24921) (xy 332.541586 -57.229738) (xy 332.495428 -57.203089) (xy 332.453757 -57.169858)
			(xy 332.417505 -57.130787) (xy 332.387481 -57.08675) (xy 332.364355 -57.038729) (xy 332.348645 -56.987799)
			(xy 332.340702 -56.935095) (xy 331.773022 -56.935095) (xy 331.773022 -58.106056) (xy 331.817472 -58.150506)
			(xy 336.88147 -58.150506)
		)
		(stroke
			(width 0)
			(type solid)
		)
		(fill yes)
		(layer "B.Cu")
		(net "P1V8_PCH_AUX")
	)
	(gr_poly
		(pts
			(xy 348.980252 -348.514416) (xy 348.987652 -348.507576) (xy 349.006251 -348.499858) (xy 349.01632 -348.49943)
			(xy 355.362256 -348.49943) (xy 355.372321 -348.499864) (xy 355.390908 -348.507596) (xy 355.398324 -348.514416)
			(xy 355.66096 -348.777052) (xy 360.521504 -348.777052) (xy 361.029504 -348.777052) (xy 362.070904 -348.777052)
			(xy 363.1438 -349.849948) (xy 363.1438 -351.119948) (xy 363.4232 -351.119948) (xy 363.4232 -349.595948)
			(xy 363.423638 -349.582626) (xy 363.430523 -349.556888) (xy 363.443837 -349.533811) (xy 363.462672 -349.514967)
			(xy 363.485744 -349.501642) (xy 363.511478 -349.494744) (xy 363.5248 -349.494348) (xy 365.0488 -349.494348)
			(xy 365.062128 -349.494696) (xy 365.087875 -349.501597) (xy 365.110957 -349.514929) (xy 365.129801 -349.533781)
			(xy 365.143121 -349.55687) (xy 365.15001 -349.58262) (xy 365.1504 -349.595948) (xy 365.1504 -350.400309)
			(xy 365.897664 -350.400309) (xy 365.897664 -350.315587) (xy 365.905717 -350.23125) (xy 365.921751 -350.14806)
			(xy 365.945619 -350.06677) (xy 365.977107 -349.988118) (xy 366.015929 -349.912815) (xy 366.061732 -349.841543)
			(xy 366.114103 -349.774947) (xy 366.172568 -349.713632) (xy 366.236596 -349.658151) (xy 366.305608 -349.609008)
			(xy 366.378978 -349.566648) (xy 366.456043 -349.531453) (xy 366.536105 -349.503744) (xy 366.618438 -349.48377)
			(xy 366.702297 -349.471713) (xy 366.786922 -349.467682) (xy 366.871547 -349.471713) (xy 366.955406 -349.48377)
			(xy 367.037739 -349.503744) (xy 367.117801 -349.531453) (xy 367.194866 -349.566648) (xy 367.268236 -349.609008)
			(xy 367.337248 -349.658151) (xy 367.401276 -349.713632) (xy 367.459741 -349.774947) (xy 367.512112 -349.841543)
			(xy 367.557915 -349.912815) (xy 367.596737 -349.988118) (xy 367.628225 -350.06677) (xy 367.652093 -350.14806)
			(xy 367.668127 -350.23125) (xy 367.67618 -350.315587) (xy 367.676684 -350.357948) (xy 367.67618 -350.400309)
			(xy 367.668127 -350.484646) (xy 367.652093 -350.567836) (xy 367.628225 -350.649126) (xy 367.596737 -350.727778)
			(xy 367.557915 -350.803081) (xy 367.512112 -350.874353) (xy 367.459741 -350.940949) (xy 367.401276 -351.002264)
			(xy 367.337248 -351.057745) (xy 367.268236 -351.106888) (xy 367.194866 -351.149248) (xy 367.117801 -351.184443)
			(xy 367.037739 -351.212152) (xy 366.955406 -351.232126) (xy 366.871547 -351.244183) (xy 366.786922 -351.248215)
			(xy 366.702297 -351.244183) (xy 366.618438 -351.232126) (xy 366.536105 -351.212152) (xy 366.456043 -351.184443)
			(xy 366.378978 -351.149248) (xy 366.305608 -351.106888) (xy 366.236596 -351.057745) (xy 366.172568 -351.002264)
			(xy 366.114103 -350.940949) (xy 366.061732 -350.874353) (xy 366.015929 -350.803081) (xy 365.977107 -350.727778)
			(xy 365.945619 -350.649126) (xy 365.921751 -350.567836) (xy 365.905717 -350.484646) (xy 365.897664 -350.400309)
			(xy 365.1504 -350.400309) (xy 365.1504 -351.119948) (xy 365.150007 -351.133269) (xy 365.143102 -351.159)
			(xy 365.129774 -351.182069) (xy 365.11093 -351.200903) (xy 365.087856 -351.21422) (xy 365.062121 -351.221114)
			(xy 365.0488 -351.221548) (xy 363.5248 -351.221548) (xy 363.511485 -351.221066) (xy 363.485763 -351.214176)
			(xy 363.462699 -351.200865) (xy 363.443865 -351.182039) (xy 363.430543 -351.158982) (xy 363.42364 -351.133263)
			(xy 363.4232 -351.119948) (xy 363.1438 -351.119948) (xy 363.1438 -351.399348) (xy 363.601 -351.856548)
			(xy 370.6876 -351.856548) (xy 372.4148 -350.129348) (xy 389.340852 -350.129348) (xy 389.962644 -349.507556)
			(xy 389.962644 -343.455752) (xy 389.736584 -343.229692) (xy 389.714994 -343.229692) (xy 389.705451 -343.229245)
			(xy 389.687709 -343.222196) (xy 389.673744 -343.209178) (xy 389.669274 -343.200736) (xy 389.665464 -343.192608)
			(xy 389.607298 -343.134442) (xy 386.108194 -343.134442) (xy 386.070856 -343.17178) (xy 386.070856 -346.11183)
			(xy 386.08127 -346.142564) (xy 386.086096 -346.148914) (xy 386.102283 -346.171201) (xy 386.131776 -346.217728)
			(xy 386.145024 -346.241878) (xy 386.149962 -346.250167) (xy 386.164706 -346.262588) (xy 386.173726 -346.266008)
			(xy 386.214523 -346.280245) (xy 386.293761 -346.314727) (xy 386.369782 -346.355815) (xy 386.442039 -346.403213)
			(xy 386.510007 -346.456578) (xy 386.573196 -346.515525) (xy 386.631149 -346.579627) (xy 386.683447 -346.64842)
			(xy 386.729711 -346.721408) (xy 386.750052 -346.75953) (xy 386.756656 -346.771722) (xy 386.801614 -346.799662)
			(xy 387.646672 -346.799662) (xy 387.656735 -346.8001) (xy 387.675315 -346.80784) (xy 387.68274 -346.814648)
			(xy 387.941566 -347.073474) (xy 387.948405 -347.080875) (xy 387.956117 -347.099474) (xy 387.956552 -347.109542)
			(xy 387.956552 -348.302834) (xy 387.956121 -348.3129) (xy 387.948393 -348.331491) (xy 387.941566 -348.338902)
			(xy 387.802628 -348.47784) (xy 387.795229 -348.484682) (xy 387.77663 -348.4924) (xy 387.76656 -348.492826)
			(xy 381.69723 -348.492826) (xy 381.687179 -348.492322) (xy 381.668615 -348.484603) (xy 381.661162 -348.47784)
			(xy 381.535686 -348.352364) (xy 381.528836 -348.344968) (xy 381.521101 -348.326369) (xy 381.5207 -348.316296)
			(xy 381.5207 -348.076266) (xy 381.513334 -348.063312) (xy 381.513334 -344.137996) (xy 381.492211 -344.102132)
			(xy 381.457021 -344.0267) (xy 381.430254 -343.947885) (xy 381.412228 -343.866623) (xy 381.403157 -343.783882)
			(xy 381.40259 -343.742264) (xy 381.403166 -343.700944) (xy 381.412127 -343.618792) (xy 381.429908 -343.538087)
			(xy 381.456301 -343.459776) (xy 381.490998 -343.384772) (xy 381.51181 -343.349072) (xy 381.515874 -343.34196)
			(xy 381.5207 -343.320878) (xy 381.5207 -338.60867) (xy 381.520192 -338.608416) (xy 381.520192 -338.489798)
			(xy 381.5207 -338.48929) (xy 381.5207 -337.439254) (xy 381.505968 -337.402932) (xy 381.446786 -337.34375)
			(xy 377.947682 -337.34375) (xy 377.910344 -337.381088) (xy 377.910344 -340.321138) (xy 377.920758 -340.351872)
			(xy 377.925584 -340.358222) (xy 377.941771 -340.380509) (xy 377.971264 -340.427036) (xy 377.984512 -340.451186)
			(xy 377.989449 -340.459475) (xy 378.004193 -340.471898) (xy 378.013214 -340.475316) (xy 378.053363 -340.489348)
			(xy 378.131387 -340.523211) (xy 378.206307 -340.563478) (xy 378.277598 -340.609866) (xy 378.344762 -340.662053)
			(xy 378.407329 -340.719671) (xy 378.46486 -340.782318) (xy 378.491242 -340.815676) (xy 378.498878 -340.824556)
			(xy 378.519927 -340.834761) (xy 378.531628 -340.835234) (xy 379.086872 -340.835234) (xy 379.096936 -340.835671)
			(xy 379.115518 -340.843408) (xy 379.12294 -340.85022) (xy 379.781816 -341.509096) (xy 379.788672 -341.51649)
			(xy 379.796421 -341.535089) (xy 379.796802 -341.545164) (xy 379.796802 -342.958166) (xy 379.796367 -342.968231)
			(xy 379.788636 -342.986818) (xy 379.781816 -342.994234) (xy 379.496574 -343.279476) (xy 379.489175 -343.286321)
			(xy 379.470577 -343.29405) (xy 379.460506 -343.294462) (xy 374.541034 -343.294462) (xy 374.53097 -343.294026)
			(xy 374.512386 -343.286291) (xy 374.504966 -343.279476) (xy 373.375174 -342.149684) (xy 373.368322 -342.142288)
			(xy 373.360582 -342.123689) (xy 373.360188 -342.113616) (xy 373.360188 -342.10371) (xy 373.352822 -342.077548)
			(xy 373.352822 -338.340954) (xy 373.331699 -338.30509) (xy 373.296509 -338.229658) (xy 373.269743 -338.150843)
			(xy 373.251719 -338.069581) (xy 373.242652 -337.98684) (xy 373.242078 -337.945222) (xy 373.242651 -337.903901)
			(xy 373.251606 -337.821746) (xy 373.269381 -337.741039) (xy 373.295769 -337.662724) (xy 373.330461 -337.587716)
			(xy 373.351298 -337.55203) (xy 373.355362 -337.544918) (xy 373.360188 -337.523836) (xy 373.360188 -335.198466)
			(xy 373.35968 -335.198212) (xy 373.35968 -335.079594) (xy 373.360188 -335.079086) (xy 373.360188 -334.02905)
			(xy 373.345456 -333.992728) (xy 373.286274 -333.933546) (xy 369.78717 -333.933546) (xy 369.749832 -333.970884)
			(xy 369.749832 -336.910934) (xy 369.760246 -336.941668) (xy 369.765072 -336.948018) (xy 369.781257 -336.970306)
			(xy 369.810748 -337.016835) (xy 369.824 -337.040982) (xy 369.828943 -337.049263) (xy 369.843695 -337.061663)
			(xy 369.852702 -337.065112) (xy 369.894723 -337.079817) (xy 369.976256 -337.11559) (xy 370.054348 -337.158353)
			(xy 370.128403 -337.20778) (xy 370.197853 -337.263493) (xy 370.262167 -337.325064) (xy 370.291868 -337.358228)
			(xy 371.44452 -337.358228) (xy 371.700044 -337.613752) (xy 371.700044 -338.183982) (xy 371.700552 -338.191348)
			(xy 371.700552 -339.577172) (xy 371.700114 -339.587235) (xy 371.692376 -339.605816) (xy 371.685566 -339.61324)
			(xy 371.668548 -339.630258) (xy 371.397276 -339.901276) (xy 371.389877 -339.908121) (xy 371.371279 -339.915851)
			(xy 371.361208 -339.916262) (xy 366.080802 -339.916262) (xy 366.070732 -339.915838) (xy 366.052131 -339.90812)
			(xy 366.044734 -339.901276) (xy 365.2647 -339.121242) (xy 365.2647 -335.672176) (xy 365.239443 -335.641894)
			(xy 365.194633 -335.577003) (xy 365.15676 -335.507834) (xy 365.12623 -335.435125) (xy 365.103368 -335.359653)
			(xy 365.088419 -335.282224) (xy 365.081541 -335.203665) (xy 365.08281 -335.124817) (xy 365.092211 -335.04652)
			(xy 365.109644 -334.969612) (xy 365.134923 -334.894915) (xy 365.150908 -334.858868) (xy 365.134341 -334.821418)
			(xy 365.108398 -334.743742) (xy 365.090926 -334.663734) (xy 365.082125 -334.582315) (xy 365.081566 -334.541368)
			(xy 365.081566 -334.541114) (xy 365.082104 -334.500086) (xy 365.090905 -334.418503) (xy 365.108417 -334.338337)
			(xy 365.134438 -334.260516) (xy 365.168667 -334.185939) (xy 365.210708 -334.115471) (xy 365.234982 -334.08239)
			(xy 365.261398 -334.047084) (xy 365.14786 -333.933546) (xy 361.626658 -333.933546) (xy 361.58932 -333.970884)
			(xy 361.58932 -336.885026) (xy 361.81919 -337.114896) (xy 361.83189 -337.12404) (xy 361.835192 -337.125818)
			(xy 361.874757 -337.146888) (xy 361.950393 -337.195006) (xy 362.021496 -337.249599) (xy 362.087514 -337.310244)
			(xy 362.147933 -337.376469) (xy 362.202283 -337.447759) (xy 362.250142 -337.523559) (xy 362.271056 -337.563206)
			(xy 362.274612 -337.570318) (xy 362.318554 -337.61426) (xy 363.465872 -337.61426) (xy 363.475935 -337.614698)
			(xy 363.494515 -337.622437) (xy 363.50194 -337.629246) (xy 363.709966 -337.837272) (xy 363.716805 -337.844673)
			(xy 363.724518 -337.863271) (xy 363.724952 -337.87334) (xy 363.724952 -339.5853) (xy 363.724527 -339.595369)
			(xy 363.716808 -339.613969) (xy 363.709966 -339.621368) (xy 363.496098 -339.835236) (xy 363.488703 -339.842089)
			(xy 363.470104 -339.849833) (xy 363.46003 -339.850222) (xy 357.446834 -339.850222) (xy 357.436769 -339.849787)
			(xy 357.418179 -339.842059) (xy 357.410766 -339.835236) (xy 357.041958 -339.466428) (xy 357.035116 -339.459029)
			(xy 357.027399 -339.44043) (xy 357.026972 -339.43036) (xy 357.026972 -338.813394) (xy 357.031798 -338.808568)
			(xy 357.031798 -335.5721) (xy 357.010674 -335.536237) (xy 356.97548 -335.460805) (xy 356.94871 -335.38199)
			(xy 356.930682 -335.300728) (xy 356.92161 -335.217987) (xy 356.921054 -335.176368) (xy 356.921606 -335.135421)
			(xy 356.930405 -335.054) (xy 356.947878 -334.973992) (xy 356.973824 -334.896316) (xy 356.990396 -334.858868)
			(xy 356.97382 -334.821421) (xy 356.947865 -334.743747) (xy 356.930387 -334.663738) (xy 356.921588 -334.582316)
			(xy 356.921054 -334.541368) (xy 356.92163 -334.500048) (xy 356.93059 -334.417895) (xy 356.94837 -334.33719)
			(xy 356.974762 -334.258878) (xy 357.009456 -334.183873) (xy 357.030274 -334.148176) (xy 357.034338 -334.141064)
			(xy 357.039164 -334.119982) (xy 357.039164 -334.02905) (xy 357.024432 -333.992728) (xy 356.96525 -333.933546)
			(xy 353.466146 -333.933546) (xy 353.428808 -333.970884) (xy 353.428808 -336.848196) (xy 353.745292 -337.16468)
			(xy 353.749356 -337.168998) (xy 353.754436 -337.172046) (xy 353.791246 -337.196144) (xy 353.860994 -337.249782)
			(xy 353.925844 -337.309248) (xy 353.985311 -337.374098) (xy 354.03895 -337.443845) (xy 354.063046 -337.480656)
			(xy 354.06584 -337.485228) (xy 354.160074 -337.579462) (xy 355.358954 -337.579462) (xy 355.369018 -337.579897)
			(xy 355.387603 -337.587632) (xy 355.395022 -337.594448) (xy 355.64445 -337.843876) (xy 355.65129 -337.851276)
			(xy 355.659005 -337.869875) (xy 355.659436 -337.879944) (xy 355.659436 -339.591142) (xy 355.659004 -339.601207)
			(xy 355.651271 -339.619795) (xy 355.64445 -339.62721) (xy 355.532182 -339.739478) (xy 355.520752 -339.739478)
			(xy 355.409754 -339.850476) (xy 355.402354 -339.857318) (xy 355.383756 -339.865039) (xy 355.373686 -339.865462)
			(xy 349.496634 -339.865462) (xy 349.48657 -339.865026) (xy 349.467986 -339.857291) (xy 349.460566 -339.850476)
			(xy 349.002096 -339.391752) (xy 348.908116 -339.297772) (xy 348.908116 -334.992218) (xy 348.885381 -334.960365)
			(xy 348.845817 -334.892839) (xy 348.813376 -334.821617) (xy 348.7884 -334.747447) (xy 348.771151 -334.671109)
			(xy 348.761811 -334.593406) (xy 348.760478 -334.515154) (xy 348.767166 -334.437178) (xy 348.781805 -334.360297)
			(xy 348.804241 -334.285319) (xy 348.834238 -334.213033) (xy 348.87148 -334.1442) (xy 348.89313 -334.1116)
			(xy 348.917006 -334.076802) (xy 348.885256 -334.045306) (xy 348.86392 -333.992728) (xy 348.804738 -333.933546)
			(xy 345.305634 -333.933546) (xy 345.268296 -333.970884) (xy 345.268296 -336.910934) (xy 345.27871 -336.941668)
			(xy 345.283536 -336.948018) (xy 345.299722 -336.970306) (xy 345.329213 -337.016834) (xy 345.342464 -337.040982)
			(xy 345.347404 -337.049267) (xy 345.362153 -337.061676) (xy 345.371166 -337.065112) (xy 345.412783 -337.079664)
			(xy 345.493564 -337.115002) (xy 345.570982 -337.157199) (xy 345.644457 -337.20594) (xy 345.713437 -337.260857)
			(xy 345.777404 -337.32154) (xy 345.835879 -337.387531) (xy 345.888422 -337.458337) (xy 345.934639 -337.533425)
			(xy 345.954858 -337.572604) (xy 345.961208 -337.585304) (xy 346.006674 -337.614006) (xy 347.253814 -337.614006)
			(xy 347.263883 -337.614432) (xy 347.282483 -337.622151) (xy 347.289882 -337.628992) (xy 347.43009 -337.7692)
			(xy 347.436937 -337.776598) (xy 347.444673 -337.795196) (xy 347.445076 -337.805268) (xy 347.445076 -339.18398)
			(xy 347.444638 -339.194043) (xy 347.4369 -339.212624) (xy 347.43009 -339.220048) (xy 347.2434 -339.406738)
			(xy 347.236005 -339.413591) (xy 347.217406 -339.421336) (xy 347.207332 -339.421724) (xy 342.856312 -339.421724)
			(xy 342.469978 -339.808058) (xy 342.46258 -339.814906) (xy 342.443982 -339.822639) (xy 342.43391 -339.823044)
			(xy 341.849964 -339.823044) (xy 341.839898 -339.822613) (xy 341.821308 -339.814883) (xy 341.813896 -339.808058)
			(xy 341.095584 -339.089746) (xy 341.072216 -339.076538) (xy 341.065866 -339.075014) (xy 341.007351 -339.059345)
			(xy 340.892403 -339.021082) (xy 340.780329 -338.975076) (xy 340.72576 -338.948776) (xy 340.72576 -338.397088)
			(xy 340.73846 -338.384388) (xy 340.73846 -337.497928) (xy 340.584282 -337.34375) (xy 337.145122 -337.34375)
			(xy 337.107784 -337.381088) (xy 337.107784 -340.340442) (xy 337.2612 -340.493858) (xy 337.303966 -340.511432)
			(xy 337.386428 -340.553265) (xy 337.464752 -340.602411) (xy 337.538291 -340.658463) (xy 337.606439 -340.72096)
			(xy 337.668632 -340.789385) (xy 337.724357 -340.863173) (xy 337.773154 -340.941715) (xy 337.794346 -340.982808)
			(xy 337.800696 -340.995508) (xy 337.846162 -341.02421) (xy 338.985352 -341.02421) (xy 338.990305 -341.024334)
			(xy 339.000023 -341.026262) (xy 339.004656 -341.02802) (xy 339.1154 -341.074248) (xy 339.119961 -341.076259)
			(xy 339.12827 -341.081764) (xy 339.13191 -341.08517) (xy 339.235288 -341.188548) (xy 339.238723 -341.192165)
			(xy 339.244226 -341.200482) (xy 339.24621 -341.205058) (xy 339.292438 -341.315802) (xy 339.294212 -341.32043)
			(xy 339.296132 -341.330151) (xy 339.296248 -341.335106) (xy 339.296248 -342.733884) (xy 339.295808 -342.743946)
			(xy 339.288066 -342.762524) (xy 339.281262 -342.769952) (xy 338.873338 -343.177876) (xy 338.865937 -343.184715)
			(xy 338.847339 -343.192431) (xy 338.83727 -343.192862) (xy 334.495648 -343.192862) (xy 334.211168 -343.477342)
			(xy 334.20377 -343.48419) (xy 334.185172 -343.491922) (xy 334.1751 -343.492328) (xy 333.772764 -343.492328)
			(xy 333.762696 -343.491899) (xy 333.744098 -343.484179) (xy 333.736696 -343.477342) (xy 333.452216 -343.192862)
			(xy 329.099672 -343.192862) (xy 328.947272 -343.345262) (xy 328.947272 -344.664284) (xy 344.41511 -344.664284)
			(xy 344.41511 -343.140284) (xy 344.415521 -343.126964) (xy 344.42242 -343.101232) (xy 344.435743 -343.078162)
			(xy 344.454583 -343.059327) (xy 344.477656 -343.04601) (xy 344.50339 -343.039117) (xy 344.51671 -343.038684)
			(xy 346.04071 -343.038684) (xy 346.054028 -343.039126) (xy 346.079756 -343.046021) (xy 346.102823 -343.059339)
			(xy 346.121657 -343.078173) (xy 346.134977 -343.101239) (xy 346.141874 -343.126966) (xy 346.14231 -343.140284)
			(xy 346.14231 -343.944645) (xy 346.889574 -343.944645) (xy 346.889574 -343.859923) (xy 346.897627 -343.775586)
			(xy 346.913661 -343.692396) (xy 346.937529 -343.611106) (xy 346.969017 -343.532454) (xy 347.007839 -343.457151)
			(xy 347.053642 -343.385879) (xy 347.106013 -343.319283) (xy 347.164478 -343.257968) (xy 347.228506 -343.202487)
			(xy 347.297518 -343.153344) (xy 347.370888 -343.110984) (xy 347.447953 -343.075789) (xy 347.528015 -343.04808)
			(xy 347.610348 -343.028106) (xy 347.694207 -343.016049) (xy 347.778832 -343.012018) (xy 347.863457 -343.016049)
			(xy 347.947316 -343.028106) (xy 348.029649 -343.04808) (xy 348.109711 -343.075789) (xy 348.186776 -343.110984)
			(xy 348.260146 -343.153344) (xy 348.329158 -343.202487) (xy 348.393186 -343.257968) (xy 348.451651 -343.319283)
			(xy 348.504022 -343.385879) (xy 348.549825 -343.457151) (xy 348.588647 -343.532454) (xy 348.620135 -343.611106)
			(xy 348.644003 -343.692396) (xy 348.660037 -343.775586) (xy 348.66809 -343.859923) (xy 348.668594 -343.902284)
			(xy 348.66809 -343.944645) (xy 348.660037 -344.028982) (xy 348.644003 -344.112172) (xy 348.620135 -344.193462)
			(xy 348.588647 -344.272114) (xy 348.549825 -344.347417) (xy 348.504022 -344.418689) (xy 348.451651 -344.485285)
			(xy 348.393186 -344.5466) (xy 348.329158 -344.602081) (xy 348.260146 -344.651224) (xy 348.237525 -344.664284)
			(xy 351.975674 -344.664284) (xy 351.975674 -343.140284) (xy 351.97612 -343.126967) (xy 351.983016 -343.10124)
			(xy 351.996334 -343.078174) (xy 352.015166 -343.05934) (xy 352.038231 -343.04602) (xy 352.063957 -343.039122)
			(xy 352.077274 -343.038684) (xy 353.601274 -343.038684) (xy 353.614595 -343.039118) (xy 353.640332 -343.046008)
			(xy 353.663408 -343.059324) (xy 353.682251 -343.078159) (xy 353.695576 -343.101229) (xy 353.702476 -343.126963)
			(xy 353.702874 -343.140284) (xy 353.702874 -343.944645) (xy 354.450138 -343.944645) (xy 354.450138 -343.859923)
			(xy 354.458191 -343.775586) (xy 354.474225 -343.692396) (xy 354.498093 -343.611106) (xy 354.529581 -343.532454)
			(xy 354.568403 -343.457151) (xy 354.614206 -343.385879) (xy 354.666577 -343.319283) (xy 354.725042 -343.257968)
			(xy 354.78907 -343.202487) (xy 354.858082 -343.153344) (xy 354.931452 -343.110984) (xy 355.008517 -343.075789)
			(xy 355.088579 -343.04808) (xy 355.170912 -343.028106) (xy 355.254771 -343.016049) (xy 355.339396 -343.012018)
			(xy 355.424021 -343.016049) (xy 355.50788 -343.028106) (xy 355.590213 -343.04808) (xy 355.670275 -343.075789)
			(xy 355.74734 -343.110984) (xy 355.82071 -343.153344) (xy 355.889722 -343.202487) (xy 355.95375 -343.257968)
			(xy 356.012215 -343.319283) (xy 356.064586 -343.385879) (xy 356.110389 -343.457151) (xy 356.149211 -343.532454)
			(xy 356.180699 -343.611106) (xy 356.204567 -343.692396) (xy 356.220601 -343.775586) (xy 356.228654 -343.859923)
			(xy 356.229158 -343.902284) (xy 356.228654 -343.944645) (xy 356.220601 -344.028982) (xy 356.204567 -344.112172)
			(xy 356.180699 -344.193462) (xy 356.149211 -344.272114) (xy 356.110389 -344.347417) (xy 356.064586 -344.418689)
			(xy 356.012215 -344.485285) (xy 355.95375 -344.5466) (xy 355.889722 -344.602081) (xy 355.82071 -344.651224)
			(xy 355.798089 -344.664284) (xy 359.681018 -344.664284) (xy 359.681018 -343.140284) (xy 359.681382 -343.126958)
			(xy 359.688284 -343.101215) (xy 359.701614 -343.078136) (xy 359.720463 -343.059293) (xy 359.743547 -343.045971)
			(xy 359.769292 -343.039078) (xy 359.782618 -343.038684) (xy 361.306618 -343.038684) (xy 361.319936 -343.039119)
			(xy 361.345664 -343.046016) (xy 361.368731 -343.059335) (xy 361.387566 -343.07817) (xy 361.400885 -343.101238)
			(xy 361.407782 -343.126966) (xy 361.408218 -343.140284) (xy 361.408218 -343.944645) (xy 362.155482 -343.944645)
			(xy 362.155482 -343.859923) (xy 362.163535 -343.775586) (xy 362.179569 -343.692396) (xy 362.203437 -343.611106)
			(xy 362.234925 -343.532454) (xy 362.273747 -343.457151) (xy 362.31955 -343.385879) (xy 362.371921 -343.319283)
			(xy 362.430386 -343.257968) (xy 362.494414 -343.202487) (xy 362.563426 -343.153344) (xy 362.636796 -343.110984)
			(xy 362.713861 -343.075789) (xy 362.793923 -343.04808) (xy 362.876256 -343.028106) (xy 362.960115 -343.016049)
			(xy 363.04474 -343.012018) (xy 363.129365 -343.016049) (xy 363.213224 -343.028106) (xy 363.295557 -343.04808)
			(xy 363.375619 -343.075789) (xy 363.452684 -343.110984) (xy 363.526054 -343.153344) (xy 363.595066 -343.202487)
			(xy 363.659094 -343.257968) (xy 363.717559 -343.319283) (xy 363.76993 -343.385879) (xy 363.815733 -343.457151)
			(xy 363.854555 -343.532454) (xy 363.886043 -343.611106) (xy 363.909911 -343.692396) (xy 363.925945 -343.775586)
			(xy 363.933998 -343.859923) (xy 363.934502 -343.902284) (xy 363.933998 -343.944645) (xy 363.925945 -344.028982)
			(xy 363.909911 -344.112172) (xy 363.886043 -344.193462) (xy 363.854555 -344.272114) (xy 363.815733 -344.347417)
			(xy 363.76993 -344.418689) (xy 363.717559 -344.485285) (xy 363.659094 -344.5466) (xy 363.595066 -344.602081)
			(xy 363.526054 -344.651224) (xy 363.503433 -344.664284) (xy 367.241582 -344.664284) (xy 367.241582 -343.140284)
			(xy 367.24202 -343.126966) (xy 367.248917 -343.101238) (xy 367.262236 -343.078172) (xy 367.28107 -343.059337)
			(xy 367.304137 -343.046018) (xy 367.329864 -343.039121) (xy 367.343182 -343.038684) (xy 368.867182 -343.038684)
			(xy 368.880504 -343.039111) (xy 368.90624 -343.046003) (xy 368.929316 -343.05932) (xy 368.948159 -343.078157)
			(xy 368.961484 -343.101228) (xy 368.968384 -343.126962) (xy 368.968782 -343.140284) (xy 368.968782 -343.944645)
			(xy 369.716046 -343.944645) (xy 369.716046 -343.859923) (xy 369.724099 -343.775586) (xy 369.740133 -343.692396)
			(xy 369.764001 -343.611106) (xy 369.795489 -343.532454) (xy 369.834311 -343.457151) (xy 369.880114 -343.385879)
			(xy 369.932485 -343.319283) (xy 369.99095 -343.257968) (xy 370.054978 -343.202487) (xy 370.12399 -343.153344)
			(xy 370.19736 -343.110984) (xy 370.274425 -343.075789) (xy 370.354487 -343.04808) (xy 370.43682 -343.028106)
			(xy 370.520679 -343.016049) (xy 370.605304 -343.012018) (xy 370.689929 -343.016049) (xy 370.773788 -343.028106)
			(xy 370.856121 -343.04808) (xy 370.936183 -343.075789) (xy 371.013248 -343.110984) (xy 371.086618 -343.153344)
			(xy 371.15563 -343.202487) (xy 371.219658 -343.257968) (xy 371.278123 -343.319283) (xy 371.330494 -343.385879)
			(xy 371.376297 -343.457151) (xy 371.415119 -343.532454) (xy 371.446607 -343.611106) (xy 371.470475 -343.692396)
			(xy 371.486509 -343.775586) (xy 371.494562 -343.859923) (xy 371.495066 -343.902284) (xy 371.494562 -343.944645)
			(xy 371.486509 -344.028982) (xy 371.470475 -344.112172) (xy 371.446607 -344.193462) (xy 371.415119 -344.272114)
			(xy 371.376297 -344.347417) (xy 371.330494 -344.418689) (xy 371.278123 -344.485285) (xy 371.219658 -344.5466)
			(xy 371.15563 -344.602081) (xy 371.086618 -344.651224) (xy 371.013248 -344.693584) (xy 370.936183 -344.728779)
			(xy 370.856121 -344.756488) (xy 370.773788 -344.776462) (xy 370.689929 -344.788519) (xy 370.605304 -344.792551)
			(xy 370.520679 -344.788519) (xy 370.43682 -344.776462) (xy 370.354487 -344.756488) (xy 370.274425 -344.728779)
			(xy 370.19736 -344.693584) (xy 370.12399 -344.651224) (xy 370.054978 -344.602081) (xy 369.99095 -344.5466)
			(xy 369.932485 -344.485285) (xy 369.880114 -344.418689) (xy 369.834311 -344.347417) (xy 369.795489 -344.272114)
			(xy 369.764001 -344.193462) (xy 369.740133 -344.112172) (xy 369.724099 -344.028982) (xy 369.716046 -343.944645)
			(xy 368.968782 -343.944645) (xy 368.968782 -344.664284) (xy 368.96839 -344.677609) (xy 368.961495 -344.70335)
			(xy 368.948172 -344.72643) (xy 368.929328 -344.745273) (xy 368.906248 -344.758596) (xy 368.880507 -344.76549)
			(xy 368.867182 -344.765884) (xy 368.750342 -344.765884) (xy 368.74831 -344.766138) (xy 368.740182 -344.766392)
			(xy 367.470182 -344.766392) (xy 367.4618 -344.766138) (xy 367.459768 -344.765884) (xy 367.343182 -344.765884)
			(xy 367.329861 -344.765481) (xy 367.304128 -344.758581) (xy 367.281058 -344.745256) (xy 367.262223 -344.726415)
			(xy 367.248906 -344.70334) (xy 367.242014 -344.677605) (xy 367.241582 -344.664284) (xy 363.503433 -344.664284)
			(xy 363.452684 -344.693584) (xy 363.375619 -344.728779) (xy 363.295557 -344.756488) (xy 363.213224 -344.776462)
			(xy 363.129365 -344.788519) (xy 363.04474 -344.792551) (xy 362.960115 -344.788519) (xy 362.876256 -344.776462)
			(xy 362.793923 -344.756488) (xy 362.713861 -344.728779) (xy 362.636796 -344.693584) (xy 362.563426 -344.651224)
			(xy 362.494414 -344.602081) (xy 362.430386 -344.5466) (xy 362.371921 -344.485285) (xy 362.31955 -344.418689)
			(xy 362.273747 -344.347417) (xy 362.234925 -344.272114) (xy 362.203437 -344.193462) (xy 362.179569 -344.112172)
			(xy 362.163535 -344.028982) (xy 362.155482 -343.944645) (xy 361.408218 -343.944645) (xy 361.408218 -344.664284)
			(xy 361.407752 -344.677601) (xy 361.400863 -344.703327) (xy 361.38755 -344.726394) (xy 361.368721 -344.745229)
			(xy 361.345659 -344.75855) (xy 361.319934 -344.765447) (xy 361.306618 -344.765884) (xy 361.189778 -344.765884)
			(xy 361.187746 -344.766138) (xy 361.179618 -344.766392) (xy 359.909618 -344.766392) (xy 359.901236 -344.766138)
			(xy 359.899204 -344.765884) (xy 359.782618 -344.765884) (xy 359.769294 -344.765488) (xy 359.743552 -344.758594)
			(xy 359.720473 -344.745272) (xy 359.70163 -344.726428) (xy 359.688306 -344.70335) (xy 359.681412 -344.677608)
			(xy 359.681018 -344.664284) (xy 355.798089 -344.664284) (xy 355.74734 -344.693584) (xy 355.670275 -344.728779)
			(xy 355.590213 -344.756488) (xy 355.50788 -344.776462) (xy 355.424021 -344.788519) (xy 355.339396 -344.792551)
			(xy 355.254771 -344.788519) (xy 355.170912 -344.776462) (xy 355.088579 -344.756488) (xy 355.008517 -344.728779)
			(xy 354.931452 -344.693584) (xy 354.858082 -344.651224) (xy 354.78907 -344.602081) (xy 354.725042 -344.5466)
			(xy 354.666577 -344.485285) (xy 354.614206 -344.418689) (xy 354.568403 -344.347417) (xy 354.529581 -344.272114)
			(xy 354.498093 -344.193462) (xy 354.474225 -344.112172) (xy 354.458191 -344.028982) (xy 354.450138 -343.944645)
			(xy 353.702874 -343.944645) (xy 353.702874 -344.664284) (xy 353.70249 -344.677609) (xy 353.695595 -344.703352)
			(xy 353.68227 -344.726432) (xy 353.663424 -344.745276) (xy 353.640343 -344.758598) (xy 353.614599 -344.765491)
			(xy 353.601274 -344.765884) (xy 353.484434 -344.765884) (xy 353.482402 -344.766138) (xy 353.474274 -344.766392)
			(xy 352.204274 -344.766392) (xy 352.195892 -344.766138) (xy 352.19386 -344.765884) (xy 352.077274 -344.765884)
			(xy 352.063953 -344.765488) (xy 352.03822 -344.758586) (xy 352.01515 -344.74526) (xy 351.996314 -344.726417)
			(xy 351.982998 -344.703341) (xy 351.976106 -344.677605) (xy 351.975674 -344.664284) (xy 348.237525 -344.664284)
			(xy 348.186776 -344.693584) (xy 348.109711 -344.728779) (xy 348.029649 -344.756488) (xy 347.947316 -344.776462)
			(xy 347.863457 -344.788519) (xy 347.778832 -344.792551) (xy 347.694207 -344.788519) (xy 347.610348 -344.776462)
			(xy 347.528015 -344.756488) (xy 347.447953 -344.728779) (xy 347.370888 -344.693584) (xy 347.297518 -344.651224)
			(xy 347.228506 -344.602081) (xy 347.164478 -344.5466) (xy 347.106013 -344.485285) (xy 347.053642 -344.418689)
			(xy 347.007839 -344.347417) (xy 346.969017 -344.272114) (xy 346.937529 -344.193462) (xy 346.913661 -344.112172)
			(xy 346.897627 -344.028982) (xy 346.889574 -343.944645) (xy 346.14231 -343.944645) (xy 346.14231 -344.664284)
			(xy 346.14189 -344.677606) (xy 346.134998 -344.703344) (xy 346.121679 -344.72642) (xy 346.102841 -344.745263)
			(xy 346.079768 -344.758588) (xy 346.054032 -344.765487) (xy 346.04071 -344.765884) (xy 345.92387 -344.765884)
			(xy 345.921838 -344.766138) (xy 345.91371 -344.766392) (xy 344.64371 -344.766392) (xy 344.635328 -344.766138)
			(xy 344.633296 -344.765884) (xy 344.51671 -344.765884) (xy 344.503385 -344.765495) (xy 344.477644 -344.758599)
			(xy 344.454565 -344.745275) (xy 344.435721 -344.726431) (xy 344.422398 -344.703351) (xy 344.415504 -344.677609)
			(xy 344.41511 -344.664284) (xy 328.947272 -344.664284) (xy 328.947272 -346.047822) (xy 329.413362 -346.513912)
			(xy 329.41641 -346.516706) (xy 329.416918 -346.517214) (xy 329.446812 -346.543331) (xy 329.502885 -346.599527)
			(xy 329.528932 -346.629482) (xy 329.714352 -346.814902) (xy 330.82484 -346.814902) (xy 330.829187 -346.815007)
			(xy 330.837748 -346.816532) (xy 330.841858 -346.81795) (xy 330.849986 -346.820744) (xy 331.035152 -346.820744)
			(xy 331.045217 -346.821178) (xy 331.063804 -346.828911) (xy 331.07122 -346.83573) (xy 331.147166 -346.911676)
			(xy 331.154004 -346.919077) (xy 331.161716 -346.937676) (xy 331.162152 -346.947744) (xy 331.162152 -349.053912)
			(xy 331.200506 -349.103188) (xy 331.21727 -349.107506) (xy 331.317434 -349.133458) (xy 331.51595 -349.191905)
			(xy 331.712138 -349.257744) (xy 331.905724 -349.330882) (xy 332.096435 -349.411217) (xy 332.284005 -349.498636)
			(xy 332.468171 -349.593016) (xy 332.648673 -349.694226) (xy 332.82526 -349.802123) (xy 332.997683 -349.916556)
			(xy 333.165701 -350.037364) (xy 333.329077 -350.164379) (xy 333.487584 -350.297421) (xy 333.640998 -350.436305)
			(xy 333.789104 -350.580835) (xy 333.931695 -350.73081) (xy 334.068571 -350.886018) (xy 334.19954 -351.046242)
			(xy 334.324419 -351.211257) (xy 334.443031 -351.380832) (xy 334.555211 -351.554729) (xy 334.660801 -351.732704)
			(xy 334.759654 -351.914508) (xy 334.851631 -352.099886) (xy 334.936602 -352.288578) (xy 335.014449 -352.480318)
			(xy 335.085062 -352.674839) (xy 335.148343 -352.871867) (xy 335.204202 -353.071127) (xy 335.252562 -353.272338)
			(xy 335.273396 -353.37369) (xy 335.276952 -353.39147) (xy 335.326736 -353.432364) (xy 344.062304 -353.432364)
		)
		(stroke
			(width 0)
			(type solid)
		)
		(fill yes)
		(layer "B.Cu")
		(net "SW_P12V_PVCCIN_CPU0_FLT")
	)
	(gr_poly
		(pts
			(xy 108.632244 -241.244374) (xy 108.632244 -240.48085) (xy 108.20019 -240.048796) (xy 108.20019 -238.91367)
			(xy 108.293916 -238.819944) (xy 108.298488 -238.815372) (xy 108.379768 -238.734092) (xy 108.63072 -238.48314)
			(xy 114.14379 -238.48314) (xy 114.713766 -237.913164) (xy 117.068854 -237.913164) (xy 117.231922 -238.076232)
			(xy 117.231922 -238.140494) (xy 117.232176 -238.140748) (xy 117.232176 -239.456722) (xy 117.31498 -239.53978)
			(xy 118.63578 -239.53978) (xy 118.76278 -239.41278) (xy 118.76278 -239.10798) (xy 119.017288 -238.853472)
			(xy 119.373142 -238.853472) (xy 119.426482 -238.800132) (xy 119.426482 -237.868714) (xy 119.18823 -237.630462)
			(xy 117.459506 -237.630462) (xy 117.088158 -237.25886) (xy 117.088158 -236.31652) (xy 117.034564 -236.262926)
			(xy 116.241576 -236.262926) (xy 116.05387 -236.07522) (xy 116.05387 -235.901484) (xy 116.053426 -235.887477)
			(xy 116.045815 -235.860517) (xy 116.031169 -235.836636) (xy 116.010588 -235.81763) (xy 115.98562 -235.804927)
			(xy 115.958141 -235.79948) (xy 115.944142 -235.800138) (xy 115.907058 -235.801662) (xy 115.877345 -235.801186)
			(xy 115.818418 -235.79349) (xy 115.760983 -235.778234) (xy 115.706005 -235.755673) (xy 115.654409 -235.726187)
			(xy 115.607063 -235.690272) (xy 115.564762 -235.648532) (xy 115.528219 -235.601669) (xy 115.498047 -235.550471)
			(xy 115.474755 -235.495799) (xy 115.458733 -235.438573) (xy 115.450252 -235.379754) (xy 115.44935 -235.35005)
			(xy 115.448842 -235.300012) (xy 115.116102 -235.300012) (xy 115.096883 -235.299441) (xy 115.059755 -235.28949)
			(xy 115.02647 -235.270266) (xy 115.01247 -235.257086) (xy 114.561112 -234.805728) (xy 114.361722 -234.805728)
			(xy 114.32413 -234.843066) (xy 114.332512 -234.871768) (xy 114.338929 -234.895834) (xy 114.34581 -234.945163)
			(xy 114.346228 -234.970066) (xy 114.34573 -234.996715) (xy 114.337787 -235.049419) (xy 114.322077 -235.100349)
			(xy 114.298951 -235.14837) (xy 114.268927 -235.192407) (xy 114.232675 -235.231478) (xy 114.191004 -235.264709)
			(xy 114.144846 -235.291358) (xy 114.095232 -235.31083) (xy 114.04327 -235.32269) (xy 113.99012 -235.326674)
			(xy 113.93697 -235.32269) (xy 113.885008 -235.31083) (xy 113.835394 -235.291358) (xy 113.789236 -235.264709)
			(xy 113.747565 -235.231478) (xy 113.711313 -235.192407) (xy 113.681289 -235.14837) (xy 113.658163 -235.100349)
			(xy 113.642453 -235.049419) (xy 113.63451 -234.996715) (xy 113.634012 -234.970066) (xy 113.634335 -234.947826)
			(xy 113.639846 -234.903689) (xy 113.650828 -234.860586) (xy 113.65865 -234.839764) (xy 113.663375 -234.826439)
			(xy 113.666076 -234.798308) (xy 113.660968 -234.770513) (xy 113.648441 -234.74518) (xy 113.629454 -234.724248)
			(xy 113.605459 -234.709319) (xy 113.578292 -234.701534) (xy 113.564162 -234.70108) (xy 113.476024 -234.70108)
			(xy 113.461887 -234.701539) (xy 113.434696 -234.709291) (xy 113.410676 -234.724207) (xy 113.391672 -234.745142)
			(xy 113.379142 -234.770489) (xy 113.374049 -234.7983) (xy 113.376782 -234.826442) (xy 113.381536 -234.839764)
			(xy 113.393016 -234.871109) (xy 113.40541 -234.936693) (xy 113.406174 -234.970066) (xy 113.405676 -234.996715)
			(xy 113.397733 -235.049419) (xy 113.382023 -235.100349) (xy 113.358897 -235.14837) (xy 113.328873 -235.192407)
			(xy 113.292621 -235.231478) (xy 113.25095 -235.264709) (xy 113.204792 -235.291358) (xy 113.155178 -235.31083)
			(xy 113.103216 -235.32269) (xy 113.050066 -235.326674) (xy 112.996916 -235.32269) (xy 112.944954 -235.31083)
			(xy 112.89534 -235.291358) (xy 112.849182 -235.264709) (xy 112.807511 -235.231478) (xy 112.771259 -235.192407)
			(xy 112.741235 -235.14837) (xy 112.718109 -235.100349) (xy 112.702399 -235.049419) (xy 112.694456 -234.996715)
			(xy 112.693958 -234.970066) (xy 112.694281 -234.947826) (xy 112.699791 -234.903688) (xy 112.710772 -234.860585)
			(xy 112.718596 -234.839764) (xy 112.723322 -234.826441) (xy 112.726026 -234.798314) (xy 112.720918 -234.770522)
			(xy 112.70839 -234.745194) (xy 112.6894 -234.724269) (xy 112.665403 -234.709349) (xy 112.638236 -234.701577)
			(xy 112.624108 -234.70108) (xy 111.596424 -234.70108) (xy 111.582287 -234.701539) (xy 111.555096 -234.709291)
			(xy 111.531076 -234.724207) (xy 111.512072 -234.745142) (xy 111.499542 -234.770489) (xy 111.494449 -234.7983)
			(xy 111.497182 -234.826442) (xy 111.501936 -234.839764) (xy 111.513416 -234.871109) (xy 111.52581 -234.936693)
			(xy 111.526574 -234.970066) (xy 111.526076 -234.996715) (xy 111.518133 -235.049419) (xy 111.502423 -235.100349)
			(xy 111.479297 -235.14837) (xy 111.449273 -235.192407) (xy 111.413021 -235.231478) (xy 111.37135 -235.264709)
			(xy 111.325192 -235.291358) (xy 111.275578 -235.31083) (xy 111.223616 -235.32269) (xy 111.170466 -235.326674)
			(xy 111.117316 -235.32269) (xy 111.065354 -235.31083) (xy 111.01574 -235.291358) (xy 110.969582 -235.264709)
			(xy 110.927911 -235.231478) (xy 110.891659 -235.192407) (xy 110.861635 -235.14837) (xy 110.838509 -235.100349)
			(xy 110.822799 -235.049419) (xy 110.814856 -234.996715) (xy 110.814358 -234.970066) (xy 110.814493 -234.957641)
			(xy 110.81627 -234.932853) (xy 110.817914 -234.920536) (xy 110.821978 -234.890818) (xy 110.569756 -234.70108)
			(xy 109.716824 -234.70108) (xy 109.702687 -234.701539) (xy 109.675496 -234.709291) (xy 109.651476 -234.724207)
			(xy 109.632472 -234.745142) (xy 109.619942 -234.770489) (xy 109.614849 -234.7983) (xy 109.617582 -234.826442)
			(xy 109.622336 -234.839764) (xy 109.633816 -234.871109) (xy 109.64621 -234.936693) (xy 109.646974 -234.970066)
			(xy 109.646476 -234.996715) (xy 109.638533 -235.049419) (xy 109.622823 -235.100349) (xy 109.599697 -235.14837)
			(xy 109.569673 -235.192407) (xy 109.533421 -235.231478) (xy 109.49175 -235.264709) (xy 109.445592 -235.291358)
			(xy 109.395978 -235.31083) (xy 109.344016 -235.32269) (xy 109.290866 -235.326674) (xy 109.237716 -235.32269)
			(xy 109.185754 -235.31083) (xy 109.13614 -235.291358) (xy 109.089982 -235.264709) (xy 109.048311 -235.231478)
			(xy 109.012059 -235.192407) (xy 108.982035 -235.14837) (xy 108.958909 -235.100349) (xy 108.943199 -235.049419)
			(xy 108.935256 -234.996715) (xy 108.934758 -234.970066) (xy 108.935081 -234.947826) (xy 108.940591 -234.903688)
			(xy 108.951572 -234.860585) (xy 108.959396 -234.839764) (xy 108.964122 -234.826441) (xy 108.966826 -234.798314)
			(xy 108.961718 -234.770522) (xy 108.94919 -234.745194) (xy 108.9302 -234.724269) (xy 108.906203 -234.709349)
			(xy 108.879036 -234.701577) (xy 108.864908 -234.70108) (xy 108.7374 -234.70108) (xy 108.543852 -234.894628)
			(xy 108.541058 -234.91063) (xy 108.536291 -234.936607) (xy 108.521566 -234.98733) (xy 108.501113 -235.036026)
			(xy 108.48848 -235.05922) (xy 108.48848 -235.810531) (xy 109.40541 -235.810531) (xy 109.40541 -235.757233)
			(xy 109.413353 -235.704529) (xy 109.429063 -235.653599) (xy 109.452189 -235.605578) (xy 109.482213 -235.561541)
			(xy 109.518465 -235.52247) (xy 109.560136 -235.489239) (xy 109.606294 -235.46259) (xy 109.655908 -235.443118)
			(xy 109.70787 -235.431258) (xy 109.76102 -235.427275) (xy 109.81417 -235.431258) (xy 109.866132 -235.443118)
			(xy 109.915746 -235.46259) (xy 109.961904 -235.489239) (xy 110.003575 -235.52247) (xy 110.039827 -235.561541)
			(xy 110.069851 -235.605578) (xy 110.092977 -235.653599) (xy 110.108687 -235.704529) (xy 110.11663 -235.757233)
			(xy 110.117128 -235.783882) (xy 110.11663 -235.810531) (xy 110.34521 -235.810531) (xy 110.34521 -235.757233)
			(xy 110.353153 -235.704529) (xy 110.368863 -235.653599) (xy 110.391989 -235.605578) (xy 110.422013 -235.561541)
			(xy 110.458265 -235.52247) (xy 110.499936 -235.489239) (xy 110.546094 -235.46259) (xy 110.595708 -235.443118)
			(xy 110.64767 -235.431258) (xy 110.70082 -235.427275) (xy 110.75397 -235.431258) (xy 110.805932 -235.443118)
			(xy 110.855546 -235.46259) (xy 110.901704 -235.489239) (xy 110.943375 -235.52247) (xy 110.979627 -235.561541)
			(xy 111.009651 -235.605578) (xy 111.032777 -235.653599) (xy 111.048487 -235.704529) (xy 111.05643 -235.757233)
			(xy 111.056928 -235.783882) (xy 111.05643 -235.810531) (xy 111.28501 -235.810531) (xy 111.28501 -235.757233)
			(xy 111.292953 -235.704529) (xy 111.308663 -235.653599) (xy 111.331789 -235.605578) (xy 111.361813 -235.561541)
			(xy 111.398065 -235.52247) (xy 111.439736 -235.489239) (xy 111.485894 -235.46259) (xy 111.535508 -235.443118)
			(xy 111.58747 -235.431258) (xy 111.64062 -235.427275) (xy 111.69377 -235.431258) (xy 111.745732 -235.443118)
			(xy 111.795346 -235.46259) (xy 111.841504 -235.489239) (xy 111.883175 -235.52247) (xy 111.919427 -235.561541)
			(xy 111.949451 -235.605578) (xy 111.972577 -235.653599) (xy 111.988287 -235.704529) (xy 111.99623 -235.757233)
			(xy 111.996728 -235.783882) (xy 111.99623 -235.810531) (xy 112.22481 -235.810531) (xy 112.22481 -235.757233)
			(xy 112.232753 -235.704529) (xy 112.248463 -235.653599) (xy 112.271589 -235.605578) (xy 112.301613 -235.561541)
			(xy 112.337865 -235.52247) (xy 112.379536 -235.489239) (xy 112.425694 -235.46259) (xy 112.475308 -235.443118)
			(xy 112.52727 -235.431258) (xy 112.58042 -235.427275) (xy 112.63357 -235.431258) (xy 112.685532 -235.443118)
			(xy 112.735146 -235.46259) (xy 112.781304 -235.489239) (xy 112.822975 -235.52247) (xy 112.859227 -235.561541)
			(xy 112.889251 -235.605578) (xy 112.912377 -235.653599) (xy 112.928087 -235.704529) (xy 112.93603 -235.757233)
			(xy 112.936528 -235.783882) (xy 112.93603 -235.810531) (xy 114.10441 -235.810531) (xy 114.10441 -235.757233)
			(xy 114.112353 -235.704529) (xy 114.128063 -235.653599) (xy 114.151189 -235.605578) (xy 114.181213 -235.561541)
			(xy 114.217465 -235.52247) (xy 114.259136 -235.489239) (xy 114.305294 -235.46259) (xy 114.354908 -235.443118)
			(xy 114.40687 -235.431258) (xy 114.46002 -235.427275) (xy 114.51317 -235.431258) (xy 114.565132 -235.443118)
			(xy 114.614746 -235.46259) (xy 114.660904 -235.489239) (xy 114.702575 -235.52247) (xy 114.738827 -235.561541)
			(xy 114.768851 -235.605578) (xy 114.791977 -235.653599) (xy 114.807687 -235.704529) (xy 114.81563 -235.757233)
			(xy 114.816128 -235.783882) (xy 114.81563 -235.810531) (xy 114.807687 -235.863235) (xy 114.791977 -235.914165)
			(xy 114.768851 -235.962186) (xy 114.738827 -236.006223) (xy 114.702575 -236.045294) (xy 114.660904 -236.078525)
			(xy 114.614746 -236.105174) (xy 114.565132 -236.124646) (xy 114.51317 -236.136506) (xy 114.46002 -236.14049)
			(xy 114.40687 -236.136506) (xy 114.354908 -236.124646) (xy 114.305294 -236.105174) (xy 114.259136 -236.078525)
			(xy 114.217465 -236.045294) (xy 114.181213 -236.006223) (xy 114.151189 -235.962186) (xy 114.128063 -235.914165)
			(xy 114.112353 -235.863235) (xy 114.10441 -235.810531) (xy 112.93603 -235.810531) (xy 112.928087 -235.863235)
			(xy 112.912377 -235.914165) (xy 112.889251 -235.962186) (xy 112.859227 -236.006223) (xy 112.822975 -236.045294)
			(xy 112.781304 -236.078525) (xy 112.735146 -236.105174) (xy 112.685532 -236.124646) (xy 112.63357 -236.136506)
			(xy 112.58042 -236.14049) (xy 112.52727 -236.136506) (xy 112.475308 -236.124646) (xy 112.425694 -236.105174)
			(xy 112.379536 -236.078525) (xy 112.337865 -236.045294) (xy 112.301613 -236.006223) (xy 112.271589 -235.962186)
			(xy 112.248463 -235.914165) (xy 112.232753 -235.863235) (xy 112.22481 -235.810531) (xy 111.99623 -235.810531)
			(xy 111.988287 -235.863235) (xy 111.972577 -235.914165) (xy 111.949451 -235.962186) (xy 111.919427 -236.006223)
			(xy 111.883175 -236.045294) (xy 111.841504 -236.078525) (xy 111.795346 -236.105174) (xy 111.745732 -236.124646)
			(xy 111.69377 -236.136506) (xy 111.64062 -236.14049) (xy 111.58747 -236.136506) (xy 111.535508 -236.124646)
			(xy 111.485894 -236.105174) (xy 111.439736 -236.078525) (xy 111.398065 -236.045294) (xy 111.361813 -236.006223)
			(xy 111.331789 -235.962186) (xy 111.308663 -235.914165) (xy 111.292953 -235.863235) (xy 111.28501 -235.810531)
			(xy 111.05643 -235.810531) (xy 111.048487 -235.863235) (xy 111.032777 -235.914165) (xy 111.009651 -235.962186)
			(xy 110.979627 -236.006223) (xy 110.943375 -236.045294) (xy 110.901704 -236.078525) (xy 110.855546 -236.105174)
			(xy 110.805932 -236.124646) (xy 110.75397 -236.136506) (xy 110.70082 -236.14049) (xy 110.64767 -236.136506)
			(xy 110.595708 -236.124646) (xy 110.546094 -236.105174) (xy 110.499936 -236.078525) (xy 110.458265 -236.045294)
			(xy 110.422013 -236.006223) (xy 110.391989 -235.962186) (xy 110.368863 -235.914165) (xy 110.353153 -235.863235)
			(xy 110.34521 -235.810531) (xy 110.11663 -235.810531) (xy 110.108687 -235.863235) (xy 110.092977 -235.914165)
			(xy 110.069851 -235.962186) (xy 110.039827 -236.006223) (xy 110.003575 -236.045294) (xy 109.961904 -236.078525)
			(xy 109.915746 -236.105174) (xy 109.866132 -236.124646) (xy 109.81417 -236.136506) (xy 109.76102 -236.14049)
			(xy 109.70787 -236.136506) (xy 109.655908 -236.124646) (xy 109.606294 -236.105174) (xy 109.560136 -236.078525)
			(xy 109.518465 -236.045294) (xy 109.482213 -236.006223) (xy 109.452189 -235.962186) (xy 109.429063 -235.914165)
			(xy 109.413353 -235.863235) (xy 109.40541 -235.810531) (xy 108.48848 -235.810531) (xy 108.48848 -236.624347)
			(xy 108.935256 -236.624347) (xy 108.935256 -236.571049) (xy 108.943199 -236.518345) (xy 108.958909 -236.467415)
			(xy 108.982035 -236.419394) (xy 109.012059 -236.375357) (xy 109.048311 -236.336286) (xy 109.089982 -236.303055)
			(xy 109.13614 -236.276406) (xy 109.185754 -236.256934) (xy 109.237716 -236.245074) (xy 109.290866 -236.241091)
			(xy 109.344016 -236.245074) (xy 109.395978 -236.256934) (xy 109.445592 -236.276406) (xy 109.49175 -236.303055)
			(xy 109.533421 -236.336286) (xy 109.569673 -236.375357) (xy 109.599697 -236.419394) (xy 109.622823 -236.467415)
			(xy 109.638533 -236.518345) (xy 109.646476 -236.571049) (xy 109.646974 -236.597698) (xy 109.646476 -236.624347)
			(xy 110.814856 -236.624347) (xy 110.814856 -236.571049) (xy 110.822799 -236.518345) (xy 110.838509 -236.467415)
			(xy 110.861635 -236.419394) (xy 110.891659 -236.375357) (xy 110.927911 -236.336286) (xy 110.969582 -236.303055)
			(xy 111.01574 -236.276406) (xy 111.065354 -236.256934) (xy 111.117316 -236.245074) (xy 111.170466 -236.241091)
			(xy 111.223616 -236.245074) (xy 111.275578 -236.256934) (xy 111.325192 -236.276406) (xy 111.37135 -236.303055)
			(xy 111.413021 -236.336286) (xy 111.449273 -236.375357) (xy 111.479297 -236.419394) (xy 111.502423 -236.467415)
			(xy 111.518133 -236.518345) (xy 111.526076 -236.571049) (xy 111.526574 -236.597698) (xy 111.526076 -236.624347)
			(xy 112.694456 -236.624347) (xy 112.694456 -236.571049) (xy 112.702399 -236.518345) (xy 112.718109 -236.467415)
			(xy 112.741235 -236.419394) (xy 112.771259 -236.375357) (xy 112.807511 -236.336286) (xy 112.849182 -236.303055)
			(xy 112.89534 -236.276406) (xy 112.944954 -236.256934) (xy 112.996916 -236.245074) (xy 113.050066 -236.241091)
			(xy 113.103216 -236.245074) (xy 113.155178 -236.256934) (xy 113.204792 -236.276406) (xy 113.25095 -236.303055)
			(xy 113.292621 -236.336286) (xy 113.328873 -236.375357) (xy 113.358897 -236.419394) (xy 113.382023 -236.467415)
			(xy 113.397733 -236.518345) (xy 113.405676 -236.571049) (xy 113.406174 -236.597698) (xy 113.405676 -236.624347)
			(xy 113.63451 -236.624347) (xy 113.63451 -236.571049) (xy 113.642453 -236.518345) (xy 113.658163 -236.467415)
			(xy 113.681289 -236.419394) (xy 113.711313 -236.375357) (xy 113.747565 -236.336286) (xy 113.789236 -236.303055)
			(xy 113.835394 -236.276406) (xy 113.885008 -236.256934) (xy 113.93697 -236.245074) (xy 113.99012 -236.241091)
			(xy 114.04327 -236.245074) (xy 114.095232 -236.256934) (xy 114.144846 -236.276406) (xy 114.191004 -236.303055)
			(xy 114.232675 -236.336286) (xy 114.268927 -236.375357) (xy 114.298951 -236.419394) (xy 114.322077 -236.467415)
			(xy 114.337787 -236.518345) (xy 114.34573 -236.571049) (xy 114.346228 -236.597698) (xy 114.34573 -236.624347)
			(xy 114.337787 -236.677051) (xy 114.322077 -236.727981) (xy 114.298951 -236.776002) (xy 114.268927 -236.820039)
			(xy 114.232675 -236.85911) (xy 114.191004 -236.892341) (xy 114.144846 -236.91899) (xy 114.095232 -236.938462)
			(xy 114.04327 -236.950322) (xy 113.99012 -236.954306) (xy 113.93697 -236.950322) (xy 113.885008 -236.938462)
			(xy 113.835394 -236.91899) (xy 113.789236 -236.892341) (xy 113.747565 -236.85911) (xy 113.711313 -236.820039)
			(xy 113.681289 -236.776002) (xy 113.658163 -236.727981) (xy 113.642453 -236.677051) (xy 113.63451 -236.624347)
			(xy 113.405676 -236.624347) (xy 113.397733 -236.677051) (xy 113.382023 -236.727981) (xy 113.358897 -236.776002)
			(xy 113.328873 -236.820039) (xy 113.292621 -236.85911) (xy 113.25095 -236.892341) (xy 113.204792 -236.91899)
			(xy 113.155178 -236.938462) (xy 113.103216 -236.950322) (xy 113.050066 -236.954306) (xy 112.996916 -236.950322)
			(xy 112.944954 -236.938462) (xy 112.89534 -236.91899) (xy 112.849182 -236.892341) (xy 112.807511 -236.85911)
			(xy 112.771259 -236.820039) (xy 112.741235 -236.776002) (xy 112.718109 -236.727981) (xy 112.702399 -236.677051)
			(xy 112.694456 -236.624347) (xy 111.526076 -236.624347) (xy 111.518133 -236.677051) (xy 111.502423 -236.727981)
			(xy 111.479297 -236.776002) (xy 111.449273 -236.820039) (xy 111.413021 -236.85911) (xy 111.37135 -236.892341)
			(xy 111.325192 -236.91899) (xy 111.275578 -236.938462) (xy 111.223616 -236.950322) (xy 111.170466 -236.954306)
			(xy 111.117316 -236.950322) (xy 111.065354 -236.938462) (xy 111.01574 -236.91899) (xy 110.969582 -236.892341)
			(xy 110.927911 -236.85911) (xy 110.891659 -236.820039) (xy 110.861635 -236.776002) (xy 110.838509 -236.727981)
			(xy 110.822799 -236.677051) (xy 110.814856 -236.624347) (xy 109.646476 -236.624347) (xy 109.638533 -236.677051)
			(xy 109.622823 -236.727981) (xy 109.599697 -236.776002) (xy 109.569673 -236.820039) (xy 109.533421 -236.85911)
			(xy 109.49175 -236.892341) (xy 109.445592 -236.91899) (xy 109.395978 -236.938462) (xy 109.344016 -236.950322)
			(xy 109.290866 -236.954306) (xy 109.237716 -236.950322) (xy 109.185754 -236.938462) (xy 109.13614 -236.91899)
			(xy 109.089982 -236.892341) (xy 109.048311 -236.85911) (xy 109.012059 -236.820039) (xy 108.982035 -236.776002)
			(xy 108.958909 -236.727981) (xy 108.943199 -236.677051) (xy 108.935256 -236.624347) (xy 108.48848 -236.624347)
			(xy 108.48848 -237.438417) (xy 109.40541 -237.438417) (xy 109.40541 -237.385119) (xy 109.413353 -237.332415)
			(xy 109.429063 -237.281485) (xy 109.452189 -237.233464) (xy 109.482213 -237.189427) (xy 109.518465 -237.150356)
			(xy 109.560136 -237.117125) (xy 109.606294 -237.090476) (xy 109.655908 -237.071004) (xy 109.70787 -237.059144)
			(xy 109.76102 -237.055161) (xy 109.81417 -237.059144) (xy 109.866132 -237.071004) (xy 109.915746 -237.090476)
			(xy 109.961904 -237.117125) (xy 110.003575 -237.150356) (xy 110.039827 -237.189427) (xy 110.069851 -237.233464)
			(xy 110.092977 -237.281485) (xy 110.108687 -237.332415) (xy 110.11663 -237.385119) (xy 110.117128 -237.411768)
			(xy 110.11663 -237.438417) (xy 110.34521 -237.438417) (xy 110.34521 -237.385119) (xy 110.353153 -237.332415)
			(xy 110.368863 -237.281485) (xy 110.391989 -237.233464) (xy 110.422013 -237.189427) (xy 110.458265 -237.150356)
			(xy 110.499936 -237.117125) (xy 110.546094 -237.090476) (xy 110.595708 -237.071004) (xy 110.64767 -237.059144)
			(xy 110.70082 -237.055161) (xy 110.75397 -237.059144) (xy 110.805932 -237.071004) (xy 110.855546 -237.090476)
			(xy 110.901704 -237.117125) (xy 110.943375 -237.150356) (xy 110.979627 -237.189427) (xy 111.009651 -237.233464)
			(xy 111.032777 -237.281485) (xy 111.048487 -237.332415) (xy 111.05643 -237.385119) (xy 111.056928 -237.411768)
			(xy 111.05643 -237.438417) (xy 111.28501 -237.438417) (xy 111.28501 -237.385119) (xy 111.292953 -237.332415)
			(xy 111.308663 -237.281485) (xy 111.331789 -237.233464) (xy 111.361813 -237.189427) (xy 111.398065 -237.150356)
			(xy 111.439736 -237.117125) (xy 111.485894 -237.090476) (xy 111.535508 -237.071004) (xy 111.58747 -237.059144)
			(xy 111.64062 -237.055161) (xy 111.69377 -237.059144) (xy 111.745732 -237.071004) (xy 111.795346 -237.090476)
			(xy 111.841504 -237.117125) (xy 111.883175 -237.150356) (xy 111.919427 -237.189427) (xy 111.949451 -237.233464)
			(xy 111.972577 -237.281485) (xy 111.988287 -237.332415) (xy 111.99623 -237.385119) (xy 111.996728 -237.411768)
			(xy 111.99623 -237.438417) (xy 112.22481 -237.438417) (xy 112.22481 -237.385119) (xy 112.232753 -237.332415)
			(xy 112.248463 -237.281485) (xy 112.271589 -237.233464) (xy 112.301613 -237.189427) (xy 112.337865 -237.150356)
			(xy 112.379536 -237.117125) (xy 112.425694 -237.090476) (xy 112.475308 -237.071004) (xy 112.52727 -237.059144)
			(xy 112.58042 -237.055161) (xy 112.63357 -237.059144) (xy 112.685532 -237.071004) (xy 112.735146 -237.090476)
			(xy 112.781304 -237.117125) (xy 112.822975 -237.150356) (xy 112.859227 -237.189427) (xy 112.889251 -237.233464)
			(xy 112.912377 -237.281485) (xy 112.928087 -237.332415) (xy 112.93603 -237.385119) (xy 112.936528 -237.411768)
			(xy 112.93603 -237.438417) (xy 113.16461 -237.438417) (xy 113.16461 -237.385119) (xy 113.172553 -237.332415)
			(xy 113.188263 -237.281485) (xy 113.211389 -237.233464) (xy 113.241413 -237.189427) (xy 113.277665 -237.150356)
			(xy 113.319336 -237.117125) (xy 113.365494 -237.090476) (xy 113.415108 -237.071004) (xy 113.46707 -237.059144)
			(xy 113.52022 -237.055161) (xy 113.57337 -237.059144) (xy 113.625332 -237.071004) (xy 113.674946 -237.090476)
			(xy 113.721104 -237.117125) (xy 113.762775 -237.150356) (xy 113.799027 -237.189427) (xy 113.829051 -237.233464)
			(xy 113.852177 -237.281485) (xy 113.867887 -237.332415) (xy 113.87583 -237.385119) (xy 113.876328 -237.411768)
			(xy 113.87583 -237.438417) (xy 113.867887 -237.491121) (xy 113.852177 -237.542051) (xy 113.829051 -237.590072)
			(xy 113.799027 -237.634109) (xy 113.762775 -237.67318) (xy 113.721104 -237.706411) (xy 113.674946 -237.73306)
			(xy 113.625332 -237.752532) (xy 113.57337 -237.764392) (xy 113.52022 -237.768376) (xy 113.46707 -237.764392)
			(xy 113.415108 -237.752532) (xy 113.365494 -237.73306) (xy 113.319336 -237.706411) (xy 113.277665 -237.67318)
			(xy 113.241413 -237.634109) (xy 113.211389 -237.590072) (xy 113.188263 -237.542051) (xy 113.172553 -237.491121)
			(xy 113.16461 -237.438417) (xy 112.93603 -237.438417) (xy 112.928087 -237.491121) (xy 112.912377 -237.542051)
			(xy 112.889251 -237.590072) (xy 112.859227 -237.634109) (xy 112.822975 -237.67318) (xy 112.781304 -237.706411)
			(xy 112.735146 -237.73306) (xy 112.685532 -237.752532) (xy 112.63357 -237.764392) (xy 112.58042 -237.768376)
			(xy 112.52727 -237.764392) (xy 112.475308 -237.752532) (xy 112.425694 -237.73306) (xy 112.379536 -237.706411)
			(xy 112.337865 -237.67318) (xy 112.301613 -237.634109) (xy 112.271589 -237.590072) (xy 112.248463 -237.542051)
			(xy 112.232753 -237.491121) (xy 112.22481 -237.438417) (xy 111.99623 -237.438417) (xy 111.988287 -237.491121)
			(xy 111.972577 -237.542051) (xy 111.949451 -237.590072) (xy 111.919427 -237.634109) (xy 111.883175 -237.67318)
			(xy 111.841504 -237.706411) (xy 111.795346 -237.73306) (xy 111.745732 -237.752532) (xy 111.69377 -237.764392)
			(xy 111.64062 -237.768376) (xy 111.58747 -237.764392) (xy 111.535508 -237.752532) (xy 111.485894 -237.73306)
			(xy 111.439736 -237.706411) (xy 111.398065 -237.67318) (xy 111.361813 -237.634109) (xy 111.331789 -237.590072)
			(xy 111.308663 -237.542051) (xy 111.292953 -237.491121) (xy 111.28501 -237.438417) (xy 111.05643 -237.438417)
			(xy 111.048487 -237.491121) (xy 111.032777 -237.542051) (xy 111.009651 -237.590072) (xy 110.979627 -237.634109)
			(xy 110.943375 -237.67318) (xy 110.901704 -237.706411) (xy 110.855546 -237.73306) (xy 110.805932 -237.752532)
			(xy 110.75397 -237.764392) (xy 110.70082 -237.768376) (xy 110.64767 -237.764392) (xy 110.595708 -237.752532)
			(xy 110.546094 -237.73306) (xy 110.499936 -237.706411) (xy 110.458265 -237.67318) (xy 110.422013 -237.634109)
			(xy 110.391989 -237.590072) (xy 110.368863 -237.542051) (xy 110.353153 -237.491121) (xy 110.34521 -237.438417)
			(xy 110.11663 -237.438417) (xy 110.108687 -237.491121) (xy 110.092977 -237.542051) (xy 110.069851 -237.590072)
			(xy 110.039827 -237.634109) (xy 110.003575 -237.67318) (xy 109.961904 -237.706411) (xy 109.915746 -237.73306)
			(xy 109.866132 -237.752532) (xy 109.81417 -237.764392) (xy 109.76102 -237.768376) (xy 109.70787 -237.764392)
			(xy 109.655908 -237.752532) (xy 109.606294 -237.73306) (xy 109.560136 -237.706411) (xy 109.518465 -237.67318)
			(xy 109.482213 -237.634109) (xy 109.452189 -237.590072) (xy 109.429063 -237.542051) (xy 109.413353 -237.491121)
			(xy 109.40541 -237.438417) (xy 108.48848 -237.438417) (xy 108.48848 -237.549944) (xy 108.060744 -237.97768)
			(xy 103.45674 -237.97768) (xy 102.83952 -237.36046) (xy 102.687374 -237.36046) (xy 102.596696 -237.451138)
			(xy 102.594156 -237.467394) (xy 102.587298 -237.499906) (xy 102.585774 -237.506002) (xy 102.585774 -237.77194)
			(xy 102.101904 -238.25581) (xy 102.099618 -238.272574) (xy 102.095316 -238.298823) (xy 102.079434 -238.349586)
			(xy 102.055635 -238.397152) (xy 102.02453 -238.440297) (xy 101.986922 -238.477909) (xy 101.943779 -238.509018)
			(xy 101.896215 -238.532822) (xy 101.845454 -238.548709) (xy 101.819202 -238.55299) (xy 101.802438 -238.555276)
			(xy 101.625146 -238.732568) (xy 101.625146 -238.967518) (xy 101.626162 -238.972598) (xy 101.629371 -238.989112)
			(xy 101.632809 -239.022579) (xy 101.63302 -239.0394) (xy 101.885792 -239.0394) (xy 101.889775 -238.986254)
			(xy 101.901634 -238.934294) (xy 101.921104 -238.884683) (xy 101.94775 -238.838527) (xy 101.980977 -238.796857)
			(xy 102.020044 -238.760605) (xy 102.064077 -238.73058) (xy 102.112093 -238.707453) (xy 102.163019 -238.69174)
			(xy 102.215718 -238.683792) (xy 102.242366 -238.683292) (xy 102.268713 -238.683768) (xy 102.320831 -238.691528)
			(xy 102.371237 -238.706883) (xy 102.41883 -238.729498) (xy 102.462571 -238.75888) (xy 102.501504 -238.794387)
			(xy 102.534781 -238.835243) (xy 102.561673 -238.880556) (xy 102.581595 -238.929338) (xy 102.588314 -238.954818)
			(xy 102.592072 -238.968298) (xy 102.60585 -238.992642) (xy 102.625723 -239.012329) (xy 102.650195 -239.025877)
			(xy 102.677428 -239.032269) (xy 102.705374 -239.031023) (xy 102.73193 -239.022233) (xy 102.743762 -239.014762)
			(xy 102.765976 -239.000297) (xy 102.813796 -238.977423) (xy 102.864478 -238.961888) (xy 102.916901 -238.954034)
			(xy 102.943406 -238.953548) (xy 102.968076 -238.953948) (xy 103.016944 -238.960755) (xy 103.064402 -238.974251)
			(xy 103.109539 -238.994178) (xy 103.151489 -239.020152) (xy 103.170736 -239.03559) (xy 103.181866 -239.044217)
			(xy 103.207626 -239.055564) (xy 103.235506 -239.059445) (xy 103.263386 -239.055564) (xy 103.289146 -239.044217)
			(xy 103.300276 -239.03559) (xy 103.321692 -239.018467) (xy 103.368749 -238.990328) (xy 103.419566 -238.969739)
			(xy 103.472939 -238.957187) (xy 103.527606 -238.95297) (xy 103.582273 -238.957187) (xy 103.635646 -238.969739)
			(xy 103.686463 -238.990328) (xy 103.73352 -239.018467) (xy 103.754936 -239.03559) (xy 103.766066 -239.044217)
			(xy 103.791826 -239.055564) (xy 103.819706 -239.059445) (xy 103.847586 -239.055564) (xy 103.873346 -239.044217)
			(xy 103.884476 -239.03559) (xy 103.903716 -239.020146) (xy 103.945674 -238.994188) (xy 103.990814 -238.974272)
			(xy 104.038271 -238.960779) (xy 104.087137 -238.953968) (xy 104.111806 -238.953548) (xy 104.138452 -238.954134)
			(xy 104.191148 -238.962078) (xy 104.242071 -238.977787) (xy 104.290085 -239.000909) (xy 104.334116 -239.03093)
			(xy 104.373181 -239.067178) (xy 104.406407 -239.108843) (xy 104.433053 -239.154995) (xy 104.452522 -239.204602)
			(xy 104.464381 -239.256558) (xy 104.468363 -239.3097) (xy 104.464381 -239.362842) (xy 104.452522 -239.414798)
			(xy 104.433053 -239.464405) (xy 104.406407 -239.510557) (xy 104.373181 -239.552222) (xy 104.334116 -239.58847)
			(xy 104.290085 -239.618491) (xy 104.242071 -239.641613) (xy 104.191148 -239.657322) (xy 104.138452 -239.665266)
			(xy 104.111806 -239.665764) (xy 104.087136 -239.665354) (xy 104.038269 -239.658549) (xy 103.990811 -239.645055)
			(xy 103.945674 -239.625131) (xy 103.903724 -239.599159) (xy 103.884476 -239.583722) (xy 103.873346 -239.575095)
			(xy 103.847586 -239.563748) (xy 103.819706 -239.559867) (xy 103.791826 -239.563748) (xy 103.766066 -239.575095)
			(xy 103.754936 -239.583722) (xy 103.73352 -239.600845) (xy 103.686463 -239.628984) (xy 103.635646 -239.649573)
			(xy 103.582273 -239.662125) (xy 103.527606 -239.666342) (xy 103.472939 -239.662125) (xy 103.419566 -239.649573)
			(xy 103.368749 -239.628984) (xy 103.321692 -239.600845) (xy 103.300276 -239.583722) (xy 103.289146 -239.575095)
			(xy 103.263386 -239.563748) (xy 103.235506 -239.559867) (xy 103.207626 -239.563748) (xy 103.181866 -239.575095)
			(xy 103.170736 -239.583722) (xy 103.151493 -239.599163) (xy 103.109536 -239.625121) (xy 103.064397 -239.645037)
			(xy 103.01694 -239.658531) (xy 102.968075 -239.665344) (xy 102.943406 -239.665764) (xy 102.91706 -239.665256)
			(xy 102.864941 -239.657506) (xy 102.814534 -239.642158) (xy 102.76694 -239.619548) (xy 102.723198 -239.590171)
			(xy 102.684263 -239.554667) (xy 102.650987 -239.513812) (xy 102.624095 -239.468499) (xy 102.604176 -239.419717)
			(xy 102.597458 -239.394238) (xy 102.59376 -239.38074) (xy 102.579968 -239.356396) (xy 102.560084 -239.336711)
			(xy 102.535601 -239.323165) (xy 102.50836 -239.316778) (xy 102.480408 -239.318028) (xy 102.453845 -239.326821)
			(xy 102.44201 -239.334294) (xy 102.4198 -239.348766) (xy 102.371979 -239.371639) (xy 102.321296 -239.387173)
			(xy 102.268871 -239.395024) (xy 102.242366 -239.395508) (xy 102.215718 -239.395008) (xy 102.163019 -239.38706)
			(xy 102.112093 -239.371347) (xy 102.064077 -239.34822) (xy 102.020044 -239.318195) (xy 101.980977 -239.281943)
			(xy 101.94775 -239.240273) (xy 101.921104 -239.194117) (xy 101.901634 -239.144506) (xy 101.889775 -239.092546)
			(xy 101.885792 -239.0394) (xy 101.63302 -239.0394) (xy 101.632799 -239.056221) (xy 101.629364 -239.089687)
			(xy 101.626162 -239.106202) (xy 101.625146 -239.111282) (xy 101.625146 -239.225836) (xy 101.936296 -239.536986)
			(xy 101.942646 -239.540288) (xy 101.964922 -239.552905) (xy 102.005934 -239.583549) (xy 102.042135 -239.619748)
			(xy 102.072781 -239.660757) (xy 102.085394 -239.683036) (xy 102.088696 -239.689386) (xy 102.418896 -240.019332)
			(xy 102.451916 -240.019332) (xy 102.6414 -240.20907) (xy 102.6414 -240.81867) (xy 102.876096 -241.053112)
			(xy 104.110536 -241.053112) (xy 104.164384 -241.107214) (xy 104.79786 -241.107214) (xy 104.805988 -241.10696)
			(xy 106.72064 -241.10696) (xy 106.728514 -241.107214) (xy 107.046014 -241.107214) (xy 107.269026 -241.329972)
			(xy 107.282234 -241.34318) (xy 108.533184 -241.34318)
		)
		(stroke
			(width 0)
			(type solid)
		)
		(fill yes)
		(layer "B.Cu")
		(net "GND")
	)
	(gr_poly
		(pts
			(xy 356.572058 -241.24412) (xy 356.572058 -240.480596) (xy 356.140004 -240.048542) (xy 356.140004 -238.913416)
			(xy 356.14864 -238.90478) (xy 356.14864 -238.875062) (xy 356.562914 -238.460788) (xy 357.186738 -238.460788)
			(xy 357.188516 -238.462312) (xy 362.08208 -238.462312) (xy 362.691426 -237.85322) (xy 364.957614 -237.85322)
			(xy 365.210852 -238.106204) (xy 365.210852 -239.495584) (xy 365.254794 -239.539526) (xy 366.575594 -239.539526)
			(xy 366.702594 -239.412526) (xy 366.702594 -239.107726) (xy 366.957102 -238.853218) (xy 367.312956 -238.853218)
			(xy 367.366296 -238.799878) (xy 367.366296 -237.86846) (xy 367.128044 -237.630208) (xy 365.39932 -237.630208)
			(xy 365.027972 -237.258606) (xy 365.027972 -236.316266) (xy 364.974378 -236.262672) (xy 364.18139 -236.262672)
			(xy 363.993684 -236.074966) (xy 363.993684 -235.373926) (xy 363.993171 -235.358558) (xy 363.984054 -235.329207)
			(xy 363.966609 -235.303904) (xy 363.942419 -235.284944) (xy 363.913681 -235.27405) (xy 363.883001 -235.272209)
			(xy 363.867954 -235.275374) (xy 363.841317 -235.281446) (xy 363.787068 -235.287939) (xy 363.75975 -235.288328)
			(xy 363.731038 -235.287877) (xy 363.674064 -235.280691) (xy 363.618436 -235.266438) (xy 363.565026 -235.245341)
			(xy 363.514674 -235.217732) (xy 363.468169 -235.184044) (xy 363.42624 -235.144805) (xy 363.389547 -235.100632)
			(xy 363.358665 -235.052218) (xy 363.345984 -235.026454) (xy 363.332268 -234.997244) (xy 363.241082 -234.997244)
			(xy 363.224706 -234.996851) (xy 363.19258 -234.990481) (xy 363.162313 -234.977968) (xy 363.135068 -234.959793)
			(xy 363.123226 -234.948476) (xy 362.938314 -234.763564) (xy 362.925106 -234.748832) (xy 362.90544 -234.744239)
			(xy 362.865169 -234.741257) (xy 362.825001 -234.745412) (xy 362.786193 -234.756574) (xy 362.76788 -234.765088)
			(xy 362.754926 -234.772454) (xy 362.736892 -234.782868) (xy 362.732066 -234.785662) (xy 362.700348 -234.801927)
			(xy 362.634303 -234.828756) (xy 362.565904 -234.84884) (xy 362.49584 -234.861979) (xy 362.424812 -234.868041)
			(xy 362.389166 -234.867958) (xy 362.37573 -234.868161) (xy 362.349693 -234.874772) (xy 362.326283 -234.887948)
			(xy 362.307124 -234.906778) (xy 362.293543 -234.929955) (xy 362.286482 -234.955873) (xy 362.286042 -234.969304)
			(xy 362.286042 -234.969558) (xy 362.285562 -234.997572) (xy 362.276874 -235.052921) (xy 362.259627 -235.106227)
			(xy 362.234246 -235.156176) (xy 362.201357 -235.201534) (xy 362.161772 -235.241183) (xy 362.116468 -235.274145)
			(xy 362.066561 -235.299606) (xy 362.013282 -235.31694) (xy 361.957947 -235.325718) (xy 361.929934 -235.326174)
			(xy 361.9044 -235.325731) (xy 361.853857 -235.318428) (xy 361.804876 -235.303981) (xy 361.758459 -235.282687)
			(xy 361.71556 -235.254983) (xy 361.677057 -235.221435) (xy 361.643741 -235.182732) (xy 361.616293 -235.139668)
			(xy 361.595277 -235.093125) (xy 361.581123 -235.044058) (xy 361.577128 -235.018834) (xy 361.574902 -235.005694)
			(xy 361.564525 -234.981155) (xy 361.548145 -234.960141) (xy 361.526881 -234.944088) (xy 361.502184 -234.934091)
			(xy 361.475741 -234.930833) (xy 361.449356 -234.934536) (xy 361.43692 -234.939332) (xy 361.347258 -234.977432)
			(xy 361.343956 -235.00715) (xy 361.340776 -235.033079) (xy 361.327798 -235.083679) (xy 361.307569 -235.131842)
			(xy 361.280522 -235.176533) (xy 361.247238 -235.216794) (xy 361.208431 -235.251763) (xy 361.164932 -235.280688)
			(xy 361.117675 -235.30295) (xy 361.067673 -235.318071) (xy 361.015999 -235.325727) (xy 360.98988 -235.326174)
			(xy 360.961897 -235.325652) (xy 360.906619 -235.316893) (xy 360.853393 -235.299595) (xy 360.803528 -235.274184)
			(xy 360.758252 -235.241284) (xy 360.718681 -235.201706) (xy 360.685788 -235.156426) (xy 360.660384 -235.106557)
			(xy 360.643094 -235.053328) (xy 360.634344 -234.998049) (xy 360.633772 -234.970066) (xy 360.634085 -234.947784)
			(xy 360.639591 -234.903562) (xy 360.650589 -234.860377) (xy 360.65841 -234.83951) (xy 360.663143 -234.826184)
			(xy 360.665857 -234.798045) (xy 360.660756 -234.770241) (xy 360.648229 -234.744899) (xy 360.629237 -234.723961)
			(xy 360.605233 -234.70903) (xy 360.578056 -234.701249) (xy 360.563922 -234.700826) (xy 359.536238 -234.700826)
			(xy 359.522103 -234.701283) (xy 359.494916 -234.709033) (xy 359.4709 -234.723948) (xy 359.451901 -234.744883)
			(xy 359.439378 -234.770228) (xy 359.434294 -234.798037) (xy 359.437038 -234.826174) (xy 359.44175 -234.83951)
			(xy 359.453255 -234.870915) (xy 359.465662 -234.936628) (xy 359.466388 -234.970066) (xy 359.46587 -234.998053)
			(xy 359.457118 -235.053337) (xy 359.439825 -235.106572) (xy 359.414417 -235.156445) (xy 359.381518 -235.201729)
			(xy 359.34194 -235.241309) (xy 359.296657 -235.274209) (xy 359.246785 -235.29962) (xy 359.193551 -235.316915)
			(xy 359.138266 -235.325669) (xy 359.11028 -235.326174) (xy 359.08415 -235.325705) (xy 359.032453 -235.318049)
			(xy 358.982431 -235.302919) (xy 358.935158 -235.280639) (xy 358.891649 -235.251689) (xy 358.852839 -235.21669)
			(xy 358.819561 -235.176394) (xy 358.792531 -235.131667) (xy 358.772329 -235.083469) (xy 358.759389 -235.032836)
			(xy 358.756204 -235.006896) (xy 358.752902 -234.977178) (xy 358.328468 -234.796838) (xy 358.312212 -234.788456)
			(xy 358.284526 -234.772454) (xy 358.267104 -234.762948) (xy 358.22979 -234.749442) (xy 358.190703 -234.742586)
			(xy 358.151019 -234.742586) (xy 358.111932 -234.749442) (xy 358.074618 -234.762948) (xy 358.057196 -234.772454)
			(xy 358.047036 -234.778296) (xy 358.043734 -234.780074) (xy 358.011193 -234.797431) (xy 357.943232 -234.826085)
			(xy 357.872669 -234.847548) (xy 357.800263 -234.86159) (xy 357.726793 -234.868061) (xy 357.689912 -234.867958)
			(xy 357.676459 -234.86817) (xy 357.650396 -234.874811) (xy 357.626974 -234.888032) (xy 357.60782 -234.906913)
			(xy 357.594265 -234.930144) (xy 357.587252 -234.95611) (xy 357.586788 -234.969558) (xy 357.586308 -234.997571)
			(xy 357.577619 -235.052917) (xy 357.560371 -235.106219) (xy 357.53499 -235.156163) (xy 357.5021 -235.201517)
			(xy 357.462514 -235.24116) (xy 357.417209 -235.274116) (xy 357.367302 -235.299572) (xy 357.314025 -235.316898)
			(xy 357.258692 -235.325667) (xy 357.23068 -235.326174) (xy 357.203446 -235.325655) (xy 357.149615 -235.31736)
			(xy 357.097674 -235.300964) (xy 357.048834 -235.276852) (xy 357.004236 -235.245585) (xy 356.964917 -235.207893)
			(xy 356.931796 -235.164653) (xy 356.905644 -235.116875) (xy 356.887072 -235.065672) (xy 356.876512 -235.012239)
			(xy 356.874826 -234.985052) (xy 356.873855 -234.971735) (xy 356.865832 -234.946277) (xy 356.851478 -234.923772)
			(xy 356.831777 -234.905762) (xy 356.808077 -234.89348) (xy 356.782003 -234.887767) (xy 356.768654 -234.888024)
			(xy 356.54742 -234.888024) (xy 356.536244 -234.92333) (xy 356.524816 -234.956568) (xy 356.493212 -235.019345)
			(xy 356.452385 -235.076554) (xy 356.428294 -235.102146) (xy 356.428294 -235.136436) (xy 356.540308 -235.248196)
			(xy 356.540308 -235.810531) (xy 357.345224 -235.810531) (xy 357.345224 -235.757233) (xy 357.353167 -235.704529)
			(xy 357.368877 -235.653599) (xy 357.392003 -235.605578) (xy 357.422027 -235.561541) (xy 357.458279 -235.52247)
			(xy 357.49995 -235.489239) (xy 357.546108 -235.46259) (xy 357.595722 -235.443118) (xy 357.647684 -235.431258)
			(xy 357.700834 -235.427275) (xy 357.753984 -235.431258) (xy 357.805946 -235.443118) (xy 357.85556 -235.46259)
			(xy 357.901718 -235.489239) (xy 357.943389 -235.52247) (xy 357.979641 -235.561541) (xy 358.009665 -235.605578)
			(xy 358.032791 -235.653599) (xy 358.048501 -235.704529) (xy 358.056444 -235.757233) (xy 358.056942 -235.783882)
			(xy 358.056444 -235.810531) (xy 358.285024 -235.810531) (xy 358.285024 -235.757233) (xy 358.292967 -235.704529)
			(xy 358.308677 -235.653599) (xy 358.331803 -235.605578) (xy 358.361827 -235.561541) (xy 358.398079 -235.52247)
			(xy 358.43975 -235.489239) (xy 358.485908 -235.46259) (xy 358.535522 -235.443118) (xy 358.587484 -235.431258)
			(xy 358.640634 -235.427275) (xy 358.693784 -235.431258) (xy 358.745746 -235.443118) (xy 358.79536 -235.46259)
			(xy 358.841518 -235.489239) (xy 358.883189 -235.52247) (xy 358.919441 -235.561541) (xy 358.949465 -235.605578)
			(xy 358.972591 -235.653599) (xy 358.988301 -235.704529) (xy 358.996244 -235.757233) (xy 358.996742 -235.783882)
			(xy 358.996244 -235.810531) (xy 359.224824 -235.810531) (xy 359.224824 -235.757233) (xy 359.232767 -235.704529)
			(xy 359.248477 -235.653599) (xy 359.271603 -235.605578) (xy 359.301627 -235.561541) (xy 359.337879 -235.52247)
			(xy 359.37955 -235.489239) (xy 359.425708 -235.46259) (xy 359.475322 -235.443118) (xy 359.527284 -235.431258)
			(xy 359.580434 -235.427275) (xy 359.633584 -235.431258) (xy 359.685546 -235.443118) (xy 359.73516 -235.46259)
			(xy 359.781318 -235.489239) (xy 359.822989 -235.52247) (xy 359.859241 -235.561541) (xy 359.889265 -235.605578)
			(xy 359.912391 -235.653599) (xy 359.928101 -235.704529) (xy 359.936044 -235.757233) (xy 359.936542 -235.783882)
			(xy 359.936044 -235.810531) (xy 360.164624 -235.810531) (xy 360.164624 -235.757233) (xy 360.172567 -235.704529)
			(xy 360.188277 -235.653599) (xy 360.211403 -235.605578) (xy 360.241427 -235.561541) (xy 360.277679 -235.52247)
			(xy 360.31935 -235.489239) (xy 360.365508 -235.46259) (xy 360.415122 -235.443118) (xy 360.467084 -235.431258)
			(xy 360.520234 -235.427275) (xy 360.573384 -235.431258) (xy 360.625346 -235.443118) (xy 360.67496 -235.46259)
			(xy 360.721118 -235.489239) (xy 360.762789 -235.52247) (xy 360.799041 -235.561541) (xy 360.829065 -235.605578)
			(xy 360.852191 -235.653599) (xy 360.867901 -235.704529) (xy 360.875844 -235.757233) (xy 360.876342 -235.783882)
			(xy 360.875844 -235.810531) (xy 362.044224 -235.810531) (xy 362.044224 -235.757233) (xy 362.052167 -235.704529)
			(xy 362.067877 -235.653599) (xy 362.091003 -235.605578) (xy 362.121027 -235.561541) (xy 362.157279 -235.52247)
			(xy 362.19895 -235.489239) (xy 362.245108 -235.46259) (xy 362.294722 -235.443118) (xy 362.346684 -235.431258)
			(xy 362.399834 -235.427275) (xy 362.452984 -235.431258) (xy 362.504946 -235.443118) (xy 362.55456 -235.46259)
			(xy 362.600718 -235.489239) (xy 362.642389 -235.52247) (xy 362.678641 -235.561541) (xy 362.708665 -235.605578)
			(xy 362.731791 -235.653599) (xy 362.747501 -235.704529) (xy 362.755444 -235.757233) (xy 362.755942 -235.783882)
			(xy 362.755444 -235.810531) (xy 362.747501 -235.863235) (xy 362.731791 -235.914165) (xy 362.708665 -235.962186)
			(xy 362.678641 -236.006223) (xy 362.642389 -236.045294) (xy 362.600718 -236.078525) (xy 362.55456 -236.105174)
			(xy 362.504946 -236.124646) (xy 362.452984 -236.136506) (xy 362.399834 -236.14049) (xy 362.346684 -236.136506)
			(xy 362.294722 -236.124646) (xy 362.245108 -236.105174) (xy 362.19895 -236.078525) (xy 362.157279 -236.045294)
			(xy 362.121027 -236.006223) (xy 362.091003 -235.962186) (xy 362.067877 -235.914165) (xy 362.052167 -235.863235)
			(xy 362.044224 -235.810531) (xy 360.875844 -235.810531) (xy 360.867901 -235.863235) (xy 360.852191 -235.914165)
			(xy 360.829065 -235.962186) (xy 360.799041 -236.006223) (xy 360.762789 -236.045294) (xy 360.721118 -236.078525)
			(xy 360.67496 -236.105174) (xy 360.625346 -236.124646) (xy 360.573384 -236.136506) (xy 360.520234 -236.14049)
			(xy 360.467084 -236.136506) (xy 360.415122 -236.124646) (xy 360.365508 -236.105174) (xy 360.31935 -236.078525)
			(xy 360.277679 -236.045294) (xy 360.241427 -236.006223) (xy 360.211403 -235.962186) (xy 360.188277 -235.914165)
			(xy 360.172567 -235.863235) (xy 360.164624 -235.810531) (xy 359.936044 -235.810531) (xy 359.928101 -235.863235)
			(xy 359.912391 -235.914165) (xy 359.889265 -235.962186) (xy 359.859241 -236.006223) (xy 359.822989 -236.045294)
			(xy 359.781318 -236.078525) (xy 359.73516 -236.105174) (xy 359.685546 -236.124646) (xy 359.633584 -236.136506)
			(xy 359.580434 -236.14049) (xy 359.527284 -236.136506) (xy 359.475322 -236.124646) (xy 359.425708 -236.105174)
			(xy 359.37955 -236.078525) (xy 359.337879 -236.045294) (xy 359.301627 -236.006223) (xy 359.271603 -235.962186)
			(xy 359.248477 -235.914165) (xy 359.232767 -235.863235) (xy 359.224824 -235.810531) (xy 358.996244 -235.810531)
			(xy 358.988301 -235.863235) (xy 358.972591 -235.914165) (xy 358.949465 -235.962186) (xy 358.919441 -236.006223)
			(xy 358.883189 -236.045294) (xy 358.841518 -236.078525) (xy 358.79536 -236.105174) (xy 358.745746 -236.124646)
			(xy 358.693784 -236.136506) (xy 358.640634 -236.14049) (xy 358.587484 -236.136506) (xy 358.535522 -236.124646)
			(xy 358.485908 -236.105174) (xy 358.43975 -236.078525) (xy 358.398079 -236.045294) (xy 358.361827 -236.006223)
			(xy 358.331803 -235.962186) (xy 358.308677 -235.914165) (xy 358.292967 -235.863235) (xy 358.285024 -235.810531)
			(xy 358.056444 -235.810531) (xy 358.048501 -235.863235) (xy 358.032791 -235.914165) (xy 358.009665 -235.962186)
			(xy 357.979641 -236.006223) (xy 357.943389 -236.045294) (xy 357.901718 -236.078525) (xy 357.85556 -236.105174)
			(xy 357.805946 -236.124646) (xy 357.753984 -236.136506) (xy 357.700834 -236.14049) (xy 357.647684 -236.136506)
			(xy 357.595722 -236.124646) (xy 357.546108 -236.105174) (xy 357.49995 -236.078525) (xy 357.458279 -236.045294)
			(xy 357.422027 -236.006223) (xy 357.392003 -235.962186) (xy 357.368877 -235.914165) (xy 357.353167 -235.863235)
			(xy 357.345224 -235.810531) (xy 356.540308 -235.810531) (xy 356.540308 -236.624601) (xy 356.87507 -236.624601)
			(xy 356.87507 -236.571303) (xy 356.883013 -236.518599) (xy 356.898723 -236.467669) (xy 356.921849 -236.419648)
			(xy 356.951873 -236.375611) (xy 356.988125 -236.33654) (xy 357.029796 -236.303309) (xy 357.075954 -236.27666)
			(xy 357.125568 -236.257188) (xy 357.17753 -236.245328) (xy 357.23068 -236.241345) (xy 357.28383 -236.245328)
			(xy 357.335792 -236.257188) (xy 357.385406 -236.27666) (xy 357.431564 -236.303309) (xy 357.473235 -236.33654)
			(xy 357.509487 -236.375611) (xy 357.539511 -236.419648) (xy 357.562637 -236.467669) (xy 357.578347 -236.518599)
			(xy 357.58629 -236.571303) (xy 357.586788 -236.597952) (xy 357.58629 -236.624601) (xy 358.75467 -236.624601)
			(xy 358.75467 -236.571303) (xy 358.762613 -236.518599) (xy 358.778323 -236.467669) (xy 358.801449 -236.419648)
			(xy 358.831473 -236.375611) (xy 358.867725 -236.33654) (xy 358.909396 -236.303309) (xy 358.955554 -236.27666)
			(xy 359.005168 -236.257188) (xy 359.05713 -236.245328) (xy 359.11028 -236.241345) (xy 359.16343 -236.245328)
			(xy 359.215392 -236.257188) (xy 359.265006 -236.27666) (xy 359.311164 -236.303309) (xy 359.352835 -236.33654)
			(xy 359.389087 -236.375611) (xy 359.419111 -236.419648) (xy 359.442237 -236.467669) (xy 359.457947 -236.518599)
			(xy 359.46589 -236.571303) (xy 359.466388 -236.597952) (xy 359.46589 -236.624601) (xy 360.63427 -236.624601)
			(xy 360.63427 -236.571303) (xy 360.642213 -236.518599) (xy 360.657923 -236.467669) (xy 360.681049 -236.419648)
			(xy 360.711073 -236.375611) (xy 360.747325 -236.33654) (xy 360.788996 -236.303309) (xy 360.835154 -236.27666)
			(xy 360.884768 -236.257188) (xy 360.93673 -236.245328) (xy 360.98988 -236.241345) (xy 361.04303 -236.245328)
			(xy 361.094992 -236.257188) (xy 361.144606 -236.27666) (xy 361.190764 -236.303309) (xy 361.232435 -236.33654)
			(xy 361.268687 -236.375611) (xy 361.298711 -236.419648) (xy 361.321837 -236.467669) (xy 361.337547 -236.518599)
			(xy 361.34549 -236.571303) (xy 361.345988 -236.597952) (xy 361.34549 -236.624601) (xy 361.574324 -236.624601)
			(xy 361.574324 -236.571303) (xy 361.582267 -236.518599) (xy 361.597977 -236.467669) (xy 361.621103 -236.419648)
			(xy 361.651127 -236.375611) (xy 361.687379 -236.33654) (xy 361.72905 -236.303309) (xy 361.775208 -236.27666)
			(xy 361.824822 -236.257188) (xy 361.876784 -236.245328) (xy 361.929934 -236.241345) (xy 361.983084 -236.245328)
			(xy 362.035046 -236.257188) (xy 362.08466 -236.27666) (xy 362.130818 -236.303309) (xy 362.172489 -236.33654)
			(xy 362.208741 -236.375611) (xy 362.238765 -236.419648) (xy 362.261891 -236.467669) (xy 362.277601 -236.518599)
			(xy 362.285544 -236.571303) (xy 362.286042 -236.597952) (xy 362.285544 -236.624601) (xy 362.277601 -236.677305)
			(xy 362.261891 -236.728235) (xy 362.238765 -236.776256) (xy 362.208741 -236.820293) (xy 362.172489 -236.859364)
			(xy 362.130818 -236.892595) (xy 362.08466 -236.919244) (xy 362.035046 -236.938716) (xy 361.983084 -236.950576)
			(xy 361.929934 -236.95456) (xy 361.876784 -236.950576) (xy 361.824822 -236.938716) (xy 361.775208 -236.919244)
			(xy 361.72905 -236.892595) (xy 361.687379 -236.859364) (xy 361.651127 -236.820293) (xy 361.621103 -236.776256)
			(xy 361.597977 -236.728235) (xy 361.582267 -236.677305) (xy 361.574324 -236.624601) (xy 361.34549 -236.624601)
			(xy 361.337547 -236.677305) (xy 361.321837 -236.728235) (xy 361.298711 -236.776256) (xy 361.268687 -236.820293)
			(xy 361.232435 -236.859364) (xy 361.190764 -236.892595) (xy 361.144606 -236.919244) (xy 361.094992 -236.938716)
			(xy 361.04303 -236.950576) (xy 360.98988 -236.95456) (xy 360.93673 -236.950576) (xy 360.884768 -236.938716)
			(xy 360.835154 -236.919244) (xy 360.788996 -236.892595) (xy 360.747325 -236.859364) (xy 360.711073 -236.820293)
			(xy 360.681049 -236.776256) (xy 360.657923 -236.728235) (xy 360.642213 -236.677305) (xy 360.63427 -236.624601)
			(xy 359.46589 -236.624601) (xy 359.457947 -236.677305) (xy 359.442237 -236.728235) (xy 359.419111 -236.776256)
			(xy 359.389087 -236.820293) (xy 359.352835 -236.859364) (xy 359.311164 -236.892595) (xy 359.265006 -236.919244)
			(xy 359.215392 -236.938716) (xy 359.16343 -236.950576) (xy 359.11028 -236.95456) (xy 359.05713 -236.950576)
			(xy 359.005168 -236.938716) (xy 358.955554 -236.919244) (xy 358.909396 -236.892595) (xy 358.867725 -236.859364)
			(xy 358.831473 -236.820293) (xy 358.801449 -236.776256) (xy 358.778323 -236.728235) (xy 358.762613 -236.677305)
			(xy 358.75467 -236.624601) (xy 357.58629 -236.624601) (xy 357.578347 -236.677305) (xy 357.562637 -236.728235)
			(xy 357.539511 -236.776256) (xy 357.509487 -236.820293) (xy 357.473235 -236.859364) (xy 357.431564 -236.892595)
			(xy 357.385406 -236.919244) (xy 357.335792 -236.938716) (xy 357.28383 -236.950576) (xy 357.23068 -236.95456)
			(xy 357.17753 -236.950576) (xy 357.125568 -236.938716) (xy 357.075954 -236.919244) (xy 357.029796 -236.892595)
			(xy 356.988125 -236.859364) (xy 356.951873 -236.820293) (xy 356.921849 -236.776256) (xy 356.898723 -236.728235)
			(xy 356.883013 -236.677305) (xy 356.87507 -236.624601) (xy 356.540308 -236.624601) (xy 356.540308 -237.438163)
			(xy 357.345224 -237.438163) (xy 357.345224 -237.384865) (xy 357.353167 -237.332161) (xy 357.368877 -237.281231)
			(xy 357.392003 -237.23321) (xy 357.422027 -237.189173) (xy 357.458279 -237.150102) (xy 357.49995 -237.116871)
			(xy 357.546108 -237.090222) (xy 357.595722 -237.07075) (xy 357.647684 -237.05889) (xy 357.700834 -237.054907)
			(xy 357.753984 -237.05889) (xy 357.805946 -237.07075) (xy 357.85556 -237.090222) (xy 357.901718 -237.116871)
			(xy 357.943389 -237.150102) (xy 357.979641 -237.189173) (xy 358.009665 -237.23321) (xy 358.032791 -237.281231)
			(xy 358.048501 -237.332161) (xy 358.056444 -237.384865) (xy 358.056942 -237.411514) (xy 358.056444 -237.438163)
			(xy 358.285024 -237.438163) (xy 358.285024 -237.384865) (xy 358.292967 -237.332161) (xy 358.308677 -237.281231)
			(xy 358.331803 -237.23321) (xy 358.361827 -237.189173) (xy 358.398079 -237.150102) (xy 358.43975 -237.116871)
			(xy 358.485908 -237.090222) (xy 358.535522 -237.07075) (xy 358.587484 -237.05889) (xy 358.640634 -237.054907)
			(xy 358.693784 -237.05889) (xy 358.745746 -237.07075) (xy 358.79536 -237.090222) (xy 358.841518 -237.116871)
			(xy 358.883189 -237.150102) (xy 358.919441 -237.189173) (xy 358.949465 -237.23321) (xy 358.972591 -237.281231)
			(xy 358.988301 -237.332161) (xy 358.996244 -237.384865) (xy 358.996742 -237.411514) (xy 358.996244 -237.438163)
			(xy 359.224824 -237.438163) (xy 359.224824 -237.384865) (xy 359.232767 -237.332161) (xy 359.248477 -237.281231)
			(xy 359.271603 -237.23321) (xy 359.301627 -237.189173) (xy 359.337879 -237.150102) (xy 359.37955 -237.116871)
			(xy 359.425708 -237.090222) (xy 359.475322 -237.07075) (xy 359.527284 -237.05889) (xy 359.580434 -237.054907)
			(xy 359.633584 -237.05889) (xy 359.685546 -237.07075) (xy 359.73516 -237.090222) (xy 359.781318 -237.116871)
			(xy 359.822989 -237.150102) (xy 359.859241 -237.189173) (xy 359.889265 -237.23321) (xy 359.912391 -237.281231)
			(xy 359.928101 -237.332161) (xy 359.936044 -237.384865) (xy 359.936542 -237.411514) (xy 359.936044 -237.438163)
			(xy 360.164624 -237.438163) (xy 360.164624 -237.384865) (xy 360.172567 -237.332161) (xy 360.188277 -237.281231)
			(xy 360.211403 -237.23321) (xy 360.241427 -237.189173) (xy 360.277679 -237.150102) (xy 360.31935 -237.116871)
			(xy 360.365508 -237.090222) (xy 360.415122 -237.07075) (xy 360.467084 -237.05889) (xy 360.520234 -237.054907)
			(xy 360.573384 -237.05889) (xy 360.625346 -237.07075) (xy 360.67496 -237.090222) (xy 360.721118 -237.116871)
			(xy 360.762789 -237.150102) (xy 360.799041 -237.189173) (xy 360.829065 -237.23321) (xy 360.852191 -237.281231)
			(xy 360.867901 -237.332161) (xy 360.875844 -237.384865) (xy 360.876342 -237.411514) (xy 360.875844 -237.438163)
			(xy 361.104424 -237.438163) (xy 361.104424 -237.384865) (xy 361.112367 -237.332161) (xy 361.128077 -237.281231)
			(xy 361.151203 -237.23321) (xy 361.181227 -237.189173) (xy 361.217479 -237.150102) (xy 361.25915 -237.116871)
			(xy 361.305308 -237.090222) (xy 361.354922 -237.07075) (xy 361.406884 -237.05889) (xy 361.460034 -237.054907)
			(xy 361.513184 -237.05889) (xy 361.565146 -237.07075) (xy 361.61476 -237.090222) (xy 361.660918 -237.116871)
			(xy 361.702589 -237.150102) (xy 361.738841 -237.189173) (xy 361.768865 -237.23321) (xy 361.791991 -237.281231)
			(xy 361.807701 -237.332161) (xy 361.815644 -237.384865) (xy 361.816142 -237.411514) (xy 361.815644 -237.438163)
			(xy 361.807701 -237.490867) (xy 361.791991 -237.541797) (xy 361.768865 -237.589818) (xy 361.738841 -237.633855)
			(xy 361.702589 -237.672926) (xy 361.660918 -237.706157) (xy 361.61476 -237.732806) (xy 361.565146 -237.752278)
			(xy 361.513184 -237.764138) (xy 361.460034 -237.768122) (xy 361.406884 -237.764138) (xy 361.354922 -237.752278)
			(xy 361.305308 -237.732806) (xy 361.25915 -237.706157) (xy 361.217479 -237.672926) (xy 361.181227 -237.633855)
			(xy 361.151203 -237.589818) (xy 361.128077 -237.541797) (xy 361.112367 -237.490867) (xy 361.104424 -237.438163)
			(xy 360.875844 -237.438163) (xy 360.867901 -237.490867) (xy 360.852191 -237.541797) (xy 360.829065 -237.589818)
			(xy 360.799041 -237.633855) (xy 360.762789 -237.672926) (xy 360.721118 -237.706157) (xy 360.67496 -237.732806)
			(xy 360.625346 -237.752278) (xy 360.573384 -237.764138) (xy 360.520234 -237.768122) (xy 360.467084 -237.764138)
			(xy 360.415122 -237.752278) (xy 360.365508 -237.732806) (xy 360.31935 -237.706157) (xy 360.277679 -237.672926)
			(xy 360.241427 -237.633855) (xy 360.211403 -237.589818) (xy 360.188277 -237.541797) (xy 360.172567 -237.490867)
			(xy 360.164624 -237.438163) (xy 359.936044 -237.438163) (xy 359.928101 -237.490867) (xy 359.912391 -237.541797)
			(xy 359.889265 -237.589818) (xy 359.859241 -237.633855) (xy 359.822989 -237.672926) (xy 359.781318 -237.706157)
			(xy 359.73516 -237.732806) (xy 359.685546 -237.752278) (xy 359.633584 -237.764138) (xy 359.580434 -237.768122)
			(xy 359.527284 -237.764138) (xy 359.475322 -237.752278) (xy 359.425708 -237.732806) (xy 359.37955 -237.706157)
			(xy 359.337879 -237.672926) (xy 359.301627 -237.633855) (xy 359.271603 -237.589818) (xy 359.248477 -237.541797)
			(xy 359.232767 -237.490867) (xy 359.224824 -237.438163) (xy 358.996244 -237.438163) (xy 358.988301 -237.490867)
			(xy 358.972591 -237.541797) (xy 358.949465 -237.589818) (xy 358.919441 -237.633855) (xy 358.883189 -237.672926)
			(xy 358.841518 -237.706157) (xy 358.79536 -237.732806) (xy 358.745746 -237.752278) (xy 358.693784 -237.764138)
			(xy 358.640634 -237.768122) (xy 358.587484 -237.764138) (xy 358.535522 -237.752278) (xy 358.485908 -237.732806)
			(xy 358.43975 -237.706157) (xy 358.398079 -237.672926) (xy 358.361827 -237.633855) (xy 358.331803 -237.589818)
			(xy 358.308677 -237.541797) (xy 358.292967 -237.490867) (xy 358.285024 -237.438163) (xy 358.056444 -237.438163)
			(xy 358.048501 -237.490867) (xy 358.032791 -237.541797) (xy 358.009665 -237.589818) (xy 357.979641 -237.633855)
			(xy 357.943389 -237.672926) (xy 357.901718 -237.706157) (xy 357.85556 -237.732806) (xy 357.805946 -237.752278)
			(xy 357.753984 -237.764138) (xy 357.700834 -237.768122) (xy 357.647684 -237.764138) (xy 357.595722 -237.752278)
			(xy 357.546108 -237.732806) (xy 357.49995 -237.706157) (xy 357.458279 -237.672926) (xy 357.422027 -237.633855)
			(xy 357.392003 -237.589818) (xy 357.368877 -237.541797) (xy 357.353167 -237.490867) (xy 357.345224 -237.438163)
			(xy 356.540308 -237.438163) (xy 356.540308 -237.44936) (xy 356.006654 -237.98276) (xy 351.40011 -237.98276)
			(xy 351.206308 -237.788958) (xy 350.940624 -237.522766) (xy 350.940624 -236.511338) (xy 351.011998 -236.439964)
			(xy 351.011998 -236.245654) (xy 350.911414 -236.14507) (xy 350.651318 -236.14507) (xy 350.525588 -236.2708)
			(xy 350.525588 -237.31601) (xy 350.527112 -237.32236) (xy 350.532431 -237.344264) (xy 350.538158 -237.388976)
			(xy 350.538542 -237.411514) (xy 350.538177 -237.434053) (xy 350.53244 -237.478765) (xy 350.527112 -237.500668)
			(xy 350.525588 -237.507018) (xy 350.525588 -237.771686) (xy 350.275144 -238.02213) (xy 350.275144 -239.3094)
			(xy 350.52657 -239.3094) (xy 350.530554 -239.256245) (xy 350.542415 -239.204278) (xy 350.56189 -239.154659)
			(xy 350.588543 -239.108497) (xy 350.621778 -239.066823) (xy 350.660854 -239.030568) (xy 350.704897 -239.000543)
			(xy 350.752923 -238.977417) (xy 350.803859 -238.961708) (xy 350.856568 -238.953766) (xy 350.88322 -238.953294)
			(xy 350.907891 -238.953676) (xy 350.95676 -238.960486) (xy 351.004219 -238.973986) (xy 351.049355 -238.993917)
			(xy 351.091303 -239.019896) (xy 351.11055 -239.035336) (xy 351.12168 -239.043963) (xy 351.14744 -239.05531)
			(xy 351.17532 -239.059191) (xy 351.2032 -239.05531) (xy 351.22896 -239.043963) (xy 351.24009 -239.035336)
			(xy 351.261506 -239.018213) (xy 351.308563 -238.990074) (xy 351.35938 -238.969485) (xy 351.412753 -238.956933)
			(xy 351.46742 -238.952716) (xy 351.522087 -238.956933) (xy 351.57546 -238.969485) (xy 351.626277 -238.990074)
			(xy 351.673334 -239.018213) (xy 351.69475 -239.035336) (xy 351.70588 -239.043963) (xy 351.73164 -239.05531)
			(xy 351.75952 -239.059191) (xy 351.7874 -239.05531) (xy 351.81316 -239.043963) (xy 351.82429 -239.035336)
			(xy 351.843554 -239.019923) (xy 351.885506 -238.993962) (xy 351.93064 -238.974041) (xy 351.978092 -238.96054)
			(xy 352.026953 -238.953719) (xy 352.05162 -238.953294) (xy 352.078268 -238.953789) (xy 352.13097 -238.961735)
			(xy 352.181898 -238.977447) (xy 352.229916 -239.000574) (xy 352.273951 -239.030599) (xy 352.31302 -239.066851)
			(xy 352.346249 -239.108521) (xy 352.372897 -239.154678) (xy 352.392367 -239.204291) (xy 352.404227 -239.256252)
			(xy 352.406951 -239.2926) (xy 353.347006 -239.2926) (xy 353.350989 -239.239449) (xy 353.36285 -239.187486)
			(xy 353.382324 -239.13787) (xy 353.408976 -239.091712) (xy 353.44221 -239.050042) (xy 353.481283 -239.013791)
			(xy 353.525324 -238.983769) (xy 353.573347 -238.960646) (xy 353.62428 -238.94494) (xy 353.676986 -238.937001)
			(xy 353.703636 -238.93653) (xy 353.728304 -238.936975) (xy 353.77717 -238.943772) (xy 353.824628 -238.957258)
			(xy 353.869765 -238.977175) (xy 353.911717 -239.003139) (xy 353.930966 -239.018572) (xy 353.942096 -239.027199)
			(xy 353.967856 -239.038546) (xy 353.995736 -239.042427) (xy 354.023616 -239.038546) (xy 354.049376 -239.027199)
			(xy 354.060506 -239.018572) (xy 354.079769 -239.003157) (xy 354.121721 -238.977196) (xy 354.166855 -238.957274)
			(xy 354.214307 -238.943774) (xy 354.263169 -238.936954) (xy 354.287836 -238.93653) (xy 354.314486 -238.936954)
			(xy 354.367191 -238.944903) (xy 354.418123 -238.960618) (xy 354.466144 -238.983748) (xy 354.510181 -239.013776)
			(xy 354.549251 -239.050032) (xy 354.582482 -239.091706) (xy 354.609131 -239.137867) (xy 354.628603 -239.187483)
			(xy 354.640463 -239.239448) (xy 354.644446 -239.2926) (xy 354.640463 -239.345752) (xy 354.628603 -239.397717)
			(xy 354.609131 -239.447333) (xy 354.582482 -239.493494) (xy 354.549251 -239.535168) (xy 354.510181 -239.571424)
			(xy 354.466144 -239.601452) (xy 354.418123 -239.624582) (xy 354.367191 -239.640297) (xy 354.314486 -239.648246)
			(xy 354.287836 -239.648746) (xy 354.263167 -239.648323) (xy 354.2143 -239.641521) (xy 354.166842 -239.628031)
			(xy 354.121704 -239.608109) (xy 354.079754 -239.582139) (xy 354.060506 -239.566704) (xy 354.049376 -239.558077)
			(xy 354.023616 -239.54673) (xy 353.995736 -239.542849) (xy 353.967856 -239.54673) (xy 353.942096 -239.558077)
			(xy 353.930966 -239.566704) (xy 353.91171 -239.582128) (xy 353.869757 -239.608089) (xy 353.824621 -239.628009)
			(xy 353.777167 -239.641507) (xy 353.728304 -239.648323) (xy 353.703636 -239.648746) (xy 353.676986 -239.648199)
			(xy 353.62428 -239.64026) (xy 353.573347 -239.624554) (xy 353.525324 -239.601431) (xy 353.481283 -239.571409)
			(xy 353.44221 -239.535158) (xy 353.408976 -239.493488) (xy 353.382324 -239.44733) (xy 353.36285 -239.397714)
			(xy 353.350989 -239.345751) (xy 353.347006 -239.2926) (xy 352.406951 -239.2926) (xy 352.40821 -239.3094)
			(xy 352.404227 -239.362548) (xy 352.392367 -239.414509) (xy 352.372897 -239.464122) (xy 352.346249 -239.510279)
			(xy 352.31302 -239.551949) (xy 352.273951 -239.588201) (xy 352.229916 -239.618226) (xy 352.181898 -239.641353)
			(xy 352.13097 -239.657065) (xy 352.078268 -239.665011) (xy 352.05162 -239.66551) (xy 352.02695 -239.665104)
			(xy 351.978082 -239.6583) (xy 351.930624 -239.644805) (xy 351.885486 -239.62488) (xy 351.843537 -239.598906)
			(xy 351.82429 -239.583468) (xy 351.81316 -239.574841) (xy 351.7874 -239.563494) (xy 351.75952 -239.559613)
			(xy 351.73164 -239.563494) (xy 351.70588 -239.574841) (xy 351.69475 -239.583468) (xy 351.673334 -239.600591)
			(xy 351.626277 -239.62873) (xy 351.57546 -239.649319) (xy 351.522087 -239.661871) (xy 351.46742 -239.666088)
			(xy 351.412753 -239.661871) (xy 351.35938 -239.649319) (xy 351.308563 -239.62873) (xy 351.261506 -239.600591)
			(xy 351.24009 -239.583468) (xy 351.22896 -239.574841) (xy 351.2032 -239.563494) (xy 351.17532 -239.559613)
			(xy 351.14744 -239.563494) (xy 351.12168 -239.574841) (xy 351.11055 -239.583468) (xy 351.091307 -239.598909)
			(xy 351.04935 -239.624866) (xy 351.00421 -239.644782) (xy 350.956754 -239.658276) (xy 350.907889 -239.665089)
			(xy 350.88322 -239.66551) (xy 350.856568 -239.665034) (xy 350.803859 -239.657092) (xy 350.752923 -239.641383)
			(xy 350.704897 -239.618257) (xy 350.660854 -239.588232) (xy 350.621778 -239.551977) (xy 350.588543 -239.510303)
			(xy 350.56189 -239.464141) (xy 350.542415 -239.414522) (xy 350.530554 -239.362555) (xy 350.52657 -239.3094)
			(xy 350.275144 -239.3094) (xy 350.275144 -239.935766) (xy 350.358456 -240.019332) (xy 350.39173 -240.019332)
			(xy 350.581468 -240.208816) (xy 350.581468 -240.818416) (xy 350.81591 -241.053112) (xy 352.05035 -241.053112)
			(xy 352.104198 -241.10696) (xy 352.354896 -241.10696) (xy 352.411284 -241.050572) (xy 354.730304 -241.050572)
			(xy 354.786692 -241.10696) (xy 354.985828 -241.10696) (xy 355.208586 -241.329972) (xy 356.48646 -241.329972)
		)
		(stroke
			(width 0)
			(type solid)
		)
		(fill yes)
		(layer "B.Cu")
		(net "GND")
	)
	(gr_poly
		(pts
			(arc
				(start 194.443604 -441.479432)
				(mid 194.479525 -441.464553)
				(end 194.494404 -441.428632)
			)
			(arc
				(start 194.494404 -441.17006)
				(mid 194.790421 -440.455411)
				(end 195.50507 -440.159394)
			)
			(arc
				(start 276.314916 -440.159394)
				(mid 277.029565 -440.455411)
				(end 277.325582 -441.17006)
			)
			(arc
				(start 277.325582 -441.428632)
				(mid 277.340461 -441.464553)
				(end 277.376382 -441.479432)
			)
			(arc
				(start 463.300064 -441.479432)
				(mid 464.353268 -441.04318)
				(end 464.78952 -439.989976)
			)
			(arc
				(start 464.78952 -409.528264)
				(mid 464.980687 -408.567674)
				(end 465.52485 -407.753312)
			)
			(arc
				(start 467.353396 -405.924766)
				(mid 467.676179 -405.441593)
				(end 467.789514 -404.871682)
			)
			(arc
				(start 467.789514 -82.82813)
				(mid 467.980666 -81.867526)
				(end 468.524844 -81.053178)
			)
			(arc
				(start 470.853262 -78.72476)
				(mid 471.176045 -78.241587)
				(end 471.28938 -77.671676)
			)
			(arc
				(start 471.28938 -26.50617)
				(mid 471.28206 -26.479899)
				(end 471.262202 -26.461212)
			)
			(xy 471.170254 -26.412698) (xy 471.141806 -26.414476)
			(arc
				(start 471.130376 -26.42235)
				(mid 470.970782 -26.527543)
				(end 470.807288 -26.626566)
			)
			(arc
				(start 470.807288 -26.626566)
				(mid 470.788726 -26.645142)
				(end 470.781888 -26.670508)
			)
			(arc
				(start 470.781888 -31.103316)
				(mid 470.783107 -31.114378)
				(end 470.786714 -31.124906)
			)
			(arc
				(start 470.786714 -31.124906)
				(mid 470.983736 -31.69779)
				(end 471.05062 -32.29991)
			)
			(arc
				(start 471.05062 -33.899856)
				(mid 470.98379 -34.501988)
				(end 470.786714 -35.07486)
			)
			(arc
				(start 470.786714 -35.07486)
				(mid 470.783116 -35.08539)
				(end 470.781888 -35.09645)
			)
			(arc
				(start 470.781888 -77.672184)
				(mid 470.707176 -78.047677)
				(end 470.494614 -78.366112)
			)
			(arc
				(start 468.166196 -80.69453)
				(mid 467.512084 -81.673433)
				(end 467.282276 -82.82813)
			)
			(arc
				(start 467.282276 -115.09883)
				(mid 467.283688 -115.110723)
				(end 467.287864 -115.121944)
			)
			(arc
				(start 467.287864 -115.121944)
				(mid 467.319142 -115.206449)
				(end 467.329774 -115.295934)
			)
			(arc
				(start 467.329774 -115.295934)
				(mid 467.31919 -115.38543)
				(end 467.287864 -115.469924)
			)
			(arc
				(start 467.287864 -115.469924)
				(mid 467.283709 -115.481151)
				(end 467.282276 -115.493038)
			)
			(arc
				(start 467.282276 -358.935274)
				(mid 467.28295 -358.943778)
				(end 467.28507 -358.952038)
			)
			(arc
				(start 467.28507 -358.952038)
				(mid 467.514132 -359.845086)
				(end 467.59114 -360.76382)
			)
			(arc
				(start 467.59114 -360.76382)
				(mid 467.514124 -361.682553)
				(end 467.28507 -362.575602)
			)
			(arc
				(start 467.28507 -362.575602)
				(mid 467.282984 -362.583868)
				(end 467.282276 -362.592366)
			)
			(arc
				(start 467.282276 -404.871936)
				(mid 467.207495 -405.247595)
				(end 466.994748 -405.566118)
			)
			(arc
				(start 465.166202 -407.394664)
				(mid 464.5119 -408.373524)
				(end 464.282028 -409.528264)
			)
			(xy 464.282028 -435.023514)
			(arc
				(start 464.282536 -435.026308)
				(mid 464.305002 -435.31281)
				(end 464.312508 -435.600094)
			)
			(arc
				(start 464.312508 -435.600094)
				(mid 464.305004 -435.887378)
				(end 464.282536 -436.17388)
			)
			(xy 464.282028 -436.176674)
			(arc
				(start 464.282028 -439.989976)
				(mid 463.994417 -440.684329)
				(end 463.300064 -440.97194)
			)
			(xy 460.036418 -440.97194)
			(arc
				(start 460.03083 -440.973464)
				(mid 459.41931 -441.077737)
				(end 458.799946 -441.112656)
			)
			(arc
				(start 458.799946 -441.112656)
				(mid 458.180577 -441.077605)
				(end 457.569062 -440.97321)
			)
			(xy 457.557632 -440.97194) (xy 410.917898 -440.97194)
			(arc
				(start 410.910024 -440.974734)
				(mid 410.831038 -440.993945)
				(end 410.750004 -441.000388)
			)
			(arc
				(start 410.750004 -441.000388)
				(mid 410.668968 -440.993957)
				(end 410.589984 -440.974734)
			)
			(xy 410.58211 -440.97194) (xy 406.917906 -440.97194)
			(arc
				(start 406.910032 -440.974734)
				(mid 406.831046 -440.993945)
				(end 406.750012 -441.000388)
			)
			(arc
				(start 406.750012 -441.000388)
				(mid 406.668976 -440.993957)
				(end 406.589992 -440.974734)
			)
			(xy 406.582118 -440.97194) (xy 402.917914 -440.97194)
			(arc
				(start 402.91004 -440.974734)
				(mid 402.831054 -440.993945)
				(end 402.75002 -441.000388)
			)
			(arc
				(start 402.75002 -441.000388)
				(mid 402.668984 -440.993957)
				(end 402.59 -440.974734)
			)
			(xy 402.582126 -440.97194) (xy 399.222214 -440.97194) (xy 399.208244 -440.976004)
			(arc
				(start 399.202148 -440.980068)
				(mid 399.169197 -440.995208)
				(end 399.133314 -441.000388)
			)
			(arc
				(start 398.366742 -441.000388)
				(mid 398.330875 -440.995154)
				(end 398.297908 -440.980068)
			)
			(xy 398.291812 -440.976004) (xy 398.277842 -440.97194) (xy 393.917932 -440.97194)
			(arc
				(start 393.910058 -440.974734)
				(mid 393.831072 -440.993945)
				(end 393.750038 -441.000388)
			)
			(arc
				(start 393.750038 -441.000388)
				(mid 393.669002 -440.993957)
				(end 393.590018 -440.974734)
			)
			(xy 393.582144 -440.97194) (xy 389.91794 -440.97194)
			(arc
				(start 389.910066 -440.974734)
				(mid 389.83108 -440.993945)
				(end 389.750046 -441.000388)
			)
			(arc
				(start 389.750046 -441.000388)
				(mid 389.66901 -440.993957)
				(end 389.590026 -440.974734)
			)
			(xy 389.582152 -440.97194) (xy 385.917948 -440.97194)
			(arc
				(start 385.910074 -440.974734)
				(mid 385.831088 -440.993945)
				(end 385.750054 -441.000388)
			)
			(arc
				(start 385.750054 -441.000388)
				(mid 385.669018 -440.993957)
				(end 385.590034 -440.974734)
			)
			(xy 385.58216 -440.97194) (xy 382.222248 -440.97194) (xy 382.208278 -440.976004)
			(arc
				(start 382.202182 -440.980068)
				(mid 382.169231 -440.995208)
				(end 382.133348 -441.000388)
			)
			(arc
				(start 381.366776 -441.000388)
				(mid 381.330909 -440.995154)
				(end 381.297942 -440.980068)
			)
			(xy 381.291846 -440.976004) (xy 381.277876 -440.97194) (xy 372.540784 -440.97194)
			(arc
				(start 372.529354 -440.97321)
				(mid 371.917842 -441.077633)
				(end 371.29847 -441.112656)
			)
			(arc
				(start 371.29847 -441.112656)
				(mid 370.679101 -441.077605)
				(end 370.067586 -440.97321)
			)
			(xy 370.056156 -440.97194) (xy 343.817956 -440.97194)
			(arc
				(start 343.810082 -440.974734)
				(mid 343.731096 -440.993945)
				(end 343.650062 -441.000388)
			)
			(arc
				(start 343.650062 -441.000388)
				(mid 343.569026 -440.993957)
				(end 343.490042 -440.974734)
			)
			(xy 343.482168 -440.97194) (xy 339.817964 -440.97194)
			(arc
				(start 339.81009 -440.974734)
				(mid 339.731104 -440.993945)
				(end 339.65007 -441.000388)
			)
			(arc
				(start 339.65007 -441.000388)
				(mid 339.569034 -440.993957)
				(end 339.49005 -440.974734)
			)
			(xy 339.482176 -440.97194) (xy 335.817972 -440.97194)
			(arc
				(start 335.810098 -440.974734)
				(mid 335.731112 -440.993945)
				(end 335.650078 -441.000388)
			)
			(arc
				(start 335.650078 -441.000388)
				(mid 335.569042 -440.993957)
				(end 335.490058 -440.974734)
			)
			(xy 335.482184 -440.97194) (xy 332.122272 -440.97194) (xy 332.108302 -440.976004)
			(arc
				(start 332.102206 -440.980068)
				(mid 332.069255 -440.995208)
				(end 332.033372 -441.000388)
			)
			(arc
				(start 331.2668 -441.000388)
				(mid 331.230933 -440.995154)
				(end 331.197966 -440.980068)
			)
			(xy 331.19187 -440.976004) (xy 331.1779 -440.97194) (xy 326.81799 -440.97194)
			(arc
				(start 326.810116 -440.974734)
				(mid 326.73113 -440.993945)
				(end 326.650096 -441.000388)
			)
			(arc
				(start 326.650096 -441.000388)
				(mid 326.56906 -440.993957)
				(end 326.490076 -440.974734)
			)
			(xy 326.482202 -440.97194) (xy 322.817998 -440.97194)
			(arc
				(start 322.810124 -440.974734)
				(mid 322.731138 -440.993945)
				(end 322.650104 -441.000388)
			)
			(arc
				(start 322.650104 -441.000388)
				(mid 322.569068 -440.993957)
				(end 322.490084 -440.974734)
			)
			(xy 322.48221 -440.97194) (xy 318.818006 -440.97194)
			(arc
				(start 318.810132 -440.974734)
				(mid 318.731146 -440.993945)
				(end 318.650112 -441.000388)
			)
			(arc
				(start 318.650112 -441.000388)
				(mid 318.569076 -440.993957)
				(end 318.490092 -440.974734)
			)
			(xy 318.482218 -440.97194) (xy 315.122306 -440.97194) (xy 315.108336 -440.976004)
			(arc
				(start 315.10224 -440.980068)
				(mid 315.069289 -440.995208)
				(end 315.033406 -441.000388)
			)
			(arc
				(start 314.266834 -441.000388)
				(mid 314.230967 -440.995154)
				(end 314.198 -440.980068)
			)
			(xy 314.191904 -440.976004) (xy 314.177934 -440.97194) (xy 294.792146 -440.97194)
			(arc
				(start 294.780716 -440.97321)
				(mid 294.169204 -441.077633)
				(end 293.549832 -441.112656)
			)
			(arc
				(start 293.549832 -441.112656)
				(mid 292.930463 -441.077605)
				(end 292.318948 -440.97321)
			)
			(xy 292.307518 -440.97194)
			(arc
				(start 277.82012 -440.97194)
				(mid 277.31587 -440.028787)
				(end 276.314916 -439.652156)
			)
			(arc
				(start 195.50507 -439.652156)
				(mid 194.504157 -440.028834)
				(end 193.999866 -440.97194)
			)
			(xy 180.992272 -440.97194)
			(arc
				(start 180.980842 -440.97321)
				(mid 180.36933 -441.077633)
				(end 179.749958 -441.112656)
			)
			(arc
				(start 179.749958 -441.112656)
				(mid 179.130589 -441.077605)
				(end 178.519074 -440.97321)
			)
			(xy 178.507644 -440.97194) (xy 154.917902 -440.97194)
			(arc
				(start 154.910028 -440.974734)
				(mid 154.831042 -440.993945)
				(end 154.750008 -441.000388)
			)
			(arc
				(start 154.750008 -441.000388)
				(mid 154.668972 -440.993957)
				(end 154.589988 -440.974734)
			)
			(xy 154.582114 -440.97194) (xy 150.91791 -440.97194)
			(arc
				(start 150.910036 -440.974734)
				(mid 150.83105 -440.993945)
				(end 150.750016 -441.000388)
			)
			(arc
				(start 150.750016 -441.000388)
				(mid 150.66898 -440.993957)
				(end 150.589996 -440.974734)
			)
			(xy 150.582122 -440.97194) (xy 146.917918 -440.97194)
			(arc
				(start 146.910044 -440.974734)
				(mid 146.831058 -440.993945)
				(end 146.750024 -441.000388)
			)
			(arc
				(start 146.750024 -441.000388)
				(mid 146.668988 -440.993957)
				(end 146.590004 -440.974734)
			)
			(xy 146.58213 -440.97194) (xy 143.222218 -440.97194) (xy 143.208248 -440.976004)
			(arc
				(start 143.202152 -440.980068)
				(mid 143.169201 -440.995208)
				(end 143.133318 -441.000388)
			)
			(arc
				(start 142.366746 -441.000388)
				(mid 142.330879 -440.995154)
				(end 142.297912 -440.980068)
			)
			(xy 142.291816 -440.976004) (xy 142.277846 -440.97194) (xy 137.917936 -440.97194)
			(arc
				(start 137.910062 -440.974734)
				(mid 137.831076 -440.993945)
				(end 137.750042 -441.000388)
			)
			(arc
				(start 137.750042 -441.000388)
				(mid 137.669006 -440.993957)
				(end 137.590022 -440.974734)
			)
			(xy 137.582148 -440.97194) (xy 133.917944 -440.97194)
			(arc
				(start 133.91007 -440.974734)
				(mid 133.831084 -440.993945)
				(end 133.75005 -441.000388)
			)
			(arc
				(start 133.75005 -441.000388)
				(mid 133.669014 -440.993957)
				(end 133.59003 -440.974734)
			)
			(xy 133.582156 -440.97194) (xy 129.917952 -440.97194)
			(arc
				(start 129.910078 -440.974734)
				(mid 129.831092 -440.993945)
				(end 129.750058 -441.000388)
			)
			(arc
				(start 129.750058 -441.000388)
				(mid 129.669022 -440.993957)
				(end 129.590038 -440.974734)
			)
			(xy 129.582164 -440.97194) (xy 126.222252 -440.97194) (xy 126.208282 -440.976004)
			(arc
				(start 126.202186 -440.980068)
				(mid 126.169235 -440.995208)
				(end 126.133352 -441.000388)
			)
			(arc
				(start 125.36678 -441.000388)
				(mid 125.330913 -440.995154)
				(end 125.297946 -440.980068)
			)
			(xy 125.29185 -440.976004) (xy 125.27788 -440.97194) (xy 101.742494 -440.97194)
			(arc
				(start 101.731064 -440.97321)
				(mid 101.119552 -441.077633)
				(end 100.50018 -441.112656)
			)
			(arc
				(start 100.50018 -441.112656)
				(mid 99.880811 -441.077605)
				(end 99.269296 -440.97321)
			)
			(xy 99.257866 -440.97194) (xy 87.81796 -440.97194)
			(arc
				(start 87.810086 -440.974734)
				(mid 87.7311 -440.993945)
				(end 87.650066 -441.000388)
			)
			(arc
				(start 87.650066 -441.000388)
				(mid 87.56903 -440.993957)
				(end 87.490046 -440.974734)
			)
			(xy 87.482172 -440.97194) (xy 83.817968 -440.97194)
			(arc
				(start 83.810094 -440.974734)
				(mid 83.731108 -440.993945)
				(end 83.650074 -441.000388)
			)
			(arc
				(start 83.650074 -441.000388)
				(mid 83.569038 -440.993957)
				(end 83.490054 -440.974734)
			)
			(xy 83.48218 -440.97194) (xy 79.817976 -440.97194)
			(arc
				(start 79.810102 -440.974734)
				(mid 79.731116 -440.993945)
				(end 79.650082 -441.000388)
			)
			(arc
				(start 79.650082 -441.000388)
				(mid 79.569046 -440.993957)
				(end 79.490062 -440.974734)
			)
			(xy 79.482188 -440.97194) (xy 76.122276 -440.97194) (xy 76.108306 -440.976004)
			(arc
				(start 76.10221 -440.980068)
				(mid 76.069259 -440.995208)
				(end 76.033376 -441.000388)
			)
			(arc
				(start 75.266804 -441.000388)
				(mid 75.230937 -440.995154)
				(end 75.19797 -440.980068)
			)
			(xy 75.191874 -440.976004) (xy 75.177904 -440.97194) (xy 70.817994 -440.97194)
			(arc
				(start 70.81012 -440.974734)
				(mid 70.731134 -440.993945)
				(end 70.6501 -441.000388)
			)
			(arc
				(start 70.6501 -441.000388)
				(mid 70.569064 -440.993957)
				(end 70.49008 -440.974734)
			)
			(xy 70.482206 -440.97194) (xy 66.818002 -440.97194)
			(arc
				(start 66.810128 -440.974734)
				(mid 66.731142 -440.993945)
				(end 66.650108 -441.000388)
			)
			(arc
				(start 66.650108 -441.000388)
				(mid 66.569072 -440.993957)
				(end 66.490088 -440.974734)
			)
			(xy 66.482214 -440.97194) (xy 62.81801 -440.97194)
			(arc
				(start 62.810136 -440.974734)
				(mid 62.73115 -440.993945)
				(end 62.650116 -441.000388)
			)
			(arc
				(start 62.650116 -441.000388)
				(mid 62.56908 -440.993957)
				(end 62.490096 -440.974734)
			)
			(xy 62.482222 -440.97194) (xy 59.12231 -440.97194) (xy 59.10834 -440.976004)
			(arc
				(start 59.102244 -440.980068)
				(mid 59.069293 -440.995208)
				(end 59.03341 -441.000388)
			)
			(arc
				(start 58.266838 -441.000388)
				(mid 58.230971 -440.995154)
				(end 58.198004 -440.980068)
			)
			(xy 58.191908 -440.976004) (xy 58.177938 -440.97194) (xy 14.242288 -440.97194)
			(arc
				(start 14.230858 -440.97321)
				(mid 13.619346 -441.077633)
				(end 12.999974 -441.112656)
			)
			(arc
				(start 12.999974 -441.112656)
				(mid 12.380609 -441.077751)
				(end 11.76909 -440.973464)
			)
			(xy 11.763502 -440.97194)
			(arc
				(start 8.50011 -440.97194)
				(mid 7.805667 -440.684345)
				(end 7.517892 -439.989976)
			)
			(xy 7.517892 -436.17896)
			(arc
				(start 7.517638 -436.17642)
				(mid 7.494973 -435.888653)
				(end 7.487412 -435.600094)
			)
			(arc
				(start 7.487412 -435.600094)
				(mid 7.494983 -435.311536)
				(end 7.517638 -435.023768)
			)
			(xy 7.517892 -435.021228)
			(arc
				(start 7.517892 -409.528264)
				(mid 7.287997 -408.373534)
				(end 6.633718 -407.394664)
			)
			(arc
				(start 3.305302 -404.066248)
				(mid 3.092701 -403.747829)
				(end 3.018028 -403.37232)
			)
			(xy 3.018028 -192.650364) (xy 3.018028 -152.084532)
			(arc
				(start 3.018028 -81.32826)
				(mid 2.788133 -80.17353)
				(end 2.133854 -79.19466)
			)
			(arc
				(start 1.305306 -78.366112)
				(mid 1.092705 -78.047693)
				(end 1.018032 -77.672184)
			)
			(arc
				(start 1.018032 -42.244772)
				(mid 1.013298 -42.223357)
				(end 0.999998 -42.20591)
			)
			(arc
				(start 0.999998 -42.20591)
				(mid 0.873253 -41.933622)
				(end 0.999998 -41.661334)
			)
			(arc
				(start 0.999998 -41.661334)
				(mid 1.013327 -41.6439)
				(end 1.018032 -41.622472)
			)
			(arc
				(start 1.018032 -41.222422)
				(mid 1.013298 -41.201007)
				(end 0.999998 -41.18356)
			)
			(arc
				(start 0.999998 -41.18356)
				(mid 0.873253 -40.911272)
				(end 0.999998 -40.638984)
			)
			(arc
				(start 0.999998 -40.638984)
				(mid 1.013327 -40.62155)
				(end 1.018032 -40.600122)
			)
			(arc
				(start 1.018032 -40.167814)
				(mid 1.012748 -40.145255)
				(end 0.997966 -40.127428)
			)
			(arc
				(start 0.997966 -40.127428)
				(mid 0.84779 -39.824152)
				(end 0.997966 -39.520876)
			)
			(arc
				(start 0.997966 -39.520876)
				(mid 1.012704 -39.503027)
				(end 1.018032 -39.48049)
			)
			(arc
				(start 1.018032 -39.099998)
				(mid 1.013298 -39.078583)
				(end 0.999998 -39.061136)
			)
			(arc
				(start 0.999998 -39.061136)
				(mid 0.873253 -38.788848)
				(end 0.999998 -38.51656)
			)
			(arc
				(start 0.999998 -38.51656)
				(mid 1.013327 -38.499126)
				(end 1.018032 -38.477698)
			)
			(arc
				(start 1.018032 -38.110414)
				(mid 1.011311 -38.085415)
				(end 0.99314 -38.06698)
			)
			(arc
				(start 0.99314 -38.06698)
				(mid 0.807128 -37.73932)
				(end 0.99314 -37.41166)
			)
			(arc
				(start 0.99314 -37.41166)
				(mid 1.011304 -37.393221)
				(end 1.018032 -37.368226)
			)
			(arc
				(start 1.018032 -37.067236)
				(mid 1.011311 -37.042237)
				(end 0.99314 -37.023802)
			)
			(arc
				(start 0.99314 -37.023802)
				(mid 0.807128 -36.696142)
				(end 0.99314 -36.368482)
			)
			(arc
				(start 0.99314 -36.368482)
				(mid 1.011304 -36.350043)
				(end 1.018032 -36.325048)
			)
			(arc
				(start 1.018032 -36.059364)
				(mid 1.010415 -36.032609)
				(end 0.989838 -36.013898)
			)
			(arc
				(start 0.989838 -36.013898)
				(mid 0.81023 -35.849993)
				(end 0.743712 -35.616134)
			)
			(arc
				(start 0.743712 -35.616134)
				(mid 0.810292 -35.382314)
				(end 0.989838 -35.21837)
			)
			(arc
				(start 0.989838 -35.21837)
				(mid 1.010395 -35.199647)
				(end 1.018032 -35.172904)
			)
			(arc
				(start 1.018032 -26.670508)
				(mid 1.011233 -26.645119)
				(end 0.992632 -26.626566)
			)
			(arc
				(start 0.992632 -26.626566)
				(mid 0.82914 -26.527671)
				(end 0.669544 -26.422604)
			)
			(xy 0.65786 -26.414476) (xy 0.62992 -26.412698)
			(arc
				(start 0.537718 -26.461466)
				(mid 0.517872 -26.48016)
				(end 0.51054 -26.506424)
			)
			(arc
				(start 0.51054 -77.671676)
				(mid 0.623884 -78.241583)
				(end 0.946658 -78.72476)
			)
			(arc
				(start 1.775206 -79.553308)
				(mid 2.319424 -80.367648)
				(end 2.510536 -81.32826)
			)
			(arc
				(start 2.510536 -403.371812)
				(mid 2.62388 -403.941719)
				(end 2.946654 -404.424896)
			)
			(arc
				(start 6.27507 -407.753312)
				(mid 6.819424 -408.567623)
				(end 7.010654 -409.528264)
			)
			(arc
				(start 7.010654 -439.989976)
				(mid 7.446906 -441.04318)
				(end 8.50011 -441.479432)
			)
		)
		(stroke
			(width 0)
			(type solid)
		)
		(fill yes)
		(layer "B.Cu")
		(net "GND")
	)
	(gr_poly
		(pts
			(xy 190.707264 -125.760226) (xy 190.718684 -125.731743) (xy 190.748063 -125.677865) (xy 190.784373 -125.628393)
			(xy 190.826965 -125.584214) (xy 190.875076 -125.546118) (xy 190.927843 -125.514789) (xy 190.984321 -125.490788)
			(xy 191.043499 -125.474544) (xy 191.104317 -125.466348) (xy 191.165683 -125.466348) (xy 191.226501 -125.474544)
			(xy 191.285679 -125.490788) (xy 191.342157 -125.514789) (xy 191.394924 -125.546118) (xy 191.443035 -125.584214)
			(xy 191.485627 -125.628393) (xy 191.521937 -125.677865) (xy 191.551316 -125.731743) (xy 191.562736 -125.760226)
			(xy 191.575182 -125.792992) (xy 191.88176 -125.792992) (xy 191.902448 -125.774036) (xy 191.94776 -125.740941)
			(xy 191.996875 -125.71381) (xy 192.049014 -125.693074) (xy 192.103348 -125.679063) (xy 192.159013 -125.672)
			(xy 192.187068 -125.67158) (xy 192.21512 -125.672028) (xy 192.270774 -125.679119) (xy 192.325097 -125.693144)
			(xy 192.377228 -125.713879) (xy 192.426344 -125.740996) (xy 192.471665 -125.774067) (xy 192.492376 -125.792992)
			(xy 194.801236 -125.792992) (xy 195.0466 -125.547374) (xy 195.0466 -125.059186) (xy 194.96278 -124.975112)
			(xy 192.901062 -124.975112) (xy 192.875993 -124.974642) (xy 192.826474 -124.966791) (xy 192.778793 -124.951288)
			(xy 192.734125 -124.928514) (xy 192.693571 -124.899032) (xy 192.67551 -124.88164) (xy 192.574164 -124.780548)
			(xy 190.153798 -124.780548) (xy 187.7568 -122.38355) (xy 187.746725 -122.374175) (xy 187.722746 -122.360691)
			(xy 187.69604 -122.354091) (xy 187.66854 -122.354855) (xy 187.642241 -122.362926) (xy 187.619047 -122.377719)
			(xy 187.60948 -122.387614) (xy 187.59368 -122.405836) (xy 187.557705 -122.437957) (xy 187.517446 -122.464512)
			(xy 187.473757 -122.484938) (xy 187.427564 -122.498803) (xy 187.379848 -122.505813) (xy 187.355734 -122.506232)
			(xy 187.329742 -122.505751) (xy 187.278398 -122.497625) (xy 187.228958 -122.481566) (xy 187.182638 -122.45797)
			(xy 187.14058 -122.427419) (xy 187.103819 -122.390664) (xy 187.07326 -122.348612) (xy 187.049657 -122.302296)
			(xy 187.033589 -122.252858) (xy 187.025453 -122.201516) (xy 187.025026 -122.175524) (xy 187.025461 -122.15141)
			(xy 187.032463 -122.103693) (xy 187.046323 -122.0575) (xy 187.066746 -122.01381) (xy 187.093299 -121.97355)
			(xy 187.125419 -121.937574) (xy 187.143644 -121.921778) (xy 187.153607 -121.912258) (xy 187.168475 -121.889072)
			(xy 187.176585 -121.862748) (xy 187.177344 -121.835215) (xy 187.170697 -121.808485) (xy 187.15713 -121.784513)
			(xy 187.147708 -121.774458) (xy 186.156854 -120.783604) (xy 186.14678 -120.774171) (xy 186.122768 -120.760592)
			(xy 186.095996 -120.753941) (xy 186.068421 -120.754702) (xy 186.042057 -120.762822) (xy 186.018831 -120.777705)
			(xy 186.00928 -120.787668) (xy 185.993482 -120.805893) (xy 185.957508 -120.838017) (xy 185.917249 -120.864576)
			(xy 185.87356 -120.885006) (xy 185.827367 -120.898873) (xy 185.779649 -120.905883) (xy 185.755534 -120.906286)
			(xy 185.729544 -120.905805) (xy 185.678202 -120.897678) (xy 185.628765 -120.881619) (xy 185.582448 -120.858022)
			(xy 185.540394 -120.82747) (xy 185.503637 -120.790715) (xy 185.473084 -120.748662) (xy 185.449486 -120.702347)
			(xy 185.433425 -120.652909) (xy 185.425296 -120.601568) (xy 185.424826 -120.575578) (xy 185.425264 -120.551465)
			(xy 185.432272 -120.503752) (xy 185.446137 -120.457563) (xy 185.466564 -120.413878) (xy 185.49312 -120.373623)
			(xy 185.525241 -120.337653) (xy 185.543444 -120.321832) (xy 185.553412 -120.312288) (xy 185.568285 -120.289054)
			(xy 185.576399 -120.262688) (xy 185.577162 -120.235113) (xy 185.570519 -120.208338) (xy 185.556954 -120.184318)
			(xy 185.547508 -120.174258) (xy 185.42254 -120.04929) (xy 185.42254 -118.336568) (xy 185.418222 -118.326662)
			(xy 185.405531 -118.296699) (xy 185.389684 -118.233591) (xy 185.386726 -118.201186) (xy 185.385681 -118.191658)
			(xy 185.37748 -118.17435) (xy 185.363507 -118.161252) (xy 185.345706 -118.154187) (xy 185.326553 -118.154138)
			(xy 185.308716 -118.161112) (xy 185.294675 -118.174138) (xy 185.286386 -118.191404) (xy 185.28538 -118.200932)
			(xy 185.283022 -118.225536) (xy 185.271931 -118.2737) (xy 185.253797 -118.319677) (xy 185.229023 -118.362444)
			(xy 185.198162 -118.401049) (xy 185.161899 -118.434631) (xy 185.121043 -118.462444) (xy 185.076504 -118.483868)
			(xy 185.029272 -118.498426) (xy 184.9804 -118.505793) (xy 184.955688 -118.50624) (xy 184.929699 -118.505729)
			(xy 184.878361 -118.497597) (xy 184.828927 -118.481533) (xy 184.782615 -118.457934) (xy 184.740564 -118.427381)
			(xy 184.703811 -118.390627) (xy 184.673259 -118.348575) (xy 184.649662 -118.302262) (xy 184.633601 -118.252827)
			(xy 184.62547 -118.201489) (xy 184.62547 -118.149511) (xy 184.633601 -118.098173) (xy 184.649662 -118.048738)
			(xy 184.673259 -118.002425) (xy 184.703811 -117.960373) (xy 184.740564 -117.923619) (xy 184.782615 -117.893066)
			(xy 184.828927 -117.869467) (xy 184.878361 -117.853403) (xy 184.929699 -117.845271) (xy 184.955688 -117.844824)
			(xy 184.981457 -117.845333) (xy 185.032364 -117.853364) (xy 185.057034 -117.860826) (xy 185.108596 -117.776498)
			(xy 185.030618 -117.69852) (xy 185.005218 -117.70233) (xy 184.992911 -117.704098) (xy 184.96812 -117.706007)
			(xy 184.955688 -117.70614) (xy 184.929701 -117.70563) (xy 184.878366 -117.697498) (xy 184.828935 -117.681436)
			(xy 184.782624 -117.65784) (xy 184.740575 -117.627291) (xy 184.703822 -117.59054) (xy 184.67327 -117.548493)
			(xy 184.649672 -117.502184) (xy 184.633607 -117.452754) (xy 184.625472 -117.401419) (xy 184.62498 -117.375432)
			(xy 184.625113 -117.363) (xy 184.627019 -117.338208) (xy 184.62879 -117.325902) (xy 184.6326 -117.300502)
			(xy 184.554622 -117.222524) (xy 184.470294 -117.274086) (xy 184.477743 -117.298759) (xy 184.485785 -117.349664)
			(xy 184.486296 -117.375432) (xy 184.485786 -117.401419) (xy 184.477656 -117.452754) (xy 184.461595 -117.502184)
			(xy 184.437999 -117.548494) (xy 184.407449 -117.590542) (xy 184.370698 -117.627293) (xy 184.32865 -117.657843)
			(xy 184.28234 -117.681439) (xy 184.23291 -117.6975) (xy 184.181575 -117.70563) (xy 184.129601 -117.70563)
			(xy 184.078266 -117.6975) (xy 184.028836 -117.681439) (xy 183.982526 -117.657843) (xy 183.940478 -117.627293)
			(xy 183.903727 -117.590542) (xy 183.873177 -117.548494) (xy 183.849581 -117.502184) (xy 183.83352 -117.452754)
			(xy 183.82539 -117.401419) (xy 183.82488 -117.375432) (xy 183.824973 -117.362682) (xy 183.826884 -117.337254)
			(xy 183.82869 -117.324632) (xy 183.832951 -117.30016) (xy 183.847841 -117.252771) (xy 183.869642 -117.208138)
			(xy 183.897864 -117.167262) (xy 183.931875 -117.131059) (xy 183.970912 -117.100342) (xy 183.992266 -117.08765)
			(xy 184.004433 -117.080785) (xy 184.024738 -117.061614) (xy 184.039096 -117.037662) (xy 184.046432 -117.010717)
			(xy 184.046198 -116.982792) (xy 184.038413 -116.955974) (xy 184.023658 -116.932265) (xy 184.003035 -116.913436)
			(xy 183.990742 -116.906802) (xy 183.964189 -116.892939) (xy 183.915568 -116.85796) (xy 183.873217 -116.815605)
			(xy 183.838242 -116.766981) (xy 183.824372 -116.740432) (xy 183.817797 -116.728292) (xy 183.799305 -116.707807)
			(xy 183.776 -116.693027) (xy 183.749587 -116.685031) (xy 183.721997 -116.684405) (xy 183.695249 -116.691195)
			(xy 183.671298 -116.704904) (xy 183.651896 -116.72453) (xy 183.644794 -116.736368) (xy 183.632171 -116.758102)
			(xy 183.601376 -116.79782) (xy 183.564923 -116.83242) (xy 183.523653 -116.861103) (xy 183.478517 -116.883208)
			(xy 183.430554 -116.898225) (xy 183.380871 -116.905809) (xy 183.355742 -116.906294) (xy 183.329751 -116.905814)
			(xy 183.278408 -116.897688) (xy 183.228969 -116.881629) (xy 183.182651 -116.858033) (xy 183.140595 -116.827482)
			(xy 183.103836 -116.790727) (xy 183.073281 -116.748673) (xy 183.049682 -116.702357) (xy 183.033619 -116.652919)
			(xy 183.025488 -116.601577) (xy 183.025034 -116.575586) (xy 183.025505 -116.55011) (xy 183.033324 -116.49976)
			(xy 183.048773 -116.451206) (xy 183.071487 -116.405597) (xy 183.100929 -116.364011) (xy 183.136401 -116.327434)
			(xy 183.177064 -116.296732) (xy 183.199278 -116.284248) (xy 183.210572 -116.276763) (xy 183.229051 -116.256959)
			(xy 183.241674 -116.232995) (xy 183.247554 -116.206555) (xy 183.246277 -116.179499) (xy 183.237933 -116.153731)
			(xy 183.223109 -116.131062) (xy 183.202847 -116.113087) (xy 183.190896 -116.106702) (xy 183.16434 -116.092842)
			(xy 183.115714 -116.057867) (xy 183.073357 -116.015515) (xy 183.038377 -115.966892) (xy 183.024526 -115.940332)
			(xy 183.01811 -115.928271) (xy 182.999997 -115.907834) (xy 182.977112 -115.892934) (xy 182.951093 -115.88464)
			(xy 182.923807 -115.883546) (xy 182.897208 -115.88973) (xy 182.873203 -115.90275) (xy 182.853512 -115.921671)
			(xy 182.846218 -115.93322) (xy 182.833725 -115.955308) (xy 182.803016 -115.995704) (xy 182.76649 -116.030928)
			(xy 182.725006 -116.060152) (xy 182.679541 -116.082686) (xy 182.631164 -116.098002) (xy 182.581014 -116.105739)
			(xy 182.555642 -116.106194) (xy 182.529652 -116.105714) (xy 182.47831 -116.097588) (xy 182.428872 -116.081531)
			(xy 182.382555 -116.057936) (xy 182.3405 -116.027386) (xy 182.303742 -115.990632) (xy 182.273186 -115.948581)
			(xy 182.249586 -115.902267) (xy 182.233521 -115.852831) (xy 182.225389 -115.80149) (xy 182.225389 -115.74951)
			(xy 182.233521 -115.698169) (xy 182.249586 -115.648733) (xy 182.273186 -115.602419) (xy 182.303742 -115.560368)
			(xy 182.3405 -115.523614) (xy 182.382555 -115.493064) (xy 182.428872 -115.469469) (xy 182.47831 -115.453412)
			(xy 182.529652 -115.445286) (xy 182.555642 -115.444778) (xy 182.581011 -115.445243) (xy 182.631153 -115.453001)
			(xy 182.67952 -115.468329) (xy 182.724979 -115.490865) (xy 182.76646 -115.520083) (xy 182.802991 -115.555294)
			(xy 182.833714 -115.595674) (xy 182.846218 -115.617752) (xy 182.853598 -115.629218) (xy 182.873296 -115.648058)
			(xy 182.897276 -115.661017) (xy 182.92383 -115.66717) (xy 182.951065 -115.66608) (xy 182.977043 -115.657824)
			(xy 182.99991 -115.64299) (xy 183.018039 -115.622636) (xy 183.024526 -115.61064) (xy 183.030224 -115.599413)
			(xy 183.042935 -115.577677) (xy 183.049926 -115.567206) (xy 183.049926 -115.101624) (xy 183.046624 -115.092988)
			(xy 183.036881 -115.065668) (xy 183.026032 -115.008693) (xy 183.025034 -114.979704) (xy 183.025034 -114.976656)
			(xy 183.025034 -114.975386) (xy 183.025699 -114.945307) (xy 183.036569 -114.88614) (xy 183.046624 -114.857784)
			(xy 183.049926 -114.849148) (xy 183.049926 -114.301778) (xy 183.046624 -114.293142) (xy 183.036877 -114.265822)
			(xy 183.026018 -114.208848) (xy 183.025034 -114.179858) (xy 183.025034 -114.17681) (xy 183.025034 -114.17554)
			(xy 183.025694 -114.145461) (xy 183.036555 -114.08629) (xy 183.046624 -114.057938) (xy 183.049926 -114.049302)
			(xy 183.049926 -112.766094) (xy 183.002428 -112.718596) (xy 182.99122 -112.708133) (xy 182.964098 -112.693858)
			(xy 182.933967 -112.688249) (xy 182.903525 -112.691807) (xy 182.8755 -112.704213) (xy 182.8524 -112.724357)
			(xy 182.843932 -112.737138) (xy 182.83129 -112.758749) (xy 182.800504 -112.798232) (xy 182.764113 -112.832617)
			(xy 182.722951 -112.861118) (xy 182.67796 -112.883084) (xy 182.63017 -112.898009) (xy 182.580675 -112.905554)
			(xy 182.555642 -112.906048) (xy 182.529649 -112.905568) (xy 182.478303 -112.897442) (xy 182.428861 -112.881384)
			(xy 182.382539 -112.857789) (xy 182.340478 -112.827239) (xy 182.303715 -112.790484) (xy 182.273154 -112.748431)
			(xy 182.249547 -112.702115) (xy 182.233477 -112.652676) (xy 182.225338 -112.601332) (xy 182.224934 -112.57534)
			(xy 182.2254 -112.550308) (xy 182.232961 -112.500819) (xy 182.2479 -112.453036) (xy 182.269875 -112.408053)
			(xy 182.298384 -112.366899) (xy 182.332775 -112.330517) (xy 182.37226 -112.299738) (xy 182.393844 -112.28705)
			(xy 182.406627 -112.278573) (xy 182.426803 -112.255491) (xy 182.43923 -112.227465) (xy 182.44279 -112.197014)
			(xy 182.437163 -112.166878) (xy 182.422856 -112.139763) (xy 182.412386 -112.128554) (xy 182.26532 -111.981488)
			(xy 182.26532 -111.934244) (xy 182.259986 -111.923576) (xy 182.248951 -111.900466) (xy 182.233343 -111.851692)
			(xy 182.225423 -111.801099) (xy 182.224934 -111.775494) (xy 182.22541 -111.749887) (xy 182.233308 -111.699287)
			(xy 182.24893 -111.650514) (xy 182.259986 -111.627412) (xy 182.26532 -111.616744) (xy 182.26532 -111.595408)
			(xy 182.41518 -111.445548) (xy 182.41518 -111.308388) (xy 181.78018 -110.673388) (xy 181.60492 -110.673388)
			(xy 181.51856 -110.759748) (xy 181.51856 -110.887764) (xy 181.617366 -110.98657) (xy 181.813708 -111.182658)
			(xy 181.813708 -111.227108) (xy 181.89448 -111.227108) (xy 181.95036 -111.282988) (xy 181.95036 -111.508032)
			(xy 181.971066 -111.523722) (xy 182.007781 -111.560473) (xy 182.0383 -111.602511) (xy 182.061871 -111.648804)
			(xy 182.077915 -111.698213) (xy 182.086037 -111.749522) (xy 182.086038 -111.801471) (xy 182.077917 -111.85278)
			(xy 182.061874 -111.902189) (xy 182.038304 -111.948483) (xy 182.007786 -111.990522) (xy 181.971071 -112.027273)
			(xy 181.95036 -112.042956) (xy 181.95036 -112.307878) (xy 181.971063 -112.323568) (xy 182.007772 -112.360318)
			(xy 182.038282 -112.402358) (xy 182.06184 -112.448651) (xy 182.077868 -112.49806) (xy 182.085971 -112.549368)
			(xy 182.086504 -112.57534) (xy 182.086412 -112.58809) (xy 182.084503 -112.613518) (xy 182.082694 -112.62614)
			(xy 182.078211 -112.651829) (xy 182.062219 -112.701463) (xy 182.038626 -112.747967) (xy 182.00802 -112.790186)
			(xy 181.971159 -112.827072) (xy 181.95036 -112.842802) (xy 181.95036 -113.066068) (xy 181.8894 -113.127028)
			(xy 181.813708 -113.127028) (xy 181.813708 -113.627408) (xy 181.89194 -113.627408) (xy 181.95036 -113.685828)
			(xy 181.95036 -113.908078) (xy 181.971063 -113.923768) (xy 182.007772 -113.960518) (xy 182.038282 -114.002558)
			(xy 182.06184 -114.048851) (xy 182.077868 -114.09826) (xy 182.085971 -114.149568) (xy 182.086504 -114.17554)
			(xy 182.086014 -114.201255) (xy 182.085971 -114.201527) (xy 182.225444 -114.201527) (xy 182.225444 -114.149553)
			(xy 182.233574 -114.098218) (xy 182.249635 -114.048788) (xy 182.273231 -114.002478) (xy 182.303781 -113.96043)
			(xy 182.340532 -113.923679) (xy 182.38258 -113.893129) (xy 182.42889 -113.869533) (xy 182.47832 -113.853472)
			(xy 182.529655 -113.845342) (xy 182.581629 -113.845342) (xy 182.632964 -113.853472) (xy 182.682394 -113.869533)
			(xy 182.728704 -113.893129) (xy 182.770752 -113.923679) (xy 182.807503 -113.96043) (xy 182.838053 -114.002478)
			(xy 182.861649 -114.048788) (xy 182.87771 -114.098218) (xy 182.88584 -114.149553) (xy 182.88635 -114.17554)
			(xy 182.88584 -114.201527) (xy 182.87771 -114.252862) (xy 182.861649 -114.302292) (xy 182.838053 -114.348602)
			(xy 182.807503 -114.39065) (xy 182.770752 -114.427401) (xy 182.728704 -114.457951) (xy 182.682394 -114.481547)
			(xy 182.632964 -114.497608) (xy 182.581629 -114.505738) (xy 182.529655 -114.505738) (xy 182.47832 -114.497608)
			(xy 182.42889 -114.481547) (xy 182.38258 -114.457951) (xy 182.340532 -114.427401) (xy 182.303781 -114.39065)
			(xy 182.273231 -114.348602) (xy 182.249635 -114.302292) (xy 182.233574 -114.252862) (xy 182.225444 -114.201527)
			(xy 182.085971 -114.201527) (xy 182.078053 -114.252065) (xy 182.06233 -114.301032) (xy 182.039222 -114.346979)
			(xy 182.009285 -114.388798) (xy 181.973241 -114.425484) (xy 181.9529 -114.441224) (xy 181.9529 -114.709956)
			(xy 181.973254 -114.725654) (xy 182.009305 -114.76229) (xy 182.039249 -114.804066) (xy 182.062363 -114.849974)
			(xy 182.07809 -114.898908) (xy 182.086051 -114.949687) (xy 182.086504 -114.975386) (xy 182.086038 -115.000829)
			(xy 182.085954 -115.001373) (xy 182.225444 -115.001373) (xy 182.225444 -114.949399) (xy 182.233574 -114.898064)
			(xy 182.249635 -114.848634) (xy 182.273231 -114.802324) (xy 182.303781 -114.760276) (xy 182.340532 -114.723525)
			(xy 182.38258 -114.692975) (xy 182.42889 -114.669379) (xy 182.47832 -114.653318) (xy 182.529655 -114.645188)
			(xy 182.581629 -114.645188) (xy 182.632964 -114.653318) (xy 182.682394 -114.669379) (xy 182.728704 -114.692975)
			(xy 182.770752 -114.723525) (xy 182.807503 -114.760276) (xy 182.838053 -114.802324) (xy 182.861649 -114.848634)
			(xy 182.87771 -114.898064) (xy 182.88584 -114.949399) (xy 182.88635 -114.975386) (xy 182.88584 -115.001373)
			(xy 182.87771 -115.052708) (xy 182.861649 -115.102138) (xy 182.838053 -115.148448) (xy 182.807503 -115.190496)
			(xy 182.770752 -115.227247) (xy 182.728704 -115.257797) (xy 182.682394 -115.281393) (xy 182.632964 -115.297454)
			(xy 182.581629 -115.305584) (xy 182.529655 -115.305584) (xy 182.47832 -115.297454) (xy 182.42889 -115.281393)
			(xy 182.38258 -115.257797) (xy 182.340532 -115.227247) (xy 182.303781 -115.190496) (xy 182.273231 -115.148448)
			(xy 182.249635 -115.102138) (xy 182.233574 -115.052708) (xy 182.225444 -115.001373) (xy 182.085954 -115.001373)
			(xy 182.078245 -115.051115) (xy 182.062842 -115.099613) (xy 182.040191 -115.14518) (xy 182.010828 -115.18674)
			(xy 181.975445 -115.223311) (xy 181.95544 -115.239038) (xy 181.95544 -115.456208) (xy 181.88686 -115.524788)
			(xy 181.813708 -115.524788) (xy 181.813708 -115.566698) (xy 181.617366 -115.762786) (xy 181.51856 -115.861592)
			(xy 181.51856 -116.165122) (xy 181.518989 -116.17868) (xy 181.526131 -116.204838) (xy 181.539905 -116.228194)
			(xy 181.559341 -116.247102) (xy 181.583068 -116.260228) (xy 181.609413 -116.266647) (xy 181.636519 -116.265906)
			(xy 181.649624 -116.262404) (xy 181.675403 -116.254231) (xy 181.728758 -116.24543) (xy 181.755796 -116.244878)
			(xy 181.781784 -116.245387) (xy 181.83312 -116.253517) (xy 181.882552 -116.269578) (xy 181.928863 -116.293173)
			(xy 181.970912 -116.323723) (xy 182.007666 -116.360474) (xy 182.038217 -116.402522) (xy 182.061815 -116.448832)
			(xy 182.077879 -116.498263) (xy 182.086011 -116.549598) (xy 182.086504 -116.575586) (xy 182.086414 -116.588336)
			(xy 182.085422 -116.601573) (xy 182.225444 -116.601573) (xy 182.225444 -116.549599) (xy 182.233574 -116.498264)
			(xy 182.249635 -116.448834) (xy 182.273231 -116.402524) (xy 182.303781 -116.360476) (xy 182.340532 -116.323725)
			(xy 182.38258 -116.293175) (xy 182.42889 -116.269579) (xy 182.47832 -116.253518) (xy 182.529655 -116.245388)
			(xy 182.581629 -116.245388) (xy 182.632964 -116.253518) (xy 182.682394 -116.269579) (xy 182.728704 -116.293175)
			(xy 182.770752 -116.323725) (xy 182.807503 -116.360476) (xy 182.838053 -116.402524) (xy 182.861649 -116.448834)
			(xy 182.87771 -116.498264) (xy 182.88584 -116.549599) (xy 182.88635 -116.575586) (xy 182.88584 -116.601573)
			(xy 182.87771 -116.652908) (xy 182.861649 -116.702338) (xy 182.838053 -116.748648) (xy 182.807503 -116.790696)
			(xy 182.770752 -116.827447) (xy 182.728704 -116.857997) (xy 182.682394 -116.881593) (xy 182.632964 -116.897654)
			(xy 182.581629 -116.905784) (xy 182.529655 -116.905784) (xy 182.47832 -116.897654) (xy 182.42889 -116.881593)
			(xy 182.38258 -116.857997) (xy 182.340532 -116.827447) (xy 182.303781 -116.790696) (xy 182.273231 -116.748648)
			(xy 182.249635 -116.702338) (xy 182.233574 -116.652908) (xy 182.225444 -116.601573) (xy 182.085422 -116.601573)
			(xy 182.084509 -116.613765) (xy 182.082694 -116.626386) (xy 182.078316 -116.651368) (xy 182.062963 -116.699704)
			(xy 182.040415 -116.745131) (xy 182.011199 -116.786586) (xy 181.976 -116.823098) (xy 181.935643 -116.853812)
			(xy 181.891072 -116.878009) (xy 181.843331 -116.895121) (xy 181.818534 -116.900452) (xy 181.772306 -116.946934)
			(xy 181.838092 -117.01272) (xy 182.15356 -117.01272) (xy 182.282592 -117.141752) (xy 182.318406 -117.109748)
			(xy 182.329074 -117.100604) (xy 182.348274 -117.085317) (xy 182.390077 -117.059605) (xy 182.435016 -117.039878)
			(xy 182.482238 -117.02651) (xy 182.530849 -117.019755) (xy 182.555388 -117.019324) (xy 182.555642 -117.019324)
			(xy 182.583622 -117.019876) (xy 182.638892 -117.028637) (xy 182.692112 -117.045935) (xy 182.74197 -117.071346)
			(xy 182.787239 -117.104243) (xy 182.826805 -117.143817) (xy 182.859693 -117.189093) (xy 182.885093 -117.238957)
			(xy 182.902381 -117.29218) (xy 182.91113 -117.347452) (xy 182.91175 -117.375432) (xy 182.911278 -117.401401)
			(xy 182.911275 -117.401419) (xy 183.025544 -117.401419) (xy 183.025544 -117.349445) (xy 183.033674 -117.29811)
			(xy 183.049735 -117.24868) (xy 183.073331 -117.20237) (xy 183.103881 -117.160322) (xy 183.140632 -117.123571)
			(xy 183.18268 -117.093021) (xy 183.22899 -117.069425) (xy 183.27842 -117.053364) (xy 183.329755 -117.045234)
			(xy 183.381729 -117.045234) (xy 183.433064 -117.053364) (xy 183.482494 -117.069425) (xy 183.528804 -117.093021)
			(xy 183.570852 -117.123571) (xy 183.607603 -117.160322) (xy 183.638153 -117.20237) (xy 183.661749 -117.24868)
			(xy 183.67781 -117.29811) (xy 183.68594 -117.349445) (xy 183.68645 -117.375432) (xy 183.68594 -117.401419)
			(xy 183.67781 -117.452754) (xy 183.661749 -117.502184) (xy 183.638153 -117.548494) (xy 183.607603 -117.590542)
			(xy 183.570852 -117.627293) (xy 183.528804 -117.657843) (xy 183.482494 -117.681439) (xy 183.433064 -117.6975)
			(xy 183.381729 -117.70563) (xy 183.329755 -117.70563) (xy 183.27842 -117.6975) (xy 183.22899 -117.681439)
			(xy 183.18268 -117.657843) (xy 183.140632 -117.627293) (xy 183.103881 -117.590542) (xy 183.073331 -117.548494)
			(xy 183.049735 -117.502184) (xy 183.033674 -117.452754) (xy 183.025544 -117.401419) (xy 182.911275 -117.401419)
			(xy 182.903736 -117.45279) (xy 182.888815 -117.50254) (xy 182.866832 -117.549597) (xy 182.838252 -117.592966)
			(xy 182.821326 -117.612668) (xy 182.789322 -117.648482) (xy 183.087518 -117.946678) (xy 183.136032 -117.928136)
			(xy 183.142636 -117.922548) (xy 183.165181 -117.904356) (xy 183.215315 -117.875338) (xy 183.269735 -117.855489)
			(xy 183.326779 -117.845414) (xy 183.355742 -117.844824) (xy 183.381725 -117.845337) (xy 183.433049 -117.853472)
			(xy 183.482469 -117.869535) (xy 183.528768 -117.893131) (xy 183.570807 -117.923678) (xy 183.607549 -117.960425)
			(xy 183.638091 -118.002468) (xy 183.661681 -118.04877) (xy 183.677738 -118.098192) (xy 183.685867 -118.149517)
			(xy 183.685867 -118.201483) (xy 183.685861 -118.201519) (xy 183.82539 -118.201519) (xy 183.82539 -118.149545)
			(xy 183.83352 -118.09821) (xy 183.849581 -118.04878) (xy 183.873177 -118.00247) (xy 183.903727 -117.960422)
			(xy 183.940478 -117.923671) (xy 183.982526 -117.893121) (xy 184.028836 -117.869525) (xy 184.078266 -117.853464)
			(xy 184.129601 -117.845334) (xy 184.181575 -117.845334) (xy 184.23291 -117.853464) (xy 184.28234 -117.869525)
			(xy 184.32865 -117.893121) (xy 184.370698 -117.923671) (xy 184.407449 -117.960422) (xy 184.437999 -118.00247)
			(xy 184.461595 -118.04878) (xy 184.477656 -118.09821) (xy 184.485786 -118.149545) (xy 184.486296 -118.175532)
			(xy 184.485786 -118.201519) (xy 184.477656 -118.252854) (xy 184.461595 -118.302284) (xy 184.437999 -118.348594)
			(xy 184.407449 -118.390642) (xy 184.370698 -118.427393) (xy 184.32865 -118.457943) (xy 184.28234 -118.481539)
			(xy 184.23291 -118.4976) (xy 184.181575 -118.50573) (xy 184.129601 -118.50573) (xy 184.078266 -118.4976)
			(xy 184.028836 -118.481539) (xy 183.982526 -118.457943) (xy 183.940478 -118.427393) (xy 183.903727 -118.390642)
			(xy 183.873177 -118.348594) (xy 183.849581 -118.302284) (xy 183.83352 -118.252854) (xy 183.82539 -118.201519)
			(xy 183.685861 -118.201519) (xy 183.677738 -118.252808) (xy 183.661681 -118.30223) (xy 183.638091 -118.348532)
			(xy 183.607549 -118.390575) (xy 183.570807 -118.427322) (xy 183.528768 -118.457869) (xy 183.482469 -118.481465)
			(xy 183.433049 -118.497528) (xy 183.381725 -118.505663) (xy 183.355742 -118.50624) (xy 183.33466 -118.505478)
			(xy 183.32958 -118.505478) (xy 183.32042 -118.505919) (xy 183.303301 -118.51246) (xy 183.289568 -118.524595)
			(xy 183.280969 -118.540778) (xy 183.278599 -118.558951) (xy 183.280304 -118.567962) (xy 183.282844 -118.578884)
			(xy 183.285384 -118.583964) (xy 183.293004 -118.600728) (xy 183.297895 -118.612279) (xy 183.306283 -118.635922)
			(xy 183.309768 -118.647972) (xy 183.3212 -118.646437) (xy 183.344208 -118.644781) (xy 183.355742 -118.64467)
			(xy 183.381728 -118.645183) (xy 183.433058 -118.653318) (xy 183.482485 -118.669383) (xy 183.52879 -118.69298)
			(xy 183.570834 -118.723531) (xy 183.607582 -118.760281) (xy 183.63813 -118.802327) (xy 183.661725 -118.848634)
			(xy 183.677786 -118.898061) (xy 183.685919 -118.949392) (xy 183.68645 -118.975378) (xy 183.685987 -119.000553)
			(xy 183.685863 -119.001365) (xy 183.82539 -119.001365) (xy 183.82539 -118.949391) (xy 183.83352 -118.898056)
			(xy 183.849581 -118.848626) (xy 183.873177 -118.802316) (xy 183.903727 -118.760268) (xy 183.940478 -118.723517)
			(xy 183.982526 -118.692967) (xy 184.028836 -118.669371) (xy 184.078266 -118.65331) (xy 184.129601 -118.64518)
			(xy 184.181575 -118.64518) (xy 184.23291 -118.65331) (xy 184.28234 -118.669371) (xy 184.32865 -118.692967)
			(xy 184.370698 -118.723517) (xy 184.407449 -118.760268) (xy 184.437999 -118.802316) (xy 184.461595 -118.848626)
			(xy 184.477656 -118.898056) (xy 184.485786 -118.949391) (xy 184.486296 -118.975378) (xy 184.485786 -119.001365)
			(xy 184.62549 -119.001365) (xy 184.62549 -118.949391) (xy 184.63362 -118.898056) (xy 184.649681 -118.848626)
			(xy 184.673277 -118.802316) (xy 184.703827 -118.760268) (xy 184.740578 -118.723517) (xy 184.782626 -118.692967)
			(xy 184.828936 -118.669371) (xy 184.878366 -118.65331) (xy 184.929701 -118.64518) (xy 184.981675 -118.64518)
			(xy 185.03301 -118.65331) (xy 185.08244 -118.669371) (xy 185.12875 -118.692967) (xy 185.170798 -118.723517)
			(xy 185.207549 -118.760268) (xy 185.238099 -118.802316) (xy 185.261695 -118.848626) (xy 185.277756 -118.898056)
			(xy 185.285886 -118.949391) (xy 185.286396 -118.975378) (xy 185.285886 -119.001365) (xy 185.277756 -119.0527)
			(xy 185.261695 -119.10213) (xy 185.238099 -119.14844) (xy 185.207549 -119.190488) (xy 185.170798 -119.227239)
			(xy 185.12875 -119.257789) (xy 185.08244 -119.281385) (xy 185.03301 -119.297446) (xy 184.981675 -119.305576)
			(xy 184.929701 -119.305576) (xy 184.878366 -119.297446) (xy 184.828936 -119.281385) (xy 184.782626 -119.257789)
			(xy 184.740578 -119.227239) (xy 184.703827 -119.190488) (xy 184.673277 -119.14844) (xy 184.649681 -119.10213)
			(xy 184.63362 -119.0527) (xy 184.62549 -119.001365) (xy 184.485786 -119.001365) (xy 184.477656 -119.0527)
			(xy 184.461595 -119.10213) (xy 184.437999 -119.14844) (xy 184.407449 -119.190488) (xy 184.370698 -119.227239)
			(xy 184.32865 -119.257789) (xy 184.28234 -119.281385) (xy 184.23291 -119.297446) (xy 184.181575 -119.305576)
			(xy 184.129601 -119.305576) (xy 184.078266 -119.297446) (xy 184.028836 -119.281385) (xy 183.982526 -119.257789)
			(xy 183.940478 -119.227239) (xy 183.903727 -119.190488) (xy 183.873177 -119.14844) (xy 183.849581 -119.10213)
			(xy 183.83352 -119.0527) (xy 183.82539 -119.001365) (xy 183.685863 -119.001365) (xy 183.67837 -119.050323)
			(xy 183.663293 -119.098362) (xy 183.641104 -119.143559) (xy 183.612318 -119.184868) (xy 183.577601 -119.221333)
			(xy 183.537754 -119.252112) (xy 183.493701 -119.276492) (xy 183.44646 -119.293909) (xy 183.397124 -119.30396)
			(xy 183.371998 -119.305578) (xy 183.362287 -119.306436) (xy 183.344548 -119.314478) (xy 183.331088 -119.328556)
			(xy 183.323851 -119.346639) (xy 183.323484 -119.356378) (xy 183.323484 -119.394478) (xy 183.323928 -119.404201)
			(xy 183.331178 -119.422245) (xy 183.344612 -119.436306) (xy 183.362307 -119.444373) (xy 183.371998 -119.445278)
			(xy 183.397114 -119.446988) (xy 183.446435 -119.457056) (xy 183.493662 -119.47448) (xy 183.537704 -119.498858)
			(xy 183.577544 -119.529627) (xy 183.612263 -119.566076) (xy 183.641059 -119.607364) (xy 183.663268 -119.652539)
			(xy 183.678377 -119.700557) (xy 183.686036 -119.750309) (xy 183.68645 -119.775478) (xy 183.685925 -119.801465)
			(xy 183.82539 -119.801465) (xy 183.82539 -119.749491) (xy 183.83352 -119.698156) (xy 183.849581 -119.648726)
			(xy 183.873177 -119.602416) (xy 183.903727 -119.560368) (xy 183.940478 -119.523617) (xy 183.982526 -119.493067)
			(xy 184.028836 -119.469471) (xy 184.078266 -119.45341) (xy 184.129601 -119.44528) (xy 184.181575 -119.44528)
			(xy 184.23291 -119.45341) (xy 184.28234 -119.469471) (xy 184.32865 -119.493067) (xy 184.370698 -119.523617)
			(xy 184.407449 -119.560368) (xy 184.437999 -119.602416) (xy 184.461595 -119.648726) (xy 184.477656 -119.698156)
			(xy 184.485786 -119.749491) (xy 184.486296 -119.775478) (xy 184.485786 -119.801465) (xy 184.62549 -119.801465)
			(xy 184.62549 -119.749491) (xy 184.63362 -119.698156) (xy 184.649681 -119.648726) (xy 184.673277 -119.602416)
			(xy 184.703827 -119.560368) (xy 184.740578 -119.523617) (xy 184.782626 -119.493067) (xy 184.828936 -119.469471)
			(xy 184.878366 -119.45341) (xy 184.929701 -119.44528) (xy 184.981675 -119.44528) (xy 185.03301 -119.45341)
			(xy 185.08244 -119.469471) (xy 185.12875 -119.493067) (xy 185.170798 -119.523617) (xy 185.207549 -119.560368)
			(xy 185.238099 -119.602416) (xy 185.261695 -119.648726) (xy 185.277756 -119.698156) (xy 185.285886 -119.749491)
			(xy 185.286396 -119.775478) (xy 185.285886 -119.801465) (xy 185.277756 -119.8528) (xy 185.261695 -119.90223)
			(xy 185.238099 -119.94854) (xy 185.207549 -119.990588) (xy 185.170798 -120.027339) (xy 185.12875 -120.057889)
			(xy 185.08244 -120.081485) (xy 185.03301 -120.097546) (xy 184.981675 -120.105676) (xy 184.929701 -120.105676)
			(xy 184.878366 -120.097546) (xy 184.828936 -120.081485) (xy 184.782626 -120.057889) (xy 184.740578 -120.027339)
			(xy 184.703827 -119.990588) (xy 184.673277 -119.94854) (xy 184.649681 -119.90223) (xy 184.63362 -119.8528)
			(xy 184.62549 -119.801465) (xy 184.485786 -119.801465) (xy 184.477656 -119.8528) (xy 184.461595 -119.90223)
			(xy 184.437999 -119.94854) (xy 184.407449 -119.990588) (xy 184.370698 -120.027339) (xy 184.32865 -120.057889)
			(xy 184.28234 -120.081485) (xy 184.23291 -120.097546) (xy 184.181575 -120.105676) (xy 184.129601 -120.105676)
			(xy 184.078266 -120.097546) (xy 184.028836 -120.081485) (xy 183.982526 -120.057889) (xy 183.940478 -120.027339)
			(xy 183.903727 -119.990588) (xy 183.873177 -119.94854) (xy 183.849581 -119.90223) (xy 183.83352 -119.8528)
			(xy 183.82539 -119.801465) (xy 183.685925 -119.801465) (xy 183.685903 -119.802545) (xy 183.677078 -119.855955)
			(xy 183.659676 -119.907215) (xy 183.63416 -119.954959) (xy 183.601213 -119.997912) (xy 183.561712 -120.034928)
			(xy 183.516713 -120.06502) (xy 183.467414 -120.087385) (xy 183.415133 -120.101426) (xy 183.388254 -120.104662)
			(xy 183.339994 -120.152922) (xy 183.443626 -120.256554) (xy 183.45531 -120.260364) (xy 183.480354 -120.268821)
			(xy 183.527579 -120.292564) (xy 183.570424 -120.323518) (xy 183.607798 -120.360895) (xy 183.638749 -120.403743)
			(xy 183.662488 -120.450969) (xy 183.670956 -120.47601) (xy 183.674766 -120.487694) (xy 183.752236 -120.565164)
			(xy 183.798718 -120.518936) (xy 183.839358 -120.478296) (xy 183.843168 -120.46712) (xy 183.852007 -120.443117)
			(xy 183.876024 -120.397956) (xy 183.906706 -120.357031) (xy 183.943324 -120.321318) (xy 183.985003 -120.291669)
			(xy 184.03075 -120.268789) (xy 184.079474 -120.253226) (xy 184.130013 -120.245349) (xy 184.155588 -120.24487)
			(xy 184.181576 -120.245379) (xy 184.232914 -120.253508) (xy 184.282347 -120.269567) (xy 184.32866 -120.293162)
			(xy 184.370712 -120.323711) (xy 184.407467 -120.360463) (xy 184.43802 -120.402511) (xy 184.46162 -120.448821)
			(xy 184.477684 -120.498253) (xy 184.485819 -120.54959) (xy 184.486296 -120.575578) (xy 184.485829 -120.601143)
			(xy 184.485763 -120.601565) (xy 184.62549 -120.601565) (xy 184.62549 -120.549591) (xy 184.63362 -120.498256)
			(xy 184.649681 -120.448826) (xy 184.673277 -120.402516) (xy 184.703827 -120.360468) (xy 184.740578 -120.323717)
			(xy 184.782626 -120.293167) (xy 184.828936 -120.269571) (xy 184.878366 -120.25351) (xy 184.929701 -120.24538)
			(xy 184.981675 -120.24538) (xy 185.03301 -120.25351) (xy 185.08244 -120.269571) (xy 185.12875 -120.293167)
			(xy 185.170798 -120.323717) (xy 185.207549 -120.360468) (xy 185.238099 -120.402516) (xy 185.261695 -120.448826)
			(xy 185.277756 -120.498256) (xy 185.285886 -120.549591) (xy 185.286396 -120.575578) (xy 185.285886 -120.601565)
			(xy 185.277756 -120.6529) (xy 185.261695 -120.70233) (xy 185.238099 -120.74864) (xy 185.207549 -120.790688)
			(xy 185.170798 -120.827439) (xy 185.12875 -120.857989) (xy 185.08244 -120.881585) (xy 185.03301 -120.897646)
			(xy 184.981675 -120.905776) (xy 184.929701 -120.905776) (xy 184.878366 -120.897646) (xy 184.828936 -120.881585)
			(xy 184.782626 -120.857989) (xy 184.740578 -120.827439) (xy 184.703827 -120.790688) (xy 184.673277 -120.74864)
			(xy 184.649681 -120.70233) (xy 184.63362 -120.6529) (xy 184.62549 -120.601565) (xy 184.485763 -120.601565)
			(xy 184.477978 -120.651666) (xy 184.462445 -120.700379) (xy 184.439599 -120.746121) (xy 184.409985 -120.787801)
			(xy 184.374309 -120.824427) (xy 184.33342 -120.855125) (xy 184.288294 -120.879164) (xy 184.2643 -120.887998)
			(xy 184.253124 -120.891808) (xy 184.21223 -120.932448) (xy 184.166002 -120.97893) (xy 184.243472 -121.0564)
			(xy 184.255156 -121.06021) (xy 184.280202 -121.068665) (xy 184.327429 -121.092404) (xy 184.370277 -121.123357)
			(xy 184.407653 -121.160735) (xy 184.438603 -121.203584) (xy 184.46234 -121.250812) (xy 184.470802 -121.275856)
			(xy 184.474612 -121.28754) (xy 184.578244 -121.391172) (xy 184.625996 -121.34342) (xy 184.628536 -121.326656)
			(xy 184.632883 -121.300856) (xy 184.648648 -121.250969) (xy 184.672071 -121.204187) (xy 184.702568 -121.161676)
			(xy 184.739379 -121.124499) (xy 184.781585 -121.093582) (xy 184.828133 -121.069696) (xy 184.877861 -121.053438)
			(xy 184.929529 -121.045213) (xy 184.955688 -121.044716) (xy 184.981677 -121.045198) (xy 185.033016 -121.053328)
			(xy 185.08245 -121.06939) (xy 185.128764 -121.092987) (xy 185.170815 -121.12354) (xy 185.207568 -121.160294)
			(xy 185.238119 -121.202347) (xy 185.261715 -121.248661) (xy 185.277775 -121.298096) (xy 185.285903 -121.349435)
			(xy 185.286396 -121.375424) (xy 185.285876 -121.401411) (xy 185.42559 -121.401411) (xy 185.42559 -121.349437)
			(xy 185.43372 -121.298102) (xy 185.449781 -121.248672) (xy 185.473377 -121.202362) (xy 185.503927 -121.160314)
			(xy 185.540678 -121.123563) (xy 185.582726 -121.093013) (xy 185.629036 -121.069417) (xy 185.678466 -121.053356)
			(xy 185.729801 -121.045226) (xy 185.781775 -121.045226) (xy 185.83311 -121.053356) (xy 185.88254 -121.069417)
			(xy 185.92885 -121.093013) (xy 185.970898 -121.123563) (xy 186.007649 -121.160314) (xy 186.038199 -121.202362)
			(xy 186.061795 -121.248672) (xy 186.077856 -121.298102) (xy 186.085986 -121.349437) (xy 186.086496 -121.375424)
			(xy 186.085986 -121.401411) (xy 186.077856 -121.452746) (xy 186.061795 -121.502176) (xy 186.038199 -121.548486)
			(xy 186.007649 -121.590534) (xy 185.970898 -121.627285) (xy 185.92885 -121.657835) (xy 185.88254 -121.681431)
			(xy 185.83311 -121.697492) (xy 185.781775 -121.705622) (xy 185.729801 -121.705622) (xy 185.678466 -121.697492)
			(xy 185.629036 -121.681431) (xy 185.582726 -121.657835) (xy 185.540678 -121.627285) (xy 185.503927 -121.590534)
			(xy 185.473377 -121.548486) (xy 185.449781 -121.502176) (xy 185.43372 -121.452746) (xy 185.42559 -121.401411)
			(xy 185.285876 -121.401411) (xy 185.285854 -121.402495) (xy 185.277036 -121.455914) (xy 185.259639 -121.507185)
			(xy 185.234128 -121.554939) (xy 185.201182 -121.597904) (xy 185.161682 -121.634932) (xy 185.11668 -121.665035)
			(xy 185.067379 -121.687411) (xy 185.015092 -121.701462) (xy 184.9882 -121.704608) (xy 184.93994 -121.752868)
			(xy 185.036206 -121.849134) (xy 185.050684 -121.852182) (xy 185.077071 -121.858418) (xy 185.127504 -121.878318)
			(xy 185.174016 -121.906177) (xy 185.215361 -121.941249) (xy 185.250431 -121.982596) (xy 185.278289 -122.029109)
			(xy 185.298186 -122.079543) (xy 185.30443 -122.105928) (xy 185.307478 -122.120406) (xy 185.388583 -122.201511)
			(xy 186.225436 -122.201511) (xy 186.225436 -122.149537) (xy 186.233566 -122.098202) (xy 186.249627 -122.048772)
			(xy 186.273223 -122.002462) (xy 186.303773 -121.960414) (xy 186.340524 -121.923663) (xy 186.382572 -121.893113)
			(xy 186.428882 -121.869517) (xy 186.478312 -121.853456) (xy 186.529647 -121.845326) (xy 186.581621 -121.845326)
			(xy 186.632956 -121.853456) (xy 186.682386 -121.869517) (xy 186.728696 -121.893113) (xy 186.770744 -121.923663)
			(xy 186.807495 -121.960414) (xy 186.838045 -122.002462) (xy 186.861641 -122.048772) (xy 186.877702 -122.098202)
			(xy 186.885832 -122.149537) (xy 186.886342 -122.175524) (xy 186.885832 -122.201511) (xy 186.877702 -122.252846)
			(xy 186.861641 -122.302276) (xy 186.838045 -122.348586) (xy 186.807495 -122.390634) (xy 186.770744 -122.427385)
			(xy 186.728696 -122.457935) (xy 186.682386 -122.481531) (xy 186.632956 -122.497592) (xy 186.581621 -122.505722)
			(xy 186.529647 -122.505722) (xy 186.478312 -122.497592) (xy 186.428882 -122.481531) (xy 186.382572 -122.457935)
			(xy 186.340524 -122.427385) (xy 186.303773 -122.390634) (xy 186.273223 -122.348586) (xy 186.249627 -122.302276)
			(xy 186.233566 -122.252846) (xy 186.225436 -122.201511) (xy 185.388583 -122.201511) (xy 188.251084 -125.064012)
			(xy 188.275214 -125.061726) (xy 188.28655 -125.060659) (xy 188.309294 -125.059517) (xy 188.32068 -125.05944)
			(xy 188.350649 -125.059908) (xy 188.410074 -125.067729) (xy 188.467969 -125.083241) (xy 188.523344 -125.106178)
			(xy 188.575251 -125.136147) (xy 188.622802 -125.172635) (xy 188.665183 -125.215019) (xy 188.701669 -125.262572)
			(xy 188.731634 -125.314481) (xy 188.754568 -125.369858) (xy 188.770076 -125.427754) (xy 188.777894 -125.487179)
			(xy 188.778388 -125.517148) (xy 188.778306 -125.529236) (xy 188.777033 -125.553378) (xy 188.775848 -125.565408)
			(xy 188.773816 -125.586744) (xy 188.980064 -125.792992) (xy 190.694818 -125.792992)
		)
		(stroke
			(width 0)
			(type solid)
		)
		(fill yes)
		(layer "B.Cu")
		(net "P3V3_AUX_FPGA_VCCIO2")
	)
	(gr_poly
		(pts
			(xy 99.607878 -248.153174) (xy 99.602036 -248.142252) (xy 99.590522 -248.118921) (xy 99.574222 -248.069515)
			(xy 99.565957 -248.01815) (xy 99.56546 -247.992138) (xy 99.565964 -247.96643) (xy 99.574007 -247.915648)
			(xy 99.589895 -247.866749) (xy 99.613238 -247.820937) (xy 99.643459 -247.779341) (xy 99.679815 -247.742985)
			(xy 99.721411 -247.712764) (xy 99.767223 -247.689421) (xy 99.816122 -247.673533) (xy 99.866904 -247.66549)
			(xy 99.91832 -247.66549) (xy 99.969102 -247.673533) (xy 100.018001 -247.689421) (xy 100.063813 -247.712764)
			(xy 100.105409 -247.742985) (xy 100.141765 -247.779341) (xy 100.171986 -247.820937) (xy 100.195329 -247.866749)
			(xy 100.211217 -247.915648) (xy 100.21926 -247.96643) (xy 100.219764 -247.992138) (xy 100.219335 -248.015913)
			(xy 100.212444 -248.062961) (xy 100.206048 -248.085864) (xy 100.202604 -248.098938) (xy 100.201976 -248.125957)
			(xy 100.208457 -248.152195) (xy 100.221593 -248.175815) (xy 100.240464 -248.195162) (xy 100.263749 -248.208882)
			(xy 100.289817 -248.216015) (xy 100.30333 -248.21642) (xy 100.391468 -248.21642) (xy 100.404851 -248.216019)
			(xy 100.430694 -248.209057) (xy 100.453834 -248.195607) (xy 100.472673 -248.176595) (xy 100.485911 -248.153334)
			(xy 100.492636 -248.127428) (xy 100.492383 -248.100664) (xy 100.489258 -248.087642) (xy 100.483178 -248.064236)
			(xy 100.476676 -248.016317) (xy 100.476304 -247.992138) (xy 100.476802 -247.965489) (xy 100.484745 -247.912785)
			(xy 100.500455 -247.861855) (xy 100.523581 -247.813834) (xy 100.553605 -247.769797) (xy 100.589857 -247.730726)
			(xy 100.631528 -247.697495) (xy 100.677686 -247.670846) (xy 100.7273 -247.651374) (xy 100.779262 -247.639514)
			(xy 100.832412 -247.635531) (xy 100.885562 -247.639514) (xy 100.937524 -247.651374) (xy 100.987138 -247.670846)
			(xy 101.033296 -247.697495) (xy 101.074967 -247.730726) (xy 101.111219 -247.769797) (xy 101.141243 -247.813834)
			(xy 101.164369 -247.861855) (xy 101.180079 -247.912785) (xy 101.188022 -247.965489) (xy 101.18852 -247.992138)
			(xy 101.18813 -248.016316) (xy 101.181629 -248.064233) (xy 101.175566 -248.087642) (xy 101.172379 -248.100644)
			(xy 101.172174 -248.127404) (xy 101.178928 -248.153298) (xy 101.192179 -248.176548) (xy 101.211016 -248.195557)
			(xy 101.234144 -248.209018) (xy 101.259976 -248.216008) (xy 101.273356 -248.21642) (xy 101.361494 -248.21642)
			(xy 101.375021 -248.21601) (xy 101.401131 -248.208925) (xy 101.42446 -248.195225) (xy 101.443366 -248.175873)
			(xy 101.45652 -248.152232) (xy 101.462995 -248.125964) (xy 101.462337 -248.098918) (xy 101.458776 -248.085864)
			(xy 101.452372 -248.062963) (xy 101.445484 -248.015914) (xy 101.44506 -247.992138) (xy 101.445564 -247.96643)
			(xy 101.453607 -247.915648) (xy 101.469495 -247.866749) (xy 101.492838 -247.820937) (xy 101.523059 -247.779341)
			(xy 101.559415 -247.742985) (xy 101.601011 -247.712764) (xy 101.646823 -247.689421) (xy 101.695722 -247.673533)
			(xy 101.746504 -247.66549) (xy 101.79792 -247.66549) (xy 101.848702 -247.673533) (xy 101.897601 -247.689421)
			(xy 101.943413 -247.712764) (xy 101.985009 -247.742985) (xy 102.021365 -247.779341) (xy 102.051586 -247.820937)
			(xy 102.074929 -247.866749) (xy 102.090817 -247.915648) (xy 102.09886 -247.96643) (xy 102.099364 -247.992138)
			(xy 102.098935 -248.015913) (xy 102.092044 -248.062961) (xy 102.085648 -248.085864) (xy 102.082204 -248.098938)
			(xy 102.081576 -248.125957) (xy 102.088057 -248.152195) (xy 102.101193 -248.175815) (xy 102.120064 -248.195162)
			(xy 102.143349 -248.208882) (xy 102.169417 -248.216015) (xy 102.18293 -248.21642) (xy 104.650286 -248.21642)
			(xy 104.783636 -248.08307) (xy 104.783636 -246.54637) (xy 104.612186 -246.37492) (xy 102.524306 -246.37492)
			(xy 102.346506 -246.19712) (xy 102.346506 -246.008398) (xy 102.346104 -245.995032) (xy 102.339164 -245.969216)
			(xy 102.325759 -245.946088) (xy 102.30681 -245.927232) (xy 102.283615 -245.913943) (xy 102.257766 -245.907131)
			(xy 102.244398 -245.906798) (xy 102.242366 -245.906798) (xy 102.215719 -245.906298) (xy 102.163021 -245.89835)
			(xy 102.112096 -245.882638) (xy 102.064082 -245.859511) (xy 102.02005 -245.829487) (xy 101.980985 -245.793236)
			(xy 101.947758 -245.751568) (xy 101.921113 -245.705413) (xy 101.901643 -245.655803) (xy 101.889785 -245.603845)
			(xy 101.885802 -245.5507) (xy 101.889785 -245.497555) (xy 101.901643 -245.445597) (xy 101.921113 -245.395987)
			(xy 101.947758 -245.349832) (xy 101.980985 -245.308164) (xy 102.02005 -245.271913) (xy 102.064082 -245.241889)
			(xy 102.112096 -245.218762) (xy 102.163021 -245.20305) (xy 102.215719 -245.195102) (xy 102.242366 -245.194582)
			(xy 102.244398 -245.194582) (xy 102.257765 -245.194247) (xy 102.283611 -245.187434) (xy 102.306803 -245.174144)
			(xy 102.325749 -245.155289) (xy 102.339149 -245.132161) (xy 102.346084 -245.106347) (xy 102.346506 -245.092982)
			(xy 102.346506 -244.62232) (xy 102.9462 -244.022626) (xy 102.9462 -242.81003) (xy 103.20655 -242.54968)
			(xy 103.852726 -242.54968) (xy 104.101646 -242.30076) (xy 104.101646 -241.40414) (xy 104.005126 -241.30762)
			(xy 102.770686 -241.30762) (xy 102.387146 -240.92408) (xy 102.387146 -240.31448) (xy 102.346506 -240.27384)
			(xy 101.655118 -240.27384) (xy 101.640728 -240.274335) (xy 101.613091 -240.282362) (xy 101.588793 -240.297785)
			(xy 101.569765 -240.319376) (xy 101.55752 -240.34542) (xy 101.55303 -240.373847) (xy 101.556653 -240.402398)
			(xy 101.5681 -240.428802) (xy 101.576886 -240.44021) (xy 101.592275 -240.459451) (xy 101.618163 -240.50137)
			(xy 101.638025 -240.546458) (xy 101.651481 -240.593854) (xy 101.658276 -240.642652) (xy 101.658674 -240.667286)
			(xy 101.658176 -240.693935) (xy 101.650233 -240.746639) (xy 101.634523 -240.797569) (xy 101.611397 -240.84559)
			(xy 101.581373 -240.889627) (xy 101.545121 -240.928698) (xy 101.50345 -240.961929) (xy 101.457292 -240.988578)
			(xy 101.407678 -241.00805) (xy 101.355716 -241.01991) (xy 101.302566 -241.023894) (xy 101.249416 -241.01991)
			(xy 101.197454 -241.00805) (xy 101.14784 -240.988578) (xy 101.101682 -240.961929) (xy 101.060011 -240.928698)
			(xy 101.023759 -240.889627) (xy 100.993735 -240.84559) (xy 100.970609 -240.797569) (xy 100.954899 -240.746639)
			(xy 100.946956 -240.693935) (xy 100.946458 -240.667286) (xy 100.946876 -240.642653) (xy 100.953669 -240.593856)
			(xy 100.967122 -240.546462) (xy 100.98698 -240.501375) (xy 101.012863 -240.459455) (xy 101.028246 -240.44021)
			(xy 101.037044 -240.428809) (xy 101.04849 -240.402398) (xy 101.052112 -240.373843) (xy 101.047621 -240.34541)
			(xy 101.035375 -240.319361) (xy 101.016346 -240.297763) (xy 100.992046 -240.282334) (xy 100.964406 -240.274298)
			(xy 100.950014 -240.27384) (xy 100.67671 -240.27384) (xy 100.661956 -240.274336) (xy 100.633678 -240.28277)
			(xy 100.608991 -240.298936) (xy 100.589957 -240.321485) (xy 100.578163 -240.348534) (xy 100.574595 -240.377826)
			(xy 100.579551 -240.406916) (xy 100.592616 -240.433375) (xy 100.602288 -240.444528) (xy 100.618648 -240.462784)
			(xy 100.646271 -240.50328) (xy 100.667534 -240.547448) (xy 100.68196 -240.594297) (xy 100.689226 -240.642776)
			(xy 100.689664 -240.667286) (xy 100.68916 -240.692974) (xy 100.681123 -240.743717) (xy 100.665247 -240.792578)
			(xy 100.641923 -240.838354) (xy 100.611726 -240.879918) (xy 100.575398 -240.916246) (xy 100.533834 -240.946443)
			(xy 100.488058 -240.969767) (xy 100.439197 -240.985643) (xy 100.388454 -240.99368) (xy 100.337078 -240.99368)
			(xy 100.286335 -240.985643) (xy 100.237474 -240.969767) (xy 100.191698 -240.946443) (xy 100.150134 -240.916246)
			(xy 100.113806 -240.879918) (xy 100.083609 -240.838354) (xy 100.060285 -240.792578) (xy 100.044409 -240.743717)
			(xy 100.036372 -240.692974) (xy 100.035868 -240.667286) (xy 100.036291 -240.642776) (xy 100.043577 -240.594302)
			(xy 100.058014 -240.547458) (xy 100.079279 -240.503292) (xy 100.106896 -240.462794) (xy 100.123244 -240.444528)
			(xy 100.13292 -240.433377) (xy 100.145982 -240.406914) (xy 100.150935 -240.377822) (xy 100.147366 -240.348528)
			(xy 100.135574 -240.321476) (xy 100.11654 -240.298923) (xy 100.091855 -240.282752) (xy 100.063577 -240.274311)
			(xy 100.048822 -240.27384) (xy 99.953826 -240.27384) (xy 99.735132 -240.492534) (xy 99.749102 -240.524284)
			(xy 99.758581 -240.546919) (xy 99.771932 -240.594141) (xy 99.778673 -240.642749) (xy 99.779074 -240.667286)
			(xy 99.778554 -240.695271) (xy 99.7698 -240.750552) (xy 99.752505 -240.803783) (xy 99.727095 -240.853653)
			(xy 99.694196 -240.898933) (xy 99.654618 -240.938509) (xy 99.609336 -240.971406) (xy 99.559465 -240.996813)
			(xy 99.506233 -241.014105) (xy 99.450951 -241.022856) (xy 99.422966 -241.023394) (xy 99.418902 -241.023394)
			(xy 99.405491 -241.023669) (xy 99.379532 -241.030396) (xy 99.356221 -241.04365) (xy 99.337166 -241.062517)
			(xy 99.323681 -241.085696) (xy 99.316697 -241.111586) (xy 99.316286 -241.124994) (xy 99.316286 -241.50681)
			(xy 99.565964 -241.50681) (xy 99.565964 -241.455394) (xy 99.574007 -241.404612) (xy 99.589895 -241.355713)
			(xy 99.613238 -241.309901) (xy 99.643459 -241.268305) (xy 99.679815 -241.231949) (xy 99.721411 -241.201728)
			(xy 99.767223 -241.178385) (xy 99.816122 -241.162497) (xy 99.866904 -241.154454) (xy 99.91832 -241.154454)
			(xy 99.969102 -241.162497) (xy 100.018001 -241.178385) (xy 100.063813 -241.201728) (xy 100.105409 -241.231949)
			(xy 100.141765 -241.268305) (xy 100.171986 -241.309901) (xy 100.195329 -241.355713) (xy 100.211217 -241.404612)
			(xy 100.21926 -241.455394) (xy 100.219764 -241.481102) (xy 100.21926 -241.50681) (xy 100.219111 -241.507751)
			(xy 100.477056 -241.507751) (xy 100.477056 -241.454453) (xy 100.484999 -241.401749) (xy 100.500709 -241.350819)
			(xy 100.523835 -241.302798) (xy 100.553859 -241.258761) (xy 100.590111 -241.21969) (xy 100.631782 -241.186459)
			(xy 100.67794 -241.15981) (xy 100.727554 -241.140338) (xy 100.779516 -241.128478) (xy 100.832666 -241.124495)
			(xy 100.885816 -241.128478) (xy 100.937778 -241.140338) (xy 100.987392 -241.15981) (xy 101.03355 -241.186459)
			(xy 101.075221 -241.21969) (xy 101.111473 -241.258761) (xy 101.141497 -241.302798) (xy 101.164623 -241.350819)
			(xy 101.180333 -241.401749) (xy 101.188276 -241.454453) (xy 101.188774 -241.481102) (xy 101.188276 -241.507751)
			(xy 101.180333 -241.560455) (xy 101.164623 -241.611385) (xy 101.141497 -241.659406) (xy 101.111473 -241.703443)
			(xy 101.075221 -241.742514) (xy 101.03355 -241.775745) (xy 100.987392 -241.802394) (xy 100.937778 -241.821866)
			(xy 100.885816 -241.833726) (xy 100.832666 -241.83771) (xy 100.779516 -241.833726) (xy 100.727554 -241.821866)
			(xy 100.67794 -241.802394) (xy 100.631782 -241.775745) (xy 100.590111 -241.742514) (xy 100.553859 -241.703443)
			(xy 100.523835 -241.659406) (xy 100.500709 -241.611385) (xy 100.484999 -241.560455) (xy 100.477056 -241.507751)
			(xy 100.219111 -241.507751) (xy 100.211217 -241.557592) (xy 100.195329 -241.606491) (xy 100.171986 -241.652303)
			(xy 100.141765 -241.693899) (xy 100.105409 -241.730255) (xy 100.063813 -241.760476) (xy 100.018001 -241.783819)
			(xy 99.969102 -241.799707) (xy 99.91832 -241.80775) (xy 99.866904 -241.80775) (xy 99.816122 -241.799707)
			(xy 99.767223 -241.783819) (xy 99.721411 -241.760476) (xy 99.679815 -241.730255) (xy 99.643459 -241.693899)
			(xy 99.613238 -241.652303) (xy 99.589895 -241.606491) (xy 99.574007 -241.557592) (xy 99.565964 -241.50681)
			(xy 99.316286 -241.50681) (xy 99.316286 -241.83721) (xy 99.316694 -241.850618) (xy 99.323679 -241.876508)
			(xy 99.337165 -241.899686) (xy 99.356221 -241.918553) (xy 99.379532 -241.931808) (xy 99.405491 -241.938535)
			(xy 99.418902 -241.93881) (xy 99.422966 -241.93881) (xy 99.449617 -241.939281) (xy 99.502326 -241.947221)
			(xy 99.553262 -241.962928) (xy 99.601287 -241.986052) (xy 99.64533 -242.016076) (xy 99.684406 -242.052329)
			(xy 99.717641 -242.094001) (xy 99.744294 -242.140162) (xy 99.763769 -242.18978) (xy 99.77563 -242.241746)
			(xy 99.779614 -242.2949) (xy 99.777615 -242.321567) (xy 100.007156 -242.321567) (xy 100.007156 -242.268269)
			(xy 100.015099 -242.215565) (xy 100.030809 -242.164635) (xy 100.053935 -242.116614) (xy 100.083959 -242.072577)
			(xy 100.120211 -242.033506) (xy 100.161882 -242.000275) (xy 100.20804 -241.973626) (xy 100.257654 -241.954154)
			(xy 100.309616 -241.942294) (xy 100.362766 -241.938311) (xy 100.415916 -241.942294) (xy 100.467878 -241.954154)
			(xy 100.517492 -241.973626) (xy 100.56365 -242.000275) (xy 100.605321 -242.033506) (xy 100.641573 -242.072577)
			(xy 100.671597 -242.116614) (xy 100.694723 -242.164635) (xy 100.710433 -242.215565) (xy 100.718376 -242.268269)
			(xy 100.718874 -242.294918) (xy 100.718376 -242.321567) (xy 100.710433 -242.374271) (xy 100.694723 -242.425201)
			(xy 100.671597 -242.473222) (xy 100.641573 -242.517259) (xy 100.605321 -242.55633) (xy 100.56365 -242.589561)
			(xy 100.517492 -242.61621) (xy 100.467878 -242.635682) (xy 100.415916 -242.647542) (xy 100.362766 -242.651526)
			(xy 100.309616 -242.647542) (xy 100.257654 -242.635682) (xy 100.20804 -242.61621) (xy 100.161882 -242.589561)
			(xy 100.120211 -242.55633) (xy 100.083959 -242.517259) (xy 100.053935 -242.473222) (xy 100.030809 -242.425201)
			(xy 100.015099 -242.374271) (xy 100.007156 -242.321567) (xy 99.777615 -242.321567) (xy 99.77563 -242.348054)
			(xy 99.763769 -242.40002) (xy 99.744294 -242.449638) (xy 99.717641 -242.495799) (xy 99.684406 -242.537471)
			(xy 99.64533 -242.573724) (xy 99.601287 -242.603748) (xy 99.553262 -242.626872) (xy 99.502326 -242.642579)
			(xy 99.449617 -242.650519) (xy 99.422966 -242.651026) (xy 99.418902 -242.651026) (xy 99.405492 -242.651301)
			(xy 99.379537 -242.658028) (xy 99.35623 -242.671284) (xy 99.33718 -242.690152) (xy 99.323701 -242.71333)
			(xy 99.316725 -242.73922) (xy 99.316286 -242.752626) (xy 99.316286 -243.134696) (xy 99.565964 -243.134696)
			(xy 99.565964 -243.08328) (xy 99.574007 -243.032498) (xy 99.589895 -242.983599) (xy 99.613238 -242.937787)
			(xy 99.643459 -242.896191) (xy 99.679815 -242.859835) (xy 99.721411 -242.829614) (xy 99.767223 -242.806271)
			(xy 99.816122 -242.790383) (xy 99.866904 -242.78234) (xy 99.91832 -242.78234) (xy 99.969102 -242.790383)
			(xy 100.018001 -242.806271) (xy 100.063813 -242.829614) (xy 100.105409 -242.859835) (xy 100.141765 -242.896191)
			(xy 100.171986 -242.937787) (xy 100.195329 -242.983599) (xy 100.211217 -243.032498) (xy 100.21926 -243.08328)
			(xy 100.219764 -243.108988) (xy 100.21926 -243.134696) (xy 100.219111 -243.135637) (xy 100.476802 -243.135637)
			(xy 100.476802 -243.082339) (xy 100.484745 -243.029635) (xy 100.500455 -242.978705) (xy 100.523581 -242.930684)
			(xy 100.553605 -242.886647) (xy 100.589857 -242.847576) (xy 100.631528 -242.814345) (xy 100.677686 -242.787696)
			(xy 100.7273 -242.768224) (xy 100.779262 -242.756364) (xy 100.832412 -242.752381) (xy 100.885562 -242.756364)
			(xy 100.937524 -242.768224) (xy 100.987138 -242.787696) (xy 101.033296 -242.814345) (xy 101.074967 -242.847576)
			(xy 101.111219 -242.886647) (xy 101.141243 -242.930684) (xy 101.164369 -242.978705) (xy 101.180079 -243.029635)
			(xy 101.188022 -243.082339) (xy 101.18852 -243.108988) (xy 101.188022 -243.135637) (xy 101.416602 -243.135637)
			(xy 101.416602 -243.082339) (xy 101.424545 -243.029635) (xy 101.440255 -242.978705) (xy 101.463381 -242.930684)
			(xy 101.493405 -242.886647) (xy 101.529657 -242.847576) (xy 101.571328 -242.814345) (xy 101.617486 -242.787696)
			(xy 101.6671 -242.768224) (xy 101.719062 -242.756364) (xy 101.772212 -242.752381) (xy 101.825362 -242.756364)
			(xy 101.877324 -242.768224) (xy 101.926938 -242.787696) (xy 101.973096 -242.814345) (xy 102.014767 -242.847576)
			(xy 102.051019 -242.886647) (xy 102.081043 -242.930684) (xy 102.104169 -242.978705) (xy 102.119879 -243.029635)
			(xy 102.127822 -243.082339) (xy 102.12832 -243.108988) (xy 102.127822 -243.135637) (xy 102.119879 -243.188341)
			(xy 102.104169 -243.239271) (xy 102.081043 -243.287292) (xy 102.051019 -243.331329) (xy 102.014767 -243.3704)
			(xy 101.973096 -243.403631) (xy 101.926938 -243.43028) (xy 101.877324 -243.449752) (xy 101.825362 -243.461612)
			(xy 101.772212 -243.465596) (xy 101.719062 -243.461612) (xy 101.6671 -243.449752) (xy 101.617486 -243.43028)
			(xy 101.571328 -243.403631) (xy 101.529657 -243.3704) (xy 101.493405 -243.331329) (xy 101.463381 -243.287292)
			(xy 101.440255 -243.239271) (xy 101.424545 -243.188341) (xy 101.416602 -243.135637) (xy 101.188022 -243.135637)
			(xy 101.180079 -243.188341) (xy 101.164369 -243.239271) (xy 101.141243 -243.287292) (xy 101.111219 -243.331329)
			(xy 101.074967 -243.3704) (xy 101.033296 -243.403631) (xy 100.987138 -243.43028) (xy 100.937524 -243.449752)
			(xy 100.885562 -243.461612) (xy 100.832412 -243.465596) (xy 100.779262 -243.461612) (xy 100.7273 -243.449752)
			(xy 100.677686 -243.43028) (xy 100.631528 -243.403631) (xy 100.589857 -243.3704) (xy 100.553605 -243.331329)
			(xy 100.523581 -243.287292) (xy 100.500455 -243.239271) (xy 100.484745 -243.188341) (xy 100.476802 -243.135637)
			(xy 100.219111 -243.135637) (xy 100.211217 -243.185478) (xy 100.195329 -243.234377) (xy 100.171986 -243.280189)
			(xy 100.141765 -243.321785) (xy 100.105409 -243.358141) (xy 100.063813 -243.388362) (xy 100.018001 -243.411705)
			(xy 99.969102 -243.427593) (xy 99.91832 -243.435636) (xy 99.866904 -243.435636) (xy 99.816122 -243.427593)
			(xy 99.767223 -243.411705) (xy 99.721411 -243.388362) (xy 99.679815 -243.358141) (xy 99.643459 -243.321785)
			(xy 99.613238 -243.280189) (xy 99.589895 -243.234377) (xy 99.574007 -243.185478) (xy 99.565964 -243.134696)
			(xy 99.316286 -243.134696) (xy 99.316286 -243.465096) (xy 99.316692 -243.478505) (xy 99.323675 -243.504398)
			(xy 99.33716 -243.52758) (xy 99.356216 -243.54645) (xy 99.379529 -243.559706) (xy 99.40549 -243.566434)
			(xy 99.418902 -243.566696) (xy 99.422966 -243.566696) (xy 99.449619 -243.567167) (xy 99.502329 -243.575107)
			(xy 99.553267 -243.590815) (xy 99.601294 -243.61394) (xy 99.645339 -243.643965) (xy 99.684416 -243.680219)
			(xy 99.717653 -243.721894) (xy 99.744307 -243.768056) (xy 99.763782 -243.817676) (xy 99.775644 -243.869644)
			(xy 99.779628 -243.9228) (xy 99.777701 -243.948512) (xy 100.036118 -243.948512) (xy 100.036118 -243.897096)
			(xy 100.044161 -243.846314) (xy 100.060049 -243.797415) (xy 100.083392 -243.751603) (xy 100.113613 -243.710007)
			(xy 100.149969 -243.673651) (xy 100.191565 -243.64343) (xy 100.237377 -243.620087) (xy 100.286276 -243.604199)
			(xy 100.337058 -243.596156) (xy 100.388474 -243.596156) (xy 100.439256 -243.604199) (xy 100.488155 -243.620087)
			(xy 100.533967 -243.64343) (xy 100.575563 -243.673651) (xy 100.611919 -243.710007) (xy 100.64214 -243.751603)
			(xy 100.665483 -243.797415) (xy 100.681371 -243.846314) (xy 100.689414 -243.897096) (xy 100.689918 -243.922804)
			(xy 100.689414 -243.948512) (xy 100.689265 -243.949453) (xy 100.946702 -243.949453) (xy 100.946702 -243.896155)
			(xy 100.954645 -243.843451) (xy 100.970355 -243.792521) (xy 100.993481 -243.7445) (xy 101.023505 -243.700463)
			(xy 101.059757 -243.661392) (xy 101.101428 -243.628161) (xy 101.147586 -243.601512) (xy 101.1972 -243.58204)
			(xy 101.249162 -243.57018) (xy 101.302312 -243.566197) (xy 101.355462 -243.57018) (xy 101.407424 -243.58204)
			(xy 101.457038 -243.601512) (xy 101.503196 -243.628161) (xy 101.544867 -243.661392) (xy 101.581119 -243.700463)
			(xy 101.611143 -243.7445) (xy 101.634269 -243.792521) (xy 101.649979 -243.843451) (xy 101.657922 -243.896155)
			(xy 101.65842 -243.922804) (xy 101.657922 -243.949453) (xy 101.886756 -243.949453) (xy 101.886756 -243.896155)
			(xy 101.894699 -243.843451) (xy 101.910409 -243.792521) (xy 101.933535 -243.7445) (xy 101.963559 -243.700463)
			(xy 101.999811 -243.661392) (xy 102.041482 -243.628161) (xy 102.08764 -243.601512) (xy 102.137254 -243.58204)
			(xy 102.189216 -243.57018) (xy 102.242366 -243.566197) (xy 102.295516 -243.57018) (xy 102.347478 -243.58204)
			(xy 102.397092 -243.601512) (xy 102.44325 -243.628161) (xy 102.484921 -243.661392) (xy 102.521173 -243.700463)
			(xy 102.551197 -243.7445) (xy 102.574323 -243.792521) (xy 102.590033 -243.843451) (xy 102.597976 -243.896155)
			(xy 102.598474 -243.922804) (xy 102.597976 -243.949453) (xy 102.590033 -244.002157) (xy 102.574323 -244.053087)
			(xy 102.551197 -244.101108) (xy 102.521173 -244.145145) (xy 102.484921 -244.184216) (xy 102.44325 -244.217447)
			(xy 102.397092 -244.244096) (xy 102.347478 -244.263568) (xy 102.295516 -244.275428) (xy 102.242366 -244.279412)
			(xy 102.189216 -244.275428) (xy 102.137254 -244.263568) (xy 102.08764 -244.244096) (xy 102.041482 -244.217447)
			(xy 101.999811 -244.184216) (xy 101.963559 -244.145145) (xy 101.933535 -244.101108) (xy 101.910409 -244.053087)
			(xy 101.894699 -244.002157) (xy 101.886756 -243.949453) (xy 101.657922 -243.949453) (xy 101.649979 -244.002157)
			(xy 101.634269 -244.053087) (xy 101.611143 -244.101108) (xy 101.581119 -244.145145) (xy 101.544867 -244.184216)
			(xy 101.503196 -244.217447) (xy 101.457038 -244.244096) (xy 101.407424 -244.263568) (xy 101.355462 -244.275428)
			(xy 101.302312 -244.279412) (xy 101.249162 -244.275428) (xy 101.1972 -244.263568) (xy 101.147586 -244.244096)
			(xy 101.101428 -244.217447) (xy 101.059757 -244.184216) (xy 101.023505 -244.145145) (xy 100.993481 -244.101108)
			(xy 100.970355 -244.053087) (xy 100.954645 -244.002157) (xy 100.946702 -243.949453) (xy 100.689265 -243.949453)
			(xy 100.681371 -243.999294) (xy 100.665483 -244.048193) (xy 100.64214 -244.094005) (xy 100.611919 -244.135601)
			(xy 100.575563 -244.171957) (xy 100.533967 -244.202178) (xy 100.488155 -244.225521) (xy 100.439256 -244.241409)
			(xy 100.388474 -244.249452) (xy 100.337058 -244.249452) (xy 100.286276 -244.241409) (xy 100.237377 -244.225521)
			(xy 100.191565 -244.202178) (xy 100.149969 -244.171957) (xy 100.113613 -244.135601) (xy 100.083392 -244.094005)
			(xy 100.060049 -244.048193) (xy 100.044161 -243.999294) (xy 100.036118 -243.948512) (xy 99.777701 -243.948512)
			(xy 99.775644 -243.975956) (xy 99.763782 -244.027924) (xy 99.744307 -244.077544) (xy 99.717653 -244.123706)
			(xy 99.684416 -244.165381) (xy 99.645339 -244.201635) (xy 99.601294 -244.23166) (xy 99.553267 -244.254785)
			(xy 99.502329 -244.270493) (xy 99.449619 -244.278433) (xy 99.422966 -244.278912) (xy 99.418902 -244.278912)
			(xy 99.405492 -244.279187) (xy 99.379535 -244.285914) (xy 99.356226 -244.299169) (xy 99.337174 -244.318037)
			(xy 99.323692 -244.341215) (xy 99.316712 -244.367105) (xy 99.316286 -244.380512) (xy 99.316286 -244.762328)
			(xy 99.565964 -244.762328) (xy 99.565964 -244.710912) (xy 99.574007 -244.66013) (xy 99.589895 -244.611231)
			(xy 99.613238 -244.565419) (xy 99.643459 -244.523823) (xy 99.679815 -244.487467) (xy 99.721411 -244.457246)
			(xy 99.767223 -244.433903) (xy 99.816122 -244.418015) (xy 99.866904 -244.409972) (xy 99.91832 -244.409972)
			(xy 99.969102 -244.418015) (xy 100.018001 -244.433903) (xy 100.063813 -244.457246) (xy 100.105409 -244.487467)
			(xy 100.141765 -244.523823) (xy 100.171986 -244.565419) (xy 100.195329 -244.611231) (xy 100.211217 -244.66013)
			(xy 100.21926 -244.710912) (xy 100.219764 -244.73662) (xy 100.21926 -244.762328) (xy 100.505764 -244.762328)
			(xy 100.505764 -244.710912) (xy 100.513807 -244.66013) (xy 100.529695 -244.611231) (xy 100.553038 -244.565419)
			(xy 100.583259 -244.523823) (xy 100.619615 -244.487467) (xy 100.661211 -244.457246) (xy 100.707023 -244.433903)
			(xy 100.755922 -244.418015) (xy 100.806704 -244.409972) (xy 100.85812 -244.409972) (xy 100.908902 -244.418015)
			(xy 100.957801 -244.433903) (xy 101.003613 -244.457246) (xy 101.045209 -244.487467) (xy 101.081565 -244.523823)
			(xy 101.111786 -244.565419) (xy 101.135129 -244.611231) (xy 101.151017 -244.66013) (xy 101.15906 -244.710912)
			(xy 101.159564 -244.73662) (xy 101.15906 -244.762328) (xy 101.158911 -244.763269) (xy 101.416602 -244.763269)
			(xy 101.416602 -244.709971) (xy 101.424545 -244.657267) (xy 101.440255 -244.606337) (xy 101.463381 -244.558316)
			(xy 101.493405 -244.514279) (xy 101.529657 -244.475208) (xy 101.571328 -244.441977) (xy 101.617486 -244.415328)
			(xy 101.6671 -244.395856) (xy 101.719062 -244.383996) (xy 101.772212 -244.380013) (xy 101.825362 -244.383996)
			(xy 101.877324 -244.395856) (xy 101.926938 -244.415328) (xy 101.973096 -244.441977) (xy 102.014767 -244.475208)
			(xy 102.051019 -244.514279) (xy 102.081043 -244.558316) (xy 102.104169 -244.606337) (xy 102.119879 -244.657267)
			(xy 102.127822 -244.709971) (xy 102.12832 -244.73662) (xy 102.127822 -244.763269) (xy 102.119879 -244.815973)
			(xy 102.104169 -244.866903) (xy 102.081043 -244.914924) (xy 102.051019 -244.958961) (xy 102.014767 -244.998032)
			(xy 101.973096 -245.031263) (xy 101.926938 -245.057912) (xy 101.877324 -245.077384) (xy 101.825362 -245.089244)
			(xy 101.772212 -245.093228) (xy 101.719062 -245.089244) (xy 101.6671 -245.077384) (xy 101.617486 -245.057912)
			(xy 101.571328 -245.031263) (xy 101.529657 -244.998032) (xy 101.493405 -244.958961) (xy 101.463381 -244.914924)
			(xy 101.440255 -244.866903) (xy 101.424545 -244.815973) (xy 101.416602 -244.763269) (xy 101.158911 -244.763269)
			(xy 101.151017 -244.81311) (xy 101.135129 -244.862009) (xy 101.111786 -244.907821) (xy 101.081565 -244.949417)
			(xy 101.045209 -244.985773) (xy 101.003613 -245.015994) (xy 100.957801 -245.039337) (xy 100.908902 -245.055225)
			(xy 100.85812 -245.063268) (xy 100.806704 -245.063268) (xy 100.755922 -245.055225) (xy 100.707023 -245.039337)
			(xy 100.661211 -245.015994) (xy 100.619615 -244.985773) (xy 100.583259 -244.949417) (xy 100.553038 -244.907821)
			(xy 100.529695 -244.862009) (xy 100.513807 -244.81311) (xy 100.505764 -244.762328) (xy 100.21926 -244.762328)
			(xy 100.211217 -244.81311) (xy 100.195329 -244.862009) (xy 100.171986 -244.907821) (xy 100.141765 -244.949417)
			(xy 100.105409 -244.985773) (xy 100.063813 -245.015994) (xy 100.018001 -245.039337) (xy 99.969102 -245.055225)
			(xy 99.91832 -245.063268) (xy 99.866904 -245.063268) (xy 99.816122 -245.055225) (xy 99.767223 -245.039337)
			(xy 99.721411 -245.015994) (xy 99.679815 -244.985773) (xy 99.643459 -244.949417) (xy 99.613238 -244.907821)
			(xy 99.589895 -244.862009) (xy 99.574007 -244.81311) (xy 99.565964 -244.762328) (xy 99.316286 -244.762328)
			(xy 99.316286 -245.092982) (xy 99.316691 -245.106392) (xy 99.323671 -245.132289) (xy 99.337155 -245.155473)
			(xy 99.356212 -245.174346) (xy 99.379526 -245.187605) (xy 99.405489 -245.194334) (xy 99.418902 -245.194582)
			(xy 99.422966 -245.194582) (xy 99.44962 -245.195053) (xy 99.502332 -245.202993) (xy 99.553272 -245.218702)
			(xy 99.601301 -245.241828) (xy 99.645347 -245.271854) (xy 99.684426 -245.30811) (xy 99.717664 -245.349786)
			(xy 99.744319 -245.39595) (xy 99.763795 -245.445572) (xy 99.775658 -245.497542) (xy 99.779642 -245.5507)
			(xy 99.777716 -245.576398) (xy 100.036118 -245.576398) (xy 100.036118 -245.524982) (xy 100.044161 -245.4742)
			(xy 100.060049 -245.425301) (xy 100.083392 -245.379489) (xy 100.113613 -245.337893) (xy 100.149969 -245.301537)
			(xy 100.191565 -245.271316) (xy 100.237377 -245.247973) (xy 100.286276 -245.232085) (xy 100.337058 -245.224042)
			(xy 100.388474 -245.224042) (xy 100.439256 -245.232085) (xy 100.488155 -245.247973) (xy 100.533967 -245.271316)
			(xy 100.575563 -245.301537) (xy 100.611919 -245.337893) (xy 100.64214 -245.379489) (xy 100.665483 -245.425301)
			(xy 100.681371 -245.4742) (xy 100.689414 -245.524982) (xy 100.689918 -245.55069) (xy 100.689414 -245.576398)
			(xy 100.689265 -245.577339) (xy 100.946956 -245.577339) (xy 100.946956 -245.524041) (xy 100.954899 -245.471337)
			(xy 100.970609 -245.420407) (xy 100.993735 -245.372386) (xy 101.023759 -245.328349) (xy 101.060011 -245.289278)
			(xy 101.101682 -245.256047) (xy 101.14784 -245.229398) (xy 101.197454 -245.209926) (xy 101.249416 -245.198066)
			(xy 101.302566 -245.194083) (xy 101.355716 -245.198066) (xy 101.407678 -245.209926) (xy 101.457292 -245.229398)
			(xy 101.50345 -245.256047) (xy 101.545121 -245.289278) (xy 101.581373 -245.328349) (xy 101.611397 -245.372386)
			(xy 101.634523 -245.420407) (xy 101.650233 -245.471337) (xy 101.658176 -245.524041) (xy 101.658674 -245.55069)
			(xy 101.658176 -245.577339) (xy 101.650233 -245.630043) (xy 101.634523 -245.680973) (xy 101.611397 -245.728994)
			(xy 101.581373 -245.773031) (xy 101.545121 -245.812102) (xy 101.50345 -245.845333) (xy 101.457292 -245.871982)
			(xy 101.407678 -245.891454) (xy 101.355716 -245.903314) (xy 101.302566 -245.907298) (xy 101.249416 -245.903314)
			(xy 101.197454 -245.891454) (xy 101.14784 -245.871982) (xy 101.101682 -245.845333) (xy 101.060011 -245.812102)
			(xy 101.023759 -245.773031) (xy 100.993735 -245.728994) (xy 100.970609 -245.680973) (xy 100.954899 -245.630043)
			(xy 100.946956 -245.577339) (xy 100.689265 -245.577339) (xy 100.681371 -245.62718) (xy 100.665483 -245.676079)
			(xy 100.64214 -245.721891) (xy 100.611919 -245.763487) (xy 100.575563 -245.799843) (xy 100.533967 -245.830064)
			(xy 100.488155 -245.853407) (xy 100.439256 -245.869295) (xy 100.388474 -245.877338) (xy 100.337058 -245.877338)
			(xy 100.286276 -245.869295) (xy 100.237377 -245.853407) (xy 100.191565 -245.830064) (xy 100.149969 -245.799843)
			(xy 100.113613 -245.763487) (xy 100.083392 -245.721891) (xy 100.060049 -245.676079) (xy 100.044161 -245.62718)
			(xy 100.036118 -245.576398) (xy 99.777716 -245.576398) (xy 99.775658 -245.603858) (xy 99.763795 -245.655828)
			(xy 99.744319 -245.70545) (xy 99.717664 -245.751614) (xy 99.684426 -245.79329) (xy 99.645347 -245.829546)
			(xy 99.601301 -245.859572) (xy 99.553272 -245.882698) (xy 99.502332 -245.898407) (xy 99.44962 -245.906347)
			(xy 99.422966 -245.906798) (xy 99.418902 -245.906798) (xy 99.405491 -245.907073) (xy 99.379533 -245.9138)
			(xy 99.356223 -245.927054) (xy 99.337168 -245.945922) (xy 99.323683 -245.9691) (xy 99.3167 -245.99499)
			(xy 99.316286 -246.008398) (xy 99.316286 -246.390214) (xy 99.565964 -246.390214) (xy 99.565964 -246.338798)
			(xy 99.574007 -246.288016) (xy 99.589895 -246.239117) (xy 99.613238 -246.193305) (xy 99.643459 -246.151709)
			(xy 99.679815 -246.115353) (xy 99.721411 -246.085132) (xy 99.767223 -246.061789) (xy 99.816122 -246.045901)
			(xy 99.866904 -246.037858) (xy 99.91832 -246.037858) (xy 99.969102 -246.045901) (xy 100.018001 -246.061789)
			(xy 100.063813 -246.085132) (xy 100.105409 -246.115353) (xy 100.141765 -246.151709) (xy 100.171986 -246.193305)
			(xy 100.195329 -246.239117) (xy 100.211217 -246.288016) (xy 100.21926 -246.338798) (xy 100.219764 -246.364506)
			(xy 100.21926 -246.390214) (xy 100.219111 -246.391155) (xy 100.477056 -246.391155) (xy 100.477056 -246.337857)
			(xy 100.484999 -246.285153) (xy 100.500709 -246.234223) (xy 100.523835 -246.186202) (xy 100.553859 -246.142165)
			(xy 100.590111 -246.103094) (xy 100.631782 -246.069863) (xy 100.67794 -246.043214) (xy 100.727554 -246.023742)
			(xy 100.779516 -246.011882) (xy 100.832666 -246.007899) (xy 100.885816 -246.011882) (xy 100.937778 -246.023742)
			(xy 100.987392 -246.043214) (xy 101.03355 -246.069863) (xy 101.075221 -246.103094) (xy 101.111473 -246.142165)
			(xy 101.141497 -246.186202) (xy 101.164623 -246.234223) (xy 101.180333 -246.285153) (xy 101.188276 -246.337857)
			(xy 101.188774 -246.364506) (xy 101.188276 -246.391155) (xy 101.416602 -246.391155) (xy 101.416602 -246.337857)
			(xy 101.424545 -246.285153) (xy 101.440255 -246.234223) (xy 101.463381 -246.186202) (xy 101.493405 -246.142165)
			(xy 101.529657 -246.103094) (xy 101.571328 -246.069863) (xy 101.617486 -246.043214) (xy 101.6671 -246.023742)
			(xy 101.719062 -246.011882) (xy 101.772212 -246.007899) (xy 101.825362 -246.011882) (xy 101.877324 -246.023742)
			(xy 101.926938 -246.043214) (xy 101.973096 -246.069863) (xy 102.014767 -246.103094) (xy 102.051019 -246.142165)
			(xy 102.081043 -246.186202) (xy 102.104169 -246.234223) (xy 102.119879 -246.285153) (xy 102.127822 -246.337857)
			(xy 102.12832 -246.364506) (xy 102.127822 -246.391155) (xy 102.119879 -246.443859) (xy 102.104169 -246.494789)
			(xy 102.081043 -246.54281) (xy 102.051019 -246.586847) (xy 102.014767 -246.625918) (xy 101.973096 -246.659149)
			(xy 101.926938 -246.685798) (xy 101.877324 -246.70527) (xy 101.825362 -246.71713) (xy 101.772212 -246.721114)
			(xy 101.719062 -246.71713) (xy 101.6671 -246.70527) (xy 101.617486 -246.685798) (xy 101.571328 -246.659149)
			(xy 101.529657 -246.625918) (xy 101.493405 -246.586847) (xy 101.463381 -246.54281) (xy 101.440255 -246.494789)
			(xy 101.424545 -246.443859) (xy 101.416602 -246.391155) (xy 101.188276 -246.391155) (xy 101.180333 -246.443859)
			(xy 101.164623 -246.494789) (xy 101.141497 -246.54281) (xy 101.111473 -246.586847) (xy 101.075221 -246.625918)
			(xy 101.03355 -246.659149) (xy 100.987392 -246.685798) (xy 100.937778 -246.70527) (xy 100.885816 -246.71713)
			(xy 100.832666 -246.721114) (xy 100.779516 -246.71713) (xy 100.727554 -246.70527) (xy 100.67794 -246.685798)
			(xy 100.631782 -246.659149) (xy 100.590111 -246.625918) (xy 100.553859 -246.586847) (xy 100.523835 -246.54281)
			(xy 100.500709 -246.494789) (xy 100.484999 -246.443859) (xy 100.477056 -246.391155) (xy 100.219111 -246.391155)
			(xy 100.211217 -246.440996) (xy 100.195329 -246.489895) (xy 100.171986 -246.535707) (xy 100.141765 -246.577303)
			(xy 100.105409 -246.613659) (xy 100.063813 -246.64388) (xy 100.018001 -246.667223) (xy 99.969102 -246.683111)
			(xy 99.91832 -246.691154) (xy 99.866904 -246.691154) (xy 99.816122 -246.683111) (xy 99.767223 -246.667223)
			(xy 99.721411 -246.64388) (xy 99.679815 -246.613659) (xy 99.643459 -246.577303) (xy 99.613238 -246.535707)
			(xy 99.589895 -246.489895) (xy 99.574007 -246.440996) (xy 99.565964 -246.390214) (xy 99.316286 -246.390214)
			(xy 99.316286 -246.720614) (xy 99.316695 -246.734022) (xy 99.32368 -246.759911) (xy 99.337166 -246.783088)
			(xy 99.356222 -246.801954) (xy 99.379533 -246.815208) (xy 99.405491 -246.821935) (xy 99.418902 -246.822214)
			(xy 99.422966 -246.822214) (xy 99.449617 -246.822685) (xy 99.502325 -246.830624) (xy 99.55326 -246.846332)
			(xy 99.601285 -246.869455) (xy 99.645327 -246.899479) (xy 99.684403 -246.935732) (xy 99.717638 -246.977404)
			(xy 99.74429 -247.023564) (xy 99.763765 -247.073181) (xy 99.775626 -247.125147) (xy 99.77961 -247.1783)
			(xy 99.777611 -247.204971) (xy 100.007156 -247.204971) (xy 100.007156 -247.151673) (xy 100.015099 -247.098969)
			(xy 100.030809 -247.048039) (xy 100.053935 -247.000018) (xy 100.083959 -246.955981) (xy 100.120211 -246.91691)
			(xy 100.161882 -246.883679) (xy 100.20804 -246.85703) (xy 100.257654 -246.837558) (xy 100.309616 -246.825698)
			(xy 100.362766 -246.821715) (xy 100.415916 -246.825698) (xy 100.467878 -246.837558) (xy 100.517492 -246.85703)
			(xy 100.56365 -246.883679) (xy 100.605321 -246.91691) (xy 100.641573 -246.955981) (xy 100.671597 -247.000018)
			(xy 100.694723 -247.048039) (xy 100.710433 -247.098969) (xy 100.718376 -247.151673) (xy 100.718874 -247.178322)
			(xy 100.718394 -247.20403) (xy 100.975918 -247.20403) (xy 100.975918 -247.152614) (xy 100.983961 -247.101832)
			(xy 100.999849 -247.052933) (xy 101.023192 -247.007121) (xy 101.053413 -246.965525) (xy 101.089769 -246.929169)
			(xy 101.131365 -246.898948) (xy 101.177177 -246.875605) (xy 101.226076 -246.859717) (xy 101.276858 -246.851674)
			(xy 101.328274 -246.851674) (xy 101.379056 -246.859717) (xy 101.427955 -246.875605) (xy 101.473767 -246.898948)
			(xy 101.515363 -246.929169) (xy 101.551719 -246.965525) (xy 101.58194 -247.007121) (xy 101.605283 -247.052933)
			(xy 101.621171 -247.101832) (xy 101.629214 -247.152614) (xy 101.629718 -247.178322) (xy 101.629214 -247.20403)
			(xy 101.915718 -247.20403) (xy 101.915718 -247.152614) (xy 101.923761 -247.101832) (xy 101.939649 -247.052933)
			(xy 101.962992 -247.007121) (xy 101.993213 -246.965525) (xy 102.029569 -246.929169) (xy 102.071165 -246.898948)
			(xy 102.116977 -246.875605) (xy 102.165876 -246.859717) (xy 102.216658 -246.851674) (xy 102.268074 -246.851674)
			(xy 102.318856 -246.859717) (xy 102.367755 -246.875605) (xy 102.413567 -246.898948) (xy 102.455163 -246.929169)
			(xy 102.491519 -246.965525) (xy 102.52174 -247.007121) (xy 102.545083 -247.052933) (xy 102.560971 -247.101832)
			(xy 102.569014 -247.152614) (xy 102.569518 -247.178322) (xy 102.569014 -247.20403) (xy 102.560971 -247.254812)
			(xy 102.545083 -247.303711) (xy 102.52174 -247.349523) (xy 102.491519 -247.391119) (xy 102.455163 -247.427475)
			(xy 102.413567 -247.457696) (xy 102.367755 -247.481039) (xy 102.318856 -247.496927) (xy 102.268074 -247.50497)
			(xy 102.216658 -247.50497) (xy 102.165876 -247.496927) (xy 102.116977 -247.481039) (xy 102.071165 -247.457696)
			(xy 102.029569 -247.427475) (xy 101.993213 -247.391119) (xy 101.962992 -247.349523) (xy 101.939649 -247.303711)
			(xy 101.923761 -247.254812) (xy 101.915718 -247.20403) (xy 101.629214 -247.20403) (xy 101.621171 -247.254812)
			(xy 101.605283 -247.303711) (xy 101.58194 -247.349523) (xy 101.551719 -247.391119) (xy 101.515363 -247.427475)
			(xy 101.473767 -247.457696) (xy 101.427955 -247.481039) (xy 101.379056 -247.496927) (xy 101.328274 -247.50497)
			(xy 101.276858 -247.50497) (xy 101.226076 -247.496927) (xy 101.177177 -247.481039) (xy 101.131365 -247.457696)
			(xy 101.089769 -247.427475) (xy 101.053413 -247.391119) (xy 101.023192 -247.349523) (xy 100.999849 -247.303711)
			(xy 100.983961 -247.254812) (xy 100.975918 -247.20403) (xy 100.718394 -247.20403) (xy 100.718376 -247.204971)
			(xy 100.710433 -247.257675) (xy 100.694723 -247.308605) (xy 100.671597 -247.356626) (xy 100.641573 -247.400663)
			(xy 100.605321 -247.439734) (xy 100.56365 -247.472965) (xy 100.517492 -247.499614) (xy 100.467878 -247.519086)
			(xy 100.415916 -247.530946) (xy 100.362766 -247.53493) (xy 100.309616 -247.530946) (xy 100.257654 -247.519086)
			(xy 100.20804 -247.499614) (xy 100.161882 -247.472965) (xy 100.120211 -247.439734) (xy 100.083959 -247.400663)
			(xy 100.053935 -247.356626) (xy 100.030809 -247.308605) (xy 100.015099 -247.257675) (xy 100.007156 -247.204971)
			(xy 99.777611 -247.204971) (xy 99.775626 -247.231453) (xy 99.763765 -247.283419) (xy 99.74429 -247.333036)
			(xy 99.717638 -247.379196) (xy 99.684403 -247.420868) (xy 99.645327 -247.457121) (xy 99.601285 -247.487145)
			(xy 99.55326 -247.510268) (xy 99.502325 -247.525976) (xy 99.449617 -247.533915) (xy 99.422966 -247.53443)
			(xy 99.418902 -247.53443) (xy 99.405492 -247.534705) (xy 99.379538 -247.541432) (xy 99.356231 -247.554688)
			(xy 99.337182 -247.573556) (xy 99.323704 -247.596735) (xy 99.316728 -247.622624) (xy 99.316286 -247.63603)
			(xy 99.316286 -248.02338) (xy 99.509326 -248.21642) (xy 99.607878 -248.21642)
		)
		(stroke
			(width 0)
			(type solid)
		)
		(fill yes)
		(layer "B.Cu")
		(net "PVCCD_HV_CPU1")
	)
	(gr_poly
		(pts
			(xy 347.547692 -248.15292) (xy 347.542104 -248.141998) (xy 347.530611 -248.118705) (xy 347.514335 -248.069383)
			(xy 347.506066 -248.018107) (xy 347.505528 -247.992138) (xy 347.506032 -247.96643) (xy 347.514075 -247.915648)
			(xy 347.529963 -247.866749) (xy 347.553306 -247.820937) (xy 347.583527 -247.779341) (xy 347.619883 -247.742985)
			(xy 347.661479 -247.712764) (xy 347.707291 -247.689421) (xy 347.75619 -247.673533) (xy 347.806972 -247.66549)
			(xy 347.858388 -247.66549) (xy 347.90917 -247.673533) (xy 347.958069 -247.689421) (xy 348.003881 -247.712764)
			(xy 348.045477 -247.742985) (xy 348.081833 -247.779341) (xy 348.112054 -247.820937) (xy 348.135397 -247.866749)
			(xy 348.151285 -247.915648) (xy 348.159328 -247.96643) (xy 348.159832 -247.992138) (xy 348.159393 -248.01585)
			(xy 348.152508 -248.062772) (xy 348.146116 -248.08561) (xy 348.142678 -248.098678) (xy 348.142058 -248.125682)
			(xy 348.148545 -248.151904) (xy 348.161684 -248.175505) (xy 348.180554 -248.194833) (xy 348.203834 -248.208533)
			(xy 348.229893 -248.215645) (xy 348.243398 -248.216166) (xy 348.331536 -248.216166) (xy 348.344924 -248.215768)
			(xy 348.370782 -248.208813) (xy 348.393936 -248.195364) (xy 348.412789 -248.17635) (xy 348.426041 -248.153083)
			(xy 348.432778 -248.127168) (xy 348.432534 -248.100393) (xy 348.429326 -248.087388) (xy 348.423263 -248.064044)
			(xy 348.416769 -248.016253) (xy 348.416372 -247.992138) (xy 348.41687 -247.965489) (xy 348.424813 -247.912785)
			(xy 348.440523 -247.861855) (xy 348.463649 -247.813834) (xy 348.493673 -247.769797) (xy 348.529925 -247.730726)
			(xy 348.571596 -247.697495) (xy 348.617754 -247.670846) (xy 348.667368 -247.651374) (xy 348.71933 -247.639514)
			(xy 348.77248 -247.635531) (xy 348.82563 -247.639514) (xy 348.877592 -247.651374) (xy 348.927206 -247.670846)
			(xy 348.973364 -247.697495) (xy 349.015035 -247.730726) (xy 349.051287 -247.769797) (xy 349.081311 -247.813834)
			(xy 349.104437 -247.861855) (xy 349.120147 -247.912785) (xy 349.12809 -247.965489) (xy 349.128588 -247.992138)
			(xy 349.128189 -248.016253) (xy 349.121694 -248.064044) (xy 349.115634 -248.087388) (xy 349.112453 -248.100387)
			(xy 349.112259 -248.127141) (xy 349.119019 -248.153026) (xy 349.13227 -248.176268) (xy 349.151103 -248.195271)
			(xy 349.174224 -248.20873) (xy 349.200048 -248.215723) (xy 349.213424 -248.216166) (xy 349.301562 -248.216166)
			(xy 349.31508 -248.215748) (xy 349.341166 -248.208652) (xy 349.36447 -248.194948) (xy 349.383353 -248.1756)
			(xy 349.396486 -248.15197) (xy 349.402946 -248.125718) (xy 349.402278 -248.098692) (xy 349.398844 -248.08561)
			(xy 349.392458 -248.062771) (xy 349.385579 -248.015849) (xy 349.385128 -247.992138) (xy 349.385632 -247.96643)
			(xy 349.393675 -247.915648) (xy 349.409563 -247.866749) (xy 349.432906 -247.820937) (xy 349.463127 -247.779341)
			(xy 349.499483 -247.742985) (xy 349.541079 -247.712764) (xy 349.586891 -247.689421) (xy 349.63579 -247.673533)
			(xy 349.686572 -247.66549) (xy 349.737988 -247.66549) (xy 349.78877 -247.673533) (xy 349.837669 -247.689421)
			(xy 349.883481 -247.712764) (xy 349.925077 -247.742985) (xy 349.961433 -247.779341) (xy 349.991654 -247.820937)
			(xy 350.014997 -247.866749) (xy 350.030885 -247.915648) (xy 350.038928 -247.96643) (xy 350.039432 -247.992138)
			(xy 350.038993 -248.01585) (xy 350.032108 -248.062772) (xy 350.025716 -248.08561) (xy 350.022278 -248.098678)
			(xy 350.021658 -248.125682) (xy 350.028145 -248.151904) (xy 350.041284 -248.175505) (xy 350.060154 -248.194833)
			(xy 350.083434 -248.208533) (xy 350.109493 -248.215645) (xy 350.122998 -248.216166) (xy 352.5901 -248.216166)
			(xy 352.713036 -248.092976) (xy 352.713036 -247.005856) (xy 352.79076 -246.928386) (xy 352.79076 -246.501666)
			(xy 352.66376 -246.374666) (xy 350.46412 -246.374666) (xy 350.28632 -246.196866) (xy 350.28632 -246.008398)
			(xy 350.285918 -245.995031) (xy 350.278978 -245.969214) (xy 350.265574 -245.946084) (xy 350.246625 -245.927226)
			(xy 350.223431 -245.913934) (xy 350.19758 -245.907118) (xy 350.184212 -245.906798) (xy 350.182434 -245.906798)
			(xy 350.155782 -245.906327) (xy 350.103073 -245.898387) (xy 350.052136 -245.88268) (xy 350.004109 -245.859555)
			(xy 349.960065 -245.82953) (xy 349.920989 -245.793276) (xy 349.887752 -245.751603) (xy 349.861099 -245.705441)
			(xy 349.841624 -245.655822) (xy 349.829762 -245.603855) (xy 349.825778 -245.5507) (xy 349.829762 -245.497545)
			(xy 349.841624 -245.445578) (xy 349.861099 -245.395959) (xy 349.887752 -245.349797) (xy 349.920989 -245.308124)
			(xy 349.960065 -245.27187) (xy 350.004109 -245.241845) (xy 350.052136 -245.21872) (xy 350.103073 -245.203013)
			(xy 350.155782 -245.195073) (xy 350.182434 -245.194582) (xy 350.184212 -245.194582) (xy 350.197577 -245.194245)
			(xy 350.223421 -245.18743) (xy 350.246609 -245.174139) (xy 350.265552 -245.155284) (xy 350.27895 -245.132158)
			(xy 350.285884 -245.106346) (xy 350.28632 -245.092982) (xy 350.28632 -244.622066) (xy 350.886014 -244.022372)
			(xy 350.886014 -242.809776) (xy 351.146364 -242.549426) (xy 351.155 -242.549426) (xy 351.162874 -242.541552)
			(xy 351.800414 -242.541552) (xy 352.04146 -242.300506) (xy 352.04146 -241.403886) (xy 351.94494 -241.307366)
			(xy 350.7105 -241.307366) (xy 350.32696 -240.923826) (xy 350.32696 -240.314226) (xy 350.28632 -240.273586)
			(xy 349.594932 -240.273586) (xy 349.580536 -240.274079) (xy 349.552885 -240.282105) (xy 349.528573 -240.29753)
			(xy 349.509532 -240.319128) (xy 349.497275 -240.345181) (xy 349.492776 -240.373619) (xy 349.496392 -240.402184)
			(xy 349.507837 -240.428604) (xy 349.5167 -240.439956) (xy 349.532138 -240.459203) (xy 349.558114 -240.501152)
			(xy 349.578042 -240.546289) (xy 349.59154 -240.593747) (xy 349.598348 -240.642616) (xy 349.598742 -240.667286)
			(xy 349.598244 -240.693935) (xy 349.590301 -240.746639) (xy 349.574591 -240.797569) (xy 349.551465 -240.84559)
			(xy 349.521441 -240.889627) (xy 349.485189 -240.928698) (xy 349.443518 -240.961929) (xy 349.39736 -240.988578)
			(xy 349.347746 -241.00805) (xy 349.295784 -241.01991) (xy 349.242634 -241.023894) (xy 349.189484 -241.01991)
			(xy 349.137522 -241.00805) (xy 349.087908 -240.988578) (xy 349.04175 -240.961929) (xy 349.000079 -240.928698)
			(xy 348.963827 -240.889627) (xy 348.933803 -240.84559) (xy 348.910677 -240.797569) (xy 348.894967 -240.746639)
			(xy 348.887024 -240.693935) (xy 348.886526 -240.667286) (xy 348.886947 -240.642617) (xy 348.89376 -240.593753)
			(xy 348.907255 -240.546296) (xy 348.927172 -240.501158) (xy 348.95313 -240.459201) (xy 348.968568 -240.439956)
			(xy 348.977356 -240.428557) (xy 348.988784 -240.402154) (xy 348.992394 -240.373611) (xy 348.987898 -240.345195)
			(xy 348.975653 -240.31916) (xy 348.956633 -240.297575) (xy 348.932346 -240.282153) (xy 348.904721 -240.274117)
			(xy 348.890336 -240.273586) (xy 348.616524 -240.273586) (xy 348.601752 -240.274095) (xy 348.573446 -240.28256)
			(xy 348.54874 -240.298762) (xy 348.529696 -240.32135) (xy 348.517902 -240.348438) (xy 348.514341 -240.377767)
			(xy 348.519312 -240.406891) (xy 348.532399 -240.433379) (xy 348.542102 -240.444528) (xy 348.558488 -240.462774)
			(xy 348.586163 -240.503258) (xy 348.607479 -240.547422) (xy 348.621956 -240.594275) (xy 348.629271 -240.642766)
			(xy 348.629732 -240.667286) (xy 348.629228 -240.692974) (xy 348.621191 -240.743717) (xy 348.605315 -240.792578)
			(xy 348.581991 -240.838354) (xy 348.551794 -240.879918) (xy 348.515466 -240.916246) (xy 348.473902 -240.946443)
			(xy 348.428126 -240.969767) (xy 348.379265 -240.985643) (xy 348.328522 -240.99368) (xy 348.277146 -240.99368)
			(xy 348.226403 -240.985643) (xy 348.177542 -240.969767) (xy 348.131766 -240.946443) (xy 348.090202 -240.916246)
			(xy 348.053874 -240.879918) (xy 348.023677 -240.838354) (xy 348.000353 -240.792578) (xy 347.984477 -240.743717)
			(xy 347.97644 -240.692974) (xy 347.975936 -240.667286) (xy 347.976375 -240.642766) (xy 347.983701 -240.594276)
			(xy 347.998187 -240.547424) (xy 348.019507 -240.503261) (xy 348.047184 -240.462778) (xy 348.063566 -240.444528)
			(xy 348.073288 -240.433379) (xy 348.086431 -240.406892) (xy 348.091438 -240.377751) (xy 348.087892 -240.348397)
			(xy 348.076088 -240.321287) (xy 348.057016 -240.298693) (xy 348.032272 -240.282506) (xy 348.003929 -240.274082)
			(xy 347.989144 -240.273586) (xy 347.89364 -240.273586) (xy 347.674946 -240.49228) (xy 347.688916 -240.52403)
			(xy 347.698444 -240.546699) (xy 347.711882 -240.594001) (xy 347.718694 -240.6427) (xy 347.719142 -240.667286)
			(xy 347.718594 -240.695271) (xy 347.709841 -240.750552) (xy 347.692548 -240.803783) (xy 347.667141 -240.853653)
			(xy 347.634246 -240.898936) (xy 347.594672 -240.938515) (xy 347.549394 -240.971416) (xy 347.499527 -240.99683)
			(xy 347.446298 -241.01413) (xy 347.391019 -241.02289) (xy 347.363034 -241.023394) (xy 347.35897 -241.023394)
			(xy 347.345535 -241.023636) (xy 347.319519 -241.030317) (xy 347.296145 -241.043553) (xy 347.277032 -241.062427)
			(xy 347.263504 -241.085633) (xy 347.256497 -241.111563) (xy 347.2561 -241.124994) (xy 347.2561 -241.50681)
			(xy 347.506032 -241.50681) (xy 347.506032 -241.455394) (xy 347.514075 -241.404612) (xy 347.529963 -241.355713)
			(xy 347.553306 -241.309901) (xy 347.583527 -241.268305) (xy 347.619883 -241.231949) (xy 347.661479 -241.201728)
			(xy 347.707291 -241.178385) (xy 347.75619 -241.162497) (xy 347.806972 -241.154454) (xy 347.858388 -241.154454)
			(xy 347.90917 -241.162497) (xy 347.958069 -241.178385) (xy 348.003881 -241.201728) (xy 348.045477 -241.231949)
			(xy 348.081833 -241.268305) (xy 348.112054 -241.309901) (xy 348.135397 -241.355713) (xy 348.151285 -241.404612)
			(xy 348.159328 -241.455394) (xy 348.159832 -241.481102) (xy 348.159328 -241.50681) (xy 348.159179 -241.507751)
			(xy 348.417124 -241.507751) (xy 348.417124 -241.454453) (xy 348.425067 -241.401749) (xy 348.440777 -241.350819)
			(xy 348.463903 -241.302798) (xy 348.493927 -241.258761) (xy 348.530179 -241.21969) (xy 348.57185 -241.186459)
			(xy 348.618008 -241.15981) (xy 348.667622 -241.140338) (xy 348.719584 -241.128478) (xy 348.772734 -241.124495)
			(xy 348.825884 -241.128478) (xy 348.877846 -241.140338) (xy 348.92746 -241.15981) (xy 348.973618 -241.186459)
			(xy 349.015289 -241.21969) (xy 349.051541 -241.258761) (xy 349.081565 -241.302798) (xy 349.104691 -241.350819)
			(xy 349.120401 -241.401749) (xy 349.128344 -241.454453) (xy 349.128842 -241.481102) (xy 349.128344 -241.507751)
			(xy 349.120401 -241.560455) (xy 349.104691 -241.611385) (xy 349.081565 -241.659406) (xy 349.051541 -241.703443)
			(xy 349.015289 -241.742514) (xy 348.973618 -241.775745) (xy 348.92746 -241.802394) (xy 348.877846 -241.821866)
			(xy 348.825884 -241.833726) (xy 348.772734 -241.83771) (xy 348.719584 -241.833726) (xy 348.667622 -241.821866)
			(xy 348.618008 -241.802394) (xy 348.57185 -241.775745) (xy 348.530179 -241.742514) (xy 348.493927 -241.703443)
			(xy 348.463903 -241.659406) (xy 348.440777 -241.611385) (xy 348.425067 -241.560455) (xy 348.417124 -241.507751)
			(xy 348.159179 -241.507751) (xy 348.151285 -241.557592) (xy 348.135397 -241.606491) (xy 348.112054 -241.652303)
			(xy 348.081833 -241.693899) (xy 348.045477 -241.730255) (xy 348.003881 -241.760476) (xy 347.958069 -241.783819)
			(xy 347.90917 -241.799707) (xy 347.858388 -241.80775) (xy 347.806972 -241.80775) (xy 347.75619 -241.799707)
			(xy 347.707291 -241.783819) (xy 347.661479 -241.760476) (xy 347.619883 -241.730255) (xy 347.583527 -241.693899)
			(xy 347.553306 -241.652303) (xy 347.529963 -241.606491) (xy 347.514075 -241.557592) (xy 347.506032 -241.50681)
			(xy 347.2561 -241.50681) (xy 347.2561 -241.83721) (xy 347.256511 -241.850638) (xy 347.263518 -241.876565)
			(xy 347.277045 -241.899766) (xy 347.296155 -241.918637) (xy 347.319525 -241.93187) (xy 347.345537 -241.93855)
			(xy 347.35897 -241.93881) (xy 347.363034 -241.93881) (xy 347.38968 -241.939311) (xy 347.442377 -241.947258)
			(xy 347.493301 -241.96297) (xy 347.541314 -241.986096) (xy 347.585345 -242.01612) (xy 347.624409 -242.05237)
			(xy 347.657635 -242.094037) (xy 347.68428 -242.140191) (xy 347.703749 -242.1898) (xy 347.715607 -242.241756)
			(xy 347.719589 -242.2949) (xy 347.717591 -242.321567) (xy 347.947224 -242.321567) (xy 347.947224 -242.268269)
			(xy 347.955167 -242.215565) (xy 347.970877 -242.164635) (xy 347.994003 -242.116614) (xy 348.024027 -242.072577)
			(xy 348.060279 -242.033506) (xy 348.10195 -242.000275) (xy 348.148108 -241.973626) (xy 348.197722 -241.954154)
			(xy 348.249684 -241.942294) (xy 348.302834 -241.938311) (xy 348.355984 -241.942294) (xy 348.407946 -241.954154)
			(xy 348.45756 -241.973626) (xy 348.503718 -242.000275) (xy 348.545389 -242.033506) (xy 348.581641 -242.072577)
			(xy 348.611665 -242.116614) (xy 348.634791 -242.164635) (xy 348.650501 -242.215565) (xy 348.658444 -242.268269)
			(xy 348.658942 -242.294918) (xy 348.658444 -242.321567) (xy 348.650501 -242.374271) (xy 348.634791 -242.425201)
			(xy 348.611665 -242.473222) (xy 348.581641 -242.517259) (xy 348.545389 -242.55633) (xy 348.503718 -242.589561)
			(xy 348.45756 -242.61621) (xy 348.407946 -242.635682) (xy 348.355984 -242.647542) (xy 348.302834 -242.651526)
			(xy 348.249684 -242.647542) (xy 348.197722 -242.635682) (xy 348.148108 -242.61621) (xy 348.10195 -242.589561)
			(xy 348.060279 -242.55633) (xy 348.024027 -242.517259) (xy 347.994003 -242.473222) (xy 347.970877 -242.425201)
			(xy 347.955167 -242.374271) (xy 347.947224 -242.321567) (xy 347.717591 -242.321567) (xy 347.715607 -242.348044)
			(xy 347.703749 -242.4) (xy 347.68428 -242.449609) (xy 347.657635 -242.495763) (xy 347.624409 -242.53743)
			(xy 347.585345 -242.57368) (xy 347.541314 -242.603704) (xy 347.493301 -242.62683) (xy 347.442377 -242.642542)
			(xy 347.38968 -242.650489) (xy 347.363034 -242.651026) (xy 347.35897 -242.651026) (xy 347.345537 -242.651268)
			(xy 347.319523 -242.65795) (xy 347.296154 -242.671186) (xy 347.277046 -242.690061) (xy 347.263524 -242.713267)
			(xy 347.256524 -242.739197) (xy 347.2561 -242.752626) (xy 347.2561 -243.134696) (xy 347.506032 -243.134696)
			(xy 347.506032 -243.08328) (xy 347.514075 -243.032498) (xy 347.529963 -242.983599) (xy 347.553306 -242.937787)
			(xy 347.583527 -242.896191) (xy 347.619883 -242.859835) (xy 347.661479 -242.829614) (xy 347.707291 -242.806271)
			(xy 347.75619 -242.790383) (xy 347.806972 -242.78234) (xy 347.858388 -242.78234) (xy 347.90917 -242.790383)
			(xy 347.958069 -242.806271) (xy 348.003881 -242.829614) (xy 348.045477 -242.859835) (xy 348.081833 -242.896191)
			(xy 348.112054 -242.937787) (xy 348.135397 -242.983599) (xy 348.151285 -243.032498) (xy 348.159328 -243.08328)
			(xy 348.159832 -243.108988) (xy 348.159328 -243.134696) (xy 348.159179 -243.135637) (xy 348.41687 -243.135637)
			(xy 348.41687 -243.082339) (xy 348.424813 -243.029635) (xy 348.440523 -242.978705) (xy 348.463649 -242.930684)
			(xy 348.493673 -242.886647) (xy 348.529925 -242.847576) (xy 348.571596 -242.814345) (xy 348.617754 -242.787696)
			(xy 348.667368 -242.768224) (xy 348.71933 -242.756364) (xy 348.77248 -242.752381) (xy 348.82563 -242.756364)
			(xy 348.877592 -242.768224) (xy 348.927206 -242.787696) (xy 348.973364 -242.814345) (xy 349.015035 -242.847576)
			(xy 349.051287 -242.886647) (xy 349.081311 -242.930684) (xy 349.104437 -242.978705) (xy 349.120147 -243.029635)
			(xy 349.12809 -243.082339) (xy 349.128588 -243.108988) (xy 349.12809 -243.135637) (xy 349.35667 -243.135637)
			(xy 349.35667 -243.082339) (xy 349.364613 -243.029635) (xy 349.380323 -242.978705) (xy 349.403449 -242.930684)
			(xy 349.433473 -242.886647) (xy 349.469725 -242.847576) (xy 349.511396 -242.814345) (xy 349.557554 -242.787696)
			(xy 349.607168 -242.768224) (xy 349.65913 -242.756364) (xy 349.71228 -242.752381) (xy 349.76543 -242.756364)
			(xy 349.817392 -242.768224) (xy 349.867006 -242.787696) (xy 349.913164 -242.814345) (xy 349.954835 -242.847576)
			(xy 349.991087 -242.886647) (xy 350.021111 -242.930684) (xy 350.044237 -242.978705) (xy 350.059947 -243.029635)
			(xy 350.06789 -243.082339) (xy 350.068388 -243.108988) (xy 350.06789 -243.135637) (xy 350.059947 -243.188341)
			(xy 350.044237 -243.239271) (xy 350.021111 -243.287292) (xy 349.991087 -243.331329) (xy 349.954835 -243.3704)
			(xy 349.913164 -243.403631) (xy 349.867006 -243.43028) (xy 349.817392 -243.449752) (xy 349.76543 -243.461612)
			(xy 349.71228 -243.465596) (xy 349.65913 -243.461612) (xy 349.607168 -243.449752) (xy 349.557554 -243.43028)
			(xy 349.511396 -243.403631) (xy 349.469725 -243.3704) (xy 349.433473 -243.331329) (xy 349.403449 -243.287292)
			(xy 349.380323 -243.239271) (xy 349.364613 -243.188341) (xy 349.35667 -243.135637) (xy 349.12809 -243.135637)
			(xy 349.120147 -243.188341) (xy 349.104437 -243.239271) (xy 349.081311 -243.287292) (xy 349.051287 -243.331329)
			(xy 349.015035 -243.3704) (xy 348.973364 -243.403631) (xy 348.927206 -243.43028) (xy 348.877592 -243.449752)
			(xy 348.82563 -243.461612) (xy 348.77248 -243.465596) (xy 348.71933 -243.461612) (xy 348.667368 -243.449752)
			(xy 348.617754 -243.43028) (xy 348.571596 -243.403631) (xy 348.529925 -243.3704) (xy 348.493673 -243.331329)
			(xy 348.463649 -243.287292) (xy 348.440523 -243.239271) (xy 348.424813 -243.188341) (xy 348.41687 -243.135637)
			(xy 348.159179 -243.135637) (xy 348.151285 -243.185478) (xy 348.135397 -243.234377) (xy 348.112054 -243.280189)
			(xy 348.081833 -243.321785) (xy 348.045477 -243.358141) (xy 348.003881 -243.388362) (xy 347.958069 -243.411705)
			(xy 347.90917 -243.427593) (xy 347.858388 -243.435636) (xy 347.806972 -243.435636) (xy 347.75619 -243.427593)
			(xy 347.707291 -243.411705) (xy 347.661479 -243.388362) (xy 347.619883 -243.358141) (xy 347.583527 -243.321785)
			(xy 347.553306 -243.280189) (xy 347.529963 -243.234377) (xy 347.514075 -243.185478) (xy 347.506032 -243.134696)
			(xy 347.2561 -243.134696) (xy 347.2561 -243.465096) (xy 347.256509 -243.478526) (xy 347.263514 -243.504455)
			(xy 347.27704 -243.52766) (xy 347.29615 -243.546533) (xy 347.319522 -243.559769) (xy 347.345536 -243.56645)
			(xy 347.35897 -243.566696) (xy 347.363034 -243.566696) (xy 347.389681 -243.567196) (xy 347.44238 -243.575144)
			(xy 347.493306 -243.590857) (xy 347.541321 -243.613984) (xy 347.585354 -243.644008) (xy 347.62442 -243.68026)
			(xy 347.657647 -243.721929) (xy 347.684293 -243.768084) (xy 347.703763 -243.817695) (xy 347.715621 -243.869654)
			(xy 347.719604 -243.9228) (xy 347.717677 -243.948512) (xy 347.976186 -243.948512) (xy 347.976186 -243.897096)
			(xy 347.984229 -243.846314) (xy 348.000117 -243.797415) (xy 348.02346 -243.751603) (xy 348.053681 -243.710007)
			(xy 348.090037 -243.673651) (xy 348.131633 -243.64343) (xy 348.177445 -243.620087) (xy 348.226344 -243.604199)
			(xy 348.277126 -243.596156) (xy 348.328542 -243.596156) (xy 348.379324 -243.604199) (xy 348.428223 -243.620087)
			(xy 348.474035 -243.64343) (xy 348.515631 -243.673651) (xy 348.551987 -243.710007) (xy 348.582208 -243.751603)
			(xy 348.605551 -243.797415) (xy 348.621439 -243.846314) (xy 348.629482 -243.897096) (xy 348.629986 -243.922804)
			(xy 348.629482 -243.948512) (xy 348.629333 -243.949453) (xy 348.88677 -243.949453) (xy 348.88677 -243.896155)
			(xy 348.894713 -243.843451) (xy 348.910423 -243.792521) (xy 348.933549 -243.7445) (xy 348.963573 -243.700463)
			(xy 348.999825 -243.661392) (xy 349.041496 -243.628161) (xy 349.087654 -243.601512) (xy 349.137268 -243.58204)
			(xy 349.18923 -243.57018) (xy 349.24238 -243.566197) (xy 349.29553 -243.57018) (xy 349.347492 -243.58204)
			(xy 349.397106 -243.601512) (xy 349.443264 -243.628161) (xy 349.484935 -243.661392) (xy 349.521187 -243.700463)
			(xy 349.551211 -243.7445) (xy 349.574337 -243.792521) (xy 349.590047 -243.843451) (xy 349.59799 -243.896155)
			(xy 349.598488 -243.922804) (xy 349.59799 -243.949453) (xy 349.826824 -243.949453) (xy 349.826824 -243.896155)
			(xy 349.834767 -243.843451) (xy 349.850477 -243.792521) (xy 349.873603 -243.7445) (xy 349.903627 -243.700463)
			(xy 349.939879 -243.661392) (xy 349.98155 -243.628161) (xy 350.027708 -243.601512) (xy 350.077322 -243.58204)
			(xy 350.129284 -243.57018) (xy 350.182434 -243.566197) (xy 350.235584 -243.57018) (xy 350.287546 -243.58204)
			(xy 350.33716 -243.601512) (xy 350.383318 -243.628161) (xy 350.424989 -243.661392) (xy 350.461241 -243.700463)
			(xy 350.491265 -243.7445) (xy 350.514391 -243.792521) (xy 350.530101 -243.843451) (xy 350.538044 -243.896155)
			(xy 350.538542 -243.922804) (xy 350.538044 -243.949453) (xy 350.530101 -244.002157) (xy 350.514391 -244.053087)
			(xy 350.491265 -244.101108) (xy 350.461241 -244.145145) (xy 350.424989 -244.184216) (xy 350.383318 -244.217447)
			(xy 350.33716 -244.244096) (xy 350.287546 -244.263568) (xy 350.235584 -244.275428) (xy 350.182434 -244.279412)
			(xy 350.129284 -244.275428) (xy 350.077322 -244.263568) (xy 350.027708 -244.244096) (xy 349.98155 -244.217447)
			(xy 349.939879 -244.184216) (xy 349.903627 -244.145145) (xy 349.873603 -244.101108) (xy 349.850477 -244.053087)
			(xy 349.834767 -244.002157) (xy 349.826824 -243.949453) (xy 349.59799 -243.949453) (xy 349.590047 -244.002157)
			(xy 349.574337 -244.053087) (xy 349.551211 -244.101108) (xy 349.521187 -244.145145) (xy 349.484935 -244.184216)
			(xy 349.443264 -244.217447) (xy 349.397106 -244.244096) (xy 349.347492 -244.263568) (xy 349.29553 -244.275428)
			(xy 349.24238 -244.279412) (xy 349.18923 -244.275428) (xy 349.137268 -244.263568) (xy 349.087654 -244.244096)
			(xy 349.041496 -244.217447) (xy 348.999825 -244.184216) (xy 348.963573 -244.145145) (xy 348.933549 -244.101108)
			(xy 348.910423 -244.053087) (xy 348.894713 -244.002157) (xy 348.88677 -243.949453) (xy 348.629333 -243.949453)
			(xy 348.621439 -243.999294) (xy 348.605551 -244.048193) (xy 348.582208 -244.094005) (xy 348.551987 -244.135601)
			(xy 348.515631 -244.171957) (xy 348.474035 -244.202178) (xy 348.428223 -244.225521) (xy 348.379324 -244.241409)
			(xy 348.328542 -244.249452) (xy 348.277126 -244.249452) (xy 348.226344 -244.241409) (xy 348.177445 -244.225521)
			(xy 348.131633 -244.202178) (xy 348.090037 -244.171957) (xy 348.053681 -244.135601) (xy 348.02346 -244.094005)
			(xy 348.000117 -244.048193) (xy 347.984229 -243.999294) (xy 347.976186 -243.948512) (xy 347.717677 -243.948512)
			(xy 347.715621 -243.975946) (xy 347.703763 -244.027905) (xy 347.684293 -244.077516) (xy 347.657647 -244.123671)
			(xy 347.62442 -244.16534) (xy 347.585354 -244.201592) (xy 347.541321 -244.231616) (xy 347.493306 -244.254743)
			(xy 347.44238 -244.270456) (xy 347.389681 -244.278404) (xy 347.363034 -244.278912) (xy 347.35897 -244.278912)
			(xy 347.345536 -244.279154) (xy 347.319521 -244.285835) (xy 347.29615 -244.299072) (xy 347.27704 -244.317946)
			(xy 347.263515 -244.341152) (xy 347.256512 -244.367082) (xy 347.2561 -244.380512) (xy 347.2561 -244.762328)
			(xy 347.506032 -244.762328) (xy 347.506032 -244.710912) (xy 347.514075 -244.66013) (xy 347.529963 -244.611231)
			(xy 347.553306 -244.565419) (xy 347.583527 -244.523823) (xy 347.619883 -244.487467) (xy 347.661479 -244.457246)
			(xy 347.707291 -244.433903) (xy 347.75619 -244.418015) (xy 347.806972 -244.409972) (xy 347.858388 -244.409972)
			(xy 347.90917 -244.418015) (xy 347.958069 -244.433903) (xy 348.003881 -244.457246) (xy 348.045477 -244.487467)
			(xy 348.081833 -244.523823) (xy 348.112054 -244.565419) (xy 348.135397 -244.611231) (xy 348.151285 -244.66013)
			(xy 348.159328 -244.710912) (xy 348.159832 -244.73662) (xy 348.159328 -244.762328) (xy 348.445832 -244.762328)
			(xy 348.445832 -244.710912) (xy 348.453875 -244.66013) (xy 348.469763 -244.611231) (xy 348.493106 -244.565419)
			(xy 348.523327 -244.523823) (xy 348.559683 -244.487467) (xy 348.601279 -244.457246) (xy 348.647091 -244.433903)
			(xy 348.69599 -244.418015) (xy 348.746772 -244.409972) (xy 348.798188 -244.409972) (xy 348.84897 -244.418015)
			(xy 348.897869 -244.433903) (xy 348.943681 -244.457246) (xy 348.985277 -244.487467) (xy 349.021633 -244.523823)
			(xy 349.051854 -244.565419) (xy 349.075197 -244.611231) (xy 349.091085 -244.66013) (xy 349.099128 -244.710912)
			(xy 349.099632 -244.73662) (xy 349.099128 -244.762328) (xy 349.098979 -244.763269) (xy 349.35667 -244.763269)
			(xy 349.35667 -244.709971) (xy 349.364613 -244.657267) (xy 349.380323 -244.606337) (xy 349.403449 -244.558316)
			(xy 349.433473 -244.514279) (xy 349.469725 -244.475208) (xy 349.511396 -244.441977) (xy 349.557554 -244.415328)
			(xy 349.607168 -244.395856) (xy 349.65913 -244.383996) (xy 349.71228 -244.380013) (xy 349.76543 -244.383996)
			(xy 349.817392 -244.395856) (xy 349.867006 -244.415328) (xy 349.913164 -244.441977) (xy 349.954835 -244.475208)
			(xy 349.991087 -244.514279) (xy 350.021111 -244.558316) (xy 350.044237 -244.606337) (xy 350.059947 -244.657267)
			(xy 350.06789 -244.709971) (xy 350.068388 -244.73662) (xy 350.06789 -244.763269) (xy 350.059947 -244.815973)
			(xy 350.044237 -244.866903) (xy 350.021111 -244.914924) (xy 349.991087 -244.958961) (xy 349.954835 -244.998032)
			(xy 349.913164 -245.031263) (xy 349.867006 -245.057912) (xy 349.817392 -245.077384) (xy 349.76543 -245.089244)
			(xy 349.71228 -245.093228) (xy 349.65913 -245.089244) (xy 349.607168 -245.077384) (xy 349.557554 -245.057912)
			(xy 349.511396 -245.031263) (xy 349.469725 -244.998032) (xy 349.433473 -244.958961) (xy 349.403449 -244.914924)
			(xy 349.380323 -244.866903) (xy 349.364613 -244.815973) (xy 349.35667 -244.763269) (xy 349.098979 -244.763269)
			(xy 349.091085 -244.81311) (xy 349.075197 -244.862009) (xy 349.051854 -244.907821) (xy 349.021633 -244.949417)
			(xy 348.985277 -244.985773) (xy 348.943681 -245.015994) (xy 348.897869 -245.039337) (xy 348.84897 -245.055225)
			(xy 348.798188 -245.063268) (xy 348.746772 -245.063268) (xy 348.69599 -245.055225) (xy 348.647091 -245.039337)
			(xy 348.601279 -245.015994) (xy 348.559683 -244.985773) (xy 348.523327 -244.949417) (xy 348.493106 -244.907821)
			(xy 348.469763 -244.862009) (xy 348.453875 -244.81311) (xy 348.445832 -244.762328) (xy 348.159328 -244.762328)
			(xy 348.151285 -244.81311) (xy 348.135397 -244.862009) (xy 348.112054 -244.907821) (xy 348.081833 -244.949417)
			(xy 348.045477 -244.985773) (xy 348.003881 -245.015994) (xy 347.958069 -245.039337) (xy 347.90917 -245.055225)
			(xy 347.858388 -245.063268) (xy 347.806972 -245.063268) (xy 347.75619 -245.055225) (xy 347.707291 -245.039337)
			(xy 347.661479 -245.015994) (xy 347.619883 -244.985773) (xy 347.583527 -244.949417) (xy 347.553306 -244.907821)
			(xy 347.529963 -244.862009) (xy 347.514075 -244.81311) (xy 347.506032 -244.762328) (xy 347.2561 -244.762328)
			(xy 347.2561 -245.092982) (xy 347.256508 -245.106413) (xy 347.26351 -245.132345) (xy 347.277035 -245.155554)
			(xy 347.296145 -245.17443) (xy 347.319518 -245.187668) (xy 347.345535 -245.19435) (xy 347.35897 -245.194582)
			(xy 347.363034 -245.194582) (xy 347.389682 -245.195082) (xy 347.442383 -245.20303) (xy 347.493311 -245.218744)
			(xy 347.541328 -245.241872) (xy 347.585363 -245.271897) (xy 347.62443 -245.30815) (xy 347.657659 -245.349821)
			(xy 347.684305 -245.395978) (xy 347.703776 -245.445591) (xy 347.715635 -245.497552) (xy 347.719618 -245.5507)
			(xy 347.717692 -245.576398) (xy 347.976186 -245.576398) (xy 347.976186 -245.524982) (xy 347.984229 -245.4742)
			(xy 348.000117 -245.425301) (xy 348.02346 -245.379489) (xy 348.053681 -245.337893) (xy 348.090037 -245.301537)
			(xy 348.131633 -245.271316) (xy 348.177445 -245.247973) (xy 348.226344 -245.232085) (xy 348.277126 -245.224042)
			(xy 348.328542 -245.224042) (xy 348.379324 -245.232085) (xy 348.428223 -245.247973) (xy 348.474035 -245.271316)
			(xy 348.515631 -245.301537) (xy 348.551987 -245.337893) (xy 348.582208 -245.379489) (xy 348.605551 -245.425301)
			(xy 348.621439 -245.4742) (xy 348.629482 -245.524982) (xy 348.629986 -245.55069) (xy 348.629482 -245.576398)
			(xy 348.629333 -245.577339) (xy 348.887024 -245.577339) (xy 348.887024 -245.524041) (xy 348.894967 -245.471337)
			(xy 348.910677 -245.420407) (xy 348.933803 -245.372386) (xy 348.963827 -245.328349) (xy 349.000079 -245.289278)
			(xy 349.04175 -245.256047) (xy 349.087908 -245.229398) (xy 349.137522 -245.209926) (xy 349.189484 -245.198066)
			(xy 349.242634 -245.194083) (xy 349.295784 -245.198066) (xy 349.347746 -245.209926) (xy 349.39736 -245.229398)
			(xy 349.443518 -245.256047) (xy 349.485189 -245.289278) (xy 349.521441 -245.328349) (xy 349.551465 -245.372386)
			(xy 349.574591 -245.420407) (xy 349.590301 -245.471337) (xy 349.598244 -245.524041) (xy 349.598742 -245.55069)
			(xy 349.598244 -245.577339) (xy 349.590301 -245.630043) (xy 349.574591 -245.680973) (xy 349.551465 -245.728994)
			(xy 349.521441 -245.773031) (xy 349.485189 -245.812102) (xy 349.443518 -245.845333) (xy 349.39736 -245.871982)
			(xy 349.347746 -245.891454) (xy 349.295784 -245.903314) (xy 349.242634 -245.907298) (xy 349.189484 -245.903314)
			(xy 349.137522 -245.891454) (xy 349.087908 -245.871982) (xy 349.04175 -245.845333) (xy 349.000079 -245.812102)
			(xy 348.963827 -245.773031) (xy 348.933803 -245.728994) (xy 348.910677 -245.680973) (xy 348.894967 -245.630043)
			(xy 348.887024 -245.577339) (xy 348.629333 -245.577339) (xy 348.621439 -245.62718) (xy 348.605551 -245.676079)
			(xy 348.582208 -245.721891) (xy 348.551987 -245.763487) (xy 348.515631 -245.799843) (xy 348.474035 -245.830064)
			(xy 348.428223 -245.853407) (xy 348.379324 -245.869295) (xy 348.328542 -245.877338) (xy 348.277126 -245.877338)
			(xy 348.226344 -245.869295) (xy 348.177445 -245.853407) (xy 348.131633 -245.830064) (xy 348.090037 -245.799843)
			(xy 348.053681 -245.763487) (xy 348.02346 -245.721891) (xy 348.000117 -245.676079) (xy 347.984229 -245.62718)
			(xy 347.976186 -245.576398) (xy 347.717692 -245.576398) (xy 347.715635 -245.603848) (xy 347.703776 -245.655809)
			(xy 347.684305 -245.705422) (xy 347.657659 -245.751579) (xy 347.62443 -245.79325) (xy 347.585363 -245.829503)
			(xy 347.541328 -245.859528) (xy 347.493311 -245.882656) (xy 347.442383 -245.89837) (xy 347.389682 -245.906318)
			(xy 347.363034 -245.906798) (xy 347.35897 -245.906798) (xy 347.345536 -245.90704) (xy 347.319519 -245.913721)
			(xy 347.296146 -245.926957) (xy 347.277034 -245.945831) (xy 347.263507 -245.969037) (xy 347.2565 -245.994968)
			(xy 347.2561 -246.008398) (xy 347.2561 -246.390214) (xy 347.506032 -246.390214) (xy 347.506032 -246.338798)
			(xy 347.514075 -246.288016) (xy 347.529963 -246.239117) (xy 347.553306 -246.193305) (xy 347.583527 -246.151709)
			(xy 347.619883 -246.115353) (xy 347.661479 -246.085132) (xy 347.707291 -246.061789) (xy 347.75619 -246.045901)
			(xy 347.806972 -246.037858) (xy 347.858388 -246.037858) (xy 347.90917 -246.045901) (xy 347.958069 -246.061789)
			(xy 348.003881 -246.085132) (xy 348.045477 -246.115353) (xy 348.081833 -246.151709) (xy 348.112054 -246.193305)
			(xy 348.135397 -246.239117) (xy 348.151285 -246.288016) (xy 348.159328 -246.338798) (xy 348.159832 -246.364506)
			(xy 348.159328 -246.390214) (xy 348.159179 -246.391155) (xy 348.417124 -246.391155) (xy 348.417124 -246.337857)
			(xy 348.425067 -246.285153) (xy 348.440777 -246.234223) (xy 348.463903 -246.186202) (xy 348.493927 -246.142165)
			(xy 348.530179 -246.103094) (xy 348.57185 -246.069863) (xy 348.618008 -246.043214) (xy 348.667622 -246.023742)
			(xy 348.719584 -246.011882) (xy 348.772734 -246.007899) (xy 348.825884 -246.011882) (xy 348.877846 -246.023742)
			(xy 348.92746 -246.043214) (xy 348.973618 -246.069863) (xy 349.015289 -246.103094) (xy 349.051541 -246.142165)
			(xy 349.081565 -246.186202) (xy 349.104691 -246.234223) (xy 349.120401 -246.285153) (xy 349.128344 -246.337857)
			(xy 349.128842 -246.364506) (xy 349.128344 -246.391155) (xy 349.35667 -246.391155) (xy 349.35667 -246.337857)
			(xy 349.364613 -246.285153) (xy 349.380323 -246.234223) (xy 349.403449 -246.186202) (xy 349.433473 -246.142165)
			(xy 349.469725 -246.103094) (xy 349.511396 -246.069863) (xy 349.557554 -246.043214) (xy 349.607168 -246.023742)
			(xy 349.65913 -246.011882) (xy 349.71228 -246.007899) (xy 349.76543 -246.011882) (xy 349.817392 -246.023742)
			(xy 349.867006 -246.043214) (xy 349.913164 -246.069863) (xy 349.954835 -246.103094) (xy 349.991087 -246.142165)
			(xy 350.021111 -246.186202) (xy 350.044237 -246.234223) (xy 350.059947 -246.285153) (xy 350.06789 -246.337857)
			(xy 350.068388 -246.364506) (xy 350.06789 -246.391155) (xy 350.059947 -246.443859) (xy 350.044237 -246.494789)
			(xy 350.021111 -246.54281) (xy 349.991087 -246.586847) (xy 349.954835 -246.625918) (xy 349.913164 -246.659149)
			(xy 349.867006 -246.685798) (xy 349.817392 -246.70527) (xy 349.76543 -246.71713) (xy 349.71228 -246.721114)
			(xy 349.65913 -246.71713) (xy 349.607168 -246.70527) (xy 349.557554 -246.685798) (xy 349.511396 -246.659149)
			(xy 349.469725 -246.625918) (xy 349.433473 -246.586847) (xy 349.403449 -246.54281) (xy 349.380323 -246.494789)
			(xy 349.364613 -246.443859) (xy 349.35667 -246.391155) (xy 349.128344 -246.391155) (xy 349.120401 -246.443859)
			(xy 349.104691 -246.494789) (xy 349.081565 -246.54281) (xy 349.051541 -246.586847) (xy 349.015289 -246.625918)
			(xy 348.973618 -246.659149) (xy 348.92746 -246.685798) (xy 348.877846 -246.70527) (xy 348.825884 -246.71713)
			(xy 348.772734 -246.721114) (xy 348.719584 -246.71713) (xy 348.667622 -246.70527) (xy 348.618008 -246.685798)
			(xy 348.57185 -246.659149) (xy 348.530179 -246.625918) (xy 348.493927 -246.586847) (xy 348.463903 -246.54281)
			(xy 348.440777 -246.494789) (xy 348.425067 -246.443859) (xy 348.417124 -246.391155) (xy 348.159179 -246.391155)
			(xy 348.151285 -246.440996) (xy 348.135397 -246.489895) (xy 348.112054 -246.535707) (xy 348.081833 -246.577303)
			(xy 348.045477 -246.613659) (xy 348.003881 -246.64388) (xy 347.958069 -246.667223) (xy 347.90917 -246.683111)
			(xy 347.858388 -246.691154) (xy 347.806972 -246.691154) (xy 347.75619 -246.683111) (xy 347.707291 -246.667223)
			(xy 347.661479 -246.64388) (xy 347.619883 -246.613659) (xy 347.583527 -246.577303) (xy 347.553306 -246.535707)
			(xy 347.529963 -246.489895) (xy 347.514075 -246.440996) (xy 347.506032 -246.390214) (xy 347.2561 -246.390214)
			(xy 347.2561 -246.720614) (xy 347.256511 -246.734042) (xy 347.263519 -246.759968) (xy 347.277046 -246.783168)
			(xy 347.296156 -246.802038) (xy 347.319526 -246.815271) (xy 347.345538 -246.82195) (xy 347.35897 -246.822214)
			(xy 347.363034 -246.822214) (xy 347.38968 -246.822715) (xy 347.442376 -246.830662) (xy 347.493299 -246.846374)
			(xy 347.541312 -246.8695) (xy 347.585342 -246.899523) (xy 347.624406 -246.935772) (xy 347.657632 -246.977439)
			(xy 347.684276 -247.023592) (xy 347.703745 -247.073201) (xy 347.715603 -247.125157) (xy 347.719585 -247.1783)
			(xy 347.717587 -247.204971) (xy 347.947224 -247.204971) (xy 347.947224 -247.151673) (xy 347.955167 -247.098969)
			(xy 347.970877 -247.048039) (xy 347.994003 -247.000018) (xy 348.024027 -246.955981) (xy 348.060279 -246.91691)
			(xy 348.10195 -246.883679) (xy 348.148108 -246.85703) (xy 348.197722 -246.837558) (xy 348.249684 -246.825698)
			(xy 348.302834 -246.821715) (xy 348.355984 -246.825698) (xy 348.407946 -246.837558) (xy 348.45756 -246.85703)
			(xy 348.503718 -246.883679) (xy 348.545389 -246.91691) (xy 348.581641 -246.955981) (xy 348.611665 -247.000018)
			(xy 348.634791 -247.048039) (xy 348.650501 -247.098969) (xy 348.658444 -247.151673) (xy 348.658942 -247.178322)
			(xy 348.658462 -247.20403) (xy 348.915986 -247.20403) (xy 348.915986 -247.152614) (xy 348.924029 -247.101832)
			(xy 348.939917 -247.052933) (xy 348.96326 -247.007121) (xy 348.993481 -246.965525) (xy 349.029837 -246.929169)
			(xy 349.071433 -246.898948) (xy 349.117245 -246.875605) (xy 349.166144 -246.859717) (xy 349.216926 -246.851674)
			(xy 349.268342 -246.851674) (xy 349.319124 -246.859717) (xy 349.368023 -246.875605) (xy 349.413835 -246.898948)
			(xy 349.455431 -246.929169) (xy 349.491787 -246.965525) (xy 349.522008 -247.007121) (xy 349.545351 -247.052933)
			(xy 349.561239 -247.101832) (xy 349.569282 -247.152614) (xy 349.569786 -247.178322) (xy 349.569282 -247.20403)
			(xy 349.855786 -247.20403) (xy 349.855786 -247.152614) (xy 349.863829 -247.101832) (xy 349.879717 -247.052933)
			(xy 349.90306 -247.007121) (xy 349.933281 -246.965525) (xy 349.969637 -246.929169) (xy 350.011233 -246.898948)
			(xy 350.057045 -246.875605) (xy 350.105944 -246.859717) (xy 350.156726 -246.851674) (xy 350.208142 -246.851674)
			(xy 350.258924 -246.859717) (xy 350.307823 -246.875605) (xy 350.353635 -246.898948) (xy 350.395231 -246.929169)
			(xy 350.431587 -246.965525) (xy 350.461808 -247.007121) (xy 350.485151 -247.052933) (xy 350.501039 -247.101832)
			(xy 350.509082 -247.152614) (xy 350.509586 -247.178322) (xy 350.509082 -247.20403) (xy 350.501039 -247.254812)
			(xy 350.485151 -247.303711) (xy 350.461808 -247.349523) (xy 350.431587 -247.391119) (xy 350.395231 -247.427475)
			(xy 350.353635 -247.457696) (xy 350.307823 -247.481039) (xy 350.258924 -247.496927) (xy 350.208142 -247.50497)
			(xy 350.156726 -247.50497) (xy 350.105944 -247.496927) (xy 350.057045 -247.481039) (xy 350.011233 -247.457696)
			(xy 349.969637 -247.427475) (xy 349.933281 -247.391119) (xy 349.90306 -247.349523) (xy 349.879717 -247.303711)
			(xy 349.863829 -247.254812) (xy 349.855786 -247.20403) (xy 349.569282 -247.20403) (xy 349.561239 -247.254812)
			(xy 349.545351 -247.303711) (xy 349.522008 -247.349523) (xy 349.491787 -247.391119) (xy 349.455431 -247.427475)
			(xy 349.413835 -247.457696) (xy 349.368023 -247.481039) (xy 349.319124 -247.496927) (xy 349.268342 -247.50497)
			(xy 349.216926 -247.50497) (xy 349.166144 -247.496927) (xy 349.117245 -247.481039) (xy 349.071433 -247.457696)
			(xy 349.029837 -247.427475) (xy 348.993481 -247.391119) (xy 348.96326 -247.349523) (xy 348.939917 -247.303711)
			(xy 348.924029 -247.254812) (xy 348.915986 -247.20403) (xy 348.658462 -247.20403) (xy 348.658444 -247.204971)
			(xy 348.650501 -247.257675) (xy 348.634791 -247.308605) (xy 348.611665 -247.356626) (xy 348.581641 -247.400663)
			(xy 348.545389 -247.439734) (xy 348.503718 -247.472965) (xy 348.45756 -247.499614) (xy 348.407946 -247.519086)
			(xy 348.355984 -247.530946) (xy 348.302834 -247.53493) (xy 348.249684 -247.530946) (xy 348.197722 -247.519086)
			(xy 348.148108 -247.499614) (xy 348.10195 -247.472965) (xy 348.060279 -247.439734) (xy 348.024027 -247.400663)
			(xy 347.994003 -247.356626) (xy 347.970877 -247.308605) (xy 347.955167 -247.257675) (xy 347.947224 -247.204971)
			(xy 347.717587 -247.204971) (xy 347.715603 -247.231443) (xy 347.703745 -247.283399) (xy 347.684276 -247.333008)
			(xy 347.657632 -247.379161) (xy 347.624406 -247.420828) (xy 347.585342 -247.457077) (xy 347.541312 -247.4871)
			(xy 347.493299 -247.510226) (xy 347.442376 -247.525938) (xy 347.38968 -247.533885) (xy 347.363034 -247.53443)
			(xy 347.35897 -247.53443) (xy 347.345537 -247.534672) (xy 347.319524 -247.541354) (xy 347.296155 -247.554591)
			(xy 347.277048 -247.573466) (xy 347.263527 -247.596671) (xy 347.256528 -247.622601) (xy 347.2561 -247.63603)
			(xy 347.2561 -248.023126) (xy 347.44914 -248.216166) (xy 347.547692 -248.216166)
		)
		(stroke
			(width 0)
			(type solid)
		)
		(fill yes)
		(layer "B.Cu")
		(net "PVCCD_HV_CPU0")
	)
	(gr_poly
		(pts
			(xy 292.1 -440.59348) (xy 292.11594 -440.592827) (xy 292.146246 -440.582925) (xy 292.172015 -440.564151)
			(xy 292.190731 -440.53834) (xy 292.196266 -440.523376) (xy 292.099235 -440.496185) (xy 291.90717 -440.435133)
			(xy 291.717663 -440.366549) (xy 291.53101 -440.290541) (xy 291.347502 -440.207226) (xy 291.167425 -440.116736)
			(xy 290.991058 -440.01921) (xy 290.818677 -439.9148) (xy 290.650551 -439.80367) (xy 290.48694 -439.685992)
			(xy 290.328101 -439.56195) (xy 290.17428 -439.431736) (xy 290.025717 -439.295554) (xy 289.882643 -439.153616)
			(xy 289.745282 -439.006143) (xy 289.613847 -438.853364) (xy 289.488543 -438.695518) (xy 289.369565 -438.532851)
			(xy 289.257098 -438.365615) (xy 289.151319 -438.194072) (xy 289.052391 -438.018488) (xy 288.960468 -437.839137)
			(xy 288.875694 -437.656299) (xy 288.798201 -437.470257) (xy 288.72811 -437.281303) (xy 288.665529 -437.089731)
			(xy 288.610556 -436.895838) (xy 288.563277 -436.699926) (xy 288.523766 -436.502302) (xy 288.492084 -436.303273)
			(xy 288.46828 -436.103148) (xy 288.452391 -435.90224) (xy 288.444443 -435.700862) (xy 288.443924 -435.600094)
			(xy 288.444429 -435.498567) (xy 288.452502 -435.295675) (xy 288.468634 -435.093263) (xy 288.492801 -434.891653)
			(xy 288.524964 -434.691163) (xy 288.565073 -434.492111) (xy 288.613064 -434.29481) (xy 288.66886 -434.099573)
			(xy 288.732375 -433.906709) (xy 288.803506 -433.716523) (xy 288.882143 -433.529314) (xy 288.96816 -433.345381)
			(xy 289.061422 -433.165012) (xy 289.161781 -432.988493) (xy 289.269078 -432.816105) (xy 289.383144 -432.648118)
			(xy 289.503799 -432.484799) (xy 289.630851 -432.326405) (xy 289.7641 -432.173189) (xy 289.903335 -432.02539)
			(xy 290.048335 -431.883245) (xy 290.198873 -431.746976) (xy 290.354708 -431.6168) (xy 290.515596 -431.492922)
			(xy 290.681282 -431.375538) (xy 290.851504 -431.264835) (xy 291.025992 -431.160986) (xy 291.204471 -431.064157)
			(xy 291.386658 -430.974499) (xy 291.572266 -430.892156) (xy 291.761 -430.817257) (xy 291.952563 -430.749921)
			(xy 292.146652 -430.690253) (xy 292.34296 -430.63835) (xy 292.541176 -430.594291) (xy 292.740986 -430.558148)
			(xy 292.942076 -430.529978) (xy 293.144127 -430.509824) (xy 293.346819 -430.497719) (xy 293.549832 -430.493682)
			(xy 293.752845 -430.497719) (xy 293.955537 -430.509824) (xy 294.157588 -430.529978) (xy 294.358678 -430.558148)
			(xy 294.558488 -430.594291) (xy 294.756704 -430.63835) (xy 294.953012 -430.690253) (xy 295.147101 -430.749921)
			(xy 295.338664 -430.817257) (xy 295.527398 -430.892156) (xy 295.713006 -430.974499) (xy 295.895193 -431.064157)
			(xy 296.073672 -431.160986) (xy 296.24816 -431.264835) (xy 296.418382 -431.375538) (xy 296.584068 -431.492922)
			(xy 296.744956 -431.6168) (xy 296.900791 -431.746976) (xy 297.051329 -431.883245) (xy 297.196329 -432.02539)
			(xy 297.335564 -432.173189) (xy 297.468813 -432.326405) (xy 297.595865 -432.484799) (xy 297.71652 -432.648118)
			(xy 297.830586 -432.816105) (xy 297.937883 -432.988493) (xy 298.038242 -433.165012) (xy 298.131504 -433.345381)
			(xy 298.217521 -433.529314) (xy 298.296158 -433.716523) (xy 298.367289 -433.906709) (xy 298.430804 -434.099573)
			(xy 298.4866 -434.29481) (xy 298.534591 -434.492111) (xy 298.5747 -434.691163) (xy 298.606863 -434.891653)
			(xy 298.63103 -435.093263) (xy 298.647162 -435.295675) (xy 298.655235 -435.498567) (xy 298.65574 -435.600094)
			(xy 298.655244 -435.700852) (xy 298.647293 -435.902211) (xy 298.631404 -436.103099) (xy 298.6076 -436.303204)
			(xy 298.575919 -436.502214) (xy 298.536411 -436.699819) (xy 298.489136 -436.895711) (xy 298.434169 -437.089585)
			(xy 298.371595 -437.28114) (xy 298.301511 -437.470076) (xy 298.224028 -437.6561) (xy 298.139265 -437.838922)
			(xy 298.047354 -438.018257) (xy 297.948438 -438.193825) (xy 297.842673 -438.365354) (xy 297.730221 -438.532577)
			(xy 297.61126 -438.695232) (xy 297.485973 -438.853067) (xy 297.354555 -439.005835) (xy 297.217213 -439.153299)
			(xy 297.074159 -439.295229) (xy 296.925616 -439.431404) (xy 296.771816 -439.561612) (xy 296.612998 -439.68565)
			(xy 296.449409 -439.803325) (xy 296.281305 -439.914453) (xy 296.108947 -440.018863) (xy 295.932603 -440.11639)
			(xy 295.752549 -440.206883) (xy 295.569064 -440.290202) (xy 295.382435 -440.366215) (xy 295.192951 -440.434806)
			(xy 295.000909 -440.495867) (xy 294.903906 -440.523122) (xy 294.909426 -440.538105) (xy 294.928151 -440.563947)
			(xy 294.953914 -440.582779) (xy 294.98422 -440.592778) (xy 295.000172 -440.59348) (xy 299.94098 -440.59348)
			(xy 300.87824 -439.65622) (xy 300.87824 -431.804318) (xy 297.456352 -428.38243) (xy 297.45432 -428.380398)
			(xy 292.204902 -423.130726) (xy 292.188222 -423.113498) (xy 292.1597 -423.074951) (xy 292.137267 -423.032569)
			(xy 292.128956 -423.010076) (xy 292.12066 -422.984648) (xy 292.111723 -422.931916) (xy 292.111176 -422.905174)
			(xy 292.111176 -418.385244) (xy 291.606732 -417.8808) (xy 291.596939 -417.87163) (xy 291.573659 -417.858312)
			(xy 291.547716 -417.851511) (xy 291.520897 -417.851695) (xy 291.495049 -417.858851) (xy 291.483288 -417.865306)
			(xy 291.531517 -417.945464) (xy 291.62149 -418.109503) (xy 291.703891 -418.277474) (xy 291.778549 -418.449027)
			(xy 291.845308 -418.623805) (xy 291.904029 -418.801444) (xy 291.954591 -418.981577) (xy 291.996888 -419.163826)
			(xy 292.030833 -419.347815) (xy 292.056354 -419.53316) (xy 292.073399 -419.719476) (xy 292.081932 -419.906375)
			(xy 292.082474 -419.999922) (xy 292.081972 -420.090691) (xy 292.073942 -420.272052) (xy 292.057897 -420.452881)
			(xy 292.03387 -420.632822) (xy 292.001907 -420.811525) (xy 291.96207 -420.988639) (xy 291.914438 -421.163817)
			(xy 291.859104 -421.336718) (xy 291.796176 -421.507001) (xy 291.725778 -421.674334) (xy 291.648047 -421.838389)
			(xy 291.563135 -421.998846) (xy 291.471209 -422.155389) (xy 291.372448 -422.307713) (xy 291.267046 -422.45552)
			(xy 291.155209 -422.598519) (xy 291.037157 -422.736432) (xy 290.913119 -422.868988) (xy 290.78334 -422.995927)
			(xy 290.648073 -423.117002) (xy 290.507582 -423.231974) (xy 290.362144 -423.34062) (xy 290.212042 -423.442727)
			(xy 290.05757 -423.538094) (xy 289.899031 -423.626534) (xy 289.736736 -423.707876) (xy 289.571001 -423.781959)
			(xy 289.402151 -423.848638) (xy 289.230518 -423.907784) (xy 289.056436 -423.959279) (xy 288.880246 -424.003024)
			(xy 288.702294 -424.038933) (xy 288.522928 -424.066935) (xy 288.342499 -424.086976) (xy 288.16136 -424.099016)
			(xy 287.979866 -424.103032) (xy 287.798372 -424.099016) (xy 287.617233 -424.086976) (xy 287.436804 -424.066935)
			(xy 287.257438 -424.038933) (xy 287.079486 -424.003024) (xy 286.903296 -423.959279) (xy 286.729214 -423.907784)
			(xy 286.557581 -423.848638) (xy 286.388731 -423.781959) (xy 286.222996 -423.707876) (xy 286.060701 -423.626534)
			(xy 285.902162 -423.538094) (xy 285.74769 -423.442727) (xy 285.597588 -423.34062) (xy 285.45215 -423.231974)
			(xy 285.311659 -423.117002) (xy 285.176392 -422.995927) (xy 285.046613 -422.868988) (xy 284.922575 -422.736432)
			(xy 284.804523 -422.598519) (xy 284.692686 -422.45552) (xy 284.587284 -422.307713) (xy 284.488523 -422.155389)
			(xy 284.396597 -421.998846) (xy 284.311685 -421.838389) (xy 284.233954 -421.674334) (xy 284.163556 -421.507001)
			(xy 284.100628 -421.336718) (xy 284.045294 -421.163817) (xy 283.997662 -420.988639) (xy 283.957825 -420.811525)
			(xy 283.925862 -420.632822) (xy 283.901835 -420.452881) (xy 283.88579 -420.272052) (xy 283.87776 -420.090691)
			(xy 283.877258 -419.999922) (xy 283.877767 -419.90828) (xy 283.885955 -419.72518) (xy 283.902312 -419.542628)
			(xy 283.926804 -419.360989) (xy 283.959384 -419.180625) (xy 283.999985 -419.001895) (xy 284.048528 -418.825157)
			(xy 284.104914 -418.650763) (xy 284.169032 -418.479061) (xy 284.240754 -418.310394) (xy 284.319936 -418.145097)
			(xy 284.406421 -417.983502) (xy 284.500036 -417.82593) (xy 284.600594 -417.672695) (xy 284.707895 -417.524104)
			(xy 284.821724 -417.380453) (xy 284.941855 -417.242029) (xy 285.068047 -417.109107) (xy 285.20005 -416.981953)
			(xy 285.337598 -416.860821) (xy 285.480419 -416.745952) (xy 285.628228 -416.637576) (xy 285.780728 -416.535908)
			(xy 285.937617 -416.441152) (xy 286.09858 -416.353496) (xy 286.263297 -416.273116) (xy 286.347154 -416.23615)
			(xy 286.340708 -416.223078) (xy 286.321678 -416.201016) (xy 286.297202 -416.185212) (xy 286.269265 -416.176947)
			(xy 286.254698 -416.17646) (xy 267.29182 -416.17646) (xy 266.659868 -416.808412) (xy 266.659868 -417.02482)
			(xy 276.170642 -417.02482) (xy 276.174713 -416.969198) (xy 276.186839 -416.914761) (xy 276.206762 -416.86267)
			(xy 276.234058 -416.814035) (xy 276.268144 -416.769892) (xy 276.308293 -416.731183) (xy 276.353651 -416.698732)
			(xy 276.403251 -416.673231) (xy 276.456035 -416.655224) (xy 276.510878 -416.645094) (xy 276.566612 -416.643057)
			(xy 276.622049 -416.649157) (xy 276.676006 -416.663263) (xy 276.727335 -416.685075) (xy 276.774941 -416.714129)
			(xy 276.817809 -416.749804) (xy 276.855026 -416.791341) (xy 276.885799 -416.837854) (xy 276.907361 -416.88385)
			(xy 280.663902 -416.88385) (xy 280.667973 -416.828228) (xy 280.680099 -416.773791) (xy 280.700022 -416.7217)
			(xy 280.727318 -416.673065) (xy 280.761404 -416.628922) (xy 280.801553 -416.590213) (xy 280.846911 -416.557762)
			(xy 280.896511 -416.532261) (xy 280.949295 -416.514254) (xy 281.004138 -416.504124) (xy 281.059872 -416.502087)
			(xy 281.115309 -416.508187) (xy 281.169266 -416.522293) (xy 281.220595 -416.544105) (xy 281.268201 -416.573159)
			(xy 281.311069 -416.608834) (xy 281.348286 -416.650371) (xy 281.379059 -416.696884) (xy 281.402731 -416.747381)
			(xy 281.418799 -416.800788) (xy 281.426919 -416.855964) (xy 281.427428 -416.88385) (xy 281.426919 -416.911736)
			(xy 281.418799 -416.966912) (xy 281.402731 -417.020319) (xy 281.379059 -417.070816) (xy 281.348286 -417.117329)
			(xy 281.311069 -417.158866) (xy 281.268201 -417.194541) (xy 281.220595 -417.223595) (xy 281.169266 -417.245407)
			(xy 281.115309 -417.259513) (xy 281.059872 -417.265613) (xy 281.004138 -417.263576) (xy 280.949295 -417.253446)
			(xy 280.896511 -417.235439) (xy 280.846911 -417.209938) (xy 280.801553 -417.177487) (xy 280.761404 -417.138778)
			(xy 280.727318 -417.094635) (xy 280.700022 -417.046) (xy 280.680099 -416.993909) (xy 280.667973 -416.939472)
			(xy 280.663902 -416.88385) (xy 276.907361 -416.88385) (xy 276.909471 -416.888351) (xy 276.925539 -416.941758)
			(xy 276.933659 -416.996934) (xy 276.934168 -417.02482) (xy 276.933659 -417.052706) (xy 276.925539 -417.107882)
			(xy 276.909471 -417.161289) (xy 276.885799 -417.211786) (xy 276.855026 -417.258299) (xy 276.817809 -417.299836)
			(xy 276.774941 -417.335511) (xy 276.727335 -417.364565) (xy 276.676006 -417.386377) (xy 276.622049 -417.400483)
			(xy 276.566612 -417.406583) (xy 276.510878 -417.404546) (xy 276.456035 -417.394416) (xy 276.403251 -417.376409)
			(xy 276.353651 -417.350908) (xy 276.308293 -417.318457) (xy 276.268144 -417.279748) (xy 276.234058 -417.235605)
			(xy 276.206762 -417.18697) (xy 276.186839 -417.134879) (xy 276.174713 -417.080442) (xy 276.170642 -417.02482)
			(xy 266.659868 -417.02482) (xy 266.659868 -418.36594) (xy 274.953982 -418.36594) (xy 274.958053 -418.310318)
			(xy 274.970179 -418.255881) (xy 274.990102 -418.20379) (xy 275.017398 -418.155155) (xy 275.051484 -418.111012)
			(xy 275.091633 -418.072303) (xy 275.136991 -418.039852) (xy 275.186591 -418.014351) (xy 275.239375 -417.996344)
			(xy 275.294218 -417.986214) (xy 275.349952 -417.984177) (xy 275.405389 -417.990277) (xy 275.459346 -418.004383)
			(xy 275.510675 -418.026195) (xy 275.558281 -418.055249) (xy 275.601149 -418.090924) (xy 275.638366 -418.132461)
			(xy 275.669139 -418.178974) (xy 275.692811 -418.229471) (xy 275.708879 -418.282878) (xy 275.716999 -418.338054)
			(xy 275.717508 -418.36594) (xy 275.716999 -418.393826) (xy 275.708879 -418.449002) (xy 275.692811 -418.502409)
			(xy 275.669139 -418.552906) (xy 275.638366 -418.599419) (xy 275.601149 -418.640956) (xy 275.558281 -418.676631)
			(xy 275.510675 -418.705685) (xy 275.459346 -418.727497) (xy 275.405389 -418.741603) (xy 275.349952 -418.747703)
			(xy 275.294218 -418.745666) (xy 275.239375 -418.735536) (xy 275.186591 -418.717529) (xy 275.136991 -418.692028)
			(xy 275.091633 -418.659577) (xy 275.051484 -418.620868) (xy 275.017398 -418.576725) (xy 274.990102 -418.52809)
			(xy 274.970179 -418.475999) (xy 274.958053 -418.421562) (xy 274.953982 -418.36594) (xy 266.659868 -418.36594)
			(xy 266.659868 -420.127938) (xy 265.129518 -421.658288) (xy 252.159262 -421.658288) (xy 251.792994 -421.291766)
			(xy 250.43384 -422.65092) (xy 246.06504 -422.65092) (xy 245.43512 -423.28084) (xy 282.347922 -423.28084)
			(xy 282.351993 -423.225218) (xy 282.364119 -423.170781) (xy 282.384042 -423.11869) (xy 282.411338 -423.070055)
			(xy 282.445424 -423.025912) (xy 282.485573 -422.987203) (xy 282.530931 -422.954752) (xy 282.580531 -422.929251)
			(xy 282.633315 -422.911244) (xy 282.688158 -422.901114) (xy 282.743892 -422.899077) (xy 282.799329 -422.905177)
			(xy 282.853286 -422.919283) (xy 282.904615 -422.941095) (xy 282.952221 -422.970149) (xy 282.995089 -423.005824)
			(xy 283.032306 -423.047361) (xy 283.063079 -423.093874) (xy 283.086751 -423.144371) (xy 283.102819 -423.197778)
			(xy 283.110939 -423.252954) (xy 283.111448 -423.28084) (xy 283.110939 -423.308726) (xy 283.102819 -423.363902)
			(xy 283.086751 -423.417309) (xy 283.063079 -423.467806) (xy 283.032306 -423.514319) (xy 282.995089 -423.555856)
			(xy 282.952221 -423.591531) (xy 282.904615 -423.620585) (xy 282.853286 -423.642397) (xy 282.799329 -423.656503)
			(xy 282.743892 -423.662603) (xy 282.688158 -423.660566) (xy 282.633315 -423.650436) (xy 282.580531 -423.632429)
			(xy 282.530931 -423.606928) (xy 282.485573 -423.574477) (xy 282.445424 -423.535768) (xy 282.411338 -423.491625)
			(xy 282.384042 -423.44299) (xy 282.364119 -423.390899) (xy 282.351993 -423.336462) (xy 282.347922 -423.28084)
			(xy 245.43512 -423.28084) (xy 243.563812 -425.152148) (xy 276.956434 -425.152148) (xy 276.956435 -425.097638)
			(xy 276.964194 -425.043684) (xy 276.979553 -424.991382) (xy 277.002198 -424.941799) (xy 277.03167 -424.895943)
			(xy 277.067367 -424.854749) (xy 277.108565 -424.819054) (xy 277.154422 -424.789585) (xy 277.204007 -424.766943)
			(xy 277.25631 -424.751588) (xy 277.310265 -424.743834) (xy 277.33752 -424.743372) (xy 277.360289 -424.743721)
			(xy 277.405495 -424.749201) (xy 277.42769 -424.754294) (xy 277.441172 -424.757127) (xy 277.468696 -424.756194)
			(xy 277.494973 -424.747948) (xy 277.518097 -424.732989) (xy 277.536389 -424.7124) (xy 277.548522 -424.687677)
			(xy 277.553617 -424.660612) (xy 277.552912 -424.646852) (xy 277.551642 -424.61434) (xy 277.552112 -424.587083)
			(xy 277.559865 -424.533123) (xy 277.575219 -424.480815) (xy 277.597861 -424.431226) (xy 277.62733 -424.385363)
			(xy 277.663026 -424.344162) (xy 277.704223 -424.30846) (xy 277.750082 -424.278985) (xy 277.799668 -424.256336)
			(xy 277.851974 -424.240976) (xy 277.905933 -424.233216) (xy 277.960447 -424.233214) (xy 278.014407 -424.240971)
			(xy 278.066713 -424.256329) (xy 278.116301 -424.278975) (xy 278.162161 -424.308448) (xy 278.20336 -424.344147)
			(xy 278.239058 -424.385347) (xy 278.26853 -424.431208) (xy 278.291174 -424.480797) (xy 278.306531 -424.533103)
			(xy 278.314286 -424.587063) (xy 278.314284 -424.641577) (xy 278.306522 -424.695536) (xy 278.29116 -424.747841)
			(xy 278.268511 -424.797427) (xy 278.239034 -424.843285) (xy 278.203331 -424.884481) (xy 278.162129 -424.920176)
			(xy 278.116266 -424.949644) (xy 278.066675 -424.972285) (xy 278.014367 -424.987637) (xy 277.960407 -424.995389)
			(xy 277.93315 -424.995848) (xy 277.910382 -424.995486) (xy 277.865175 -424.990015) (xy 277.84298 -424.984926)
			(xy 277.829492 -424.982146) (xy 277.80198 -424.983087) (xy 277.775716 -424.991331) (xy 277.752601 -425.006283)
			(xy 277.734312 -425.026857) (xy 277.722173 -425.051564) (xy 277.717063 -425.078614) (xy 277.717758 -425.092368)
			(xy 277.719028 -425.12488) (xy 277.718566 -425.152135) (xy 277.710812 -425.20609) (xy 277.695457 -425.258393)
			(xy 277.672815 -425.307978) (xy 277.643346 -425.353835) (xy 277.607651 -425.395033) (xy 277.566457 -425.43073)
			(xy 277.520601 -425.460202) (xy 277.471018 -425.482847) (xy 277.418716 -425.498206) (xy 277.364762 -425.505965)
			(xy 277.310252 -425.505966) (xy 277.256297 -425.498209) (xy 277.203995 -425.482852) (xy 277.154411 -425.460208)
			(xy 277.108554 -425.430738) (xy 277.067358 -425.395042) (xy 277.031662 -425.353846) (xy 277.002192 -425.307989)
			(xy 276.979548 -425.258405) (xy 276.964191 -425.206103) (xy 276.956434 -425.152148) (xy 243.563812 -425.152148)
			(xy 242.45951 -426.25645) (xy 242.45951 -426.7708) (xy 281.131262 -426.7708) (xy 281.135333 -426.715178)
			(xy 281.147459 -426.660741) (xy 281.167382 -426.60865) (xy 281.194678 -426.560015) (xy 281.228764 -426.515872)
			(xy 281.268913 -426.477163) (xy 281.314271 -426.444712) (xy 281.363871 -426.419211) (xy 281.416655 -426.401204)
			(xy 281.471498 -426.391074) (xy 281.527232 -426.389037) (xy 281.582669 -426.395137) (xy 281.636626 -426.409243)
			(xy 281.687955 -426.431055) (xy 281.735561 -426.460109) (xy 281.778429 -426.495784) (xy 281.815646 -426.537321)
			(xy 281.846419 -426.583834) (xy 281.870091 -426.634331) (xy 281.886159 -426.687738) (xy 281.894279 -426.742914)
			(xy 281.894788 -426.7708) (xy 281.894279 -426.798686) (xy 281.886159 -426.853862) (xy 281.870091 -426.907269)
			(xy 281.846419 -426.957766) (xy 281.818874 -426.9994) (xy 293.673782 -426.9994) (xy 293.677853 -426.943778)
			(xy 293.689979 -426.889341) (xy 293.709902 -426.83725) (xy 293.737198 -426.788615) (xy 293.771284 -426.744472)
			(xy 293.811433 -426.705763) (xy 293.856791 -426.673312) (xy 293.906391 -426.647811) (xy 293.959175 -426.629804)
			(xy 294.014018 -426.619674) (xy 294.069752 -426.617637) (xy 294.125189 -426.623737) (xy 294.179146 -426.637843)
			(xy 294.230475 -426.659655) (xy 294.278081 -426.688709) (xy 294.320949 -426.724384) (xy 294.358166 -426.765921)
			(xy 294.388939 -426.812434) (xy 294.412611 -426.862931) (xy 294.417294 -426.878496) (xy 294.531286 -426.878496)
			(xy 294.535357 -426.822874) (xy 294.547483 -426.768437) (xy 294.567406 -426.716346) (xy 294.594702 -426.667711)
			(xy 294.628788 -426.623568) (xy 294.668937 -426.584859) (xy 294.714295 -426.552408) (xy 294.763895 -426.526907)
			(xy 294.816679 -426.5089) (xy 294.871522 -426.49877) (xy 294.927256 -426.496733) (xy 294.982693 -426.502833)
			(xy 295.03665 -426.516939) (xy 295.087979 -426.538751) (xy 295.135585 -426.567805) (xy 295.178453 -426.60348)
			(xy 295.21567 -426.645017) (xy 295.246443 -426.69153) (xy 295.270115 -426.742027) (xy 295.286183 -426.795434)
			(xy 295.294303 -426.85061) (xy 295.294812 -426.878496) (xy 295.294303 -426.906382) (xy 295.286183 -426.961558)
			(xy 295.270115 -427.014965) (xy 295.246443 -427.065462) (xy 295.21567 -427.111975) (xy 295.178453 -427.153512)
			(xy 295.135585 -427.189187) (xy 295.087979 -427.218241) (xy 295.03665 -427.240053) (xy 294.982693 -427.254159)
			(xy 294.927256 -427.260259) (xy 294.871522 -427.258222) (xy 294.816679 -427.248092) (xy 294.763895 -427.230085)
			(xy 294.714295 -427.204584) (xy 294.668937 -427.172133) (xy 294.628788 -427.133424) (xy 294.594702 -427.089281)
			(xy 294.567406 -427.040646) (xy 294.547483 -426.988555) (xy 294.535357 -426.934118) (xy 294.531286 -426.878496)
			(xy 294.417294 -426.878496) (xy 294.428679 -426.916338) (xy 294.436799 -426.971514) (xy 294.437308 -426.9994)
			(xy 294.436799 -427.027286) (xy 294.428679 -427.082462) (xy 294.412611 -427.135869) (xy 294.388939 -427.186366)
			(xy 294.358166 -427.232879) (xy 294.320949 -427.274416) (xy 294.278081 -427.310091) (xy 294.230475 -427.339145)
			(xy 294.179146 -427.360957) (xy 294.125189 -427.375063) (xy 294.069752 -427.381163) (xy 294.014018 -427.379126)
			(xy 293.959175 -427.368996) (xy 293.906391 -427.350989) (xy 293.856791 -427.325488) (xy 293.811433 -427.293037)
			(xy 293.771284 -427.254328) (xy 293.737198 -427.210185) (xy 293.709902 -427.16155) (xy 293.689979 -427.109459)
			(xy 293.677853 -427.055022) (xy 293.673782 -426.9994) (xy 281.818874 -426.9994) (xy 281.815646 -427.004279)
			(xy 281.778429 -427.045816) (xy 281.735561 -427.081491) (xy 281.687955 -427.110545) (xy 281.636626 -427.132357)
			(xy 281.582669 -427.146463) (xy 281.527232 -427.152563) (xy 281.471498 -427.150526) (xy 281.416655 -427.140396)
			(xy 281.363871 -427.122389) (xy 281.314271 -427.096888) (xy 281.268913 -427.064437) (xy 281.228764 -427.025728)
			(xy 281.194678 -426.981585) (xy 281.167382 -426.93295) (xy 281.147459 -426.880859) (xy 281.135333 -426.826422)
			(xy 281.131262 -426.7708) (xy 242.45951 -426.7708) (xy 242.45951 -433.04206) (xy 267.01141 -433.04206)
			(xy 267.01543 -432.866756) (xy 267.027484 -432.69182) (xy 267.047545 -432.517622) (xy 267.075571 -432.344526)
			(xy 267.111504 -432.172897) (xy 267.155267 -432.003095) (xy 267.20677 -431.835479) (xy 267.265903 -431.6704)
			(xy 267.332542 -431.508206) (xy 267.406547 -431.349238) (xy 267.487762 -431.19383) (xy 267.576017 -431.042308)
			(xy 267.671126 -430.894992) (xy 267.772888 -430.752191) (xy 267.881091 -430.614206) (xy 267.995506 -430.481327)
			(xy 268.115893 -430.353833) (xy 268.241998 -430.231992) (xy 268.373557 -430.116061) (xy 268.510292 -430.006284)
			(xy 268.651917 -429.902891) (xy 268.798133 -429.806099) (xy 268.948632 -429.716113) (xy 269.103099 -429.633121)
			(xy 269.261209 -429.557298) (xy 269.422628 -429.488804) (xy 269.587018 -429.427782) (xy 269.754033 -429.374362)
			(xy 269.923321 -429.328654) (xy 270.094527 -429.290756) (xy 270.26729 -429.260747) (xy 270.441247 -429.23869)
			(xy 270.616033 -429.224631) (xy 270.79128 -429.218601) (xy 270.966618 -429.220611) (xy 271.14168 -429.230658)
			(xy 271.316098 -429.248721) (xy 271.489504 -429.274761) (xy 271.661533 -429.308723) (xy 271.831825 -429.350537)
			(xy 272.000021 -429.400114) (xy 272.165767 -429.457351) (xy 272.328714 -429.522126) (xy 272.488521 -429.594303)
			(xy 272.64485 -429.673731) (xy 272.797374 -429.760243) (xy 272.94577 -429.853656) (xy 273.089728 -429.953775)
			(xy 273.228945 -430.060389) (xy 273.363127 -430.173273) (xy 273.491993 -430.29219) (xy 273.615272 -430.41689)
			(xy 273.732703 -430.547111) (xy 273.844042 -430.682578) (xy 273.949052 -430.823008) (xy 274.047513 -430.968105)
			(xy 274.139219 -431.117563) (xy 274.223977 -431.271068) (xy 274.301607 -431.428298) (xy 274.371948 -431.588921)
			(xy 274.43485 -431.752601) (xy 274.490182 -431.918992) (xy 274.537828 -432.087745) (xy 274.577686 -432.258505)
			(xy 274.609674 -432.430913) (xy 274.633724 -432.604606) (xy 274.649786 -432.779219) (xy 274.657825 -432.954385)
			(xy 274.658328 -433.04206) (xy 274.657825 -433.129735) (xy 274.649786 -433.304901) (xy 274.633724 -433.479514)
			(xy 274.609674 -433.653207) (xy 274.577686 -433.825615) (xy 274.537828 -433.996375) (xy 274.490182 -434.165128)
			(xy 274.43485 -434.331519) (xy 274.371948 -434.495199) (xy 274.301607 -434.655822) (xy 274.223977 -434.813052)
			(xy 274.139219 -434.966557) (xy 274.123129 -434.99278) (xy 278.489676 -434.99278) (xy 278.493642 -434.908249)
			(xy 278.505507 -434.824462) (xy 278.525165 -434.742153) (xy 278.552445 -434.662047) (xy 278.587106 -434.584848)
			(xy 278.628844 -434.511233) (xy 278.677291 -434.44185) (xy 278.732023 -434.377309) (xy 278.792559 -434.318177)
			(xy 278.858365 -434.264973) (xy 278.928865 -434.218165) (xy 279.003437 -434.178164) (xy 279.081428 -434.145322)
			(xy 279.162152 -434.119928) (xy 279.244899 -434.102205) (xy 279.328941 -434.092307) (xy 279.413542 -434.090324)
			(xy 279.497956 -434.096271) (xy 279.581443 -434.110096) (xy 279.663268 -434.131679) (xy 279.742712 -434.160829)
			(xy 279.819078 -434.19729) (xy 279.891694 -434.240742) (xy 279.959922 -434.290803) (xy 280.023162 -434.347033)
			(xy 280.080859 -434.408938) (xy 280.132506 -434.475974) (xy 280.177648 -434.547551) (xy 280.21589 -434.623041)
			(xy 280.246894 -434.70178) (xy 280.259789 -434.7464) (xy 282.099512 -434.7464) (xy 282.100064 -434.716636)
			(xy 282.109322 -434.657834) (xy 282.127599 -434.601182) (xy 282.154451 -434.548054) (xy 282.189226 -434.499741)
			(xy 282.209748 -434.478176) (xy 282.220182 -434.466921) (xy 282.234296 -434.439682) (xy 282.239712 -434.409485)
			(xy 282.235945 -434.379038) (xy 282.223332 -434.351072) (xy 282.213558 -434.339238) (xy 282.195524 -434.318194)
			(xy 282.165095 -434.271876) (xy 282.141694 -434.22164) (xy 282.125814 -434.168545) (xy 282.117789 -434.11371)
			(xy 282.117292 -434.086) (xy 282.117782 -434.058727) (xy 282.125557 -434.004736) (xy 282.140935 -433.952402)
			(xy 282.163602 -433.902787) (xy 282.193098 -433.856903) (xy 282.228823 -433.815682) (xy 282.249118 -433.797456)
			(xy 282.259544 -433.787753) (xy 282.275115 -433.763926) (xy 282.283494 -433.736722) (xy 282.284027 -433.708263)
			(xy 282.276674 -433.680765) (xy 282.262007 -433.65637) (xy 282.251912 -433.646326) (xy 282.233129 -433.628194)
			(xy 282.200149 -433.587724) (xy 282.172992 -433.543137) (xy 282.152166 -433.495265) (xy 282.138058 -433.445001)
			(xy 282.130932 -433.393283) (xy 282.1305 -433.36718) (xy 282.130986 -433.339929) (xy 282.138742 -433.285981)
			(xy 282.154097 -433.233686) (xy 282.176739 -433.184109) (xy 282.206205 -433.138259) (xy 282.241896 -433.097068)
			(xy 282.283087 -433.061377) (xy 282.328937 -433.031911) (xy 282.378514 -433.009269) (xy 282.430809 -432.993914)
			(xy 282.484757 -432.986158) (xy 282.539259 -432.986158) (xy 282.593207 -432.993914) (xy 282.645502 -433.009269)
			(xy 282.695079 -433.031911) (xy 282.740929 -433.061377) (xy 282.78212 -433.097068) (xy 282.817811 -433.138259)
			(xy 282.847277 -433.184109) (xy 282.869919 -433.233686) (xy 282.885274 -433.285981) (xy 282.89303 -433.339929)
			(xy 282.893516 -433.36718) (xy 282.893044 -433.394454) (xy 282.885269 -433.448447) (xy 282.86989 -433.500783)
			(xy 282.847219 -433.550398) (xy 282.817718 -433.596281) (xy 282.781988 -433.637499) (xy 282.76169 -433.655724)
			(xy 282.751184 -433.665347) (xy 282.735615 -433.689197) (xy 282.727245 -433.716421) (xy 282.726726 -433.744898)
			(xy 282.734099 -433.772409) (xy 282.748789 -433.79681) (xy 282.758896 -433.806854) (xy 282.77772 -433.824946)
			(xy 282.810695 -433.865425) (xy 282.837846 -433.91002) (xy 282.858666 -433.9579) (xy 282.872765 -434.008171)
			(xy 282.879881 -434.059895) (xy 282.880308 -434.086) (xy 282.87975 -434.115763) (xy 282.870492 -434.174566)
			(xy 282.852217 -434.231217) (xy 282.825366 -434.284345) (xy 282.790593 -434.332658) (xy 282.770072 -434.354224)
			(xy 282.759637 -434.365478) (xy 282.74552 -434.392717) (xy 282.740103 -434.422915) (xy 282.743871 -434.453363)
			(xy 282.756486 -434.481329) (xy 282.766262 -434.493162) (xy 282.784283 -434.514217) (xy 282.814716 -434.560531)
			(xy 282.838121 -434.610764) (xy 282.854004 -434.663857) (xy 282.86203 -434.718691) (xy 282.862528 -434.7464)
			(xy 282.862042 -434.773651) (xy 282.854286 -434.827599) (xy 282.838931 -434.879894) (xy 282.816289 -434.929471)
			(xy 282.786823 -434.975321) (xy 282.751132 -435.016512) (xy 282.709941 -435.052203) (xy 282.664091 -435.081669)
			(xy 282.614514 -435.104311) (xy 282.562219 -435.119666) (xy 282.508271 -435.127422) (xy 282.453769 -435.127422)
			(xy 282.399821 -435.119666) (xy 282.347526 -435.104311) (xy 282.297949 -435.081669) (xy 282.252099 -435.052203)
			(xy 282.210908 -435.016512) (xy 282.175217 -434.975321) (xy 282.145751 -434.929471) (xy 282.123109 -434.879894)
			(xy 282.107754 -434.827599) (xy 282.099998 -434.773651) (xy 282.099512 -434.7464) (xy 280.259789 -434.7464)
			(xy 280.270389 -434.783077) (xy 280.286168 -434.866216) (xy 280.294092 -434.950468) (xy 280.294588 -434.99278)
			(xy 280.294092 -435.035092) (xy 280.286168 -435.119344) (xy 280.270389 -435.202483) (xy 280.246894 -435.28378)
			(xy 280.21589 -435.362519) (xy 280.177648 -435.438009) (xy 280.132506 -435.509586) (xy 280.080859 -435.576622)
			(xy 280.023162 -435.638527) (xy 279.959922 -435.694757) (xy 279.891694 -435.744818) (xy 279.819078 -435.78827)
			(xy 279.743464 -435.824372) (xy 282.536882 -435.824372) (xy 282.536882 -435.764436) (xy 282.544705 -435.705014)
			(xy 282.560218 -435.647121) (xy 282.583154 -435.591748) (xy 282.613121 -435.539842) (xy 282.649608 -435.492292)
			(xy 282.691988 -435.449912) (xy 282.739538 -435.413425) (xy 282.791444 -435.383458) (xy 282.846817 -435.360522)
			(xy 282.90471 -435.345009) (xy 282.964132 -435.337186) (xy 283.024068 -435.337186) (xy 283.08349 -435.345009)
			(xy 283.141383 -435.360522) (xy 283.196756 -435.383458) (xy 283.248662 -435.413425) (xy 283.296212 -435.449912)
			(xy 283.338592 -435.492292) (xy 283.375079 -435.539842) (xy 283.405046 -435.591748) (xy 283.427982 -435.647121)
			(xy 283.443495 -435.705014) (xy 283.451318 -435.764436) (xy 283.451808 -435.794404) (xy 283.451318 -435.824372)
			(xy 283.443495 -435.883794) (xy 283.427982 -435.941687) (xy 283.405046 -435.99706) (xy 283.375079 -436.048966)
			(xy 283.338592 -436.096516) (xy 283.296212 -436.138896) (xy 283.248662 -436.175383) (xy 283.196756 -436.20535)
			(xy 283.141383 -436.228286) (xy 283.08349 -436.243799) (xy 283.024068 -436.251622) (xy 282.964132 -436.251622)
			(xy 282.90471 -436.243799) (xy 282.846817 -436.228286) (xy 282.791444 -436.20535) (xy 282.739538 -436.175383)
			(xy 282.691988 -436.138896) (xy 282.649608 -436.096516) (xy 282.613121 -436.048966) (xy 282.583154 -435.99706)
			(xy 282.560218 -435.941687) (xy 282.544705 -435.883794) (xy 282.536882 -435.824372) (xy 279.743464 -435.824372)
			(xy 279.742712 -435.824731) (xy 279.663268 -435.853881) (xy 279.581443 -435.875464) (xy 279.497956 -435.889289)
			(xy 279.413542 -435.895236) (xy 279.328941 -435.893253) (xy 279.244899 -435.883355) (xy 279.162152 -435.865632)
			(xy 279.081428 -435.840238) (xy 279.003437 -435.807396) (xy 278.928865 -435.767395) (xy 278.858365 -435.720587)
			(xy 278.792559 -435.667383) (xy 278.732023 -435.608251) (xy 278.677291 -435.54371) (xy 278.628844 -435.474327)
			(xy 278.587106 -435.400712) (xy 278.552445 -435.323513) (xy 278.525165 -435.243407) (xy 278.505507 -435.161098)
			(xy 278.493642 -435.077311) (xy 278.489676 -434.99278) (xy 274.123129 -434.99278) (xy 274.047513 -435.116015)
			(xy 273.949052 -435.261112) (xy 273.844042 -435.401542) (xy 273.732703 -435.537009) (xy 273.615272 -435.66723)
			(xy 273.491993 -435.79193) (xy 273.363127 -435.910847) (xy 273.228945 -436.023731) (xy 273.089728 -436.130345)
			(xy 272.94577 -436.230464) (xy 272.797374 -436.323877) (xy 272.64485 -436.410389) (xy 272.488521 -436.489817)
			(xy 272.328714 -436.561994) (xy 272.165767 -436.626769) (xy 272.000021 -436.684006) (xy 271.831825 -436.733583)
			(xy 271.661533 -436.775397) (xy 271.489504 -436.809359) (xy 271.316098 -436.835399) (xy 271.14168 -436.853462)
			(xy 270.966618 -436.863509) (xy 270.79128 -436.865519) (xy 270.616033 -436.859489) (xy 270.441247 -436.84543)
			(xy 270.26729 -436.823373) (xy 270.094527 -436.793364) (xy 269.923321 -436.755466) (xy 269.754033 -436.709758)
			(xy 269.587018 -436.656338) (xy 269.422628 -436.595316) (xy 269.261209 -436.526822) (xy 269.103099 -436.450999)
			(xy 268.948632 -436.368007) (xy 268.798133 -436.278021) (xy 268.651917 -436.181229) (xy 268.510292 -436.077836)
			(xy 268.373557 -435.968059) (xy 268.241998 -435.852128) (xy 268.115893 -435.730287) (xy 267.995506 -435.602793)
			(xy 267.881091 -435.469914) (xy 267.772888 -435.331929) (xy 267.671126 -435.189128) (xy 267.576017 -435.041812)
			(xy 267.487762 -434.89029) (xy 267.406547 -434.734882) (xy 267.332542 -434.575914) (xy 267.265903 -434.41372)
			(xy 267.20677 -434.248641) (xy 267.155267 -434.081025) (xy 267.111504 -433.911223) (xy 267.075571 -433.739594)
			(xy 267.047545 -433.566498) (xy 267.027484 -433.3923) (xy 267.01543 -433.217364) (xy 267.01141 -433.04206)
			(xy 242.45951 -433.04206) (xy 242.45951 -438.30748) (xy 278.490172 -438.30748) (xy 278.490172 -436.75808)
			(xy 278.49072 -436.741366) (xy 278.499375 -436.709077) (xy 278.516091 -436.680128) (xy 278.539728 -436.656491)
			(xy 278.568677 -436.639775) (xy 278.600966 -436.63112) (xy 278.61768 -436.630572) (xy 280.16708 -436.630572)
			(xy 280.183792 -436.631155) (xy 280.216079 -436.639801) (xy 280.245029 -436.656508) (xy 280.262532 -436.674006)
			(xy 281.726384 -436.674006) (xy 281.730455 -436.618384) (xy 281.742581 -436.563947) (xy 281.762504 -436.511856)
			(xy 281.7898 -436.463221) (xy 281.823886 -436.419078) (xy 281.864035 -436.380369) (xy 281.909393 -436.347918)
			(xy 281.958993 -436.322417) (xy 282.011777 -436.30441) (xy 282.06662 -436.29428) (xy 282.122354 -436.292243)
			(xy 282.177791 -436.298343) (xy 282.231748 -436.312449) (xy 282.283077 -436.334261) (xy 282.330683 -436.363315)
			(xy 282.373551 -436.39899) (xy 282.410768 -436.440527) (xy 282.441541 -436.48704) (xy 282.465213 -436.537537)
			(xy 282.481281 -436.590944) (xy 282.489401 -436.64612) (xy 282.48991 -436.674006) (xy 282.489401 -436.701892)
			(xy 282.481281 -436.757068) (xy 282.465213 -436.810475) (xy 282.441541 -436.860972) (xy 282.410768 -436.907485)
			(xy 282.373551 -436.949022) (xy 282.330683 -436.984697) (xy 282.283077 -437.013751) (xy 282.231748 -437.035563)
			(xy 282.177791 -437.049669) (xy 282.122354 -437.055769) (xy 282.06662 -437.053732) (xy 282.011777 -437.043602)
			(xy 281.958993 -437.025595) (xy 281.909393 -437.000094) (xy 281.864035 -436.967643) (xy 281.823886 -436.928934)
			(xy 281.7898 -436.884791) (xy 281.762504 -436.836156) (xy 281.742581 -436.784065) (xy 281.730455 -436.729628)
			(xy 281.726384 -436.674006) (xy 280.262532 -436.674006) (xy 280.268667 -436.680139) (xy 280.285384 -436.709083)
			(xy 280.29404 -436.741368) (xy 280.294588 -436.75808) (xy 280.294588 -437.5658) (xy 282.650182 -437.5658)
			(xy 282.654253 -437.510178) (xy 282.666379 -437.455741) (xy 282.686302 -437.40365) (xy 282.713598 -437.355015)
			(xy 282.747684 -437.310872) (xy 282.787833 -437.272163) (xy 282.833191 -437.239712) (xy 282.882791 -437.214211)
			(xy 282.935575 -437.196204) (xy 282.990418 -437.186074) (xy 283.046152 -437.184037) (xy 283.101589 -437.190137)
			(xy 283.155546 -437.204243) (xy 283.206875 -437.226055) (xy 283.254481 -437.255109) (xy 283.297349 -437.290784)
			(xy 283.334566 -437.332321) (xy 283.365339 -437.378834) (xy 283.389011 -437.429331) (xy 283.405079 -437.482738)
			(xy 283.413199 -437.537914) (xy 283.413708 -437.5658) (xy 283.413199 -437.593686) (xy 283.405079 -437.648862)
			(xy 283.389011 -437.702269) (xy 283.365339 -437.752766) (xy 283.334566 -437.799279) (xy 283.297349 -437.840816)
			(xy 283.254481 -437.876491) (xy 283.206875 -437.905545) (xy 283.155546 -437.927357) (xy 283.101589 -437.941463)
			(xy 283.046152 -437.947563) (xy 282.990418 -437.945526) (xy 282.935575 -437.935396) (xy 282.882791 -437.917389)
			(xy 282.833191 -437.891888) (xy 282.787833 -437.859437) (xy 282.747684 -437.820728) (xy 282.713598 -437.776585)
			(xy 282.686302 -437.72795) (xy 282.666379 -437.675859) (xy 282.654253 -437.621422) (xy 282.650182 -437.5658)
			(xy 280.294588 -437.5658) (xy 280.294588 -438.30748) (xy 280.294094 -438.324202) (xy 280.285441 -438.356508)
			(xy 280.268721 -438.385472) (xy 280.245072 -438.409121) (xy 280.216108 -438.425841) (xy 280.183802 -438.434494)
			(xy 280.16708 -438.434988) (xy 278.61768 -438.434988) (xy 278.600963 -438.43448) (xy 278.568668 -438.425821)
			(xy 278.539715 -438.409099) (xy 278.516077 -438.385453) (xy 278.499364 -438.356495) (xy 278.490715 -438.324198)
			(xy 278.490172 -438.30748) (xy 242.45951 -438.30748) (xy 242.45951 -438.71515) (xy 242.82146 -439.0771)
			(xy 276.96414 -439.0771) (xy 277.38324 -439.4962) (xy 283.895292 -439.4962) (xy 283.895717 -439.470224)
			(xy 283.90276 -439.418751) (xy 283.916731 -439.368713) (xy 283.937369 -439.321036) (xy 283.964293 -439.276604)
			(xy 283.997002 -439.236242) (xy 284.034891 -439.200697) (xy 284.05582 -439.185304) (xy 284.066833 -439.176895)
			(xy 284.084255 -439.155363) (xy 284.095248 -439.129941) (xy 284.099005 -439.1025) (xy 284.095248 -439.075059)
			(xy 284.084255 -439.049637) (xy 284.066833 -439.028105) (xy 284.05582 -439.019696) (xy 284.034878 -439.004323)
			(xy 283.997003 -438.968765) (xy 283.964305 -438.928395) (xy 283.93739 -438.88396) (xy 283.916755 -438.836282)
			(xy 283.902783 -438.786246) (xy 283.895731 -438.734775) (xy 283.895292 -438.7088) (xy 283.895749 -438.681934)
			(xy 283.903276 -438.628732) (xy 283.918196 -438.577113) (xy 283.940213 -438.528099) (xy 283.968892 -438.48266)
			(xy 284.003663 -438.441696) (xy 284.04384 -438.406018) (xy 284.06598 -438.390792) (xy 284.077295 -438.382758)
			(xy 284.095473 -438.361805) (xy 284.107329 -438.336728) (xy 284.111986 -438.309383) (xy 284.109099 -438.281795)
			(xy 284.098882 -438.256006) (xy 284.082091 -438.233927) (xy 284.071314 -438.225184) (xy 284.048329 -438.207012)
			(xy 284.007658 -438.164837) (xy 283.973912 -438.116941) (xy 283.947882 -438.06445) (xy 283.930182 -438.008597)
			(xy 283.921226 -437.950695) (xy 283.920692 -437.9214) (xy 283.921178 -437.894149) (xy 283.928934 -437.840201)
			(xy 283.944289 -437.787906) (xy 283.966931 -437.738329) (xy 283.996397 -437.692479) (xy 284.032088 -437.651288)
			(xy 284.073279 -437.615597) (xy 284.119129 -437.586131) (xy 284.168706 -437.563489) (xy 284.221001 -437.548134)
			(xy 284.274949 -437.540378) (xy 284.329451 -437.540378) (xy 284.383399 -437.548134) (xy 284.435694 -437.563489)
			(xy 284.485271 -437.586131) (xy 284.531121 -437.615597) (xy 284.572312 -437.651288) (xy 284.608003 -437.692479)
			(xy 284.637469 -437.738329) (xy 284.660111 -437.787906) (xy 284.675466 -437.840201) (xy 284.683222 -437.894149)
			(xy 284.683708 -437.9214) (xy 284.683251 -437.948266) (xy 284.675724 -438.001468) (xy 284.660804 -438.053087)
			(xy 284.638787 -438.102101) (xy 284.610108 -438.14754) (xy 284.575337 -438.188504) (xy 284.53516 -438.224182)
			(xy 284.51302 -438.239408) (xy 284.501705 -438.247442) (xy 284.483527 -438.268395) (xy 284.471671 -438.293472)
			(xy 284.467014 -438.320817) (xy 284.469901 -438.348405) (xy 284.480118 -438.374194) (xy 284.496909 -438.396273)
			(xy 284.507686 -438.405016) (xy 284.530671 -438.423188) (xy 284.571342 -438.465363) (xy 284.605088 -438.513259)
			(xy 284.631118 -438.56575) (xy 284.648818 -438.621603) (xy 284.657774 -438.679505) (xy 284.658308 -438.7088)
			(xy 284.657883 -438.734776) (xy 284.65084 -438.786249) (xy 284.636869 -438.836287) (xy 284.616231 -438.883964)
			(xy 284.589307 -438.928396) (xy 284.556598 -438.968758) (xy 284.518709 -439.004303) (xy 284.49778 -439.019696)
			(xy 284.486767 -439.028105) (xy 284.469345 -439.049637) (xy 284.458352 -439.075059) (xy 284.454595 -439.1025)
			(xy 284.458352 -439.129941) (xy 284.469345 -439.155363) (xy 284.486767 -439.176895) (xy 284.49778 -439.185304)
			(xy 284.518722 -439.200677) (xy 284.556597 -439.236235) (xy 284.589295 -439.276605) (xy 284.61621 -439.32104)
			(xy 284.636845 -439.368718) (xy 284.650817 -439.418754) (xy 284.657869 -439.470225) (xy 284.658308 -439.4962)
			(xy 284.657822 -439.523451) (xy 284.650066 -439.577399) (xy 284.634711 -439.629694) (xy 284.612069 -439.679271)
			(xy 284.582603 -439.725121) (xy 284.546912 -439.766312) (xy 284.505721 -439.802003) (xy 284.459871 -439.831469)
			(xy 284.410294 -439.854111) (xy 284.357999 -439.869466) (xy 284.304051 -439.877222) (xy 284.249549 -439.877222)
			(xy 284.195601 -439.869466) (xy 284.143306 -439.854111) (xy 284.093729 -439.831469) (xy 284.047879 -439.802003)
			(xy 284.006688 -439.766312) (xy 283.970997 -439.725121) (xy 283.941531 -439.679271) (xy 283.918889 -439.629694)
			(xy 283.903534 -439.577399) (xy 283.895778 -439.523451) (xy 283.895292 -439.4962) (xy 277.38324 -439.4962)
			(xy 278.48052 -440.59348)
		)
		(stroke
			(width 0)
			(type solid)
		)
		(fill yes)
		(layer "B.Cu")
		(net "GND")
	)
	(gr_poly
		(pts
			(xy 281.69362 -74.691748) (xy 286.37992 -74.691748) (xy 286.7787 -74.292968) (xy 286.7787 -63.431928)
			(xy 290.40074 -59.809888) (xy 301.6631 -59.809888) (xy 302.1584 -59.314588) (xy 302.1584 -57.852818)
			(xy 302.157938 -57.839074) (xy 302.150588 -57.812585) (xy 302.136443 -57.789014) (xy 302.116526 -57.770067)
			(xy 302.092278 -57.757116) (xy 302.065456 -57.751098) (xy 302.037999 -57.752448) (xy 302.024796 -57.756298)
			(xy 301.995534 -57.765413) (xy 301.935043 -57.775245) (xy 301.9044 -57.775856) (xy 301.877145 -57.77537)
			(xy 301.823191 -57.767613) (xy 301.770889 -57.752256) (xy 301.721306 -57.729612) (xy 301.67545 -57.700142)
			(xy 301.634254 -57.664446) (xy 301.598558 -57.62325) (xy 301.569088 -57.577394) (xy 301.546444 -57.527811)
			(xy 301.531087 -57.475509) (xy 301.52333 -57.421555) (xy 301.52333 -57.367045) (xy 301.531087 -57.313091)
			(xy 301.546444 -57.260789) (xy 301.569088 -57.211206) (xy 301.598558 -57.16535) (xy 301.634254 -57.124154)
			(xy 301.67545 -57.088458) (xy 301.721306 -57.058988) (xy 301.770889 -57.036344) (xy 301.823191 -57.020987)
			(xy 301.877145 -57.01323) (xy 301.9044 -57.01284) (xy 301.935041 -57.01347) (xy 301.995532 -57.023292)
			(xy 302.024796 -57.032398) (xy 302.037992 -57.036301) (xy 302.065463 -57.037681) (xy 302.092306 -57.031673)
			(xy 302.116569 -57.018715) (xy 302.136489 -56.999747) (xy 302.15062 -56.976148) (xy 302.157935 -56.949632)
			(xy 302.1584 -56.935878) (xy 302.1584 -46.192948) (xy 302.48606 -45.865288) (xy 307.49748 -45.865288)
			(xy 308.448456 -46.816264) (xy 308.463188 -46.819312) (xy 308.492402 -46.825906) (xy 308.548935 -46.84568)
			(xy 308.602405 -46.872658) (xy 308.651901 -46.90638) (xy 308.696575 -46.946269) (xy 308.735666 -46.991643)
			(xy 308.768504 -47.041728) (xy 308.781958 -47.068486) (xy 308.795928 -47.097188) (xy 310.849264 -47.097188)
			(xy 310.856884 -47.094648) (xy 310.880921 -47.087295) (xy 310.930558 -47.07938) (xy 310.95569 -47.0789)
			(xy 316.100714 -47.0789) (xy 316.34176 -46.838108) (xy 316.34176 -46.060868) (xy 315.62802 -45.347128)
			(xy 311.781952 -45.347128) (xy 311.767982 -45.375068) (xy 311.754844 -45.399831) (xy 311.722414 -45.445552)
			(xy 311.683647 -45.48604) (xy 311.639376 -45.520424) (xy 311.590554 -45.547966) (xy 311.538229 -45.568072)
			(xy 311.483526 -45.580312) (xy 311.427622 -45.584421) (xy 311.371718 -45.580312) (xy 311.317015 -45.568072)
			(xy 311.26469 -45.547966) (xy 311.215868 -45.520424) (xy 311.171597 -45.48604) (xy 311.13283 -45.445552)
			(xy 311.1004 -45.399831) (xy 311.087262 -45.375068) (xy 311.073292 -45.347128) (xy 310.30926 -45.347128)
			(xy 307.0225 -42.060368) (xy 297.42638 -42.060368) (xy 296.97172 -42.515028) (xy 296.97172 -43.428916)
			(xy 302.061862 -43.428916) (xy 302.061862 -43.36898) (xy 302.069685 -43.309558) (xy 302.085198 -43.251665)
			(xy 302.108134 -43.196292) (xy 302.138101 -43.144386) (xy 302.174588 -43.096836) (xy 302.216968 -43.054456)
			(xy 302.264518 -43.017969) (xy 302.316424 -42.988002) (xy 302.371797 -42.965066) (xy 302.42969 -42.949553)
			(xy 302.489112 -42.94173) (xy 302.549048 -42.94173) (xy 302.60847 -42.949553) (xy 302.666363 -42.965066)
			(xy 302.721736 -42.988002) (xy 302.773642 -43.017969) (xy 302.821192 -43.054456) (xy 302.863572 -43.096836)
			(xy 302.900059 -43.144386) (xy 302.930026 -43.196292) (xy 302.952962 -43.251665) (xy 302.968475 -43.309558)
			(xy 302.976298 -43.36898) (xy 302.976788 -43.398948) (xy 302.976298 -43.428916) (xy 302.968475 -43.488338)
			(xy 302.952962 -43.546231) (xy 302.930026 -43.601604) (xy 302.900059 -43.65351) (xy 302.863572 -43.70106)
			(xy 302.821192 -43.74344) (xy 302.773642 -43.779927) (xy 302.721736 -43.809894) (xy 302.666363 -43.83283)
			(xy 302.60847 -43.848343) (xy 302.549048 -43.856166) (xy 302.489112 -43.856166) (xy 302.42969 -43.848343)
			(xy 302.371797 -43.83283) (xy 302.316424 -43.809894) (xy 302.264518 -43.779927) (xy 302.216968 -43.74344)
			(xy 302.174588 -43.70106) (xy 302.138101 -43.65351) (xy 302.108134 -43.601604) (xy 302.085198 -43.546231)
			(xy 302.069685 -43.488338) (xy 302.061862 -43.428916) (xy 296.97172 -43.428916) (xy 296.97172 -44.049188)
			(xy 297.189648 -44.267116) (xy 306.506354 -44.267116) (xy 306.506354 -44.20718) (xy 306.514177 -44.147758)
			(xy 306.52969 -44.089865) (xy 306.552626 -44.034492) (xy 306.582593 -43.982586) (xy 306.61908 -43.935036)
			(xy 306.66146 -43.892656) (xy 306.70901 -43.856169) (xy 306.760916 -43.826202) (xy 306.816289 -43.803266)
			(xy 306.874182 -43.787753) (xy 306.933604 -43.77993) (xy 306.99354 -43.77993) (xy 307.052962 -43.787753)
			(xy 307.110855 -43.803266) (xy 307.166228 -43.826202) (xy 307.218134 -43.856169) (xy 307.265684 -43.892656)
			(xy 307.308064 -43.935036) (xy 307.344551 -43.982586) (xy 307.374518 -44.034492) (xy 307.397454 -44.089865)
			(xy 307.412967 -44.147758) (xy 307.42079 -44.20718) (xy 307.42128 -44.237148) (xy 307.42079 -44.267116)
			(xy 307.412967 -44.326538) (xy 307.397454 -44.384431) (xy 307.374518 -44.439804) (xy 307.344551 -44.49171)
			(xy 307.308064 -44.53926) (xy 307.265684 -44.58164) (xy 307.218134 -44.618127) (xy 307.166228 -44.648094)
			(xy 307.110855 -44.67103) (xy 307.052962 -44.686543) (xy 306.99354 -44.694366) (xy 306.933604 -44.694366)
			(xy 306.874182 -44.686543) (xy 306.816289 -44.67103) (xy 306.760916 -44.648094) (xy 306.70901 -44.618127)
			(xy 306.66146 -44.58164) (xy 306.61908 -44.53926) (xy 306.582593 -44.49171) (xy 306.552626 -44.439804)
			(xy 306.52969 -44.384431) (xy 306.514177 -44.326538) (xy 306.506354 -44.267116) (xy 297.189648 -44.267116)
			(xy 297.4848 -44.562268) (xy 297.4848 -44.72051) (xy 297.573192 -44.72051) (xy 297.584114 -44.684696)
			(xy 297.593094 -44.656956) (xy 297.617121 -44.603829) (xy 297.647701 -44.554185) (xy 297.684339 -44.508826)
			(xy 297.726441 -44.468488) (xy 297.773325 -44.433824) (xy 297.824233 -44.405395) (xy 297.878338 -44.383663)
			(xy 297.934766 -44.368979) (xy 297.992602 -44.36158) (xy 298.021756 -44.3611) (xy 298.051726 -44.361566)
			(xy 298.111155 -44.369385) (xy 298.169054 -44.384894) (xy 298.224434 -44.407828) (xy 298.276346 -44.437795)
			(xy 298.323902 -44.474282) (xy 298.366289 -44.516665) (xy 298.40278 -44.564217) (xy 298.432752 -44.616126)
			(xy 298.455692 -44.671504) (xy 298.471207 -44.729402) (xy 298.479031 -44.78883) (xy 298.479031 -44.84877)
			(xy 298.471207 -44.908198) (xy 298.455692 -44.966096) (xy 298.432752 -45.021474) (xy 298.40278 -45.073383)
			(xy 298.366289 -45.120935) (xy 298.323902 -45.163318) (xy 298.276346 -45.199805) (xy 298.224434 -45.229772)
			(xy 298.169054 -45.252706) (xy 298.111155 -45.268215) (xy 298.051726 -45.276034) (xy 298.021756 -45.276516)
			(xy 297.992573 -45.276055) (xy 297.93468 -45.268631) (xy 297.878201 -45.253909) (xy 297.824051 -45.232128)
			(xy 297.773108 -45.203641) (xy 297.726199 -45.168911) (xy 297.684085 -45.1285) (xy 297.665394 -45.106082)
			(xy 297.656314 -45.095529) (xy 297.633629 -45.079409) (xy 297.607432 -45.070016) (xy 297.579672 -45.068048)
			(xy 297.552413 -45.073651) (xy 297.527679 -45.086408) (xy 297.507311 -45.105371) (xy 297.492821 -45.129131)
			(xy 297.485288 -45.155922) (xy 297.4848 -45.169836) (xy 297.4848 -47.518254) (xy 299.69456 -47.518254)
			(xy 299.694562 -47.458314) (xy 299.702388 -47.398888) (xy 299.717904 -47.340992) (xy 299.740844 -47.285616)
			(xy 299.770816 -47.233708) (xy 299.807307 -47.186157) (xy 299.849693 -47.143776) (xy 299.897248 -47.10729)
			(xy 299.949159 -47.077323) (xy 300.004537 -47.054388) (xy 300.062435 -47.038879) (xy 300.121862 -47.031059)
			(xy 300.181802 -47.031063) (xy 300.241228 -47.038891) (xy 300.299123 -47.054409) (xy 300.354498 -47.077351)
			(xy 300.406405 -47.107325) (xy 300.453955 -47.143818) (xy 300.496335 -47.186205) (xy 300.532819 -47.233762)
			(xy 300.562784 -47.285673) (xy 300.585717 -47.341052) (xy 300.601224 -47.398951) (xy 300.609042 -47.458378)
			(xy 300.609508 -47.488348) (xy 300.607476 -47.530004) (xy 300.606557 -47.544506) (xy 300.612096 -47.573023)
			(xy 300.625445 -47.598823) (xy 300.645521 -47.619819) (xy 300.670699 -47.634308) (xy 300.698939 -47.641117)
			(xy 300.727953 -47.639695) (xy 300.741842 -47.635414) (xy 300.771862 -47.625819) (xy 300.83403 -47.615486)
			(xy 300.86554 -47.61484) (xy 300.892793 -47.615233) (xy 300.946743 -47.622995) (xy 300.99904 -47.638355)
			(xy 301.048618 -47.661002) (xy 301.094469 -47.690473) (xy 301.13566 -47.726169) (xy 301.171351 -47.767363)
			(xy 301.200818 -47.813217) (xy 301.223459 -47.862798) (xy 301.238814 -47.915096) (xy 301.24657 -47.969047)
			(xy 301.24657 -48.023553) (xy 301.238814 -48.077504) (xy 301.223459 -48.129802) (xy 301.200818 -48.179383)
			(xy 301.171351 -48.225237) (xy 301.13566 -48.266431) (xy 301.094469 -48.302127) (xy 301.048618 -48.331598)
			(xy 300.99904 -48.354245) (xy 300.946743 -48.369605) (xy 300.892793 -48.377367) (xy 300.86554 -48.377856)
			(xy 300.838349 -48.377291) (xy 300.784519 -48.369574) (xy 300.73233 -48.35429) (xy 300.68284 -48.33175)
			(xy 300.637053 -48.30241) (xy 300.595897 -48.266865) (xy 300.560205 -48.225835) (xy 300.530702 -48.180153)
			(xy 300.507986 -48.130744) (xy 300.492517 -48.07861) (xy 300.484608 -48.024807) (xy 300.484032 -47.997618)
			(xy 300.48345 -47.983138) (xy 300.475215 -47.955368) (xy 300.459515 -47.931027) (xy 300.437613 -47.912073)
			(xy 300.411272 -47.900028) (xy 300.382608 -47.895863) (xy 300.353927 -47.899912) (xy 300.340522 -47.905416)
			(xy 300.310735 -47.918259) (xy 300.248452 -47.936379) (xy 300.184233 -47.94551) (xy 300.1518 -47.946056)
			(xy 300.12183 -47.945539) (xy 300.062404 -47.937715) (xy 300.004507 -47.922201) (xy 299.94913 -47.899263)
			(xy 299.897222 -47.869293) (xy 299.849669 -47.832803) (xy 299.807286 -47.790419) (xy 299.770798 -47.742865)
			(xy 299.74083 -47.690955) (xy 299.717894 -47.635578) (xy 299.702382 -47.577681) (xy 299.69456 -47.518254)
			(xy 297.4848 -47.518254) (xy 297.4848 -49.012094) (xy 297.485266 -49.025946) (xy 297.492714 -49.05263)
			(xy 297.507062 -49.076329) (xy 297.527254 -49.095296) (xy 297.551803 -49.108136) (xy 297.578901 -49.113902)
			(xy 297.60655 -49.112169) (xy 297.632716 -49.103065) (xy 297.655469 -49.087261) (xy 297.664632 -49.076864)
			(xy 297.682846 -49.055635) (xy 297.72443 -49.018224) (xy 297.771031 -48.987287) (xy 297.821651 -48.963489)
			(xy 297.875204 -48.94734) (xy 297.930542 -48.939186) (xy 297.95851 -48.938688) (xy 297.985761 -48.939174)
			(xy 298.039708 -48.946932) (xy 298.092002 -48.962288) (xy 298.141579 -48.98493) (xy 298.187429 -49.014397)
			(xy 298.228618 -49.050089) (xy 298.264309 -49.09128) (xy 298.293774 -49.13713) (xy 298.316415 -49.186707)
			(xy 298.33177 -49.239001) (xy 298.339526 -49.292949) (xy 298.339526 -49.347451) (xy 298.33177 -49.401399)
			(xy 298.316415 -49.453693) (xy 298.293774 -49.50327) (xy 298.264309 -49.54912) (xy 298.228618 -49.590311)
			(xy 298.187429 -49.626003) (xy 298.141579 -49.65547) (xy 298.092002 -49.678112) (xy 298.039708 -49.693468)
			(xy 297.985761 -49.701226) (xy 297.95851 -49.701704) (xy 297.930545 -49.701208) (xy 297.875215 -49.693033)
			(xy 297.82167 -49.676871) (xy 297.771057 -49.653068) (xy 297.724459 -49.622134) (xy 297.682875 -49.58473)
			(xy 297.664632 -49.563528) (xy 297.655442 -49.55316) (xy 297.632697 -49.537363) (xy 297.606541 -49.528264)
			(xy 297.578902 -49.526532) (xy 297.551816 -49.532296) (xy 297.527276 -49.54513) (xy 297.507091 -49.56409)
			(xy 297.492747 -49.587778) (xy 297.485301 -49.614451) (xy 297.4848 -49.628298) (xy 297.4848 -52.156868)
			(xy 300.216822 -52.156868) (xy 300.220893 -52.101246) (xy 300.233019 -52.046809) (xy 300.252942 -51.994718)
			(xy 300.280238 -51.946083) (xy 300.314324 -51.90194) (xy 300.354473 -51.863231) (xy 300.399831 -51.83078)
			(xy 300.449431 -51.805279) (xy 300.502215 -51.787272) (xy 300.557058 -51.777142) (xy 300.612792 -51.775105)
			(xy 300.668229 -51.781205) (xy 300.722186 -51.795311) (xy 300.773515 -51.817123) (xy 300.821121 -51.846177)
			(xy 300.863989 -51.881852) (xy 300.901206 -51.923389) (xy 300.931979 -51.969902) (xy 300.955651 -52.020399)
			(xy 300.971719 -52.073806) (xy 300.979839 -52.128982) (xy 300.980348 -52.156868) (xy 300.979839 -52.184754)
			(xy 300.971719 -52.23993) (xy 300.955651 -52.293337) (xy 300.931979 -52.343834) (xy 300.901206 -52.390347)
			(xy 300.863989 -52.431884) (xy 300.821121 -52.467559) (xy 300.773515 -52.496613) (xy 300.722186 -52.518425)
			(xy 300.668229 -52.532531) (xy 300.612792 -52.538631) (xy 300.557058 -52.536594) (xy 300.502215 -52.526464)
			(xy 300.449431 -52.508457) (xy 300.399831 -52.482956) (xy 300.354473 -52.450505) (xy 300.314324 -52.411796)
			(xy 300.280238 -52.367653) (xy 300.252942 -52.319018) (xy 300.233019 -52.266927) (xy 300.220893 -52.21249)
			(xy 300.216822 -52.156868) (xy 297.4848 -52.156868) (xy 297.4848 -53.023516) (xy 297.485269 -53.038149)
			(xy 297.49355 -53.066219) (xy 297.509455 -53.090785) (xy 297.531678 -53.109828) (xy 297.55839 -53.121783)
			(xy 297.587397 -53.125667) (xy 297.616314 -53.121161) (xy 297.642763 -53.108634) (xy 297.653964 -53.099208)
			(xy 297.675042 -53.081123) (xy 297.721447 -53.050609) (xy 297.771783 -53.027142) (xy 297.824989 -53.011217)
			(xy 297.879941 -53.003171) (xy 297.90771 -53.002688) (xy 297.934961 -53.003174) (xy 297.988909 -53.010932)
			(xy 298.041204 -53.026289) (xy 298.090781 -53.048932) (xy 298.116834 -53.065676) (xy 299.636162 -53.065676)
			(xy 299.636162 -53.00574) (xy 299.643985 -52.946318) (xy 299.659498 -52.888425) (xy 299.682434 -52.833052)
			(xy 299.712401 -52.781146) (xy 299.748888 -52.733596) (xy 299.791268 -52.691216) (xy 299.838818 -52.654729)
			(xy 299.890724 -52.624762) (xy 299.946097 -52.601826) (xy 300.00399 -52.586313) (xy 300.063412 -52.57849)
			(xy 300.123348 -52.57849) (xy 300.18277 -52.586313) (xy 300.240663 -52.601826) (xy 300.296036 -52.624762)
			(xy 300.347942 -52.654729) (xy 300.395492 -52.691216) (xy 300.437872 -52.733596) (xy 300.474359 -52.781146)
			(xy 300.504326 -52.833052) (xy 300.527262 -52.888425) (xy 300.542775 -52.946318) (xy 300.550598 -53.00574)
			(xy 300.551088 -53.035708) (xy 300.550598 -53.065676) (xy 300.542775 -53.125098) (xy 300.527262 -53.182991)
			(xy 300.504326 -53.238364) (xy 300.474359 -53.29027) (xy 300.437872 -53.33782) (xy 300.395492 -53.3802)
			(xy 300.347942 -53.416687) (xy 300.296036 -53.446654) (xy 300.240663 -53.46959) (xy 300.18277 -53.485103)
			(xy 300.123348 -53.492926) (xy 300.063412 -53.492926) (xy 300.00399 -53.485103) (xy 299.946097 -53.46959)
			(xy 299.890724 -53.446654) (xy 299.838818 -53.416687) (xy 299.791268 -53.3802) (xy 299.748888 -53.33782)
			(xy 299.712401 -53.29027) (xy 299.682434 -53.238364) (xy 299.659498 -53.182991) (xy 299.643985 -53.125098)
			(xy 299.636162 -53.065676) (xy 298.116834 -53.065676) (xy 298.136631 -53.078399) (xy 298.177821 -53.114092)
			(xy 298.213512 -53.155283) (xy 298.242977 -53.201135) (xy 298.265617 -53.250713) (xy 298.280971 -53.303008)
			(xy 298.288727 -53.356957) (xy 298.288726 -53.411459) (xy 298.280968 -53.465407) (xy 298.265612 -53.517702)
			(xy 298.242969 -53.567279) (xy 298.213502 -53.61313) (xy 298.177809 -53.654319) (xy 298.136618 -53.69001)
			(xy 298.090767 -53.719476) (xy 298.041189 -53.742117) (xy 297.988894 -53.757471) (xy 297.934945 -53.765227)
			(xy 297.880443 -53.765226) (xy 297.826495 -53.757468) (xy 297.7742 -53.742112) (xy 297.724622 -53.71947)
			(xy 297.678772 -53.690003) (xy 297.637582 -53.654311) (xy 297.601891 -53.61312) (xy 297.572425 -53.567269)
			(xy 297.549784 -53.517691) (xy 297.534429 -53.465396) (xy 297.526673 -53.411447) (xy 297.526202 -53.384196)
			(xy 297.52671 -53.363622) (xy 297.526977 -53.35001) (xy 297.521147 -53.323426) (xy 297.508502 -53.299326)
			(xy 297.489941 -53.279422) (xy 297.466782 -53.265127) (xy 297.440669 -53.257456) (xy 297.413458 -53.256955)
			(xy 297.387081 -53.263659) (xy 297.363411 -53.277092) (xy 297.353482 -53.286406) (xy 297.15206 -53.487828)
			(xy 288.7345 -53.487828) (xy 287.934654 -54.287674) (xy 291.411912 -54.287674) (xy 291.415983 -54.232052)
			(xy 291.428109 -54.177615) (xy 291.448032 -54.125524) (xy 291.475328 -54.076889) (xy 291.509414 -54.032746)
			(xy 291.549563 -53.994037) (xy 291.594921 -53.961586) (xy 291.644521 -53.936085) (xy 291.697305 -53.918078)
			(xy 291.752148 -53.907948) (xy 291.807882 -53.905911) (xy 291.863319 -53.912011) (xy 291.917276 -53.926117)
			(xy 291.968605 -53.947929) (xy 292.016211 -53.976983) (xy 292.059079 -54.012658) (xy 292.096296 -54.054195)
			(xy 292.127069 -54.100708) (xy 292.150741 -54.151205) (xy 292.166809 -54.204612) (xy 292.174929 -54.259788)
			(xy 292.175438 -54.287674) (xy 292.174929 -54.31556) (xy 292.173837 -54.32298) (xy 294.418002 -54.32298)
			(xy 294.422073 -54.267358) (xy 294.434199 -54.212921) (xy 294.454122 -54.16083) (xy 294.481418 -54.112195)
			(xy 294.515504 -54.068052) (xy 294.555653 -54.029343) (xy 294.601011 -53.996892) (xy 294.650611 -53.971391)
			(xy 294.703395 -53.953384) (xy 294.758238 -53.943254) (xy 294.813972 -53.941217) (xy 294.869409 -53.947317)
			(xy 294.923366 -53.961423) (xy 294.974695 -53.983235) (xy 295.022301 -54.012289) (xy 295.065169 -54.047964)
			(xy 295.102386 -54.089501) (xy 295.133159 -54.136014) (xy 295.156831 -54.186511) (xy 295.172899 -54.239918)
			(xy 295.181019 -54.295094) (xy 295.181528 -54.32298) (xy 295.181019 -54.350866) (xy 295.172899 -54.406042)
			(xy 295.156831 -54.459449) (xy 295.133159 -54.509946) (xy 295.102386 -54.556459) (xy 295.065169 -54.597996)
			(xy 295.022301 -54.633671) (xy 294.974695 -54.662725) (xy 294.923366 -54.684537) (xy 294.869409 -54.698643)
			(xy 294.813972 -54.704743) (xy 294.758238 -54.702706) (xy 294.703395 -54.692576) (xy 294.650611 -54.674569)
			(xy 294.601011 -54.649068) (xy 294.555653 -54.616617) (xy 294.515504 -54.577908) (xy 294.481418 -54.533765)
			(xy 294.454122 -54.48513) (xy 294.434199 -54.433039) (xy 294.422073 -54.378602) (xy 294.418002 -54.32298)
			(xy 292.173837 -54.32298) (xy 292.166809 -54.370736) (xy 292.150741 -54.424143) (xy 292.127069 -54.47464)
			(xy 292.096296 -54.521153) (xy 292.059079 -54.56269) (xy 292.016211 -54.598365) (xy 291.968605 -54.627419)
			(xy 291.917276 -54.649231) (xy 291.863319 -54.663337) (xy 291.807882 -54.669437) (xy 291.752148 -54.6674)
			(xy 291.697305 -54.65727) (xy 291.644521 -54.639263) (xy 291.594921 -54.613762) (xy 291.549563 -54.581311)
			(xy 291.509414 -54.542602) (xy 291.475328 -54.498459) (xy 291.448032 -54.449824) (xy 291.428109 -54.397733)
			(xy 291.415983 -54.343296) (xy 291.411912 -54.287674) (xy 287.934654 -54.287674) (xy 285.66237 -56.559958)
			(xy 291.299898 -56.559958) (xy 291.303969 -56.504336) (xy 291.316095 -56.449899) (xy 291.336018 -56.397808)
			(xy 291.363314 -56.349173) (xy 291.3974 -56.30503) (xy 291.437549 -56.266321) (xy 291.482907 -56.23387)
			(xy 291.532507 -56.208369) (xy 291.585291 -56.190362) (xy 291.640134 -56.180232) (xy 291.695868 -56.178195)
			(xy 291.751305 -56.184295) (xy 291.805262 -56.198401) (xy 291.856591 -56.220213) (xy 291.904197 -56.249267)
			(xy 291.947065 -56.284942) (xy 291.984282 -56.326479) (xy 292.015055 -56.372992) (xy 292.038727 -56.423489)
			(xy 292.050363 -56.462164) (xy 297.432712 -56.462164) (xy 297.432712 -56.402228) (xy 297.440535 -56.342806)
			(xy 297.456048 -56.284913) (xy 297.478984 -56.22954) (xy 297.508951 -56.177634) (xy 297.545438 -56.130084)
			(xy 297.587818 -56.087704) (xy 297.635368 -56.051217) (xy 297.687274 -56.02125) (xy 297.742647 -55.998314)
			(xy 297.80054 -55.982801) (xy 297.859962 -55.974978) (xy 297.919898 -55.974978) (xy 297.97932 -55.982801)
			(xy 298.037213 -55.998314) (xy 298.092586 -56.02125) (xy 298.144492 -56.051217) (xy 298.192042 -56.087704)
			(xy 298.234422 -56.130084) (xy 298.270909 -56.177634) (xy 298.300876 -56.22954) (xy 298.323812 -56.284913)
			(xy 298.339325 -56.342806) (xy 298.347148 -56.402228) (xy 298.347638 -56.432196) (xy 298.347198 -56.459116)
			(xy 299.643782 -56.459116) (xy 299.643782 -56.39918) (xy 299.651605 -56.339758) (xy 299.667118 -56.281865)
			(xy 299.690054 -56.226492) (xy 299.720021 -56.174586) (xy 299.756508 -56.127036) (xy 299.798888 -56.084656)
			(xy 299.846438 -56.048169) (xy 299.898344 -56.018202) (xy 299.953717 -55.995266) (xy 300.01161 -55.979753)
			(xy 300.071032 -55.97193) (xy 300.130968 -55.97193) (xy 300.19039 -55.979753) (xy 300.248283 -55.995266)
			(xy 300.303656 -56.018202) (xy 300.355562 -56.048169) (xy 300.403112 -56.084656) (xy 300.445492 -56.127036)
			(xy 300.481979 -56.174586) (xy 300.511946 -56.226492) (xy 300.534882 -56.281865) (xy 300.550395 -56.339758)
			(xy 300.558218 -56.39918) (xy 300.558708 -56.429148) (xy 300.558218 -56.459116) (xy 300.550395 -56.518538)
			(xy 300.534882 -56.576431) (xy 300.511946 -56.631804) (xy 300.481979 -56.68371) (xy 300.445492 -56.73126)
			(xy 300.403112 -56.77364) (xy 300.355562 -56.810127) (xy 300.303656 -56.840094) (xy 300.248283 -56.86303)
			(xy 300.19039 -56.878543) (xy 300.130968 -56.886366) (xy 300.071032 -56.886366) (xy 300.01161 -56.878543)
			(xy 299.953717 -56.86303) (xy 299.898344 -56.840094) (xy 299.846438 -56.810127) (xy 299.798888 -56.77364)
			(xy 299.756508 -56.73126) (xy 299.720021 -56.68371) (xy 299.690054 -56.631804) (xy 299.667118 -56.576431)
			(xy 299.651605 -56.518538) (xy 299.643782 -56.459116) (xy 298.347198 -56.459116) (xy 298.347148 -56.462164)
			(xy 298.339325 -56.521586) (xy 298.323812 -56.579479) (xy 298.300876 -56.634852) (xy 298.270909 -56.686758)
			(xy 298.234422 -56.734308) (xy 298.192042 -56.776688) (xy 298.144492 -56.813175) (xy 298.092586 -56.843142)
			(xy 298.037213 -56.866078) (xy 297.97932 -56.881591) (xy 297.919898 -56.889414) (xy 297.859962 -56.889414)
			(xy 297.80054 -56.881591) (xy 297.742647 -56.866078) (xy 297.687274 -56.843142) (xy 297.635368 -56.813175)
			(xy 297.587818 -56.776688) (xy 297.545438 -56.734308) (xy 297.508951 -56.686758) (xy 297.478984 -56.634852)
			(xy 297.456048 -56.579479) (xy 297.440535 -56.521586) (xy 297.432712 -56.462164) (xy 292.050363 -56.462164)
			(xy 292.054795 -56.476896) (xy 292.062915 -56.532072) (xy 292.063424 -56.559958) (xy 292.062915 -56.587844)
			(xy 292.054795 -56.64302) (xy 292.038727 -56.696427) (xy 292.015055 -56.746924) (xy 291.984282 -56.793437)
			(xy 291.947065 -56.834974) (xy 291.904197 -56.870649) (xy 291.856591 -56.899703) (xy 291.805262 -56.921515)
			(xy 291.751305 -56.935621) (xy 291.695868 -56.941721) (xy 291.640134 -56.939684) (xy 291.585291 -56.929554)
			(xy 291.532507 -56.911547) (xy 291.482907 -56.886046) (xy 291.437549 -56.853595) (xy 291.3974 -56.814886)
			(xy 291.363314 -56.770743) (xy 291.336018 -56.722108) (xy 291.316095 -56.670017) (xy 291.303969 -56.61558)
			(xy 291.299898 -56.559958) (xy 285.66237 -56.559958) (xy 284.71876 -57.503568) (xy 279.25268 -57.503568)
			(xy 279.000595 -57.755653) (xy 289.041036 -57.755653) (xy 289.041036 -57.701147) (xy 289.048793 -57.647195)
			(xy 289.064148 -57.594896) (xy 289.08679 -57.545315) (xy 289.116258 -57.499461) (xy 289.151951 -57.458266)
			(xy 289.193143 -57.422571) (xy 289.238996 -57.393101) (xy 289.288576 -57.370456) (xy 289.340873 -57.355097)
			(xy 289.394825 -57.347337) (xy 289.422078 -57.34685) (xy 289.449448 -57.347317) (xy 289.503628 -57.355133)
			(xy 289.556131 -57.370621) (xy 289.605878 -57.393463) (xy 289.651845 -57.423188) (xy 289.672776 -57.44083)
			(xy 289.684104 -57.450066) (xy 289.710661 -57.462242) (xy 289.739578 -57.466415) (xy 289.768495 -57.462242)
			(xy 289.795052 -57.450066) (xy 289.80638 -57.44083) (xy 289.827313 -57.423189) (xy 289.873281 -57.393465)
			(xy 289.923027 -57.370619) (xy 289.975529 -57.355123) (xy 290.029707 -57.347294) (xy 290.084449 -57.347294)
			(xy 290.138627 -57.355123) (xy 290.191129 -57.370619) (xy 290.240875 -57.393465) (xy 290.286843 -57.423189)
			(xy 290.307776 -57.44083) (xy 290.319104 -57.450066) (xy 290.345661 -57.462242) (xy 290.374578 -57.466415)
			(xy 290.403495 -57.462242) (xy 290.430052 -57.450066) (xy 290.44138 -57.44083) (xy 290.462313 -57.423191)
			(xy 290.508285 -57.393479) (xy 290.558032 -57.370642) (xy 290.610533 -57.355151) (xy 290.664709 -57.347323)
			(xy 290.692078 -57.34685) (xy 290.719329 -57.347396) (xy 290.773276 -57.355149) (xy 290.825571 -57.370502)
			(xy 290.875148 -57.39314) (xy 290.920999 -57.422605) (xy 290.96219 -57.458294) (xy 290.997882 -57.499483)
			(xy 291.027349 -57.545332) (xy 291.049991 -57.594908) (xy 291.065346 -57.647202) (xy 291.073103 -57.701149)
			(xy 291.073103 -57.755651) (xy 291.065346 -57.809598) (xy 291.049991 -57.861892) (xy 291.027349 -57.911468)
			(xy 290.997882 -57.957317) (xy 290.96219 -57.998506) (xy 290.920999 -58.034195) (xy 290.875148 -58.06366)
			(xy 290.825571 -58.086298) (xy 290.773276 -58.101651) (xy 290.719329 -58.109404) (xy 290.692078 -58.109866)
			(xy 290.664707 -58.109421) (xy 290.610527 -58.101599) (xy 290.558023 -58.086106) (xy 290.508276 -58.063259)
			(xy 290.462311 -58.03353) (xy 290.44138 -58.015886) (xy 290.430052 -58.00665) (xy 290.403495 -57.994474)
			(xy 290.374578 -57.990301) (xy 290.345661 -57.994474) (xy 290.319104 -58.00665) (xy 290.307776 -58.015886)
			(xy 290.286843 -58.033527) (xy 290.240875 -58.063251) (xy 290.191129 -58.086097) (xy 290.138627 -58.101593)
			(xy 290.084449 -58.109422) (xy 290.029707 -58.109422) (xy 289.975529 -58.101593) (xy 289.923027 -58.086097)
			(xy 289.873281 -58.063251) (xy 289.827313 -58.033527) (xy 289.80638 -58.015886) (xy 289.795052 -58.00665)
			(xy 289.768495 -57.994474) (xy 289.739578 -57.990301) (xy 289.710661 -57.994474) (xy 289.684104 -58.00665)
			(xy 289.672776 -58.015886) (xy 289.651824 -58.033501) (xy 289.605857 -58.063217) (xy 289.556115 -58.086058)
			(xy 289.503618 -58.101554) (xy 289.449446 -58.109389) (xy 289.422078 -58.109866) (xy 289.394825 -58.109463)
			(xy 289.340873 -58.101703) (xy 289.288576 -58.086344) (xy 289.238996 -58.063699) (xy 289.193143 -58.034229)
			(xy 289.151951 -57.998534) (xy 289.116258 -57.957339) (xy 289.08679 -57.911485) (xy 289.064148 -57.861904)
			(xy 289.048793 -57.809605) (xy 289.041036 -57.755653) (xy 279.000595 -57.755653) (xy 278.308308 -58.44794)
			(xy 290.872162 -58.44794) (xy 290.876233 -58.392318) (xy 290.888359 -58.337881) (xy 290.908282 -58.28579)
			(xy 290.935578 -58.237155) (xy 290.969664 -58.193012) (xy 291.009813 -58.154303) (xy 291.055171 -58.121852)
			(xy 291.104771 -58.096351) (xy 291.157555 -58.078344) (xy 291.212398 -58.068214) (xy 291.268132 -58.066177)
			(xy 291.323569 -58.072277) (xy 291.377526 -58.086383) (xy 291.428855 -58.108195) (xy 291.476461 -58.137249)
			(xy 291.519329 -58.172924) (xy 291.556546 -58.214461) (xy 291.587319 -58.260974) (xy 291.610991 -58.311471)
			(xy 291.627059 -58.364878) (xy 291.635179 -58.420054) (xy 291.635688 -58.44794) (xy 291.63547 -58.459878)
			(xy 293.79367 -58.459878) (xy 293.797741 -58.404256) (xy 293.809867 -58.349819) (xy 293.82979 -58.297728)
			(xy 293.857086 -58.249093) (xy 293.891172 -58.20495) (xy 293.931321 -58.166241) (xy 293.976679 -58.13379)
			(xy 294.026279 -58.108289) (xy 294.079063 -58.090282) (xy 294.133906 -58.080152) (xy 294.18964 -58.078115)
			(xy 294.245077 -58.084215) (xy 294.299034 -58.098321) (xy 294.350363 -58.120133) (xy 294.397969 -58.149187)
			(xy 294.440837 -58.184862) (xy 294.478054 -58.226399) (xy 294.508827 -58.272912) (xy 294.532499 -58.323409)
			(xy 294.548567 -58.376816) (xy 294.556687 -58.431992) (xy 294.557196 -58.459878) (xy 294.556687 -58.487764)
			(xy 294.548567 -58.54294) (xy 294.532499 -58.596347) (xy 294.508827 -58.646844) (xy 294.478054 -58.693357)
			(xy 294.440837 -58.734894) (xy 294.397969 -58.770569) (xy 294.350363 -58.799623) (xy 294.299034 -58.821435)
			(xy 294.245077 -58.835541) (xy 294.18964 -58.841641) (xy 294.133906 -58.839604) (xy 294.079063 -58.829474)
			(xy 294.026279 -58.811467) (xy 293.976679 -58.785966) (xy 293.931321 -58.753515) (xy 293.891172 -58.714806)
			(xy 293.857086 -58.670663) (xy 293.82979 -58.622028) (xy 293.809867 -58.569937) (xy 293.797741 -58.5155)
			(xy 293.79367 -58.459878) (xy 291.63547 -58.459878) (xy 291.635179 -58.475826) (xy 291.627059 -58.531002)
			(xy 291.610991 -58.584409) (xy 291.587319 -58.634906) (xy 291.556546 -58.681419) (xy 291.519329 -58.722956)
			(xy 291.476461 -58.758631) (xy 291.428855 -58.787685) (xy 291.377526 -58.809497) (xy 291.323569 -58.823603)
			(xy 291.268132 -58.829703) (xy 291.212398 -58.827666) (xy 291.157555 -58.817536) (xy 291.104771 -58.799529)
			(xy 291.055171 -58.774028) (xy 291.009813 -58.741577) (xy 290.969664 -58.702868) (xy 290.935578 -58.658725)
			(xy 290.908282 -58.61009) (xy 290.888359 -58.557999) (xy 290.876233 -58.503562) (xy 290.872162 -58.44794)
			(xy 278.308308 -58.44794) (xy 274.55114 -62.205108) (xy 273.851878 -62.205108) (xy 273.791182 -62.26556)
			(xy 278.771602 -62.26556) (xy 278.775673 -62.209938) (xy 278.787799 -62.155501) (xy 278.807722 -62.10341)
			(xy 278.835018 -62.054775) (xy 278.869104 -62.010632) (xy 278.909253 -61.971923) (xy 278.954611 -61.939472)
			(xy 279.004211 -61.913971) (xy 279.056995 -61.895964) (xy 279.111838 -61.885834) (xy 279.167572 -61.883797)
			(xy 279.223009 -61.889897) (xy 279.276966 -61.904003) (xy 279.328295 -61.925815) (xy 279.375901 -61.954869)
			(xy 279.418769 -61.990544) (xy 279.455986 -62.032081) (xy 279.486759 -62.078594) (xy 279.510431 -62.129091)
			(xy 279.526499 -62.182498) (xy 279.534619 -62.237674) (xy 279.535128 -62.26556) (xy 279.534619 -62.293446)
			(xy 279.526499 -62.348622) (xy 279.510431 -62.402029) (xy 279.486759 -62.452526) (xy 279.455986 -62.499039)
			(xy 279.418769 -62.540576) (xy 279.375901 -62.576251) (xy 279.328295 -62.605305) (xy 279.276966 -62.627117)
			(xy 279.223009 -62.641223) (xy 279.167572 -62.647323) (xy 279.111838 -62.645286) (xy 279.056995 -62.635156)
			(xy 279.004211 -62.617149) (xy 278.954611 -62.591648) (xy 278.909253 -62.559197) (xy 278.869104 -62.520488)
			(xy 278.835018 -62.476345) (xy 278.807722 -62.42771) (xy 278.787799 -62.375619) (xy 278.775673 -62.321182)
			(xy 278.771602 -62.26556) (xy 273.791182 -62.26556) (xy 273.788632 -62.2681) (xy 273.770586 -62.28551)
			(xy 273.730035 -62.315004) (xy 273.685364 -62.337781) (xy 273.637677 -62.353279) (xy 273.588151 -62.361115)
			(xy 273.56308 -62.361572) (xy 271.463008 -62.361572) (xy 271.244314 -62.580266) (xy 271.244314 -63.877952)
			(xy 278.687789 -63.877952) (xy 278.691811 -63.792232) (xy 278.703842 -63.707264) (xy 278.723778 -63.623797)
			(xy 278.751441 -63.542563) (xy 278.78659 -63.464277) (xy 278.828916 -63.389626) (xy 278.878045 -63.319267)
			(xy 278.933548 -63.253817) (xy 278.994935 -63.193853) (xy 279.061668 -63.1399) (xy 279.13316 -63.092433)
			(xy 279.208782 -63.051869) (xy 279.287871 -63.018565) (xy 279.369731 -62.992813) (xy 279.453642 -62.97484)
			(xy 279.538868 -62.964804) (xy 279.62466 -62.962792) (xy 279.710262 -62.968823) (xy 279.794924 -62.982843)
			(xy 279.877901 -63.004729) (xy 279.958464 -63.03429) (xy 280.035904 -63.071264) (xy 280.109543 -63.115328)
			(xy 280.178731 -63.166094) (xy 280.242862 -63.223115) (xy 280.301371 -63.285891) (xy 280.353744 -63.353871)
			(xy 280.399522 -63.426456) (xy 280.438302 -63.503008) (xy 280.469743 -63.582856) (xy 280.493569 -63.665297)
			(xy 280.50957 -63.749607) (xy 280.517605 -63.835045) (xy 280.518108 -63.877952) (xy 280.517605 -63.920859)
			(xy 280.50957 -64.006297) (xy 280.493569 -64.090607) (xy 280.469743 -64.173048) (xy 280.438302 -64.252896)
			(xy 280.399522 -64.329448) (xy 280.353744 -64.402033) (xy 280.301371 -64.470013) (xy 280.242862 -64.532789)
			(xy 280.178731 -64.58981) (xy 280.109543 -64.640576) (xy 280.035904 -64.68464) (xy 279.958464 -64.721614)
			(xy 279.877901 -64.751175) (xy 279.794924 -64.773061) (xy 279.710262 -64.787081) (xy 279.62466 -64.793112)
			(xy 279.538868 -64.7911) (xy 279.453642 -64.781064) (xy 279.369731 -64.763091) (xy 279.287871 -64.737339)
			(xy 279.208782 -64.704035) (xy 279.13316 -64.663471) (xy 279.061668 -64.616004) (xy 278.994935 -64.562051)
			(xy 278.933548 -64.502087) (xy 278.878045 -64.436637) (xy 278.828916 -64.366278) (xy 278.78659 -64.291627)
			(xy 278.751441 -64.213341) (xy 278.723778 -64.132107) (xy 278.703842 -64.04864) (xy 278.691811 -63.963672)
			(xy 278.687789 -63.877952) (xy 271.244314 -63.877952) (xy 271.244314 -64.965576) (xy 284.071042 -64.965576)
			(xy 284.071042 -64.90564) (xy 284.078865 -64.846218) (xy 284.094378 -64.788325) (xy 284.117314 -64.732952)
			(xy 284.147281 -64.681046) (xy 284.183768 -64.633496) (xy 284.226148 -64.591116) (xy 284.273698 -64.554629)
			(xy 284.325604 -64.524662) (xy 284.380977 -64.501726) (xy 284.43887 -64.486213) (xy 284.498292 -64.47839)
			(xy 284.558228 -64.47839) (xy 284.61765 -64.486213) (xy 284.675543 -64.501726) (xy 284.730916 -64.524662)
			(xy 284.782822 -64.554629) (xy 284.830372 -64.591116) (xy 284.872752 -64.633496) (xy 284.909239 -64.681046)
			(xy 284.939206 -64.732952) (xy 284.962142 -64.788325) (xy 284.977655 -64.846218) (xy 284.985478 -64.90564)
			(xy 284.985968 -64.935608) (xy 284.985478 -64.965576) (xy 284.977655 -65.024998) (xy 284.962142 -65.082891)
			(xy 284.939206 -65.138264) (xy 284.909239 -65.19017) (xy 284.872752 -65.23772) (xy 284.830372 -65.2801)
			(xy 284.782822 -65.316587) (xy 284.730916 -65.346554) (xy 284.675543 -65.36949) (xy 284.61765 -65.385003)
			(xy 284.558228 -65.392826) (xy 284.498292 -65.392826) (xy 284.43887 -65.385003) (xy 284.380977 -65.36949)
			(xy 284.325604 -65.346554) (xy 284.273698 -65.316587) (xy 284.226148 -65.2801) (xy 284.183768 -65.23772)
			(xy 284.147281 -65.19017) (xy 284.117314 -65.138264) (xy 284.094378 -65.082891) (xy 284.078865 -65.024998)
			(xy 284.071042 -64.965576) (xy 271.244314 -64.965576) (xy 271.244314 -66.221864) (xy 271.687798 -66.665348)
			(xy 278.713692 -66.665348) (xy 278.713692 -65.090548) (xy 278.714131 -65.07716) (xy 278.721052 -65.051293)
			(xy 278.734432 -65.0281) (xy 278.753362 -65.009162) (xy 278.776549 -64.99577) (xy 278.802412 -64.988838)
			(xy 278.8158 -64.98844) (xy 280.3906 -64.98844) (xy 280.403994 -64.98879) (xy 280.42987 -64.995726)
			(xy 280.453068 -65.009124) (xy 280.472006 -65.028071) (xy 280.485393 -65.051275) (xy 280.492316 -65.077153)
			(xy 280.492708 -65.090548) (xy 280.492708 -65.996816) (xy 285.130222 -65.996816) (xy 285.130222 -65.93688)
			(xy 285.138045 -65.877458) (xy 285.153558 -65.819565) (xy 285.176494 -65.764192) (xy 285.206461 -65.712286)
			(xy 285.242948 -65.664736) (xy 285.285328 -65.622356) (xy 285.332878 -65.585869) (xy 285.384784 -65.555902)
			(xy 285.440157 -65.532966) (xy 285.49805 -65.517453) (xy 285.557472 -65.50963) (xy 285.617408 -65.50963)
			(xy 285.67683 -65.517453) (xy 285.734723 -65.532966) (xy 285.790096 -65.555902) (xy 285.842002 -65.585869)
			(xy 285.889552 -65.622356) (xy 285.931932 -65.664736) (xy 285.968419 -65.712286) (xy 285.998386 -65.764192)
			(xy 286.021322 -65.819565) (xy 286.036835 -65.877458) (xy 286.044658 -65.93688) (xy 286.045148 -65.966848)
			(xy 286.044658 -65.996816) (xy 286.036835 -66.056238) (xy 286.021322 -66.114131) (xy 285.998386 -66.169504)
			(xy 285.968419 -66.22141) (xy 285.931932 -66.26896) (xy 285.889552 -66.31134) (xy 285.842002 -66.347827)
			(xy 285.790096 -66.377794) (xy 285.734723 -66.40073) (xy 285.67683 -66.416243) (xy 285.617408 -66.424066)
			(xy 285.557472 -66.424066) (xy 285.49805 -66.416243) (xy 285.440157 -66.40073) (xy 285.384784 -66.377794)
			(xy 285.332878 -66.347827) (xy 285.285328 -66.31134) (xy 285.242948 -66.26896) (xy 285.206461 -66.22141)
			(xy 285.176494 -66.169504) (xy 285.153558 -66.114131) (xy 285.138045 -66.056238) (xy 285.130222 -65.996816)
			(xy 280.492708 -65.996816) (xy 280.492708 -66.665348) (xy 280.492313 -66.678735) (xy 280.485373 -66.704596)
			(xy 280.471979 -66.727779) (xy 280.453041 -66.746708) (xy 280.429851 -66.760092) (xy 280.403988 -66.76702)
			(xy 280.3906 -66.767456) (xy 278.8158 -66.767456) (xy 278.802419 -66.766972) (xy 278.776568 -66.760047)
			(xy 278.753388 -66.746669) (xy 278.73446 -66.72775) (xy 278.721071 -66.704577) (xy 278.714135 -66.678729)
			(xy 278.713692 -66.665348) (xy 271.687798 -66.665348) (xy 272.749772 -67.727322) (xy 272.749772 -70.050152)
			(xy 278.662389 -70.050152) (xy 278.666411 -69.964432) (xy 278.678442 -69.879464) (xy 278.698378 -69.795997)
			(xy 278.726041 -69.714763) (xy 278.76119 -69.636477) (xy 278.803516 -69.561826) (xy 278.852645 -69.491467)
			(xy 278.908148 -69.426017) (xy 278.969535 -69.366053) (xy 279.036268 -69.3121) (xy 279.10776 -69.264633)
			(xy 279.183382 -69.224069) (xy 279.262471 -69.190765) (xy 279.344331 -69.165013) (xy 279.428242 -69.14704)
			(xy 279.513468 -69.137004) (xy 279.59926 -69.134992) (xy 279.684862 -69.141023) (xy 279.769524 -69.155043)
			(xy 279.852501 -69.176929) (xy 279.933064 -69.20649) (xy 280.010504 -69.243464) (xy 280.084143 -69.287528)
			(xy 280.153331 -69.338294) (xy 280.217462 -69.395315) (xy 280.275971 -69.458091) (xy 280.328344 -69.526071)
			(xy 280.374122 -69.598656) (xy 280.412902 -69.675208) (xy 280.444343 -69.755056) (xy 280.468169 -69.837497)
			(xy 280.48417 -69.921807) (xy 280.492205 -70.007245) (xy 280.492708 -70.050152) (xy 280.492205 -70.093059)
			(xy 280.48417 -70.178497) (xy 280.468169 -70.262807) (xy 280.444343 -70.345248) (xy 280.412902 -70.425096)
			(xy 280.374122 -70.501648) (xy 280.328344 -70.574233) (xy 280.275971 -70.642213) (xy 280.217462 -70.704989)
			(xy 280.153331 -70.76201) (xy 280.084143 -70.812776) (xy 280.010504 -70.85684) (xy 279.933064 -70.893814)
			(xy 279.852501 -70.923375) (xy 279.769524 -70.945261) (xy 279.684862 -70.959281) (xy 279.59926 -70.965312)
			(xy 279.513468 -70.9633) (xy 279.428242 -70.953264) (xy 279.344331 -70.935291) (xy 279.262471 -70.909539)
			(xy 279.183382 -70.876235) (xy 279.10776 -70.835671) (xy 279.036268 -70.788204) (xy 278.969535 -70.734251)
			(xy 278.908148 -70.674287) (xy 278.852645 -70.608837) (xy 278.803516 -70.538478) (xy 278.76119 -70.463827)
			(xy 278.726041 -70.385541) (xy 278.698378 -70.304307) (xy 278.678442 -70.22084) (xy 278.666411 -70.135872)
			(xy 278.662389 -70.050152) (xy 272.749772 -70.050152) (xy 272.749772 -72.837548) (xy 278.688292 -72.837548)
			(xy 278.688292 -71.262748) (xy 278.688731 -71.24936) (xy 278.695652 -71.223493) (xy 278.709032 -71.2003)
			(xy 278.727962 -71.181362) (xy 278.751149 -71.16797) (xy 278.777012 -71.161038) (xy 278.7904 -71.16064)
			(xy 280.3652 -71.16064) (xy 280.378594 -71.16099) (xy 280.40447 -71.167926) (xy 280.427668 -71.181324)
			(xy 280.446606 -71.200271) (xy 280.459993 -71.223475) (xy 280.466916 -71.249353) (xy 280.467308 -71.262748)
			(xy 280.467308 -72.837548) (xy 280.466913 -72.850935) (xy 280.459973 -72.876796) (xy 280.446579 -72.899979)
			(xy 280.427641 -72.918908) (xy 280.404451 -72.932292) (xy 280.378588 -72.93922) (xy 280.3652 -72.939656)
			(xy 278.7904 -72.939656) (xy 278.777019 -72.939172) (xy 278.751168 -72.932247) (xy 278.727988 -72.918869)
			(xy 278.70906 -72.89995) (xy 278.695671 -72.876777) (xy 278.688735 -72.850929) (xy 278.688292 -72.837548)
			(xy 272.749772 -72.837548) (xy 272.749772 -74.589132) (xy 272.871438 -74.710798) (xy 281.674824 -74.710798)
		)
		(stroke
			(width 0)
			(type solid)
		)
		(fill yes)
		(layer "B.Cu")
		(net "P1V05_PCH_AUX")
	)
	(gr_poly
		(pts
			(xy 39.52494 -330.065888) (xy 67.10426 -330.065888) (xy 67.429888 -329.74026) (xy 67.429888 -320.21018)
			(xy 67.357498 -320.13779) (xy 63.798958 -320.13779) (xy 63.787782 -320.143886) (xy 63.761644 -320.157351)
			(xy 63.706018 -320.176392) (xy 63.648016 -320.186012) (xy 63.618618 -320.186558) (xy 63.589226 -320.185954)
			(xy 63.531237 -320.176314) (xy 63.475609 -320.157309) (xy 63.449454 -320.143886) (xy 63.438278 -320.13779)
			(xy 63.33617 -320.13779) (xy 63.33617 -320.20764) (xy 63.348616 -320.222118) (xy 63.369819 -320.247239)
			(xy 63.40555 -320.302416) (xy 63.433013 -320.36214) (xy 63.451642 -320.425181) (xy 63.461053 -320.49024)
			(xy 63.461646 -320.523108) (xy 63.461155 -320.553076) (xy 63.453332 -320.6125) (xy 63.437819 -320.670394)
			(xy 63.414883 -320.725768) (xy 63.384915 -320.777675) (xy 63.348429 -320.825227) (xy 63.306049 -320.86761)
			(xy 63.2585 -320.904099) (xy 63.206595 -320.934069) (xy 63.151222 -320.957009) (xy 63.093329 -320.972526)
			(xy 63.033906 -320.980354) (xy 63.003938 -320.980816) (xy 62.974531 -320.980365) (xy 62.916202 -320.972834)
			(xy 62.859318 -320.957893) (xy 62.804818 -320.935787) (xy 62.753598 -320.906881) (xy 62.706505 -320.871651)
			(xy 62.664312 -320.830677) (xy 62.627718 -320.784636) (xy 62.597323 -320.734286) (xy 62.57363 -320.680456)
			(xy 62.557028 -320.624034) (xy 62.547792 -320.565951) (xy 62.546484 -320.53657) (xy 62.545511 -320.521643)
			(xy 62.536001 -320.493299) (xy 62.518687 -320.468924) (xy 62.495056 -320.450609) (xy 62.467132 -320.439925)
			(xy 62.437311 -320.437787) (xy 62.408149 -320.444379) (xy 62.394846 -320.451226) (xy 62.369803 -320.464805)
			(xy 62.317 -320.486181) (xy 62.261896 -320.50063) (xy 62.205397 -320.507916) (xy 62.176914 -320.508376)
			(xy 61.996066 -320.508376) (xy 61.966947 -320.507918) (xy 61.909206 -320.500311) (xy 61.852954 -320.485231)
			(xy 61.799151 -320.462937) (xy 61.748718 -320.43381) (xy 61.70252 -320.398349) (xy 61.681614 -320.378074)
			(xy 61.441076 -320.13779) (xy 59.985656 -320.13779) (xy 59.97829 -320.14033) (xy 59.977528 -320.140584)
			(xy 59.942222 -320.189098) (xy 59.973972 -320.236088) (xy 59.998441 -320.24635) (xy 60.044282 -320.273066)
			(xy 60.085645 -320.306296) (xy 60.121614 -320.345301) (xy 60.15139 -320.389216) (xy 60.174312 -320.437068)
			(xy 60.189872 -320.487793) (xy 60.197725 -320.540267) (xy 60.198254 -320.566796) (xy 60.197705 -320.594781)
			(xy 60.188951 -320.650061) (xy 60.171658 -320.703291) (xy 60.14625 -320.753162) (xy 60.113355 -320.798444)
			(xy 60.073782 -320.838023) (xy 60.028504 -320.870924) (xy 59.978638 -320.896338) (xy 59.92541 -320.913639)
			(xy 59.870131 -320.922401) (xy 59.842146 -320.922904) (xy 59.815103 -320.922397) (xy 59.76164 -320.91421)
			(xy 59.71003 -320.898032) (xy 59.661461 -320.874236) (xy 59.617048 -320.843368) (xy 59.577814 -320.80614)
			(xy 59.544661 -320.763406) (xy 59.518351 -320.71615) (xy 59.50839 -320.691002) (xy 59.50458 -320.680588)
			(xy 59.157108 -320.333116) (xy 59.136026 -320.333116) (xy 59.104629 -320.332574) (xy 59.04243 -320.323946)
			(xy 58.981992 -320.306904) (xy 58.924447 -320.281767) (xy 58.870876 -320.249006) (xy 58.822281 -320.209235)
			(xy 58.779574 -320.163199) (xy 58.761122 -320.13779) (xy 56.27243 -320.13779) (xy 56.25211 -320.157856)
			(xy 56.25084 -320.186304) (xy 56.248932 -320.21659) (xy 56.238118 -320.276304) (xy 56.219507 -320.334064)
			(xy 56.193426 -320.388859) (xy 56.160333 -320.439726) (xy 56.120808 -320.485775) (xy 56.075545 -320.526196)
			(xy 56.025337 -320.560281) (xy 55.971065 -320.587433) (xy 55.913681 -320.607174) (xy 55.854192 -320.619159)
			(xy 55.79364 -320.623178) (xy 55.733088 -320.619159) (xy 55.673599 -320.607174) (xy 55.616215 -320.587433)
			(xy 55.561943 -320.560281) (xy 55.511735 -320.526196) (xy 55.466472 -320.485775) (xy 55.426947 -320.439726)
			(xy 55.393854 -320.388859) (xy 55.367773 -320.334064) (xy 55.349162 -320.276304) (xy 55.338348 -320.21659)
			(xy 55.33644 -320.186304) (xy 55.334154 -320.13779) (xy 54.69636 -320.13779) (xy 54.689502 -320.139822)
			(xy 54.659114 -320.148055) (xy 54.596775 -320.156854) (xy 54.565296 -320.157348) (xy 54.533818 -320.156834)
			(xy 54.471482 -320.148034) (xy 54.44109 -320.139822) (xy 54.434232 -320.13779) (xy 52.89296 -320.13779)
			(xy 52.885594 -320.14033) (xy 52.852436 -320.150237) (xy 52.784051 -320.160829) (xy 52.74945 -320.161412)
			(xy 52.640738 -320.161412) (xy 52.626113 -320.161898) (xy 52.598063 -320.170196) (xy 52.57351 -320.186095)
			(xy 52.554463 -320.208295) (xy 52.54248 -320.234979) (xy 52.538541 -320.263964) (xy 52.542969 -320.292878)
			(xy 52.555401 -320.319355) (xy 52.564792 -320.330576) (xy 52.581589 -320.350218) (xy 52.609923 -320.393439)
			(xy 52.631716 -320.440301) (xy 52.646508 -320.489819) (xy 52.653991 -320.540956) (xy 52.654454 -320.566796)
			(xy 52.653905 -320.594781) (xy 52.645151 -320.650061) (xy 52.627858 -320.703291) (xy 52.60245 -320.753162)
			(xy 52.569555 -320.798444) (xy 52.529982 -320.838023) (xy 52.484704 -320.870924) (xy 52.434838 -320.896338)
			(xy 52.38161 -320.913639) (xy 52.326331 -320.922401) (xy 52.298346 -320.922904) (xy 52.297838 -320.922904)
			(xy 52.272416 -320.922432) (xy 52.222095 -320.915159) (xy 52.173321 -320.900799) (xy 52.15001 -320.890646)
			(xy 52.140104 -320.88582) (xy 51.900328 -320.88582) (xy 51.878699 -320.907337) (xy 51.830733 -320.945036)
			(xy 51.778185 -320.976031) (xy 51.721985 -320.999773) (xy 51.663131 -321.015842) (xy 51.602664 -321.023952)
			(xy 51.57216 -321.024504) (xy 51.542194 -321.024011) (xy 51.482776 -321.016184) (xy 51.424887 -321.000668)
			(xy 51.369519 -320.97773) (xy 51.317618 -320.94776) (xy 51.270073 -320.911274) (xy 51.227697 -320.868894)
			(xy 51.191215 -320.821345) (xy 51.161251 -320.769441) (xy 51.138318 -320.714071) (xy 51.122807 -320.656181)
			(xy 51.114986 -320.596762) (xy 51.114452 -320.566796) (xy 51.114748 -320.544032) (xy 51.119329 -320.498734)
			(xy 51.123596 -320.476372) (xy 51.126084 -320.46153) (xy 51.123272 -320.431583) (xy 51.111859 -320.403754)
			(xy 51.092834 -320.380456) (xy 51.067848 -320.36371) (xy 51.039068 -320.354969) (xy 51.024028 -320.354452)
			(xy 50.725832 -320.354452) (xy 50.700764 -320.353981) (xy 50.651246 -320.346126) (xy 50.603566 -320.330621)
			(xy 50.5589 -320.307847) (xy 50.518347 -320.278365) (xy 50.50028 -320.26098) (xy 50.376836 -320.13779)
			(xy 48.30445 -320.13779) (xy 48.288702 -320.153284) (xy 48.286924 -320.185796) (xy 48.284784 -320.215897)
			(xy 48.273578 -320.275192) (xy 48.254676 -320.3325) (xy 48.228406 -320.386827) (xy 48.195223 -320.437231)
			(xy 48.155704 -320.482835) (xy 48.110534 -320.52285) (xy 48.060497 -320.556582) (xy 48.00646 -320.583444)
			(xy 47.949362 -320.602972) (xy 47.890192 -320.614825) (xy 47.829978 -320.618799) (xy 47.769764 -320.614825)
			(xy 47.710594 -320.602972) (xy 47.653496 -320.583444) (xy 47.599459 -320.556582) (xy 47.549422 -320.52285)
			(xy 47.504252 -320.482835) (xy 47.464733 -320.437231) (xy 47.43155 -320.386827) (xy 47.40528 -320.3325)
			(xy 47.386378 -320.275192) (xy 47.375172 -320.215897) (xy 47.373032 -320.185796) (xy 47.370238 -320.13779)
			(xy 47.19447 -320.13779) (xy 47.18304 -320.143886) (xy 47.158492 -320.156764) (xy 47.106886 -320.177009)
			(xy 47.053164 -320.190684) (xy 46.998159 -320.197578) (xy 46.970442 -320.197988) (xy 46.969934 -320.197988)
			(xy 46.940683 -320.197502) (xy 46.882691 -320.189795) (xy 46.826207 -320.174562) (xy 46.772203 -320.152065)
			(xy 46.746668 -320.13779) (xy 45.41266 -320.13779) (xy 45.405294 -320.14033) (xy 45.372136 -320.150237)
			(xy 45.303751 -320.160829) (xy 45.26915 -320.161412) (xy 45.096938 -320.161412) (xy 45.082313 -320.161898)
			(xy 45.054263 -320.170196) (xy 45.02971 -320.186095) (xy 45.010663 -320.208295) (xy 44.99868 -320.234979)
			(xy 44.994741 -320.263964) (xy 44.999169 -320.292878) (xy 45.011601 -320.319355) (xy 45.020992 -320.330576)
			(xy 45.037789 -320.350218) (xy 45.066123 -320.393439) (xy 45.087916 -320.440301) (xy 45.102708 -320.489819)
			(xy 45.110191 -320.540956) (xy 45.110654 -320.566796) (xy 45.110105 -320.594781) (xy 45.101351 -320.650061)
			(xy 45.084058 -320.703291) (xy 45.05865 -320.753162) (xy 45.025755 -320.798444) (xy 44.986182 -320.838023)
			(xy 44.940904 -320.870924) (xy 44.891038 -320.896338) (xy 44.83781 -320.913639) (xy 44.782531 -320.922401)
			(xy 44.754546 -320.922904) (xy 44.727503 -320.922397) (xy 44.67404 -320.91421) (xy 44.62243 -320.898032)
			(xy 44.573861 -320.874236) (xy 44.529448 -320.843368) (xy 44.490214 -320.80614) (xy 44.457061 -320.763406)
			(xy 44.430751 -320.71615) (xy 44.42079 -320.691002) (xy 44.41698 -320.680588) (xy 44.265596 -320.529204)
			(xy 44.238164 -320.5353) (xy 44.213349 -320.540538) (xy 44.16294 -320.546133) (xy 44.13758 -320.546476)
			(xy 44.106142 -320.545954) (xy 44.043859 -320.537346) (xy 43.98334 -320.520296) (xy 43.925724 -320.495123)
			(xy 43.872095 -320.462302) (xy 43.823463 -320.42245) (xy 43.780742 -320.376317) (xy 43.744737 -320.324772)
			(xy 43.716126 -320.268784) (xy 43.695445 -320.209407) (xy 43.688762 -320.178684) (xy 43.680634 -320.13779)
			(xy 40.70731 -320.13779) (xy 40.685713 -320.159173) (xy 40.637849 -320.196627) (xy 40.585448 -320.227414)
			(xy 40.529432 -320.250991) (xy 40.470787 -320.266943) (xy 40.410546 -320.274991) (xy 40.34977 -320.274991)
			(xy 40.289529 -320.266943) (xy 40.230884 -320.250991) (xy 40.174868 -320.227414) (xy 40.122467 -320.196627)
			(xy 40.074603 -320.159173) (xy 40.053006 -320.13779) (xy 37.624004 -320.13779) (xy 37.616638 -320.14033)
			(xy 37.583479 -320.150233) (xy 37.515095 -320.160816) (xy 37.480494 -320.161412) (xy 37.359844 -320.161412)
			(xy 37.359844 -320.24193) (xy 37.385498 -320.256662) (xy 37.408712 -320.27029) (xy 37.451113 -320.303449)
			(xy 37.488037 -320.342616) (xy 37.518641 -320.386897) (xy 37.542227 -320.435283) (xy 37.558256 -320.486668)
			(xy 37.566364 -320.539882) (xy 37.566854 -320.566796) (xy 37.566366 -320.593658) (xy 37.558299 -320.646774)
			(xy 37.542348 -320.698076) (xy 37.518875 -320.746402) (xy 37.488412 -320.790655) (xy 37.451649 -320.829832)
			(xy 37.40942 -320.863045) (xy 37.362683 -320.88954) (xy 37.337746 -320.899536) (xy 37.327586 -320.903346)
			(xy 37.309298 -320.92138) (xy 37.291249 -320.938785) (xy 37.250695 -320.968267) (xy 37.206024 -320.991033)
			(xy 37.158338 -321.006522) (xy 37.108815 -321.014351) (xy 37.083746 -321.014852) (xy 36.822888 -321.014852)
			(xy 36.801262 -321.036374) (xy 36.753299 -321.074085) (xy 36.700752 -321.105092) (xy 36.644553 -321.128845)
			(xy 36.585697 -321.144924) (xy 36.525226 -321.153043) (xy 36.49472 -321.153536) (xy 36.464751 -321.153047)
			(xy 36.405325 -321.145226) (xy 36.347428 -321.129716) (xy 36.292051 -321.106781) (xy 36.240142 -321.076815)
			(xy 36.192588 -321.040329) (xy 36.150203 -320.997948) (xy 36.113712 -320.950398) (xy 36.08374 -320.898492)
			(xy 36.0608 -320.843117) (xy 36.045283 -320.785222) (xy 36.037456 -320.725797) (xy 36.037012 -320.695828)
			(xy 36.037547 -320.664597) (xy 36.04605 -320.602717) (xy 36.062887 -320.542567) (xy 36.087746 -320.485265)
			(xy 36.120166 -320.431875) (xy 36.159543 -320.383389) (xy 36.205148 -320.340708) (xy 36.230306 -320.322194)
			(xy 36.241646 -320.31354) (xy 36.259405 -320.29123) (xy 36.270304 -320.264881) (xy 36.273493 -320.236546)
			(xy 36.268726 -320.208433) (xy 36.256371 -320.182734) (xy 36.237394 -320.161451) (xy 36.213273 -320.146245)
			(xy 36.185888 -320.138299) (xy 36.171632 -320.13779) (xy 33.16351 -320.13779) (xy 33.141913 -320.159173)
			(xy 33.094049 -320.196627) (xy 33.041648 -320.227414) (xy 32.985632 -320.250991) (xy 32.926987 -320.266943)
			(xy 32.866746 -320.274991) (xy 32.80597 -320.274991) (xy 32.745729 -320.266943) (xy 32.687084 -320.250991)
			(xy 32.631068 -320.227414) (xy 32.578667 -320.196627) (xy 32.530803 -320.159173) (xy 32.509206 -320.13779)
			(xy 30.33776 -320.13779) (xy 30.330394 -320.14033) (xy 30.297236 -320.150237) (xy 30.228851 -320.160829)
			(xy 30.19425 -320.161412) (xy 29.902404 -320.161412) (xy 29.892369 -320.161834) (xy 29.873831 -320.169525)
			(xy 29.859656 -320.183733) (xy 29.85201 -320.20229) (xy 29.85206 -320.22236) (xy 29.859798 -320.240878)
			(xy 29.86659 -320.24828) (xy 29.892498 -320.274442) (xy 29.908281 -320.290715) (xy 29.935564 -320.326919)
			(xy 29.946854 -320.346578) (xy 29.964734 -320.37029) (xy 29.993179 -320.422419) (xy 30.012592 -320.478541)
			(xy 30.022434 -320.537104) (xy 30.023054 -320.566796) (xy 30.022505 -320.594781) (xy 30.013751 -320.650061)
			(xy 29.996458 -320.703291) (xy 29.97105 -320.753162) (xy 29.938155 -320.798444) (xy 29.898582 -320.838023)
			(xy 29.853304 -320.870924) (xy 29.803438 -320.896338) (xy 29.75021 -320.913639) (xy 29.694931 -320.922401)
			(xy 29.666946 -320.922904) (xy 29.641284 -320.922458) (xy 29.59049 -320.915095) (xy 29.541281 -320.900513)
			(xy 29.494675 -320.879016) (xy 29.45164 -320.851049) (xy 29.413066 -320.817193) (xy 29.379754 -320.778147)
			(xy 29.352395 -320.734723) (xy 29.331555 -320.68782) (xy 29.317666 -320.63841) (xy 29.313886 -320.613024)
			(xy 29.3116 -320.596006) (xy 28.967938 -320.252344) (xy 28.947618 -320.251582) (xy 28.915965 -320.250112)
			(xy 28.85349 -320.239531) (xy 28.793071 -320.220436) (xy 28.735862 -320.193193) (xy 28.682956 -320.158321)
			(xy 28.65882 -320.13779) (xy 25.61971 -320.13779) (xy 25.598113 -320.159173) (xy 25.550249 -320.196627)
			(xy 25.497848 -320.227414) (xy 25.441832 -320.250991) (xy 25.383187 -320.266943) (xy 25.322946 -320.274991)
			(xy 25.26217 -320.274991) (xy 25.201929 -320.266943) (xy 25.143284 -320.250991) (xy 25.087268 -320.227414)
			(xy 25.034867 -320.196627) (xy 24.987003 -320.159173) (xy 24.965406 -320.13779) (xy 22.536404 -320.13779)
			(xy 22.529038 -320.14033) (xy 22.495879 -320.150233) (xy 22.427495 -320.160816) (xy 22.392894 -320.161412)
			(xy 22.338284 -320.161412) (xy 22.338284 -320.232786) (xy 22.352508 -320.247772) (xy 22.371238 -320.267922)
			(xy 22.40218 -320.313402) (xy 22.424857 -320.363518) (xy 22.432264 -320.390012) (xy 22.447014 -320.41712)
			(xy 22.467968 -320.47516) (xy 22.478613 -320.535943) (xy 22.479254 -320.566796) (xy 22.478705 -320.594781)
			(xy 22.469951 -320.650061) (xy 22.452658 -320.703291) (xy 22.42725 -320.753162) (xy 22.394355 -320.798444)
			(xy 22.354782 -320.838023) (xy 22.309504 -320.870924) (xy 22.259638 -320.896338) (xy 22.20641 -320.913639)
			(xy 22.151131 -320.922401) (xy 22.123146 -320.922904) (xy 22.096018 -320.922397) (xy 22.04239 -320.914169)
			(xy 21.990633 -320.897897) (xy 21.941944 -320.873958) (xy 21.897454 -320.842906) (xy 21.858191 -320.805462)
			(xy 21.825067 -320.762492) (xy 21.798849 -320.714992) (xy 21.780143 -320.664063) (xy 21.769384 -320.610885)
			(xy 21.767546 -320.583814) (xy 21.76653 -320.564256) (xy 21.441918 -320.239644) (xy 21.421598 -320.238882)
			(xy 21.391909 -320.237529) (xy 21.33323 -320.228103) (xy 21.276262 -320.211171) (xy 21.221959 -320.187019)
			(xy 21.171233 -320.156051) (xy 21.147786 -320.13779) (xy 18.07591 -320.13779) (xy 18.054313 -320.159173)
			(xy 18.006449 -320.196627) (xy 17.954048 -320.227414) (xy 17.898032 -320.250991) (xy 17.839387 -320.266943)
			(xy 17.779146 -320.274991) (xy 17.71837 -320.274991) (xy 17.658129 -320.266943) (xy 17.599484 -320.250991)
			(xy 17.543468 -320.227414) (xy 17.491067 -320.196627) (xy 17.443203 -320.159173) (xy 17.421606 -320.13779)
			(xy 15.27556 -320.13779) (xy 15.268194 -320.14033) (xy 15.235036 -320.150237) (xy 15.166651 -320.160829)
			(xy 15.13205 -320.161412) (xy 14.948662 -320.161412) (xy 14.933605 -320.16196) (xy 14.904803 -320.17075)
			(xy 14.879815 -320.187555) (xy 14.860812 -320.210916) (xy 14.849446 -320.238802) (xy 14.846703 -320.26879)
			(xy 14.852822 -320.298275) (xy 14.859508 -320.31178) (xy 14.869712 -320.331278) (xy 14.885265 -320.372446)
			(xy 14.890496 -320.393822) (xy 14.904602 -320.420451) (xy 14.924635 -320.477279) (xy 14.934813 -320.536669)
			(xy 14.935454 -320.566796) (xy 14.934905 -320.594781) (xy 14.926151 -320.650061) (xy 14.908858 -320.703291)
			(xy 14.88345 -320.753162) (xy 14.850555 -320.798444) (xy 14.810982 -320.838023) (xy 14.765704 -320.870924)
			(xy 14.715838 -320.896338) (xy 14.66261 -320.913639) (xy 14.607331 -320.922401) (xy 14.579346 -320.922904)
			(xy 14.551985 -320.922407) (xy 14.497906 -320.91404) (xy 14.445745 -320.897497) (xy 14.39673 -320.873166)
			(xy 14.352014 -320.841622) (xy 14.312653 -320.803607) (xy 14.279572 -320.760017) (xy 14.253551 -320.711877)
			(xy 14.235202 -320.660323) (xy 14.224959 -320.606569) (xy 14.223492 -320.579242) (xy 14.22273 -320.559176)
			(xy 13.880338 -320.216784) (xy 13.860018 -320.216022) (xy 13.827718 -320.214509) (xy 13.763996 -320.203528)
			(xy 13.70245 -320.183699) (xy 13.644302 -320.155417) (xy 13.617194 -320.13779) (xy 10.483342 -320.13779)
			(xy 10.457211 -320.156023) (xy 10.40091 -320.185857) (xy 10.341014 -320.20759) (xy 10.278681 -320.2208)
			(xy 10.215118 -320.225232) (xy 10.151555 -320.2208) (xy 10.089222 -320.20759) (xy 10.029326 -320.185857)
			(xy 9.973025 -320.156023) (xy 9.946894 -320.13779) (xy 7.72414 -320.13779) (xy 7.716774 -320.14033)
			(xy 7.683616 -320.150235) (xy 7.615231 -320.160824) (xy 7.58063 -320.161412) (xy 7.511796 -320.161412)
			(xy 7.476998 -320.19621) (xy 7.476998 -321.027552) (xy 7.3406 -321.16395) (xy 6.799326 -321.16395)
			(xy 6.799072 -321.164204) (xy 5.894324 -321.164204) (xy 5.765038 -321.29349) (xy 5.765038 -323.438266)
			(xy 6.996176 -323.438266) (xy 6.996176 -321.957446) (xy 7.272274 -321.681348) (xy 9.007094 -321.681348)
			(xy 9.283192 -321.957446) (xy 9.283192 -323.438266) (xy 11.060176 -323.438266) (xy 11.060176 -321.957446)
			(xy 11.336274 -321.681348) (xy 13.071094 -321.681348) (xy 13.347192 -321.957446) (xy 13.347192 -323.438266)
			(xy 14.539976 -323.438266) (xy 14.539976 -321.957446) (xy 14.816074 -321.681348) (xy 16.550894 -321.681348)
			(xy 16.826992 -321.957446) (xy 16.826992 -323.438266) (xy 18.603976 -323.438266) (xy 18.603976 -321.957446)
			(xy 18.880074 -321.681348) (xy 20.614894 -321.681348) (xy 20.890992 -321.957446) (xy 20.890992 -323.438266)
			(xy 22.083776 -323.438266) (xy 22.083776 -321.957446) (xy 22.359874 -321.681348) (xy 24.094694 -321.681348)
			(xy 24.370792 -321.957446) (xy 24.370792 -323.438266) (xy 26.147776 -323.438266) (xy 26.147776 -321.957446)
			(xy 26.423874 -321.681348) (xy 28.158694 -321.681348) (xy 28.434792 -321.957446) (xy 28.434792 -323.438266)
			(xy 29.627576 -323.438266) (xy 29.627576 -321.957446) (xy 29.903674 -321.681348) (xy 31.638494 -321.681348)
			(xy 31.914592 -321.957446) (xy 31.914592 -323.438266) (xy 33.691576 -323.438266) (xy 33.691576 -321.957446)
			(xy 33.967674 -321.681348) (xy 35.702494 -321.681348) (xy 35.978592 -321.957446) (xy 35.978592 -323.438266)
			(xy 37.171376 -323.438266) (xy 37.171376 -321.957446) (xy 37.447474 -321.681348) (xy 39.182294 -321.681348)
			(xy 39.458392 -321.957446) (xy 39.458392 -323.438266) (xy 41.235376 -323.438266) (xy 41.235376 -321.957446)
			(xy 41.511474 -321.681348) (xy 43.246294 -321.681348) (xy 43.522392 -321.957446) (xy 43.522392 -323.438266)
			(xy 44.715176 -323.438266) (xy 44.715176 -321.957446) (xy 44.991274 -321.681348) (xy 46.726094 -321.681348)
			(xy 47.002192 -321.957446) (xy 47.002192 -323.438266) (xy 46.822868 -323.61759) (xy 48.340264 -323.61759)
			(xy 48.340264 -321.945254) (xy 48.603916 -321.681348) (xy 50.790094 -321.681348) (xy 51.066192 -321.957446)
			(xy 51.066192 -323.438266) (xy 50.848514 -323.655944) (xy 51.875944 -323.655944) (xy 51.875944 -322.053458)
			(xy 52.248054 -321.681348) (xy 54.269894 -321.681348) (xy 54.545992 -321.957446) (xy 54.545992 -323.438266)
			(xy 56.322976 -323.438266) (xy 56.322976 -321.957446) (xy 56.599074 -321.681348) (xy 58.333894 -321.681348)
			(xy 58.609992 -321.957446) (xy 58.609992 -323.438266) (xy 59.802776 -323.438266) (xy 59.802776 -321.957446)
			(xy 60.078874 -321.681348) (xy 61.813694 -321.681348) (xy 62.089792 -321.957446) (xy 62.089792 -323.438266)
			(xy 63.866776 -323.438266) (xy 63.866776 -321.957446) (xy 64.142874 -321.681348) (xy 65.877694 -321.681348)
			(xy 66.153792 -321.957446) (xy 66.153792 -323.438266) (xy 65.623694 -323.968364) (xy 64.396874 -323.968364)
			(xy 63.866776 -323.438266) (xy 62.089792 -323.438266) (xy 61.559694 -323.968364) (xy 60.915296 -323.968364)
			(xy 60.89446 -323.983735) (xy 60.849228 -324.008932) (xy 60.800827 -324.027319) (xy 60.750274 -324.038508)
			(xy 60.698634 -324.042264) (xy 60.646994 -324.038508) (xy 60.596441 -324.027319) (xy 60.54804 -324.008932)
			(xy 60.502808 -323.983735) (xy 60.481972 -323.968364) (xy 60.332874 -323.968364) (xy 59.802776 -323.438266)
			(xy 58.609992 -323.438266) (xy 58.079894 -323.968364) (xy 56.853074 -323.968364) (xy 56.322976 -323.438266)
			(xy 54.545992 -323.438266) (xy 54.015894 -323.968364) (xy 52.188364 -323.968364) (xy 51.875944 -323.655944)
			(xy 50.848514 -323.655944) (xy 50.536094 -323.968364) (xy 48.690784 -323.968364) (xy 48.340264 -323.61759)
			(xy 46.822868 -323.61759) (xy 46.472094 -323.968364) (xy 45.245274 -323.968364) (xy 44.715176 -323.438266)
			(xy 43.522392 -323.438266) (xy 42.992294 -323.968364) (xy 41.765474 -323.968364) (xy 41.235376 -323.438266)
			(xy 39.458392 -323.438266) (xy 38.928294 -323.968364) (xy 37.701474 -323.968364) (xy 37.171376 -323.438266)
			(xy 35.978592 -323.438266) (xy 35.448494 -323.968364) (xy 34.221674 -323.968364) (xy 33.691576 -323.438266)
			(xy 31.914592 -323.438266) (xy 31.384494 -323.968364) (xy 30.157674 -323.968364) (xy 29.627576 -323.438266)
			(xy 28.434792 -323.438266) (xy 27.904694 -323.968364) (xy 26.677874 -323.968364) (xy 26.147776 -323.438266)
			(xy 24.370792 -323.438266) (xy 23.840694 -323.968364) (xy 22.613874 -323.968364) (xy 22.083776 -323.438266)
			(xy 20.890992 -323.438266) (xy 20.360894 -323.968364) (xy 19.134074 -323.968364) (xy 18.603976 -323.438266)
			(xy 16.826992 -323.438266) (xy 16.296894 -323.968364) (xy 15.070074 -323.968364) (xy 14.539976 -323.438266)
			(xy 13.347192 -323.438266) (xy 12.817094 -323.968364) (xy 11.590274 -323.968364) (xy 11.060176 -323.438266)
			(xy 9.283192 -323.438266) (xy 8.753094 -323.968364) (xy 7.526274 -323.968364) (xy 6.996176 -323.438266)
			(xy 5.765038 -323.438266) (xy 5.765038 -327.06666) (xy 8.563862 -327.06666) (xy 8.567905 -326.976634)
			(xy 8.580002 -326.887332) (xy 8.600055 -326.799474) (xy 8.627902 -326.713768) (xy 8.663321 -326.630903)
			(xy 8.706024 -326.551546) (xy 8.75567 -326.476337) (xy 8.811857 -326.40588) (xy 8.874133 -326.340744)
			(xy 8.941998 -326.281453) (xy 9.014904 -326.228483) (xy 9.092265 -326.182262) (xy 9.173458 -326.143162)
			(xy 9.257829 -326.111497) (xy 9.344698 -326.087522) (xy 9.433367 -326.071431) (xy 9.523121 -326.063353)
			(xy 9.56818 -326.062848) (xy 10.81278 -326.062848) (xy 10.857838 -326.063361) (xy 10.947592 -326.071439)
			(xy 11.03626 -326.08753) (xy 11.123129 -326.111504) (xy 11.207499 -326.143169) (xy 11.288691 -326.182269)
			(xy 11.366051 -326.22849) (xy 11.438957 -326.281459) (xy 11.506821 -326.34075) (xy 11.569097 -326.405886)
			(xy 11.625284 -326.476341) (xy 11.674929 -326.55155) (xy 11.717632 -326.630906) (xy 11.75305 -326.713771)
			(xy 11.780898 -326.799477) (xy 11.80095 -326.887334) (xy 11.813047 -326.976634) (xy 11.81709 -327.06666)
			(xy 16.107662 -327.06666) (xy 16.111705 -326.976634) (xy 16.123802 -326.887332) (xy 16.143855 -326.799474)
			(xy 16.171702 -326.713768) (xy 16.207121 -326.630903) (xy 16.249824 -326.551546) (xy 16.29947 -326.476337)
			(xy 16.355657 -326.40588) (xy 16.417933 -326.340744) (xy 16.485798 -326.281453) (xy 16.558704 -326.228483)
			(xy 16.636065 -326.182262) (xy 16.717258 -326.143162) (xy 16.801629 -326.111497) (xy 16.888498 -326.087522)
			(xy 16.977167 -326.071431) (xy 17.066921 -326.063353) (xy 17.11198 -326.062848) (xy 18.35658 -326.062848)
			(xy 18.401638 -326.063361) (xy 18.491392 -326.071439) (xy 18.58006 -326.08753) (xy 18.666929 -326.111504)
			(xy 18.751299 -326.143169) (xy 18.832491 -326.182269) (xy 18.909851 -326.22849) (xy 18.982757 -326.281459)
			(xy 19.050621 -326.34075) (xy 19.112897 -326.405886) (xy 19.169084 -326.476341) (xy 19.218729 -326.55155)
			(xy 19.261432 -326.630906) (xy 19.29685 -326.713771) (xy 19.324698 -326.799477) (xy 19.34475 -326.887334)
			(xy 19.356847 -326.976634) (xy 19.36089 -327.06666) (xy 23.651462 -327.06666) (xy 23.655505 -326.976634)
			(xy 23.667602 -326.887332) (xy 23.687655 -326.799474) (xy 23.715502 -326.713768) (xy 23.750921 -326.630903)
			(xy 23.793624 -326.551546) (xy 23.84327 -326.476337) (xy 23.899457 -326.40588) (xy 23.961733 -326.340744)
			(xy 24.029598 -326.281453) (xy 24.102504 -326.228483) (xy 24.179865 -326.182262) (xy 24.261058 -326.143162)
			(xy 24.345429 -326.111497) (xy 24.432298 -326.087522) (xy 24.520967 -326.071431) (xy 24.610721 -326.063353)
			(xy 24.65578 -326.062848) (xy 25.90038 -326.062848) (xy 25.945438 -326.063361) (xy 26.035192 -326.071439)
			(xy 26.12386 -326.08753) (xy 26.210729 -326.111504) (xy 26.295099 -326.143169) (xy 26.376291 -326.182269)
			(xy 26.453651 -326.22849) (xy 26.526557 -326.281459) (xy 26.594421 -326.34075) (xy 26.656697 -326.405886)
			(xy 26.712884 -326.476341) (xy 26.762529 -326.55155) (xy 26.805232 -326.630906) (xy 26.84065 -326.713771)
			(xy 26.868498 -326.799477) (xy 26.88855 -326.887334) (xy 26.900647 -326.976634) (xy 26.90469 -327.06666)
			(xy 31.195262 -327.06666) (xy 31.199305 -326.976634) (xy 31.211402 -326.887332) (xy 31.231455 -326.799474)
			(xy 31.259302 -326.713768) (xy 31.294721 -326.630903) (xy 31.337424 -326.551546) (xy 31.38707 -326.476337)
			(xy 31.443257 -326.40588) (xy 31.505533 -326.340744) (xy 31.573398 -326.281453) (xy 31.646304 -326.228483)
			(xy 31.723665 -326.182262) (xy 31.804858 -326.143162) (xy 31.889229 -326.111497) (xy 31.976098 -326.087522)
			(xy 32.064767 -326.071431) (xy 32.154521 -326.063353) (xy 32.19958 -326.062848) (xy 33.44418 -326.062848)
			(xy 33.489238 -326.063361) (xy 33.578992 -326.071439) (xy 33.66766 -326.08753) (xy 33.754529 -326.111504)
			(xy 33.838899 -326.143169) (xy 33.920091 -326.182269) (xy 33.997451 -326.22849) (xy 34.070357 -326.281459)
			(xy 34.138221 -326.34075) (xy 34.200497 -326.405886) (xy 34.256684 -326.476341) (xy 34.306329 -326.55155)
			(xy 34.349032 -326.630906) (xy 34.38445 -326.713771) (xy 34.412298 -326.799477) (xy 34.43235 -326.887334)
			(xy 34.444447 -326.976634) (xy 34.44849 -327.06666) (xy 38.739062 -327.06666) (xy 38.743105 -326.976634)
			(xy 38.755202 -326.887332) (xy 38.775255 -326.799474) (xy 38.803102 -326.713768) (xy 38.838521 -326.630903)
			(xy 38.881224 -326.551546) (xy 38.93087 -326.476337) (xy 38.987057 -326.40588) (xy 39.049333 -326.340744)
			(xy 39.117198 -326.281453) (xy 39.190104 -326.228483) (xy 39.267465 -326.182262) (xy 39.348658 -326.143162)
			(xy 39.433029 -326.111497) (xy 39.519898 -326.087522) (xy 39.608567 -326.071431) (xy 39.698321 -326.063353)
			(xy 39.74338 -326.062848) (xy 40.98798 -326.062848) (xy 41.033038 -326.063361) (xy 41.122792 -326.071439)
			(xy 41.21146 -326.08753) (xy 41.298329 -326.111504) (xy 41.382699 -326.143169) (xy 41.463891 -326.182269)
			(xy 41.541251 -326.22849) (xy 41.614157 -326.281459) (xy 41.682021 -326.34075) (xy 41.744297 -326.405886)
			(xy 41.800484 -326.476341) (xy 41.850129 -326.55155) (xy 41.892832 -326.630906) (xy 41.92825 -326.713771)
			(xy 41.956098 -326.799477) (xy 41.97615 -326.887334) (xy 41.988247 -326.976634) (xy 41.99229 -327.06666)
			(xy 46.282862 -327.06666) (xy 46.286905 -326.976634) (xy 46.299002 -326.887332) (xy 46.319055 -326.799474)
			(xy 46.346902 -326.713768) (xy 46.382321 -326.630903) (xy 46.425024 -326.551546) (xy 46.47467 -326.476337)
			(xy 46.530857 -326.40588) (xy 46.593133 -326.340744) (xy 46.660998 -326.281453) (xy 46.733904 -326.228483)
			(xy 46.811265 -326.182262) (xy 46.892458 -326.143162) (xy 46.976829 -326.111497) (xy 47.063698 -326.087522)
			(xy 47.152367 -326.071431) (xy 47.242121 -326.063353) (xy 47.28718 -326.062848) (xy 48.53178 -326.062848)
			(xy 48.576838 -326.063361) (xy 48.666592 -326.071439) (xy 48.75526 -326.08753) (xy 48.842129 -326.111504)
			(xy 48.926499 -326.143169) (xy 49.007691 -326.182269) (xy 49.085051 -326.22849) (xy 49.157957 -326.281459)
			(xy 49.225821 -326.34075) (xy 49.288097 -326.405886) (xy 49.344284 -326.476341) (xy 49.393929 -326.55155)
			(xy 49.436632 -326.630906) (xy 49.47205 -326.713771) (xy 49.499898 -326.799477) (xy 49.51995 -326.887334)
			(xy 49.532047 -326.976634) (xy 49.53609 -327.06666) (xy 49.534191 -327.108936) (xy 53.916556 -327.108936)
			(xy 53.916556 -327.024384) (xy 53.924358 -326.940192) (xy 53.939894 -326.857079) (xy 53.963033 -326.775754)
			(xy 53.993577 -326.696911) (xy 54.031266 -326.621222) (xy 54.075777 -326.549334) (xy 54.126731 -326.481859)
			(xy 54.183694 -326.419374) (xy 54.246179 -326.362411) (xy 54.313654 -326.311457) (xy 54.385542 -326.266946)
			(xy 54.461231 -326.229257) (xy 54.540074 -326.198713) (xy 54.621399 -326.175574) (xy 54.704512 -326.160038)
			(xy 54.788704 -326.152236) (xy 54.83098 -326.151748) (xy 56.07558 -326.151748) (xy 56.117856 -326.152244)
			(xy 56.202047 -326.160046) (xy 56.28516 -326.175582) (xy 56.366484 -326.198721) (xy 56.445326 -326.229265)
			(xy 56.521014 -326.266953) (xy 56.592902 -326.311463) (xy 56.660376 -326.362417) (xy 56.72286 -326.41938)
			(xy 56.779823 -326.481864) (xy 56.830777 -326.549338) (xy 56.875287 -326.621226) (xy 56.912975 -326.696914)
			(xy 56.943519 -326.775756) (xy 56.966658 -326.85708) (xy 56.982194 -326.940193) (xy 56.989996 -327.024384)
			(xy 56.989996 -327.108936) (xy 56.989992 -327.108978) (xy 61.460336 -327.108978) (xy 61.460336 -327.024422)
			(xy 61.468138 -326.940228) (xy 61.483675 -326.857112) (xy 61.506814 -326.775785) (xy 61.537359 -326.696939)
			(xy 61.575048 -326.621248) (xy 61.61956 -326.549358) (xy 61.670515 -326.481881) (xy 61.727479 -326.419393)
			(xy 61.789965 -326.362428) (xy 61.857441 -326.311471) (xy 61.929331 -326.266957) (xy 62.005021 -326.229267)
			(xy 62.083866 -326.19872) (xy 62.165193 -326.175579) (xy 62.248308 -326.160041) (xy 62.332502 -326.152237)
			(xy 62.37478 -326.151748) (xy 63.61938 -326.151748) (xy 63.661655 -326.152308) (xy 63.745846 -326.160108)
			(xy 63.828957 -326.175643) (xy 63.910281 -326.19878) (xy 63.989123 -326.229321) (xy 64.06481 -326.267008)
			(xy 64.136697 -326.311517) (xy 64.204171 -326.36247) (xy 64.266655 -326.41943) (xy 64.323618 -326.481914)
			(xy 64.374572 -326.549386) (xy 64.419082 -326.621272) (xy 64.45677 -326.696959) (xy 64.487314 -326.7758)
			(xy 64.510453 -326.857123) (xy 64.525989 -326.940234) (xy 64.533791 -327.024425) (xy 64.533791 -327.108975)
			(xy 64.525989 -327.193166) (xy 64.510453 -327.276277) (xy 64.487314 -327.3576) (xy 64.45677 -327.436441)
			(xy 64.419082 -327.512128) (xy 64.374572 -327.584014) (xy 64.323618 -327.651486) (xy 64.266655 -327.71397)
			(xy 64.204171 -327.77093) (xy 64.136697 -327.821883) (xy 64.06481 -327.866392) (xy 63.989123 -327.904079)
			(xy 63.910281 -327.93462) (xy 63.828957 -327.957757) (xy 63.745846 -327.973292) (xy 63.661655 -327.981092)
			(xy 63.61938 -327.981564) (xy 62.37478 -327.981564) (xy 62.332502 -327.981163) (xy 62.248308 -327.973359)
			(xy 62.165193 -327.957821) (xy 62.083866 -327.93468) (xy 62.005021 -327.904133) (xy 61.929331 -327.866443)
			(xy 61.857441 -327.821929) (xy 61.789965 -327.770972) (xy 61.727479 -327.714007) (xy 61.670515 -327.651519)
			(xy 61.61956 -327.584042) (xy 61.575048 -327.512152) (xy 61.537359 -327.436461) (xy 61.506814 -327.357615)
			(xy 61.483675 -327.276288) (xy 61.468138 -327.193172) (xy 61.460336 -327.108978) (xy 56.989992 -327.108978)
			(xy 56.982194 -327.193127) (xy 56.966658 -327.27624) (xy 56.943519 -327.357564) (xy 56.912975 -327.436406)
			(xy 56.875287 -327.512094) (xy 56.830777 -327.583982) (xy 56.779823 -327.651456) (xy 56.72286 -327.71394)
			(xy 56.660376 -327.770903) (xy 56.592902 -327.821857) (xy 56.521014 -327.866367) (xy 56.445326 -327.904055)
			(xy 56.366484 -327.934599) (xy 56.28516 -327.957738) (xy 56.202047 -327.973274) (xy 56.117856 -327.981076)
			(xy 56.07558 -327.981564) (xy 54.83098 -327.981564) (xy 54.788704 -327.981084) (xy 54.704512 -327.973282)
			(xy 54.621399 -327.957746) (xy 54.540074 -327.934607) (xy 54.461231 -327.904063) (xy 54.385542 -327.866374)
			(xy 54.313654 -327.821863) (xy 54.246179 -327.770909) (xy 54.183694 -327.713946) (xy 54.126731 -327.651461)
			(xy 54.075777 -327.583986) (xy 54.031266 -327.512098) (xy 53.993577 -327.436409) (xy 53.963033 -327.357566)
			(xy 53.939894 -327.276241) (xy 53.924358 -327.193128) (xy 53.916556 -327.108936) (xy 49.534191 -327.108936)
			(xy 49.532047 -327.156686) (xy 49.51995 -327.245986) (xy 49.499898 -327.333843) (xy 49.47205 -327.419549)
			(xy 49.436632 -327.502414) (xy 49.393929 -327.58177) (xy 49.344284 -327.656979) (xy 49.288097 -327.727434)
			(xy 49.225821 -327.79257) (xy 49.157957 -327.851861) (xy 49.085051 -327.90483) (xy 49.007691 -327.951051)
			(xy 48.926499 -327.990151) (xy 48.842129 -328.021816) (xy 48.75526 -328.04579) (xy 48.666592 -328.061881)
			(xy 48.576838 -328.069959) (xy 48.53178 -328.070464) (xy 47.28718 -328.070464) (xy 47.242121 -328.069967)
			(xy 47.152367 -328.061889) (xy 47.063698 -328.045798) (xy 46.976829 -328.021823) (xy 46.892458 -327.990158)
			(xy 46.811265 -327.951058) (xy 46.733904 -327.904837) (xy 46.660998 -327.851867) (xy 46.593133 -327.792576)
			(xy 46.530857 -327.72744) (xy 46.47467 -327.656983) (xy 46.425024 -327.581774) (xy 46.382321 -327.502417)
			(xy 46.346902 -327.419552) (xy 46.319055 -327.333846) (xy 46.299002 -327.245988) (xy 46.286905 -327.156686)
			(xy 46.282862 -327.06666) (xy 41.99229 -327.06666) (xy 41.988247 -327.156686) (xy 41.97615 -327.245986)
			(xy 41.956098 -327.333843) (xy 41.92825 -327.419549) (xy 41.892832 -327.502414) (xy 41.850129 -327.58177)
			(xy 41.800484 -327.656979) (xy 41.744297 -327.727434) (xy 41.682021 -327.79257) (xy 41.614157 -327.851861)
			(xy 41.541251 -327.90483) (xy 41.463891 -327.951051) (xy 41.382699 -327.990151) (xy 41.298329 -328.021816)
			(xy 41.21146 -328.04579) (xy 41.122792 -328.061881) (xy 41.033038 -328.069959) (xy 40.98798 -328.070464)
			(xy 39.74338 -328.070464) (xy 39.698321 -328.069967) (xy 39.608567 -328.061889) (xy 39.519898 -328.045798)
			(xy 39.433029 -328.021823) (xy 39.348658 -327.990158) (xy 39.267465 -327.951058) (xy 39.190104 -327.904837)
			(xy 39.117198 -327.851867) (xy 39.049333 -327.792576) (xy 38.987057 -327.72744) (xy 38.93087 -327.656983)
			(xy 38.881224 -327.581774) (xy 38.838521 -327.502417) (xy 38.803102 -327.419552) (xy 38.775255 -327.333846)
			(xy 38.755202 -327.245988) (xy 38.743105 -327.156686) (xy 38.739062 -327.06666) (xy 34.44849 -327.06666)
			(xy 34.444447 -327.156686) (xy 34.43235 -327.245986) (xy 34.412298 -327.333843) (xy 34.38445 -327.419549)
			(xy 34.349032 -327.502414) (xy 34.306329 -327.58177) (xy 34.256684 -327.656979) (xy 34.200497 -327.727434)
			(xy 34.138221 -327.79257) (xy 34.070357 -327.851861) (xy 33.997451 -327.90483) (xy 33.920091 -327.951051)
			(xy 33.838899 -327.990151) (xy 33.754529 -328.021816) (xy 33.66766 -328.04579) (xy 33.578992 -328.061881)
			(xy 33.489238 -328.069959) (xy 33.44418 -328.070464) (xy 32.19958 -328.070464) (xy 32.154521 -328.069967)
			(xy 32.064767 -328.061889) (xy 31.976098 -328.045798) (xy 31.889229 -328.021823) (xy 31.804858 -327.990158)
			(xy 31.723665 -327.951058) (xy 31.646304 -327.904837) (xy 31.573398 -327.851867) (xy 31.505533 -327.792576)
			(xy 31.443257 -327.72744) (xy 31.38707 -327.656983) (xy 31.337424 -327.581774) (xy 31.294721 -327.502417)
			(xy 31.259302 -327.419552) (xy 31.231455 -327.333846) (xy 31.211402 -327.245988) (xy 31.199305 -327.156686)
			(xy 31.195262 -327.06666) (xy 26.90469 -327.06666) (xy 26.900647 -327.156686) (xy 26.88855 -327.245986)
			(xy 26.868498 -327.333843) (xy 26.84065 -327.419549) (xy 26.805232 -327.502414) (xy 26.762529 -327.58177)
			(xy 26.712884 -327.656979) (xy 26.656697 -327.727434) (xy 26.594421 -327.79257) (xy 26.526557 -327.851861)
			(xy 26.453651 -327.90483) (xy 26.376291 -327.951051) (xy 26.295099 -327.990151) (xy 26.210729 -328.021816)
			(xy 26.12386 -328.04579) (xy 26.035192 -328.061881) (xy 25.945438 -328.069959) (xy 25.90038 -328.070464)
			(xy 24.65578 -328.070464) (xy 24.610721 -328.069967) (xy 24.520967 -328.061889) (xy 24.432298 -328.045798)
			(xy 24.345429 -328.021823) (xy 24.261058 -327.990158) (xy 24.179865 -327.951058) (xy 24.102504 -327.904837)
			(xy 24.029598 -327.851867) (xy 23.961733 -327.792576) (xy 23.899457 -327.72744) (xy 23.84327 -327.656983)
			(xy 23.793624 -327.581774) (xy 23.750921 -327.502417) (xy 23.715502 -327.419552) (xy 23.687655 -327.333846)
			(xy 23.667602 -327.245988) (xy 23.655505 -327.156686) (xy 23.651462 -327.06666) (xy 19.36089 -327.06666)
			(xy 19.356847 -327.156686) (xy 19.34475 -327.245986) (xy 19.324698 -327.333843) (xy 19.29685 -327.419549)
			(xy 19.261432 -327.502414) (xy 19.218729 -327.58177) (xy 19.169084 -327.656979) (xy 19.112897 -327.727434)
			(xy 19.050621 -327.79257) (xy 18.982757 -327.851861) (xy 18.909851 -327.90483) (xy 18.832491 -327.951051)
			(xy 18.751299 -327.990151) (xy 18.666929 -328.021816) (xy 18.58006 -328.04579) (xy 18.491392 -328.061881)
			(xy 18.401638 -328.069959) (xy 18.35658 -328.070464) (xy 17.11198 -328.070464) (xy 17.066921 -328.069967)
			(xy 16.977167 -328.061889) (xy 16.888498 -328.045798) (xy 16.801629 -328.021823) (xy 16.717258 -327.990158)
			(xy 16.636065 -327.951058) (xy 16.558704 -327.904837) (xy 16.485798 -327.851867) (xy 16.417933 -327.792576)
			(xy 16.355657 -327.72744) (xy 16.29947 -327.656983) (xy 16.249824 -327.581774) (xy 16.207121 -327.502417)
			(xy 16.171702 -327.419552) (xy 16.143855 -327.333846) (xy 16.123802 -327.245988) (xy 16.111705 -327.156686)
			(xy 16.107662 -327.06666) (xy 11.81709 -327.06666) (xy 11.813047 -327.156686) (xy 11.80095 -327.245986)
			(xy 11.780898 -327.333843) (xy 11.75305 -327.419549) (xy 11.717632 -327.502414) (xy 11.674929 -327.58177)
			(xy 11.625284 -327.656979) (xy 11.569097 -327.727434) (xy 11.506821 -327.79257) (xy 11.438957 -327.851861)
			(xy 11.366051 -327.90483) (xy 11.288691 -327.951051) (xy 11.207499 -327.990151) (xy 11.123129 -328.021816)
			(xy 11.03626 -328.04579) (xy 10.947592 -328.061881) (xy 10.857838 -328.069959) (xy 10.81278 -328.070464)
			(xy 9.56818 -328.070464) (xy 9.523121 -328.069967) (xy 9.433367 -328.061889) (xy 9.344698 -328.045798)
			(xy 9.257829 -328.021823) (xy 9.173458 -327.990158) (xy 9.092265 -327.951058) (xy 9.014904 -327.904837)
			(xy 8.941998 -327.851867) (xy 8.874133 -327.792576) (xy 8.811857 -327.72744) (xy 8.75567 -327.656983)
			(xy 8.706024 -327.581774) (xy 8.663321 -327.502417) (xy 8.627902 -327.419552) (xy 8.600055 -327.333846)
			(xy 8.580002 -327.245988) (xy 8.567905 -327.156686) (xy 8.563862 -327.06666) (xy 5.765038 -327.06666)
			(xy 5.765038 -332.29677) (xy 6.100064 -332.631796) (xy 16.067024 -332.631796) (xy 18.644616 -335.209388)
			(xy 34.38144 -335.209388)
		)
		(stroke
			(width 0)
			(type solid)
		)
		(fill yes)
		(layer "B.Cu")
		(net "P12V_S3_AUX_CPU1_NVDIMM")
	)
	(gr_poly
		(pts
			(xy 99.259644 -216.744296) (xy 99.268851 -216.734515) (xy 99.282232 -216.711234) (xy 99.289073 -216.685268)
			(xy 99.288898 -216.658416) (xy 99.28172 -216.632541) (xy 99.268037 -216.609436) (xy 99.248797 -216.590705)
			(xy 99.237292 -216.583768) (xy 99.212275 -216.569207) (xy 99.166559 -216.533705) (xy 99.126736 -216.4917)
			(xy 99.093721 -216.444157) (xy 99.068272 -216.39217) (xy 99.050976 -216.336932) (xy 99.04223 -216.279715)
			(xy 99.041712 -216.250774) (xy 99.0422 -216.223525) (xy 99.04996 -216.169581) (xy 99.065317 -216.11729)
			(xy 99.08796 -216.067718) (xy 99.117427 -216.021872) (xy 99.153119 -215.980687) (xy 99.194309 -215.945)
			(xy 99.240158 -215.915538) (xy 99.289733 -215.892901) (xy 99.342026 -215.87755) (xy 99.39597 -215.869797)
			(xy 99.42322 -215.869266) (xy 99.452159 -215.869805) (xy 99.50937 -215.878556) (xy 99.564602 -215.895855)
			(xy 99.616584 -215.921304) (xy 99.664122 -215.954317) (xy 99.706123 -215.994137) (xy 99.741623 -216.039848)
			(xy 99.756214 -216.064846) (xy 99.763123 -216.076354) (xy 99.781877 -216.095546) (xy 99.804983 -216.109189)
			(xy 99.830845 -216.116342) (xy 99.857678 -216.116512) (xy 99.883629 -216.109685) (xy 99.906905 -216.096334)
			(xy 99.916742 -216.087198) (xy 100.279962 -215.723978) (xy 100.279962 -214.94369) (xy 100.246942 -214.931244)
			(xy 100.223691 -214.922064) (xy 100.180046 -214.897697) (xy 100.140584 -214.867015) (xy 100.106212 -214.830722)
			(xy 100.077718 -214.789652) (xy 100.055757 -214.744748) (xy 100.040833 -214.697041) (xy 100.03329 -214.647627)
			(xy 100.03282 -214.622634) (xy 100.033181 -214.599657) (xy 100.039493 -214.554141) (xy 100.052069 -214.509943)
			(xy 100.061014 -214.488776) (xy 100.07092 -214.466424) (xy 99.857306 -214.061294) (xy 99.833176 -214.056722)
			(xy 99.808255 -214.051631) (xy 99.760254 -214.034807) (xy 99.715406 -214.010813) (xy 99.674773 -213.980218)
			(xy 99.639318 -213.943748) (xy 99.609882 -213.902268) (xy 99.587163 -213.856761) (xy 99.571699 -213.808305)
			(xy 99.563858 -213.758049) (xy 99.563428 -213.732618) (xy 99.563934 -213.706729) (xy 99.572031 -213.655587)
			(xy 99.588028 -213.606342) (xy 99.611532 -213.560205) (xy 99.641964 -213.518313) (xy 99.678574 -213.481698)
			(xy 99.720461 -213.451259) (xy 99.766594 -213.427748) (xy 99.815837 -213.411743) (xy 99.866977 -213.403638)
			(xy 99.892866 -213.40318) (xy 99.918405 -213.403665) (xy 99.968871 -213.411554) (xy 100.017515 -213.427134)
			(xy 100.063174 -213.450031) (xy 100.104755 -213.479698) (xy 100.141261 -213.515423) (xy 100.171819 -213.556353)
			(xy 100.184204 -213.578694) (xy 100.198682 -213.605618) (xy 100.279962 -213.605618) (xy 100.279962 -213.44255)
			(xy 101.119178 -212.603334) (xy 101.119178 -209.27441) (xy 101.355398 -209.03819) (xy 104.413558 -209.03819)
			(xy 104.65054 -209.275172) (xy 104.65054 -212.397848) (xy 105.08234 -212.829648) (xy 107.531916 -212.829648)
			(xy 107.649772 -212.711792) (xy 107.649772 -199.595486) (xy 107.172506 -199.11822) (xy 95.458026 -199.11822)
			(xy 95.051626 -199.52462) (xy 95.051626 -208.95056) (xy 91.632786 -212.3694) (xy 90.817446 -212.3694)
			(xy 89.651586 -213.53526) (xy 89.651586 -213.732618) (xy 90.165428 -213.732618) (xy 90.165936 -213.706731)
			(xy 90.174035 -213.655593) (xy 90.190034 -213.606353) (xy 90.21354 -213.560221) (xy 90.243972 -213.518334)
			(xy 90.280582 -213.481724) (xy 90.322469 -213.451292) (xy 90.368601 -213.427786) (xy 90.417841 -213.411787)
			(xy 90.468979 -213.403688) (xy 90.520753 -213.403688) (xy 90.571891 -213.411787) (xy 90.621131 -213.427786)
			(xy 90.667263 -213.451292) (xy 90.70915 -213.481724) (xy 90.74576 -213.518334) (xy 90.776192 -213.560221)
			(xy 90.799698 -213.606353) (xy 90.815697 -213.655593) (xy 90.823796 -213.706731) (xy 90.824304 -213.732618)
			(xy 90.823953 -213.755595) (xy 90.823443 -213.759267) (xy 91.079056 -213.759267) (xy 91.079056 -213.705969)
			(xy 91.086999 -213.653265) (xy 91.102709 -213.602335) (xy 91.125835 -213.554314) (xy 91.155859 -213.510277)
			(xy 91.192111 -213.471206) (xy 91.233782 -213.437975) (xy 91.27994 -213.411326) (xy 91.329554 -213.391854)
			(xy 91.381516 -213.379994) (xy 91.434666 -213.376011) (xy 91.487816 -213.379994) (xy 91.539778 -213.391854)
			(xy 91.589392 -213.411326) (xy 91.63555 -213.437975) (xy 91.677221 -213.471206) (xy 91.713473 -213.510277)
			(xy 91.743497 -213.554314) (xy 91.766623 -213.602335) (xy 91.782333 -213.653265) (xy 91.790276 -213.705969)
			(xy 91.790774 -213.732618) (xy 92.045028 -213.732618) (xy 92.045536 -213.706731) (xy 92.053635 -213.655593)
			(xy 92.069634 -213.606353) (xy 92.09314 -213.560221) (xy 92.123572 -213.518334) (xy 92.160182 -213.481724)
			(xy 92.202069 -213.451292) (xy 92.248201 -213.427786) (xy 92.297441 -213.411787) (xy 92.348579 -213.403688)
			(xy 92.400353 -213.403688) (xy 92.451491 -213.411787) (xy 92.500731 -213.427786) (xy 92.546863 -213.451292)
			(xy 92.58875 -213.481724) (xy 92.62536 -213.518334) (xy 92.655792 -213.560221) (xy 92.679298 -213.606353)
			(xy 92.695297 -213.655593) (xy 92.703396 -213.706731) (xy 92.703904 -213.732618) (xy 92.703553 -213.755595)
			(xy 92.703043 -213.759267) (xy 92.958656 -213.759267) (xy 92.958656 -213.705969) (xy 92.966599 -213.653265)
			(xy 92.982309 -213.602335) (xy 93.005435 -213.554314) (xy 93.035459 -213.510277) (xy 93.071711 -213.471206)
			(xy 93.113382 -213.437975) (xy 93.15954 -213.411326) (xy 93.209154 -213.391854) (xy 93.261116 -213.379994)
			(xy 93.314266 -213.376011) (xy 93.367416 -213.379994) (xy 93.419378 -213.391854) (xy 93.468992 -213.411326)
			(xy 93.51515 -213.437975) (xy 93.556821 -213.471206) (xy 93.593073 -213.510277) (xy 93.623097 -213.554314)
			(xy 93.646223 -213.602335) (xy 93.661933 -213.653265) (xy 93.669876 -213.705969) (xy 93.670374 -213.732618)
			(xy 93.924628 -213.732618) (xy 93.925136 -213.706731) (xy 93.933235 -213.655593) (xy 93.949234 -213.606353)
			(xy 93.97274 -213.560221) (xy 94.003172 -213.518334) (xy 94.039782 -213.481724) (xy 94.081669 -213.451292)
			(xy 94.127801 -213.427786) (xy 94.177041 -213.411787) (xy 94.228179 -213.403688) (xy 94.279953 -213.403688)
			(xy 94.331091 -213.411787) (xy 94.380331 -213.427786) (xy 94.426463 -213.451292) (xy 94.46835 -213.481724)
			(xy 94.50496 -213.518334) (xy 94.535392 -213.560221) (xy 94.558898 -213.606353) (xy 94.574897 -213.655593)
			(xy 94.582996 -213.706731) (xy 94.583504 -213.732618) (xy 94.583153 -213.755595) (xy 94.582643 -213.759267)
			(xy 94.838256 -213.759267) (xy 94.838256 -213.705969) (xy 94.846199 -213.653265) (xy 94.861909 -213.602335)
			(xy 94.885035 -213.554314) (xy 94.915059 -213.510277) (xy 94.951311 -213.471206) (xy 94.992982 -213.437975)
			(xy 95.03914 -213.411326) (xy 95.088754 -213.391854) (xy 95.140716 -213.379994) (xy 95.193866 -213.376011)
			(xy 95.247016 -213.379994) (xy 95.298978 -213.391854) (xy 95.348592 -213.411326) (xy 95.39475 -213.437975)
			(xy 95.436421 -213.471206) (xy 95.472673 -213.510277) (xy 95.502697 -213.554314) (xy 95.525823 -213.602335)
			(xy 95.541533 -213.653265) (xy 95.549476 -213.705969) (xy 95.549974 -213.732618) (xy 95.804228 -213.732618)
			(xy 95.804736 -213.706731) (xy 95.812835 -213.655593) (xy 95.828834 -213.606353) (xy 95.85234 -213.560221)
			(xy 95.882772 -213.518334) (xy 95.919382 -213.481724) (xy 95.961269 -213.451292) (xy 96.007401 -213.427786)
			(xy 96.056641 -213.411787) (xy 96.107779 -213.403688) (xy 96.159553 -213.403688) (xy 96.210691 -213.411787)
			(xy 96.259931 -213.427786) (xy 96.306063 -213.451292) (xy 96.34795 -213.481724) (xy 96.38456 -213.518334)
			(xy 96.414992 -213.560221) (xy 96.438498 -213.606353) (xy 96.454497 -213.655593) (xy 96.462596 -213.706731)
			(xy 96.463104 -213.732618) (xy 96.462753 -213.755595) (xy 96.462243 -213.759267) (xy 96.717856 -213.759267)
			(xy 96.717856 -213.705969) (xy 96.725799 -213.653265) (xy 96.741509 -213.602335) (xy 96.764635 -213.554314)
			(xy 96.794659 -213.510277) (xy 96.830911 -213.471206) (xy 96.872582 -213.437975) (xy 96.91874 -213.411326)
			(xy 96.968354 -213.391854) (xy 97.020316 -213.379994) (xy 97.073466 -213.376011) (xy 97.126616 -213.379994)
			(xy 97.178578 -213.391854) (xy 97.228192 -213.411326) (xy 97.27435 -213.437975) (xy 97.316021 -213.471206)
			(xy 97.352273 -213.510277) (xy 97.382297 -213.554314) (xy 97.405423 -213.602335) (xy 97.421133 -213.653265)
			(xy 97.429076 -213.705969) (xy 97.429574 -213.732618) (xy 97.683828 -213.732618) (xy 97.684336 -213.706731)
			(xy 97.692435 -213.655593) (xy 97.708434 -213.606353) (xy 97.73194 -213.560221) (xy 97.762372 -213.518334)
			(xy 97.798982 -213.481724) (xy 97.840869 -213.451292) (xy 97.887001 -213.427786) (xy 97.936241 -213.411787)
			(xy 97.987379 -213.403688) (xy 98.039153 -213.403688) (xy 98.090291 -213.411787) (xy 98.139531 -213.427786)
			(xy 98.185663 -213.451292) (xy 98.22755 -213.481724) (xy 98.26416 -213.518334) (xy 98.294592 -213.560221)
			(xy 98.318098 -213.606353) (xy 98.334097 -213.655593) (xy 98.342196 -213.706731) (xy 98.342704 -213.732618)
			(xy 98.342353 -213.755595) (xy 98.341843 -213.759267) (xy 98.597456 -213.759267) (xy 98.597456 -213.705969)
			(xy 98.605399 -213.653265) (xy 98.621109 -213.602335) (xy 98.644235 -213.554314) (xy 98.674259 -213.510277)
			(xy 98.710511 -213.471206) (xy 98.752182 -213.437975) (xy 98.79834 -213.411326) (xy 98.847954 -213.391854)
			(xy 98.899916 -213.379994) (xy 98.953066 -213.376011) (xy 99.006216 -213.379994) (xy 99.058178 -213.391854)
			(xy 99.107792 -213.411326) (xy 99.15395 -213.437975) (xy 99.195621 -213.471206) (xy 99.231873 -213.510277)
			(xy 99.261897 -213.554314) (xy 99.285023 -213.602335) (xy 99.300733 -213.653265) (xy 99.308676 -213.705969)
			(xy 99.309174 -213.732618) (xy 99.308676 -213.759267) (xy 99.300733 -213.811971) (xy 99.285023 -213.862901)
			(xy 99.261897 -213.910922) (xy 99.231873 -213.954959) (xy 99.195621 -213.99403) (xy 99.15395 -214.027261)
			(xy 99.107792 -214.05391) (xy 99.058178 -214.073382) (xy 99.006216 -214.085242) (xy 98.953066 -214.089226)
			(xy 98.899916 -214.085242) (xy 98.847954 -214.073382) (xy 98.79834 -214.05391) (xy 98.752182 -214.027261)
			(xy 98.710511 -213.99403) (xy 98.674259 -213.954959) (xy 98.644235 -213.910922) (xy 98.621109 -213.862901)
			(xy 98.605399 -213.811971) (xy 98.597456 -213.759267) (xy 98.341843 -213.759267) (xy 98.336032 -213.80111)
			(xy 98.323448 -213.845306) (xy 98.31451 -213.866476) (xy 98.304604 -213.888828) (xy 98.518218 -214.293958)
			(xy 98.542348 -214.29853) (xy 98.567267 -214.303641) (xy 98.615277 -214.320441) (xy 98.660136 -214.344419)
			(xy 98.700776 -214.375006) (xy 98.736234 -214.411476) (xy 98.765666 -214.452961) (xy 98.788373 -214.498476)
			(xy 98.803815 -214.54694) (xy 98.811627 -214.597201) (xy 98.812096 -214.622634) (xy 98.811588 -214.648521)
			(xy 98.803489 -214.699659) (xy 98.78749 -214.748899) (xy 98.763984 -214.795031) (xy 98.733552 -214.836918)
			(xy 98.696942 -214.873528) (xy 98.655055 -214.90396) (xy 98.608923 -214.927466) (xy 98.559683 -214.943465)
			(xy 98.508545 -214.951564) (xy 98.456771 -214.951564) (xy 98.405633 -214.943465) (xy 98.356393 -214.927466)
			(xy 98.310261 -214.90396) (xy 98.268374 -214.873528) (xy 98.231764 -214.836918) (xy 98.201332 -214.795031)
			(xy 98.177826 -214.748899) (xy 98.161827 -214.699659) (xy 98.153728 -214.648521) (xy 98.15322 -214.622634)
			(xy 98.153587 -214.599658) (xy 98.1599 -214.554143) (xy 98.172479 -214.509947) (xy 98.181414 -214.488776)
			(xy 98.19132 -214.466424) (xy 97.977706 -214.061294) (xy 97.953576 -214.056722) (xy 97.92865 -214.051639)
			(xy 97.880636 -214.034839) (xy 97.835775 -214.010859) (xy 97.795132 -213.980269) (xy 97.759674 -213.943796)
			(xy 97.730243 -213.902307) (xy 97.707538 -213.856787) (xy 97.6921 -213.808318) (xy 97.684294 -213.758052)
			(xy 97.683828 -213.732618) (xy 97.429574 -213.732618) (xy 97.429076 -213.759267) (xy 97.421133 -213.811971)
			(xy 97.405423 -213.862901) (xy 97.382297 -213.910922) (xy 97.352273 -213.954959) (xy 97.316021 -213.99403)
			(xy 97.27435 -214.027261) (xy 97.228192 -214.05391) (xy 97.178578 -214.073382) (xy 97.126616 -214.085242)
			(xy 97.073466 -214.089226) (xy 97.020316 -214.085242) (xy 96.968354 -214.073382) (xy 96.91874 -214.05391)
			(xy 96.872582 -214.027261) (xy 96.830911 -213.99403) (xy 96.794659 -213.954959) (xy 96.764635 -213.910922)
			(xy 96.741509 -213.862901) (xy 96.725799 -213.811971) (xy 96.717856 -213.759267) (xy 96.462243 -213.759267)
			(xy 96.456432 -213.80111) (xy 96.443848 -213.845306) (xy 96.43491 -213.866476) (xy 96.425004 -213.888828)
			(xy 96.638618 -214.293958) (xy 96.662748 -214.29853) (xy 96.687667 -214.303641) (xy 96.735677 -214.320441)
			(xy 96.780536 -214.344419) (xy 96.821176 -214.375006) (xy 96.856634 -214.411476) (xy 96.886066 -214.452961)
			(xy 96.908773 -214.498476) (xy 96.924215 -214.54694) (xy 96.932027 -214.597201) (xy 96.932496 -214.622634)
			(xy 96.931988 -214.648521) (xy 96.923889 -214.699659) (xy 96.90789 -214.748899) (xy 96.884384 -214.795031)
			(xy 96.853952 -214.836918) (xy 96.817342 -214.873528) (xy 96.775455 -214.90396) (xy 96.729323 -214.927466)
			(xy 96.680083 -214.943465) (xy 96.628945 -214.951564) (xy 96.577171 -214.951564) (xy 96.526033 -214.943465)
			(xy 96.476793 -214.927466) (xy 96.430661 -214.90396) (xy 96.388774 -214.873528) (xy 96.352164 -214.836918)
			(xy 96.321732 -214.795031) (xy 96.298226 -214.748899) (xy 96.282227 -214.699659) (xy 96.274128 -214.648521)
			(xy 96.27362 -214.622634) (xy 96.273987 -214.599658) (xy 96.2803 -214.554143) (xy 96.292879 -214.509947)
			(xy 96.301814 -214.488776) (xy 96.31172 -214.466424) (xy 96.098106 -214.061294) (xy 96.073976 -214.056722)
			(xy 96.04905 -214.051639) (xy 96.001036 -214.034839) (xy 95.956175 -214.010859) (xy 95.915532 -213.980269)
			(xy 95.880074 -213.943796) (xy 95.850643 -213.902307) (xy 95.827938 -213.856787) (xy 95.8125 -213.808318)
			(xy 95.804694 -213.758052) (xy 95.804228 -213.732618) (xy 95.549974 -213.732618) (xy 95.549476 -213.759267)
			(xy 95.541533 -213.811971) (xy 95.525823 -213.862901) (xy 95.502697 -213.910922) (xy 95.472673 -213.954959)
			(xy 95.436421 -213.99403) (xy 95.39475 -214.027261) (xy 95.348592 -214.05391) (xy 95.298978 -214.073382)
			(xy 95.247016 -214.085242) (xy 95.193866 -214.089226) (xy 95.140716 -214.085242) (xy 95.088754 -214.073382)
			(xy 95.03914 -214.05391) (xy 94.992982 -214.027261) (xy 94.951311 -213.99403) (xy 94.915059 -213.954959)
			(xy 94.885035 -213.910922) (xy 94.861909 -213.862901) (xy 94.846199 -213.811971) (xy 94.838256 -213.759267)
			(xy 94.582643 -213.759267) (xy 94.576832 -213.80111) (xy 94.564248 -213.845306) (xy 94.55531 -213.866476)
			(xy 94.545404 -213.888828) (xy 94.759018 -214.293958) (xy 94.783148 -214.29853) (xy 94.808067 -214.303641)
			(xy 94.856077 -214.320441) (xy 94.900936 -214.344419) (xy 94.941576 -214.375006) (xy 94.977034 -214.411476)
			(xy 95.006466 -214.452961) (xy 95.029173 -214.498476) (xy 95.044615 -214.54694) (xy 95.052427 -214.597201)
			(xy 95.052896 -214.622634) (xy 95.052388 -214.648521) (xy 95.044289 -214.699659) (xy 95.02829 -214.748899)
			(xy 95.004784 -214.795031) (xy 94.974352 -214.836918) (xy 94.937742 -214.873528) (xy 94.895855 -214.90396)
			(xy 94.849723 -214.927466) (xy 94.800483 -214.943465) (xy 94.749345 -214.951564) (xy 94.697571 -214.951564)
			(xy 94.646433 -214.943465) (xy 94.597193 -214.927466) (xy 94.551061 -214.90396) (xy 94.509174 -214.873528)
			(xy 94.472564 -214.836918) (xy 94.442132 -214.795031) (xy 94.418626 -214.748899) (xy 94.402627 -214.699659)
			(xy 94.394528 -214.648521) (xy 94.39402 -214.622634) (xy 94.394387 -214.599658) (xy 94.4007 -214.554143)
			(xy 94.413279 -214.509947) (xy 94.422214 -214.488776) (xy 94.43212 -214.466424) (xy 94.218506 -214.061294)
			(xy 94.194376 -214.056722) (xy 94.16945 -214.051639) (xy 94.121436 -214.034839) (xy 94.076575 -214.010859)
			(xy 94.035932 -213.980269) (xy 94.000474 -213.943796) (xy 93.971043 -213.902307) (xy 93.948338 -213.856787)
			(xy 93.9329 -213.808318) (xy 93.925094 -213.758052) (xy 93.924628 -213.732618) (xy 93.670374 -213.732618)
			(xy 93.669876 -213.759267) (xy 93.661933 -213.811971) (xy 93.646223 -213.862901) (xy 93.623097 -213.910922)
			(xy 93.593073 -213.954959) (xy 93.556821 -213.99403) (xy 93.51515 -214.027261) (xy 93.468992 -214.05391)
			(xy 93.419378 -214.073382) (xy 93.367416 -214.085242) (xy 93.314266 -214.089226) (xy 93.261116 -214.085242)
			(xy 93.209154 -214.073382) (xy 93.15954 -214.05391) (xy 93.113382 -214.027261) (xy 93.071711 -213.99403)
			(xy 93.035459 -213.954959) (xy 93.005435 -213.910922) (xy 92.982309 -213.862901) (xy 92.966599 -213.811971)
			(xy 92.958656 -213.759267) (xy 92.703043 -213.759267) (xy 92.697232 -213.80111) (xy 92.684648 -213.845306)
			(xy 92.67571 -213.866476) (xy 92.665804 -213.888828) (xy 92.879418 -214.293958) (xy 92.903548 -214.29853)
			(xy 92.928467 -214.303641) (xy 92.976477 -214.320441) (xy 93.021336 -214.344419) (xy 93.061976 -214.375006)
			(xy 93.097434 -214.411476) (xy 93.126866 -214.452961) (xy 93.149573 -214.498476) (xy 93.165015 -214.54694)
			(xy 93.172827 -214.597201) (xy 93.173296 -214.622634) (xy 93.172788 -214.648521) (xy 93.164689 -214.699659)
			(xy 93.14869 -214.748899) (xy 93.125184 -214.795031) (xy 93.094752 -214.836918) (xy 93.058142 -214.873528)
			(xy 93.016255 -214.90396) (xy 92.970123 -214.927466) (xy 92.920883 -214.943465) (xy 92.869745 -214.951564)
			(xy 92.817971 -214.951564) (xy 92.766833 -214.943465) (xy 92.717593 -214.927466) (xy 92.671461 -214.90396)
			(xy 92.629574 -214.873528) (xy 92.592964 -214.836918) (xy 92.562532 -214.795031) (xy 92.539026 -214.748899)
			(xy 92.523027 -214.699659) (xy 92.514928 -214.648521) (xy 92.51442 -214.622634) (xy 92.514787 -214.599658)
			(xy 92.5211 -214.554143) (xy 92.533679 -214.509947) (xy 92.542614 -214.488776) (xy 92.55252 -214.466424)
			(xy 92.338906 -214.061294) (xy 92.314776 -214.056722) (xy 92.28985 -214.051639) (xy 92.241836 -214.034839)
			(xy 92.196975 -214.010859) (xy 92.156332 -213.980269) (xy 92.120874 -213.943796) (xy 92.091443 -213.902307)
			(xy 92.068738 -213.856787) (xy 92.0533 -213.808318) (xy 92.045494 -213.758052) (xy 92.045028 -213.732618)
			(xy 91.790774 -213.732618) (xy 91.790276 -213.759267) (xy 91.782333 -213.811971) (xy 91.766623 -213.862901)
			(xy 91.743497 -213.910922) (xy 91.713473 -213.954959) (xy 91.677221 -213.99403) (xy 91.63555 -214.027261)
			(xy 91.589392 -214.05391) (xy 91.539778 -214.073382) (xy 91.487816 -214.085242) (xy 91.434666 -214.089226)
			(xy 91.381516 -214.085242) (xy 91.329554 -214.073382) (xy 91.27994 -214.05391) (xy 91.233782 -214.027261)
			(xy 91.192111 -213.99403) (xy 91.155859 -213.954959) (xy 91.125835 -213.910922) (xy 91.102709 -213.862901)
			(xy 91.086999 -213.811971) (xy 91.079056 -213.759267) (xy 90.823443 -213.759267) (xy 90.817632 -213.80111)
			(xy 90.805048 -213.845306) (xy 90.79611 -213.866476) (xy 90.786204 -213.888828) (xy 90.999818 -214.293958)
			(xy 91.023948 -214.29853) (xy 91.048867 -214.303641) (xy 91.096877 -214.320441) (xy 91.141736 -214.344419)
			(xy 91.182376 -214.375006) (xy 91.217834 -214.411476) (xy 91.247266 -214.452961) (xy 91.269973 -214.498476)
			(xy 91.285415 -214.54694) (xy 91.293227 -214.597201) (xy 91.293696 -214.622634) (xy 91.293188 -214.648521)
			(xy 91.285089 -214.699659) (xy 91.26909 -214.748899) (xy 91.245584 -214.795031) (xy 91.215152 -214.836918)
			(xy 91.178542 -214.873528) (xy 91.136655 -214.90396) (xy 91.090523 -214.927466) (xy 91.041283 -214.943465)
			(xy 90.990145 -214.951564) (xy 90.938371 -214.951564) (xy 90.887233 -214.943465) (xy 90.837993 -214.927466)
			(xy 90.791861 -214.90396) (xy 90.749974 -214.873528) (xy 90.713364 -214.836918) (xy 90.682932 -214.795031)
			(xy 90.659426 -214.748899) (xy 90.643427 -214.699659) (xy 90.635328 -214.648521) (xy 90.63482 -214.622634)
			(xy 90.635187 -214.599658) (xy 90.6415 -214.554143) (xy 90.654079 -214.509947) (xy 90.663014 -214.488776)
			(xy 90.67292 -214.466424) (xy 90.459306 -214.061294) (xy 90.435176 -214.056722) (xy 90.41025 -214.051639)
			(xy 90.362236 -214.034839) (xy 90.317375 -214.010859) (xy 90.276732 -213.980269) (xy 90.241274 -213.943796)
			(xy 90.211843 -213.902307) (xy 90.189138 -213.856787) (xy 90.1737 -213.808318) (xy 90.165894 -213.758052)
			(xy 90.165428 -213.732618) (xy 89.651586 -213.732618) (xy 89.651586 -214.287608) (xy 89.652074 -214.301933)
			(xy 89.660034 -214.329456) (xy 89.675325 -214.353686) (xy 89.696744 -214.372715) (xy 89.722605 -214.385046)
			(xy 89.750873 -214.38971) (xy 89.779325 -214.386339) (xy 89.805721 -214.375198) (xy 89.817194 -214.366602)
			(xy 89.839344 -214.349395) (xy 89.888278 -214.32199) (xy 89.941143 -214.303261) (xy 89.996416 -214.293747)
			(xy 90.024458 -214.293196) (xy 90.050349 -214.293674) (xy 90.101493 -214.301769) (xy 90.150741 -214.317766)
			(xy 90.19688 -214.341272) (xy 90.238773 -214.371707) (xy 90.275388 -214.408321) (xy 90.305824 -214.450213)
			(xy 90.329331 -214.496351) (xy 90.345329 -214.545599) (xy 90.353425 -214.596743) (xy 90.353896 -214.622634)
			(xy 90.35343 -214.647968) (xy 90.345672 -214.69804) (xy 90.330346 -214.746335) (xy 90.307811 -214.791716)
			(xy 90.278599 -214.833116) (xy 90.243396 -214.869559) (xy 90.203032 -214.900187) (xy 90.158458 -214.924279)
			(xy 90.110722 -214.941268) (xy 90.085926 -214.946484) (xy 90.063066 -214.950802) (xy 89.858088 -215.305894)
			(xy 89.865962 -215.327738) (xy 89.874608 -215.354146) (xy 89.88393 -215.408922) (xy 89.884504 -215.436704)
			(xy 91.10472 -215.436704) (xy 91.105229 -215.41136) (xy 91.113 -215.36127) (xy 91.128346 -215.31296)
			(xy 91.150903 -215.267567) (xy 91.180142 -215.226161) (xy 91.215373 -215.189717) (xy 91.255765 -215.159094)
			(xy 91.300369 -215.135013) (xy 91.348132 -215.118041) (xy 91.372944 -215.112854) (xy 91.395804 -215.108536)
			(xy 91.600782 -214.753444) (xy 91.592908 -214.7316) (xy 91.584329 -214.705181) (xy 91.575132 -214.650406)
			(xy 91.57462 -214.622634) (xy 91.575128 -214.596747) (xy 91.583227 -214.545609) (xy 91.599226 -214.496369)
			(xy 91.622732 -214.450237) (xy 91.653164 -214.40835) (xy 91.689774 -214.37174) (xy 91.731661 -214.341308)
			(xy 91.777793 -214.317802) (xy 91.827033 -214.301803) (xy 91.878171 -214.293704) (xy 91.929945 -214.293704)
			(xy 91.981083 -214.301803) (xy 92.030323 -214.317802) (xy 92.076455 -214.341308) (xy 92.118342 -214.37174)
			(xy 92.154952 -214.40835) (xy 92.185384 -214.450237) (xy 92.20889 -214.496369) (xy 92.224889 -214.545609)
			(xy 92.232988 -214.596747) (xy 92.233496 -214.622634) (xy 92.233047 -214.64797) (xy 92.22529 -214.698044)
			(xy 92.209963 -214.746341) (xy 92.187427 -214.791726) (xy 92.158212 -214.833128) (xy 92.123008 -214.869572)
			(xy 92.082642 -214.900202) (xy 92.038065 -214.924296) (xy 91.990327 -214.941286) (xy 91.965526 -214.946484)
			(xy 91.942666 -214.950802) (xy 91.737688 -215.305894) (xy 91.745562 -215.327738) (xy 91.75421 -215.354146)
			(xy 91.763529 -215.408922) (xy 91.764104 -215.436704) (xy 92.98432 -215.436704) (xy 92.984829 -215.41136)
			(xy 92.9926 -215.36127) (xy 93.007946 -215.31296) (xy 93.030503 -215.267567) (xy 93.059742 -215.226161)
			(xy 93.094973 -215.189717) (xy 93.135365 -215.159094) (xy 93.179969 -215.135013) (xy 93.227732 -215.118041)
			(xy 93.252544 -215.112854) (xy 93.275404 -215.108536) (xy 93.480382 -214.753444) (xy 93.472508 -214.7316)
			(xy 93.463929 -214.705181) (xy 93.454732 -214.650406) (xy 93.45422 -214.622634) (xy 93.454728 -214.596747)
			(xy 93.462827 -214.545609) (xy 93.478826 -214.496369) (xy 93.502332 -214.450237) (xy 93.532764 -214.40835)
			(xy 93.569374 -214.37174) (xy 93.611261 -214.341308) (xy 93.657393 -214.317802) (xy 93.706633 -214.301803)
			(xy 93.757771 -214.293704) (xy 93.809545 -214.293704) (xy 93.860683 -214.301803) (xy 93.909923 -214.317802)
			(xy 93.956055 -214.341308) (xy 93.997942 -214.37174) (xy 94.034552 -214.40835) (xy 94.064984 -214.450237)
			(xy 94.08849 -214.496369) (xy 94.104489 -214.545609) (xy 94.112588 -214.596747) (xy 94.113096 -214.622634)
			(xy 94.112647 -214.64797) (xy 94.10489 -214.698044) (xy 94.089563 -214.746341) (xy 94.067027 -214.791726)
			(xy 94.037812 -214.833128) (xy 94.002608 -214.869572) (xy 93.962242 -214.900202) (xy 93.917665 -214.924296)
			(xy 93.869927 -214.941286) (xy 93.845126 -214.946484) (xy 93.822266 -214.950802) (xy 93.617288 -215.305894)
			(xy 93.625162 -215.327738) (xy 93.63381 -215.354146) (xy 93.643129 -215.408922) (xy 93.643704 -215.436704)
			(xy 94.86392 -215.436704) (xy 94.864429 -215.41136) (xy 94.8722 -215.36127) (xy 94.887546 -215.31296)
			(xy 94.910103 -215.267567) (xy 94.939342 -215.226161) (xy 94.974573 -215.189717) (xy 95.014965 -215.159094)
			(xy 95.059569 -215.135013) (xy 95.107332 -215.118041) (xy 95.132144 -215.112854) (xy 95.155004 -215.108536)
			(xy 95.359982 -214.753444) (xy 95.352108 -214.7316) (xy 95.343529 -214.705181) (xy 95.334332 -214.650406)
			(xy 95.33382 -214.622634) (xy 95.334328 -214.596747) (xy 95.342427 -214.545609) (xy 95.358426 -214.496369)
			(xy 95.381932 -214.450237) (xy 95.412364 -214.40835) (xy 95.448974 -214.37174) (xy 95.490861 -214.341308)
			(xy 95.536993 -214.317802) (xy 95.586233 -214.301803) (xy 95.637371 -214.293704) (xy 95.689145 -214.293704)
			(xy 95.740283 -214.301803) (xy 95.789523 -214.317802) (xy 95.835655 -214.341308) (xy 95.877542 -214.37174)
			(xy 95.914152 -214.40835) (xy 95.944584 -214.450237) (xy 95.96809 -214.496369) (xy 95.984089 -214.545609)
			(xy 95.992188 -214.596747) (xy 95.992696 -214.622634) (xy 95.992247 -214.64797) (xy 95.98449 -214.698044)
			(xy 95.969163 -214.746341) (xy 95.946627 -214.791726) (xy 95.917412 -214.833128) (xy 95.882208 -214.869572)
			(xy 95.841842 -214.900202) (xy 95.797265 -214.924296) (xy 95.749527 -214.941286) (xy 95.724726 -214.946484)
			(xy 95.701866 -214.950802) (xy 95.496888 -215.305894) (xy 95.504762 -215.327738) (xy 95.51341 -215.354146)
			(xy 95.522729 -215.408922) (xy 95.523304 -215.436704) (xy 96.74352 -215.436704) (xy 96.744029 -215.41136)
			(xy 96.7518 -215.36127) (xy 96.767146 -215.31296) (xy 96.789703 -215.267567) (xy 96.818942 -215.226161)
			(xy 96.854173 -215.189717) (xy 96.894565 -215.159094) (xy 96.939169 -215.135013) (xy 96.986932 -215.118041)
			(xy 97.011744 -215.112854) (xy 97.034604 -215.108536) (xy 97.239582 -214.753444) (xy 97.231708 -214.7316)
			(xy 97.223129 -214.705181) (xy 97.213932 -214.650406) (xy 97.21342 -214.622634) (xy 97.213928 -214.596747)
			(xy 97.222027 -214.545609) (xy 97.238026 -214.496369) (xy 97.261532 -214.450237) (xy 97.291964 -214.40835)
			(xy 97.328574 -214.37174) (xy 97.370461 -214.341308) (xy 97.416593 -214.317802) (xy 97.465833 -214.301803)
			(xy 97.516971 -214.293704) (xy 97.568745 -214.293704) (xy 97.619883 -214.301803) (xy 97.669123 -214.317802)
			(xy 97.715255 -214.341308) (xy 97.757142 -214.37174) (xy 97.793752 -214.40835) (xy 97.824184 -214.450237)
			(xy 97.84769 -214.496369) (xy 97.863689 -214.545609) (xy 97.871788 -214.596747) (xy 97.872296 -214.622634)
			(xy 97.871847 -214.64797) (xy 97.86409 -214.698044) (xy 97.848763 -214.746341) (xy 97.826227 -214.791726)
			(xy 97.797012 -214.833128) (xy 97.761808 -214.869572) (xy 97.721442 -214.900202) (xy 97.676865 -214.924296)
			(xy 97.629127 -214.941286) (xy 97.604326 -214.946484) (xy 97.581466 -214.950802) (xy 97.376488 -215.305894)
			(xy 97.384362 -215.327738) (xy 97.39301 -215.354146) (xy 97.402329 -215.408922) (xy 97.402904 -215.436704)
			(xy 98.62312 -215.436704) (xy 98.623629 -215.41136) (xy 98.6314 -215.36127) (xy 98.646746 -215.31296)
			(xy 98.669303 -215.267567) (xy 98.698542 -215.226161) (xy 98.733773 -215.189717) (xy 98.774165 -215.159094)
			(xy 98.818769 -215.135013) (xy 98.866532 -215.118041) (xy 98.891344 -215.112854) (xy 98.914204 -215.108536)
			(xy 99.119182 -214.753444) (xy 99.111308 -214.7316) (xy 99.102729 -214.705181) (xy 99.093532 -214.650406)
			(xy 99.09302 -214.622634) (xy 99.093528 -214.596747) (xy 99.101627 -214.545609) (xy 99.117626 -214.496369)
			(xy 99.141132 -214.450237) (xy 99.171564 -214.40835) (xy 99.208174 -214.37174) (xy 99.250061 -214.341308)
			(xy 99.296193 -214.317802) (xy 99.345433 -214.301803) (xy 99.396571 -214.293704) (xy 99.448345 -214.293704)
			(xy 99.499483 -214.301803) (xy 99.548723 -214.317802) (xy 99.594855 -214.341308) (xy 99.636742 -214.37174)
			(xy 99.673352 -214.40835) (xy 99.703784 -214.450237) (xy 99.72729 -214.496369) (xy 99.743289 -214.545609)
			(xy 99.751388 -214.596747) (xy 99.751896 -214.622634) (xy 99.751447 -214.64797) (xy 99.74369 -214.698044)
			(xy 99.728363 -214.746341) (xy 99.705827 -214.791726) (xy 99.676612 -214.833128) (xy 99.641408 -214.869572)
			(xy 99.601042 -214.900202) (xy 99.556465 -214.924296) (xy 99.508727 -214.941286) (xy 99.483926 -214.946484)
			(xy 99.461066 -214.950802) (xy 99.256088 -215.305894) (xy 99.263962 -215.327738) (xy 99.27261 -215.354146)
			(xy 99.281929 -215.408922) (xy 99.282504 -215.436704) (xy 99.281996 -215.462611) (xy 99.27389 -215.513788)
			(xy 99.257878 -215.563067) (xy 99.234355 -215.609234) (xy 99.203899 -215.651153) (xy 99.167261 -215.687791)
			(xy 99.125342 -215.718247) (xy 99.079175 -215.74177) (xy 99.029896 -215.757782) (xy 98.978719 -215.765888)
			(xy 98.926905 -215.765888) (xy 98.875728 -215.757782) (xy 98.826449 -215.74177) (xy 98.780282 -215.718247)
			(xy 98.738363 -215.687791) (xy 98.701725 -215.651153) (xy 98.671269 -215.609234) (xy 98.647746 -215.563067)
			(xy 98.631734 -215.513788) (xy 98.623628 -215.462611) (xy 98.62312 -215.436704) (xy 97.402904 -215.436704)
			(xy 97.402396 -215.462611) (xy 97.39429 -215.513788) (xy 97.378278 -215.563067) (xy 97.354755 -215.609234)
			(xy 97.324299 -215.651153) (xy 97.287661 -215.687791) (xy 97.245742 -215.718247) (xy 97.199575 -215.74177)
			(xy 97.150296 -215.757782) (xy 97.099119 -215.765888) (xy 97.047305 -215.765888) (xy 96.996128 -215.757782)
			(xy 96.946849 -215.74177) (xy 96.900682 -215.718247) (xy 96.858763 -215.687791) (xy 96.822125 -215.651153)
			(xy 96.791669 -215.609234) (xy 96.768146 -215.563067) (xy 96.752134 -215.513788) (xy 96.744028 -215.462611)
			(xy 96.74352 -215.436704) (xy 95.523304 -215.436704) (xy 95.522796 -215.462611) (xy 95.51469 -215.513788)
			(xy 95.498678 -215.563067) (xy 95.475155 -215.609234) (xy 95.444699 -215.651153) (xy 95.408061 -215.687791)
			(xy 95.366142 -215.718247) (xy 95.319975 -215.74177) (xy 95.270696 -215.757782) (xy 95.219519 -215.765888)
			(xy 95.167705 -215.765888) (xy 95.116528 -215.757782) (xy 95.067249 -215.74177) (xy 95.021082 -215.718247)
			(xy 94.979163 -215.687791) (xy 94.942525 -215.651153) (xy 94.912069 -215.609234) (xy 94.888546 -215.563067)
			(xy 94.872534 -215.513788) (xy 94.864428 -215.462611) (xy 94.86392 -215.436704) (xy 93.643704 -215.436704)
			(xy 93.643196 -215.462611) (xy 93.63509 -215.513788) (xy 93.619078 -215.563067) (xy 93.595555 -215.609234)
			(xy 93.565099 -215.651153) (xy 93.528461 -215.687791) (xy 93.486542 -215.718247) (xy 93.440375 -215.74177)
			(xy 93.391096 -215.757782) (xy 93.339919 -215.765888) (xy 93.288105 -215.765888) (xy 93.236928 -215.757782)
			(xy 93.187649 -215.74177) (xy 93.141482 -215.718247) (xy 93.099563 -215.687791) (xy 93.062925 -215.651153)
			(xy 93.032469 -215.609234) (xy 93.008946 -215.563067) (xy 92.992934 -215.513788) (xy 92.984828 -215.462611)
			(xy 92.98432 -215.436704) (xy 91.764104 -215.436704) (xy 91.763596 -215.462611) (xy 91.75549 -215.513788)
			(xy 91.739478 -215.563067) (xy 91.715955 -215.609234) (xy 91.685499 -215.651153) (xy 91.648861 -215.687791)
			(xy 91.606942 -215.718247) (xy 91.560775 -215.74177) (xy 91.511496 -215.757782) (xy 91.460319 -215.765888)
			(xy 91.408505 -215.765888) (xy 91.357328 -215.757782) (xy 91.308049 -215.74177) (xy 91.261882 -215.718247)
			(xy 91.219963 -215.687791) (xy 91.183325 -215.651153) (xy 91.152869 -215.609234) (xy 91.129346 -215.563067)
			(xy 91.113334 -215.513788) (xy 91.105228 -215.462611) (xy 91.10472 -215.436704) (xy 89.884504 -215.436704)
			(xy 89.884114 -215.458865) (xy 89.878102 -215.502777) (xy 89.866242 -215.545483) (xy 89.857834 -215.56599)
			(xy 89.844372 -215.597486) (xy 90.17381 -215.926924) (xy 90.18143 -215.93048) (xy 90.200371 -215.940147)
			(xy 90.236025 -215.963324) (xy 90.25255 -215.976708) (xy 90.69959 -215.976708) (xy 90.721063 -215.956662)
			(xy 90.769023 -215.922746) (xy 90.821617 -215.896586) (xy 90.877601 -215.8788) (xy 90.935649 -215.869811)
			(xy 90.96502 -215.869266) (xy 90.994402 -215.86981) (xy 91.052469 -215.878825) (xy 91.108467 -215.896639)
			(xy 91.16107 -215.922831) (xy 91.209034 -215.95678) (xy 91.251225 -215.997683) (xy 91.286642 -216.044573)
			(xy 91.301062 -216.07018) (xy 91.568778 -216.07018) (xy 91.583164 -216.044553) (xy 91.61859 -215.997662)
			(xy 91.660786 -215.956758) (xy 91.708756 -215.922807) (xy 91.761363 -215.896612) (xy 91.817364 -215.878792)
			(xy 91.875436 -215.86977) (xy 91.90482 -215.869266) (xy 91.932071 -215.869753) (xy 91.986018 -215.877512)
			(xy 92.038312 -215.892868) (xy 92.087888 -215.91551) (xy 92.133738 -215.944977) (xy 92.174928 -215.980668)
			(xy 92.21062 -216.021857) (xy 92.240087 -216.067707) (xy 92.262729 -216.117283) (xy 92.278087 -216.169576)
			(xy 92.285846 -216.223523) (xy 92.286328 -216.250774) (xy 92.28591 -216.275945) (xy 92.285747 -216.277169)
			(xy 92.488756 -216.277169) (xy 92.488756 -216.223871) (xy 92.496699 -216.171167) (xy 92.512409 -216.120237)
			(xy 92.535535 -216.072216) (xy 92.565559 -216.028179) (xy 92.601811 -215.989108) (xy 92.643482 -215.955877)
			(xy 92.68964 -215.929228) (xy 92.739254 -215.909756) (xy 92.791216 -215.897896) (xy 92.844366 -215.893913)
			(xy 92.897516 -215.897896) (xy 92.949478 -215.909756) (xy 92.999092 -215.929228) (xy 93.04525 -215.955877)
			(xy 93.086921 -215.989108) (xy 93.123173 -216.028179) (xy 93.153197 -216.072216) (xy 93.176323 -216.120237)
			(xy 93.192033 -216.171167) (xy 93.199976 -216.223871) (xy 93.200474 -216.25052) (xy 93.199976 -216.277169)
			(xy 93.428556 -216.277169) (xy 93.428556 -216.223871) (xy 93.436499 -216.171167) (xy 93.452209 -216.120237)
			(xy 93.475335 -216.072216) (xy 93.505359 -216.028179) (xy 93.541611 -215.989108) (xy 93.583282 -215.955877)
			(xy 93.62944 -215.929228) (xy 93.679054 -215.909756) (xy 93.731016 -215.897896) (xy 93.784166 -215.893913)
			(xy 93.837316 -215.897896) (xy 93.889278 -215.909756) (xy 93.938892 -215.929228) (xy 93.98505 -215.955877)
			(xy 94.026721 -215.989108) (xy 94.062973 -216.028179) (xy 94.092997 -216.072216) (xy 94.116123 -216.120237)
			(xy 94.131833 -216.171167) (xy 94.139776 -216.223871) (xy 94.140274 -216.25052) (xy 94.139776 -216.277169)
			(xy 94.368356 -216.277169) (xy 94.368356 -216.223871) (xy 94.376299 -216.171167) (xy 94.392009 -216.120237)
			(xy 94.415135 -216.072216) (xy 94.445159 -216.028179) (xy 94.481411 -215.989108) (xy 94.523082 -215.955877)
			(xy 94.56924 -215.929228) (xy 94.618854 -215.909756) (xy 94.670816 -215.897896) (xy 94.723966 -215.893913)
			(xy 94.777116 -215.897896) (xy 94.829078 -215.909756) (xy 94.878692 -215.929228) (xy 94.92485 -215.955877)
			(xy 94.966521 -215.989108) (xy 95.002773 -216.028179) (xy 95.032797 -216.072216) (xy 95.055923 -216.120237)
			(xy 95.071633 -216.171167) (xy 95.079576 -216.223871) (xy 95.080074 -216.25052) (xy 95.079576 -216.277169)
			(xy 95.308156 -216.277169) (xy 95.308156 -216.223871) (xy 95.316099 -216.171167) (xy 95.331809 -216.120237)
			(xy 95.354935 -216.072216) (xy 95.384959 -216.028179) (xy 95.421211 -215.989108) (xy 95.462882 -215.955877)
			(xy 95.50904 -215.929228) (xy 95.558654 -215.909756) (xy 95.610616 -215.897896) (xy 95.663766 -215.893913)
			(xy 95.716916 -215.897896) (xy 95.768878 -215.909756) (xy 95.818492 -215.929228) (xy 95.86465 -215.955877)
			(xy 95.906321 -215.989108) (xy 95.942573 -216.028179) (xy 95.972597 -216.072216) (xy 95.995723 -216.120237)
			(xy 96.011433 -216.171167) (xy 96.019376 -216.223871) (xy 96.019874 -216.25052) (xy 96.019376 -216.277169)
			(xy 96.247956 -216.277169) (xy 96.247956 -216.223871) (xy 96.255899 -216.171167) (xy 96.271609 -216.120237)
			(xy 96.294735 -216.072216) (xy 96.324759 -216.028179) (xy 96.361011 -215.989108) (xy 96.402682 -215.955877)
			(xy 96.44884 -215.929228) (xy 96.498454 -215.909756) (xy 96.550416 -215.897896) (xy 96.603566 -215.893913)
			(xy 96.656716 -215.897896) (xy 96.708678 -215.909756) (xy 96.758292 -215.929228) (xy 96.80445 -215.955877)
			(xy 96.846121 -215.989108) (xy 96.882373 -216.028179) (xy 96.912397 -216.072216) (xy 96.935523 -216.120237)
			(xy 96.951233 -216.171167) (xy 96.959176 -216.223871) (xy 96.959674 -216.25052) (xy 96.959176 -216.277169)
			(xy 97.187756 -216.277169) (xy 97.187756 -216.223871) (xy 97.195699 -216.171167) (xy 97.211409 -216.120237)
			(xy 97.234535 -216.072216) (xy 97.264559 -216.028179) (xy 97.300811 -215.989108) (xy 97.342482 -215.955877)
			(xy 97.38864 -215.929228) (xy 97.438254 -215.909756) (xy 97.490216 -215.897896) (xy 97.543366 -215.893913)
			(xy 97.596516 -215.897896) (xy 97.648478 -215.909756) (xy 97.698092 -215.929228) (xy 97.74425 -215.955877)
			(xy 97.785921 -215.989108) (xy 97.822173 -216.028179) (xy 97.852197 -216.072216) (xy 97.875323 -216.120237)
			(xy 97.891033 -216.171167) (xy 97.898976 -216.223871) (xy 97.899474 -216.25052) (xy 97.898976 -216.277169)
			(xy 98.127556 -216.277169) (xy 98.127556 -216.223871) (xy 98.135499 -216.171167) (xy 98.151209 -216.120237)
			(xy 98.174335 -216.072216) (xy 98.204359 -216.028179) (xy 98.240611 -215.989108) (xy 98.282282 -215.955877)
			(xy 98.32844 -215.929228) (xy 98.378054 -215.909756) (xy 98.430016 -215.897896) (xy 98.483166 -215.893913)
			(xy 98.536316 -215.897896) (xy 98.588278 -215.909756) (xy 98.637892 -215.929228) (xy 98.68405 -215.955877)
			(xy 98.725721 -215.989108) (xy 98.761973 -216.028179) (xy 98.791997 -216.072216) (xy 98.815123 -216.120237)
			(xy 98.830833 -216.171167) (xy 98.838776 -216.223871) (xy 98.839274 -216.25052) (xy 98.838776 -216.277169)
			(xy 98.830833 -216.329873) (xy 98.815123 -216.380803) (xy 98.791997 -216.428824) (xy 98.761973 -216.472861)
			(xy 98.725721 -216.511932) (xy 98.68405 -216.545163) (xy 98.637892 -216.571812) (xy 98.588278 -216.591284)
			(xy 98.536316 -216.603144) (xy 98.483166 -216.607128) (xy 98.430016 -216.603144) (xy 98.378054 -216.591284)
			(xy 98.32844 -216.571812) (xy 98.282282 -216.545163) (xy 98.240611 -216.511932) (xy 98.204359 -216.472861)
			(xy 98.174335 -216.428824) (xy 98.151209 -216.380803) (xy 98.135499 -216.329873) (xy 98.127556 -216.277169)
			(xy 97.898976 -216.277169) (xy 97.891033 -216.329873) (xy 97.875323 -216.380803) (xy 97.852197 -216.428824)
			(xy 97.822173 -216.472861) (xy 97.785921 -216.511932) (xy 97.74425 -216.545163) (xy 97.698092 -216.571812)
			(xy 97.648478 -216.591284) (xy 97.596516 -216.603144) (xy 97.543366 -216.607128) (xy 97.490216 -216.603144)
			(xy 97.438254 -216.591284) (xy 97.38864 -216.571812) (xy 97.342482 -216.545163) (xy 97.300811 -216.511932)
			(xy 97.264559 -216.472861) (xy 97.234535 -216.428824) (xy 97.211409 -216.380803) (xy 97.195699 -216.329873)
			(xy 97.187756 -216.277169) (xy 96.959176 -216.277169) (xy 96.951233 -216.329873) (xy 96.935523 -216.380803)
			(xy 96.912397 -216.428824) (xy 96.882373 -216.472861) (xy 96.846121 -216.511932) (xy 96.80445 -216.545163)
			(xy 96.758292 -216.571812) (xy 96.708678 -216.591284) (xy 96.656716 -216.603144) (xy 96.603566 -216.607128)
			(xy 96.550416 -216.603144) (xy 96.498454 -216.591284) (xy 96.44884 -216.571812) (xy 96.402682 -216.545163)
			(xy 96.361011 -216.511932) (xy 96.324759 -216.472861) (xy 96.294735 -216.428824) (xy 96.271609 -216.380803)
			(xy 96.255899 -216.329873) (xy 96.247956 -216.277169) (xy 96.019376 -216.277169) (xy 96.011433 -216.329873)
			(xy 95.995723 -216.380803) (xy 95.972597 -216.428824) (xy 95.942573 -216.472861) (xy 95.906321 -216.511932)
			(xy 95.86465 -216.545163) (xy 95.818492 -216.571812) (xy 95.768878 -216.591284) (xy 95.716916 -216.603144)
			(xy 95.663766 -216.607128) (xy 95.610616 -216.603144) (xy 95.558654 -216.591284) (xy 95.50904 -216.571812)
			(xy 95.462882 -216.545163) (xy 95.421211 -216.511932) (xy 95.384959 -216.472861) (xy 95.354935 -216.428824)
			(xy 95.331809 -216.380803) (xy 95.316099 -216.329873) (xy 95.308156 -216.277169) (xy 95.079576 -216.277169)
			(xy 95.071633 -216.329873) (xy 95.055923 -216.380803) (xy 95.032797 -216.428824) (xy 95.002773 -216.472861)
			(xy 94.966521 -216.511932) (xy 94.92485 -216.545163) (xy 94.878692 -216.571812) (xy 94.829078 -216.591284)
			(xy 94.777116 -216.603144) (xy 94.723966 -216.607128) (xy 94.670816 -216.603144) (xy 94.618854 -216.591284)
			(xy 94.56924 -216.571812) (xy 94.523082 -216.545163) (xy 94.481411 -216.511932) (xy 94.445159 -216.472861)
			(xy 94.415135 -216.428824) (xy 94.392009 -216.380803) (xy 94.376299 -216.329873) (xy 94.368356 -216.277169)
			(xy 94.139776 -216.277169) (xy 94.131833 -216.329873) (xy 94.116123 -216.380803) (xy 94.092997 -216.428824)
			(xy 94.062973 -216.472861) (xy 94.026721 -216.511932) (xy 93.98505 -216.545163) (xy 93.938892 -216.571812)
			(xy 93.889278 -216.591284) (xy 93.837316 -216.603144) (xy 93.784166 -216.607128) (xy 93.731016 -216.603144)
			(xy 93.679054 -216.591284) (xy 93.62944 -216.571812) (xy 93.583282 -216.545163) (xy 93.541611 -216.511932)
			(xy 93.505359 -216.472861) (xy 93.475335 -216.428824) (xy 93.452209 -216.380803) (xy 93.436499 -216.329873)
			(xy 93.428556 -216.277169) (xy 93.199976 -216.277169) (xy 93.192033 -216.329873) (xy 93.176323 -216.380803)
			(xy 93.153197 -216.428824) (xy 93.123173 -216.472861) (xy 93.086921 -216.511932) (xy 93.04525 -216.545163)
			(xy 92.999092 -216.571812) (xy 92.949478 -216.591284) (xy 92.897516 -216.603144) (xy 92.844366 -216.607128)
			(xy 92.791216 -216.603144) (xy 92.739254 -216.591284) (xy 92.68964 -216.571812) (xy 92.643482 -216.545163)
			(xy 92.601811 -216.511932) (xy 92.565559 -216.472861) (xy 92.535535 -216.428824) (xy 92.512409 -216.380803)
			(xy 92.496699 -216.329873) (xy 92.488756 -216.277169) (xy 92.285747 -216.277169) (xy 92.279251 -216.325845)
			(xy 92.266072 -216.374432) (xy 92.246603 -216.420858) (xy 92.234258 -216.442798) (xy 92.541344 -216.749884)
			(xy 92.547694 -216.75344) (xy 92.576396 -216.77122) (xy 93.07068 -216.77122) (xy 93.091317 -216.754642)
			(xy 93.136304 -216.726743) (xy 93.184717 -216.705335) (xy 93.235626 -216.690831) (xy 93.288052 -216.683508)
			(xy 93.340988 -216.683508) (xy 93.393414 -216.690831) (xy 93.444323 -216.705335) (xy 93.492736 -216.726743)
			(xy 93.537723 -216.754642) (xy 93.55836 -216.77122) (xy 94.052136 -216.77122) (xy 94.074535 -216.756407)
			(xy 94.122845 -216.732961) (xy 94.174126 -216.71703) (xy 94.227217 -216.708973) (xy 94.280915 -216.708973)
			(xy 94.334006 -216.71703) (xy 94.385287 -216.732961) (xy 94.433597 -216.756407) (xy 94.455996 -216.77122)
			(xy 94.95028 -216.77122) (xy 94.970917 -216.754642) (xy 95.015904 -216.726743) (xy 95.064317 -216.705335)
			(xy 95.115226 -216.690831) (xy 95.167652 -216.683508) (xy 95.220588 -216.683508) (xy 95.273014 -216.690831)
			(xy 95.323923 -216.705335) (xy 95.372336 -216.726743) (xy 95.417323 -216.754642) (xy 95.43796 -216.77122)
			(xy 95.931736 -216.77122) (xy 95.954135 -216.756407) (xy 96.002445 -216.732961) (xy 96.053726 -216.71703)
			(xy 96.106817 -216.708973) (xy 96.160515 -216.708973) (xy 96.213606 -216.71703) (xy 96.264887 -216.732961)
			(xy 96.313197 -216.756407) (xy 96.335596 -216.77122) (xy 96.82988 -216.77122) (xy 96.850517 -216.754642)
			(xy 96.895504 -216.726743) (xy 96.943917 -216.705335) (xy 96.994826 -216.690831) (xy 97.047252 -216.683508)
			(xy 97.100188 -216.683508) (xy 97.152614 -216.690831) (xy 97.203523 -216.705335) (xy 97.251936 -216.726743)
			(xy 97.296923 -216.754642) (xy 97.31756 -216.77122) (xy 97.811336 -216.77122) (xy 97.833735 -216.756407)
			(xy 97.882045 -216.732961) (xy 97.933326 -216.71703) (xy 97.986417 -216.708973) (xy 98.040115 -216.708973)
			(xy 98.093206 -216.71703) (xy 98.144487 -216.732961) (xy 98.192797 -216.756407) (xy 98.215196 -216.77122)
			(xy 98.70948 -216.77122) (xy 98.730115 -216.754639) (xy 98.7751 -216.726738) (xy 98.823514 -216.705332)
			(xy 98.874425 -216.690834) (xy 98.926852 -216.683523) (xy 98.95332 -216.683082) (xy 98.984056 -216.683701)
			(xy 99.044731 -216.693561) (xy 99.103041 -216.713021) (xy 99.157475 -216.741579) (xy 99.182428 -216.759536)
			(xy 99.217734 -216.786206)
		)
		(stroke
			(width 0)
			(type solid)
		)
		(fill yes)
		(layer "B.Cu")
		(net "PVCCFA_EHV_CPU1")
	)
	(gr_poly
		(pts
			(xy 347.199458 -216.744042) (xy 347.208671 -216.73426) (xy 347.222062 -216.710974) (xy 347.228912 -216.685)
			(xy 347.228744 -216.658139) (xy 347.221571 -216.632252) (xy 347.20789 -216.609135) (xy 347.18865 -216.59039)
			(xy 347.177106 -216.583514) (xy 347.152092 -216.56895) (xy 347.106381 -216.533445) (xy 347.066561 -216.491438)
			(xy 347.033548 -216.443896) (xy 347.0081 -216.39191) (xy 346.990802 -216.336675) (xy 346.982051 -216.27946)
			(xy 346.981526 -216.25052) (xy 346.981988 -216.223267) (xy 346.989743 -216.169316) (xy 347.005097 -216.117018)
			(xy 347.027739 -216.067437) (xy 347.057207 -216.021584) (xy 347.092901 -215.980392) (xy 347.134095 -215.944699)
			(xy 347.179949 -215.915233) (xy 347.229531 -215.892593) (xy 347.28183 -215.87724) (xy 347.335781 -215.869487)
			(xy 347.363034 -215.869012) (xy 347.391973 -215.869552) (xy 347.449185 -215.878304) (xy 347.504417 -215.895603)
			(xy 347.5564 -215.92105) (xy 347.603939 -215.954062) (xy 347.645944 -215.99388) (xy 347.681448 -216.039588)
			(xy 347.696028 -216.064592) (xy 347.70294 -216.076106) (xy 347.7217 -216.095309) (xy 347.744813 -216.108965)
			(xy 347.770684 -216.116132) (xy 347.79753 -216.116316) (xy 347.823497 -216.109503) (xy 347.846795 -216.096165)
			(xy 347.856556 -216.086944) (xy 348.219776 -215.723724) (xy 348.219776 -214.94369) (xy 348.186756 -214.931244)
			(xy 348.163535 -214.922032) (xy 348.119952 -214.897617) (xy 348.08055 -214.866909) (xy 348.046231 -214.83061)
			(xy 348.017778 -214.78955) (xy 347.995843 -214.744668) (xy 347.980928 -214.696992) (xy 347.973374 -214.647611)
			(xy 347.972888 -214.622634) (xy 347.97325 -214.599657) (xy 347.979563 -214.554141) (xy 347.992141 -214.509944)
			(xy 348.001082 -214.488776) (xy 348.010988 -214.466424) (xy 347.797374 -214.061294) (xy 347.773244 -214.056722)
			(xy 347.748324 -214.051629) (xy 347.700328 -214.034801) (xy 347.655484 -214.010805) (xy 347.614854 -213.98021)
			(xy 347.579403 -213.94374) (xy 347.549971 -213.902261) (xy 347.527254 -213.856755) (xy 347.511792 -213.808301)
			(xy 347.503952 -213.758048) (xy 347.503496 -213.732618) (xy 347.503976 -213.706729) (xy 347.512074 -213.655587)
			(xy 347.528073 -213.606342) (xy 347.55158 -213.560207) (xy 347.582015 -213.518317) (xy 347.618629 -213.481705)
			(xy 347.66052 -213.451272) (xy 347.706657 -213.427767) (xy 347.755903 -213.41177) (xy 347.807045 -213.403675)
			(xy 347.832934 -213.40318) (xy 347.858022 -213.403651) (xy 347.907617 -213.411256) (xy 347.955488 -213.426285)
			(xy 348.000531 -213.448392) (xy 348.041706 -213.477067) (xy 348.078062 -213.511646) (xy 348.093792 -213.531196)
			(xy 348.100797 -213.539504) (xy 348.119937 -213.549752) (xy 348.141601 -213.55119) (xy 348.161928 -213.543563)
			(xy 348.169992 -213.536276) (xy 348.219776 -213.486492) (xy 348.219776 -213.442296) (xy 349.217996 -212.444076)
			(xy 349.217996 -209.490056) (xy 349.485204 -209.223356) (xy 352.33864 -209.223356) (xy 352.598228 -209.483198)
			(xy 352.598228 -212.405468) (xy 352.887026 -212.694266) (xy 355.493066 -212.694266) (xy 355.589586 -212.597746)
			(xy 355.589586 -198.914258) (xy 355.200458 -198.52513) (xy 342.185498 -198.52513) (xy 339.627464 -201.083164)
			(xy 339.627464 -207.149446) (xy 337.453224 -209.323686) (xy 337.453224 -213.732618) (xy 338.105496 -213.732618)
			(xy 338.106004 -213.706731) (xy 338.114103 -213.655593) (xy 338.130102 -213.606353) (xy 338.153608 -213.560221)
			(xy 338.18404 -213.518334) (xy 338.22065 -213.481724) (xy 338.262537 -213.451292) (xy 338.308669 -213.427786)
			(xy 338.357909 -213.411787) (xy 338.409047 -213.403688) (xy 338.460821 -213.403688) (xy 338.511959 -213.411787)
			(xy 338.561199 -213.427786) (xy 338.607331 -213.451292) (xy 338.649218 -213.481724) (xy 338.685828 -213.518334)
			(xy 338.71626 -213.560221) (xy 338.739766 -213.606353) (xy 338.755765 -213.655593) (xy 338.763864 -213.706731)
			(xy 338.764372 -213.732618) (xy 338.764023 -213.755595) (xy 338.763513 -213.759267) (xy 339.019124 -213.759267)
			(xy 339.019124 -213.705969) (xy 339.027067 -213.653265) (xy 339.042777 -213.602335) (xy 339.065903 -213.554314)
			(xy 339.095927 -213.510277) (xy 339.132179 -213.471206) (xy 339.17385 -213.437975) (xy 339.220008 -213.411326)
			(xy 339.269622 -213.391854) (xy 339.321584 -213.379994) (xy 339.374734 -213.376011) (xy 339.427884 -213.379994)
			(xy 339.479846 -213.391854) (xy 339.52946 -213.411326) (xy 339.575618 -213.437975) (xy 339.617289 -213.471206)
			(xy 339.653541 -213.510277) (xy 339.683565 -213.554314) (xy 339.706691 -213.602335) (xy 339.722401 -213.653265)
			(xy 339.730344 -213.705969) (xy 339.730842 -213.732618) (xy 339.985096 -213.732618) (xy 339.985604 -213.706731)
			(xy 339.993703 -213.655593) (xy 340.009702 -213.606353) (xy 340.033208 -213.560221) (xy 340.06364 -213.518334)
			(xy 340.10025 -213.481724) (xy 340.142137 -213.451292) (xy 340.188269 -213.427786) (xy 340.237509 -213.411787)
			(xy 340.288647 -213.403688) (xy 340.340421 -213.403688) (xy 340.391559 -213.411787) (xy 340.440799 -213.427786)
			(xy 340.486931 -213.451292) (xy 340.528818 -213.481724) (xy 340.565428 -213.518334) (xy 340.59586 -213.560221)
			(xy 340.619366 -213.606353) (xy 340.635365 -213.655593) (xy 340.643464 -213.706731) (xy 340.643972 -213.732618)
			(xy 340.643623 -213.755595) (xy 340.643113 -213.759267) (xy 340.898724 -213.759267) (xy 340.898724 -213.705969)
			(xy 340.906667 -213.653265) (xy 340.922377 -213.602335) (xy 340.945503 -213.554314) (xy 340.975527 -213.510277)
			(xy 341.011779 -213.471206) (xy 341.05345 -213.437975) (xy 341.099608 -213.411326) (xy 341.149222 -213.391854)
			(xy 341.201184 -213.379994) (xy 341.254334 -213.376011) (xy 341.307484 -213.379994) (xy 341.359446 -213.391854)
			(xy 341.40906 -213.411326) (xy 341.455218 -213.437975) (xy 341.496889 -213.471206) (xy 341.533141 -213.510277)
			(xy 341.563165 -213.554314) (xy 341.586291 -213.602335) (xy 341.602001 -213.653265) (xy 341.609944 -213.705969)
			(xy 341.610442 -213.732618) (xy 341.864696 -213.732618) (xy 341.865204 -213.706731) (xy 341.873303 -213.655593)
			(xy 341.889302 -213.606353) (xy 341.912808 -213.560221) (xy 341.94324 -213.518334) (xy 341.97985 -213.481724)
			(xy 342.021737 -213.451292) (xy 342.067869 -213.427786) (xy 342.117109 -213.411787) (xy 342.168247 -213.403688)
			(xy 342.220021 -213.403688) (xy 342.271159 -213.411787) (xy 342.320399 -213.427786) (xy 342.366531 -213.451292)
			(xy 342.408418 -213.481724) (xy 342.445028 -213.518334) (xy 342.47546 -213.560221) (xy 342.498966 -213.606353)
			(xy 342.514965 -213.655593) (xy 342.523064 -213.706731) (xy 342.523572 -213.732618) (xy 342.523223 -213.755595)
			(xy 342.522713 -213.759267) (xy 342.778324 -213.759267) (xy 342.778324 -213.705969) (xy 342.786267 -213.653265)
			(xy 342.801977 -213.602335) (xy 342.825103 -213.554314) (xy 342.855127 -213.510277) (xy 342.891379 -213.471206)
			(xy 342.93305 -213.437975) (xy 342.979208 -213.411326) (xy 343.028822 -213.391854) (xy 343.080784 -213.379994)
			(xy 343.133934 -213.376011) (xy 343.187084 -213.379994) (xy 343.239046 -213.391854) (xy 343.28866 -213.411326)
			(xy 343.334818 -213.437975) (xy 343.376489 -213.471206) (xy 343.412741 -213.510277) (xy 343.442765 -213.554314)
			(xy 343.465891 -213.602335) (xy 343.481601 -213.653265) (xy 343.489544 -213.705969) (xy 343.490042 -213.732618)
			(xy 343.744296 -213.732618) (xy 343.744804 -213.706731) (xy 343.752903 -213.655593) (xy 343.768902 -213.606353)
			(xy 343.792408 -213.560221) (xy 343.82284 -213.518334) (xy 343.85945 -213.481724) (xy 343.901337 -213.451292)
			(xy 343.947469 -213.427786) (xy 343.996709 -213.411787) (xy 344.047847 -213.403688) (xy 344.099621 -213.403688)
			(xy 344.150759 -213.411787) (xy 344.199999 -213.427786) (xy 344.246131 -213.451292) (xy 344.288018 -213.481724)
			(xy 344.324628 -213.518334) (xy 344.35506 -213.560221) (xy 344.378566 -213.606353) (xy 344.394565 -213.655593)
			(xy 344.402664 -213.706731) (xy 344.403172 -213.732618) (xy 344.402823 -213.755595) (xy 344.402313 -213.759267)
			(xy 344.657924 -213.759267) (xy 344.657924 -213.705969) (xy 344.665867 -213.653265) (xy 344.681577 -213.602335)
			(xy 344.704703 -213.554314) (xy 344.734727 -213.510277) (xy 344.770979 -213.471206) (xy 344.81265 -213.437975)
			(xy 344.858808 -213.411326) (xy 344.908422 -213.391854) (xy 344.960384 -213.379994) (xy 345.013534 -213.376011)
			(xy 345.066684 -213.379994) (xy 345.118646 -213.391854) (xy 345.16826 -213.411326) (xy 345.214418 -213.437975)
			(xy 345.256089 -213.471206) (xy 345.292341 -213.510277) (xy 345.322365 -213.554314) (xy 345.345491 -213.602335)
			(xy 345.361201 -213.653265) (xy 345.369144 -213.705969) (xy 345.369642 -213.732618) (xy 345.623896 -213.732618)
			(xy 345.624404 -213.706731) (xy 345.632503 -213.655593) (xy 345.648502 -213.606353) (xy 345.672008 -213.560221)
			(xy 345.70244 -213.518334) (xy 345.73905 -213.481724) (xy 345.780937 -213.451292) (xy 345.827069 -213.427786)
			(xy 345.876309 -213.411787) (xy 345.927447 -213.403688) (xy 345.979221 -213.403688) (xy 346.030359 -213.411787)
			(xy 346.079599 -213.427786) (xy 346.125731 -213.451292) (xy 346.167618 -213.481724) (xy 346.204228 -213.518334)
			(xy 346.23466 -213.560221) (xy 346.258166 -213.606353) (xy 346.274165 -213.655593) (xy 346.282264 -213.706731)
			(xy 346.282772 -213.732618) (xy 346.282423 -213.755595) (xy 346.281913 -213.759267) (xy 346.537524 -213.759267)
			(xy 346.537524 -213.705969) (xy 346.545467 -213.653265) (xy 346.561177 -213.602335) (xy 346.584303 -213.554314)
			(xy 346.614327 -213.510277) (xy 346.650579 -213.471206) (xy 346.69225 -213.437975) (xy 346.738408 -213.411326)
			(xy 346.788022 -213.391854) (xy 346.839984 -213.379994) (xy 346.893134 -213.376011) (xy 346.946284 -213.379994)
			(xy 346.998246 -213.391854) (xy 347.04786 -213.411326) (xy 347.094018 -213.437975) (xy 347.135689 -213.471206)
			(xy 347.171941 -213.510277) (xy 347.201965 -213.554314) (xy 347.225091 -213.602335) (xy 347.240801 -213.653265)
			(xy 347.248744 -213.705969) (xy 347.249242 -213.732618) (xy 347.248744 -213.759267) (xy 347.240801 -213.811971)
			(xy 347.225091 -213.862901) (xy 347.201965 -213.910922) (xy 347.171941 -213.954959) (xy 347.135689 -213.99403)
			(xy 347.094018 -214.027261) (xy 347.04786 -214.05391) (xy 346.998246 -214.073382) (xy 346.946284 -214.085242)
			(xy 346.893134 -214.089226) (xy 346.839984 -214.085242) (xy 346.788022 -214.073382) (xy 346.738408 -214.05391)
			(xy 346.69225 -214.027261) (xy 346.650579 -213.99403) (xy 346.614327 -213.954959) (xy 346.584303 -213.910922)
			(xy 346.561177 -213.862901) (xy 346.545467 -213.811971) (xy 346.537524 -213.759267) (xy 346.281913 -213.759267)
			(xy 346.276102 -213.801111) (xy 346.263516 -213.845306) (xy 346.254578 -213.866476) (xy 346.244672 -213.888828)
			(xy 346.458286 -214.293958) (xy 346.482416 -214.29853) (xy 346.50733 -214.303664) (xy 346.55534 -214.320459)
			(xy 346.600199 -214.344434) (xy 346.640841 -214.375017) (xy 346.676299 -214.411484) (xy 346.705732 -214.452967)
			(xy 346.72844 -214.49848) (xy 346.743883 -214.546942) (xy 346.751695 -214.597202) (xy 346.752164 -214.622634)
			(xy 346.751656 -214.648521) (xy 346.743557 -214.699659) (xy 346.727558 -214.748899) (xy 346.704052 -214.795031)
			(xy 346.67362 -214.836918) (xy 346.63701 -214.873528) (xy 346.595123 -214.90396) (xy 346.548991 -214.927466)
			(xy 346.499751 -214.943465) (xy 346.448613 -214.951564) (xy 346.396839 -214.951564) (xy 346.345701 -214.943465)
			(xy 346.296461 -214.927466) (xy 346.250329 -214.90396) (xy 346.208442 -214.873528) (xy 346.171832 -214.836918)
			(xy 346.1414 -214.795031) (xy 346.117894 -214.748899) (xy 346.101895 -214.699659) (xy 346.093796 -214.648521)
			(xy 346.093288 -214.622634) (xy 346.093658 -214.599658) (xy 346.09997 -214.554143) (xy 346.112548 -214.509947)
			(xy 346.121482 -214.488776) (xy 346.131388 -214.466424) (xy 345.917774 -214.061294) (xy 345.893644 -214.056722)
			(xy 345.868713 -214.051663) (xy 345.820699 -214.034858) (xy 345.775839 -214.010874) (xy 345.735197 -213.980281)
			(xy 345.699739 -213.943805) (xy 345.670309 -213.902313) (xy 345.647605 -213.856791) (xy 345.632167 -213.80832)
			(xy 345.624362 -213.758053) (xy 345.623896 -213.732618) (xy 345.369642 -213.732618) (xy 345.369144 -213.759267)
			(xy 345.361201 -213.811971) (xy 345.345491 -213.862901) (xy 345.322365 -213.910922) (xy 345.292341 -213.954959)
			(xy 345.256089 -213.99403) (xy 345.214418 -214.027261) (xy 345.16826 -214.05391) (xy 345.118646 -214.073382)
			(xy 345.066684 -214.085242) (xy 345.013534 -214.089226) (xy 344.960384 -214.085242) (xy 344.908422 -214.073382)
			(xy 344.858808 -214.05391) (xy 344.81265 -214.027261) (xy 344.770979 -213.99403) (xy 344.734727 -213.954959)
			(xy 344.704703 -213.910922) (xy 344.681577 -213.862901) (xy 344.665867 -213.811971) (xy 344.657924 -213.759267)
			(xy 344.402313 -213.759267) (xy 344.396502 -213.801111) (xy 344.383916 -213.845306) (xy 344.374978 -213.866476)
			(xy 344.365072 -213.888828) (xy 344.578686 -214.293958) (xy 344.602816 -214.29853) (xy 344.62773 -214.303664)
			(xy 344.67574 -214.320459) (xy 344.720599 -214.344434) (xy 344.761241 -214.375017) (xy 344.796699 -214.411484)
			(xy 344.826132 -214.452967) (xy 344.84884 -214.49848) (xy 344.864283 -214.546942) (xy 344.872095 -214.597202)
			(xy 344.872564 -214.622634) (xy 344.872056 -214.648521) (xy 344.863957 -214.699659) (xy 344.847958 -214.748899)
			(xy 344.824452 -214.795031) (xy 344.79402 -214.836918) (xy 344.75741 -214.873528) (xy 344.715523 -214.90396)
			(xy 344.669391 -214.927466) (xy 344.620151 -214.943465) (xy 344.569013 -214.951564) (xy 344.517239 -214.951564)
			(xy 344.466101 -214.943465) (xy 344.416861 -214.927466) (xy 344.370729 -214.90396) (xy 344.328842 -214.873528)
			(xy 344.292232 -214.836918) (xy 344.2618 -214.795031) (xy 344.238294 -214.748899) (xy 344.222295 -214.699659)
			(xy 344.214196 -214.648521) (xy 344.213688 -214.622634) (xy 344.214058 -214.599658) (xy 344.22037 -214.554143)
			(xy 344.232948 -214.509947) (xy 344.241882 -214.488776) (xy 344.251788 -214.466424) (xy 344.038174 -214.061294)
			(xy 344.014044 -214.056722) (xy 343.989113 -214.051663) (xy 343.941099 -214.034858) (xy 343.896239 -214.010874)
			(xy 343.855597 -213.980281) (xy 343.820139 -213.943805) (xy 343.790709 -213.902313) (xy 343.768005 -213.856791)
			(xy 343.752567 -213.80832) (xy 343.744762 -213.758053) (xy 343.744296 -213.732618) (xy 343.490042 -213.732618)
			(xy 343.489544 -213.759267) (xy 343.481601 -213.811971) (xy 343.465891 -213.862901) (xy 343.442765 -213.910922)
			(xy 343.412741 -213.954959) (xy 343.376489 -213.99403) (xy 343.334818 -214.027261) (xy 343.28866 -214.05391)
			(xy 343.239046 -214.073382) (xy 343.187084 -214.085242) (xy 343.133934 -214.089226) (xy 343.080784 -214.085242)
			(xy 343.028822 -214.073382) (xy 342.979208 -214.05391) (xy 342.93305 -214.027261) (xy 342.891379 -213.99403)
			(xy 342.855127 -213.954959) (xy 342.825103 -213.910922) (xy 342.801977 -213.862901) (xy 342.786267 -213.811971)
			(xy 342.778324 -213.759267) (xy 342.522713 -213.759267) (xy 342.516902 -213.801111) (xy 342.504316 -213.845306)
			(xy 342.495378 -213.866476) (xy 342.485472 -213.888828) (xy 342.699086 -214.293958) (xy 342.723216 -214.29853)
			(xy 342.74813 -214.303664) (xy 342.79614 -214.320459) (xy 342.840999 -214.344434) (xy 342.881641 -214.375017)
			(xy 342.917099 -214.411484) (xy 342.946532 -214.452967) (xy 342.96924 -214.49848) (xy 342.984683 -214.546942)
			(xy 342.992495 -214.597202) (xy 342.992964 -214.622634) (xy 342.992456 -214.648521) (xy 342.984357 -214.699659)
			(xy 342.968358 -214.748899) (xy 342.944852 -214.795031) (xy 342.91442 -214.836918) (xy 342.87781 -214.873528)
			(xy 342.835923 -214.90396) (xy 342.789791 -214.927466) (xy 342.740551 -214.943465) (xy 342.689413 -214.951564)
			(xy 342.637639 -214.951564) (xy 342.586501 -214.943465) (xy 342.537261 -214.927466) (xy 342.491129 -214.90396)
			(xy 342.449242 -214.873528) (xy 342.412632 -214.836918) (xy 342.3822 -214.795031) (xy 342.358694 -214.748899)
			(xy 342.342695 -214.699659) (xy 342.334596 -214.648521) (xy 342.334088 -214.622634) (xy 342.334458 -214.599658)
			(xy 342.34077 -214.554143) (xy 342.353348 -214.509947) (xy 342.362282 -214.488776) (xy 342.372188 -214.466424)
			(xy 342.158574 -214.061294) (xy 342.134444 -214.056722) (xy 342.109513 -214.051663) (xy 342.061499 -214.034858)
			(xy 342.016639 -214.010874) (xy 341.975997 -213.980281) (xy 341.940539 -213.943805) (xy 341.911109 -213.902313)
			(xy 341.888405 -213.856791) (xy 341.872967 -213.80832) (xy 341.865162 -213.758053) (xy 341.864696 -213.732618)
			(xy 341.610442 -213.732618) (xy 341.609944 -213.759267) (xy 341.602001 -213.811971) (xy 341.586291 -213.862901)
			(xy 341.563165 -213.910922) (xy 341.533141 -213.954959) (xy 341.496889 -213.99403) (xy 341.455218 -214.027261)
			(xy 341.40906 -214.05391) (xy 341.359446 -214.073382) (xy 341.307484 -214.085242) (xy 341.254334 -214.089226)
			(xy 341.201184 -214.085242) (xy 341.149222 -214.073382) (xy 341.099608 -214.05391) (xy 341.05345 -214.027261)
			(xy 341.011779 -213.99403) (xy 340.975527 -213.954959) (xy 340.945503 -213.910922) (xy 340.922377 -213.862901)
			(xy 340.906667 -213.811971) (xy 340.898724 -213.759267) (xy 340.643113 -213.759267) (xy 340.637302 -213.801111)
			(xy 340.624716 -213.845306) (xy 340.615778 -213.866476) (xy 340.605872 -213.888828) (xy 340.819486 -214.293958)
			(xy 340.843616 -214.29853) (xy 340.86853 -214.303664) (xy 340.91654 -214.320459) (xy 340.961399 -214.344434)
			(xy 341.002041 -214.375017) (xy 341.037499 -214.411484) (xy 341.066932 -214.452967) (xy 341.08964 -214.49848)
			(xy 341.105083 -214.546942) (xy 341.112895 -214.597202) (xy 341.113364 -214.622634) (xy 341.112856 -214.648521)
			(xy 341.104757 -214.699659) (xy 341.088758 -214.748899) (xy 341.065252 -214.795031) (xy 341.03482 -214.836918)
			(xy 340.99821 -214.873528) (xy 340.956323 -214.90396) (xy 340.910191 -214.927466) (xy 340.860951 -214.943465)
			(xy 340.809813 -214.951564) (xy 340.758039 -214.951564) (xy 340.706901 -214.943465) (xy 340.657661 -214.927466)
			(xy 340.611529 -214.90396) (xy 340.569642 -214.873528) (xy 340.533032 -214.836918) (xy 340.5026 -214.795031)
			(xy 340.479094 -214.748899) (xy 340.463095 -214.699659) (xy 340.454996 -214.648521) (xy 340.454488 -214.622634)
			(xy 340.454858 -214.599658) (xy 340.46117 -214.554143) (xy 340.473748 -214.509947) (xy 340.482682 -214.488776)
			(xy 340.492588 -214.466424) (xy 340.278974 -214.061294) (xy 340.254844 -214.056722) (xy 340.229913 -214.051663)
			(xy 340.181899 -214.034858) (xy 340.137039 -214.010874) (xy 340.096397 -213.980281) (xy 340.060939 -213.943805)
			(xy 340.031509 -213.902313) (xy 340.008805 -213.856791) (xy 339.993367 -213.80832) (xy 339.985562 -213.758053)
			(xy 339.985096 -213.732618) (xy 339.730842 -213.732618) (xy 339.730344 -213.759267) (xy 339.722401 -213.811971)
			(xy 339.706691 -213.862901) (xy 339.683565 -213.910922) (xy 339.653541 -213.954959) (xy 339.617289 -213.99403)
			(xy 339.575618 -214.027261) (xy 339.52946 -214.05391) (xy 339.479846 -214.073382) (xy 339.427884 -214.085242)
			(xy 339.374734 -214.089226) (xy 339.321584 -214.085242) (xy 339.269622 -214.073382) (xy 339.220008 -214.05391)
			(xy 339.17385 -214.027261) (xy 339.132179 -213.99403) (xy 339.095927 -213.954959) (xy 339.065903 -213.910922)
			(xy 339.042777 -213.862901) (xy 339.027067 -213.811971) (xy 339.019124 -213.759267) (xy 338.763513 -213.759267)
			(xy 338.757702 -213.801111) (xy 338.745116 -213.845306) (xy 338.736178 -213.866476) (xy 338.726272 -213.888828)
			(xy 338.939886 -214.293958) (xy 338.964016 -214.29853) (xy 338.98893 -214.303664) (xy 339.03694 -214.320459)
			(xy 339.081799 -214.344434) (xy 339.122441 -214.375017) (xy 339.157899 -214.411484) (xy 339.187332 -214.452967)
			(xy 339.21004 -214.49848) (xy 339.225483 -214.546942) (xy 339.233295 -214.597202) (xy 339.233764 -214.622634)
			(xy 339.233256 -214.648521) (xy 339.225157 -214.699659) (xy 339.209158 -214.748899) (xy 339.185652 -214.795031)
			(xy 339.15522 -214.836918) (xy 339.11861 -214.873528) (xy 339.076723 -214.90396) (xy 339.030591 -214.927466)
			(xy 338.981351 -214.943465) (xy 338.930213 -214.951564) (xy 338.878439 -214.951564) (xy 338.827301 -214.943465)
			(xy 338.778061 -214.927466) (xy 338.731929 -214.90396) (xy 338.690042 -214.873528) (xy 338.653432 -214.836918)
			(xy 338.623 -214.795031) (xy 338.599494 -214.748899) (xy 338.583495 -214.699659) (xy 338.575396 -214.648521)
			(xy 338.574888 -214.622634) (xy 338.575258 -214.599658) (xy 338.58157 -214.554143) (xy 338.594148 -214.509947)
			(xy 338.603082 -214.488776) (xy 338.612988 -214.466424) (xy 338.399374 -214.061294) (xy 338.375244 -214.056722)
			(xy 338.350313 -214.051663) (xy 338.302299 -214.034858) (xy 338.257439 -214.010874) (xy 338.216797 -213.980281)
			(xy 338.181339 -213.943805) (xy 338.151909 -213.902313) (xy 338.129205 -213.856791) (xy 338.113767 -213.80832)
			(xy 338.105962 -213.758053) (xy 338.105496 -213.732618) (xy 337.453224 -213.732618) (xy 337.453224 -214.734394)
			(xy 337.453728 -214.749197) (xy 337.462217 -214.77756) (xy 337.478482 -214.802298) (xy 337.501159 -214.821332)
			(xy 337.528342 -214.833064) (xy 337.557747 -214.836507) (xy 337.586905 -214.831373) (xy 337.613366 -214.818093)
			(xy 337.634907 -214.797783) (xy 337.642708 -214.785194) (xy 337.66125 -214.753444) (xy 337.653376 -214.7316)
			(xy 337.644798 -214.705181) (xy 337.635606 -214.650406) (xy 337.635088 -214.622634) (xy 337.635596 -214.596747)
			(xy 337.643695 -214.545609) (xy 337.659694 -214.496369) (xy 337.6832 -214.450237) (xy 337.713632 -214.40835)
			(xy 337.750242 -214.37174) (xy 337.792129 -214.341308) (xy 337.838261 -214.317802) (xy 337.887501 -214.301803)
			(xy 337.938639 -214.293704) (xy 337.990413 -214.293704) (xy 338.041551 -214.301803) (xy 338.090791 -214.317802)
			(xy 338.136923 -214.341308) (xy 338.17881 -214.37174) (xy 338.21542 -214.40835) (xy 338.245852 -214.450237)
			(xy 338.269358 -214.496369) (xy 338.285357 -214.545609) (xy 338.293456 -214.596747) (xy 338.293964 -214.622634)
			(xy 338.293498 -214.647968) (xy 338.28574 -214.698037) (xy 338.270413 -214.746331) (xy 338.247877 -214.79171)
			(xy 338.218664 -214.833108) (xy 338.18346 -214.869548) (xy 338.143096 -214.900173) (xy 338.098521 -214.924261)
			(xy 338.050785 -214.941245) (xy 338.025994 -214.946484) (xy 338.003134 -214.950802) (xy 337.798156 -215.305894)
			(xy 337.80603 -215.327738) (xy 337.814677 -215.354146) (xy 337.823999 -215.408922) (xy 337.824572 -215.436704)
			(xy 339.044788 -215.436704) (xy 339.045323 -215.411361) (xy 339.053093 -215.361274) (xy 339.068437 -215.312966)
			(xy 339.090992 -215.267575) (xy 339.120227 -215.226169) (xy 339.155454 -215.189725) (xy 339.195843 -215.159101)
			(xy 339.240442 -215.135018) (xy 339.288201 -215.118043) (xy 339.313012 -215.112854) (xy 339.335872 -215.108536)
			(xy 339.54085 -214.753444) (xy 339.532976 -214.7316) (xy 339.524399 -214.705181) (xy 339.5152 -214.650406)
			(xy 339.514688 -214.622634) (xy 339.515196 -214.596747) (xy 339.523295 -214.545609) (xy 339.539294 -214.496369)
			(xy 339.5628 -214.450237) (xy 339.593232 -214.40835) (xy 339.629842 -214.37174) (xy 339.671729 -214.341308)
			(xy 339.717861 -214.317802) (xy 339.767101 -214.301803) (xy 339.818239 -214.293704) (xy 339.870013 -214.293704)
			(xy 339.921151 -214.301803) (xy 339.970391 -214.317802) (xy 340.016523 -214.341308) (xy 340.05841 -214.37174)
			(xy 340.09502 -214.40835) (xy 340.125452 -214.450237) (xy 340.148958 -214.496369) (xy 340.164957 -214.545609)
			(xy 340.173056 -214.596747) (xy 340.173564 -214.622634) (xy 340.173141 -214.647971) (xy 340.165383 -214.698047)
			(xy 340.150054 -214.746347) (xy 340.127515 -214.791733) (xy 340.098298 -214.833136) (xy 340.06309 -214.869581)
			(xy 340.02272 -214.90021) (xy 339.978139 -214.924301) (xy 339.930397 -214.941288) (xy 339.905594 -214.946484)
			(xy 339.882734 -214.950802) (xy 339.677756 -215.305894) (xy 339.68563 -215.327738) (xy 339.694277 -215.354146)
			(xy 339.703597 -215.408922) (xy 339.704172 -215.436704) (xy 340.924388 -215.436704) (xy 340.924923 -215.411361)
			(xy 340.932693 -215.361274) (xy 340.948037 -215.312966) (xy 340.970592 -215.267575) (xy 340.999827 -215.226169)
			(xy 341.035054 -215.189725) (xy 341.075443 -215.159101) (xy 341.120042 -215.135018) (xy 341.167801 -215.118043)
			(xy 341.192612 -215.112854) (xy 341.215472 -215.108536) (xy 341.42045 -214.753444) (xy 341.412576 -214.7316)
			(xy 341.403999 -214.705181) (xy 341.3948 -214.650406) (xy 341.394288 -214.622634) (xy 341.394796 -214.596747)
			(xy 341.402895 -214.545609) (xy 341.418894 -214.496369) (xy 341.4424 -214.450237) (xy 341.472832 -214.40835)
			(xy 341.509442 -214.37174) (xy 341.551329 -214.341308) (xy 341.597461 -214.317802) (xy 341.646701 -214.301803)
			(xy 341.697839 -214.293704) (xy 341.749613 -214.293704) (xy 341.800751 -214.301803) (xy 341.849991 -214.317802)
			(xy 341.896123 -214.341308) (xy 341.93801 -214.37174) (xy 341.97462 -214.40835) (xy 342.005052 -214.450237)
			(xy 342.028558 -214.496369) (xy 342.044557 -214.545609) (xy 342.052656 -214.596747) (xy 342.053164 -214.622634)
			(xy 342.052741 -214.647971) (xy 342.044983 -214.698047) (xy 342.029654 -214.746347) (xy 342.007115 -214.791733)
			(xy 341.977898 -214.833136) (xy 341.94269 -214.869581) (xy 341.90232 -214.90021) (xy 341.857739 -214.924301)
			(xy 341.809997 -214.941288) (xy 341.785194 -214.946484) (xy 341.762334 -214.950802) (xy 341.557356 -215.305894)
			(xy 341.56523 -215.327738) (xy 341.573877 -215.354146) (xy 341.583197 -215.408922) (xy 341.583772 -215.436704)
			(xy 342.803988 -215.436704) (xy 342.804523 -215.411361) (xy 342.812293 -215.361274) (xy 342.827637 -215.312966)
			(xy 342.850192 -215.267575) (xy 342.879427 -215.226169) (xy 342.914654 -215.189725) (xy 342.955043 -215.159101)
			(xy 342.999642 -215.135018) (xy 343.047401 -215.118043) (xy 343.072212 -215.112854) (xy 343.095072 -215.108536)
			(xy 343.30005 -214.753444) (xy 343.292176 -214.7316) (xy 343.283599 -214.705181) (xy 343.2744 -214.650406)
			(xy 343.273888 -214.622634) (xy 343.274396 -214.596747) (xy 343.282495 -214.545609) (xy 343.298494 -214.496369)
			(xy 343.322 -214.450237) (xy 343.352432 -214.40835) (xy 343.389042 -214.37174) (xy 343.430929 -214.341308)
			(xy 343.477061 -214.317802) (xy 343.526301 -214.301803) (xy 343.577439 -214.293704) (xy 343.629213 -214.293704)
			(xy 343.680351 -214.301803) (xy 343.729591 -214.317802) (xy 343.775723 -214.341308) (xy 343.81761 -214.37174)
			(xy 343.85422 -214.40835) (xy 343.884652 -214.450237) (xy 343.908158 -214.496369) (xy 343.924157 -214.545609)
			(xy 343.932256 -214.596747) (xy 343.932764 -214.622634) (xy 343.932341 -214.647971) (xy 343.924583 -214.698047)
			(xy 343.909254 -214.746347) (xy 343.886715 -214.791733) (xy 343.857498 -214.833136) (xy 343.82229 -214.869581)
			(xy 343.78192 -214.90021) (xy 343.737339 -214.924301) (xy 343.689597 -214.941288) (xy 343.664794 -214.946484)
			(xy 343.641934 -214.950802) (xy 343.436956 -215.305894) (xy 343.44483 -215.327738) (xy 343.453477 -215.354146)
			(xy 343.462797 -215.408922) (xy 343.463372 -215.436704) (xy 344.683588 -215.436704) (xy 344.684123 -215.411361)
			(xy 344.691893 -215.361274) (xy 344.707237 -215.312966) (xy 344.729792 -215.267575) (xy 344.759027 -215.226169)
			(xy 344.794254 -215.189725) (xy 344.834643 -215.159101) (xy 344.879242 -215.135018) (xy 344.927001 -215.118043)
			(xy 344.951812 -215.112854) (xy 344.974672 -215.108536) (xy 345.17965 -214.753444) (xy 345.171776 -214.7316)
			(xy 345.163199 -214.705181) (xy 345.154 -214.650406) (xy 345.153488 -214.622634) (xy 345.153996 -214.596747)
			(xy 345.162095 -214.545609) (xy 345.178094 -214.496369) (xy 345.2016 -214.450237) (xy 345.232032 -214.40835)
			(xy 345.268642 -214.37174) (xy 345.310529 -214.341308) (xy 345.356661 -214.317802) (xy 345.405901 -214.301803)
			(xy 345.457039 -214.293704) (xy 345.508813 -214.293704) (xy 345.559951 -214.301803) (xy 345.609191 -214.317802)
			(xy 345.655323 -214.341308) (xy 345.69721 -214.37174) (xy 345.73382 -214.40835) (xy 345.764252 -214.450237)
			(xy 345.787758 -214.496369) (xy 345.803757 -214.545609) (xy 345.811856 -214.596747) (xy 345.812364 -214.622634)
			(xy 345.811941 -214.647971) (xy 345.804183 -214.698047) (xy 345.788854 -214.746347) (xy 345.766315 -214.791733)
			(xy 345.737098 -214.833136) (xy 345.70189 -214.869581) (xy 345.66152 -214.90021) (xy 345.616939 -214.924301)
			(xy 345.569197 -214.941288) (xy 345.544394 -214.946484) (xy 345.521534 -214.950802) (xy 345.316556 -215.305894)
			(xy 345.32443 -215.327738) (xy 345.333077 -215.354146) (xy 345.342397 -215.408922) (xy 345.342972 -215.436704)
			(xy 346.563188 -215.436704) (xy 346.563723 -215.411361) (xy 346.571493 -215.361274) (xy 346.586837 -215.312966)
			(xy 346.609392 -215.267575) (xy 346.638627 -215.226169) (xy 346.673854 -215.189725) (xy 346.714243 -215.159101)
			(xy 346.758842 -215.135018) (xy 346.806601 -215.118043) (xy 346.831412 -215.112854) (xy 346.854272 -215.108536)
			(xy 347.05925 -214.753444) (xy 347.051376 -214.7316) (xy 347.042799 -214.705181) (xy 347.0336 -214.650406)
			(xy 347.033088 -214.622634) (xy 347.033596 -214.596747) (xy 347.041695 -214.545609) (xy 347.057694 -214.496369)
			(xy 347.0812 -214.450237) (xy 347.111632 -214.40835) (xy 347.148242 -214.37174) (xy 347.190129 -214.341308)
			(xy 347.236261 -214.317802) (xy 347.285501 -214.301803) (xy 347.336639 -214.293704) (xy 347.388413 -214.293704)
			(xy 347.439551 -214.301803) (xy 347.488791 -214.317802) (xy 347.534923 -214.341308) (xy 347.57681 -214.37174)
			(xy 347.61342 -214.40835) (xy 347.643852 -214.450237) (xy 347.667358 -214.496369) (xy 347.683357 -214.545609)
			(xy 347.691456 -214.596747) (xy 347.691964 -214.622634) (xy 347.691541 -214.647971) (xy 347.683783 -214.698047)
			(xy 347.668454 -214.746347) (xy 347.645915 -214.791733) (xy 347.616698 -214.833136) (xy 347.58149 -214.869581)
			(xy 347.54112 -214.90021) (xy 347.496539 -214.924301) (xy 347.448797 -214.941288) (xy 347.423994 -214.946484)
			(xy 347.401134 -214.950802) (xy 347.196156 -215.305894) (xy 347.20403 -215.327738) (xy 347.212677 -215.354146)
			(xy 347.221997 -215.408922) (xy 347.222572 -215.436704) (xy 347.222064 -215.462611) (xy 347.213958 -215.513788)
			(xy 347.197946 -215.563067) (xy 347.174423 -215.609234) (xy 347.143967 -215.651153) (xy 347.107329 -215.687791)
			(xy 347.06541 -215.718247) (xy 347.019243 -215.74177) (xy 346.969964 -215.757782) (xy 346.918787 -215.765888)
			(xy 346.866973 -215.765888) (xy 346.815796 -215.757782) (xy 346.766517 -215.74177) (xy 346.72035 -215.718247)
			(xy 346.678431 -215.687791) (xy 346.641793 -215.651153) (xy 346.611337 -215.609234) (xy 346.587814 -215.563067)
			(xy 346.571802 -215.513788) (xy 346.563696 -215.462611) (xy 346.563188 -215.436704) (xy 345.342972 -215.436704)
			(xy 345.342464 -215.462611) (xy 345.334358 -215.513788) (xy 345.318346 -215.563067) (xy 345.294823 -215.609234)
			(xy 345.264367 -215.651153) (xy 345.227729 -215.687791) (xy 345.18581 -215.718247) (xy 345.139643 -215.74177)
			(xy 345.090364 -215.757782) (xy 345.039187 -215.765888) (xy 344.987373 -215.765888) (xy 344.936196 -215.757782)
			(xy 344.886917 -215.74177) (xy 344.84075 -215.718247) (xy 344.798831 -215.687791) (xy 344.762193 -215.651153)
			(xy 344.731737 -215.609234) (xy 344.708214 -215.563067) (xy 344.692202 -215.513788) (xy 344.684096 -215.462611)
			(xy 344.683588 -215.436704) (xy 343.463372 -215.436704) (xy 343.462864 -215.462611) (xy 343.454758 -215.513788)
			(xy 343.438746 -215.563067) (xy 343.415223 -215.609234) (xy 343.384767 -215.651153) (xy 343.348129 -215.687791)
			(xy 343.30621 -215.718247) (xy 343.260043 -215.74177) (xy 343.210764 -215.757782) (xy 343.159587 -215.765888)
			(xy 343.107773 -215.765888) (xy 343.056596 -215.757782) (xy 343.007317 -215.74177) (xy 342.96115 -215.718247)
			(xy 342.919231 -215.687791) (xy 342.882593 -215.651153) (xy 342.852137 -215.609234) (xy 342.828614 -215.563067)
			(xy 342.812602 -215.513788) (xy 342.804496 -215.462611) (xy 342.803988 -215.436704) (xy 341.583772 -215.436704)
			(xy 341.583264 -215.462611) (xy 341.575158 -215.513788) (xy 341.559146 -215.563067) (xy 341.535623 -215.609234)
			(xy 341.505167 -215.651153) (xy 341.468529 -215.687791) (xy 341.42661 -215.718247) (xy 341.380443 -215.74177)
			(xy 341.331164 -215.757782) (xy 341.279987 -215.765888) (xy 341.228173 -215.765888) (xy 341.176996 -215.757782)
			(xy 341.127717 -215.74177) (xy 341.08155 -215.718247) (xy 341.039631 -215.687791) (xy 341.002993 -215.651153)
			(xy 340.972537 -215.609234) (xy 340.949014 -215.563067) (xy 340.933002 -215.513788) (xy 340.924896 -215.462611)
			(xy 340.924388 -215.436704) (xy 339.704172 -215.436704) (xy 339.703664 -215.462611) (xy 339.695558 -215.513788)
			(xy 339.679546 -215.563067) (xy 339.656023 -215.609234) (xy 339.625567 -215.651153) (xy 339.588929 -215.687791)
			(xy 339.54701 -215.718247) (xy 339.500843 -215.74177) (xy 339.451564 -215.757782) (xy 339.400387 -215.765888)
			(xy 339.348573 -215.765888) (xy 339.297396 -215.757782) (xy 339.248117 -215.74177) (xy 339.20195 -215.718247)
			(xy 339.160031 -215.687791) (xy 339.123393 -215.651153) (xy 339.092937 -215.609234) (xy 339.069414 -215.563067)
			(xy 339.053402 -215.513788) (xy 339.045296 -215.462611) (xy 339.044788 -215.436704) (xy 337.824572 -215.436704)
			(xy 337.824088 -215.462621) (xy 337.815968 -215.513816) (xy 337.79993 -215.563108) (xy 337.776369 -215.609278)
			(xy 337.745867 -215.651189) (xy 337.709177 -215.687804) (xy 337.667204 -215.718221) (xy 337.620986 -215.741687)
			(xy 337.59648 -215.75014) (xy 337.582469 -215.755186) (xy 337.557966 -215.772084) (xy 337.539384 -215.795337)
			(xy 337.528307 -215.822964) (xy 337.525678 -215.852613) (xy 337.531721 -215.881758) (xy 337.545922 -215.907918)
			(xy 337.556094 -215.918796) (xy 337.613752 -215.976454) (xy 337.736942 -215.976454) (xy 337.750658 -215.966294)
			(xy 337.773957 -215.949393) (xy 337.824874 -215.922553) (xy 337.879448 -215.904263) (xy 337.936255 -215.895)
			(xy 337.965034 -215.894412) (xy 337.989702 -215.894834) (xy 338.038566 -215.901649) (xy 338.086021 -215.915146)
			(xy 338.131158 -215.935064) (xy 338.173114 -215.961022) (xy 338.192364 -215.976454) (xy 338.639404 -215.976454)
			(xy 338.660878 -215.956411) (xy 338.70884 -215.922502) (xy 338.761435 -215.896347) (xy 338.817417 -215.878567)
			(xy 338.875465 -215.86958) (xy 338.904834 -215.869012) (xy 338.934216 -215.869556) (xy 338.992284 -215.878572)
			(xy 339.048282 -215.896386) (xy 339.100887 -215.922577) (xy 339.148853 -215.956524) (xy 339.191046 -215.997425)
			(xy 339.226468 -216.044313) (xy 339.240876 -216.069926) (xy 339.508592 -216.069926) (xy 339.52298 -216.044302)
			(xy 339.55841 -215.997419) (xy 339.600609 -215.956522) (xy 339.648578 -215.922578) (xy 339.701184 -215.896389)
			(xy 339.757183 -215.878574) (xy 339.815252 -215.869555) (xy 339.844634 -215.869012) (xy 339.871883 -215.869501)
			(xy 339.925826 -215.877261) (xy 339.978115 -215.892619) (xy 340.027687 -215.915263) (xy 340.073532 -215.94473)
			(xy 340.114716 -215.980422) (xy 340.150402 -216.021612) (xy 340.179863 -216.06746) (xy 340.202499 -216.117035)
			(xy 340.21785 -216.169327) (xy 340.225603 -216.223271) (xy 340.226142 -216.25052) (xy 340.225728 -216.275692)
			(xy 340.225531 -216.277169) (xy 340.428824 -216.277169) (xy 340.428824 -216.223871) (xy 340.436767 -216.171167)
			(xy 340.452477 -216.120237) (xy 340.475603 -216.072216) (xy 340.505627 -216.028179) (xy 340.541879 -215.989108)
			(xy 340.58355 -215.955877) (xy 340.629708 -215.929228) (xy 340.679322 -215.909756) (xy 340.731284 -215.897896)
			(xy 340.784434 -215.893913) (xy 340.837584 -215.897896) (xy 340.889546 -215.909756) (xy 340.93916 -215.929228)
			(xy 340.985318 -215.955877) (xy 341.026989 -215.989108) (xy 341.063241 -216.028179) (xy 341.093265 -216.072216)
			(xy 341.116391 -216.120237) (xy 341.132101 -216.171167) (xy 341.140044 -216.223871) (xy 341.140542 -216.25052)
			(xy 341.140044 -216.277169) (xy 341.368624 -216.277169) (xy 341.368624 -216.223871) (xy 341.376567 -216.171167)
			(xy 341.392277 -216.120237) (xy 341.415403 -216.072216) (xy 341.445427 -216.028179) (xy 341.481679 -215.989108)
			(xy 341.52335 -215.955877) (xy 341.569508 -215.929228) (xy 341.619122 -215.909756) (xy 341.671084 -215.897896)
			(xy 341.724234 -215.893913) (xy 341.777384 -215.897896) (xy 341.829346 -215.909756) (xy 341.87896 -215.929228)
			(xy 341.925118 -215.955877) (xy 341.966789 -215.989108) (xy 342.003041 -216.028179) (xy 342.033065 -216.072216)
			(xy 342.056191 -216.120237) (xy 342.071901 -216.171167) (xy 342.079844 -216.223871) (xy 342.080342 -216.25052)
			(xy 342.079844 -216.277169) (xy 342.308424 -216.277169) (xy 342.308424 -216.223871) (xy 342.316367 -216.171167)
			(xy 342.332077 -216.120237) (xy 342.355203 -216.072216) (xy 342.385227 -216.028179) (xy 342.421479 -215.989108)
			(xy 342.46315 -215.955877) (xy 342.509308 -215.929228) (xy 342.558922 -215.909756) (xy 342.610884 -215.897896)
			(xy 342.664034 -215.893913) (xy 342.717184 -215.897896) (xy 342.769146 -215.909756) (xy 342.81876 -215.929228)
			(xy 342.864918 -215.955877) (xy 342.906589 -215.989108) (xy 342.942841 -216.028179) (xy 342.972865 -216.072216)
			(xy 342.995991 -216.120237) (xy 343.011701 -216.171167) (xy 343.019644 -216.223871) (xy 343.020142 -216.25052)
			(xy 343.019644 -216.277169) (xy 343.248224 -216.277169) (xy 343.248224 -216.223871) (xy 343.256167 -216.171167)
			(xy 343.271877 -216.120237) (xy 343.295003 -216.072216) (xy 343.325027 -216.028179) (xy 343.361279 -215.989108)
			(xy 343.40295 -215.955877) (xy 343.449108 -215.929228) (xy 343.498722 -215.909756) (xy 343.550684 -215.897896)
			(xy 343.603834 -215.893913) (xy 343.656984 -215.897896) (xy 343.708946 -215.909756) (xy 343.75856 -215.929228)
			(xy 343.804718 -215.955877) (xy 343.846389 -215.989108) (xy 343.882641 -216.028179) (xy 343.912665 -216.072216)
			(xy 343.935791 -216.120237) (xy 343.951501 -216.171167) (xy 343.959444 -216.223871) (xy 343.959942 -216.25052)
			(xy 343.959444 -216.277169) (xy 344.188024 -216.277169) (xy 344.188024 -216.223871) (xy 344.195967 -216.171167)
			(xy 344.211677 -216.120237) (xy 344.234803 -216.072216) (xy 344.264827 -216.028179) (xy 344.301079 -215.989108)
			(xy 344.34275 -215.955877) (xy 344.388908 -215.929228) (xy 344.438522 -215.909756) (xy 344.490484 -215.897896)
			(xy 344.543634 -215.893913) (xy 344.596784 -215.897896) (xy 344.648746 -215.909756) (xy 344.69836 -215.929228)
			(xy 344.744518 -215.955877) (xy 344.786189 -215.989108) (xy 344.822441 -216.028179) (xy 344.852465 -216.072216)
			(xy 344.875591 -216.120237) (xy 344.891301 -216.171167) (xy 344.899244 -216.223871) (xy 344.899742 -216.25052)
			(xy 344.899244 -216.277169) (xy 345.127824 -216.277169) (xy 345.127824 -216.223871) (xy 345.135767 -216.171167)
			(xy 345.151477 -216.120237) (xy 345.174603 -216.072216) (xy 345.204627 -216.028179) (xy 345.240879 -215.989108)
			(xy 345.28255 -215.955877) (xy 345.328708 -215.929228) (xy 345.378322 -215.909756) (xy 345.430284 -215.897896)
			(xy 345.483434 -215.893913) (xy 345.536584 -215.897896) (xy 345.588546 -215.909756) (xy 345.63816 -215.929228)
			(xy 345.684318 -215.955877) (xy 345.725989 -215.989108) (xy 345.762241 -216.028179) (xy 345.792265 -216.072216)
			(xy 345.815391 -216.120237) (xy 345.831101 -216.171167) (xy 345.839044 -216.223871) (xy 345.839542 -216.25052)
			(xy 345.839044 -216.277169) (xy 346.067624 -216.277169) (xy 346.067624 -216.223871) (xy 346.075567 -216.171167)
			(xy 346.091277 -216.120237) (xy 346.114403 -216.072216) (xy 346.144427 -216.028179) (xy 346.180679 -215.989108)
			(xy 346.22235 -215.955877) (xy 346.268508 -215.929228) (xy 346.318122 -215.909756) (xy 346.370084 -215.897896)
			(xy 346.423234 -215.893913) (xy 346.476384 -215.897896) (xy 346.528346 -215.909756) (xy 346.57796 -215.929228)
			(xy 346.624118 -215.955877) (xy 346.665789 -215.989108) (xy 346.702041 -216.028179) (xy 346.732065 -216.072216)
			(xy 346.755191 -216.120237) (xy 346.770901 -216.171167) (xy 346.778844 -216.223871) (xy 346.779342 -216.25052)
			(xy 346.778844 -216.277169) (xy 346.770901 -216.329873) (xy 346.755191 -216.380803) (xy 346.732065 -216.428824)
			(xy 346.702041 -216.472861) (xy 346.665789 -216.511932) (xy 346.624118 -216.545163) (xy 346.57796 -216.571812)
			(xy 346.528346 -216.591284) (xy 346.476384 -216.603144) (xy 346.423234 -216.607128) (xy 346.370084 -216.603144)
			(xy 346.318122 -216.591284) (xy 346.268508 -216.571812) (xy 346.22235 -216.545163) (xy 346.180679 -216.511932)
			(xy 346.144427 -216.472861) (xy 346.114403 -216.428824) (xy 346.091277 -216.380803) (xy 346.075567 -216.329873)
			(xy 346.067624 -216.277169) (xy 345.839044 -216.277169) (xy 345.831101 -216.329873) (xy 345.815391 -216.380803)
			(xy 345.792265 -216.428824) (xy 345.762241 -216.472861) (xy 345.725989 -216.511932) (xy 345.684318 -216.545163)
			(xy 345.63816 -216.571812) (xy 345.588546 -216.591284) (xy 345.536584 -216.603144) (xy 345.483434 -216.607128)
			(xy 345.430284 -216.603144) (xy 345.378322 -216.591284) (xy 345.328708 -216.571812) (xy 345.28255 -216.545163)
			(xy 345.240879 -216.511932) (xy 345.204627 -216.472861) (xy 345.174603 -216.428824) (xy 345.151477 -216.380803)
			(xy 345.135767 -216.329873) (xy 345.127824 -216.277169) (xy 344.899244 -216.277169) (xy 344.891301 -216.329873)
			(xy 344.875591 -216.380803) (xy 344.852465 -216.428824) (xy 344.822441 -216.472861) (xy 344.786189 -216.511932)
			(xy 344.744518 -216.545163) (xy 344.69836 -216.571812) (xy 344.648746 -216.591284) (xy 344.596784 -216.603144)
			(xy 344.543634 -216.607128) (xy 344.490484 -216.603144) (xy 344.438522 -216.591284) (xy 344.388908 -216.571812)
			(xy 344.34275 -216.545163) (xy 344.301079 -216.511932) (xy 344.264827 -216.472861) (xy 344.234803 -216.428824)
			(xy 344.211677 -216.380803) (xy 344.195967 -216.329873) (xy 344.188024 -216.277169) (xy 343.959444 -216.277169)
			(xy 343.951501 -216.329873) (xy 343.935791 -216.380803) (xy 343.912665 -216.428824) (xy 343.882641 -216.472861)
			(xy 343.846389 -216.511932) (xy 343.804718 -216.545163) (xy 343.75856 -216.571812) (xy 343.708946 -216.591284)
			(xy 343.656984 -216.603144) (xy 343.603834 -216.607128) (xy 343.550684 -216.603144) (xy 343.498722 -216.591284)
			(xy 343.449108 -216.571812) (xy 343.40295 -216.545163) (xy 343.361279 -216.511932) (xy 343.325027 -216.472861)
			(xy 343.295003 -216.428824) (xy 343.271877 -216.380803) (xy 343.256167 -216.329873) (xy 343.248224 -216.277169)
			(xy 343.019644 -216.277169) (xy 343.011701 -216.329873) (xy 342.995991 -216.380803) (xy 342.972865 -216.428824)
			(xy 342.942841 -216.472861) (xy 342.906589 -216.511932) (xy 342.864918 -216.545163) (xy 342.81876 -216.571812)
			(xy 342.769146 -216.591284) (xy 342.717184 -216.603144) (xy 342.664034 -216.607128) (xy 342.610884 -216.603144)
			(xy 342.558922 -216.591284) (xy 342.509308 -216.571812) (xy 342.46315 -216.545163) (xy 342.421479 -216.511932)
			(xy 342.385227 -216.472861) (xy 342.355203 -216.428824) (xy 342.332077 -216.380803) (xy 342.316367 -216.329873)
			(xy 342.308424 -216.277169) (xy 342.079844 -216.277169) (xy 342.071901 -216.329873) (xy 342.056191 -216.380803)
			(xy 342.033065 -216.428824) (xy 342.003041 -216.472861) (xy 341.966789 -216.511932) (xy 341.925118 -216.545163)
			(xy 341.87896 -216.571812) (xy 341.829346 -216.591284) (xy 341.777384 -216.603144) (xy 341.724234 -216.607128)
			(xy 341.671084 -216.603144) (xy 341.619122 -216.591284) (xy 341.569508 -216.571812) (xy 341.52335 -216.545163)
			(xy 341.481679 -216.511932) (xy 341.445427 -216.472861) (xy 341.415403 -216.428824) (xy 341.392277 -216.380803)
			(xy 341.376567 -216.329873) (xy 341.368624 -216.277169) (xy 341.140044 -216.277169) (xy 341.132101 -216.329873)
			(xy 341.116391 -216.380803) (xy 341.093265 -216.428824) (xy 341.063241 -216.472861) (xy 341.026989 -216.511932)
			(xy 340.985318 -216.545163) (xy 340.93916 -216.571812) (xy 340.889546 -216.591284) (xy 340.837584 -216.603144)
			(xy 340.784434 -216.607128) (xy 340.731284 -216.603144) (xy 340.679322 -216.591284) (xy 340.629708 -216.571812)
			(xy 340.58355 -216.545163) (xy 340.541879 -216.511932) (xy 340.505627 -216.472861) (xy 340.475603 -216.428824)
			(xy 340.452477 -216.380803) (xy 340.436767 -216.329873) (xy 340.428824 -216.277169) (xy 340.225531 -216.277169)
			(xy 340.219074 -216.325594) (xy 340.205898 -216.374183) (xy 340.18643 -216.420611) (xy 340.174072 -216.442544)
			(xy 340.481412 -216.749884) (xy 340.490369 -216.754717) (xy 340.507779 -216.765265) (xy 340.51621 -216.770966)
			(xy 341.010494 -216.770966) (xy 341.031131 -216.754388) (xy 341.076118 -216.726489) (xy 341.124531 -216.705081)
			(xy 341.17544 -216.690577) (xy 341.227866 -216.683254) (xy 341.280802 -216.683254) (xy 341.333228 -216.690577)
			(xy 341.384137 -216.705081) (xy 341.43255 -216.726489) (xy 341.477537 -216.754388) (xy 341.498174 -216.770966)
			(xy 341.99195 -216.770966) (xy 342.014349 -216.756153) (xy 342.062659 -216.732707) (xy 342.11394 -216.716776)
			(xy 342.167031 -216.708719) (xy 342.220729 -216.708719) (xy 342.27382 -216.716776) (xy 342.325101 -216.732707)
			(xy 342.373411 -216.756153) (xy 342.39581 -216.770966) (xy 342.890094 -216.770966) (xy 342.910731 -216.754388)
			(xy 342.955718 -216.726489) (xy 343.004131 -216.705081) (xy 343.05504 -216.690577) (xy 343.107466 -216.683254)
			(xy 343.160402 -216.683254) (xy 343.212828 -216.690577) (xy 343.263737 -216.705081) (xy 343.31215 -216.726489)
			(xy 343.357137 -216.754388) (xy 343.377774 -216.770966) (xy 343.87155 -216.770966) (xy 343.893949 -216.756153)
			(xy 343.942259 -216.732707) (xy 343.99354 -216.716776) (xy 344.046631 -216.708719) (xy 344.100329 -216.708719)
			(xy 344.15342 -216.716776) (xy 344.204701 -216.732707) (xy 344.253011 -216.756153) (xy 344.27541 -216.770966)
			(xy 344.769694 -216.770966) (xy 344.790331 -216.754388) (xy 344.835318 -216.726489) (xy 344.883731 -216.705081)
			(xy 344.93464 -216.690577) (xy 344.987066 -216.683254) (xy 345.040002 -216.683254) (xy 345.092428 -216.690577)
			(xy 345.143337 -216.705081) (xy 345.19175 -216.726489) (xy 345.236737 -216.754388) (xy 345.257374 -216.770966)
			(xy 345.75115 -216.770966) (xy 345.773549 -216.756153) (xy 345.821859 -216.732707) (xy 345.87314 -216.716776)
			(xy 345.926231 -216.708719) (xy 345.979929 -216.708719) (xy 346.03302 -216.716776) (xy 346.084301 -216.732707)
			(xy 346.132611 -216.756153) (xy 346.15501 -216.770966) (xy 346.649294 -216.770966) (xy 346.66993 -216.754388)
			(xy 346.714917 -216.726492) (xy 346.763331 -216.705092) (xy 346.814241 -216.690598) (xy 346.866667 -216.68329)
			(xy 346.893134 -216.682828) (xy 346.923869 -216.683448) (xy 346.984543 -216.693311) (xy 347.04285 -216.712775)
			(xy 347.097281 -216.741337) (xy 347.122242 -216.759282) (xy 347.157548 -216.785952)
		)
		(stroke
			(width 0)
			(type solid)
		)
		(fill yes)
		(layer "B.Cu")
		(net "PVCCFA_EHV_CPU0")
	)
	(gr_poly
		(pts
			(xy 213.38032 -114.75466) (xy 213.389701 -114.744575) (xy 213.403186 -114.720572) (xy 213.40977 -114.693839)
			(xy 213.408975 -114.666318) (xy 213.400859 -114.64001) (xy 213.386012 -114.616824) (xy 213.365511 -114.598447)
			(xy 213.340847 -114.586211) (xy 213.313812 -114.581008) (xy 213.300056 -114.581686) (xy 213.26856 -114.582956)
			(xy 213.241309 -114.582468) (xy 213.187363 -114.574707) (xy 213.135071 -114.559349) (xy 213.085495 -114.536706)
			(xy 213.039647 -114.507239) (xy 212.998457 -114.471548) (xy 212.962766 -114.43036) (xy 212.933298 -114.384512)
			(xy 212.910654 -114.334937) (xy 212.895295 -114.282644) (xy 212.887533 -114.228699) (xy 212.887052 -114.201448)
			(xy 212.887535 -114.17429) (xy 212.895245 -114.120525) (xy 212.910501 -114.068396) (xy 212.932997 -114.018958)
			(xy 212.962275 -113.97321) (xy 212.997746 -113.932076) (xy 213.038691 -113.896388) (xy 213.084284 -113.866868)
			(xy 213.133603 -113.844111) (xy 213.18565 -113.828579) (xy 213.239373 -113.820584) (xy 213.266528 -113.81994)
			(xy 213.281539 -113.819341) (xy 213.31023 -113.810486) (xy 213.335106 -113.79367) (xy 213.354015 -113.770345)
			(xy 213.365323 -113.742529) (xy 213.368051 -113.712627) (xy 213.361964 -113.683224) (xy 213.355174 -113.669826)
			(xy 213.340527 -113.64164) (xy 213.319795 -113.581604) (xy 213.309317 -113.518958) (xy 213.308692 -113.4872)
			(xy 213.309178 -113.459949) (xy 213.316934 -113.406001) (xy 213.332289 -113.353706) (xy 213.354931 -113.304129)
			(xy 213.384397 -113.258279) (xy 213.420088 -113.217088) (xy 213.461279 -113.181397) (xy 213.507129 -113.151931)
			(xy 213.556706 -113.129289) (xy 213.609001 -113.113934) (xy 213.662949 -113.106178) (xy 213.717451 -113.106178)
			(xy 213.771399 -113.113934) (xy 213.823694 -113.129289) (xy 213.873271 -113.151931) (xy 213.919121 -113.181397)
			(xy 213.960312 -113.217088) (xy 213.996003 -113.258279) (xy 214.025469 -113.304129) (xy 214.048111 -113.353706)
			(xy 214.063466 -113.406001) (xy 214.071222 -113.459949) (xy 214.071708 -113.4872) (xy 214.071229 -113.514359)
			(xy 214.063525 -113.568128) (xy 214.048272 -113.62026) (xy 214.025779 -113.669703) (xy 213.996501 -113.715455)
			(xy 213.96103 -113.756591) (xy 213.920083 -113.792281) (xy 213.874487 -113.821802) (xy 213.825166 -113.844558)
			(xy 213.773115 -113.860088) (xy 213.719388 -113.868079) (xy 213.692232 -113.868708) (xy 213.67723 -113.869313)
			(xy 213.648558 -113.878173) (xy 213.623701 -113.894989) (xy 213.60481 -113.918307) (xy 213.593517 -113.946111)
			(xy 213.590799 -113.975997) (xy 213.596889 -114.005383) (xy 213.603586 -114.018822) (xy 213.618238 -114.047007)
			(xy 213.638981 -114.107042) (xy 213.649469 -114.169688) (xy 213.650068 -114.201448) (xy 213.648798 -114.232944)
			(xy 213.648107 -114.246719) (xy 213.65325 -114.273805) (xy 213.665458 -114.298524) (xy 213.683838 -114.319073)
			(xy 213.707048 -114.333951) (xy 213.733395 -114.342072) (xy 213.760954 -114.342842) (xy 213.787713 -114.336207)
			(xy 213.811718 -114.322649) (xy 213.821772 -114.313208) (xy 215.096344 -113.038636) (xy 215.06434 -113.002822)
			(xy 215.046175 -112.981721) (xy 215.015516 -112.935246) (xy 214.991928 -112.884813) (xy 214.975911 -112.83149)
			(xy 214.967804 -112.776406) (xy 214.967312 -112.748568) (xy 214.9678 -112.721319) (xy 214.975561 -112.667376)
			(xy 214.990919 -112.615086) (xy 215.013562 -112.565514) (xy 215.04303 -112.519669) (xy 215.078721 -112.478484)
			(xy 215.119911 -112.442798) (xy 215.16576 -112.413337) (xy 215.215335 -112.390701) (xy 215.267627 -112.37535)
			(xy 215.321571 -112.367597) (xy 215.34882 -112.36706) (xy 215.37666 -112.367559) (xy 215.431751 -112.375641)
			(xy 215.485082 -112.391645) (xy 215.53552 -112.41523) (xy 215.581994 -112.445896) (xy 215.603074 -112.464088)
			(xy 215.638888 -112.496092) (xy 218.57208 -109.5629) (xy 218.573858 -109.544866) (xy 218.577543 -109.513765)
			(xy 218.59233 -109.452907) (xy 218.615274 -109.394632) (xy 218.645948 -109.340029) (xy 218.683779 -109.290117)
			(xy 218.728061 -109.245828) (xy 218.777967 -109.207989) (xy 218.832565 -109.177306) (xy 218.890835 -109.154352)
			(xy 218.951691 -109.139556) (xy 218.982798 -109.135926) (xy 219.000832 -109.134148) (xy 221.99092 -106.14406)
			(xy 221.99092 -97.9805) (xy 221.8944 -97.9805) (xy 221.367858 -97.453958) (xy 221.334838 -97.47123)
			(xy 221.307363 -97.484953) (xy 221.249116 -97.504409) (xy 221.188505 -97.51428) (xy 221.1578 -97.514918)
			(xy 221.130548 -97.514432) (xy 221.0766 -97.506676) (xy 221.024305 -97.491321) (xy 220.974727 -97.46868)
			(xy 220.928876 -97.439214) (xy 220.887685 -97.403522) (xy 220.851992 -97.362332) (xy 220.822525 -97.316482)
			(xy 220.799883 -97.266904) (xy 220.784526 -97.21461) (xy 220.776768 -97.160661) (xy 220.776292 -97.13341)
			(xy 220.77693 -97.102706) (xy 220.78681 -97.042097) (xy 220.806269 -96.983852) (xy 220.81998 -96.956372)
			(xy 220.837252 -96.923352) (xy 219.346272 -95.432372) (xy 219.095574 -95.327724) (xy 219.081644 -95.322482)
			(xy 219.052051 -95.319439) (xy 219.022834 -95.325043) (xy 218.996466 -95.33882) (xy 218.97518 -95.359603)
			(xy 218.960776 -95.385633) (xy 218.954475 -95.414707) (xy 218.955112 -95.429578) (xy 218.956382 -95.459804)
			(xy 218.955896 -95.487055) (xy 218.94814 -95.541003) (xy 218.932785 -95.593298) (xy 218.910143 -95.642875)
			(xy 218.880677 -95.688725) (xy 218.844986 -95.729916) (xy 218.803795 -95.765607) (xy 218.757945 -95.795073)
			(xy 218.708368 -95.817715) (xy 218.656073 -95.83307) (xy 218.602125 -95.840826) (xy 218.547623 -95.840826)
			(xy 218.493675 -95.83307) (xy 218.44138 -95.817715) (xy 218.391803 -95.795073) (xy 218.345953 -95.765607)
			(xy 218.304762 -95.729916) (xy 218.269071 -95.688725) (xy 218.239605 -95.642875) (xy 218.216963 -95.593298)
			(xy 218.201608 -95.541003) (xy 218.193852 -95.487055) (xy 218.193366 -95.459804) (xy 218.193874 -95.4316)
			(xy 218.202183 -95.375808) (xy 218.21862 -95.321848) (xy 218.242827 -95.270899) (xy 218.258136 -95.247206)
			(xy 218.265941 -95.234672) (xy 218.274687 -95.206485) (xy 218.275016 -95.176973) (xy 218.266901 -95.148597)
			(xy 218.251018 -95.123722) (xy 218.228691 -95.104421) (xy 218.215464 -95.097854) (xy 218.190028 -95.085839)
			(xy 218.142695 -95.055444) (xy 218.10034 -95.018427) (xy 218.06388 -94.975591) (xy 218.034106 -94.927864)
			(xy 218.022424 -94.902274) (xy 218.013534 -94.881192) (xy 205.91018 -90.94724) (xy 204.75702 -90.94724)
			(xy 204.1398 -91.56446) (xy 204.140308 -91.585796) (xy 204.140308 -91.5924) (xy 205.307182 -91.5924)
			(xy 205.311253 -91.536778) (xy 205.323379 -91.482341) (xy 205.343302 -91.43025) (xy 205.370598 -91.381615)
			(xy 205.404684 -91.337472) (xy 205.444833 -91.298763) (xy 205.490191 -91.266312) (xy 205.539791 -91.240811)
			(xy 205.592575 -91.222804) (xy 205.647418 -91.212674) (xy 205.703152 -91.210637) (xy 205.758589 -91.216737)
			(xy 205.812546 -91.230843) (xy 205.863875 -91.252655) (xy 205.911481 -91.281709) (xy 205.954349 -91.317384)
			(xy 205.991566 -91.358921) (xy 206.022339 -91.405434) (xy 206.046011 -91.455931) (xy 206.062079 -91.509338)
			(xy 206.070199 -91.564514) (xy 206.070708 -91.5924) (xy 206.070199 -91.620286) (xy 206.062079 -91.675462)
			(xy 206.046011 -91.728869) (xy 206.022339 -91.779366) (xy 205.991566 -91.825879) (xy 205.954349 -91.867416)
			(xy 205.911481 -91.903091) (xy 205.863875 -91.932145) (xy 205.812546 -91.953957) (xy 205.758589 -91.968063)
			(xy 205.703152 -91.974163) (xy 205.647418 -91.972126) (xy 205.592575 -91.961996) (xy 205.539791 -91.943989)
			(xy 205.490191 -91.918488) (xy 205.444833 -91.886037) (xy 205.404684 -91.847328) (xy 205.370598 -91.803185)
			(xy 205.343302 -91.75455) (xy 205.323379 -91.702459) (xy 205.311253 -91.648022) (xy 205.307182 -91.5924)
			(xy 204.140308 -91.5924) (xy 204.139781 -91.621235) (xy 204.131108 -91.67825) (xy 204.123036 -91.705938)
			(xy 204.12075 -91.713304) (xy 204.12075 -94.671449) (xy 205.557388 -94.671449) (xy 205.557388 -94.616951)
			(xy 205.565144 -94.563007) (xy 205.580497 -94.510715) (xy 205.603136 -94.461141) (xy 205.632599 -94.415293)
			(xy 205.668287 -94.374105) (xy 205.709473 -94.338414) (xy 205.755318 -94.308948) (xy 205.804891 -94.286306)
			(xy 205.857181 -94.270949) (xy 205.911125 -94.26319) (xy 205.938374 -94.262702) (xy 205.966845 -94.263242)
			(xy 206.02315 -94.271729) (xy 206.077569 -94.288489) (xy 206.128894 -94.313148) (xy 206.175985 -94.345161)
			(xy 206.217795 -94.383816) (xy 206.253398 -94.428254) (xy 206.282002 -94.47749) (xy 206.302973 -94.530429)
			(xy 206.311517 -94.567248) (xy 208.193638 -94.567248) (xy 208.197709 -94.511626) (xy 208.209835 -94.457189)
			(xy 208.229758 -94.405098) (xy 208.257054 -94.356463) (xy 208.29114 -94.31232) (xy 208.331289 -94.273611)
			(xy 208.376647 -94.24116) (xy 208.426247 -94.215659) (xy 208.479031 -94.197652) (xy 208.533874 -94.187522)
			(xy 208.589608 -94.185485) (xy 208.645045 -94.191585) (xy 208.699002 -94.205691) (xy 208.750331 -94.227503)
			(xy 208.797937 -94.256557) (xy 208.840805 -94.292232) (xy 208.878022 -94.333769) (xy 208.908795 -94.380282)
			(xy 208.932467 -94.430779) (xy 208.948535 -94.484186) (xy 208.956655 -94.539362) (xy 208.957164 -94.567248)
			(xy 208.956655 -94.595134) (xy 208.948535 -94.65031) (xy 208.932467 -94.703717) (xy 208.908795 -94.754214)
			(xy 208.878022 -94.800727) (xy 208.840805 -94.842264) (xy 208.797937 -94.877939) (xy 208.750331 -94.906993)
			(xy 208.699002 -94.928805) (xy 208.645045 -94.942911) (xy 208.589608 -94.949011) (xy 208.533874 -94.946974)
			(xy 208.479031 -94.936844) (xy 208.426247 -94.918837) (xy 208.376647 -94.893336) (xy 208.331289 -94.860885)
			(xy 208.29114 -94.822176) (xy 208.257054 -94.778033) (xy 208.229758 -94.729398) (xy 208.209835 -94.677307)
			(xy 208.197709 -94.62287) (xy 208.193638 -94.567248) (xy 206.311517 -94.567248) (xy 206.315844 -94.585897)
			(xy 206.318612 -94.614238) (xy 206.320379 -94.629219) (xy 206.331395 -94.65728) (xy 206.350118 -94.680907)
			(xy 206.374918 -94.698046) (xy 206.403638 -94.707206) (xy 206.433782 -94.70759) (xy 206.448406 -94.7039)
			(xy 206.474561 -94.696764) (xy 206.528233 -94.689115) (xy 206.55534 -94.68866) (xy 206.58271 -94.689147)
			(xy 206.636888 -94.696957) (xy 206.689392 -94.712441) (xy 206.739139 -94.735278) (xy 206.785106 -94.765)
			(xy 206.806038 -94.78264) (xy 206.817366 -94.791876) (xy 206.843923 -94.804052) (xy 206.87284 -94.808225)
			(xy 206.901757 -94.804052) (xy 206.928314 -94.791876) (xy 206.939642 -94.78264) (xy 206.96059 -94.765021)
			(xy 207.006558 -94.735305) (xy 207.056301 -94.712464) (xy 207.108799 -94.696969) (xy 207.162972 -94.689136)
			(xy 207.19034 -94.68866) (xy 207.217587 -94.689213) (xy 207.271526 -94.696973) (xy 207.323811 -94.712331)
			(xy 207.373379 -94.734972) (xy 207.419221 -94.764437) (xy 207.460403 -94.800126) (xy 207.496087 -94.841311)
			(xy 207.525547 -94.887156) (xy 207.548183 -94.936726) (xy 207.563535 -94.989013) (xy 207.57129 -95.042953)
			(xy 207.57129 -95.097447) (xy 207.563535 -95.151387) (xy 207.562771 -95.153988) (xy 215.009982 -95.153988)
			(xy 215.014053 -95.098366) (xy 215.026179 -95.043929) (xy 215.046102 -94.991838) (xy 215.073398 -94.943203)
			(xy 215.107484 -94.89906) (xy 215.147633 -94.860351) (xy 215.192991 -94.8279) (xy 215.242591 -94.802399)
			(xy 215.295375 -94.784392) (xy 215.350218 -94.774262) (xy 215.405952 -94.772225) (xy 215.461389 -94.778325)
			(xy 215.515346 -94.792431) (xy 215.566675 -94.814243) (xy 215.614281 -94.843297) (xy 215.657149 -94.878972)
			(xy 215.694366 -94.920509) (xy 215.725139 -94.967022) (xy 215.748811 -95.017519) (xy 215.764879 -95.070926)
			(xy 215.772999 -95.126102) (xy 215.773508 -95.153988) (xy 215.772999 -95.181874) (xy 215.764879 -95.23705)
			(xy 215.748811 -95.290457) (xy 215.725139 -95.340954) (xy 215.694366 -95.387467) (xy 215.657149 -95.429004)
			(xy 215.614281 -95.464679) (xy 215.566675 -95.493733) (xy 215.515346 -95.515545) (xy 215.461389 -95.529651)
			(xy 215.405952 -95.535751) (xy 215.350218 -95.533714) (xy 215.295375 -95.523584) (xy 215.242591 -95.505577)
			(xy 215.192991 -95.480076) (xy 215.147633 -95.447625) (xy 215.107484 -95.408916) (xy 215.073398 -95.364773)
			(xy 215.046102 -95.316138) (xy 215.026179 -95.264047) (xy 215.014053 -95.20961) (xy 215.009982 -95.153988)
			(xy 207.562771 -95.153988) (xy 207.548183 -95.203674) (xy 207.525547 -95.253244) (xy 207.496087 -95.299089)
			(xy 207.460403 -95.340274) (xy 207.419221 -95.375963) (xy 207.373379 -95.405428) (xy 207.323811 -95.428069)
			(xy 207.271526 -95.443427) (xy 207.217587 -95.451187) (xy 207.19034 -95.451676) (xy 207.16297 -95.451192)
			(xy 207.108792 -95.44338) (xy 207.056289 -95.427895) (xy 207.006541 -95.405057) (xy 206.960574 -95.375336)
			(xy 206.939642 -95.357696) (xy 206.928314 -95.34846) (xy 206.901757 -95.336284) (xy 206.87284 -95.332111)
			(xy 206.843923 -95.336284) (xy 206.817366 -95.34846) (xy 206.806038 -95.357696) (xy 206.785102 -95.37533)
			(xy 206.73913 -95.405043) (xy 206.689384 -95.42788) (xy 206.636884 -95.443372) (xy 206.582709 -95.451201)
			(xy 206.55534 -95.451676) (xy 206.526869 -95.451143) (xy 206.470562 -95.442658) (xy 206.416141 -95.425899)
			(xy 206.364815 -95.401239) (xy 206.317724 -95.369226) (xy 206.275912 -95.33057) (xy 206.24031 -95.28613)
			(xy 206.211706 -95.236892) (xy 206.190738 -95.183951) (xy 206.177869 -95.128481) (xy 206.175102 -95.10014)
			(xy 206.173334 -95.08516) (xy 206.162314 -95.057103) (xy 206.143591 -95.033478) (xy 206.118792 -95.01634)
			(xy 206.090074 -95.007179) (xy 206.059932 -95.00679) (xy 206.045308 -95.010478) (xy 206.019153 -95.017613)
			(xy 205.965481 -95.025262) (xy 205.938374 -95.025718) (xy 205.911125 -95.02521) (xy 205.857181 -95.017451)
			(xy 205.804891 -95.002094) (xy 205.755318 -94.979452) (xy 205.709473 -94.949986) (xy 205.668287 -94.914295)
			(xy 205.632599 -94.873107) (xy 205.603136 -94.827259) (xy 205.580497 -94.777685) (xy 205.565144 -94.725393)
			(xy 205.557388 -94.671449) (xy 204.12075 -94.671449) (xy 204.12075 -95.88119) (xy 204.45476 -96.2152)
			(xy 207.389982 -96.2152) (xy 207.394053 -96.159578) (xy 207.406179 -96.105141) (xy 207.426102 -96.05305)
			(xy 207.453398 -96.004415) (xy 207.487484 -95.960272) (xy 207.527633 -95.921563) (xy 207.572991 -95.889112)
			(xy 207.622591 -95.863611) (xy 207.675375 -95.845604) (xy 207.730218 -95.835474) (xy 207.785952 -95.833437)
			(xy 207.841389 -95.839537) (xy 207.895346 -95.853643) (xy 207.946675 -95.875455) (xy 207.994281 -95.904509)
			(xy 208.037149 -95.940184) (xy 208.074366 -95.981721) (xy 208.105139 -96.028234) (xy 208.128811 -96.078731)
			(xy 208.144879 -96.132138) (xy 208.152999 -96.187314) (xy 208.153508 -96.2152) (xy 208.152999 -96.243086)
			(xy 208.144879 -96.298262) (xy 208.128811 -96.351669) (xy 208.105139 -96.402166) (xy 208.074366 -96.448679)
			(xy 208.037149 -96.490216) (xy 207.994281 -96.525891) (xy 207.946675 -96.554945) (xy 207.895346 -96.576757)
			(xy 207.841389 -96.590863) (xy 207.785952 -96.596963) (xy 207.730218 -96.594926) (xy 207.675375 -96.584796)
			(xy 207.622591 -96.566789) (xy 207.572991 -96.541288) (xy 207.527633 -96.508837) (xy 207.487484 -96.470128)
			(xy 207.453398 -96.425985) (xy 207.426102 -96.37735) (xy 207.406179 -96.325259) (xy 207.394053 -96.270822)
			(xy 207.389982 -96.2152) (xy 204.45476 -96.2152) (xy 206.41056 -98.171) (xy 211.276182 -98.171) (xy 211.280253 -98.115378)
			(xy 211.292379 -98.060941) (xy 211.312302 -98.00885) (xy 211.339598 -97.960215) (xy 211.373684 -97.916072)
			(xy 211.413833 -97.877363) (xy 211.459191 -97.844912) (xy 211.508791 -97.819411) (xy 211.561575 -97.801404)
			(xy 211.616418 -97.791274) (xy 211.672152 -97.789237) (xy 211.727589 -97.795337) (xy 211.781546 -97.809443)
			(xy 211.832875 -97.831255) (xy 211.880481 -97.860309) (xy 211.923349 -97.895984) (xy 211.960566 -97.937521)
			(xy 211.991339 -97.984034) (xy 212.015011 -98.034531) (xy 212.031079 -98.087938) (xy 212.039199 -98.143114)
			(xy 212.039708 -98.171) (xy 212.039199 -98.198886) (xy 212.031079 -98.254062) (xy 212.015011 -98.307469)
			(xy 211.991339 -98.357966) (xy 211.960566 -98.404479) (xy 211.923349 -98.446016) (xy 211.880481 -98.481691)
			(xy 211.832875 -98.510745) (xy 211.781546 -98.532557) (xy 211.727589 -98.546663) (xy 211.672152 -98.552763)
			(xy 211.616418 -98.550726) (xy 211.561575 -98.540596) (xy 211.508791 -98.522589) (xy 211.459191 -98.497088)
			(xy 211.413833 -98.464637) (xy 211.373684 -98.425928) (xy 211.339598 -98.381785) (xy 211.312302 -98.33315)
			(xy 211.292379 -98.281059) (xy 211.280253 -98.226622) (xy 211.276182 -98.171) (xy 206.41056 -98.171)
			(xy 207.45704 -99.21748) (xy 220.775782 -99.21748) (xy 220.779853 -99.161858) (xy 220.791979 -99.107421)
			(xy 220.811902 -99.05533) (xy 220.839198 -99.006695) (xy 220.873284 -98.962552) (xy 220.913433 -98.923843)
			(xy 220.958791 -98.891392) (xy 221.008391 -98.865891) (xy 221.061175 -98.847884) (xy 221.116018 -98.837754)
			(xy 221.171752 -98.835717) (xy 221.227189 -98.841817) (xy 221.281146 -98.855923) (xy 221.332475 -98.877735)
			(xy 221.380081 -98.906789) (xy 221.422949 -98.942464) (xy 221.460166 -98.984001) (xy 221.490939 -99.030514)
			(xy 221.514611 -99.081011) (xy 221.530679 -99.134418) (xy 221.538799 -99.189594) (xy 221.539308 -99.21748)
			(xy 221.538799 -99.245366) (xy 221.530679 -99.300542) (xy 221.514611 -99.353949) (xy 221.490939 -99.404446)
			(xy 221.460166 -99.450959) (xy 221.422949 -99.492496) (xy 221.380081 -99.528171) (xy 221.332475 -99.557225)
			(xy 221.281146 -99.579037) (xy 221.227189 -99.593143) (xy 221.171752 -99.599243) (xy 221.116018 -99.597206)
			(xy 221.061175 -99.587076) (xy 221.008391 -99.569069) (xy 220.958791 -99.543568) (xy 220.913433 -99.511117)
			(xy 220.873284 -99.472408) (xy 220.839198 -99.428265) (xy 220.811902 -99.37963) (xy 220.791979 -99.327539)
			(xy 220.779853 -99.273102) (xy 220.775782 -99.21748) (xy 207.45704 -99.21748) (xy 208.061048 -99.821488)
			(xy 212.593918 -99.821488) (xy 212.593918 -99.761552) (xy 212.601741 -99.70213) (xy 212.617254 -99.644237)
			(xy 212.64019 -99.588864) (xy 212.670157 -99.536958) (xy 212.706644 -99.489408) (xy 212.749024 -99.447028)
			(xy 212.796574 -99.410541) (xy 212.84848 -99.380574) (xy 212.903853 -99.357638) (xy 212.961746 -99.342125)
			(xy 213.021168 -99.334302) (xy 213.081104 -99.334302) (xy 213.140526 -99.342125) (xy 213.198419 -99.357638)
			(xy 213.253792 -99.380574) (xy 213.305698 -99.410541) (xy 213.353248 -99.447028) (xy 213.395628 -99.489408)
			(xy 213.432115 -99.536958) (xy 213.462082 -99.588864) (xy 213.485018 -99.644237) (xy 213.500531 -99.70213)
			(xy 213.508354 -99.761552) (xy 213.508844 -99.79152) (xy 213.508354 -99.821488) (xy 213.500531 -99.88091)
			(xy 213.485018 -99.938803) (xy 213.462082 -99.994176) (xy 213.432115 -100.046082) (xy 213.395628 -100.093632)
			(xy 213.353248 -100.136012) (xy 213.305698 -100.172499) (xy 213.253792 -100.202466) (xy 213.198419 -100.225402)
			(xy 213.168273 -100.23348) (xy 220.775782 -100.23348) (xy 220.779853 -100.177858) (xy 220.791979 -100.123421)
			(xy 220.811902 -100.07133) (xy 220.839198 -100.022695) (xy 220.873284 -99.978552) (xy 220.913433 -99.939843)
			(xy 220.958791 -99.907392) (xy 221.008391 -99.881891) (xy 221.061175 -99.863884) (xy 221.116018 -99.853754)
			(xy 221.171752 -99.851717) (xy 221.227189 -99.857817) (xy 221.281146 -99.871923) (xy 221.332475 -99.893735)
			(xy 221.380081 -99.922789) (xy 221.422949 -99.958464) (xy 221.460166 -100.000001) (xy 221.490939 -100.046514)
			(xy 221.514611 -100.097011) (xy 221.530679 -100.150418) (xy 221.538799 -100.205594) (xy 221.539308 -100.23348)
			(xy 221.538799 -100.261366) (xy 221.530679 -100.316542) (xy 221.514611 -100.369949) (xy 221.490939 -100.420446)
			(xy 221.460166 -100.466959) (xy 221.422949 -100.508496) (xy 221.380081 -100.544171) (xy 221.332475 -100.573225)
			(xy 221.281146 -100.595037) (xy 221.227189 -100.609143) (xy 221.171752 -100.615243) (xy 221.116018 -100.613206)
			(xy 221.061175 -100.603076) (xy 221.008391 -100.585069) (xy 220.958791 -100.559568) (xy 220.913433 -100.527117)
			(xy 220.873284 -100.488408) (xy 220.839198 -100.444265) (xy 220.811902 -100.39563) (xy 220.791979 -100.343539)
			(xy 220.779853 -100.289102) (xy 220.775782 -100.23348) (xy 213.168273 -100.23348) (xy 213.140526 -100.240915)
			(xy 213.081104 -100.248738) (xy 213.021168 -100.248738) (xy 212.961746 -100.240915) (xy 212.903853 -100.225402)
			(xy 212.84848 -100.202466) (xy 212.796574 -100.172499) (xy 212.749024 -100.136012) (xy 212.706644 -100.093632)
			(xy 212.670157 -100.046082) (xy 212.64019 -99.994176) (xy 212.617254 -99.938803) (xy 212.601741 -99.88091)
			(xy 212.593918 -99.821488) (xy 208.061048 -99.821488) (xy 208.5975 -100.35794) (xy 208.5975 -100.908104)
			(xy 209.168744 -100.908104) (xy 209.172815 -100.852482) (xy 209.184941 -100.798045) (xy 209.204864 -100.745954)
			(xy 209.23216 -100.697319) (xy 209.266246 -100.653176) (xy 209.306395 -100.614467) (xy 209.351753 -100.582016)
			(xy 209.401353 -100.556515) (xy 209.454137 -100.538508) (xy 209.50898 -100.528378) (xy 209.564714 -100.526341)
			(xy 209.620151 -100.532441) (xy 209.674108 -100.546547) (xy 209.725437 -100.568359) (xy 209.773043 -100.597413)
			(xy 209.815911 -100.633088) (xy 209.853128 -100.674625) (xy 209.883901 -100.721138) (xy 209.907573 -100.771635)
			(xy 209.923641 -100.825042) (xy 209.931761 -100.880218) (xy 209.93227 -100.908104) (xy 209.931761 -100.93599)
			(xy 209.923641 -100.991166) (xy 209.907573 -101.044573) (xy 209.883901 -101.09507) (xy 209.853128 -101.141583)
			(xy 209.815911 -101.18312) (xy 209.773043 -101.218795) (xy 209.725437 -101.247849) (xy 209.674108 -101.269661)
			(xy 209.620151 -101.283767) (xy 209.564714 -101.289867) (xy 209.50898 -101.28783) (xy 209.454137 -101.2777)
			(xy 209.401353 -101.259693) (xy 209.351753 -101.234192) (xy 209.306395 -101.201741) (xy 209.266246 -101.163032)
			(xy 209.23216 -101.118889) (xy 209.204864 -101.070254) (xy 209.184941 -101.018163) (xy 209.172815 -100.963726)
			(xy 209.168744 -100.908104) (xy 208.5975 -100.908104) (xy 208.5975 -101.39934) (xy 214.512142 -101.39934)
			(xy 214.516213 -101.343718) (xy 214.528339 -101.289281) (xy 214.548262 -101.23719) (xy 214.575558 -101.188555)
			(xy 214.609644 -101.144412) (xy 214.649793 -101.105703) (xy 214.695151 -101.073252) (xy 214.744751 -101.047751)
			(xy 214.797535 -101.029744) (xy 214.852378 -101.019614) (xy 214.908112 -101.017577) (xy 214.963549 -101.023677)
			(xy 215.017506 -101.037783) (xy 215.068835 -101.059595) (xy 215.116441 -101.088649) (xy 215.159309 -101.124324)
			(xy 215.196526 -101.165861) (xy 215.227299 -101.212374) (xy 215.250971 -101.262871) (xy 215.267039 -101.316278)
			(xy 215.275159 -101.371454) (xy 215.275617 -101.396542) (xy 217.916742 -101.396542) (xy 217.916742 -101.336606)
			(xy 217.924565 -101.277184) (xy 217.940078 -101.219291) (xy 217.963014 -101.163918) (xy 217.992981 -101.112012)
			(xy 218.029468 -101.064462) (xy 218.071848 -101.022082) (xy 218.119398 -100.985595) (xy 218.171304 -100.955628)
			(xy 218.226677 -100.932692) (xy 218.28457 -100.917179) (xy 218.343992 -100.909356) (xy 218.403928 -100.909356)
			(xy 218.46335 -100.917179) (xy 218.521243 -100.932692) (xy 218.576616 -100.955628) (xy 218.628522 -100.985595)
			(xy 218.676072 -101.022082) (xy 218.718452 -101.064462) (xy 218.754939 -101.112012) (xy 218.784906 -101.163918)
			(xy 218.807842 -101.219291) (xy 218.823355 -101.277184) (xy 218.831178 -101.336606) (xy 218.831668 -101.366574)
			(xy 218.831178 -101.396542) (xy 218.823355 -101.455964) (xy 218.807842 -101.513857) (xy 218.784906 -101.56923)
			(xy 218.754939 -101.621136) (xy 218.718452 -101.668686) (xy 218.676072 -101.711066) (xy 218.628522 -101.747553)
			(xy 218.576616 -101.77752) (xy 218.521243 -101.800456) (xy 218.46335 -101.815969) (xy 218.403928 -101.823792)
			(xy 218.343992 -101.823792) (xy 218.28457 -101.815969) (xy 218.226677 -101.800456) (xy 218.171304 -101.77752)
			(xy 218.119398 -101.747553) (xy 218.071848 -101.711066) (xy 218.029468 -101.668686) (xy 217.992981 -101.621136)
			(xy 217.963014 -101.56923) (xy 217.940078 -101.513857) (xy 217.924565 -101.455964) (xy 217.916742 -101.396542)
			(xy 215.275617 -101.396542) (xy 215.275668 -101.39934) (xy 215.275159 -101.427226) (xy 215.267039 -101.482402)
			(xy 215.250971 -101.535809) (xy 215.227299 -101.586306) (xy 215.196526 -101.632819) (xy 215.159309 -101.674356)
			(xy 215.116441 -101.710031) (xy 215.068835 -101.739085) (xy 215.017506 -101.760897) (xy 214.963549 -101.775003)
			(xy 214.908112 -101.781103) (xy 214.852378 -101.779066) (xy 214.797535 -101.768936) (xy 214.744751 -101.750929)
			(xy 214.695151 -101.725428) (xy 214.649793 -101.692977) (xy 214.609644 -101.654268) (xy 214.575558 -101.610125)
			(xy 214.548262 -101.56149) (xy 214.528339 -101.509399) (xy 214.516213 -101.454962) (xy 214.512142 -101.39934)
			(xy 208.5975 -101.39934) (xy 208.5975 -102.255574) (xy 220.775782 -102.255574) (xy 220.779853 -102.199952)
			(xy 220.791979 -102.145515) (xy 220.811902 -102.093424) (xy 220.839198 -102.044789) (xy 220.873284 -102.000646)
			(xy 220.913433 -101.961937) (xy 220.958791 -101.929486) (xy 221.008391 -101.903985) (xy 221.061175 -101.885978)
			(xy 221.116018 -101.875848) (xy 221.171752 -101.873811) (xy 221.227189 -101.879911) (xy 221.281146 -101.894017)
			(xy 221.332475 -101.915829) (xy 221.380081 -101.944883) (xy 221.422949 -101.980558) (xy 221.460166 -102.022095)
			(xy 221.490939 -102.068608) (xy 221.514611 -102.119105) (xy 221.530679 -102.172512) (xy 221.538799 -102.227688)
			(xy 221.539308 -102.255574) (xy 221.538799 -102.28346) (xy 221.530679 -102.338636) (xy 221.514611 -102.392043)
			(xy 221.490939 -102.44254) (xy 221.460166 -102.489053) (xy 221.422949 -102.53059) (xy 221.380081 -102.566265)
			(xy 221.332475 -102.595319) (xy 221.281146 -102.617131) (xy 221.227189 -102.631237) (xy 221.171752 -102.637337)
			(xy 221.116018 -102.6353) (xy 221.061175 -102.62517) (xy 221.008391 -102.607163) (xy 220.958791 -102.581662)
			(xy 220.913433 -102.549211) (xy 220.873284 -102.510502) (xy 220.839198 -102.466359) (xy 220.811902 -102.417724)
			(xy 220.791979 -102.365633) (xy 220.779853 -102.311196) (xy 220.775782 -102.255574) (xy 208.5975 -102.255574)
			(xy 208.5975 -102.93604) (xy 209.162902 -102.93604) (xy 209.166973 -102.880418) (xy 209.179099 -102.825981)
			(xy 209.199022 -102.77389) (xy 209.226318 -102.725255) (xy 209.260404 -102.681112) (xy 209.300553 -102.642403)
			(xy 209.345911 -102.609952) (xy 209.395511 -102.584451) (xy 209.448295 -102.566444) (xy 209.503138 -102.556314)
			(xy 209.558872 -102.554277) (xy 209.614309 -102.560377) (xy 209.668266 -102.574483) (xy 209.719595 -102.596295)
			(xy 209.767201 -102.625349) (xy 209.810069 -102.661024) (xy 209.847286 -102.702561) (xy 209.878059 -102.749074)
			(xy 209.901731 -102.799571) (xy 209.917799 -102.852978) (xy 209.925919 -102.908154) (xy 209.926428 -102.93604)
			(xy 209.925919 -102.963926) (xy 209.917799 -103.019102) (xy 209.901731 -103.072509) (xy 209.878059 -103.123006)
			(xy 209.847286 -103.169519) (xy 209.810069 -103.211056) (xy 209.767201 -103.246731) (xy 209.719595 -103.275785)
			(xy 209.668266 -103.297597) (xy 209.614309 -103.311703) (xy 209.558872 -103.317803) (xy 209.503138 -103.315766)
			(xy 209.448295 -103.305636) (xy 209.395511 -103.287629) (xy 209.345911 -103.262128) (xy 209.300553 -103.229677)
			(xy 209.260404 -103.190968) (xy 209.226318 -103.146825) (xy 209.199022 -103.09819) (xy 209.179099 -103.046099)
			(xy 209.166973 -102.991662) (xy 209.162902 -102.93604) (xy 208.5975 -102.93604) (xy 208.5975 -103.95204)
			(xy 209.162902 -103.95204) (xy 209.166973 -103.896418) (xy 209.179099 -103.841981) (xy 209.199022 -103.78989)
			(xy 209.226318 -103.741255) (xy 209.260404 -103.697112) (xy 209.300553 -103.658403) (xy 209.345911 -103.625952)
			(xy 209.395511 -103.600451) (xy 209.448295 -103.582444) (xy 209.503138 -103.572314) (xy 209.558872 -103.570277)
			(xy 209.614309 -103.576377) (xy 209.668266 -103.590483) (xy 209.719595 -103.612295) (xy 209.767201 -103.641349)
			(xy 209.810069 -103.677024) (xy 209.847286 -103.718561) (xy 209.878059 -103.765074) (xy 209.901731 -103.815571)
			(xy 209.917799 -103.868978) (xy 209.925919 -103.924154) (xy 209.926428 -103.95204) (xy 209.925919 -103.979926)
			(xy 209.917799 -104.035102) (xy 209.901731 -104.088509) (xy 209.878059 -104.139006) (xy 209.847286 -104.185519)
			(xy 209.810069 -104.227056) (xy 209.767201 -104.262731) (xy 209.719595 -104.291785) (xy 209.668266 -104.313597)
			(xy 209.614309 -104.327703) (xy 209.558872 -104.333803) (xy 209.503138 -104.331766) (xy 209.448295 -104.321636)
			(xy 209.395511 -104.303629) (xy 209.345911 -104.278128) (xy 209.300553 -104.245677) (xy 209.260404 -104.206968)
			(xy 209.226318 -104.162825) (xy 209.199022 -104.11419) (xy 209.179099 -104.062099) (xy 209.166973 -104.007662)
			(xy 209.162902 -103.95204) (xy 208.5975 -103.95204) (xy 208.5975 -104.363008) (xy 217.18065 -104.363008)
			(xy 217.18065 -104.303072) (xy 217.188473 -104.24365) (xy 217.203986 -104.185757) (xy 217.226922 -104.130384)
			(xy 217.256889 -104.078478) (xy 217.293376 -104.030928) (xy 217.335756 -103.988548) (xy 217.383306 -103.952061)
			(xy 217.435212 -103.922094) (xy 217.490585 -103.899158) (xy 217.548478 -103.883645) (xy 217.6079 -103.875822)
			(xy 217.667836 -103.875822) (xy 217.727258 -103.883645) (xy 217.785151 -103.899158) (xy 217.840524 -103.922094)
			(xy 217.89243 -103.952061) (xy 217.93998 -103.988548) (xy 217.961888 -104.010456) (xy 220.043484 -104.010456)
			(xy 220.043484 -103.95052) (xy 220.051307 -103.891098) (xy 220.06682 -103.833205) (xy 220.089756 -103.777832)
			(xy 220.119723 -103.725926) (xy 220.15621 -103.678376) (xy 220.19859 -103.635996) (xy 220.24614 -103.599509)
			(xy 220.298046 -103.569542) (xy 220.353419 -103.546606) (xy 220.411312 -103.531093) (xy 220.470734 -103.52327)
			(xy 220.53067 -103.52327) (xy 220.590092 -103.531093) (xy 220.647985 -103.546606) (xy 220.703358 -103.569542)
			(xy 220.755264 -103.599509) (xy 220.802814 -103.635996) (xy 220.845194 -103.678376) (xy 220.881681 -103.725926)
			(xy 220.911648 -103.777832) (xy 220.934584 -103.833205) (xy 220.950097 -103.891098) (xy 220.95792 -103.95052)
			(xy 220.95841 -103.980488) (xy 220.95792 -104.010456) (xy 220.950097 -104.069878) (xy 220.934584 -104.127771)
			(xy 220.911648 -104.183144) (xy 220.881681 -104.23505) (xy 220.845194 -104.2826) (xy 220.802814 -104.32498)
			(xy 220.755264 -104.361467) (xy 220.703358 -104.391434) (xy 220.647985 -104.41437) (xy 220.590092 -104.429883)
			(xy 220.53067 -104.437706) (xy 220.470734 -104.437706) (xy 220.411312 -104.429883) (xy 220.353419 -104.41437)
			(xy 220.298046 -104.391434) (xy 220.24614 -104.361467) (xy 220.19859 -104.32498) (xy 220.15621 -104.2826)
			(xy 220.119723 -104.23505) (xy 220.089756 -104.183144) (xy 220.06682 -104.127771) (xy 220.051307 -104.069878)
			(xy 220.043484 -104.010456) (xy 217.961888 -104.010456) (xy 217.98236 -104.030928) (xy 218.018847 -104.078478)
			(xy 218.048814 -104.130384) (xy 218.07175 -104.185757) (xy 218.087263 -104.24365) (xy 218.095086 -104.303072)
			(xy 218.095576 -104.33304) (xy 218.095086 -104.363008) (xy 218.087263 -104.42243) (xy 218.07175 -104.480323)
			(xy 218.048814 -104.535696) (xy 218.018847 -104.587602) (xy 217.98236 -104.635152) (xy 217.93998 -104.677532)
			(xy 217.89243 -104.714019) (xy 217.840524 -104.743986) (xy 217.785151 -104.766922) (xy 217.727258 -104.782435)
			(xy 217.667836 -104.790258) (xy 217.6079 -104.790258) (xy 217.548478 -104.782435) (xy 217.490585 -104.766922)
			(xy 217.435212 -104.743986) (xy 217.383306 -104.714019) (xy 217.335756 -104.677532) (xy 217.293376 -104.635152)
			(xy 217.256889 -104.587602) (xy 217.226922 -104.535696) (xy 217.203986 -104.480323) (xy 217.188473 -104.42243)
			(xy 217.18065 -104.363008) (xy 208.5975 -104.363008) (xy 208.5975 -104.96804) (xy 209.162902 -104.96804)
			(xy 209.166973 -104.912418) (xy 209.179099 -104.857981) (xy 209.199022 -104.80589) (xy 209.226318 -104.757255)
			(xy 209.260404 -104.713112) (xy 209.300553 -104.674403) (xy 209.345911 -104.641952) (xy 209.395511 -104.616451)
			(xy 209.448295 -104.598444) (xy 209.503138 -104.588314) (xy 209.558872 -104.586277) (xy 209.614309 -104.592377)
			(xy 209.668266 -104.606483) (xy 209.719595 -104.628295) (xy 209.767201 -104.657349) (xy 209.810069 -104.693024)
			(xy 209.847286 -104.734561) (xy 209.878059 -104.781074) (xy 209.901731 -104.831571) (xy 209.917799 -104.884978)
			(xy 209.925919 -104.940154) (xy 209.926428 -104.96804) (xy 209.925919 -104.995926) (xy 209.917799 -105.051102)
			(xy 209.901731 -105.104509) (xy 209.878059 -105.155006) (xy 209.847286 -105.201519) (xy 209.810069 -105.243056)
			(xy 209.767201 -105.278731) (xy 209.719595 -105.307785) (xy 209.668266 -105.329597) (xy 209.614309 -105.343703)
			(xy 209.558872 -105.349803) (xy 209.503138 -105.347766) (xy 209.448295 -105.337636) (xy 209.395511 -105.319629)
			(xy 209.345911 -105.294128) (xy 209.300553 -105.261677) (xy 209.260404 -105.222968) (xy 209.226318 -105.178825)
			(xy 209.199022 -105.13019) (xy 209.179099 -105.078099) (xy 209.166973 -105.023662) (xy 209.162902 -104.96804)
			(xy 208.5975 -104.96804) (xy 208.5975 -106.4006) (xy 213.079582 -106.4006) (xy 213.083653 -106.344978)
			(xy 213.095779 -106.290541) (xy 213.115702 -106.23845) (xy 213.142998 -106.189815) (xy 213.177084 -106.145672)
			(xy 213.217233 -106.106963) (xy 213.262591 -106.074512) (xy 213.312191 -106.049011) (xy 213.364975 -106.031004)
			(xy 213.419818 -106.020874) (xy 213.475552 -106.018837) (xy 213.530989 -106.024937) (xy 213.584946 -106.039043)
			(xy 213.636275 -106.060855) (xy 213.683881 -106.089909) (xy 213.726749 -106.125584) (xy 213.763966 -106.167121)
			(xy 213.794739 -106.213634) (xy 213.818411 -106.264131) (xy 213.834479 -106.317538) (xy 213.842599 -106.372714)
			(xy 213.842644 -106.3752) (xy 214.044782 -106.3752) (xy 214.048853 -106.319578) (xy 214.060979 -106.265141)
			(xy 214.080902 -106.21305) (xy 214.108198 -106.164415) (xy 214.142284 -106.120272) (xy 214.182433 -106.081563)
			(xy 214.227791 -106.049112) (xy 214.277391 -106.023611) (xy 214.330175 -106.005604) (xy 214.385018 -105.995474)
			(xy 214.440752 -105.993437) (xy 214.496189 -105.999537) (xy 214.550146 -106.013643) (xy 214.601475 -106.035455)
			(xy 214.649081 -106.064509) (xy 214.691949 -106.100184) (xy 214.728982 -106.141516) (xy 217.363022 -106.141516)
			(xy 217.363022 -106.08158) (xy 217.370845 -106.022158) (xy 217.386358 -105.964265) (xy 217.409294 -105.908892)
			(xy 217.439261 -105.856986) (xy 217.475748 -105.809436) (xy 217.518128 -105.767056) (xy 217.565678 -105.730569)
			(xy 217.617584 -105.700602) (xy 217.672957 -105.677666) (xy 217.73085 -105.662153) (xy 217.790272 -105.65433)
			(xy 217.850208 -105.65433) (xy 217.90963 -105.662153) (xy 217.967523 -105.677666) (xy 218.022896 -105.700602)
			(xy 218.074802 -105.730569) (xy 218.122352 -105.767056) (xy 218.164732 -105.809436) (xy 218.199701 -105.855008)
			(xy 220.933262 -105.855008) (xy 220.937333 -105.799386) (xy 220.949459 -105.744949) (xy 220.969382 -105.692858)
			(xy 220.996678 -105.644223) (xy 221.030764 -105.60008) (xy 221.070913 -105.561371) (xy 221.116271 -105.52892)
			(xy 221.165871 -105.503419) (xy 221.218655 -105.485412) (xy 221.273498 -105.475282) (xy 221.329232 -105.473245)
			(xy 221.384669 -105.479345) (xy 221.438626 -105.493451) (xy 221.489955 -105.515263) (xy 221.537561 -105.544317)
			(xy 221.580429 -105.579992) (xy 221.617646 -105.621529) (xy 221.648419 -105.668042) (xy 221.672091 -105.718539)
			(xy 221.688159 -105.771946) (xy 221.696279 -105.827122) (xy 221.696788 -105.855008) (xy 221.696279 -105.882894)
			(xy 221.688159 -105.93807) (xy 221.672091 -105.991477) (xy 221.648419 -106.041974) (xy 221.617646 -106.088487)
			(xy 221.580429 -106.130024) (xy 221.537561 -106.165699) (xy 221.489955 -106.194753) (xy 221.438626 -106.216565)
			(xy 221.384669 -106.230671) (xy 221.329232 -106.236771) (xy 221.273498 -106.234734) (xy 221.218655 -106.224604)
			(xy 221.165871 -106.206597) (xy 221.116271 -106.181096) (xy 221.070913 -106.148645) (xy 221.030764 -106.109936)
			(xy 220.996678 -106.065793) (xy 220.969382 -106.017158) (xy 220.949459 -105.965067) (xy 220.937333 -105.91063)
			(xy 220.933262 -105.855008) (xy 218.199701 -105.855008) (xy 218.201219 -105.856986) (xy 218.231186 -105.908892)
			(xy 218.254122 -105.964265) (xy 218.269635 -106.022158) (xy 218.277458 -106.08158) (xy 218.277948 -106.111548)
			(xy 218.277458 -106.141516) (xy 218.269635 -106.200938) (xy 218.254122 -106.258831) (xy 218.231186 -106.314204)
			(xy 218.201219 -106.36611) (xy 218.164732 -106.41366) (xy 218.122352 -106.45604) (xy 218.074802 -106.492527)
			(xy 218.022896 -106.522494) (xy 217.967523 -106.54543) (xy 217.90963 -106.560943) (xy 217.850208 -106.568766)
			(xy 217.790272 -106.568766) (xy 217.73085 -106.560943) (xy 217.672957 -106.54543) (xy 217.617584 -106.522494)
			(xy 217.565678 -106.492527) (xy 217.518128 -106.45604) (xy 217.475748 -106.41366) (xy 217.439261 -106.36611)
			(xy 217.409294 -106.314204) (xy 217.386358 -106.258831) (xy 217.370845 -106.200938) (xy 217.363022 -106.141516)
			(xy 214.728982 -106.141516) (xy 214.729166 -106.141721) (xy 214.759939 -106.188234) (xy 214.783611 -106.238731)
			(xy 214.799679 -106.292138) (xy 214.807799 -106.347314) (xy 214.808308 -106.3752) (xy 214.807799 -106.403086)
			(xy 214.799679 -106.458262) (xy 214.783611 -106.511669) (xy 214.759939 -106.562166) (xy 214.729166 -106.608679)
			(xy 214.691949 -106.650216) (xy 214.649081 -106.685891) (xy 214.601475 -106.714945) (xy 214.550146 -106.736757)
			(xy 214.496189 -106.750863) (xy 214.440752 -106.756963) (xy 214.385018 -106.754926) (xy 214.330175 -106.744796)
			(xy 214.277391 -106.726789) (xy 214.227791 -106.701288) (xy 214.182433 -106.668837) (xy 214.142284 -106.630128)
			(xy 214.108198 -106.585985) (xy 214.080902 -106.53735) (xy 214.060979 -106.485259) (xy 214.048853 -106.430822)
			(xy 214.044782 -106.3752) (xy 213.842644 -106.3752) (xy 213.843108 -106.4006) (xy 213.842599 -106.428486)
			(xy 213.834479 -106.483662) (xy 213.818411 -106.537069) (xy 213.794739 -106.587566) (xy 213.763966 -106.634079)
			(xy 213.726749 -106.675616) (xy 213.683881 -106.711291) (xy 213.636275 -106.740345) (xy 213.584946 -106.762157)
			(xy 213.530989 -106.776263) (xy 213.475552 -106.782363) (xy 213.419818 -106.780326) (xy 213.364975 -106.770196)
			(xy 213.312191 -106.752189) (xy 213.262591 -106.726688) (xy 213.217233 -106.694237) (xy 213.177084 -106.655528)
			(xy 213.142998 -106.611385) (xy 213.115702 -106.56275) (xy 213.095779 -106.510659) (xy 213.083653 -106.456222)
			(xy 213.079582 -106.4006) (xy 208.5975 -106.4006) (xy 208.5975 -106.983276) (xy 208.812382 -106.983276)
			(xy 208.816453 -106.927654) (xy 208.828579 -106.873217) (xy 208.848502 -106.821126) (xy 208.875798 -106.772491)
			(xy 208.909884 -106.728348) (xy 208.950033 -106.689639) (xy 208.995391 -106.657188) (xy 209.044991 -106.631687)
			(xy 209.097775 -106.61368) (xy 209.152618 -106.60355) (xy 209.208352 -106.601513) (xy 209.263789 -106.607613)
			(xy 209.317746 -106.621719) (xy 209.369075 -106.643531) (xy 209.416681 -106.672585) (xy 209.459549 -106.70826)
			(xy 209.496766 -106.749797) (xy 209.527539 -106.79631) (xy 209.551211 -106.846807) (xy 209.567279 -106.900214)
			(xy 209.575399 -106.95539) (xy 209.575908 -106.983276) (xy 209.575399 -107.011162) (xy 209.567279 -107.066338)
			(xy 209.551211 -107.119745) (xy 209.527539 -107.170242) (xy 209.496766 -107.216755) (xy 209.465866 -107.251242)
			(xy 214.551242 -107.251242) (xy 214.551242 -107.191306) (xy 214.559065 -107.131884) (xy 214.574578 -107.073991)
			(xy 214.597514 -107.018618) (xy 214.627481 -106.966712) (xy 214.663968 -106.919162) (xy 214.706348 -106.876782)
			(xy 214.753898 -106.840295) (xy 214.805804 -106.810328) (xy 214.861177 -106.787392) (xy 214.91907 -106.771879)
			(xy 214.978492 -106.764056) (xy 215.038428 -106.764056) (xy 215.09785 -106.771879) (xy 215.155743 -106.787392)
			(xy 215.211116 -106.810328) (xy 215.263022 -106.840295) (xy 215.310572 -106.876782) (xy 215.352952 -106.919162)
			(xy 215.389439 -106.966712) (xy 215.419406 -107.018618) (xy 215.442342 -107.073991) (xy 215.457855 -107.131884)
			(xy 215.465678 -107.191306) (xy 215.466168 -107.221274) (xy 215.465678 -107.251242) (xy 215.457855 -107.310664)
			(xy 215.442342 -107.368557) (xy 215.419406 -107.42393) (xy 215.389439 -107.475836) (xy 215.352952 -107.523386)
			(xy 215.310572 -107.565766) (xy 215.263022 -107.602253) (xy 215.211116 -107.63222) (xy 215.155743 -107.655156)
			(xy 215.09785 -107.670669) (xy 215.038428 -107.678492) (xy 214.978492 -107.678492) (xy 214.91907 -107.670669)
			(xy 214.861177 -107.655156) (xy 214.805804 -107.63222) (xy 214.753898 -107.602253) (xy 214.706348 -107.565766)
			(xy 214.663968 -107.523386) (xy 214.627481 -107.475836) (xy 214.597514 -107.42393) (xy 214.574578 -107.368557)
			(xy 214.559065 -107.310664) (xy 214.551242 -107.251242) (xy 209.465866 -107.251242) (xy 209.459549 -107.258292)
			(xy 209.416681 -107.293967) (xy 209.369075 -107.323021) (xy 209.317746 -107.344833) (xy 209.263789 -107.358939)
			(xy 209.208352 -107.365039) (xy 209.152618 -107.363002) (xy 209.097775 -107.352872) (xy 209.044991 -107.334865)
			(xy 208.995391 -107.309364) (xy 208.950033 -107.276913) (xy 208.909884 -107.238204) (xy 208.875798 -107.194061)
			(xy 208.848502 -107.145426) (xy 208.828579 -107.093335) (xy 208.816453 -107.038898) (xy 208.812382 -106.983276)
			(xy 208.5975 -106.983276) (xy 208.5975 -108.263944) (xy 208.597937 -108.277543) (xy 208.605124 -108.303774)
			(xy 208.618976 -108.327181) (xy 208.638512 -108.346103) (xy 208.662349 -108.359201) (xy 208.688796 -108.365547)
			(xy 208.702402 -108.365544) (xy 208.71688 -108.36529) (xy 208.74685 -108.365758) (xy 208.806277 -108.373579)
			(xy 208.864176 -108.389091) (xy 208.919554 -108.412027) (xy 208.971464 -108.441995) (xy 209.019019 -108.478483)
			(xy 209.023936 -108.4834) (xy 211.047582 -108.4834) (xy 211.051653 -108.427778) (xy 211.063779 -108.373341)
			(xy 211.083702 -108.32125) (xy 211.110998 -108.272615) (xy 211.145084 -108.228472) (xy 211.185233 -108.189763)
			(xy 211.230591 -108.157312) (xy 211.280191 -108.131811) (xy 211.332975 -108.113804) (xy 211.387818 -108.103674)
			(xy 211.443552 -108.101637) (xy 211.498989 -108.107737) (xy 211.552946 -108.121843) (xy 211.604275 -108.143655)
			(xy 211.651881 -108.172709) (xy 211.694749 -108.208384) (xy 211.731966 -108.249921) (xy 211.762739 -108.296434)
			(xy 211.786411 -108.346931) (xy 211.802479 -108.400338) (xy 211.810599 -108.455514) (xy 211.811108 -108.4834)
			(xy 211.810599 -108.511286) (xy 211.802479 -108.566462) (xy 211.786411 -108.619869) (xy 211.762739 -108.670366)
			(xy 211.731966 -108.716879) (xy 211.694749 -108.758416) (xy 211.651881 -108.794091) (xy 211.604275 -108.823145)
			(xy 211.552946 -108.844957) (xy 211.498989 -108.859063) (xy 211.443552 -108.865163) (xy 211.387818 -108.863126)
			(xy 211.332975 -108.852996) (xy 211.280191 -108.834989) (xy 211.230591 -108.809488) (xy 211.185233 -108.777037)
			(xy 211.145084 -108.738328) (xy 211.110998 -108.694185) (xy 211.083702 -108.64555) (xy 211.063779 -108.593459)
			(xy 211.051653 -108.539022) (xy 211.047582 -108.4834) (xy 209.023936 -108.4834) (xy 209.061403 -108.520866)
			(xy 209.097893 -108.568419) (xy 209.127864 -108.620328) (xy 209.150803 -108.675705) (xy 209.166317 -108.733603)
			(xy 209.174141 -108.79303) (xy 209.174141 -108.85297) (xy 209.166317 -108.912397) (xy 209.150803 -108.970295)
			(xy 209.127864 -109.025672) (xy 209.097893 -109.077581) (xy 209.061403 -109.125134) (xy 209.019019 -109.167517)
			(xy 208.971464 -109.204005) (xy 208.919554 -109.233973) (xy 208.864176 -109.256909) (xy 208.806277 -109.272421)
			(xy 208.74685 -109.280242) (xy 208.71688 -109.280706) (xy 208.702402 -109.280452) (xy 208.688793 -109.280443)
			(xy 208.662334 -109.286772) (xy 208.638487 -109.299864) (xy 208.618945 -109.318791) (xy 208.605096 -109.342207)
			(xy 208.597924 -109.368449) (xy 208.5975 -109.382052) (xy 208.5975 -110.3122) (xy 212.774782 -110.3122)
			(xy 212.778853 -110.256578) (xy 212.790979 -110.202141) (xy 212.810902 -110.15005) (xy 212.838198 -110.101415)
			(xy 212.872284 -110.057272) (xy 212.912433 -110.018563) (xy 212.957791 -109.986112) (xy 213.007391 -109.960611)
			(xy 213.060175 -109.942604) (xy 213.115018 -109.932474) (xy 213.170752 -109.930437) (xy 213.226189 -109.936537)
			(xy 213.280146 -109.950643) (xy 213.331475 -109.972455) (xy 213.379081 -110.001509) (xy 213.421949 -110.037184)
			(xy 213.459166 -110.078721) (xy 213.489939 -110.125234) (xy 213.513611 -110.175731) (xy 213.529679 -110.229138)
			(xy 213.537799 -110.284314) (xy 213.538308 -110.3122) (xy 213.537799 -110.340086) (xy 213.529679 -110.395262)
			(xy 213.513611 -110.448669) (xy 213.489939 -110.499166) (xy 213.459166 -110.545679) (xy 213.421949 -110.587216)
			(xy 213.379081 -110.622891) (xy 213.331475 -110.651945) (xy 213.280146 -110.673757) (xy 213.226189 -110.687863)
			(xy 213.170752 -110.693963) (xy 213.115018 -110.691926) (xy 213.060175 -110.681796) (xy 213.007391 -110.663789)
			(xy 212.957791 -110.638288) (xy 212.912433 -110.605837) (xy 212.872284 -110.567128) (xy 212.838198 -110.522985)
			(xy 212.810902 -110.47435) (xy 212.790979 -110.422259) (xy 212.778853 -110.367822) (xy 212.774782 -110.3122)
			(xy 208.5975 -110.3122) (xy 208.5975 -112.57534) (xy 210.11896 -114.0968) (xy 210.590382 -114.0968)
			(xy 210.594453 -114.041178) (xy 210.606579 -113.986741) (xy 210.626502 -113.93465) (xy 210.653798 -113.886015)
			(xy 210.687884 -113.841872) (xy 210.728033 -113.803163) (xy 210.773391 -113.770712) (xy 210.822991 -113.745211)
			(xy 210.875775 -113.727204) (xy 210.930618 -113.717074) (xy 210.986352 -113.715037) (xy 211.041789 -113.721137)
			(xy 211.095746 -113.735243) (xy 211.147075 -113.757055) (xy 211.194681 -113.786109) (xy 211.237549 -113.821784)
			(xy 211.274766 -113.863321) (xy 211.305539 -113.909834) (xy 211.329211 -113.960331) (xy 211.345279 -114.013738)
			(xy 211.353399 -114.068914) (xy 211.353908 -114.0968) (xy 211.353399 -114.124686) (xy 211.345279 -114.179862)
			(xy 211.329211 -114.233269) (xy 211.305539 -114.283766) (xy 211.274766 -114.330279) (xy 211.237549 -114.371816)
			(xy 211.194681 -114.407491) (xy 211.147075 -114.436545) (xy 211.095746 -114.458357) (xy 211.041789 -114.472463)
			(xy 210.986352 -114.478563) (xy 210.930618 -114.476526) (xy 210.875775 -114.466396) (xy 210.822991 -114.448389)
			(xy 210.773391 -114.422888) (xy 210.728033 -114.390437) (xy 210.687884 -114.351728) (xy 210.653798 -114.307585)
			(xy 210.626502 -114.25895) (xy 210.606579 -114.206859) (xy 210.594453 -114.152422) (xy 210.590382 -114.0968)
			(xy 210.11896 -114.0968) (xy 210.8073 -114.78514) (xy 213.34984 -114.78514)
		)
		(stroke
			(width 0)
			(type solid)
		)
		(fill yes)
		(layer "B.Cu")
		(net "P12V_AUX")
	)
	(gr_poly
		(pts
			(xy 434.894482 -111.203486) (xy 434.90472 -111.192509) (xy 434.918876 -111.166056) (xy 434.924738 -111.136632)
			(xy 434.9218 -111.106774) (xy 434.910315 -111.079057) (xy 434.891274 -111.055872) (xy 434.866319 -111.039218)
			(xy 434.837602 -111.03053) (xy 434.8226 -111.030004) (xy 430.175416 -111.030004) (xy 430.15035 -111.029506)
			(xy 430.100836 -111.02165) (xy 430.053161 -111.006147) (xy 430.008498 -110.983376) (xy 429.967946 -110.953899)
			(xy 429.949864 -110.936532) (xy 429.608488 -110.595156) (xy 429.59782 -110.584234) (xy 429.591138 -110.577487)
			(xy 429.574131 -110.569069) (xy 429.55523 -110.567388) (xy 429.537005 -110.572672) (xy 429.52924 -110.578138)
			(xy 429.509109 -110.59324) (xy 429.465631 -110.618583) (xy 429.419195 -110.637984) (xy 429.370611 -110.651107)
			(xy 429.320723 -110.657723) (xy 429.29556 -110.658148) (xy 429.26831 -110.65766) (xy 429.214364 -110.649899)
			(xy 429.162072 -110.63454) (xy 429.112497 -110.611898) (xy 429.066649 -110.582431) (xy 429.02546 -110.54674)
			(xy 428.989769 -110.505551) (xy 428.960302 -110.459703) (xy 428.93766 -110.410128) (xy 428.922301 -110.357836)
			(xy 428.91454 -110.30389) (xy 428.914052 -110.27664) (xy 428.9145 -110.249972) (xy 428.921935 -110.197157)
			(xy 428.93665 -110.145892) (xy 428.95836 -110.097174) (xy 428.986642 -110.051954) (xy 429.020944 -110.011113)
			(xy 429.060599 -109.975444) (xy 429.082454 -109.960156) (xy 429.093805 -109.952011) (xy 429.1119 -109.930738)
			(xy 429.123538 -109.90535) (xy 429.127843 -109.877756) (xy 429.124492 -109.85003) (xy 429.119538 -109.836966)
			(xy 429.107944 -109.813887) (xy 429.091542 -109.764916) (xy 429.083231 -109.713944) (xy 429.082708 -109.688122)
			(xy 429.082708 -109.548168) (xy 429.069246 -109.532511) (xy 429.047673 -109.497309) (xy 429.032851 -109.458774)
			(xy 429.025274 -109.418189) (xy 429.024796 -109.397546) (xy 429.024796 -109.130084) (xy 429.08474 -109.130084)
			(xy 429.08474 -108.604812) (xy 429.024796 -108.604812) (xy 429.024796 -108.33735) (xy 429.02536 -108.315508)
			(xy 429.033831 -108.272651) (xy 429.050336 -108.232202) (xy 429.06188 -108.213652) (xy 429.070262 -108.185712)
			(xy 429.057816 -108.152438) (xy 429.043043 -108.134925) (xy 429.01815 -108.096461) (xy 428.99902 -108.054829)
			(xy 428.986046 -108.010888) (xy 428.979497 -107.965542) (xy 428.979076 -107.942634) (xy 428.979076 -107.611672)
			(xy 428.979506 -107.589264) (xy 428.985876 -107.544901) (xy 428.991776 -107.52328) (xy 428.993808 -107.516422)
			(xy 428.993808 -107.479846) (xy 428.979838 -107.465114) (xy 428.960361 -107.443834) (xy 428.926358 -107.397232)
			(xy 428.898486 -107.346723) (xy 428.877186 -107.293111) (xy 428.862796 -107.237246) (xy 428.855546 -107.180014)
			(xy 428.855124 -107.15117) (xy 428.855614 -107.121202) (xy 428.863437 -107.06178) (xy 428.87895 -107.003887)
			(xy 428.901886 -106.948514) (xy 428.931853 -106.896608) (xy 428.96834 -106.849058) (xy 429.01072 -106.806678)
			(xy 429.05827 -106.770191) (xy 429.110176 -106.740224) (xy 429.165549 -106.717288) (xy 429.223442 -106.701775)
			(xy 429.282864 -106.693952) (xy 429.3428 -106.693952) (xy 429.402222 -106.701775) (xy 429.460115 -106.717288)
			(xy 429.515488 -106.740224) (xy 429.567394 -106.770191) (xy 429.614944 -106.806678) (xy 429.657324 -106.849058)
			(xy 429.693811 -106.896608) (xy 429.723778 -106.948514) (xy 429.746714 -107.003887) (xy 429.762227 -107.06178)
			(xy 429.77005 -107.121202) (xy 429.77054 -107.15117) (xy 429.770104 -107.180014) (xy 429.762856 -107.237246)
			(xy 429.74905 -107.290866) (xy 430.188352 -107.290866) (xy 430.188352 -107.23093) (xy 430.196175 -107.171508)
			(xy 430.211688 -107.113615) (xy 430.234624 -107.058242) (xy 430.264591 -107.006336) (xy 430.301078 -106.958786)
			(xy 430.343458 -106.916406) (xy 430.391008 -106.879919) (xy 430.442914 -106.849952) (xy 430.498287 -106.827016)
			(xy 430.55618 -106.811503) (xy 430.615602 -106.80368) (xy 430.675538 -106.80368) (xy 430.677574 -106.803948)
			(xy 433.265054 -106.803948) (xy 433.265054 -106.744012) (xy 433.272877 -106.68459) (xy 433.28839 -106.626697)
			(xy 433.311326 -106.571324) (xy 433.341293 -106.519418) (xy 433.37778 -106.471868) (xy 433.42016 -106.429488)
			(xy 433.46771 -106.393001) (xy 433.519616 -106.363034) (xy 433.574989 -106.340098) (xy 433.632882 -106.324585)
			(xy 433.692304 -106.316762) (xy 433.75224 -106.316762) (xy 433.811662 -106.324585) (xy 433.869555 -106.340098)
			(xy 433.924928 -106.363034) (xy 433.976834 -106.393001) (xy 434.024384 -106.429488) (xy 434.066764 -106.471868)
			(xy 434.103251 -106.519418) (xy 434.133218 -106.571324) (xy 434.156154 -106.626697) (xy 434.171667 -106.68459)
			(xy 434.17949 -106.744012) (xy 434.17998 -106.77398) (xy 434.17949 -106.803948) (xy 434.171667 -106.86337)
			(xy 434.156154 -106.921263) (xy 434.133218 -106.976636) (xy 434.103251 -107.028542) (xy 434.066764 -107.076092)
			(xy 434.024384 -107.118472) (xy 433.976834 -107.154959) (xy 433.924928 -107.184926) (xy 433.869555 -107.207862)
			(xy 433.811662 -107.223375) (xy 433.75224 -107.231198) (xy 433.692304 -107.231198) (xy 433.632882 -107.223375)
			(xy 433.574989 -107.207862) (xy 433.519616 -107.184926) (xy 433.46771 -107.154959) (xy 433.42016 -107.118472)
			(xy 433.37778 -107.076092) (xy 433.341293 -107.028542) (xy 433.311326 -106.976636) (xy 433.28839 -106.921263)
			(xy 433.272877 -106.86337) (xy 433.265054 -106.803948) (xy 430.677574 -106.803948) (xy 430.73496 -106.811503)
			(xy 430.792853 -106.827016) (xy 430.848226 -106.849952) (xy 430.900132 -106.879919) (xy 430.947682 -106.916406)
			(xy 430.990062 -106.958786) (xy 431.026549 -107.006336) (xy 431.056516 -107.058242) (xy 431.079452 -107.113615)
			(xy 431.094965 -107.171508) (xy 431.102788 -107.23093) (xy 431.103278 -107.260898) (xy 431.102788 -107.290866)
			(xy 431.094965 -107.350288) (xy 431.079452 -107.408181) (xy 431.056516 -107.463554) (xy 431.026549 -107.51546)
			(xy 430.990062 -107.56301) (xy 430.947682 -107.60539) (xy 430.900132 -107.641877) (xy 430.848226 -107.671844)
			(xy 430.838975 -107.675676) (xy 431.628278 -107.675676) (xy 431.628278 -107.61574) (xy 431.636101 -107.556318)
			(xy 431.651614 -107.498425) (xy 431.67455 -107.443052) (xy 431.704517 -107.391146) (xy 431.741004 -107.343596)
			(xy 431.783384 -107.301216) (xy 431.830934 -107.264729) (xy 431.88284 -107.234762) (xy 431.938213 -107.211826)
			(xy 431.996106 -107.196313) (xy 432.055528 -107.18849) (xy 432.115464 -107.18849) (xy 432.174886 -107.196313)
			(xy 432.232779 -107.211826) (xy 432.288152 -107.234762) (xy 432.340058 -107.264729) (xy 432.387608 -107.301216)
			(xy 432.429988 -107.343596) (xy 432.466475 -107.391146) (xy 432.496442 -107.443052) (xy 432.519378 -107.498425)
			(xy 432.534891 -107.556318) (xy 432.542714 -107.61574) (xy 432.543204 -107.645708) (xy 432.542714 -107.675676)
			(xy 432.534891 -107.735098) (xy 432.519378 -107.792991) (xy 432.496442 -107.848364) (xy 432.466475 -107.90027)
			(xy 432.429988 -107.94782) (xy 432.387608 -107.9902) (xy 432.340058 -108.026687) (xy 432.288152 -108.056654)
			(xy 432.232779 -108.07959) (xy 432.174886 -108.095103) (xy 432.115464 -108.102926) (xy 432.055528 -108.102926)
			(xy 431.996106 -108.095103) (xy 431.938213 -108.07959) (xy 431.88284 -108.056654) (xy 431.830934 -108.026687)
			(xy 431.783384 -107.9902) (xy 431.741004 -107.94782) (xy 431.704517 -107.90027) (xy 431.67455 -107.848364)
			(xy 431.651614 -107.792991) (xy 431.636101 -107.735098) (xy 431.628278 -107.675676) (xy 430.838975 -107.675676)
			(xy 430.792853 -107.69478) (xy 430.73496 -107.710293) (xy 430.675538 -107.718116) (xy 430.615602 -107.718116)
			(xy 430.55618 -107.710293) (xy 430.498287 -107.69478) (xy 430.442914 -107.671844) (xy 430.391008 -107.641877)
			(xy 430.343458 -107.60539) (xy 430.301078 -107.56301) (xy 430.264591 -107.51546) (xy 430.234624 -107.463554)
			(xy 430.211688 -107.408181) (xy 430.196175 -107.350288) (xy 430.188352 -107.290866) (xy 429.74905 -107.290866)
			(xy 429.748471 -107.293113) (xy 429.727178 -107.346728) (xy 429.699313 -107.397241) (xy 429.66532 -107.443851)
			(xy 429.645826 -107.465114) (xy 429.631856 -107.479846) (xy 429.631856 -107.597448) (xy 429.63148 -107.619784)
			(xy 429.625226 -107.664017) (xy 429.61941 -107.685586) (xy 429.617632 -107.692444) (xy 429.617632 -107.810808)
			(xy 429.636798 -107.829071) (xy 429.669399 -107.870778) (xy 429.694674 -107.917291) (xy 429.711929 -107.967337)
			(xy 429.720692 -108.019544) (xy 429.721264 -108.046012) (xy 429.721264 -108.18622) (xy 429.73482 -108.201908)
			(xy 429.756557 -108.237209) (xy 429.771501 -108.275878) (xy 429.779151 -108.316623) (xy 429.779684 -108.33735)
			(xy 429.779684 -108.604812) (xy 429.71974 -108.604812) (xy 429.71974 -109.130084) (xy 429.779684 -109.130084)
			(xy 429.779684 -109.397546) (xy 429.779151 -109.419277) (xy 429.770806 -109.461933) (xy 429.754506 -109.502225)
			(xy 429.743108 -109.520736) (xy 429.721772 -109.553248) (xy 429.721772 -109.556296) (xy 429.858571 -109.693198)
			(xy 433.258958 -109.693198) (xy 433.258958 -109.633262) (xy 433.266781 -109.57384) (xy 433.282294 -109.515947)
			(xy 433.30523 -109.460574) (xy 433.335197 -109.408668) (xy 433.371684 -109.361118) (xy 433.414064 -109.318738)
			(xy 433.461614 -109.282251) (xy 433.51352 -109.252284) (xy 433.568893 -109.229348) (xy 433.626786 -109.213835)
			(xy 433.686208 -109.206012) (xy 433.746144 -109.206012) (xy 433.805566 -109.213835) (xy 433.863459 -109.229348)
			(xy 433.918832 -109.252284) (xy 433.970738 -109.282251) (xy 434.018288 -109.318738) (xy 434.060668 -109.361118)
			(xy 434.097155 -109.408668) (xy 434.127122 -109.460574) (xy 434.150058 -109.515947) (xy 434.165571 -109.57384)
			(xy 434.173394 -109.633262) (xy 434.173884 -109.66323) (xy 434.173394 -109.693198) (xy 434.165571 -109.75262)
			(xy 434.150058 -109.810513) (xy 434.127122 -109.865886) (xy 434.097155 -109.917792) (xy 434.060668 -109.965342)
			(xy 434.018288 -110.007722) (xy 433.970738 -110.044209) (xy 433.918832 -110.074176) (xy 433.863459 -110.097112)
			(xy 433.805566 -110.112625) (xy 433.746144 -110.120448) (xy 433.686208 -110.120448) (xy 433.626786 -110.112625)
			(xy 433.568893 -110.097112) (xy 433.51352 -110.074176) (xy 433.461614 -110.044209) (xy 433.414064 -110.007722)
			(xy 433.371684 -109.965342) (xy 433.335197 -109.917792) (xy 433.30523 -109.865886) (xy 433.282294 -109.810513)
			(xy 433.266781 -109.75262) (xy 433.258958 -109.693198) (xy 429.858571 -109.693198) (xy 430.059592 -109.89437)
			(xy 430.077002 -109.912416) (xy 430.106496 -109.952967) (xy 430.129274 -109.997637) (xy 430.144772 -110.045324)
			(xy 430.152608 -110.094851) (xy 430.153064 -110.119922) (xy 430.153064 -110.237524) (xy 430.307496 -110.391956)
			(xy 435.706012 -110.391956) (xy 436.98668 -109.111288) (xy 436.98668 -97.127568) (xy 436.7149 -96.855788)
			(xy 436.705094 -96.846558) (xy 436.681748 -96.833154) (xy 436.655708 -96.826327) (xy 436.628789 -96.826554)
			(xy 436.602867 -96.833819) (xy 436.57975 -96.847614) (xy 436.56105 -96.86698) (xy 436.54807 -96.890564)
			(xy 436.544466 -96.90354) (xy 436.537254 -96.930819) (xy 436.51589 -96.983042) (xy 436.487067 -97.031548)
			(xy 436.451412 -97.075279) (xy 436.409705 -97.113281) (xy 436.362854 -97.144723) (xy 436.311883 -97.168921)
			(xy 436.257903 -97.185347) (xy 436.202092 -97.193641) (xy 436.17388 -97.194116) (xy 436.146629 -97.193629)
			(xy 436.092683 -97.18587) (xy 436.040391 -97.170513) (xy 435.990815 -97.147871) (xy 435.944967 -97.118404)
			(xy 435.903778 -97.082713) (xy 435.868088 -97.041523) (xy 435.838623 -96.995674) (xy 435.815982 -96.946098)
			(xy 435.800627 -96.893805) (xy 435.79287 -96.839859) (xy 435.792372 -96.812608) (xy 435.792886 -96.784403)
			(xy 435.801203 -96.728609) (xy 435.817644 -96.674647) (xy 435.841848 -96.623693) (xy 435.87329 -96.576857)
			(xy 435.911283 -96.53516) (xy 435.955001 -96.49951) (xy 436.00349 -96.470684) (xy 436.055694 -96.44931)
			(xy 436.082948 -96.442022) (xy 436.095913 -96.438414) (xy 436.119456 -96.425398) (xy 436.138785 -96.406686)
			(xy 436.152557 -96.383577) (xy 436.159818 -96.357673) (xy 436.160063 -96.330772) (xy 436.153275 -96.30474)
			(xy 436.139926 -96.281383) (xy 436.1307 -96.271588) (xy 435.60746 -95.748348) (xy 421.197024 -95.748348)
			(xy 420.132595 -96.812608) (xy 434.902862 -96.812608) (xy 434.906933 -96.756986) (xy 434.919059 -96.702549)
			(xy 434.938982 -96.650458) (xy 434.966278 -96.601823) (xy 435.000364 -96.55768) (xy 435.040513 -96.518971)
			(xy 435.085871 -96.48652) (xy 435.135471 -96.461019) (xy 435.188255 -96.443012) (xy 435.243098 -96.432882)
			(xy 435.298832 -96.430845) (xy 435.354269 -96.436945) (xy 435.408226 -96.451051) (xy 435.459555 -96.472863)
			(xy 435.507161 -96.501917) (xy 435.550029 -96.537592) (xy 435.587246 -96.579129) (xy 435.618019 -96.625642)
			(xy 435.641691 -96.676139) (xy 435.657759 -96.729546) (xy 435.665879 -96.784722) (xy 435.666388 -96.812608)
			(xy 435.665879 -96.840494) (xy 435.657759 -96.89567) (xy 435.641691 -96.949077) (xy 435.618019 -96.999574)
			(xy 435.587246 -97.046087) (xy 435.550029 -97.087624) (xy 435.507161 -97.123299) (xy 435.459555 -97.152353)
			(xy 435.408226 -97.174165) (xy 435.354269 -97.188271) (xy 435.298832 -97.194371) (xy 435.243098 -97.192334)
			(xy 435.188255 -97.182204) (xy 435.135471 -97.164197) (xy 435.085871 -97.138696) (xy 435.040513 -97.106245)
			(xy 435.000364 -97.067536) (xy 434.966278 -97.023393) (xy 434.938982 -96.974758) (xy 434.919059 -96.922667)
			(xy 434.906933 -96.86823) (xy 434.902862 -96.812608) (xy 420.132595 -96.812608) (xy 419.601904 -97.343214)
			(xy 419.601904 -97.701608) (xy 434.902862 -97.701608) (xy 434.906933 -97.645986) (xy 434.919059 -97.591549)
			(xy 434.938982 -97.539458) (xy 434.966278 -97.490823) (xy 435.000364 -97.44668) (xy 435.040513 -97.407971)
			(xy 435.085871 -97.37552) (xy 435.135471 -97.350019) (xy 435.188255 -97.332012) (xy 435.243098 -97.321882)
			(xy 435.298832 -97.319845) (xy 435.354269 -97.325945) (xy 435.408226 -97.340051) (xy 435.459555 -97.361863)
			(xy 435.507161 -97.390917) (xy 435.550029 -97.426592) (xy 435.587246 -97.468129) (xy 435.618019 -97.514642)
			(xy 435.641691 -97.565139) (xy 435.657759 -97.618546) (xy 435.665879 -97.673722) (xy 435.666388 -97.701608)
			(xy 435.791862 -97.701608) (xy 435.795933 -97.645986) (xy 435.808059 -97.591549) (xy 435.827982 -97.539458)
			(xy 435.855278 -97.490823) (xy 435.889364 -97.44668) (xy 435.929513 -97.407971) (xy 435.974871 -97.37552)
			(xy 436.024471 -97.350019) (xy 436.077255 -97.332012) (xy 436.132098 -97.321882) (xy 436.187832 -97.319845)
			(xy 436.243269 -97.325945) (xy 436.297226 -97.340051) (xy 436.348555 -97.361863) (xy 436.396161 -97.390917)
			(xy 436.439029 -97.426592) (xy 436.476246 -97.468129) (xy 436.507019 -97.514642) (xy 436.530691 -97.565139)
			(xy 436.546759 -97.618546) (xy 436.554879 -97.673722) (xy 436.555388 -97.701608) (xy 436.554879 -97.729494)
			(xy 436.546759 -97.78467) (xy 436.530691 -97.838077) (xy 436.507019 -97.888574) (xy 436.476246 -97.935087)
			(xy 436.439029 -97.976624) (xy 436.396161 -98.012299) (xy 436.348555 -98.041353) (xy 436.297226 -98.063165)
			(xy 436.243269 -98.077271) (xy 436.187832 -98.083371) (xy 436.132098 -98.081334) (xy 436.077255 -98.071204)
			(xy 436.024471 -98.053197) (xy 435.974871 -98.027696) (xy 435.929513 -97.995245) (xy 435.889364 -97.956536)
			(xy 435.855278 -97.912393) (xy 435.827982 -97.863758) (xy 435.808059 -97.811667) (xy 435.795933 -97.75723)
			(xy 435.791862 -97.701608) (xy 435.666388 -97.701608) (xy 435.665879 -97.729494) (xy 435.657759 -97.78467)
			(xy 435.641691 -97.838077) (xy 435.618019 -97.888574) (xy 435.587246 -97.935087) (xy 435.550029 -97.976624)
			(xy 435.507161 -98.012299) (xy 435.459555 -98.041353) (xy 435.408226 -98.063165) (xy 435.354269 -98.077271)
			(xy 435.298832 -98.083371) (xy 435.243098 -98.081334) (xy 435.188255 -98.071204) (xy 435.135471 -98.053197)
			(xy 435.085871 -98.027696) (xy 435.040513 -97.995245) (xy 435.000364 -97.956536) (xy 434.966278 -97.912393)
			(xy 434.938982 -97.863758) (xy 434.919059 -97.811667) (xy 434.906933 -97.75723) (xy 434.902862 -97.701608)
			(xy 419.601904 -97.701608) (xy 419.601904 -98.590608) (xy 434.902862 -98.590608) (xy 434.906933 -98.534986)
			(xy 434.919059 -98.480549) (xy 434.938982 -98.428458) (xy 434.966278 -98.379823) (xy 435.000364 -98.33568)
			(xy 435.040513 -98.296971) (xy 435.085871 -98.26452) (xy 435.135471 -98.239019) (xy 435.188255 -98.221012)
			(xy 435.243098 -98.210882) (xy 435.298832 -98.208845) (xy 435.354269 -98.214945) (xy 435.408226 -98.229051)
			(xy 435.459555 -98.250863) (xy 435.507161 -98.279917) (xy 435.550029 -98.315592) (xy 435.587246 -98.357129)
			(xy 435.618019 -98.403642) (xy 435.641691 -98.454139) (xy 435.657759 -98.507546) (xy 435.665879 -98.562722)
			(xy 435.666388 -98.590608) (xy 435.791862 -98.590608) (xy 435.795933 -98.534986) (xy 435.808059 -98.480549)
			(xy 435.827982 -98.428458) (xy 435.855278 -98.379823) (xy 435.889364 -98.33568) (xy 435.929513 -98.296971)
			(xy 435.974871 -98.26452) (xy 436.024471 -98.239019) (xy 436.077255 -98.221012) (xy 436.132098 -98.210882)
			(xy 436.187832 -98.208845) (xy 436.243269 -98.214945) (xy 436.297226 -98.229051) (xy 436.348555 -98.250863)
			(xy 436.396161 -98.279917) (xy 436.439029 -98.315592) (xy 436.476246 -98.357129) (xy 436.507019 -98.403642)
			(xy 436.530691 -98.454139) (xy 436.546759 -98.507546) (xy 436.554879 -98.562722) (xy 436.555388 -98.590608)
			(xy 436.554879 -98.618494) (xy 436.546759 -98.67367) (xy 436.530691 -98.727077) (xy 436.507019 -98.777574)
			(xy 436.476246 -98.824087) (xy 436.439029 -98.865624) (xy 436.396161 -98.901299) (xy 436.348555 -98.930353)
			(xy 436.297226 -98.952165) (xy 436.243269 -98.966271) (xy 436.187832 -98.972371) (xy 436.132098 -98.970334)
			(xy 436.077255 -98.960204) (xy 436.024471 -98.942197) (xy 435.974871 -98.916696) (xy 435.929513 -98.884245)
			(xy 435.889364 -98.845536) (xy 435.855278 -98.801393) (xy 435.827982 -98.752758) (xy 435.808059 -98.700667)
			(xy 435.795933 -98.64623) (xy 435.791862 -98.590608) (xy 435.666388 -98.590608) (xy 435.665879 -98.618494)
			(xy 435.657759 -98.67367) (xy 435.641691 -98.727077) (xy 435.618019 -98.777574) (xy 435.587246 -98.824087)
			(xy 435.550029 -98.865624) (xy 435.507161 -98.901299) (xy 435.459555 -98.930353) (xy 435.408226 -98.952165)
			(xy 435.354269 -98.966271) (xy 435.298832 -98.972371) (xy 435.243098 -98.970334) (xy 435.188255 -98.960204)
			(xy 435.135471 -98.942197) (xy 435.085871 -98.916696) (xy 435.040513 -98.884245) (xy 435.000364 -98.845536)
			(xy 434.966278 -98.801393) (xy 434.938982 -98.752758) (xy 434.919059 -98.700667) (xy 434.906933 -98.64623)
			(xy 434.902862 -98.590608) (xy 419.601904 -98.590608) (xy 419.601904 -99.479608) (xy 434.902862 -99.479608)
			(xy 434.906933 -99.423986) (xy 434.919059 -99.369549) (xy 434.938982 -99.317458) (xy 434.966278 -99.268823)
			(xy 435.000364 -99.22468) (xy 435.040513 -99.185971) (xy 435.085871 -99.15352) (xy 435.135471 -99.128019)
			(xy 435.188255 -99.110012) (xy 435.243098 -99.099882) (xy 435.298832 -99.097845) (xy 435.354269 -99.103945)
			(xy 435.408226 -99.118051) (xy 435.459555 -99.139863) (xy 435.507161 -99.168917) (xy 435.550029 -99.204592)
			(xy 435.587246 -99.246129) (xy 435.618019 -99.292642) (xy 435.641691 -99.343139) (xy 435.657759 -99.396546)
			(xy 435.665879 -99.451722) (xy 435.666388 -99.479608) (xy 435.791862 -99.479608) (xy 435.795933 -99.423986)
			(xy 435.808059 -99.369549) (xy 435.827982 -99.317458) (xy 435.855278 -99.268823) (xy 435.889364 -99.22468)
			(xy 435.929513 -99.185971) (xy 435.974871 -99.15352) (xy 436.024471 -99.128019) (xy 436.077255 -99.110012)
			(xy 436.132098 -99.099882) (xy 436.187832 -99.097845) (xy 436.243269 -99.103945) (xy 436.297226 -99.118051)
			(xy 436.348555 -99.139863) (xy 436.396161 -99.168917) (xy 436.439029 -99.204592) (xy 436.476246 -99.246129)
			(xy 436.507019 -99.292642) (xy 436.530691 -99.343139) (xy 436.546759 -99.396546) (xy 436.554879 -99.451722)
			(xy 436.555388 -99.479608) (xy 436.554879 -99.507494) (xy 436.546759 -99.56267) (xy 436.530691 -99.616077)
			(xy 436.507019 -99.666574) (xy 436.476246 -99.713087) (xy 436.439029 -99.754624) (xy 436.396161 -99.790299)
			(xy 436.348555 -99.819353) (xy 436.297226 -99.841165) (xy 436.243269 -99.855271) (xy 436.187832 -99.861371)
			(xy 436.132098 -99.859334) (xy 436.077255 -99.849204) (xy 436.024471 -99.831197) (xy 435.974871 -99.805696)
			(xy 435.929513 -99.773245) (xy 435.889364 -99.734536) (xy 435.855278 -99.690393) (xy 435.827982 -99.641758)
			(xy 435.808059 -99.589667) (xy 435.795933 -99.53523) (xy 435.791862 -99.479608) (xy 435.666388 -99.479608)
			(xy 435.665879 -99.507494) (xy 435.657759 -99.56267) (xy 435.641691 -99.616077) (xy 435.618019 -99.666574)
			(xy 435.587246 -99.713087) (xy 435.550029 -99.754624) (xy 435.507161 -99.790299) (xy 435.459555 -99.819353)
			(xy 435.408226 -99.841165) (xy 435.354269 -99.855271) (xy 435.298832 -99.861371) (xy 435.243098 -99.859334)
			(xy 435.188255 -99.849204) (xy 435.135471 -99.831197) (xy 435.085871 -99.805696) (xy 435.040513 -99.773245)
			(xy 435.000364 -99.734536) (xy 434.966278 -99.690393) (xy 434.938982 -99.641758) (xy 434.919059 -99.589667)
			(xy 434.906933 -99.53523) (xy 434.902862 -99.479608) (xy 419.601904 -99.479608) (xy 419.601904 -101.446076)
			(xy 420.66972 -102.513638) (xy 420.689828 -102.534566) (xy 420.72393 -102.581524) (xy 420.750281 -102.633232)
			(xy 420.753188 -102.642167) (xy 429.419772 -102.642167) (xy 429.419772 -102.582233) (xy 429.427595 -102.522812)
			(xy 429.443106 -102.46492) (xy 429.46604 -102.409548) (xy 429.496006 -102.357643) (xy 429.53249 -102.310094)
			(xy 429.574868 -102.267712) (xy 429.622415 -102.231225) (xy 429.674318 -102.201256) (xy 429.729688 -102.178317)
			(xy 429.787579 -102.162801) (xy 429.846999 -102.154974) (xy 429.876966 -102.154482) (xy 429.907522 -102.154951)
			(xy 429.968088 -102.163102) (xy 430.027032 -102.179238) (xy 430.083305 -102.203072) (xy 430.135907 -102.234179)
			(xy 430.183904 -102.272007) (xy 430.226442 -102.315885) (xy 430.245012 -102.340156) (xy 430.254259 -102.351731)
			(xy 430.277993 -102.36944) (xy 430.305804 -102.379614) (xy 430.335362 -102.381402) (xy 430.364196 -102.374655)
			(xy 430.389892 -102.359937) (xy 430.40046 -102.349554) (xy 430.418551 -102.331152) (xy 430.458784 -102.298842)
			(xy 430.503008 -102.272255) (xy 430.550414 -102.251875) (xy 430.600137 -102.238077) (xy 430.651265 -102.231112)
			(xy 430.677066 -102.230682) (xy 430.704318 -102.231187) (xy 430.758266 -102.238939) (xy 430.810563 -102.25429)
			(xy 430.860142 -102.276928) (xy 430.905995 -102.306392) (xy 430.947188 -102.342081) (xy 430.982882 -102.38327)
			(xy 431.012351 -102.429119) (xy 431.034994 -102.478696) (xy 431.050352 -102.53099) (xy 431.05811 -102.584938)
			(xy 431.058574 -102.61219) (xy 431.058574 -102.612698) (xy 431.058253 -102.634419) (xy 431.057674 -102.639451)
			(xy 431.370468 -102.639451) (xy 431.370468 -102.584949) (xy 431.378224 -102.531001) (xy 431.393579 -102.478706)
			(xy 431.41622 -102.429128) (xy 431.445685 -102.383277) (xy 431.481376 -102.342086) (xy 431.522566 -102.306394)
			(xy 431.568416 -102.276926) (xy 431.617993 -102.254284) (xy 431.670287 -102.238927) (xy 431.724235 -102.231169)
			(xy 431.751486 -102.230682) (xy 431.780039 -102.231158) (xy 431.836505 -102.239688) (xy 431.891067 -102.256544)
			(xy 431.942505 -102.28135) (xy 431.989668 -102.31355) (xy 432.031501 -102.352423) (xy 432.049682 -102.374446)
			(xy 432.059402 -102.385724) (xy 432.083861 -102.402669) (xy 432.112165 -102.411849) (xy 432.141913 -102.412485)
			(xy 432.170583 -102.404524) (xy 432.195744 -102.38864) (xy 432.205892 -102.377748) (xy 432.227746 -102.353461)
			(xy 432.277145 -102.310704) (xy 432.332122 -102.275405) (xy 432.39156 -102.248283) (xy 432.45425 -102.229889)
			(xy 432.518919 -102.220596) (xy 432.551586 -102.220014) (xy 432.581557 -102.220438) (xy 432.640987 -102.228261)
			(xy 432.698887 -102.243773) (xy 432.754266 -102.266711) (xy 432.806178 -102.296681) (xy 432.853734 -102.33317)
			(xy 432.89612 -102.375555) (xy 432.932611 -102.42311) (xy 432.962583 -102.475021) (xy 432.985522 -102.5304)
			(xy 433.001037 -102.5883) (xy 433.008861 -102.647729) (xy 433.008861 -102.707671) (xy 433.001037 -102.7671)
			(xy 432.985522 -102.825) (xy 432.962583 -102.880379) (xy 432.932611 -102.93229) (xy 432.89612 -102.979845)
			(xy 432.853734 -103.02223) (xy 432.806178 -103.058719) (xy 432.754266 -103.088689) (xy 432.698887 -103.111627)
			(xy 432.640987 -103.127139) (xy 432.581557 -103.134962) (xy 432.551586 -103.13543) (xy 432.522411 -103.13503)
			(xy 432.464533 -103.127612) (xy 432.408068 -103.112898) (xy 432.353931 -103.091126) (xy 432.303 -103.06265)
			(xy 432.256101 -103.027932) (xy 432.213996 -102.987534) (xy 432.177366 -102.942112) (xy 432.161696 -102.917498)
			(xy 432.153402 -102.905139) (xy 432.131149 -102.8854) (xy 432.104159 -102.872896) (xy 432.074713 -102.868683)
			(xy 432.045299 -102.873119) (xy 432.018404 -102.885827) (xy 432.00701 -102.8954) (xy 431.985895 -102.913822)
			(xy 431.939255 -102.944882) (xy 431.888572 -102.968781) (xy 431.834936 -102.985005) (xy 431.779504 -102.993204)
			(xy 431.751486 -102.993698) (xy 431.724235 -102.993231) (xy 431.670287 -102.985473) (xy 431.617993 -102.970116)
			(xy 431.568416 -102.947474) (xy 431.522566 -102.918006) (xy 431.481376 -102.882314) (xy 431.445685 -102.841123)
			(xy 431.41622 -102.795272) (xy 431.393579 -102.745694) (xy 431.378224 -102.693399) (xy 431.370468 -102.639451)
			(xy 431.057674 -102.639451) (xy 431.053287 -102.677577) (xy 431.048668 -102.698804) (xy 431.045917 -102.712756)
			(xy 431.047362 -102.741146) (xy 431.056565 -102.768041) (xy 431.072815 -102.791364) (xy 431.094856 -102.809315)
			(xy 431.120986 -102.820507) (xy 431.135028 -102.822756) (xy 431.16488 -102.82689) (xy 431.22321 -102.842048)
			(xy 431.279045 -102.864734) (xy 431.331418 -102.894554) (xy 431.379422 -102.930992) (xy 431.422227 -102.973418)
			(xy 431.45909 -103.021096) (xy 431.489374 -103.073202) (xy 431.512554 -103.128834) (xy 431.52823 -103.187027)
			(xy 431.536129 -103.246774) (xy 431.536602 -103.276908) (xy 431.536112 -103.306876) (xy 431.528289 -103.366298)
			(xy 431.512776 -103.424191) (xy 431.48984 -103.479564) (xy 431.459873 -103.53147) (xy 431.423386 -103.57902)
			(xy 431.381006 -103.6214) (xy 431.333456 -103.657887) (xy 431.28155 -103.687854) (xy 431.226177 -103.71079)
			(xy 431.168284 -103.726303) (xy 431.108862 -103.734126) (xy 431.048926 -103.734126) (xy 430.989504 -103.726303)
			(xy 430.931611 -103.71079) (xy 430.876238 -103.687854) (xy 430.824332 -103.657887) (xy 430.776782 -103.6214)
			(xy 430.734402 -103.57902) (xy 430.697915 -103.53147) (xy 430.667948 -103.479564) (xy 430.645012 -103.424191)
			(xy 430.629499 -103.366298) (xy 430.621676 -103.306876) (xy 430.621186 -103.276908) (xy 430.621618 -103.249425)
			(xy 430.628233 -103.194859) (xy 430.641332 -103.141476) (xy 430.65065 -103.115618) (xy 430.655256 -103.102146)
			(xy 430.657555 -103.073779) (xy 430.65193 -103.04588) (xy 430.638817 -103.02062) (xy 430.619238 -102.999964)
			(xy 430.594715 -102.98552) (xy 430.581054 -102.981506) (xy 430.555457 -102.97436) (xy 430.506387 -102.953951)
			(xy 430.46063 -102.926922) (xy 430.419071 -102.893798) (xy 430.40046 -102.874826) (xy 430.389959 -102.864344)
			(xy 430.364259 -102.849532) (xy 430.335385 -102.842738) (xy 430.305778 -102.844535) (xy 430.277938 -102.854773)
			(xy 430.25422 -102.872586) (xy 430.245012 -102.884224) (xy 430.226434 -102.908489) (xy 430.183905 -102.952374)
			(xy 430.135913 -102.990206) (xy 430.083311 -103.021312) (xy 430.027036 -103.045138) (xy 429.968089 -103.061261)
			(xy 429.907522 -103.069392) (xy 429.876966 -103.069898) (xy 429.846999 -103.069426) (xy 429.787579 -103.061599)
			(xy 429.729688 -103.046083) (xy 429.674318 -103.023144) (xy 429.622415 -102.993175) (xy 429.574868 -102.956688)
			(xy 429.53249 -102.914306) (xy 429.496006 -102.866757) (xy 429.46604 -102.814852) (xy 429.443106 -102.75948)
			(xy 429.427595 -102.701588) (xy 429.419772 -102.642167) (xy 420.753188 -102.642167) (xy 420.768236 -102.688419)
			(xy 420.777352 -102.745733) (xy 420.777924 -102.77475) (xy 420.777924 -105.85729) (xy 429.831482 -105.85729)
			(xy 429.831482 -105.797354) (xy 429.839305 -105.737932) (xy 429.854818 -105.680039) (xy 429.877754 -105.624666)
			(xy 429.907721 -105.57276) (xy 429.944208 -105.52521) (xy 429.986588 -105.48283) (xy 430.034138 -105.446343)
			(xy 430.086044 -105.416376) (xy 430.141417 -105.39344) (xy 430.19931 -105.377927) (xy 430.258732 -105.370104)
			(xy 430.318668 -105.370104) (xy 430.37809 -105.377927) (xy 430.435983 -105.39344) (xy 430.491356 -105.416376)
			(xy 430.543262 -105.446343) (xy 430.590812 -105.48283) (xy 430.633192 -105.52521) (xy 430.669679 -105.57276)
			(xy 430.699646 -105.624666) (xy 430.70142 -105.628948) (xy 433.069492 -105.628948) (xy 433.069988 -105.601579)
			(xy 433.077799 -105.547401) (xy 433.093281 -105.494898) (xy 433.116116 -105.445151) (xy 433.145834 -105.399183)
			(xy 433.163472 -105.37825) (xy 433.172664 -105.366889) (xy 433.184851 -105.340344) (xy 433.189034 -105.311436)
			(xy 433.184871 -105.282526) (xy 433.172704 -105.255972) (xy 433.163472 -105.244646) (xy 433.145837 -105.223711)
			(xy 433.116125 -105.177739) (xy 433.093289 -105.127992) (xy 433.077797 -105.075492) (xy 433.069967 -105.021317)
			(xy 433.069492 -104.993948) (xy 433.070012 -104.966037) (xy 433.078141 -104.910809) (xy 433.094231 -104.857355)
			(xy 433.117941 -104.806818) (xy 433.148762 -104.760275) (xy 433.186038 -104.718721) (xy 433.228972 -104.683044)
			(xy 433.276647 -104.654004) (xy 433.302156 -104.642666) (xy 433.314299 -104.637018) (xy 433.335399 -104.620549)
			(xy 433.351501 -104.599166) (xy 433.361499 -104.574337) (xy 433.364708 -104.547763) (xy 433.360909 -104.521267)
			(xy 433.356004 -104.508808) (xy 433.344149 -104.480056) (xy 433.327414 -104.420159) (xy 433.318952 -104.358547)
			(xy 433.318412 -104.327452) (xy 433.318902 -104.297484) (xy 433.326725 -104.238062) (xy 433.342238 -104.180169)
			(xy 433.365174 -104.124796) (xy 433.395141 -104.07289) (xy 433.431628 -104.02534) (xy 433.474008 -103.98296)
			(xy 433.521558 -103.946473) (xy 433.573464 -103.916506) (xy 433.628837 -103.89357) (xy 433.68673 -103.878057)
			(xy 433.746152 -103.870234) (xy 433.806088 -103.870234) (xy 433.86551 -103.878057) (xy 433.923403 -103.89357)
			(xy 433.978776 -103.916506) (xy 434.030682 -103.946473) (xy 434.078232 -103.98296) (xy 434.120612 -104.02534)
			(xy 434.157099 -104.07289) (xy 434.187066 -104.124796) (xy 434.210002 -104.180169) (xy 434.225515 -104.238062)
			(xy 434.233338 -104.297484) (xy 434.233828 -104.327452) (xy 434.233828 -104.32796) (xy 434.233254 -104.359795)
			(xy 434.224386 -104.422845) (xy 434.20687 -104.484059) (xy 434.194458 -104.51338) (xy 434.18942 -104.525602)
			(xy 434.185226 -104.551697) (xy 434.187877 -104.577994) (xy 434.197194 -104.602727) (xy 434.212552 -104.624237)
			(xy 434.23292 -104.641079) (xy 434.24475 -104.646984) (xy 434.269318 -104.658747) (xy 434.315114 -104.688241)
			(xy 434.356251 -104.723945) (xy 434.391895 -104.765135) (xy 434.421321 -104.810973) (xy 434.443933 -104.860529)
			(xy 434.459269 -104.912796) (xy 434.46702 -104.966713) (xy 434.467508 -104.993948) (xy 434.467009 -105.021317)
			(xy 434.459199 -105.075495) (xy 434.443718 -105.127997) (xy 434.420883 -105.177745) (xy 434.391166 -105.223713)
			(xy 434.373528 -105.244646) (xy 434.364243 -105.255938) (xy 434.352068 -105.282508) (xy 434.347903 -105.311436)
			(xy 434.352088 -105.340362) (xy 434.364282 -105.366923) (xy 434.373528 -105.37825) (xy 434.391161 -105.399187)
			(xy 434.420873 -105.445159) (xy 434.44371 -105.494905) (xy 434.459202 -105.547404) (xy 434.467033 -105.601579)
			(xy 434.467508 -105.628948) (xy 434.467067 -105.6562) (xy 434.459304 -105.71015) (xy 434.443943 -105.762445)
			(xy 434.421296 -105.812023) (xy 434.391825 -105.857873) (xy 434.356129 -105.899063) (xy 434.314934 -105.934753)
			(xy 434.269081 -105.964219) (xy 434.2195 -105.986859) (xy 434.167203 -106.002214) (xy 434.113252 -106.00997)
			(xy 434.086 -106.010456) (xy 434.058629 -106.010001) (xy 434.004449 -106.002182) (xy 433.951946 -105.986691)
			(xy 433.902199 -105.963847) (xy 433.856233 -105.934119) (xy 433.835302 -105.916476) (xy 433.823974 -105.90724)
			(xy 433.797417 -105.895064) (xy 433.7685 -105.890891) (xy 433.739583 -105.895064) (xy 433.713026 -105.90724)
			(xy 433.701698 -105.916476) (xy 433.680774 -105.934126) (xy 433.6348 -105.963837) (xy 433.58505 -105.986671)
			(xy 433.532547 -106.00216) (xy 433.47837 -106.009984) (xy 433.451 -106.010456) (xy 433.423751 -106.009922)
			(xy 433.369807 -106.002167) (xy 433.317516 -105.986814) (xy 433.267942 -105.964177) (xy 433.222094 -105.934715)
			(xy 433.180905 -105.899029) (xy 433.145214 -105.857844) (xy 433.115746 -105.812) (xy 433.093102 -105.762429)
			(xy 433.077743 -105.71014) (xy 433.069981 -105.656197) (xy 433.069492 -105.628948) (xy 430.70142 -105.628948)
			(xy 430.722582 -105.680039) (xy 430.738095 -105.737932) (xy 430.745918 -105.797354) (xy 430.746408 -105.827322)
			(xy 430.745918 -105.85729) (xy 430.738095 -105.916712) (xy 430.722582 -105.974605) (xy 430.699646 -106.029978)
			(xy 430.669679 -106.081884) (xy 430.633192 -106.129434) (xy 430.590812 -106.171814) (xy 430.543262 -106.208301)
			(xy 430.491356 -106.238268) (xy 430.435983 -106.261204) (xy 430.37809 -106.276717) (xy 430.318668 -106.28454)
			(xy 430.258732 -106.28454) (xy 430.19931 -106.276717) (xy 430.141417 -106.261204) (xy 430.086044 -106.238268)
			(xy 430.034138 -106.208301) (xy 429.986588 -106.171814) (xy 429.944208 -106.129434) (xy 429.907721 -106.081884)
			(xy 429.877754 -106.029978) (xy 429.854818 -105.974605) (xy 429.839305 -105.916712) (xy 429.831482 -105.85729)
			(xy 420.777924 -105.85729) (xy 420.777924 -110.017306) (xy 420.777341 -110.046324) (xy 420.768241 -110.103642)
			(xy 420.750296 -110.158835) (xy 420.723949 -110.210546) (xy 420.689845 -110.257505) (xy 420.66972 -110.278418)
			(xy 420.596314 -110.35157) (xy 420.59352 -110.367064) (xy 420.587047 -110.398033) (xy 420.566704 -110.457941)
			(xy 420.538304 -110.514477) (xy 420.502388 -110.566562) (xy 420.45964 -110.613203) (xy 420.410875 -110.653512)
			(xy 420.357022 -110.68672) (xy 420.29911 -110.712194) (xy 420.23824 -110.729449) (xy 420.175574 -110.738155)
			(xy 420.14394 -110.738666) (xy 420.11397 -110.738199) (xy 420.054543 -110.73038) (xy 419.996645 -110.71487)
			(xy 419.941267 -110.691934) (xy 419.889358 -110.661966) (xy 419.841804 -110.625478) (xy 419.799421 -110.583094)
			(xy 419.762933 -110.535541) (xy 419.732965 -110.483631) (xy 419.710029 -110.428253) (xy 419.69452 -110.370355)
			(xy 419.6867 -110.310928) (xy 419.686232 -110.280958) (xy 419.686669 -110.252168) (xy 419.693897 -110.195043)
			(xy 419.708233 -110.139275) (xy 419.729452 -110.085747) (xy 419.757217 -110.035302) (xy 419.79109 -109.988739)
			(xy 419.830536 -109.946793) (xy 419.874933 -109.910125) (xy 419.923578 -109.879317) (xy 419.975703 -109.854853)
			(xy 420.00297 -109.845602) (xy 420.038276 -109.834172) (xy 420.038276 -102.92842) (xy 418.97046 -101.860858)
			(xy 418.950353 -101.839929) (xy 418.916253 -101.79297) (xy 418.889904 -101.741263) (xy 418.871952 -101.686076)
			(xy 418.862836 -101.628762) (xy 418.862256 -101.599746) (xy 418.862256 -97.189544) (xy 418.862843 -97.160527)
			(xy 418.87195 -97.103213) (xy 418.889899 -97.048024) (xy 418.91625 -96.996318) (xy 418.950355 -96.949363)
			(xy 418.97046 -96.928432) (xy 419.977062 -95.92183) (xy 419.9873 -95.910865) (xy 420.001465 -95.884438)
			(xy 420.00735 -95.855038) (xy 420.004448 -95.825195) (xy 419.993008 -95.797479) (xy 419.974016 -95.774277)
			(xy 419.949107 -95.757587) (xy 419.920425 -95.748846) (xy 419.905434 -95.748348) (xy 418.10686 -95.748348)
			(xy 414.53308 -99.322128) (xy 414.53308 -104.501188) (xy 418.035232 -104.501188) (xy 418.035683 -104.473817)
			(xy 418.043503 -104.419637) (xy 418.058996 -104.367134) (xy 418.081841 -104.317387) (xy 418.111569 -104.271421)
			(xy 418.129212 -104.25049) (xy 418.138459 -104.239171) (xy 418.150634 -104.21261) (xy 418.154804 -104.183691)
			(xy 418.150629 -104.154773) (xy 418.13845 -104.128214) (xy 418.129212 -104.116886) (xy 418.111602 -104.095931)
			(xy 418.081885 -104.049965) (xy 418.059043 -104.000223) (xy 418.043546 -103.947727) (xy 418.03571 -103.893556)
			(xy 418.035232 -103.866188) (xy 418.035644 -103.838933) (xy 418.043403 -103.784978) (xy 418.058763 -103.732677)
			(xy 418.08141 -103.683094) (xy 418.110883 -103.637239) (xy 418.146582 -103.596045) (xy 418.187781 -103.560352)
			(xy 418.23364 -103.530885) (xy 418.283226 -103.508245) (xy 418.335529 -103.492892) (xy 418.389485 -103.48514)
			(xy 418.41674 -103.48468) (xy 418.442319 -103.485084) (xy 418.493018 -103.491932) (xy 418.542348 -103.505486)
			(xy 418.589428 -103.525504) (xy 418.633414 -103.551628) (xy 418.673519 -103.583389) (xy 418.691568 -103.60152)
			(xy 418.701199 -103.61092) (xy 418.724293 -103.624724) (xy 418.750189 -103.632019) (xy 418.777092 -103.6323)
			(xy 418.803136 -103.625548) (xy 418.826513 -103.612231) (xy 418.836348 -103.603044) (xy 418.857913 -103.582417)
			(xy 418.906289 -103.547481) (xy 418.959517 -103.520507) (xy 419.016298 -103.502155) (xy 419.075244 -103.492872)
			(xy 419.10508 -103.4923) (xy 419.132333 -103.492774) (xy 419.186284 -103.500528) (xy 419.238582 -103.515882)
			(xy 419.288162 -103.538523) (xy 419.334016 -103.56799) (xy 419.375209 -103.603682) (xy 419.410903 -103.644874)
			(xy 419.440371 -103.690727) (xy 419.463013 -103.740307) (xy 419.478369 -103.792605) (xy 419.486125 -103.846555)
			(xy 419.486588 -103.873808) (xy 419.48613 -103.901179) (xy 419.47831 -103.955358) (xy 419.46282 -104.007861)
			(xy 419.439976 -104.057608) (xy 419.41025 -104.103575) (xy 419.392608 -104.124506) (xy 419.383363 -104.135827)
			(xy 419.371185 -104.162387) (xy 419.367014 -104.191306) (xy 419.371189 -104.220225) (xy 419.383369 -104.246783)
			(xy 419.392608 -104.25811) (xy 419.410266 -104.279026) (xy 419.439975 -104.325004) (xy 419.462807 -104.374755)
			(xy 419.478294 -104.427259) (xy 419.486117 -104.481438) (xy 419.486588 -104.508808) (xy 419.486152 -104.536062)
			(xy 419.478393 -104.590015) (xy 419.463035 -104.642314) (xy 419.440391 -104.691896) (xy 419.41092 -104.73775)
			(xy 419.375223 -104.778943) (xy 419.334028 -104.814637) (xy 419.288171 -104.844104) (xy 419.238588 -104.866745)
			(xy 419.186287 -104.882099) (xy 419.132334 -104.889854) (xy 419.10508 -104.890316) (xy 419.079501 -104.8899)
			(xy 419.028803 -104.883055) (xy 418.979473 -104.869503) (xy 418.932393 -104.849487) (xy 418.888407 -104.823365)
			(xy 418.848301 -104.791606) (xy 418.830252 -104.773476) (xy 418.820603 -104.764096) (xy 418.797514 -104.750292)
			(xy 418.771623 -104.742994) (xy 418.744724 -104.742709) (xy 418.718683 -104.749456) (xy 418.695307 -104.762768)
			(xy 418.685472 -104.771952) (xy 418.663898 -104.792569) (xy 418.615524 -104.827506) (xy 418.562298 -104.854482)
			(xy 418.50552 -104.872837) (xy 418.446576 -104.882123) (xy 418.41674 -104.882696) (xy 418.389488 -104.882207)
			(xy 418.335537 -104.874456) (xy 418.283239 -104.859104) (xy 418.233658 -104.836465) (xy 418.187804 -104.807)
			(xy 418.146611 -104.771309) (xy 418.110916 -104.730118) (xy 418.081448 -104.684267) (xy 418.058806 -104.634687)
			(xy 418.04345 -104.58239) (xy 418.035695 -104.52844) (xy 418.035232 -104.501188) (xy 414.53308 -104.501188)
			(xy 414.53308 -110.739417) (xy 415.365214 -110.739417) (xy 415.368942 -110.686169) (xy 415.380055 -110.63396)
			(xy 415.398338 -110.58381) (xy 415.423433 -110.536698) (xy 415.454851 -110.493544) (xy 415.491977 -110.455192)
			(xy 415.512758 -110.438438) (xy 415.524538 -110.428512) (xy 415.542061 -110.403197) (xy 415.551243 -110.373811)
			(xy 415.551248 -110.343023) (xy 415.542076 -110.313634) (xy 415.524562 -110.288314) (xy 415.512758 -110.278418)
			(xy 415.492003 -110.261631) (xy 415.454873 -110.223282) (xy 415.423452 -110.180131) (xy 415.398352 -110.133022)
			(xy 415.380065 -110.082873) (xy 415.368946 -110.030665) (xy 415.365214 -109.977417) (xy 415.368942 -109.924169)
			(xy 415.380055 -109.87196) (xy 415.398338 -109.82181) (xy 415.423433 -109.774698) (xy 415.454851 -109.731544)
			(xy 415.491977 -109.693192) (xy 415.512758 -109.676438) (xy 415.524538 -109.666512) (xy 415.542061 -109.641197)
			(xy 415.551243 -109.611811) (xy 415.551248 -109.581023) (xy 415.542076 -109.551634) (xy 415.524562 -109.526314)
			(xy 415.512758 -109.516418) (xy 415.492003 -109.499631) (xy 415.454873 -109.461282) (xy 415.423452 -109.418131)
			(xy 415.398352 -109.371022) (xy 415.380065 -109.320873) (xy 415.368946 -109.268665) (xy 415.365214 -109.215417)
			(xy 415.368942 -109.162169) (xy 415.380055 -109.10996) (xy 415.398338 -109.05981) (xy 415.423433 -109.012698)
			(xy 415.454851 -108.969544) (xy 415.491977 -108.931192) (xy 415.512758 -108.914438) (xy 415.524538 -108.904512)
			(xy 415.542061 -108.879197) (xy 415.551243 -108.849811) (xy 415.551248 -108.819023) (xy 415.542076 -108.789634)
			(xy 415.524562 -108.764314) (xy 415.512758 -108.754418) (xy 415.490274 -108.736227) (xy 415.450541 -108.694206)
			(xy 415.417603 -108.646671) (xy 415.392215 -108.59471) (xy 415.374959 -108.539513) (xy 415.366228 -108.482344)
			(xy 415.365692 -108.453428) (xy 415.366181 -108.426176) (xy 415.373935 -108.372226) (xy 415.389287 -108.319928)
			(xy 415.411926 -108.270348) (xy 415.441391 -108.224495) (xy 415.477082 -108.183302) (xy 415.518273 -108.147608)
			(xy 415.564124 -108.11814) (xy 415.613702 -108.095497) (xy 415.665998 -108.08014) (xy 415.719948 -108.072383)
			(xy 415.7472 -108.07192) (xy 415.776117 -108.072431) (xy 415.833289 -108.08116) (xy 415.888488 -108.098419)
			(xy 415.94045 -108.123812) (xy 415.987984 -108.156758) (xy 416.03 -108.1965) (xy 416.04819 -108.218986)
			(xy 416.058087 -108.230791) (xy 416.083411 -108.24831) (xy 416.112804 -108.257486) (xy 416.143596 -108.257486)
			(xy 416.172989 -108.24831) (xy 416.198313 -108.230791) (xy 416.20821 -108.218986) (xy 416.226392 -108.196495)
			(xy 416.268414 -108.156761) (xy 416.315951 -108.123823) (xy 416.367914 -108.098436) (xy 416.423113 -108.081181)
			(xy 416.480284 -108.072454) (xy 416.5092 -108.07192) (xy 416.536454 -108.072355) (xy 416.590408 -108.080113)
			(xy 416.642708 -108.095471) (xy 416.69229 -108.118115) (xy 416.738144 -108.147586) (xy 416.779337 -108.183282)
			(xy 416.815031 -108.224478) (xy 416.844498 -108.270335) (xy 416.867139 -108.319919) (xy 416.882493 -108.37222)
			(xy 416.890247 -108.426174) (xy 416.890708 -108.453428) (xy 416.890173 -108.482345) (xy 416.881452 -108.539517)
			(xy 416.8642 -108.594717) (xy 416.838812 -108.646679) (xy 416.805869 -108.694213) (xy 416.766128 -108.736229)
			(xy 416.743642 -108.754418) (xy 416.731806 -108.764283) (xy 416.714284 -108.789614) (xy 416.705109 -108.819017)
			(xy 416.705114 -108.849818) (xy 416.714299 -108.879217) (xy 416.73183 -108.904542) (xy 416.743642 -108.914438)
			(xy 416.764453 -108.931158) (xy 416.801583 -108.969516) (xy 416.833005 -109.012674) (xy 416.858103 -109.059791)
			(xy 416.876388 -109.109947) (xy 416.887503 -109.162163) (xy 416.89123 -109.215417) (xy 416.887498 -109.268672)
			(xy 416.876378 -109.320886) (xy 416.858089 -109.37104) (xy 416.832986 -109.418155) (xy 416.801561 -109.461311)
			(xy 416.764427 -109.499665) (xy 416.743642 -109.516418) (xy 416.731806 -109.526283) (xy 416.714284 -109.551614)
			(xy 416.705109 -109.581017) (xy 416.705114 -109.611818) (xy 416.714299 -109.641217) (xy 416.73183 -109.666542)
			(xy 416.743642 -109.676438) (xy 416.764453 -109.693158) (xy 416.801583 -109.731516) (xy 416.833005 -109.774674)
			(xy 416.858103 -109.821791) (xy 416.876388 -109.871947) (xy 416.887503 -109.924163) (xy 416.89123 -109.977417)
			(xy 416.887498 -110.030672) (xy 416.876378 -110.082886) (xy 416.858089 -110.13304) (xy 416.832986 -110.180155)
			(xy 416.801561 -110.223311) (xy 416.764427 -110.261665) (xy 416.743642 -110.278418) (xy 416.731806 -110.288283)
			(xy 416.714284 -110.313614) (xy 416.705109 -110.343017) (xy 416.705114 -110.373818) (xy 416.714299 -110.403217)
			(xy 416.73183 -110.428542) (xy 416.743642 -110.438438) (xy 416.764453 -110.455158) (xy 416.801583 -110.493516)
			(xy 416.833005 -110.536674) (xy 416.858103 -110.583791) (xy 416.876388 -110.633947) (xy 416.887503 -110.686163)
			(xy 416.89123 -110.739417) (xy 416.887498 -110.792672) (xy 416.876378 -110.844886) (xy 416.858089 -110.89504)
			(xy 416.832986 -110.942155) (xy 416.801561 -110.985311) (xy 416.764427 -111.023665) (xy 416.743642 -111.040418)
			(xy 416.731806 -111.050283) (xy 416.714284 -111.075614) (xy 416.705109 -111.105017) (xy 416.705114 -111.135818)
			(xy 416.714299 -111.165217) (xy 416.73183 -111.190542) (xy 416.743642 -111.200438) (xy 416.766152 -111.218597)
			(xy 416.805884 -111.260625) (xy 416.838819 -111.308167) (xy 416.864202 -111.360134) (xy 416.881453 -111.415337)
			(xy 416.890176 -111.47251) (xy 416.890708 -111.501428) (xy 416.890248 -111.52868) (xy 416.882488 -111.582629)
			(xy 416.867129 -111.634924) (xy 416.844485 -111.684501) (xy 416.815016 -111.730351) (xy 416.779321 -111.771541)
			(xy 416.738129 -111.807232) (xy 416.692277 -111.836698) (xy 416.642698 -111.859339) (xy 416.590401 -111.874694)
			(xy 416.536452 -111.88245) (xy 416.5092 -111.882936) (xy 416.480282 -111.882442) (xy 416.423108 -111.873711)
			(xy 416.367908 -111.85645) (xy 416.315946 -111.831054) (xy 416.268413 -111.798105) (xy 416.226398 -111.758358)
			(xy 416.20821 -111.73587) (xy 416.198313 -111.724065) (xy 416.172989 -111.706546) (xy 416.143596 -111.69737)
			(xy 416.112804 -111.69737) (xy 416.083411 -111.706546) (xy 416.058087 -111.724065) (xy 416.04819 -111.73587)
			(xy 416.029997 -111.758352) (xy 415.987979 -111.798089) (xy 415.940444 -111.831029) (xy 415.888483 -111.856418)
			(xy 415.833286 -111.873674) (xy 415.776116 -111.882402) (xy 415.7472 -111.882936) (xy 415.71995 -111.882422)
			(xy 415.666005 -111.874667) (xy 415.613712 -111.859313) (xy 415.564137 -111.836674) (xy 415.518288 -111.80721)
			(xy 415.477098 -111.771522) (xy 415.441407 -111.730335) (xy 415.41194 -111.684488) (xy 415.389297 -111.634914)
			(xy 415.373939 -111.582623) (xy 415.36618 -111.528678) (xy 415.365692 -111.501428) (xy 415.366195 -111.47251)
			(xy 415.374923 -111.415337) (xy 415.392181 -111.360136) (xy 415.417575 -111.308173) (xy 415.450523 -111.26064)
			(xy 415.49027 -111.218626) (xy 415.512758 -111.200438) (xy 415.524538 -111.190512) (xy 415.542061 -111.165197)
			(xy 415.551243 -111.135811) (xy 415.551248 -111.105023) (xy 415.542076 -111.075634) (xy 415.524562 -111.050314)
			(xy 415.512758 -111.040418) (xy 415.492003 -111.023631) (xy 415.454873 -110.985282) (xy 415.423452 -110.942131)
			(xy 415.398352 -110.895022) (xy 415.380065 -110.844873) (xy 415.368946 -110.792665) (xy 415.365214 -110.739417)
			(xy 414.53308 -110.739417) (xy 414.53308 -111.351568) (xy 415.39414 -112.212628) (xy 433.88534 -112.212628)
		)
		(stroke
			(width 0)
			(type solid)
		)
		(fill yes)
		(layer "B.Cu")
		(net "GND")
	)
	(gr_poly
		(pts
			(xy 445.949578 -333.81569) (xy 447.039238 -333.81569) (xy 447.628518 -334.40497) (xy 456.068938 -334.40497)
			(xy 462.319116 -328.154792) (xy 462.32941 -328.143735) (xy 462.343603 -328.117086) (xy 462.349389 -328.087452)
			(xy 462.346264 -328.057421) (xy 462.334499 -328.029614) (xy 462.315121 -328.006459) (xy 462.289823 -327.989977)
			(xy 462.260813 -327.981606) (xy 462.24571 -327.98131) (xy 462.232248 -327.981564) (xy 460.987648 -327.981564)
			(xy 460.945372 -327.981093) (xy 460.86118 -327.973296) (xy 460.778066 -327.957763) (xy 460.69674 -327.934628)
			(xy 460.617896 -327.904087) (xy 460.542206 -327.866401) (xy 460.470317 -327.821893) (xy 460.402841 -327.77094)
			(xy 460.340354 -327.71398) (xy 460.28339 -327.651496) (xy 460.232435 -327.584023) (xy 460.187922 -327.512136)
			(xy 460.150233 -327.436448) (xy 460.119688 -327.357605) (xy 460.096548 -327.276281) (xy 460.081011 -327.193168)
			(xy 460.073209 -327.108976) (xy 460.073209 -327.024424) (xy 460.081011 -326.940232) (xy 460.096548 -326.857119)
			(xy 460.119688 -326.775795) (xy 460.150233 -326.696952) (xy 460.187922 -326.621265) (xy 460.232434 -326.549377)
			(xy 460.28339 -326.481904) (xy 460.340354 -326.41942) (xy 460.402841 -326.36246) (xy 460.470317 -326.311507)
			(xy 460.542206 -326.266999) (xy 460.617896 -326.229313) (xy 460.69674 -326.198772) (xy 460.778066 -326.175637)
			(xy 460.86118 -326.160104) (xy 460.945372 -326.152307) (xy 460.987648 -326.151748) (xy 462.232248 -326.151748)
			(xy 462.276612 -326.152288) (xy 462.364922 -326.160909) (xy 462.451982 -326.178037) (xy 462.536976 -326.20351)
			(xy 462.619106 -326.23709) (xy 462.6976 -326.27846) (xy 462.771722 -326.327234) (xy 462.840775 -326.382952)
			(xy 462.872836 -326.413622) (xy 462.883869 -326.423688) (xy 462.910329 -326.437509) (xy 462.939654 -326.443093)
			(xy 462.969341 -326.439963) (xy 462.996857 -326.428387) (xy 463.019854 -326.409353) (xy 463.036367 -326.384484)
			(xy 463.044989 -326.355904) (xy 463.045556 -326.340978) (xy 463.045556 -320.432176) (xy 462.715356 -320.101976)
			(xy 458.677264 -320.101976) (xy 458.652021 -320.116008) (xy 458.598676 -320.138143) (xy 458.542911 -320.153172)
			(xy 458.485668 -320.160842) (xy 458.456792 -320.161412) (xy 458.443155 -320.16189) (xy 458.416872 -320.169187)
			(xy 458.393456 -320.183178) (xy 458.374578 -320.202867) (xy 458.361581 -320.226849) (xy 458.355394 -320.253415)
			(xy 458.356456 -320.280671) (xy 458.364692 -320.306675) (xy 458.371702 -320.318384) (xy 458.38907 -320.346265)
			(xy 458.416503 -320.405949) (xy 458.435117 -320.468944) (xy 458.444528 -320.533953) (xy 458.445108 -320.566796)
			(xy 458.444618 -320.596764) (xy 458.436795 -320.656186) (xy 458.421282 -320.714079) (xy 458.398346 -320.769452)
			(xy 458.368379 -320.821358) (xy 458.331892 -320.868908) (xy 458.289512 -320.911288) (xy 458.241962 -320.947775)
			(xy 458.190056 -320.977742) (xy 458.134683 -321.000678) (xy 458.07679 -321.016191) (xy 458.017368 -321.024014)
			(xy 457.957432 -321.024014) (xy 457.89801 -321.016191) (xy 457.840117 -321.000678) (xy 457.784744 -320.977742)
			(xy 457.732838 -320.947775) (xy 457.685288 -320.911288) (xy 457.642908 -320.868908) (xy 457.606421 -320.821358)
			(xy 457.576454 -320.769452) (xy 457.553518 -320.714079) (xy 457.538005 -320.656186) (xy 457.530182 -320.596764)
			(xy 457.529692 -320.566796) (xy 457.530271 -320.534435) (xy 457.539422 -320.470361) (xy 457.557498 -320.408213)
			(xy 457.584139 -320.349227) (xy 457.618817 -320.294577) (xy 457.63942 -320.269616) (xy 457.648448 -320.25827)
			(xy 457.660333 -320.231839) (xy 457.664314 -320.203134) (xy 457.660071 -320.174466) (xy 457.647945 -320.148144)
			(xy 457.628912 -320.126289) (xy 457.604507 -320.110661) (xy 457.576694 -320.102519) (xy 457.562204 -320.101976)
			(xy 455.184764 -320.101976) (xy 454.562464 -320.724022) (xy 454.562464 -320.859912) (xy 454.576434 -320.874644)
			(xy 454.59591 -320.895924) (xy 454.629908 -320.942527) (xy 454.657776 -320.993036) (xy 454.67907 -321.046649)
			(xy 454.693454 -321.102514) (xy 454.700697 -321.159744) (xy 454.701148 -321.188588) (xy 454.700658 -321.218556)
			(xy 454.692835 -321.277978) (xy 454.677322 -321.335871) (xy 454.654386 -321.391244) (xy 454.624419 -321.44315)
			(xy 454.587932 -321.4907) (xy 454.545552 -321.53308) (xy 454.498002 -321.569567) (xy 454.446096 -321.599534)
			(xy 454.390723 -321.62247) (xy 454.33283 -321.637983) (xy 454.273408 -321.645806) (xy 454.213472 -321.645806)
			(xy 454.15405 -321.637983) (xy 454.096157 -321.62247) (xy 454.040784 -321.599534) (xy 453.988878 -321.569567)
			(xy 453.941328 -321.53308) (xy 453.898948 -321.4907) (xy 453.862461 -321.44315) (xy 453.832494 -321.391244)
			(xy 453.809558 -321.335871) (xy 453.794045 -321.277978) (xy 453.786222 -321.218556) (xy 453.785732 -321.188588)
			(xy 453.786238 -321.158082) (xy 453.794348 -321.097611) (xy 453.810422 -321.038755) (xy 453.834175 -320.982556)
			(xy 453.865186 -320.930013) (xy 453.902905 -320.882057) (xy 453.924416 -320.86042) (xy 453.924416 -320.591942)
			(xy 453.924887 -320.566873) (xy 453.932739 -320.517354) (xy 453.948242 -320.469673) (xy 453.971013 -320.425004)
			(xy 454.000492 -320.384447) (xy 454.017888 -320.36639) (xy 454.060052 -320.323972) (xy 454.017888 -320.281808)
			(xy 454.010014 -320.278252) (xy 453.98029 -320.263338) (xy 453.925119 -320.226211) (xy 453.875899 -320.181494)
			(xy 453.833665 -320.130126) (xy 453.815958 -320.101976) (xy 451.133464 -320.101976) (xy 451.108078 -320.116078)
			(xy 451.054425 -320.138296) (xy 450.998332 -320.153328) (xy 450.940758 -320.160916) (xy 450.911722 -320.161412)
			(xy 450.910706 -320.161412) (xy 450.897056 -320.161863) (xy 450.870736 -320.169117) (xy 450.847278 -320.183082)
			(xy 450.828355 -320.202762) (xy 450.815319 -320.226749) (xy 450.809102 -320.253333) (xy 450.810146 -320.280614)
			(xy 450.818378 -320.306644) (xy 450.825362 -320.318384) (xy 450.842731 -320.346265) (xy 450.870167 -320.405948)
			(xy 450.888783 -320.468943) (xy 450.898194 -320.533952) (xy 450.898768 -320.566796) (xy 450.898278 -320.596764)
			(xy 450.890455 -320.656186) (xy 450.874942 -320.714079) (xy 450.852006 -320.769452) (xy 450.822039 -320.821358)
			(xy 450.785552 -320.868908) (xy 450.743172 -320.911288) (xy 450.695622 -320.947775) (xy 450.643716 -320.977742)
			(xy 450.588343 -321.000678) (xy 450.53045 -321.016191) (xy 450.471028 -321.024014) (xy 450.411092 -321.024014)
			(xy 450.35167 -321.016191) (xy 450.293777 -321.000678) (xy 450.238404 -320.977742) (xy 450.186498 -320.947775)
			(xy 450.138948 -320.911288) (xy 450.096568 -320.868908) (xy 450.060081 -320.821358) (xy 450.030114 -320.769452)
			(xy 450.007178 -320.714079) (xy 449.991665 -320.656186) (xy 449.983842 -320.596764) (xy 449.983352 -320.566796)
			(xy 449.983931 -320.534434) (xy 449.993081 -320.47036) (xy 450.011155 -320.408211) (xy 450.037795 -320.349224)
			(xy 450.07247 -320.294572) (xy 450.09308 -320.269616) (xy 450.10211 -320.258272) (xy 450.113999 -320.231844)
			(xy 450.117983 -320.203139) (xy 450.11374 -320.174472) (xy 450.101613 -320.148152) (xy 450.082577 -320.1263)
			(xy 450.058169 -320.110678) (xy 450.030354 -320.102544) (xy 450.015864 -320.101976) (xy 446.877694 -320.101976)
			(xy 446.855002 -320.120787) (xy 446.805665 -320.153041) (xy 446.752598 -320.178697) (xy 446.696677 -320.197332)
			(xy 446.638828 -320.208637) (xy 446.580006 -320.212427) (xy 446.521184 -320.208637) (xy 446.463335 -320.197332)
			(xy 446.407414 -320.178697) (xy 446.354347 -320.153041) (xy 446.30501 -320.120787) (xy 446.282318 -320.101976)
			(xy 443.589664 -320.101976) (xy 443.564649 -320.115899) (xy 443.511799 -320.137906) (xy 443.456559 -320.152939)
			(xy 443.399844 -320.160747) (xy 443.371224 -320.161412) (xy 443.357627 -320.161961) (xy 443.33145 -320.169365)
			(xy 443.308156 -320.183414) (xy 443.289395 -320.203113) (xy 443.276496 -320.227064) (xy 443.270376 -320.253569)
			(xy 443.271466 -320.280751) (xy 443.279691 -320.306681) (xy 443.286642 -320.318384) (xy 443.304012 -320.346265)
			(xy 443.331449 -320.405948) (xy 443.350065 -320.468942) (xy 443.359478 -320.533952) (xy 443.360048 -320.566796)
			(xy 443.359558 -320.596764) (xy 443.351735 -320.656186) (xy 443.336222 -320.714079) (xy 443.313286 -320.769452)
			(xy 443.283319 -320.821358) (xy 443.246832 -320.868908) (xy 443.204452 -320.911288) (xy 443.156902 -320.947775)
			(xy 443.104996 -320.977742) (xy 443.049623 -321.000678) (xy 442.99173 -321.016191) (xy 442.932308 -321.024014)
			(xy 442.872372 -321.024014) (xy 442.81295 -321.016191) (xy 442.755057 -321.000678) (xy 442.699684 -320.977742)
			(xy 442.647778 -320.947775) (xy 442.600228 -320.911288) (xy 442.557848 -320.868908) (xy 442.521361 -320.821358)
			(xy 442.491394 -320.769452) (xy 442.468458 -320.714079) (xy 442.452945 -320.656186) (xy 442.445122 -320.596764)
			(xy 442.444632 -320.566796) (xy 442.445211 -320.534434) (xy 442.45436 -320.47036) (xy 442.472434 -320.408211)
			(xy 442.499073 -320.349223) (xy 442.533747 -320.29457) (xy 442.55436 -320.269616) (xy 442.563385 -320.258268)
			(xy 442.575266 -320.231834) (xy 442.579244 -320.203128) (xy 442.575001 -320.17446) (xy 442.562876 -320.148137)
			(xy 442.543847 -320.126279) (xy 442.519445 -320.110645) (xy 442.491634 -320.102494) (xy 442.477144 -320.101976)
			(xy 439.37555 -320.101976) (xy 439.350966 -320.121242) (xy 439.297568 -320.153639) (xy 439.240263 -320.178478)
			(xy 439.180113 -320.195297) (xy 439.118235 -320.203786) (xy 439.055777 -320.203786) (xy 438.993899 -320.195297)
			(xy 438.933749 -320.178478) (xy 438.876444 -320.153639) (xy 438.823046 -320.121242) (xy 438.798462 -320.101976)
			(xy 436.209186 -320.101976) (xy 436.20563 -320.102484) (xy 436.190032 -320.104606) (xy 436.158633 -320.106896)
			(xy 436.142892 -320.107056) (xy 435.767734 -320.107056) (xy 435.753322 -320.107552) (xy 435.725644 -320.115601)
			(xy 435.701321 -320.131067) (xy 435.682292 -320.152717) (xy 435.670074 -320.178824) (xy 435.665642 -320.207305)
			(xy 435.66935 -320.23589) (xy 435.680901 -320.262298) (xy 435.689756 -320.27368) (xy 435.709716 -320.298474)
			(xy 435.74331 -320.352535) (xy 435.769089 -320.41073) (xy 435.786557 -320.471936) (xy 435.795376 -320.534971)
			(xy 435.795928 -320.566796) (xy 435.795438 -320.596764) (xy 435.787615 -320.656186) (xy 435.772102 -320.714079)
			(xy 435.749166 -320.769452) (xy 435.719199 -320.821358) (xy 435.682712 -320.868908) (xy 435.640332 -320.911288)
			(xy 435.592782 -320.947775) (xy 435.540876 -320.977742) (xy 435.485503 -321.000678) (xy 435.42761 -321.016191)
			(xy 435.368188 -321.024014) (xy 435.308252 -321.024014) (xy 435.24883 -321.016191) (xy 435.190937 -321.000678)
			(xy 435.135564 -320.977742) (xy 435.083658 -320.947775) (xy 435.036108 -320.911288) (xy 434.993728 -320.868908)
			(xy 434.957241 -320.821358) (xy 434.927274 -320.769452) (xy 434.904338 -320.714079) (xy 434.888825 -320.656186)
			(xy 434.881002 -320.596764) (xy 434.880512 -320.566796) (xy 434.88106 -320.534971) (xy 434.88988 -320.471936)
			(xy 434.907349 -320.410731) (xy 434.93313 -320.352536) (xy 434.966727 -320.298476) (xy 434.986684 -320.27368)
			(xy 434.995528 -320.262289) (xy 435.007064 -320.235873) (xy 435.010763 -320.207286) (xy 435.00633 -320.178803)
			(xy 434.994118 -320.152693) (xy 434.9751 -320.131032) (xy 434.950788 -320.115545) (xy 434.923118 -320.107465)
			(xy 434.908706 -320.107056) (xy 434.482494 -320.107056) (xy 434.466754 -320.106878) (xy 434.435356 -320.104586)
			(xy 434.419756 -320.102484) (xy 434.4162 -320.101976) (xy 432.509422 -320.101976) (xy 431.889154 -320.722244)
			(xy 431.908245 -320.743472) (xy 431.941562 -320.789834) (xy 431.96886 -320.839978) (xy 431.989714 -320.893126)
			(xy 432.003801 -320.948453) (xy 432.010903 -321.005102) (xy 432.011328 -321.033648) (xy 432.010838 -321.063616)
			(xy 432.003015 -321.123038) (xy 431.987502 -321.180931) (xy 431.964566 -321.236304) (xy 431.934599 -321.28821)
			(xy 431.898112 -321.33576) (xy 431.855732 -321.37814) (xy 431.808182 -321.414627) (xy 431.756276 -321.444594)
			(xy 431.700903 -321.46753) (xy 431.64301 -321.483043) (xy 431.583588 -321.490866) (xy 431.523652 -321.490866)
			(xy 431.46423 -321.483043) (xy 431.406337 -321.46753) (xy 431.350964 -321.444594) (xy 431.299058 -321.414627)
			(xy 431.251508 -321.37814) (xy 431.209128 -321.33576) (xy 431.172641 -321.28821) (xy 431.142674 -321.236304)
			(xy 431.119738 -321.180931) (xy 431.104225 -321.123038) (xy 431.096402 -321.063616) (xy 431.095912 -321.033648)
			(xy 431.096353 -321.004805) (xy 431.10361 -320.947578) (xy 431.118002 -320.891716) (xy 431.1393 -320.838107)
			(xy 431.167168 -320.787599) (xy 431.201163 -320.740995) (xy 431.220626 -320.719704) (xy 431.234596 -320.704972)
			(xy 431.234596 -320.60642) (xy 431.235094 -320.581354) (xy 431.242949 -320.53184) (xy 431.258452 -320.484164)
			(xy 431.281222 -320.439501) (xy 431.310699 -320.398949) (xy 431.328068 -320.380868) (xy 431.390552 -320.31813)
			(xy 431.399973 -320.308076) (xy 431.41355 -320.284114) (xy 431.420232 -320.257395) (xy 431.419532 -320.229863)
			(xy 431.411502 -320.203518) (xy 431.396726 -320.180276) (xy 431.376277 -320.161826) (xy 431.364136 -320.155316)
			(xy 431.342158 -320.14397) (xy 431.300536 -320.117245) (xy 431.281078 -320.101976) (xy 428.502064 -320.101976)
			(xy 428.476631 -320.116128) (xy 428.422852 -320.138385) (xy 428.366626 -320.153421) (xy 428.308916 -320.160979)
			(xy 428.279814 -320.161412) (xy 428.250716 -320.160935) (xy 428.193017 -320.153349) (xy 428.136796 -320.138319)
			(xy 428.083009 -320.116099) (xy 428.057564 -320.101976) (xy 427.774608 -320.101976) (xy 427.751575 -320.122203)
			(xy 427.701078 -320.156955) (xy 427.646392 -320.184651) (xy 427.588497 -320.204797) (xy 427.52843 -320.21703)
			(xy 427.467268 -320.221132) (xy 427.406106 -320.21703) (xy 427.346039 -320.204797) (xy 427.288144 -320.184651)
			(xy 427.233458 -320.156955) (xy 427.182961 -320.122203) (xy 427.159928 -320.101976) (xy 424.4721 -320.101976)
			(xy 424.460088 -320.12928) (xy 424.430003 -320.18079) (xy 424.393483 -320.227956) (xy 424.351144 -320.269977)
			(xy 424.303706 -320.306142) (xy 424.251971 -320.335839) (xy 424.196817 -320.358563) (xy 424.139178 -320.37393)
			(xy 424.080032 -320.381679) (xy 424.02038 -320.381679) (xy 423.961234 -320.37393) (xy 423.903595 -320.358563)
			(xy 423.848441 -320.335839) (xy 423.796706 -320.306142) (xy 423.749268 -320.269977) (xy 423.706929 -320.227956)
			(xy 423.670409 -320.18079) (xy 423.640324 -320.12928) (xy 423.628312 -320.101976) (xy 421.432482 -320.101976)
			(xy 421.117268 -320.416936) (xy 421.098143 -320.435474) (xy 421.055911 -320.467931) (xy 421.009804 -320.494599)
			(xy 420.960611 -320.515021) (xy 420.909174 -320.528848) (xy 420.856371 -320.535844) (xy 420.82974 -320.536316)
			(xy 420.818818 -320.536316) (xy 420.804003 -320.53681) (xy 420.775619 -320.545303) (xy 420.750879 -320.561606)
			(xy 420.731879 -320.584339) (xy 420.720224 -320.611579) (xy 420.716901 -320.64102) (xy 420.718996 -320.655696)
			(xy 420.722332 -320.675722) (xy 420.725893 -320.716167) (xy 420.726108 -320.736468) (xy 420.725618 -320.766436)
			(xy 420.717795 -320.825858) (xy 420.702282 -320.883751) (xy 420.679346 -320.939124) (xy 420.649379 -320.99103)
			(xy 420.612892 -321.03858) (xy 420.570512 -321.08096) (xy 420.522962 -321.117447) (xy 420.471056 -321.147414)
			(xy 420.428078 -321.165216) (xy 427.151782 -321.165216) (xy 427.151782 -321.10528) (xy 427.159605 -321.045858)
			(xy 427.175118 -320.987965) (xy 427.198054 -320.932592) (xy 427.228021 -320.880686) (xy 427.264508 -320.833136)
			(xy 427.306888 -320.790756) (xy 427.354438 -320.754269) (xy 427.406344 -320.724302) (xy 427.461717 -320.701366)
			(xy 427.51961 -320.685853) (xy 427.579032 -320.67803) (xy 427.638968 -320.67803) (xy 427.69839 -320.685853)
			(xy 427.756283 -320.701366) (xy 427.811656 -320.724302) (xy 427.863562 -320.754269) (xy 427.911112 -320.790756)
			(xy 427.953492 -320.833136) (xy 427.989979 -320.880686) (xy 428.019946 -320.932592) (xy 428.042882 -320.987965)
			(xy 428.058395 -321.045858) (xy 428.066218 -321.10528) (xy 428.066708 -321.135248) (xy 428.066218 -321.165216)
			(xy 428.058395 -321.224638) (xy 428.042882 -321.282531) (xy 428.019946 -321.337904) (xy 427.989979 -321.38981)
			(xy 427.953492 -321.43736) (xy 427.911112 -321.47974) (xy 427.863562 -321.516227) (xy 427.811656 -321.546194)
			(xy 427.756283 -321.56913) (xy 427.69839 -321.584643) (xy 427.638968 -321.592466) (xy 427.579032 -321.592466)
			(xy 427.51961 -321.584643) (xy 427.461717 -321.56913) (xy 427.406344 -321.546194) (xy 427.354438 -321.516227)
			(xy 427.306888 -321.47974) (xy 427.264508 -321.43736) (xy 427.228021 -321.38981) (xy 427.198054 -321.337904)
			(xy 427.175118 -321.282531) (xy 427.159605 -321.224638) (xy 427.151782 -321.165216) (xy 420.428078 -321.165216)
			(xy 420.415683 -321.17035) (xy 420.35779 -321.185863) (xy 420.298368 -321.193686) (xy 420.238432 -321.193686)
			(xy 420.17901 -321.185863) (xy 420.121117 -321.17035) (xy 420.065744 -321.147414) (xy 420.013838 -321.117447)
			(xy 419.966288 -321.08096) (xy 419.923908 -321.03858) (xy 419.887421 -320.99103) (xy 419.857454 -320.939124)
			(xy 419.834518 -320.883751) (xy 419.819005 -320.825858) (xy 419.811182 -320.766436) (xy 419.810692 -320.736468)
			(xy 419.811157 -320.705739) (xy 419.819318 -320.644827) (xy 419.826948 -320.615056) (xy 419.830107 -320.602069)
			(xy 419.830267 -320.575349) (xy 419.823488 -320.549503) (xy 419.810233 -320.526303) (xy 419.791411 -320.507337)
			(xy 419.768311 -320.493907) (xy 419.742517 -320.486932) (xy 419.729158 -320.486532) (xy 419.398958 -320.486532)
			(xy 419.373889 -320.486063) (xy 419.324369 -320.478211) (xy 419.276688 -320.462708) (xy 419.23202 -320.439935)
			(xy 419.191465 -320.410454) (xy 419.173406 -320.39306) (xy 418.882068 -320.101976) (xy 416.877754 -320.101976)
			(xy 416.862375 -320.127752) (xy 416.825891 -320.175415) (xy 416.783492 -320.217901) (xy 416.735903 -320.254481)
			(xy 416.683942 -320.284528) (xy 416.628499 -320.307526) (xy 416.570526 -320.323081) (xy 416.511018 -320.330926)
			(xy 416.450994 -320.330926) (xy 416.391486 -320.323081) (xy 416.333513 -320.307526) (xy 416.27807 -320.284528)
			(xy 416.226109 -320.254481) (xy 416.17852 -320.217901) (xy 416.136121 -320.175415) (xy 416.099637 -320.127752)
			(xy 416.084258 -320.101976) (xy 413.414464 -320.101976) (xy 413.389031 -320.116128) (xy 413.335252 -320.138385)
			(xy 413.279026 -320.153421) (xy 413.221316 -320.160979) (xy 413.192214 -320.161412) (xy 413.164679 -320.161017)
			(xy 413.110027 -320.154243) (xy 413.056633 -320.140762) (xy 413.005317 -320.12078) (xy 412.980886 -320.108072)
			(xy 412.969456 -320.101976) (xy 412.892748 -320.101976) (xy 412.892748 -320.178938) (xy 412.914084 -320.194178)
			(xy 412.939126 -320.212655) (xy 412.984456 -320.255296) (xy 413.023584 -320.30369) (xy 413.055788 -320.356943)
			(xy 413.080473 -320.414071) (xy 413.097183 -320.474019) (xy 413.10561 -320.535679) (xy 413.106108 -320.566796)
			(xy 413.105618 -320.596764) (xy 413.097795 -320.656186) (xy 413.082282 -320.714079) (xy 413.059346 -320.769452)
			(xy 413.029379 -320.821358) (xy 412.992892 -320.868908) (xy 412.950512 -320.911288) (xy 412.902962 -320.947775)
			(xy 412.851056 -320.977742) (xy 412.795683 -321.000678) (xy 412.73779 -321.016191) (xy 412.678368 -321.024014)
			(xy 412.618432 -321.024014) (xy 412.55901 -321.016191) (xy 412.501117 -321.000678) (xy 412.445744 -320.977742)
			(xy 412.393838 -320.947775) (xy 412.346288 -320.911288) (xy 412.303908 -320.868908) (xy 412.267421 -320.821358)
			(xy 412.237454 -320.769452) (xy 412.214518 -320.714079) (xy 412.199005 -320.656186) (xy 412.191182 -320.596764)
			(xy 412.190692 -320.566796) (xy 412.191271 -320.534435) (xy 412.200422 -320.470361) (xy 412.218498 -320.408213)
			(xy 412.245139 -320.349227) (xy 412.279817 -320.294577) (xy 412.30042 -320.269616) (xy 412.309448 -320.25827)
			(xy 412.321333 -320.231839) (xy 412.325314 -320.203134) (xy 412.321071 -320.174466) (xy 412.308945 -320.148144)
			(xy 412.289912 -320.126289) (xy 412.265507 -320.110661) (xy 412.237694 -320.102519) (xy 412.223204 -320.101976)
			(xy 409.55976 -320.101976) (xy 409.539793 -320.120228) (xy 409.495371 -320.1511) (xy 409.446791 -320.174897)
			(xy 409.395171 -320.191073) (xy 409.341698 -320.199255) (xy 409.287602 -320.199255) (xy 409.234129 -320.191073)
			(xy 409.182509 -320.174897) (xy 409.133929 -320.1511) (xy 409.089507 -320.120228) (xy 409.06954 -320.101976)
			(xy 408.928062 -320.101976) (xy 408.913139 -320.102501) (xy 408.884567 -320.111126) (xy 408.8597 -320.127631)
			(xy 408.840655 -320.150611) (xy 408.829054 -320.17811) (xy 408.825883 -320.207786) (xy 408.831413 -320.237115)
			(xy 408.837892 -320.250566) (xy 408.850236 -320.275145) (xy 408.869622 -320.326617) (xy 408.882705 -320.380041)
			(xy 408.889297 -320.434647) (xy 408.889708 -320.462148) (xy 408.889218 -320.492116) (xy 408.881395 -320.551538)
			(xy 408.865882 -320.609431) (xy 408.842946 -320.664804) (xy 408.812979 -320.71671) (xy 408.776492 -320.76426)
			(xy 408.734112 -320.80664) (xy 408.686562 -320.843127) (xy 408.634656 -320.873094) (xy 408.579283 -320.89603)
			(xy 408.52139 -320.911543) (xy 408.461968 -320.919366) (xy 408.402032 -320.919366) (xy 408.34261 -320.911543)
			(xy 408.284717 -320.89603) (xy 408.229344 -320.873094) (xy 408.177438 -320.843127) (xy 408.129888 -320.80664)
			(xy 408.087508 -320.76426) (xy 408.051021 -320.71671) (xy 408.021054 -320.664804) (xy 407.998118 -320.609431)
			(xy 407.982605 -320.551538) (xy 407.974782 -320.492116) (xy 407.974292 -320.462148) (xy 407.974871 -320.429381)
			(xy 407.984258 -320.364523) (xy 408.002802 -320.301668) (xy 408.015948 -320.271648) (xy 408.021691 -320.257744)
			(xy 408.025656 -320.227938) (xy 408.020782 -320.198267) (xy 408.00749 -320.171297) (xy 407.986929 -320.149357)
			(xy 407.960876 -320.134346) (xy 407.946352 -320.130424) (xy 407.92724 -320.125777) (xy 407.889846 -320.11357)
			(xy 407.871676 -320.10604) (xy 407.862024 -320.101976) (xy 405.260556 -320.101976) (xy 404.955756 -320.406776)
			(xy 404.955756 -323.712586) (xy 405.768048 -323.712586) (xy 405.768048 -321.825366) (xy 405.993346 -321.600068)
			(xy 407.702766 -321.600068) (xy 407.902664 -321.799966) (xy 407.902664 -323.661786) (xy 407.851864 -323.712586)
			(xy 409.832048 -323.712586) (xy 409.832048 -321.825366) (xy 410.057346 -321.600068) (xy 411.766766 -321.600068)
			(xy 411.925298 -321.7586) (xy 412.578556 -321.7586) (xy 412.582539 -321.705448) (xy 412.594399 -321.653484)
			(xy 412.613871 -321.603867) (xy 412.64052 -321.557706) (xy 412.673751 -321.516033) (xy 412.712821 -321.479777)
			(xy 412.756859 -321.449749) (xy 412.804879 -321.426619) (xy 412.855811 -321.410905) (xy 412.908516 -321.402956)
			(xy 412.935166 -321.402456) (xy 412.963391 -321.402962) (xy 413.019136 -321.411864) (xy 413.072777 -321.429449)
			(xy 413.122972 -321.455278) (xy 413.168463 -321.488704) (xy 413.20811 -321.528888) (xy 413.240921 -321.574824)
			(xy 413.266072 -321.625363) (xy 413.275018 -321.652138) (xy 413.280039 -321.666193) (xy 413.296783 -321.690876)
			(xy 413.319951 -321.709659) (xy 413.347563 -321.720935) (xy 413.377256 -321.723741) (xy 413.406492 -321.717836)
			(xy 413.432768 -321.703725) (xy 413.443674 -321.69354) (xy 413.537146 -321.600068) (xy 415.246566 -321.600068)
			(xy 415.446464 -321.799966) (xy 415.446464 -322.369749) (xy 415.741388 -322.369749) (xy 415.741388 -322.315251)
			(xy 415.749143 -322.261309) (xy 415.764496 -322.209019) (xy 415.787133 -322.159446) (xy 415.816595 -322.113599)
			(xy 415.852281 -322.072411) (xy 415.893465 -322.03672) (xy 415.939309 -322.007254) (xy 415.988879 -321.984611)
			(xy 416.041168 -321.969252) (xy 416.095109 -321.961491) (xy 416.122358 -321.961002) (xy 416.149857 -321.961476)
			(xy 416.204285 -321.969388) (xy 416.257014 -321.985025) (xy 416.306955 -322.008064) (xy 416.353075 -322.038029)
			(xy 416.394419 -322.0743) (xy 416.430133 -322.116126) (xy 416.459478 -322.162642) (xy 416.4711 -322.18757)
			(xy 416.476995 -322.199647) (xy 416.493947 -322.220485) (xy 416.515741 -322.236189) (xy 416.540873 -322.245674)
			(xy 416.567608 -322.248287) (xy 416.594101 -322.243847) (xy 416.606482 -322.238624) (xy 416.63165 -322.227563)
			(xy 416.684358 -322.211948) (xy 416.738762 -322.204055) (xy 416.766248 -322.203572) (xy 416.793496 -322.204102)
			(xy 416.847435 -322.211863) (xy 416.899721 -322.227222) (xy 416.94929 -322.249864) (xy 416.995132 -322.27933)
			(xy 417.036314 -322.31502) (xy 417.071999 -322.356207) (xy 417.101459 -322.402052) (xy 417.124095 -322.451624)
			(xy 417.139447 -322.503912) (xy 417.147202 -322.557852) (xy 417.147202 -322.612348) (xy 417.139447 -322.666288)
			(xy 417.124095 -322.718576) (xy 417.101459 -322.768148) (xy 417.071999 -322.813993) (xy 417.036314 -322.85518)
			(xy 416.995132 -322.89087) (xy 416.94929 -322.920336) (xy 416.899721 -322.942978) (xy 416.847435 -322.958337)
			(xy 416.793496 -322.966098) (xy 416.766248 -322.966588) (xy 416.738748 -322.966115) (xy 416.684321 -322.958204)
			(xy 416.631591 -322.942567) (xy 416.58165 -322.919527) (xy 416.53553 -322.889562) (xy 416.494186 -322.853292)
			(xy 416.458472 -322.811465) (xy 416.429128 -322.764948) (xy 416.417506 -322.74002) (xy 416.411719 -322.727884)
			(xy 416.394745 -322.707041) (xy 416.372927 -322.691339) (xy 416.347772 -322.681863) (xy 416.321017 -322.679267)
			(xy 416.294509 -322.68373) (xy 416.282124 -322.688966) (xy 416.256955 -322.700024) (xy 416.204247 -322.715641)
			(xy 416.149844 -322.723535) (xy 416.122358 -322.724018) (xy 416.095109 -322.723509) (xy 416.041168 -322.715748)
			(xy 415.988879 -322.700389) (xy 415.939309 -322.677746) (xy 415.893465 -322.64828) (xy 415.852281 -322.612589)
			(xy 415.816595 -322.571401) (xy 415.787133 -322.525554) (xy 415.764496 -322.475981) (xy 415.749143 -322.423691)
			(xy 415.741388 -322.369749) (xy 415.446464 -322.369749) (xy 415.446464 -323.661786) (xy 415.395664 -323.712586)
			(xy 417.375848 -323.712586) (xy 417.375848 -321.825366) (xy 417.601146 -321.600068) (xy 419.310566 -321.600068)
			(xy 419.510464 -321.799966) (xy 419.510464 -323.661786) (xy 419.459664 -323.712586) (xy 420.855648 -323.712586)
			(xy 420.855648 -321.825366) (xy 421.080946 -321.600068) (xy 422.790366 -321.600068) (xy 422.990264 -321.799966)
			(xy 422.990264 -323.661786) (xy 422.939464 -323.712586) (xy 424.919648 -323.712586) (xy 424.919648 -321.825366)
			(xy 425.144946 -321.600068) (xy 426.854366 -321.600068) (xy 427.054264 -321.799966) (xy 427.054264 -323.661786)
			(xy 427.003464 -323.712586) (xy 428.399448 -323.712586) (xy 428.399448 -321.825366) (xy 428.624746 -321.600068)
			(xy 430.334166 -321.600068) (xy 430.534064 -321.799966) (xy 430.534064 -323.661786) (xy 430.483264 -323.712586)
			(xy 432.463448 -323.712586) (xy 432.463448 -321.825366) (xy 432.688746 -321.600068) (xy 434.398166 -321.600068)
			(xy 434.598064 -321.799966) (xy 434.598064 -323.661786) (xy 434.547264 -323.712586) (xy 435.943248 -323.712586)
			(xy 435.943248 -321.825366) (xy 436.168546 -321.600068) (xy 437.877966 -321.600068) (xy 438.077864 -321.799966)
			(xy 438.077864 -323.661786) (xy 438.027064 -323.712586) (xy 440.007248 -323.712586) (xy 440.007248 -321.825366)
			(xy 440.232546 -321.600068) (xy 441.941966 -321.600068) (xy 442.141864 -321.799966) (xy 442.141864 -323.661786)
			(xy 442.091064 -323.712586) (xy 443.487048 -323.712586) (xy 443.487048 -321.825366) (xy 443.712346 -321.600068)
			(xy 445.421766 -321.600068) (xy 445.621664 -321.799966) (xy 445.621664 -323.661786) (xy 445.570864 -323.712586)
			(xy 447.551048 -323.712586) (xy 447.551048 -321.825366) (xy 447.776346 -321.600068) (xy 449.485766 -321.600068)
			(xy 449.685664 -321.799966) (xy 449.685664 -323.661786) (xy 449.634864 -323.712586) (xy 451.030848 -323.712586)
			(xy 451.030848 -321.825366) (xy 451.256146 -321.600068) (xy 452.965566 -321.600068) (xy 453.165464 -321.799966)
			(xy 453.165464 -323.661786) (xy 453.114664 -323.712586) (xy 455.094848 -323.712586) (xy 455.094848 -321.825366)
			(xy 455.320146 -321.600068) (xy 457.029566 -321.600068) (xy 457.229464 -321.799966) (xy 457.229464 -323.585586)
			(xy 458.473048 -323.585586) (xy 458.473048 -321.977766) (xy 458.799946 -321.650868) (xy 462.185766 -321.650868)
			(xy 462.461864 -321.926966) (xy 462.461864 -323.636386) (xy 462.160366 -323.937884) (xy 458.825346 -323.937884)
			(xy 458.473048 -323.585586) (xy 457.229464 -323.585586) (xy 457.229464 -323.661786) (xy 456.927966 -323.963284)
			(xy 455.345546 -323.963284) (xy 455.094848 -323.712586) (xy 453.114664 -323.712586) (xy 452.863966 -323.963284)
			(xy 451.281546 -323.963284) (xy 451.030848 -323.712586) (xy 449.634864 -323.712586) (xy 449.384166 -323.963284)
			(xy 447.801746 -323.963284) (xy 447.551048 -323.712586) (xy 445.570864 -323.712586) (xy 445.320166 -323.963284)
			(xy 443.737746 -323.963284) (xy 443.487048 -323.712586) (xy 442.091064 -323.712586) (xy 441.840366 -323.963284)
			(xy 440.257946 -323.963284) (xy 440.007248 -323.712586) (xy 438.027064 -323.712586) (xy 437.776366 -323.963284)
			(xy 436.193946 -323.963284) (xy 435.943248 -323.712586) (xy 434.547264 -323.712586) (xy 434.296566 -323.963284)
			(xy 432.714146 -323.963284) (xy 432.463448 -323.712586) (xy 430.483264 -323.712586) (xy 430.232566 -323.963284)
			(xy 428.650146 -323.963284) (xy 428.399448 -323.712586) (xy 427.003464 -323.712586) (xy 426.752766 -323.963284)
			(xy 425.170346 -323.963284) (xy 424.919648 -323.712586) (xy 422.939464 -323.712586) (xy 422.688766 -323.963284)
			(xy 421.106346 -323.963284) (xy 420.855648 -323.712586) (xy 419.459664 -323.712586) (xy 419.208966 -323.963284)
			(xy 417.626546 -323.963284) (xy 417.375848 -323.712586) (xy 415.395664 -323.712586) (xy 415.144966 -323.963284)
			(xy 413.562546 -323.963284) (xy 413.311848 -323.712586) (xy 413.311848 -322.124324) (xy 413.311301 -322.110243)
			(xy 413.303612 -322.08315) (xy 413.288812 -322.05919) (xy 413.268027 -322.040186) (xy 413.242841 -322.027585)
			(xy 413.215169 -322.022347) (xy 413.18712 -322.02487) (xy 413.160827 -322.034961) (xy 413.149288 -322.043044)
			(xy 413.126015 -322.059913) (xy 413.075144 -322.086664) (xy 413.020635 -322.104893) (xy 412.963904 -322.114124)
			(xy 412.935166 -322.114672) (xy 412.908516 -322.114244) (xy 412.855811 -322.106295) (xy 412.804879 -322.090581)
			(xy 412.756859 -322.067451) (xy 412.712821 -322.037423) (xy 412.673751 -322.001167) (xy 412.64052 -321.959494)
			(xy 412.613871 -321.913333) (xy 412.594399 -321.863716) (xy 412.582539 -321.811752) (xy 412.578556 -321.7586)
			(xy 411.925298 -321.7586) (xy 411.966664 -321.799966) (xy 411.966664 -323.661786) (xy 411.665166 -323.963284)
			(xy 410.082746 -323.963284) (xy 409.832048 -323.712586) (xy 407.851864 -323.712586) (xy 407.601166 -323.963284)
			(xy 406.018746 -323.963284) (xy 405.768048 -323.712586) (xy 404.955756 -323.712586) (xy 404.955756 -327.10898)
			(xy 407.266521 -327.10898) (xy 407.266521 -327.02442) (xy 407.274324 -326.94022) (xy 407.289862 -326.857099)
			(xy 407.313004 -326.775767) (xy 407.343552 -326.696917) (xy 407.381245 -326.621222) (xy 407.425762 -326.549328)
			(xy 407.476723 -326.481848) (xy 407.533692 -326.419358) (xy 407.596185 -326.362392) (xy 407.663667 -326.311435)
			(xy 407.735564 -326.266922) (xy 407.811261 -326.229233) (xy 407.890112 -326.198689) (xy 407.971446 -326.175551)
			(xy 408.054567 -326.160017) (xy 408.138768 -326.152219) (xy 408.181048 -326.151748) (xy 409.425648 -326.151748)
			(xy 409.467921 -326.152326) (xy 409.552105 -326.160131) (xy 409.63521 -326.17567) (xy 409.716527 -326.198811)
			(xy 409.795362 -326.229355) (xy 409.871043 -326.267043) (xy 409.942923 -326.311553) (xy 410.010391 -326.362505)
			(xy 410.072869 -326.419465) (xy 410.129825 -326.481946) (xy 410.180774 -326.549416) (xy 410.22528 -326.621299)
			(xy 410.262964 -326.696982) (xy 410.293504 -326.775818) (xy 410.316641 -326.857136) (xy 410.332175 -326.940242)
			(xy 410.339976 -327.024427) (xy 410.339976 -327.108973) (xy 410.339975 -327.10898) (xy 414.810321 -327.10898)
			(xy 414.810321 -327.02442) (xy 414.818124 -326.94022) (xy 414.833662 -326.857099) (xy 414.856804 -326.775767)
			(xy 414.887352 -326.696917) (xy 414.925045 -326.621222) (xy 414.969562 -326.549328) (xy 415.020523 -326.481848)
			(xy 415.077492 -326.419358) (xy 415.139985 -326.362392) (xy 415.207467 -326.311435) (xy 415.279364 -326.266922)
			(xy 415.355061 -326.229233) (xy 415.433912 -326.198689) (xy 415.515246 -326.175551) (xy 415.598367 -326.160017)
			(xy 415.682568 -326.152219) (xy 415.724848 -326.151748) (xy 416.969448 -326.151748) (xy 417.011721 -326.152326)
			(xy 417.095905 -326.160131) (xy 417.17901 -326.17567) (xy 417.260327 -326.198811) (xy 417.339162 -326.229355)
			(xy 417.414843 -326.267043) (xy 417.486723 -326.311553) (xy 417.554191 -326.362505) (xy 417.616669 -326.419465)
			(xy 417.673625 -326.481946) (xy 417.724574 -326.549416) (xy 417.76908 -326.621299) (xy 417.806764 -326.696982)
			(xy 417.837304 -326.775818) (xy 417.860441 -326.857136) (xy 417.875975 -326.940242) (xy 417.883776 -327.024427)
			(xy 417.883776 -327.108973) (xy 417.883775 -327.10898) (xy 422.354121 -327.10898) (xy 422.354121 -327.02442)
			(xy 422.361924 -326.94022) (xy 422.377462 -326.857099) (xy 422.400604 -326.775767) (xy 422.431152 -326.696917)
			(xy 422.468845 -326.621222) (xy 422.513362 -326.549328) (xy 422.564323 -326.481848) (xy 422.621292 -326.419358)
			(xy 422.683785 -326.362392) (xy 422.751267 -326.311435) (xy 422.823164 -326.266922) (xy 422.898861 -326.229233)
			(xy 422.977712 -326.198689) (xy 423.059046 -326.175551) (xy 423.142167 -326.160017) (xy 423.226368 -326.152219)
			(xy 423.268648 -326.151748) (xy 424.513248 -326.151748) (xy 424.555521 -326.152326) (xy 424.639705 -326.160131)
			(xy 424.72281 -326.17567) (xy 424.804127 -326.198811) (xy 424.882962 -326.229355) (xy 424.958643 -326.267043)
			(xy 425.030523 -326.311553) (xy 425.097991 -326.362505) (xy 425.160469 -326.419465) (xy 425.217425 -326.481946)
			(xy 425.268374 -326.549416) (xy 425.31288 -326.621299) (xy 425.350564 -326.696982) (xy 425.381104 -326.775818)
			(xy 425.404241 -326.857136) (xy 425.419775 -326.940242) (xy 425.427576 -327.024427) (xy 425.427576 -327.108973)
			(xy 425.427575 -327.10898) (xy 429.897921 -327.10898) (xy 429.897921 -327.02442) (xy 429.905724 -326.94022)
			(xy 429.921262 -326.857099) (xy 429.944404 -326.775767) (xy 429.974952 -326.696917) (xy 430.012645 -326.621222)
			(xy 430.057162 -326.549328) (xy 430.108123 -326.481848) (xy 430.165092 -326.419358) (xy 430.227585 -326.362392)
			(xy 430.295067 -326.311435) (xy 430.366964 -326.266922) (xy 430.442661 -326.229233) (xy 430.521512 -326.198689)
			(xy 430.602846 -326.175551) (xy 430.685967 -326.160017) (xy 430.770168 -326.152219) (xy 430.812448 -326.151748)
			(xy 432.057048 -326.151748) (xy 432.099321 -326.152326) (xy 432.183505 -326.160131) (xy 432.26661 -326.17567)
			(xy 432.347927 -326.198811) (xy 432.426762 -326.229355) (xy 432.502443 -326.267043) (xy 432.574323 -326.311553)
			(xy 432.641791 -326.362505) (xy 432.704269 -326.419465) (xy 432.761225 -326.481946) (xy 432.812174 -326.549416)
			(xy 432.85668 -326.621299) (xy 432.894364 -326.696982) (xy 432.924904 -326.775818) (xy 432.948041 -326.857136)
			(xy 432.963575 -326.940242) (xy 432.971376 -327.024427) (xy 432.971376 -327.108973) (xy 432.971375 -327.10898)
			(xy 437.441721 -327.10898) (xy 437.441721 -327.02442) (xy 437.449524 -326.94022) (xy 437.465062 -326.857099)
			(xy 437.488204 -326.775767) (xy 437.518752 -326.696917) (xy 437.556445 -326.621222) (xy 437.600962 -326.549328)
			(xy 437.651923 -326.481848) (xy 437.708892 -326.419358) (xy 437.771385 -326.362392) (xy 437.838867 -326.311435)
			(xy 437.910764 -326.266922) (xy 437.986461 -326.229233) (xy 438.065312 -326.198689) (xy 438.146646 -326.175551)
			(xy 438.229767 -326.160017) (xy 438.313968 -326.152219) (xy 438.356248 -326.151748) (xy 439.600848 -326.151748)
			(xy 439.643121 -326.152326) (xy 439.727305 -326.160131) (xy 439.81041 -326.17567) (xy 439.891727 -326.198811)
			(xy 439.970562 -326.229355) (xy 440.046243 -326.267043) (xy 440.118123 -326.311553) (xy 440.185591 -326.362505)
			(xy 440.248069 -326.419465) (xy 440.305025 -326.481946) (xy 440.355974 -326.549416) (xy 440.40048 -326.621299)
			(xy 440.438164 -326.696982) (xy 440.468704 -326.775818) (xy 440.491841 -326.857136) (xy 440.507375 -326.940242)
			(xy 440.515176 -327.024427) (xy 440.515176 -327.108973) (xy 440.515175 -327.10898) (xy 444.985521 -327.10898)
			(xy 444.985521 -327.02442) (xy 444.993324 -326.94022) (xy 445.008862 -326.857099) (xy 445.032004 -326.775767)
			(xy 445.062552 -326.696917) (xy 445.100245 -326.621222) (xy 445.144762 -326.549328) (xy 445.195723 -326.481848)
			(xy 445.252692 -326.419358) (xy 445.315185 -326.362392) (xy 445.382667 -326.311435) (xy 445.454564 -326.266922)
			(xy 445.530261 -326.229233) (xy 445.609112 -326.198689) (xy 445.690446 -326.175551) (xy 445.773567 -326.160017)
			(xy 445.857768 -326.152219) (xy 445.900048 -326.151748) (xy 447.144648 -326.151748) (xy 447.186921 -326.152326)
			(xy 447.271105 -326.160131) (xy 447.35421 -326.17567) (xy 447.435527 -326.198811) (xy 447.514362 -326.229355)
			(xy 447.590043 -326.267043) (xy 447.661923 -326.311553) (xy 447.729391 -326.362505) (xy 447.791869 -326.419465)
			(xy 447.848825 -326.481946) (xy 447.899774 -326.549416) (xy 447.94428 -326.621299) (xy 447.981964 -326.696982)
			(xy 448.012504 -326.775818) (xy 448.035641 -326.857136) (xy 448.051175 -326.940242) (xy 448.058976 -327.024427)
			(xy 448.058976 -327.108973) (xy 448.058975 -327.10898) (xy 452.529321 -327.10898) (xy 452.529321 -327.02442)
			(xy 452.537124 -326.94022) (xy 452.552662 -326.857099) (xy 452.575804 -326.775767) (xy 452.606352 -326.696917)
			(xy 452.644045 -326.621222) (xy 452.688562 -326.549328) (xy 452.739523 -326.481848) (xy 452.796492 -326.419358)
			(xy 452.858985 -326.362392) (xy 452.926467 -326.311435) (xy 452.998364 -326.266922) (xy 453.074061 -326.229233)
			(xy 453.152912 -326.198689) (xy 453.234246 -326.175551) (xy 453.317367 -326.160017) (xy 453.401568 -326.152219)
			(xy 453.443848 -326.151748) (xy 454.688448 -326.151748) (xy 454.730721 -326.152326) (xy 454.814905 -326.160131)
			(xy 454.89801 -326.17567) (xy 454.979327 -326.198811) (xy 455.058162 -326.229355) (xy 455.133843 -326.267043)
			(xy 455.205723 -326.311553) (xy 455.273191 -326.362505) (xy 455.335669 -326.419465) (xy 455.392625 -326.481946)
			(xy 455.443574 -326.549416) (xy 455.48808 -326.621299) (xy 455.525764 -326.696982) (xy 455.556304 -326.775818)
			(xy 455.579441 -326.857136) (xy 455.594975 -326.940242) (xy 455.602776 -327.024427) (xy 455.602776 -327.108973)
			(xy 455.594975 -327.193158) (xy 455.579441 -327.276264) (xy 455.556304 -327.357582) (xy 455.525764 -327.436418)
			(xy 455.48808 -327.512101) (xy 455.443574 -327.583984) (xy 455.392625 -327.651454) (xy 455.335669 -327.713935)
			(xy 455.273191 -327.770895) (xy 455.205724 -327.821847) (xy 455.133843 -327.866357) (xy 455.058162 -327.904045)
			(xy 454.979327 -327.934589) (xy 454.89801 -327.95773) (xy 454.814905 -327.973269) (xy 454.730721 -327.981074)
			(xy 454.688448 -327.981564) (xy 453.443848 -327.981564) (xy 453.401568 -327.981181) (xy 453.317367 -327.973383)
			(xy 453.234246 -327.957849) (xy 453.152912 -327.934711) (xy 453.074061 -327.904167) (xy 452.998364 -327.866478)
			(xy 452.926467 -327.821965) (xy 452.858985 -327.771008) (xy 452.796492 -327.714042) (xy 452.739523 -327.651552)
			(xy 452.688562 -327.584072) (xy 452.644045 -327.512178) (xy 452.606352 -327.436483) (xy 452.575804 -327.357633)
			(xy 452.552662 -327.276301) (xy 452.537124 -327.19318) (xy 452.529321 -327.10898) (xy 448.058975 -327.10898)
			(xy 448.051175 -327.193158) (xy 448.035641 -327.276264) (xy 448.012504 -327.357582) (xy 447.981964 -327.436418)
			(xy 447.94428 -327.512101) (xy 447.899774 -327.583984) (xy 447.848825 -327.651454) (xy 447.791869 -327.713935)
			(xy 447.729391 -327.770895) (xy 447.661924 -327.821847) (xy 447.590043 -327.866357) (xy 447.514362 -327.904045)
			(xy 447.435527 -327.934589) (xy 447.35421 -327.95773) (xy 447.271105 -327.973269) (xy 447.186921 -327.981074)
			(xy 447.144648 -327.981564) (xy 445.900048 -327.981564) (xy 445.857768 -327.981181) (xy 445.773567 -327.973383)
			(xy 445.690446 -327.957849) (xy 445.609112 -327.934711) (xy 445.530261 -327.904167) (xy 445.454564 -327.866478)
			(xy 445.382667 -327.821965) (xy 445.315185 -327.771008) (xy 445.252692 -327.714042) (xy 445.195723 -327.651552)
			(xy 445.144762 -327.584072) (xy 445.100245 -327.512178) (xy 445.062552 -327.436483) (xy 445.032004 -327.357633)
			(xy 445.008862 -327.276301) (xy 444.993324 -327.19318) (xy 444.985521 -327.10898) (xy 440.515175 -327.10898)
			(xy 440.507375 -327.193158) (xy 440.491841 -327.276264) (xy 440.468704 -327.357582) (xy 440.438164 -327.436418)
			(xy 440.40048 -327.512101) (xy 440.355974 -327.583984) (xy 440.305025 -327.651454) (xy 440.248069 -327.713935)
			(xy 440.185591 -327.770895) (xy 440.118124 -327.821847) (xy 440.046243 -327.866357) (xy 439.970562 -327.904045)
			(xy 439.891727 -327.934589) (xy 439.81041 -327.95773) (xy 439.727305 -327.973269) (xy 439.643121 -327.981074)
			(xy 439.600848 -327.981564) (xy 438.356248 -327.981564) (xy 438.313968 -327.981181) (xy 438.229767 -327.973383)
			(xy 438.146646 -327.957849) (xy 438.065312 -327.934711) (xy 437.986461 -327.904167) (xy 437.910764 -327.866478)
			(xy 437.838867 -327.821965) (xy 437.771385 -327.771008) (xy 437.708892 -327.714042) (xy 437.651923 -327.651552)
			(xy 437.600962 -327.584072) (xy 437.556445 -327.512178) (xy 437.518752 -327.436483) (xy 437.488204 -327.357633)
			(xy 437.465062 -327.276301) (xy 437.449524 -327.19318) (xy 437.441721 -327.10898) (xy 432.971375 -327.10898)
			(xy 432.963575 -327.193158) (xy 432.948041 -327.276264) (xy 432.924904 -327.357582) (xy 432.894364 -327.436418)
			(xy 432.85668 -327.512101) (xy 432.812174 -327.583984) (xy 432.761225 -327.651454) (xy 432.704269 -327.713935)
			(xy 432.641791 -327.770895) (xy 432.574324 -327.821847) (xy 432.502443 -327.866357) (xy 432.426762 -327.904045)
			(xy 432.347927 -327.934589) (xy 432.26661 -327.95773) (xy 432.183505 -327.973269) (xy 432.099321 -327.981074)
			(xy 432.057048 -327.981564) (xy 430.812448 -327.981564) (xy 430.770168 -327.981181) (xy 430.685967 -327.973383)
			(xy 430.602846 -327.957849) (xy 430.521512 -327.934711) (xy 430.442661 -327.904167) (xy 430.366964 -327.866478)
			(xy 430.295067 -327.821965) (xy 430.227585 -327.771008) (xy 430.165092 -327.714042) (xy 430.108123 -327.651552)
			(xy 430.057162 -327.584072) (xy 430.012645 -327.512178) (xy 429.974952 -327.436483) (xy 429.944404 -327.357633)
			(xy 429.921262 -327.276301) (xy 429.905724 -327.19318) (xy 429.897921 -327.10898) (xy 425.427575 -327.10898)
			(xy 425.419775 -327.193158) (xy 425.404241 -327.276264) (xy 425.381104 -327.357582) (xy 425.350564 -327.436418)
			(xy 425.31288 -327.512101) (xy 425.268374 -327.583984) (xy 425.217425 -327.651454) (xy 425.160469 -327.713935)
			(xy 425.097991 -327.770895) (xy 425.030524 -327.821847) (xy 424.958643 -327.866357) (xy 424.882962 -327.904045)
			(xy 424.804127 -327.934589) (xy 424.72281 -327.95773) (xy 424.639705 -327.973269) (xy 424.555521 -327.981074)
			(xy 424.513248 -327.981564) (xy 423.268648 -327.981564) (xy 423.226368 -327.981181) (xy 423.142167 -327.973383)
			(xy 423.059046 -327.957849) (xy 422.977712 -327.934711) (xy 422.898861 -327.904167) (xy 422.823164 -327.866478)
			(xy 422.751267 -327.821965) (xy 422.683785 -327.771008) (xy 422.621292 -327.714042) (xy 422.564323 -327.651552)
			(xy 422.513362 -327.584072) (xy 422.468845 -327.512178) (xy 422.431152 -327.436483) (xy 422.400604 -327.357633)
			(xy 422.377462 -327.276301) (xy 422.361924 -327.19318) (xy 422.354121 -327.10898) (xy 417.883775 -327.10898)
			(xy 417.875975 -327.193158) (xy 417.860441 -327.276264) (xy 417.837304 -327.357582) (xy 417.806764 -327.436418)
			(xy 417.76908 -327.512101) (xy 417.724574 -327.583984) (xy 417.673625 -327.651454) (xy 417.616669 -327.713935)
			(xy 417.554191 -327.770895) (xy 417.486724 -327.821847) (xy 417.414843 -327.866357) (xy 417.339162 -327.904045)
			(xy 417.260327 -327.934589) (xy 417.17901 -327.95773) (xy 417.095905 -327.973269) (xy 417.011721 -327.981074)
			(xy 416.969448 -327.981564) (xy 415.724848 -327.981564) (xy 415.682568 -327.981181) (xy 415.598367 -327.973383)
			(xy 415.515246 -327.957849) (xy 415.433912 -327.934711) (xy 415.355061 -327.904167) (xy 415.279364 -327.866478)
			(xy 415.207467 -327.821965) (xy 415.139985 -327.771008) (xy 415.077492 -327.714042) (xy 415.020523 -327.651552)
			(xy 414.969562 -327.584072) (xy 414.925045 -327.512178) (xy 414.887352 -327.436483) (xy 414.856804 -327.357633)
			(xy 414.833662 -327.276301) (xy 414.818124 -327.19318) (xy 414.810321 -327.10898) (xy 410.339975 -327.10898)
			(xy 410.332175 -327.193158) (xy 410.316641 -327.276264) (xy 410.293504 -327.357582) (xy 410.262964 -327.436418)
			(xy 410.22528 -327.512101) (xy 410.180774 -327.583984) (xy 410.129825 -327.651454) (xy 410.072869 -327.713935)
			(xy 410.010391 -327.770895) (xy 409.942924 -327.821847) (xy 409.871043 -327.866357) (xy 409.795362 -327.904045)
			(xy 409.716527 -327.934589) (xy 409.63521 -327.95773) (xy 409.552105 -327.973269) (xy 409.467921 -327.981074)
			(xy 409.425648 -327.981564) (xy 408.181048 -327.981564) (xy 408.138768 -327.981181) (xy 408.054567 -327.973383)
			(xy 407.971446 -327.957849) (xy 407.890112 -327.934711) (xy 407.811261 -327.904167) (xy 407.735564 -327.866478)
			(xy 407.663667 -327.821965) (xy 407.596185 -327.771008) (xy 407.533692 -327.714042) (xy 407.476723 -327.651552)
			(xy 407.425762 -327.584072) (xy 407.381245 -327.512178) (xy 407.343552 -327.436483) (xy 407.313004 -327.357633)
			(xy 407.289862 -327.276301) (xy 407.274324 -327.19318) (xy 407.266521 -327.10898) (xy 404.955756 -327.10898)
			(xy 404.955756 -332.8604) (xy 443.200588 -332.8604) (xy 443.204571 -332.807254) (xy 443.216429 -332.755296)
			(xy 443.235898 -332.705684) (xy 443.262543 -332.659529) (xy 443.29577 -332.617859) (xy 443.334835 -332.581607)
			(xy 443.378866 -332.551581) (xy 443.426881 -332.528453) (xy 443.477806 -332.512739) (xy 443.530505 -332.504789)
			(xy 443.557152 -332.504288) (xy 443.58356 -332.504803) (xy 443.635796 -332.512597) (xy 443.686309 -332.528022)
			(xy 443.733988 -332.550739) (xy 443.77779 -332.580249) (xy 443.816751 -332.615906) (xy 443.833758 -332.636114)
			(xy 443.843695 -332.647507) (xy 443.868748 -332.664398) (xy 443.897644 -332.673229) (xy 443.92786 -332.673229)
			(xy 443.956756 -332.664398) (xy 443.981809 -332.647507) (xy 443.991746 -332.636114) (xy 444.008777 -332.615926)
			(xy 444.047732 -332.580262) (xy 444.091527 -332.550743) (xy 444.139202 -332.528015) (xy 444.18971 -332.512579)
			(xy 444.241945 -332.504771) (xy 444.268352 -332.504288) (xy 444.295005 -332.504766) (xy 444.347717 -332.512704)
			(xy 444.398657 -332.528411) (xy 444.446686 -332.551535) (xy 444.490732 -332.58156) (xy 444.529811 -332.617815)
			(xy 444.56305 -332.659489) (xy 444.589705 -332.705653) (xy 444.609181 -332.755273) (xy 444.621044 -332.807243)
			(xy 444.625028 -332.8604) (xy 444.621044 -332.913557) (xy 444.609181 -332.965527) (xy 444.589705 -333.015147)
			(xy 444.56305 -333.061311) (xy 444.529811 -333.102985) (xy 444.490732 -333.13924) (xy 444.446686 -333.169265)
			(xy 444.398657 -333.192389) (xy 444.347717 -333.208096) (xy 444.295005 -333.216034) (xy 444.268352 -333.216504)
			(xy 444.241944 -333.215989) (xy 444.189708 -333.208195) (xy 444.139195 -333.192771) (xy 444.091515 -333.170054)
			(xy 444.047714 -333.140543) (xy 444.008753 -333.104886) (xy 443.991746 -333.084678) (xy 443.981809 -333.073285)
			(xy 443.956756 -333.056394) (xy 443.92786 -333.047563) (xy 443.897644 -333.047563) (xy 443.868748 -333.056394)
			(xy 443.843695 -333.073285) (xy 443.833758 -333.084678) (xy 443.816723 -333.104863) (xy 443.777769 -333.140527)
			(xy 443.733975 -333.170047) (xy 443.686301 -333.192775) (xy 443.635793 -333.208212) (xy 443.583559 -333.216021)
			(xy 443.557152 -333.216504) (xy 443.530505 -333.216011) (xy 443.477806 -333.208061) (xy 443.426881 -333.192347)
			(xy 443.378866 -333.169219) (xy 443.334835 -333.139193) (xy 443.29577 -333.102941) (xy 443.262543 -333.061271)
			(xy 443.235898 -333.015116) (xy 443.216429 -332.965504) (xy 443.204571 -332.913546) (xy 443.200588 -332.8604)
			(xy 404.955756 -332.8604) (xy 404.955756 -336.949288) (xy 406.094438 -338.08797) (xy 441.677298 -338.08797)
		)
		(stroke
			(width 0)
			(type solid)
		)
		(fill yes)
		(layer "B.Cu")
		(net "P12V_S3_AUX_CPU0_NVDIMM")
	)
	(gr_poly
		(pts
			(xy 364.86592 -219.46108) (xy 364.869841 -219.434274) (xy 364.884739 -219.38219) (xy 364.907352 -219.332963)
			(xy 364.937159 -219.287728) (xy 364.973473 -219.247528) (xy 365.015456 -219.213292) (xy 365.06214 -219.185808)
			(xy 365.112447 -219.165712) (xy 365.165218 -219.153465) (xy 365.219234 -219.149351) (xy 365.27325 -219.153465)
			(xy 365.326021 -219.165712) (xy 365.376328 -219.185808) (xy 365.423012 -219.213292) (xy 365.464995 -219.247528)
			(xy 365.501309 -219.287728) (xy 365.531116 -219.332963) (xy 365.553729 -219.38219) (xy 365.568627 -219.434274)
			(xy 365.572548 -219.46108) (xy 365.578136 -219.50553) (xy 365.800132 -219.50553) (xy 365.80572 -219.46108)
			(xy 365.809641 -219.434274) (xy 365.824539 -219.38219) (xy 365.847152 -219.332963) (xy 365.876959 -219.287728)
			(xy 365.913273 -219.247528) (xy 365.955256 -219.213292) (xy 366.00194 -219.185808) (xy 366.052247 -219.165712)
			(xy 366.105018 -219.153465) (xy 366.159034 -219.149351) (xy 366.21305 -219.153465) (xy 366.265821 -219.165712)
			(xy 366.316128 -219.185808) (xy 366.362812 -219.213292) (xy 366.404795 -219.247528) (xy 366.441109 -219.287728)
			(xy 366.470916 -219.332963) (xy 366.493529 -219.38219) (xy 366.508427 -219.434274) (xy 366.512348 -219.46108)
			(xy 366.517936 -219.50553) (xy 366.739932 -219.50553) (xy 366.74552 -219.46108) (xy 366.749441 -219.434274)
			(xy 366.764339 -219.38219) (xy 366.786952 -219.332963) (xy 366.816759 -219.287728) (xy 366.853073 -219.247528)
			(xy 366.895056 -219.213292) (xy 366.94174 -219.185808) (xy 366.992047 -219.165712) (xy 367.044818 -219.153465)
			(xy 367.098834 -219.149351) (xy 367.15285 -219.153465) (xy 367.205621 -219.165712) (xy 367.255928 -219.185808)
			(xy 367.302612 -219.213292) (xy 367.344595 -219.247528) (xy 367.380909 -219.287728) (xy 367.410716 -219.332963)
			(xy 367.433329 -219.38219) (xy 367.448227 -219.434274) (xy 367.452148 -219.46108) (xy 367.457736 -219.50553)
			(xy 367.679732 -219.50553) (xy 367.68532 -219.46108) (xy 367.689241 -219.434274) (xy 367.704139 -219.38219)
			(xy 367.726752 -219.332963) (xy 367.756559 -219.287728) (xy 367.792873 -219.247528) (xy 367.834856 -219.213292)
			(xy 367.88154 -219.185808) (xy 367.931847 -219.165712) (xy 367.984618 -219.153465) (xy 368.038634 -219.149351)
			(xy 368.09265 -219.153465) (xy 368.145421 -219.165712) (xy 368.195728 -219.185808) (xy 368.242412 -219.213292)
			(xy 368.284395 -219.247528) (xy 368.320709 -219.287728) (xy 368.350516 -219.332963) (xy 368.373129 -219.38219)
			(xy 368.388027 -219.434274) (xy 368.391948 -219.46108) (xy 368.397536 -219.50553) (xy 368.619532 -219.50553)
			(xy 368.62512 -219.46108) (xy 368.629041 -219.434274) (xy 368.643939 -219.38219) (xy 368.666552 -219.332963)
			(xy 368.696359 -219.287728) (xy 368.732673 -219.247528) (xy 368.774656 -219.213292) (xy 368.82134 -219.185808)
			(xy 368.871647 -219.165712) (xy 368.924418 -219.153465) (xy 368.978434 -219.149351) (xy 369.03245 -219.153465)
			(xy 369.085221 -219.165712) (xy 369.135528 -219.185808) (xy 369.182212 -219.213292) (xy 369.224195 -219.247528)
			(xy 369.260509 -219.287728) (xy 369.290316 -219.332963) (xy 369.312929 -219.38219) (xy 369.327827 -219.434274)
			(xy 369.331748 -219.46108) (xy 369.337336 -219.50553) (xy 369.559332 -219.50553) (xy 369.56492 -219.46108)
			(xy 369.568841 -219.434274) (xy 369.583739 -219.38219) (xy 369.606352 -219.332963) (xy 369.636159 -219.287728)
			(xy 369.672473 -219.247528) (xy 369.714456 -219.213292) (xy 369.76114 -219.185808) (xy 369.811447 -219.165712)
			(xy 369.864218 -219.153465) (xy 369.918234 -219.149351) (xy 369.97225 -219.153465) (xy 370.025021 -219.165712)
			(xy 370.075328 -219.185808) (xy 370.122012 -219.213292) (xy 370.163995 -219.247528) (xy 370.200309 -219.287728)
			(xy 370.230116 -219.332963) (xy 370.252729 -219.38219) (xy 370.267627 -219.434274) (xy 370.271548 -219.46108)
			(xy 370.277136 -219.50553) (xy 370.499132 -219.50553) (xy 370.50472 -219.46108) (xy 370.508641 -219.434274)
			(xy 370.523539 -219.38219) (xy 370.546152 -219.332963) (xy 370.575959 -219.287728) (xy 370.612273 -219.247528)
			(xy 370.654256 -219.213292) (xy 370.70094 -219.185808) (xy 370.751247 -219.165712) (xy 370.804018 -219.153465)
			(xy 370.858034 -219.149351) (xy 370.91205 -219.153465) (xy 370.964821 -219.165712) (xy 371.015128 -219.185808)
			(xy 371.061812 -219.213292) (xy 371.103795 -219.247528) (xy 371.140109 -219.287728) (xy 371.169916 -219.332963)
			(xy 371.192529 -219.38219) (xy 371.207427 -219.434274) (xy 371.211348 -219.46108) (xy 371.216936 -219.50553)
			(xy 371.438932 -219.50553) (xy 371.44452 -219.46108) (xy 371.448216 -219.435614) (xy 371.46199 -219.386034)
			(xy 371.482758 -219.338953) (xy 371.510088 -219.295353) (xy 371.543409 -219.256141) (xy 371.582029 -219.222135)
			(xy 371.625142 -219.194043) (xy 371.67185 -219.172451) (xy 371.721181 -219.157808) (xy 371.772105 -219.150419)
			(xy 371.797834 -219.14993) (xy 371.822036 -219.150337) (xy 371.869994 -219.15689) (xy 371.916625 -219.16987)
			(xy 371.961072 -219.189039) (xy 372.002517 -219.214044) (xy 372.021608 -219.228924) (xy 372.057947 -219.221072)
			(xy 372.131414 -219.209633) (xy 372.16842 -219.206064) (xy 372.186962 -219.204286) (xy 372.511828 -218.87942)
			(xy 372.75135 -218.87942) (xy 372.780134 -218.837828) (xy 372.844115 -218.759476) (xy 372.879112 -218.722956)
			(xy 372.877588 -218.692222) (xy 372.878052 -218.666875) (xy 372.885812 -218.61678) (xy 372.901153 -218.568464)
			(xy 372.923713 -218.523067) (xy 372.952959 -218.481661) (xy 372.988202 -218.445223) (xy 373.028609 -218.414612)
			(xy 373.073228 -218.39055) (xy 373.121006 -218.373606) (xy 373.145812 -218.368372) (xy 373.168672 -218.364054)
			(xy 373.373904 -218.008708) (xy 373.36603 -217.98661) (xy 373.357569 -217.960365) (xy 373.348508 -217.905976)
			(xy 373.347996 -217.878406) (xy 373.348504 -217.852519) (xy 373.356603 -217.801381) (xy 373.372602 -217.752141)
			(xy 373.396108 -217.706009) (xy 373.42654 -217.664122) (xy 373.46315 -217.627512) (xy 373.505037 -217.59708)
			(xy 373.551169 -217.573574) (xy 373.600409 -217.557575) (xy 373.651547 -217.549476) (xy 373.703321 -217.549476)
			(xy 373.754459 -217.557575) (xy 373.803699 -217.573574) (xy 373.849831 -217.59708) (xy 373.891718 -217.627512)
			(xy 373.928328 -217.664122) (xy 373.95876 -217.706009) (xy 373.982266 -217.752141) (xy 373.998265 -217.801381)
			(xy 374.006364 -217.852519) (xy 374.006872 -217.878406) (xy 374.006404 -217.90378) (xy 373.998624 -217.953929)
			(xy 373.983248 -218.002293) (xy 373.960641 -218.047728) (xy 373.931336 -218.08916) (xy 373.896026 -218.12561)
			(xy 373.855545 -218.156217) (xy 373.810852 -218.180257) (xy 373.763001 -218.197162) (xy 373.73814 -218.202256)
			(xy 373.71528 -218.206574) (xy 373.695976 -218.240102) (xy 373.689078 -218.252981) (xy 373.682216 -218.281368)
			(xy 373.683678 -218.310536) (xy 373.693342 -218.338096) (xy 373.710418 -218.361788) (xy 373.733506 -218.379673)
			(xy 373.760714 -218.390284) (xy 373.775224 -218.391994) (xy 373.82074 -218.396437) (xy 373.910898 -218.41182)
			(xy 373.95531 -218.422728) (xy 373.976435 -218.40829) (xy 374.022199 -218.385407) (xy 374.07094 -218.36984)
			(xy 374.121497 -218.361961) (xy 374.14708 -218.361514) (xy 374.172704 -218.361995) (xy 374.22334 -218.3699)
			(xy 374.272149 -218.385525) (xy 374.317962 -218.408496) (xy 374.339104 -218.422982) (xy 374.384709 -218.411753)
			(xy 374.477321 -218.396079) (xy 374.570921 -218.388235) (xy 374.66485 -218.388276) (xy 374.758444 -218.396201)
			(xy 374.851042 -218.411956) (xy 374.896634 -218.423236) (xy 374.915191 -218.410526) (xy 374.955082 -218.389749)
			(xy 374.976136 -218.381834) (xy 374.986804 -218.378024) (xy 375.043954 -218.320874) (xy 375.043954 -218.161362)
			(xy 375.043464 -218.147669) (xy 375.036098 -218.121289) (xy 375.021986 -218.097816) (xy 375.002144 -218.078937)
			(xy 374.977998 -218.066009) (xy 374.951285 -218.059963) (xy 374.923925 -218.061234) (xy 374.897887 -218.069729)
			(xy 374.875043 -218.084839) (xy 374.865646 -218.094814) (xy 374.846717 -218.115671) (xy 374.803044 -218.15123)
			(xy 374.753959 -218.178844) (xy 374.700894 -218.197709) (xy 374.645394 -218.207275) (xy 374.617234 -218.207844)
			(xy 374.591343 -218.207365) (xy 374.540197 -218.19927) (xy 374.490947 -218.183272) (xy 374.444807 -218.159767)
			(xy 374.402911 -218.129333) (xy 374.366293 -218.092719) (xy 374.335854 -218.050828) (xy 374.312343 -218.00469)
			(xy 374.29634 -217.955442) (xy 374.288238 -217.904297) (xy 374.287796 -217.878406) (xy 374.288325 -217.850698)
			(xy 374.297525 -217.796052) (xy 374.306084 -217.769694) (xy 374.313958 -217.747596) (xy 374.10898 -217.392504)
			(xy 374.08612 -217.388186) (xy 374.061266 -217.383052) (xy 374.013408 -217.366165) (xy 373.968707 -217.342138)
			(xy 373.928219 -217.311539) (xy 373.892903 -217.275093) (xy 373.863594 -217.233662) (xy 373.840986 -217.188227)
			(xy 373.825613 -217.139862) (xy 373.81784 -217.089711) (xy 373.817388 -217.064336) (xy 373.817896 -217.038429)
			(xy 373.826002 -216.987252) (xy 373.842014 -216.937973) (xy 373.865537 -216.891806) (xy 373.895993 -216.849887)
			(xy 373.932631 -216.813249) (xy 373.97455 -216.782793) (xy 374.020717 -216.75927) (xy 374.069996 -216.743258)
			(xy 374.121173 -216.735152) (xy 374.172987 -216.735152) (xy 374.224164 -216.743258) (xy 374.273443 -216.75927)
			(xy 374.31961 -216.782793) (xy 374.361529 -216.813249) (xy 374.398167 -216.849887) (xy 374.428623 -216.891806)
			(xy 374.452146 -216.937973) (xy 374.468158 -216.987252) (xy 374.476264 -217.038429) (xy 374.476772 -217.064336)
			(xy 374.476169 -217.091991) (xy 374.466852 -217.146511) (xy 374.45823 -217.172794) (xy 374.45061 -217.194892)
			(xy 374.655842 -217.550238) (xy 374.678702 -217.554556) (xy 374.703522 -217.559735) (xy 374.751299 -217.576702)
			(xy 374.79591 -217.600794) (xy 374.8363 -217.63144) (xy 374.871514 -217.667916) (xy 374.900719 -217.70936)
			(xy 374.923225 -217.754791) (xy 374.938499 -217.803136) (xy 374.942862 -217.828114) (xy 374.949466 -217.871294)
			(xy 375.043954 -217.871294) (xy 375.043954 -217.59799) (xy 375.038112 -217.586814) (xy 375.018134 -217.548097)
			(xy 374.983552 -217.468122) (xy 374.969024 -217.427048) (xy 374.942579 -217.417917) (xy 374.892487 -217.393005)
			(xy 374.84657 -217.361044) (xy 374.805813 -217.322721) (xy 374.771089 -217.278856) (xy 374.743144 -217.23039)
			(xy 374.722577 -217.178362) (xy 374.709828 -217.123889) (xy 374.705172 -217.068138) (xy 374.708707 -217.012305)
			(xy 374.714008 -216.984834) (xy 374.685951 -216.95203) (xy 374.634401 -216.882781) (xy 374.588347 -216.809763)
			(xy 374.548063 -216.733409) (xy 374.513787 -216.654176) (xy 374.499378 -216.613486) (xy 374.4727 -216.60427)
			(xy 374.422187 -216.579093) (xy 374.375931 -216.546752) (xy 374.334942 -216.507952) (xy 374.300113 -216.46354)
			(xy 374.272203 -216.414483) (xy 374.251821 -216.361852) (xy 374.239411 -216.306792) (xy 374.235243 -216.250506)
			(xy 374.239409 -216.19422) (xy 374.251817 -216.13916) (xy 374.272198 -216.086528) (xy 374.300106 -216.037471)
			(xy 374.334934 -215.993057) (xy 374.375922 -215.954256) (xy 374.422176 -215.921914) (xy 374.472689 -215.896734)
			(xy 374.499378 -215.887554) (xy 374.515499 -215.842147) (xy 374.554508 -215.754035) (xy 374.600949 -215.669603)
			(xy 374.654478 -215.589478) (xy 374.714699 -215.514252) (xy 374.781165 -215.444483) (xy 374.853385 -215.380688)
			(xy 374.891808 -215.351614) (xy 374.91162 -215.337136) (xy 374.91289 -215.304116) (xy 374.91289 -215.300814)
			(xy 374.914674 -215.263822) (xy 374.923333 -215.190262) (xy 374.937739 -215.11761) (xy 374.947434 -215.081866)
			(xy 374.949212 -215.075008) (xy 374.949212 -214.749634) (xy 374.676924 -214.477346) (xy 369.524788 -214.477346)
			(xy 369.410488 -214.3633) (xy 369.39982 -214.3633) (xy 368.953796 -213.917022) (xy 368.953796 -213.504018)
			(xy 369.2398 -213.218014) (xy 369.2398 -209.617564) (xy 369.050062 -209.427826) (xy 366.48517 -209.427826)
			(xy 366.410494 -209.502502) (xy 366.410494 -212.900514) (xy 365.957104 -213.353904) (xy 365.946531 -213.365234)
			(xy 365.932174 -213.392681) (xy 365.926695 -213.423167) (xy 365.930597 -213.453895) (xy 365.943522 -213.482044)
			(xy 365.953548 -213.493858) (xy 365.9707 -213.513564) (xy 365.999643 -213.557057) (xy 366.021922 -213.604311)
			(xy 366.037061 -213.654313) (xy 366.044734 -213.705989) (xy 366.045242 -213.73211) (xy 366.045242 -213.732618)
			(xy 366.044718 -213.759267) (xy 367.213124 -213.759267) (xy 367.213124 -213.705969) (xy 367.221067 -213.653265)
			(xy 367.236777 -213.602335) (xy 367.259903 -213.554314) (xy 367.289927 -213.510277) (xy 367.326179 -213.471206)
			(xy 367.36785 -213.437975) (xy 367.414008 -213.411326) (xy 367.463622 -213.391854) (xy 367.515584 -213.379994)
			(xy 367.568734 -213.376011) (xy 367.621884 -213.379994) (xy 367.673846 -213.391854) (xy 367.72346 -213.411326)
			(xy 367.769618 -213.437975) (xy 367.811289 -213.471206) (xy 367.847541 -213.510277) (xy 367.877565 -213.554314)
			(xy 367.900691 -213.602335) (xy 367.916401 -213.653265) (xy 367.924344 -213.705969) (xy 367.924842 -213.732618)
			(xy 367.924344 -213.759267) (xy 367.916401 -213.811971) (xy 367.900691 -213.862901) (xy 367.877565 -213.910922)
			(xy 367.847541 -213.954959) (xy 367.811289 -213.99403) (xy 367.769618 -214.027261) (xy 367.72346 -214.05391)
			(xy 367.673846 -214.073382) (xy 367.621884 -214.085242) (xy 367.568734 -214.089226) (xy 367.515584 -214.085242)
			(xy 367.463622 -214.073382) (xy 367.414008 -214.05391) (xy 367.36785 -214.027261) (xy 367.326179 -213.99403)
			(xy 367.289927 -213.954959) (xy 367.259903 -213.910922) (xy 367.236777 -213.862901) (xy 367.221067 -213.811971)
			(xy 367.213124 -213.759267) (xy 366.044718 -213.759267) (xy 366.044692 -213.760601) (xy 366.035935 -213.815878)
			(xy 366.018639 -213.869105) (xy 365.99323 -213.918971) (xy 365.960335 -213.964249) (xy 365.920761 -214.003824)
			(xy 365.875485 -214.036722) (xy 365.82562 -214.062133) (xy 365.772394 -214.079431) (xy 365.717117 -214.08819)
			(xy 365.689134 -214.088726) (xy 365.688626 -214.088726) (xy 365.662504 -214.088246) (xy 365.610828 -214.080569)
			(xy 365.560829 -214.065421) (xy 365.513581 -214.043126) (xy 365.4701 -214.014163) (xy 365.450374 -213.997032)
			(xy 365.438514 -213.987079) (xy 365.410381 -213.974185) (xy 365.37968 -213.970291) (xy 365.349219 -213.975752)
			(xy 365.321782 -213.990068) (xy 365.31042 -214.000588) (xy 364.454694 -214.856314) (xy 364.454694 -215.650826)
			(xy 364.579916 -215.776048) (xy 365.477044 -215.776048) (xy 365.529622 -215.828626) (xy 365.775494 -215.828626)
			(xy 365.907574 -215.960706) (xy 365.942372 -215.936576) (xy 365.966387 -215.920633) (xy 366.018205 -215.895388)
			(xy 366.073232 -215.878229) (xy 366.130214 -215.869545) (xy 366.159034 -215.869012) (xy 366.186283 -215.869501)
			(xy 366.240226 -215.877261) (xy 366.292515 -215.892619) (xy 366.342087 -215.915263) (xy 366.387932 -215.94473)
			(xy 366.429116 -215.980422) (xy 366.464802 -216.021612) (xy 366.494263 -216.06746) (xy 366.516899 -216.117035)
			(xy 366.53225 -216.169327) (xy 366.540003 -216.223271) (xy 366.540542 -216.25052) (xy 366.540095 -216.277169)
			(xy 366.743224 -216.277169) (xy 366.743224 -216.223871) (xy 366.751167 -216.171167) (xy 366.766877 -216.120237)
			(xy 366.790003 -216.072216) (xy 366.820027 -216.028179) (xy 366.856279 -215.989108) (xy 366.89795 -215.955877)
			(xy 366.944108 -215.929228) (xy 366.993722 -215.909756) (xy 367.045684 -215.897896) (xy 367.098834 -215.893913)
			(xy 367.151984 -215.897896) (xy 367.203946 -215.909756) (xy 367.25356 -215.929228) (xy 367.299718 -215.955877)
			(xy 367.341389 -215.989108) (xy 367.377641 -216.028179) (xy 367.407665 -216.072216) (xy 367.430791 -216.120237)
			(xy 367.446501 -216.171167) (xy 367.454444 -216.223871) (xy 367.454942 -216.25052) (xy 367.454444 -216.277169)
			(xy 367.683024 -216.277169) (xy 367.683024 -216.223871) (xy 367.690967 -216.171167) (xy 367.706677 -216.120237)
			(xy 367.729803 -216.072216) (xy 367.759827 -216.028179) (xy 367.796079 -215.989108) (xy 367.83775 -215.955877)
			(xy 367.883908 -215.929228) (xy 367.933522 -215.909756) (xy 367.985484 -215.897896) (xy 368.038634 -215.893913)
			(xy 368.091784 -215.897896) (xy 368.143746 -215.909756) (xy 368.19336 -215.929228) (xy 368.239518 -215.955877)
			(xy 368.281189 -215.989108) (xy 368.317441 -216.028179) (xy 368.347465 -216.072216) (xy 368.370591 -216.120237)
			(xy 368.386301 -216.171167) (xy 368.394244 -216.223871) (xy 368.394742 -216.25052) (xy 368.394244 -216.277169)
			(xy 368.622824 -216.277169) (xy 368.622824 -216.223871) (xy 368.630767 -216.171167) (xy 368.646477 -216.120237)
			(xy 368.669603 -216.072216) (xy 368.699627 -216.028179) (xy 368.735879 -215.989108) (xy 368.77755 -215.955877)
			(xy 368.823708 -215.929228) (xy 368.873322 -215.909756) (xy 368.925284 -215.897896) (xy 368.978434 -215.893913)
			(xy 369.031584 -215.897896) (xy 369.083546 -215.909756) (xy 369.13316 -215.929228) (xy 369.179318 -215.955877)
			(xy 369.220989 -215.989108) (xy 369.257241 -216.028179) (xy 369.287265 -216.072216) (xy 369.310391 -216.120237)
			(xy 369.326101 -216.171167) (xy 369.334044 -216.223871) (xy 369.334542 -216.25052) (xy 369.334044 -216.277169)
			(xy 369.562624 -216.277169) (xy 369.562624 -216.223871) (xy 369.570567 -216.171167) (xy 369.586277 -216.120237)
			(xy 369.609403 -216.072216) (xy 369.639427 -216.028179) (xy 369.675679 -215.989108) (xy 369.71735 -215.955877)
			(xy 369.763508 -215.929228) (xy 369.813122 -215.909756) (xy 369.865084 -215.897896) (xy 369.918234 -215.893913)
			(xy 369.971384 -215.897896) (xy 370.023346 -215.909756) (xy 370.07296 -215.929228) (xy 370.119118 -215.955877)
			(xy 370.160789 -215.989108) (xy 370.197041 -216.028179) (xy 370.227065 -216.072216) (xy 370.250191 -216.120237)
			(xy 370.265901 -216.171167) (xy 370.273844 -216.223871) (xy 370.274342 -216.25052) (xy 370.273844 -216.277169)
			(xy 370.502424 -216.277169) (xy 370.502424 -216.223871) (xy 370.510367 -216.171167) (xy 370.526077 -216.120237)
			(xy 370.549203 -216.072216) (xy 370.579227 -216.028179) (xy 370.615479 -215.989108) (xy 370.65715 -215.955877)
			(xy 370.703308 -215.929228) (xy 370.752922 -215.909756) (xy 370.804884 -215.897896) (xy 370.858034 -215.893913)
			(xy 370.911184 -215.897896) (xy 370.963146 -215.909756) (xy 371.01276 -215.929228) (xy 371.058918 -215.955877)
			(xy 371.100589 -215.989108) (xy 371.136841 -216.028179) (xy 371.166865 -216.072216) (xy 371.189991 -216.120237)
			(xy 371.205701 -216.171167) (xy 371.213644 -216.223871) (xy 371.214142 -216.25052) (xy 371.213644 -216.277169)
			(xy 371.442224 -216.277169) (xy 371.442224 -216.223871) (xy 371.450167 -216.171167) (xy 371.465877 -216.120237)
			(xy 371.489003 -216.072216) (xy 371.519027 -216.028179) (xy 371.555279 -215.989108) (xy 371.59695 -215.955877)
			(xy 371.643108 -215.929228) (xy 371.692722 -215.909756) (xy 371.744684 -215.897896) (xy 371.797834 -215.893913)
			(xy 371.850984 -215.897896) (xy 371.902946 -215.909756) (xy 371.95256 -215.929228) (xy 371.998718 -215.955877)
			(xy 372.040389 -215.989108) (xy 372.076641 -216.028179) (xy 372.106665 -216.072216) (xy 372.129791 -216.120237)
			(xy 372.145501 -216.171167) (xy 372.153444 -216.223871) (xy 372.153942 -216.25052) (xy 372.153444 -216.277169)
			(xy 372.382024 -216.277169) (xy 372.382024 -216.223871) (xy 372.389967 -216.171167) (xy 372.405677 -216.120237)
			(xy 372.428803 -216.072216) (xy 372.458827 -216.028179) (xy 372.495079 -215.989108) (xy 372.53675 -215.955877)
			(xy 372.582908 -215.929228) (xy 372.632522 -215.909756) (xy 372.684484 -215.897896) (xy 372.737634 -215.893913)
			(xy 372.790784 -215.897896) (xy 372.842746 -215.909756) (xy 372.89236 -215.929228) (xy 372.938518 -215.955877)
			(xy 372.980189 -215.989108) (xy 373.016441 -216.028179) (xy 373.046465 -216.072216) (xy 373.069591 -216.120237)
			(xy 373.085301 -216.171167) (xy 373.093244 -216.223871) (xy 373.093742 -216.25052) (xy 373.093244 -216.277169)
			(xy 373.321824 -216.277169) (xy 373.321824 -216.223871) (xy 373.329767 -216.171167) (xy 373.345477 -216.120237)
			(xy 373.368603 -216.072216) (xy 373.398627 -216.028179) (xy 373.434879 -215.989108) (xy 373.47655 -215.955877)
			(xy 373.522708 -215.929228) (xy 373.572322 -215.909756) (xy 373.624284 -215.897896) (xy 373.677434 -215.893913)
			(xy 373.730584 -215.897896) (xy 373.782546 -215.909756) (xy 373.83216 -215.929228) (xy 373.878318 -215.955877)
			(xy 373.919989 -215.989108) (xy 373.956241 -216.028179) (xy 373.986265 -216.072216) (xy 374.009391 -216.120237)
			(xy 374.025101 -216.171167) (xy 374.033044 -216.223871) (xy 374.033542 -216.25052) (xy 374.033044 -216.277169)
			(xy 374.025101 -216.329873) (xy 374.009391 -216.380803) (xy 373.986265 -216.428824) (xy 373.956241 -216.472861)
			(xy 373.919989 -216.511932) (xy 373.878318 -216.545163) (xy 373.83216 -216.571812) (xy 373.782546 -216.591284)
			(xy 373.730584 -216.603144) (xy 373.677434 -216.607128) (xy 373.624284 -216.603144) (xy 373.572322 -216.591284)
			(xy 373.522708 -216.571812) (xy 373.47655 -216.545163) (xy 373.434879 -216.511932) (xy 373.398627 -216.472861)
			(xy 373.368603 -216.428824) (xy 373.345477 -216.380803) (xy 373.329767 -216.329873) (xy 373.321824 -216.277169)
			(xy 373.093244 -216.277169) (xy 373.085301 -216.329873) (xy 373.069591 -216.380803) (xy 373.046465 -216.428824)
			(xy 373.016441 -216.472861) (xy 372.980189 -216.511932) (xy 372.938518 -216.545163) (xy 372.89236 -216.571812)
			(xy 372.842746 -216.591284) (xy 372.790784 -216.603144) (xy 372.737634 -216.607128) (xy 372.684484 -216.603144)
			(xy 372.632522 -216.591284) (xy 372.582908 -216.571812) (xy 372.53675 -216.545163) (xy 372.495079 -216.511932)
			(xy 372.458827 -216.472861) (xy 372.428803 -216.428824) (xy 372.405677 -216.380803) (xy 372.389967 -216.329873)
			(xy 372.382024 -216.277169) (xy 372.153444 -216.277169) (xy 372.145501 -216.329873) (xy 372.129791 -216.380803)
			(xy 372.106665 -216.428824) (xy 372.076641 -216.472861) (xy 372.040389 -216.511932) (xy 371.998718 -216.545163)
			(xy 371.95256 -216.571812) (xy 371.902946 -216.591284) (xy 371.850984 -216.603144) (xy 371.797834 -216.607128)
			(xy 371.744684 -216.603144) (xy 371.692722 -216.591284) (xy 371.643108 -216.571812) (xy 371.59695 -216.545163)
			(xy 371.555279 -216.511932) (xy 371.519027 -216.472861) (xy 371.489003 -216.428824) (xy 371.465877 -216.380803)
			(xy 371.450167 -216.329873) (xy 371.442224 -216.277169) (xy 371.213644 -216.277169) (xy 371.205701 -216.329873)
			(xy 371.189991 -216.380803) (xy 371.166865 -216.428824) (xy 371.136841 -216.472861) (xy 371.100589 -216.511932)
			(xy 371.058918 -216.545163) (xy 371.01276 -216.571812) (xy 370.963146 -216.591284) (xy 370.911184 -216.603144)
			(xy 370.858034 -216.607128) (xy 370.804884 -216.603144) (xy 370.752922 -216.591284) (xy 370.703308 -216.571812)
			(xy 370.65715 -216.545163) (xy 370.615479 -216.511932) (xy 370.579227 -216.472861) (xy 370.549203 -216.428824)
			(xy 370.526077 -216.380803) (xy 370.510367 -216.329873) (xy 370.502424 -216.277169) (xy 370.273844 -216.277169)
			(xy 370.265901 -216.329873) (xy 370.250191 -216.380803) (xy 370.227065 -216.428824) (xy 370.197041 -216.472861)
			(xy 370.160789 -216.511932) (xy 370.119118 -216.545163) (xy 370.07296 -216.571812) (xy 370.023346 -216.591284)
			(xy 369.971384 -216.603144) (xy 369.918234 -216.607128) (xy 369.865084 -216.603144) (xy 369.813122 -216.591284)
			(xy 369.763508 -216.571812) (xy 369.71735 -216.545163) (xy 369.675679 -216.511932) (xy 369.639427 -216.472861)
			(xy 369.609403 -216.428824) (xy 369.586277 -216.380803) (xy 369.570567 -216.329873) (xy 369.562624 -216.277169)
			(xy 369.334044 -216.277169) (xy 369.326101 -216.329873) (xy 369.310391 -216.380803) (xy 369.287265 -216.428824)
			(xy 369.257241 -216.472861) (xy 369.220989 -216.511932) (xy 369.179318 -216.545163) (xy 369.13316 -216.571812)
			(xy 369.083546 -216.591284) (xy 369.031584 -216.603144) (xy 368.978434 -216.607128) (xy 368.925284 -216.603144)
			(xy 368.873322 -216.591284) (xy 368.823708 -216.571812) (xy 368.77755 -216.545163) (xy 368.735879 -216.511932)
			(xy 368.699627 -216.472861) (xy 368.669603 -216.428824) (xy 368.646477 -216.380803) (xy 368.630767 -216.329873)
			(xy 368.622824 -216.277169) (xy 368.394244 -216.277169) (xy 368.386301 -216.329873) (xy 368.370591 -216.380803)
			(xy 368.347465 -216.428824) (xy 368.317441 -216.472861) (xy 368.281189 -216.511932) (xy 368.239518 -216.545163)
			(xy 368.19336 -216.571812) (xy 368.143746 -216.591284) (xy 368.091784 -216.603144) (xy 368.038634 -216.607128)
			(xy 367.985484 -216.603144) (xy 367.933522 -216.591284) (xy 367.883908 -216.571812) (xy 367.83775 -216.545163)
			(xy 367.796079 -216.511932) (xy 367.759827 -216.472861) (xy 367.729803 -216.428824) (xy 367.706677 -216.380803)
			(xy 367.690967 -216.329873) (xy 367.683024 -216.277169) (xy 367.454444 -216.277169) (xy 367.446501 -216.329873)
			(xy 367.430791 -216.380803) (xy 367.407665 -216.428824) (xy 367.377641 -216.472861) (xy 367.341389 -216.511932)
			(xy 367.299718 -216.545163) (xy 367.25356 -216.571812) (xy 367.203946 -216.591284) (xy 367.151984 -216.603144)
			(xy 367.098834 -216.607128) (xy 367.045684 -216.603144) (xy 366.993722 -216.591284) (xy 366.944108 -216.571812)
			(xy 366.89795 -216.545163) (xy 366.856279 -216.511932) (xy 366.820027 -216.472861) (xy 366.790003 -216.428824)
			(xy 366.766877 -216.380803) (xy 366.751167 -216.329873) (xy 366.743224 -216.277169) (xy 366.540095 -216.277169)
			(xy 366.540094 -216.277216) (xy 366.532648 -216.330086) (xy 366.517903 -216.381402) (xy 366.496148 -216.430161)
			(xy 366.467807 -216.475411) (xy 366.433435 -216.516267) (xy 366.393702 -216.551933) (xy 366.349385 -216.58171)
			(xy 366.301349 -216.605018) (xy 366.250533 -216.621402) (xy 366.224312 -216.62644) (xy 366.182148 -216.633806)
			(xy 366.182148 -217.064336) (xy 366.298988 -217.064336) (xy 366.299496 -217.038429) (xy 366.307602 -216.987252)
			(xy 366.323614 -216.937973) (xy 366.347137 -216.891806) (xy 366.377593 -216.849887) (xy 366.414231 -216.813249)
			(xy 366.45615 -216.782793) (xy 366.502317 -216.75927) (xy 366.551596 -216.743258) (xy 366.602773 -216.735152)
			(xy 366.654587 -216.735152) (xy 366.705764 -216.743258) (xy 366.755043 -216.75927) (xy 366.80121 -216.782793)
			(xy 366.843129 -216.813249) (xy 366.879767 -216.849887) (xy 366.910223 -216.891806) (xy 366.933746 -216.937973)
			(xy 366.949758 -216.987252) (xy 366.957864 -217.038429) (xy 366.958372 -217.064336) (xy 366.957781 -217.090985)
			(xy 367.213124 -217.090985) (xy 367.213124 -217.037687) (xy 367.221067 -216.984983) (xy 367.236777 -216.934053)
			(xy 367.259903 -216.886032) (xy 367.289927 -216.841995) (xy 367.326179 -216.802924) (xy 367.36785 -216.769693)
			(xy 367.414008 -216.743044) (xy 367.463622 -216.723572) (xy 367.515584 -216.711712) (xy 367.568734 -216.707729)
			(xy 367.621884 -216.711712) (xy 367.673846 -216.723572) (xy 367.72346 -216.743044) (xy 367.769618 -216.769693)
			(xy 367.811289 -216.802924) (xy 367.847541 -216.841995) (xy 367.877565 -216.886032) (xy 367.900691 -216.934053)
			(xy 367.916401 -216.984983) (xy 367.924344 -217.037687) (xy 367.924842 -217.064336) (xy 368.178588 -217.064336)
			(xy 368.179096 -217.038429) (xy 368.187202 -216.987252) (xy 368.203214 -216.937973) (xy 368.226737 -216.891806)
			(xy 368.257193 -216.849887) (xy 368.293831 -216.813249) (xy 368.33575 -216.782793) (xy 368.381917 -216.75927)
			(xy 368.431196 -216.743258) (xy 368.482373 -216.735152) (xy 368.534187 -216.735152) (xy 368.585364 -216.743258)
			(xy 368.634643 -216.75927) (xy 368.68081 -216.782793) (xy 368.722729 -216.813249) (xy 368.759367 -216.849887)
			(xy 368.789823 -216.891806) (xy 368.813346 -216.937973) (xy 368.829358 -216.987252) (xy 368.837464 -217.038429)
			(xy 368.837972 -217.064336) (xy 368.837381 -217.090985) (xy 369.092724 -217.090985) (xy 369.092724 -217.037687)
			(xy 369.100667 -216.984983) (xy 369.116377 -216.934053) (xy 369.139503 -216.886032) (xy 369.169527 -216.841995)
			(xy 369.205779 -216.802924) (xy 369.24745 -216.769693) (xy 369.293608 -216.743044) (xy 369.343222 -216.723572)
			(xy 369.395184 -216.711712) (xy 369.448334 -216.707729) (xy 369.501484 -216.711712) (xy 369.553446 -216.723572)
			(xy 369.60306 -216.743044) (xy 369.649218 -216.769693) (xy 369.690889 -216.802924) (xy 369.727141 -216.841995)
			(xy 369.757165 -216.886032) (xy 369.780291 -216.934053) (xy 369.796001 -216.984983) (xy 369.803944 -217.037687)
			(xy 369.804442 -217.064336) (xy 370.058188 -217.064336) (xy 370.058696 -217.038429) (xy 370.066802 -216.987252)
			(xy 370.082814 -216.937973) (xy 370.106337 -216.891806) (xy 370.136793 -216.849887) (xy 370.173431 -216.813249)
			(xy 370.21535 -216.782793) (xy 370.261517 -216.75927) (xy 370.310796 -216.743258) (xy 370.361973 -216.735152)
			(xy 370.413787 -216.735152) (xy 370.464964 -216.743258) (xy 370.514243 -216.75927) (xy 370.56041 -216.782793)
			(xy 370.602329 -216.813249) (xy 370.638967 -216.849887) (xy 370.669423 -216.891806) (xy 370.692946 -216.937973)
			(xy 370.708958 -216.987252) (xy 370.717064 -217.038429) (xy 370.717572 -217.064336) (xy 370.716981 -217.090985)
			(xy 370.972324 -217.090985) (xy 370.972324 -217.037687) (xy 370.980267 -216.984983) (xy 370.995977 -216.934053)
			(xy 371.019103 -216.886032) (xy 371.049127 -216.841995) (xy 371.085379 -216.802924) (xy 371.12705 -216.769693)
			(xy 371.173208 -216.743044) (xy 371.222822 -216.723572) (xy 371.274784 -216.711712) (xy 371.327934 -216.707729)
			(xy 371.381084 -216.711712) (xy 371.433046 -216.723572) (xy 371.48266 -216.743044) (xy 371.528818 -216.769693)
			(xy 371.570489 -216.802924) (xy 371.606741 -216.841995) (xy 371.636765 -216.886032) (xy 371.659891 -216.934053)
			(xy 371.675601 -216.984983) (xy 371.683544 -217.037687) (xy 371.684042 -217.064336) (xy 371.937788 -217.064336)
			(xy 371.938296 -217.038429) (xy 371.946402 -216.987252) (xy 371.962414 -216.937973) (xy 371.985937 -216.891806)
			(xy 372.016393 -216.849887) (xy 372.053031 -216.813249) (xy 372.09495 -216.782793) (xy 372.141117 -216.75927)
			(xy 372.190396 -216.743258) (xy 372.241573 -216.735152) (xy 372.293387 -216.735152) (xy 372.344564 -216.743258)
			(xy 372.393843 -216.75927) (xy 372.44001 -216.782793) (xy 372.481929 -216.813249) (xy 372.518567 -216.849887)
			(xy 372.549023 -216.891806) (xy 372.572546 -216.937973) (xy 372.588558 -216.987252) (xy 372.596664 -217.038429)
			(xy 372.597172 -217.064336) (xy 372.596581 -217.090985) (xy 372.851924 -217.090985) (xy 372.851924 -217.037687)
			(xy 372.859867 -216.984983) (xy 372.875577 -216.934053) (xy 372.898703 -216.886032) (xy 372.928727 -216.841995)
			(xy 372.964979 -216.802924) (xy 373.00665 -216.769693) (xy 373.052808 -216.743044) (xy 373.102422 -216.723572)
			(xy 373.154384 -216.711712) (xy 373.207534 -216.707729) (xy 373.260684 -216.711712) (xy 373.312646 -216.723572)
			(xy 373.36226 -216.743044) (xy 373.408418 -216.769693) (xy 373.450089 -216.802924) (xy 373.486341 -216.841995)
			(xy 373.516365 -216.886032) (xy 373.539491 -216.934053) (xy 373.555201 -216.984983) (xy 373.563144 -217.037687)
			(xy 373.563642 -217.064336) (xy 373.563144 -217.090985) (xy 373.555201 -217.143689) (xy 373.539491 -217.194619)
			(xy 373.516365 -217.24264) (xy 373.486341 -217.286677) (xy 373.450089 -217.325748) (xy 373.408418 -217.358979)
			(xy 373.36226 -217.385628) (xy 373.312646 -217.4051) (xy 373.260684 -217.41696) (xy 373.207534 -217.420944)
			(xy 373.154384 -217.41696) (xy 373.102422 -217.4051) (xy 373.052808 -217.385628) (xy 373.00665 -217.358979)
			(xy 372.964979 -217.325748) (xy 372.928727 -217.286677) (xy 372.898703 -217.24264) (xy 372.875577 -217.194619)
			(xy 372.859867 -217.143689) (xy 372.851924 -217.090985) (xy 372.596581 -217.090985) (xy 372.596559 -217.091989)
			(xy 372.587238 -217.146507) (xy 372.57863 -217.172794) (xy 372.57101 -217.194892) (xy 372.776242 -217.550238)
			(xy 372.799102 -217.554556) (xy 372.823903 -217.559751) (xy 372.871642 -217.57674) (xy 372.916219 -217.600833)
			(xy 372.956584 -217.631463) (xy 372.991788 -217.667908) (xy 373.021 -217.709312) (xy 373.043533 -217.754697)
			(xy 373.058856 -217.802996) (xy 373.066608 -217.85307) (xy 373.067072 -217.878406) (xy 373.066564 -217.904293)
			(xy 373.058465 -217.955431) (xy 373.042466 -218.004671) (xy 373.01896 -218.050803) (xy 372.988528 -218.09269)
			(xy 372.951918 -218.1293) (xy 372.910031 -218.159732) (xy 372.863899 -218.183238) (xy 372.814659 -218.199237)
			(xy 372.763521 -218.207336) (xy 372.711747 -218.207336) (xy 372.660609 -218.199237) (xy 372.611369 -218.183238)
			(xy 372.565237 -218.159732) (xy 372.52335 -218.1293) (xy 372.48674 -218.09269) (xy 372.456308 -218.050803)
			(xy 372.432802 -218.004671) (xy 372.416803 -217.955431) (xy 372.408704 -217.904293) (xy 372.408196 -217.878406)
			(xy 372.408727 -217.850698) (xy 372.417921 -217.796051) (xy 372.426484 -217.769694) (xy 372.434358 -217.747596)
			(xy 372.22938 -217.392504) (xy 372.20652 -217.388186) (xy 372.181675 -217.38302) (xy 372.133826 -217.366126)
			(xy 372.089133 -217.342096) (xy 372.048653 -217.311499) (xy 372.013341 -217.275058) (xy 371.984033 -217.233634)
			(xy 371.961422 -217.188207) (xy 371.946043 -217.13985) (xy 371.938258 -217.089708) (xy 371.937788 -217.064336)
			(xy 371.684042 -217.064336) (xy 371.683544 -217.090985) (xy 371.675601 -217.143689) (xy 371.659891 -217.194619)
			(xy 371.636765 -217.24264) (xy 371.606741 -217.286677) (xy 371.570489 -217.325748) (xy 371.528818 -217.358979)
			(xy 371.48266 -217.385628) (xy 371.433046 -217.4051) (xy 371.381084 -217.41696) (xy 371.327934 -217.420944)
			(xy 371.274784 -217.41696) (xy 371.222822 -217.4051) (xy 371.173208 -217.385628) (xy 371.12705 -217.358979)
			(xy 371.085379 -217.325748) (xy 371.049127 -217.286677) (xy 371.019103 -217.24264) (xy 370.995977 -217.194619)
			(xy 370.980267 -217.143689) (xy 370.972324 -217.090985) (xy 370.716981 -217.090985) (xy 370.716959 -217.091989)
			(xy 370.707638 -217.146507) (xy 370.69903 -217.172794) (xy 370.69141 -217.194892) (xy 370.896642 -217.550238)
			(xy 370.919502 -217.554556) (xy 370.944303 -217.559751) (xy 370.992042 -217.57674) (xy 371.036619 -217.600833)
			(xy 371.076984 -217.631463) (xy 371.112188 -217.667908) (xy 371.1414 -217.709312) (xy 371.163933 -217.754697)
			(xy 371.179256 -217.802996) (xy 371.187008 -217.85307) (xy 371.187472 -217.878406) (xy 371.186964 -217.904293)
			(xy 371.178865 -217.955431) (xy 371.162866 -218.004671) (xy 371.13936 -218.050803) (xy 371.108928 -218.09269)
			(xy 371.072318 -218.1293) (xy 371.030431 -218.159732) (xy 370.984299 -218.183238) (xy 370.935059 -218.199237)
			(xy 370.883921 -218.207336) (xy 370.832147 -218.207336) (xy 370.781009 -218.199237) (xy 370.731769 -218.183238)
			(xy 370.685637 -218.159732) (xy 370.64375 -218.1293) (xy 370.60714 -218.09269) (xy 370.576708 -218.050803)
			(xy 370.553202 -218.004671) (xy 370.537203 -217.955431) (xy 370.529104 -217.904293) (xy 370.528596 -217.878406)
			(xy 370.529127 -217.850698) (xy 370.538321 -217.796051) (xy 370.546884 -217.769694) (xy 370.554758 -217.747596)
			(xy 370.34978 -217.392504) (xy 370.32692 -217.388186) (xy 370.302075 -217.38302) (xy 370.254226 -217.366126)
			(xy 370.209533 -217.342096) (xy 370.169053 -217.311499) (xy 370.133741 -217.275058) (xy 370.104433 -217.233634)
			(xy 370.081822 -217.188207) (xy 370.066443 -217.13985) (xy 370.058658 -217.089708) (xy 370.058188 -217.064336)
			(xy 369.804442 -217.064336) (xy 369.803944 -217.090985) (xy 369.796001 -217.143689) (xy 369.780291 -217.194619)
			(xy 369.757165 -217.24264) (xy 369.727141 -217.286677) (xy 369.690889 -217.325748) (xy 369.649218 -217.358979)
			(xy 369.60306 -217.385628) (xy 369.553446 -217.4051) (xy 369.501484 -217.41696) (xy 369.448334 -217.420944)
			(xy 369.395184 -217.41696) (xy 369.343222 -217.4051) (xy 369.293608 -217.385628) (xy 369.24745 -217.358979)
			(xy 369.205779 -217.325748) (xy 369.169527 -217.286677) (xy 369.139503 -217.24264) (xy 369.116377 -217.194619)
			(xy 369.100667 -217.143689) (xy 369.092724 -217.090985) (xy 368.837381 -217.090985) (xy 368.837359 -217.091989)
			(xy 368.828038 -217.146507) (xy 368.81943 -217.172794) (xy 368.81181 -217.194892) (xy 369.017042 -217.550238)
			(xy 369.039902 -217.554556) (xy 369.064703 -217.559751) (xy 369.112442 -217.57674) (xy 369.157019 -217.600833)
			(xy 369.197384 -217.631463) (xy 369.232588 -217.667908) (xy 369.2618 -217.709312) (xy 369.284333 -217.754697)
			(xy 369.299656 -217.802996) (xy 369.307408 -217.85307) (xy 369.307872 -217.878406) (xy 369.307364 -217.904293)
			(xy 369.299265 -217.955431) (xy 369.283266 -218.004671) (xy 369.25976 -218.050803) (xy 369.229328 -218.09269)
			(xy 369.192718 -218.1293) (xy 369.150831 -218.159732) (xy 369.104699 -218.183238) (xy 369.055459 -218.199237)
			(xy 369.004321 -218.207336) (xy 368.952547 -218.207336) (xy 368.901409 -218.199237) (xy 368.852169 -218.183238)
			(xy 368.806037 -218.159732) (xy 368.76415 -218.1293) (xy 368.72754 -218.09269) (xy 368.697108 -218.050803)
			(xy 368.673602 -218.004671) (xy 368.657603 -217.955431) (xy 368.649504 -217.904293) (xy 368.648996 -217.878406)
			(xy 368.649527 -217.850698) (xy 368.658721 -217.796051) (xy 368.667284 -217.769694) (xy 368.675158 -217.747596)
			(xy 368.47018 -217.392504) (xy 368.44732 -217.388186) (xy 368.422475 -217.38302) (xy 368.374626 -217.366126)
			(xy 368.329933 -217.342096) (xy 368.289453 -217.311499) (xy 368.254141 -217.275058) (xy 368.224833 -217.233634)
			(xy 368.202222 -217.188207) (xy 368.186843 -217.13985) (xy 368.179058 -217.089708) (xy 368.178588 -217.064336)
			(xy 367.924842 -217.064336) (xy 367.924344 -217.090985) (xy 367.916401 -217.143689) (xy 367.900691 -217.194619)
			(xy 367.877565 -217.24264) (xy 367.847541 -217.286677) (xy 367.811289 -217.325748) (xy 367.769618 -217.358979)
			(xy 367.72346 -217.385628) (xy 367.673846 -217.4051) (xy 367.621884 -217.41696) (xy 367.568734 -217.420944)
			(xy 367.515584 -217.41696) (xy 367.463622 -217.4051) (xy 367.414008 -217.385628) (xy 367.36785 -217.358979)
			(xy 367.326179 -217.325748) (xy 367.289927 -217.286677) (xy 367.259903 -217.24264) (xy 367.236777 -217.194619)
			(xy 367.221067 -217.143689) (xy 367.213124 -217.090985) (xy 366.957781 -217.090985) (xy 366.957759 -217.091989)
			(xy 366.948438 -217.146507) (xy 366.93983 -217.172794) (xy 366.93221 -217.194892) (xy 367.137442 -217.550238)
			(xy 367.160302 -217.554556) (xy 367.185103 -217.559751) (xy 367.232842 -217.57674) (xy 367.277419 -217.600833)
			(xy 367.317784 -217.631463) (xy 367.352988 -217.667908) (xy 367.3822 -217.709312) (xy 367.404733 -217.754697)
			(xy 367.420056 -217.802996) (xy 367.427808 -217.85307) (xy 367.428272 -217.878406) (xy 367.427764 -217.904293)
			(xy 367.419665 -217.955431) (xy 367.403666 -218.004671) (xy 367.38016 -218.050803) (xy 367.349728 -218.09269)
			(xy 367.313118 -218.1293) (xy 367.271231 -218.159732) (xy 367.225099 -218.183238) (xy 367.175859 -218.199237)
			(xy 367.124721 -218.207336) (xy 367.072947 -218.207336) (xy 367.021809 -218.199237) (xy 366.972569 -218.183238)
			(xy 366.926437 -218.159732) (xy 366.88455 -218.1293) (xy 366.84794 -218.09269) (xy 366.817508 -218.050803)
			(xy 366.794002 -218.004671) (xy 366.778003 -217.955431) (xy 366.769904 -217.904293) (xy 366.769396 -217.878406)
			(xy 366.769927 -217.850698) (xy 366.779121 -217.796051) (xy 366.787684 -217.769694) (xy 366.795558 -217.747596)
			(xy 366.59058 -217.392504) (xy 366.56772 -217.388186) (xy 366.542875 -217.38302) (xy 366.495026 -217.366126)
			(xy 366.450333 -217.342096) (xy 366.409853 -217.311499) (xy 366.374541 -217.275058) (xy 366.345233 -217.233634)
			(xy 366.322622 -217.188207) (xy 366.307243 -217.13985) (xy 366.299458 -217.089708) (xy 366.298988 -217.064336)
			(xy 366.182148 -217.064336) (xy 366.182148 -217.153744) (xy 365.723932 -217.61196) (xy 365.618268 -217.61196)
			(xy 365.510318 -217.71991) (xy 365.523272 -217.751406) (xy 365.531299 -217.771563) (xy 365.5426 -217.813452)
			(xy 365.548322 -217.856459) (xy 365.548672 -217.878152) (xy 365.548672 -217.878406) (xy 365.548164 -217.904293)
			(xy 365.540065 -217.955431) (xy 365.524066 -218.004671) (xy 365.50056 -218.050803) (xy 365.470128 -218.09269)
			(xy 365.433518 -218.1293) (xy 365.391631 -218.159732) (xy 365.345499 -218.183238) (xy 365.296259 -218.199237)
			(xy 365.245121 -218.207336) (xy 365.193347 -218.207336) (xy 365.142209 -218.199237) (xy 365.092969 -218.183238)
			(xy 365.046837 -218.159732) (xy 365.00495 -218.1293) (xy 364.96834 -218.09269) (xy 364.937908 -218.050803)
			(xy 364.914402 -218.004671) (xy 364.898403 -217.955431) (xy 364.890304 -217.904293) (xy 364.889796 -217.878406)
			(xy 364.89005 -217.863166) (xy 364.890259 -217.849445) (xy 364.884228 -217.822687) (xy 364.871287 -217.798502)
			(xy 364.852372 -217.778638) (xy 364.828849 -217.764529) (xy 364.802418 -217.757196) (xy 364.788704 -217.75674)
			(xy 364.709964 -217.75674) (xy 364.696261 -217.757229) (xy 364.669862 -217.764598) (xy 364.646369 -217.778715)
			(xy 364.62747 -217.798566) (xy 364.614524 -217.822725) (xy 364.608462 -217.849454) (xy 364.608618 -217.863166)
			(xy 364.608872 -217.878406) (xy 364.608404 -217.90378) (xy 364.600624 -217.953929) (xy 364.585248 -218.002293)
			(xy 364.562641 -218.047728) (xy 364.533336 -218.08916) (xy 364.498026 -218.12561) (xy 364.457545 -218.156217)
			(xy 364.412852 -218.180257) (xy 364.365001 -218.197162) (xy 364.34014 -218.202256) (xy 364.31728 -218.206574)
			(xy 364.161578 -218.476576) (xy 364.161578 -218.692222) (xy 365.359188 -218.692222) (xy 365.359739 -218.66688)
			(xy 365.367507 -218.616793) (xy 365.382848 -218.568485) (xy 365.405401 -218.523094) (xy 365.434634 -218.481689)
			(xy 365.469859 -218.445245) (xy 365.510246 -218.41462) (xy 365.554844 -218.390537) (xy 365.602602 -218.373561)
			(xy 365.627412 -218.368372) (xy 365.650272 -218.364054) (xy 365.855504 -218.008708) (xy 365.84763 -217.98661)
			(xy 365.839161 -217.960367) (xy 365.830092 -217.905977) (xy 365.829596 -217.878406) (xy 365.830104 -217.852519)
			(xy 365.838203 -217.801381) (xy 365.854202 -217.752141) (xy 365.877708 -217.706009) (xy 365.90814 -217.664122)
			(xy 365.94475 -217.627512) (xy 365.986637 -217.59708) (xy 366.032769 -217.573574) (xy 366.082009 -217.557575)
			(xy 366.133147 -217.549476) (xy 366.184921 -217.549476) (xy 366.236059 -217.557575) (xy 366.285299 -217.573574)
			(xy 366.331431 -217.59708) (xy 366.373318 -217.627512) (xy 366.409928 -217.664122) (xy 366.44036 -217.706009)
			(xy 366.463866 -217.752141) (xy 366.479865 -217.801381) (xy 366.487964 -217.852519) (xy 366.488472 -217.878406)
			(xy 366.488025 -217.903782) (xy 366.480255 -217.953934) (xy 366.464885 -218.002302) (xy 366.442277 -218.047739)
			(xy 366.412967 -218.089171) (xy 366.37765 -218.125617) (xy 366.33716 -218.156215) (xy 366.292456 -218.18024)
			(xy 366.244596 -218.197124) (xy 366.21974 -218.202256) (xy 366.19688 -218.206574) (xy 365.992156 -218.561412)
			(xy 366.00003 -218.583256) (xy 366.008681 -218.609663) (xy 366.017998 -218.66444) (xy 366.018572 -218.692222)
			(xy 367.238788 -218.692222) (xy 367.239339 -218.66688) (xy 367.247107 -218.616793) (xy 367.262448 -218.568485)
			(xy 367.285001 -218.523094) (xy 367.314234 -218.481689) (xy 367.349459 -218.445245) (xy 367.389846 -218.41462)
			(xy 367.434444 -218.390537) (xy 367.482202 -218.373561) (xy 367.507012 -218.368372) (xy 367.529872 -218.364054)
			(xy 367.735104 -218.008708) (xy 367.72723 -217.98661) (xy 367.718761 -217.960367) (xy 367.709692 -217.905977)
			(xy 367.709196 -217.878406) (xy 367.709704 -217.852519) (xy 367.717803 -217.801381) (xy 367.733802 -217.752141)
			(xy 367.757308 -217.706009) (xy 367.78774 -217.664122) (xy 367.82435 -217.627512) (xy 367.866237 -217.59708)
			(xy 367.912369 -217.573574) (xy 367.961609 -217.557575) (xy 368.012747 -217.549476) (xy 368.064521 -217.549476)
			(xy 368.115659 -217.557575) (xy 368.164899 -217.573574) (xy 368.211031 -217.59708) (xy 368.252918 -217.627512)
			(xy 368.289528 -217.664122) (xy 368.31996 -217.706009) (xy 368.343466 -217.752141) (xy 368.359465 -217.801381)
			(xy 368.367564 -217.852519) (xy 368.368072 -217.878406) (xy 368.367625 -217.903782) (xy 368.359855 -217.953934)
			(xy 368.344485 -218.002302) (xy 368.321877 -218.047739) (xy 368.292567 -218.089171) (xy 368.25725 -218.125617)
			(xy 368.21676 -218.156215) (xy 368.172056 -218.18024) (xy 368.124196 -218.197124) (xy 368.09934 -218.202256)
			(xy 368.07648 -218.206574) (xy 367.871756 -218.561412) (xy 367.87963 -218.583256) (xy 367.888281 -218.609663)
			(xy 367.897598 -218.66444) (xy 367.898172 -218.692222) (xy 369.118388 -218.692222) (xy 369.118939 -218.66688)
			(xy 369.126707 -218.616793) (xy 369.142048 -218.568485) (xy 369.164601 -218.523094) (xy 369.193834 -218.481689)
			(xy 369.229059 -218.445245) (xy 369.269446 -218.41462) (xy 369.314044 -218.390537) (xy 369.361802 -218.373561)
			(xy 369.386612 -218.368372) (xy 369.409472 -218.364054) (xy 369.614704 -218.008708) (xy 369.60683 -217.98661)
			(xy 369.598361 -217.960367) (xy 369.589292 -217.905977) (xy 369.588796 -217.878406) (xy 369.589304 -217.852519)
			(xy 369.597403 -217.801381) (xy 369.613402 -217.752141) (xy 369.636908 -217.706009) (xy 369.66734 -217.664122)
			(xy 369.70395 -217.627512) (xy 369.745837 -217.59708) (xy 369.791969 -217.573574) (xy 369.841209 -217.557575)
			(xy 369.892347 -217.549476) (xy 369.944121 -217.549476) (xy 369.995259 -217.557575) (xy 370.044499 -217.573574)
			(xy 370.090631 -217.59708) (xy 370.132518 -217.627512) (xy 370.169128 -217.664122) (xy 370.19956 -217.706009)
			(xy 370.223066 -217.752141) (xy 370.239065 -217.801381) (xy 370.247164 -217.852519) (xy 370.247672 -217.878406)
			(xy 370.247225 -217.903782) (xy 370.239455 -217.953934) (xy 370.224085 -218.002302) (xy 370.201477 -218.047739)
			(xy 370.172167 -218.089171) (xy 370.13685 -218.125617) (xy 370.09636 -218.156215) (xy 370.051656 -218.18024)
			(xy 370.003796 -218.197124) (xy 369.97894 -218.202256) (xy 369.95608 -218.206574) (xy 369.751356 -218.561412)
			(xy 369.75923 -218.583256) (xy 369.767881 -218.609663) (xy 369.777198 -218.66444) (xy 369.777772 -218.692222)
			(xy 370.997988 -218.692222) (xy 370.998539 -218.66688) (xy 371.006307 -218.616793) (xy 371.021648 -218.568485)
			(xy 371.044201 -218.523094) (xy 371.073434 -218.481689) (xy 371.108659 -218.445245) (xy 371.149046 -218.41462)
			(xy 371.193644 -218.390537) (xy 371.241402 -218.373561) (xy 371.266212 -218.368372) (xy 371.289072 -218.364054)
			(xy 371.494304 -218.008708) (xy 371.48643 -217.98661) (xy 371.477961 -217.960367) (xy 371.468892 -217.905977)
			(xy 371.468396 -217.878406) (xy 371.468904 -217.852519) (xy 371.477003 -217.801381) (xy 371.493002 -217.752141)
			(xy 371.516508 -217.706009) (xy 371.54694 -217.664122) (xy 371.58355 -217.627512) (xy 371.625437 -217.59708)
			(xy 371.671569 -217.573574) (xy 371.720809 -217.557575) (xy 371.771947 -217.549476) (xy 371.823721 -217.549476)
			(xy 371.874859 -217.557575) (xy 371.924099 -217.573574) (xy 371.970231 -217.59708) (xy 372.012118 -217.627512)
			(xy 372.048728 -217.664122) (xy 372.07916 -217.706009) (xy 372.102666 -217.752141) (xy 372.118665 -217.801381)
			(xy 372.126764 -217.852519) (xy 372.127272 -217.878406) (xy 372.126825 -217.903782) (xy 372.119055 -217.953934)
			(xy 372.103685 -218.002302) (xy 372.081077 -218.047739) (xy 372.051767 -218.089171) (xy 372.01645 -218.125617)
			(xy 371.97596 -218.156215) (xy 371.931256 -218.18024) (xy 371.883396 -218.197124) (xy 371.85854 -218.202256)
			(xy 371.83568 -218.206574) (xy 371.630956 -218.561412) (xy 371.63883 -218.583256) (xy 371.647481 -218.609663)
			(xy 371.656798 -218.66444) (xy 371.657372 -218.692222) (xy 371.656864 -218.718129) (xy 371.648758 -218.769306)
			(xy 371.632746 -218.818585) (xy 371.609223 -218.864752) (xy 371.578767 -218.906671) (xy 371.542129 -218.943309)
			(xy 371.50021 -218.973765) (xy 371.454043 -218.997288) (xy 371.404764 -219.0133) (xy 371.353587 -219.021406)
			(xy 371.301773 -219.021406) (xy 371.250596 -219.0133) (xy 371.201317 -218.997288) (xy 371.15515 -218.973765)
			(xy 371.113231 -218.943309) (xy 371.076593 -218.906671) (xy 371.046137 -218.864752) (xy 371.022614 -218.818585)
			(xy 371.006602 -218.769306) (xy 370.998496 -218.718129) (xy 370.997988 -218.692222) (xy 369.777772 -218.692222)
			(xy 369.777264 -218.718129) (xy 369.769158 -218.769306) (xy 369.753146 -218.818585) (xy 369.729623 -218.864752)
			(xy 369.699167 -218.906671) (xy 369.662529 -218.943309) (xy 369.62061 -218.973765) (xy 369.574443 -218.997288)
			(xy 369.525164 -219.0133) (xy 369.473987 -219.021406) (xy 369.422173 -219.021406) (xy 369.370996 -219.0133)
			(xy 369.321717 -218.997288) (xy 369.27555 -218.973765) (xy 369.233631 -218.943309) (xy 369.196993 -218.906671)
			(xy 369.166537 -218.864752) (xy 369.143014 -218.818585) (xy 369.127002 -218.769306) (xy 369.118896 -218.718129)
			(xy 369.118388 -218.692222) (xy 367.898172 -218.692222) (xy 367.897664 -218.718129) (xy 367.889558 -218.769306)
			(xy 367.873546 -218.818585) (xy 367.850023 -218.864752) (xy 367.819567 -218.906671) (xy 367.782929 -218.943309)
			(xy 367.74101 -218.973765) (xy 367.694843 -218.997288) (xy 367.645564 -219.0133) (xy 367.594387 -219.021406)
			(xy 367.542573 -219.021406) (xy 367.491396 -219.0133) (xy 367.442117 -218.997288) (xy 367.39595 -218.973765)
			(xy 367.354031 -218.943309) (xy 367.317393 -218.906671) (xy 367.286937 -218.864752) (xy 367.263414 -218.818585)
			(xy 367.247402 -218.769306) (xy 367.239296 -218.718129) (xy 367.238788 -218.692222) (xy 366.018572 -218.692222)
			(xy 366.018064 -218.718129) (xy 366.009958 -218.769306) (xy 365.993946 -218.818585) (xy 365.970423 -218.864752)
			(xy 365.939967 -218.906671) (xy 365.903329 -218.943309) (xy 365.86141 -218.973765) (xy 365.815243 -218.997288)
			(xy 365.765964 -219.0133) (xy 365.714787 -219.021406) (xy 365.662973 -219.021406) (xy 365.611796 -219.0133)
			(xy 365.562517 -218.997288) (xy 365.51635 -218.973765) (xy 365.474431 -218.943309) (xy 365.437793 -218.906671)
			(xy 365.407337 -218.864752) (xy 365.383814 -218.818585) (xy 365.367802 -218.769306) (xy 365.359696 -218.718129)
			(xy 365.359188 -218.692222) (xy 364.161578 -218.692222) (xy 364.161578 -219.048584) (xy 364.162023 -219.062201)
			(xy 364.169238 -219.088464) (xy 364.183133 -219.111888) (xy 364.202722 -219.130811) (xy 364.226612 -219.143888)
			(xy 364.253109 -219.150191) (xy 364.266734 -219.150184) (xy 364.279434 -219.14993) (xy 364.305161 -219.150385)
			(xy 364.356079 -219.157794) (xy 364.405401 -219.172453) (xy 364.4521 -219.194056) (xy 364.495205 -219.222154)
			(xy 364.533817 -219.256163) (xy 364.567135 -219.295374) (xy 364.594463 -219.338971) (xy 364.615233 -219.386046)
			(xy 364.629013 -219.435621) (xy 364.632748 -219.46108) (xy 364.638336 -219.50553) (xy 364.860332 -219.50553)
		)
		(stroke
			(width 0)
			(type solid)
		)
		(fill yes)
		(layer "B.Cu")
		(net "PVCCINFAON_CPU0")
	)
	(gr_poly
		(pts
			(xy 317.323978 -339.20811) (xy 317.323978 -320.37655) (xy 316.952884 -320.005456) (xy 311.251346 -320.005456)
			(xy 311.237523 -320.028056) (xy 311.204243 -320.069274) (xy 311.165229 -320.105111) (xy 311.121338 -320.134777)
			(xy 311.07354 -320.157618) (xy 311.022886 -320.173131) (xy 310.970494 -320.180974) (xy 310.917518 -320.180974)
			(xy 310.865126 -320.173131) (xy 310.814472 -320.157618) (xy 310.766674 -320.134777) (xy 310.722783 -320.105111)
			(xy 310.683769 -320.069274) (xy 310.650489 -320.028056) (xy 310.636666 -320.005456) (xy 310.57215 -320.005456)
			(xy 310.557126 -320.005986) (xy 310.528374 -320.014718) (xy 310.503409 -320.031439) (xy 310.484391 -320.054702)
			(xy 310.472967 -320.082494) (xy 310.471058 -320.097404) (xy 310.468099 -320.123537) (xy 310.455473 -320.174592)
			(xy 310.435475 -320.223233) (xy 310.408539 -320.268404) (xy 310.375251 -320.309121) (xy 310.336336 -320.344499)
			(xy 310.292641 -320.373767) (xy 310.245115 -320.39629) (xy 310.194793 -320.411576) (xy 310.14277 -320.419294)
			(xy 310.116474 -320.41973) (xy 310.089652 -320.419242) (xy 310.036615 -320.41119) (xy 309.985387 -320.395272)
			(xy 309.937127 -320.371849) (xy 309.892927 -320.341451) (xy 309.853787 -320.304766) (xy 309.820595 -320.262624)
			(xy 309.7941 -320.215979) (xy 309.783988 -320.19113) (xy 309.771542 -320.158364) (xy 309.66283 -320.158364)
			(xy 309.632901 -320.157635) (xy 309.574184 -320.146002) (xy 309.546244 -320.13525) (xy 309.360824 -320.058542)
			(xy 309.337661 -320.048458) (xy 309.294767 -320.021774) (xy 309.27548 -320.005456) (xy 307.803042 -320.005456)
			(xy 307.68925 -320.118994) (xy 307.67909 -320.1289) (xy 307.663525 -320.153945) (xy 307.626942 -320.200194)
			(xy 307.584723 -320.241362) (xy 307.537568 -320.27677) (xy 307.486258 -320.30583) (xy 307.431641 -320.328062)
			(xy 307.374622 -320.343098) (xy 307.316144 -320.35069) (xy 307.28666 -320.35115) (xy 307.256163 -320.350663)
			(xy 307.195705 -320.342592) (xy 307.136857 -320.326558) (xy 307.08066 -320.302846) (xy 307.028114 -320.271877)
			(xy 306.980149 -320.234199) (xy 306.958492 -320.21272) (xy 306.128166 -320.21272) (xy 306.103087 -320.212233)
			(xy 306.053552 -320.20434) (xy 306.005865 -320.188786) (xy 305.961204 -320.165953) (xy 305.92067 -320.136408)
			(xy 305.902614 -320.118994) (xy 305.788822 -320.005456) (xy 304.604928 -320.005456) (xy 304.558192 -320.051938)
			(xy 304.54013 -320.069341) (xy 304.499586 -320.098865) (xy 304.454924 -320.121686) (xy 304.407243 -320.137243)
			(xy 304.357717 -320.145154) (xy 304.33264 -320.145664) (xy 304.196242 -320.145664) (xy 303.968404 -320.373248)
			(xy 303.968404 -320.423032) (xy 303.982374 -320.437764) (xy 304.001852 -320.459043) (xy 304.035856 -320.505646)
			(xy 304.06373 -320.556154) (xy 304.085032 -320.609767) (xy 304.099423 -320.665632) (xy 304.106676 -320.722863)
			(xy 304.107088 -320.751708) (xy 304.106618 -320.781676) (xy 304.098794 -320.8411) (xy 304.08328 -320.898994)
			(xy 304.060342 -320.954367) (xy 304.030372 -321.006273) (xy 303.993884 -321.053822) (xy 303.951501 -321.096203)
			(xy 303.903949 -321.132688) (xy 303.852042 -321.162654) (xy 303.796667 -321.185589) (xy 303.738772 -321.201099)
			(xy 303.679348 -321.20892) (xy 303.64938 -321.209416) (xy 303.617592 -321.20887) (xy 303.554627 -321.20007)
			(xy 303.523904 -321.19189) (xy 303.510855 -321.188577) (xy 303.483944 -321.188178) (xy 303.457865 -321.19483)
			(xy 303.434433 -321.208069) (xy 303.415279 -321.226975) (xy 303.401734 -321.250233) (xy 303.394742 -321.276222)
			(xy 303.394364 -321.28968) (xy 303.394364 -321.649852) (xy 303.4207 -321.665069) (xy 303.469472 -321.701414)
			(xy 303.512998 -321.743901) (xy 303.550511 -321.791781) (xy 303.581349 -321.844209) (xy 303.604967 -321.900261)
			(xy 303.620951 -321.958948) (xy 303.629017 -322.019236) (xy 303.629568 -322.049648) (xy 303.629083 -322.078985)
			(xy 303.621554 -322.137174) (xy 303.606652 -322.193924) (xy 303.58462 -322.248304) (xy 303.55582 -322.299424)
			(xy 303.538636 -322.323206) (xy 303.538636 -323.352668) (xy 303.458118 -323.433186) (xy 304.263044 -323.433186)
			(xy 304.263044 -321.952366) (xy 304.539142 -321.676268) (xy 306.273962 -321.676268) (xy 306.391818 -321.794124)
			(xy 306.401697 -321.803352) (xy 306.425154 -321.816763) (xy 306.45131 -321.823544) (xy 306.478329 -321.823218)
			(xy 306.504314 -321.815808) (xy 306.527441 -321.801835) (xy 306.546087 -321.782278) (xy 306.558942 -321.758511)
			(xy 306.565105 -321.732203) (xy 306.565046 -321.718686) (xy 306.564792 -321.702684) (xy 306.565299 -321.672718)
			(xy 306.573124 -321.613298) (xy 306.588638 -321.555408) (xy 306.611575 -321.500038) (xy 306.641543 -321.448136)
			(xy 306.678029 -321.400589) (xy 306.720409 -321.358211) (xy 306.767958 -321.321728) (xy 306.819862 -321.291763)
			(xy 306.875233 -321.268829) (xy 306.933124 -321.253319) (xy 306.992544 -321.245497) (xy 307.052477 -321.245499)
			(xy 307.111897 -321.253323) (xy 307.169787 -321.268836) (xy 307.225157 -321.291772) (xy 307.27706 -321.32174)
			(xy 307.324607 -321.358225) (xy 307.366985 -321.400605) (xy 307.403469 -321.448153) (xy 307.433435 -321.500057)
			(xy 307.456369 -321.555428) (xy 307.47188 -321.613319) (xy 307.479702 -321.672739) (xy 307.479702 -321.732672)
			(xy 307.471878 -321.792092) (xy 307.456366 -321.849982) (xy 307.43343 -321.905353) (xy 307.403463 -321.957256)
			(xy 307.366978 -322.004803) (xy 307.324599 -322.047182) (xy 307.277051 -322.083666) (xy 307.225148 -322.113633)
			(xy 307.169777 -322.136568) (xy 307.111886 -322.152079) (xy 307.052466 -322.159902) (xy 307.0225 -322.160392)
			(xy 306.989303 -322.159808) (xy 306.923606 -322.150209) (xy 306.859983 -322.131227) (xy 306.799767 -322.103259)
			(xy 306.744219 -322.066891) (xy 306.71897 -322.04533) (xy 306.707776 -322.035927) (xy 306.681319 -322.023507)
			(xy 306.652428 -322.01909) (xy 306.623468 -322.023038) (xy 306.596814 -322.035028) (xy 306.574647 -322.054077)
			(xy 306.558785 -322.078626) (xy 306.550527 -322.106662) (xy 306.55006 -322.121276) (xy 306.55006 -323.433186)
			(xy 307.742844 -323.433186) (xy 307.742844 -321.952366) (xy 308.018942 -321.676268) (xy 310.357774 -321.676268)
			(xy 310.674512 -321.99326) (xy 310.674512 -323.268086) (xy 310.241188 -323.701664) (xy 308.011322 -323.701664)
			(xy 307.742844 -323.433186) (xy 306.55006 -323.433186) (xy 306.019962 -323.963284) (xy 304.793142 -323.963284)
			(xy 304.263044 -323.433186) (xy 303.458118 -323.433186) (xy 303.183544 -323.70776) (xy 300.473872 -323.70776)
			(xy 300.199044 -323.433186) (xy 300.199044 -321.952366) (xy 300.475142 -321.676268) (xy 301.999142 -321.676268)
			(xy 302.009048 -321.666616) (xy 302.259746 -321.666616) (xy 302.379634 -321.546728) (xy 302.756316 -321.546728)
			(xy 302.756316 -320.145156) (xy 302.755845 -320.131317) (xy 302.748399 -320.104658) (xy 302.734065 -320.080979)
			(xy 302.713897 -320.062021) (xy 302.689378 -320.049177) (xy 302.662311 -320.043391) (xy 302.634683 -320.045088)
			(xy 302.621442 -320.049144) (xy 302.593291 -320.058257) (xy 302.534947 -320.068093) (xy 302.505364 -320.068702)
			(xy 302.4784 -320.068204) (xy 302.425089 -320.060076) (xy 302.373609 -320.044012) (xy 302.325137 -320.020377)
			(xy 302.302672 -320.005456) (xy 300.80585 -320.005456) (xy 300.623986 -320.18732) (xy 300.62043 -320.200782)
			(xy 300.612619 -320.229023) (xy 300.590582 -320.283316) (xy 300.561605 -320.334244) (xy 300.52619 -320.380925)
			(xy 300.484951 -320.422551) (xy 300.438603 -320.4584) (xy 300.387948 -320.487851) (xy 300.333863 -320.510394)
			(xy 300.277286 -320.525639) (xy 300.219197 -320.533322) (xy 300.1899 -320.533776) (xy 300.162887 -320.533378)
			(xy 300.109259 -320.526833) (xy 300.05682 -320.513838) (xy 300.006341 -320.494586) (xy 299.958566 -320.469359)
			(xy 299.936154 -320.454274) (xy 299.927637 -320.448868) (xy 299.907933 -320.444616) (xy 299.888116 -320.448301)
			(xy 299.871258 -320.459352) (xy 299.865288 -320.467482) (xy 299.846924 -320.493569) (xy 299.804129 -320.540882)
			(xy 299.755184 -320.581798) (xy 299.701034 -320.615528) (xy 299.642728 -320.641417) (xy 299.581394 -320.658966)
			(xy 299.518218 -320.667835) (xy 299.48632 -320.668396) (xy 299.45578 -320.667897) (xy 299.39524 -320.659785)
			(xy 299.336318 -320.643689) (xy 299.280062 -320.619897) (xy 299.227472 -320.58883) (xy 299.179483 -320.551041)
			(xy 299.13695 -320.507203) (xy 299.100628 -320.458096) (xy 299.071164 -320.404591) (xy 299.049081 -320.347642)
			(xy 299.034773 -320.288261) (xy 299.031152 -320.257932) (xy 299.026326 -320.212212) (xy 298.43603 -320.212212)
			(xy 298.410962 -320.21174) (xy 298.361445 -320.203884) (xy 298.313767 -320.188377) (xy 298.269103 -320.165601)
			(xy 298.228553 -320.136117) (xy 298.210478 -320.11874) (xy 298.09694 -320.005456) (xy 297.002962 -320.005456)
			(xy 296.980085 -320.021306) (xy 296.930439 -320.046457) (xy 296.877483 -320.063573) (xy 296.822509 -320.072237)
			(xy 296.766855 -320.072237) (xy 296.711881 -320.063573) (xy 296.658925 -320.046457) (xy 296.609279 -320.021306)
			(xy 296.586402 -320.005456) (xy 295.16197 -320.005456) (xy 295.141798 -320.02478) (xy 295.096554 -320.05754)
			(xy 295.046753 -320.082839) (xy 294.993614 -320.100058) (xy 294.938439 -320.108773) (xy 294.882581 -320.108773)
			(xy 294.827406 -320.100058) (xy 294.774267 -320.082839) (xy 294.724466 -320.05754) (xy 294.679222 -320.02478)
			(xy 294.65905 -320.005456) (xy 293.299642 -320.005456) (xy 293.273734 -320.03111) (xy 293.252828 -320.051385)
			(xy 293.206633 -320.08685) (xy 293.156202 -320.115977) (xy 293.102398 -320.138266) (xy 293.046143 -320.153336)
			(xy 292.988401 -320.160928) (xy 292.959282 -320.161412) (xy 292.694614 -320.161412) (xy 292.67531 -320.161158)
			(xy 292.661374 -320.160985) (xy 292.634247 -320.167341) (xy 292.609846 -320.180791) (xy 292.589987 -320.200332)
			(xy 292.576146 -320.224512) (xy 292.569352 -320.251533) (xy 292.570111 -320.279384) (xy 292.578367 -320.305994)
			(xy 292.585648 -320.317876) (xy 292.603078 -320.345804) (xy 292.63061 -320.405602) (xy 292.649287 -320.468728)
			(xy 292.658723 -320.53388) (xy 292.659308 -320.566796) (xy 292.658818 -320.596764) (xy 292.650995 -320.656186)
			(xy 292.635482 -320.714079) (xy 292.612546 -320.769452) (xy 292.582579 -320.821358) (xy 292.546092 -320.868908)
			(xy 292.503712 -320.911288) (xy 292.456162 -320.947775) (xy 292.404256 -320.977742) (xy 292.348883 -321.000678)
			(xy 292.29099 -321.016191) (xy 292.231568 -321.024014) (xy 292.171632 -321.024014) (xy 292.11221 -321.016191)
			(xy 292.054317 -321.000678) (xy 291.998944 -320.977742) (xy 291.947038 -320.947775) (xy 291.899488 -320.911288)
			(xy 291.857108 -320.868908) (xy 291.820621 -320.821358) (xy 291.790654 -320.769452) (xy 291.767718 -320.714079)
			(xy 291.752205 -320.656186) (xy 291.744382 -320.596764) (xy 291.743892 -320.566796) (xy 291.744598 -320.531817)
			(xy 291.75532 -320.462682) (xy 291.765228 -320.429128) (xy 291.768909 -320.41598) (xy 291.769919 -320.388704)
			(xy 291.763666 -320.362136) (xy 291.750598 -320.338174) (xy 291.731649 -320.31853) (xy 291.708173 -320.304608)
			(xy 291.681847 -320.297403) (xy 291.6682 -320.297048) (xy 291.048948 -320.297048) (xy 291.023866 -320.296568)
			(xy 290.974324 -320.288686) (xy 290.926629 -320.273142) (xy 290.881957 -320.250319) (xy 290.841411 -320.22078)
			(xy 290.823396 -320.203322) (xy 290.625276 -320.005456) (xy 289.459162 -320.005456) (xy 289.436286 -320.021309)
			(xy 289.386641 -320.046463) (xy 289.333685 -320.063581) (xy 289.278709 -320.072244) (xy 289.250882 -320.072766)
			(xy 289.224909 -320.072298) (xy 289.173515 -320.064747) (xy 289.123768 -320.049794) (xy 289.076727 -320.027758)
			(xy 289.054794 -320.013838) (xy 289.042094 -320.005456) (xy 288.931096 -320.005456) (xy 288.931096 -320.154554)
			(xy 288.93135 -320.154554) (xy 288.931003 -320.176881) (xy 288.922589 -320.22073) (xy 288.905741 -320.262077)
			(xy 288.881115 -320.29932) (xy 288.849666 -320.331012) (xy 288.812613 -320.355923) (xy 288.771396 -320.373088)
			(xy 288.727614 -320.381839) (xy 288.70529 -320.382392) (xy 288.437828 -320.382392) (xy 288.437828 -320.322448)
			(xy 287.912556 -320.322448) (xy 287.912556 -320.382392) (xy 287.645094 -320.382392) (xy 287.622767 -320.381872)
			(xy 287.578981 -320.373118) (xy 287.53776 -320.355949) (xy 287.500705 -320.331033) (xy 287.469253 -320.299336)
			(xy 287.444625 -320.262089) (xy 287.427777 -320.220737) (xy 287.419362 -320.176884) (xy 287.419034 -320.154554)
			(xy 287.419288 -320.154554) (xy 287.419288 -320.06794) (xy 287.35655 -320.005456) (xy 285.755842 -320.005456)
			(xy 285.729934 -320.03111) (xy 285.709028 -320.051385) (xy 285.662833 -320.08685) (xy 285.612402 -320.115977)
			(xy 285.558598 -320.138266) (xy 285.502343 -320.153336) (xy 285.444601 -320.160928) (xy 285.415482 -320.161412)
			(xy 285.150814 -320.161412) (xy 285.124269 -320.161071) (xy 285.07155 -320.154828) (xy 285.045658 -320.148966)
			(xy 285.036303 -320.147127) (xy 285.017432 -320.149745) (xy 285.000816 -320.159065) (xy 284.988742 -320.173803)
			(xy 284.982875 -320.191929) (xy 284.984022 -320.210946) (xy 284.992026 -320.228235) (xy 284.998668 -320.235072)
			(xy 285.020719 -320.256765) (xy 285.059374 -320.305055) (xy 285.091178 -320.358108) (xy 285.115552 -320.41496)
			(xy 285.132052 -320.474575) (xy 285.140378 -320.535868) (xy 285.140908 -320.566796) (xy 285.140439 -320.596765)
			(xy 285.132616 -320.656191) (xy 285.117104 -320.714086) (xy 285.094167 -320.769462) (xy 285.064198 -320.82137)
			(xy 285.02771 -320.868923) (xy 284.985328 -320.911306) (xy 284.937776 -320.947794) (xy 284.885868 -320.977764)
			(xy 284.830493 -321.000701) (xy 284.772597 -321.016215) (xy 284.713172 -321.024039) (xy 284.653234 -321.024039)
			(xy 284.593808 -321.016216) (xy 284.535912 -321.000703) (xy 284.480537 -320.977766) (xy 284.428628 -320.947797)
			(xy 284.381076 -320.911309) (xy 284.338693 -320.868927) (xy 284.302205 -320.821375) (xy 284.272236 -320.769467)
			(xy 284.249298 -320.714092) (xy 284.233785 -320.656196) (xy 284.225961 -320.59677) (xy 284.225961 -320.536832)
			(xy 284.233784 -320.477407) (xy 284.249297 -320.419511) (xy 284.272235 -320.364135) (xy 284.302204 -320.312227)
			(xy 284.338691 -320.264675) (xy 284.381074 -320.222292) (xy 284.428626 -320.185804) (xy 284.480534 -320.155835)
			(xy 284.53591 -320.132898) (xy 284.593806 -320.117385) (xy 284.653231 -320.109561) (xy 284.6832 -320.109088)
			(xy 284.711303 -320.109514) (xy 284.767087 -320.116389) (xy 284.794452 -320.122804) (xy 284.803816 -320.124756)
			(xy 284.822774 -320.122334) (xy 284.839534 -320.113145) (xy 284.851772 -320.098464) (xy 284.857794 -320.080324)
			(xy 284.856764 -320.061239) (xy 284.848826 -320.043852) (xy 284.842204 -320.036952) (xy 284.836362 -320.03111)
			(xy 284.810454 -320.005456) (xy 282.30449 -320.005456) (xy 281.430984 -320.878708) (xy 281.430984 -321.71894)
			(xy 281.45137 -321.73936) (xy 281.487357 -321.784464) (xy 281.517366 -321.833748) (xy 281.529536 -321.85991)
			(xy 281.535716 -321.872558) (xy 281.553816 -321.894104) (xy 281.577104 -321.9099) (xy 281.603816 -321.918748)
			(xy 281.631929 -321.919978) (xy 281.659312 -321.913498) (xy 281.683891 -321.899797) (xy 281.694128 -321.890136)
			(xy 281.907742 -321.676268) (xy 283.642562 -321.676268) (xy 283.91866 -321.952366) (xy 283.91866 -323.433186)
			(xy 285.111444 -323.433186) (xy 285.111444 -321.952366) (xy 285.387542 -321.676268) (xy 287.122362 -321.676268)
			(xy 287.39846 -321.952366) (xy 287.39846 -323.356986) (xy 288.511996 -323.356986) (xy 288.511996 -322.160138)
			(xy 288.995866 -321.676268) (xy 291.678868 -321.676268) (xy 292.013132 -322.010786) (xy 292.013132 -323.31914)
			(xy 291.942774 -323.389498) (xy 292.181788 -323.389498) (xy 292.181788 -322.064634) (xy 292.568122 -321.6783)
			(xy 292.92931 -321.6783) (xy 292.931342 -321.676268) (xy 295.327578 -321.676268) (xy 295.638728 -321.987164)
			(xy 295.638728 -323.1896) (xy 296.719244 -323.1896) (xy 296.719244 -321.952366) (xy 296.995342 -321.676268)
			(xy 298.95419 -321.676268) (xy 298.968125 -321.67577) (xy 298.994934 -321.668142) (xy 299.018689 -321.653559)
			(xy 299.037624 -321.633104) (xy 299.050333 -321.608296) (xy 299.055873 -321.580979) (xy 299.055282 -321.567048)
			(xy 299.054012 -321.531488) (xy 299.054502 -321.50152) (xy 299.062325 -321.442098) (xy 299.077838 -321.384205)
			(xy 299.100774 -321.328832) (xy 299.130741 -321.276926) (xy 299.167228 -321.229376) (xy 299.209608 -321.186996)
			(xy 299.257158 -321.150509) (xy 299.309064 -321.120542) (xy 299.364437 -321.097606) (xy 299.42233 -321.082093)
			(xy 299.481752 -321.07427) (xy 299.541688 -321.07427) (xy 299.60111 -321.082093) (xy 299.659003 -321.097606)
			(xy 299.714376 -321.120542) (xy 299.766282 -321.150509) (xy 299.813832 -321.186996) (xy 299.856212 -321.229376)
			(xy 299.892699 -321.276926) (xy 299.922666 -321.328832) (xy 299.945602 -321.384205) (xy 299.961115 -321.442098)
			(xy 299.968938 -321.50152) (xy 299.969428 -321.531488) (xy 299.968862 -321.563054) (xy 299.960161 -321.625584)
			(xy 299.942951 -321.686325) (xy 299.917558 -321.744126) (xy 299.884463 -321.797889) (xy 299.844295 -321.846594)
			(xy 299.797816 -321.889318) (xy 299.745907 -321.92525) (xy 299.689552 -321.953709) (xy 299.629822 -321.974154)
			(xy 299.567849 -321.986198) (xy 299.536358 -321.988434) (xy 299.526734 -321.989411) (xy 299.509212 -321.997568)
			(xy 299.495937 -322.011616) (xy 299.488781 -322.029571) (xy 299.488352 -322.039234) (xy 299.488352 -323.23786)
			(xy 299.103034 -323.622924) (xy 297.152822 -323.622924) (xy 296.719244 -323.1896) (xy 295.638728 -323.1896)
			(xy 295.638728 -323.478652) (xy 295.306242 -323.811392) (xy 292.603682 -323.811392) (xy 292.181788 -323.389498)
			(xy 291.942774 -323.389498) (xy 291.671248 -323.661024) (xy 288.816288 -323.661024) (xy 288.511996 -323.356986)
			(xy 287.39846 -323.356986) (xy 287.39846 -323.433186) (xy 286.868362 -323.963284) (xy 285.641542 -323.963284)
			(xy 285.111444 -323.433186) (xy 283.91866 -323.433186) (xy 283.388562 -323.963284) (xy 282.161742 -323.963284)
			(xy 281.631644 -323.433186) (xy 281.631644 -322.418456) (xy 281.631199 -322.404804) (xy 281.623954 -322.37848)
			(xy 281.609992 -322.355016) (xy 281.590312 -322.33609) (xy 281.56632 -322.323055) (xy 281.539733 -322.316843)
			(xy 281.51245 -322.317897) (xy 281.486421 -322.326143) (xy 281.463507 -322.340991) (xy 281.454098 -322.350892)
			(xy 281.432298 -322.374634) (xy 281.38318 -322.416368) (xy 281.328691 -322.450797) (xy 281.26991 -322.477239)
			(xy 281.208 -322.49517) (xy 281.144187 -322.504237) (xy 281.11196 -322.504816) (xy 281.081994 -322.504323)
			(xy 281.022575 -322.496496) (xy 280.964686 -322.48098) (xy 280.909317 -322.458042) (xy 280.857416 -322.428073)
			(xy 280.80987 -322.391586) (xy 280.767492 -322.349206) (xy 280.731009 -322.301658) (xy 280.701044 -322.249754)
			(xy 280.678109 -322.194384) (xy 280.662598 -322.136494) (xy 280.654774 -322.077074) (xy 280.654252 -322.047108)
			(xy 280.654756 -322.016602) (xy 280.662864 -321.95613) (xy 280.678937 -321.897272) (xy 280.702689 -321.841073)
			(xy 280.7337 -321.788528) (xy 280.771419 -321.740572) (xy 280.792936 -321.71894) (xy 280.792936 -321.351402)
			(xy 280.792432 -321.336395) (xy 280.783772 -321.307659) (xy 280.76714 -321.282678) (xy 280.743968 -321.263604)
			(xy 280.716255 -321.252083) (xy 280.686391 -321.249108) (xy 280.65695 -321.254935) (xy 280.630471 -321.269062)
			(xy 280.619454 -321.279266) (xy 280.597946 -321.300009) (xy 280.550483 -321.336312) (xy 280.498697 -321.366125)
			(xy 280.44347 -321.388942) (xy 280.385743 -321.404373) (xy 280.326497 -321.412156) (xy 280.29662 -321.412616)
			(xy 280.26665 -321.412148) (xy 280.207222 -321.404327) (xy 280.149324 -321.388816) (xy 280.093946 -321.36588)
			(xy 280.042035 -321.335911) (xy 279.99448 -321.299424) (xy 279.952095 -321.257041) (xy 279.915604 -321.209488)
			(xy 279.885633 -321.157579) (xy 279.862693 -321.102203) (xy 279.847179 -321.044305) (xy 279.839354 -320.984878)
			(xy 279.838912 -320.954908) (xy 279.839441 -320.923352) (xy 279.848113 -320.860838) (xy 279.865295 -320.800109)
			(xy 279.890659 -320.742317) (xy 279.923725 -320.68856) (xy 279.963865 -320.639857) (xy 280.010317 -320.597132)
			(xy 280.0622 -320.561197) (xy 280.090118 -320.546476) (xy 280.097484 -320.542666) (xy 280.461212 -320.178938)
			(xy 280.471439 -320.167961) (xy 280.485578 -320.141515) (xy 280.491427 -320.112103) (xy 280.488483 -320.08226)
			(xy 280.477 -320.054558) (xy 280.457968 -320.031384) (xy 280.433026 -320.014735) (xy 280.404324 -320.006047)
			(xy 280.38933 -320.005456) (xy 278.212042 -320.005456) (xy 278.186134 -320.03111) (xy 278.165228 -320.051385)
			(xy 278.119033 -320.08685) (xy 278.068602 -320.115977) (xy 278.014798 -320.138266) (xy 277.958543 -320.153336)
			(xy 277.900801 -320.160928) (xy 277.871682 -320.161412) (xy 277.607014 -320.161412) (xy 277.58771 -320.161158)
			(xy 277.573774 -320.160985) (xy 277.546647 -320.167341) (xy 277.522246 -320.180791) (xy 277.502387 -320.200332)
			(xy 277.488546 -320.224512) (xy 277.481752 -320.251533) (xy 277.482511 -320.279384) (xy 277.490767 -320.305994)
			(xy 277.498048 -320.317876) (xy 277.515478 -320.345804) (xy 277.54301 -320.405602) (xy 277.561687 -320.468728)
			(xy 277.571123 -320.53388) (xy 277.571708 -320.566796) (xy 277.571239 -320.596765) (xy 277.563416 -320.656191)
			(xy 277.547904 -320.714086) (xy 277.524967 -320.769462) (xy 277.494998 -320.82137) (xy 277.45851 -320.868923)
			(xy 277.416128 -320.911306) (xy 277.368576 -320.947794) (xy 277.316668 -320.977764) (xy 277.261293 -321.000701)
			(xy 277.203397 -321.016215) (xy 277.143972 -321.024039) (xy 277.084034 -321.024039) (xy 277.024608 -321.016216)
			(xy 276.966712 -321.000703) (xy 276.911337 -320.977766) (xy 276.859428 -320.947797) (xy 276.811876 -320.911309)
			(xy 276.769493 -320.868927) (xy 276.733005 -320.821375) (xy 276.703036 -320.769467) (xy 276.680098 -320.714092)
			(xy 276.664585 -320.656196) (xy 276.656761 -320.59677) (xy 276.656761 -320.536832) (xy 276.664584 -320.477407)
			(xy 276.680097 -320.419511) (xy 276.703035 -320.364135) (xy 276.733004 -320.312227) (xy 276.769491 -320.264675)
			(xy 276.811874 -320.222292) (xy 276.859426 -320.185804) (xy 276.911334 -320.155835) (xy 276.96671 -320.132898)
			(xy 277.024606 -320.117385) (xy 277.084031 -320.109561) (xy 277.114 -320.109088) (xy 277.150781 -320.109795)
			(xy 277.223399 -320.12153) (xy 277.258526 -320.132456) (xy 277.2681 -320.135152) (xy 277.287924 -320.133804)
			(xy 277.305746 -320.125019) (xy 277.31889 -320.110117) (xy 277.32538 -320.091337) (xy 277.324242 -320.0715)
			(xy 277.315646 -320.053586) (xy 277.308564 -320.046604) (xy 277.298027 -320.036883) (xy 277.278073 -320.016292)
			(xy 277.268686 -320.005456) (xy 274.371562 -320.005456) (xy 274.348686 -320.021309) (xy 274.299041 -320.046463)
			(xy 274.246085 -320.063581) (xy 274.191109 -320.072244) (xy 274.163282 -320.072766) (xy 274.137309 -320.072298)
			(xy 274.085915 -320.064747) (xy 274.036168 -320.049794) (xy 273.989127 -320.027758) (xy 273.967194 -320.013838)
			(xy 273.954494 -320.005456) (xy 273.847306 -320.005456) (xy 273.83366 -320.032238) (xy 273.800385 -320.082296)
			(xy 273.760845 -320.127569) (xy 273.715722 -320.16728) (xy 273.665791 -320.200746) (xy 273.611911 -320.227391)
			(xy 273.555007 -320.246757) (xy 273.496059 -320.258512) (xy 273.43608 -320.262453) (xy 273.376101 -320.258512)
			(xy 273.317153 -320.246757) (xy 273.260249 -320.227391) (xy 273.206369 -320.200746) (xy 273.156438 -320.16728)
			(xy 273.111315 -320.127569) (xy 273.071775 -320.082296) (xy 273.0385 -320.032238) (xy 273.024854 -320.005456)
			(xy 270.668242 -320.005456) (xy 270.642334 -320.03111) (xy 270.621428 -320.051385) (xy 270.575233 -320.08685)
			(xy 270.524802 -320.115977) (xy 270.470998 -320.138266) (xy 270.414743 -320.153336) (xy 270.357001 -320.160928)
			(xy 270.327882 -320.161412) (xy 270.063214 -320.161412) (xy 270.05026 -320.161412) (xy 270.036429 -320.161485)
			(xy 270.009597 -320.16815) (xy 269.985537 -320.181769) (xy 269.966012 -320.201343) (xy 269.952454 -320.225438)
			(xy 269.945858 -320.252287) (xy 269.946706 -320.279921) (xy 269.954937 -320.306314) (xy 269.962122 -320.31813)
			(xy 269.979497 -320.346044) (xy 270.006939 -320.405792) (xy 270.025558 -320.46885) (xy 270.034971 -320.533922)
			(xy 270.035528 -320.566796) (xy 270.035059 -320.596767) (xy 270.027236 -320.656195) (xy 270.011722 -320.714094)
			(xy 269.988784 -320.769473) (xy 269.958813 -320.821384) (xy 269.922323 -320.868938) (xy 269.879938 -320.911323)
			(xy 269.832384 -320.947813) (xy 269.780473 -320.977784) (xy 269.725094 -321.000722) (xy 269.667195 -321.016236)
			(xy 269.660502 -321.017117) (xy 272.56231 -321.017117) (xy 272.56231 -320.963819) (xy 272.570253 -320.911115)
			(xy 272.585963 -320.860185) (xy 272.609089 -320.812164) (xy 272.639113 -320.768127) (xy 272.675365 -320.729056)
			(xy 272.717036 -320.695825) (xy 272.763194 -320.669176) (xy 272.812808 -320.649704) (xy 272.86477 -320.637844)
			(xy 272.91792 -320.633861) (xy 272.97107 -320.637844) (xy 273.023032 -320.649704) (xy 273.072646 -320.669176)
			(xy 273.118804 -320.695825) (xy 273.160475 -320.729056) (xy 273.196727 -320.768127) (xy 273.226751 -320.812164)
			(xy 273.249877 -320.860185) (xy 273.265587 -320.911115) (xy 273.27353 -320.963819) (xy 273.274028 -320.990468)
			(xy 273.27353 -321.017117) (xy 273.265587 -321.069821) (xy 273.249877 -321.120751) (xy 273.226751 -321.168772)
			(xy 273.196727 -321.212809) (xy 273.160475 -321.25188) (xy 273.118804 -321.285111) (xy 273.072646 -321.31176)
			(xy 273.023032 -321.331232) (xy 272.97107 -321.343092) (xy 272.91792 -321.347076) (xy 272.86477 -321.343092)
			(xy 272.812808 -321.331232) (xy 272.763194 -321.31176) (xy 272.717036 -321.285111) (xy 272.675365 -321.25188)
			(xy 272.639113 -321.212809) (xy 272.609089 -321.168772) (xy 272.585963 -321.120751) (xy 272.570253 -321.069821)
			(xy 272.56231 -321.017117) (xy 269.660502 -321.017117) (xy 269.607767 -321.024059) (xy 269.547825 -321.024059)
			(xy 269.488397 -321.016234) (xy 269.430498 -321.000719) (xy 269.37512 -320.97778) (xy 269.32321 -320.947809)
			(xy 269.275656 -320.911318) (xy 269.233271 -320.868932) (xy 269.196782 -320.821377) (xy 269.166813 -320.769466)
			(xy 269.143875 -320.714087) (xy 269.128363 -320.656187) (xy 269.12054 -320.596759) (xy 269.120542 -320.536817)
			(xy 269.128367 -320.477389) (xy 269.143883 -320.419491) (xy 269.166823 -320.364113) (xy 269.196796 -320.312203)
			(xy 269.233287 -320.26465) (xy 269.275674 -320.222266) (xy 269.32323 -320.185778) (xy 269.375141 -320.155809)
			(xy 269.430521 -320.132873) (xy 269.48842 -320.117361) (xy 269.547849 -320.10954) (xy 269.57782 -320.109088)
			(xy 269.611799 -320.109727) (xy 269.679006 -320.1198) (xy 269.711678 -320.129154) (xy 269.721178 -320.131605)
			(xy 269.740708 -320.129914) (xy 269.758177 -320.121021) (xy 269.771034 -320.106224) (xy 269.777401 -320.087684)
			(xy 269.776349 -320.06811) (xy 269.76803 -320.050359) (xy 269.761208 -320.043302) (xy 269.751646 -320.034315)
			(xy 269.733474 -320.015378) (xy 269.724886 -320.005456) (xy 266.827762 -320.005456) (xy 266.804886 -320.021309)
			(xy 266.755241 -320.046463) (xy 266.702285 -320.063581) (xy 266.647309 -320.072244) (xy 266.619482 -320.072766)
			(xy 266.592803 -320.07226) (xy 266.540043 -320.064299) (xy 266.489057 -320.04857) (xy 266.464796 -320.03746)
			(xy 266.45098 -320.031383) (xy 266.421169 -320.026758) (xy 266.391309 -320.031051) (xy 266.364008 -320.043887)
			(xy 266.341654 -320.064144) (xy 266.333478 -320.07683) (xy 266.317949 -320.101979) (xy 266.281399 -320.148431)
			(xy 266.239171 -320.189789) (xy 266.191969 -320.225364) (xy 266.140577 -320.254564) (xy 266.085853 -320.276901)
			(xy 266.028708 -320.292004) (xy 265.970094 -320.299622) (xy 265.94054 -320.300096) (xy 265.911626 -320.299651)
			(xy 265.854261 -320.292361) (xy 265.79827 -320.277904) (xy 265.744545 -320.256512) (xy 265.693942 -320.228524)
			(xy 265.647267 -320.194386) (xy 265.605262 -320.154642) (xy 265.568597 -320.109925) (xy 265.537855 -320.060946)
			(xy 265.52525 -320.03492) (xy 265.511534 -320.005456) (xy 263.124442 -320.005456) (xy 263.098534 -320.03111)
			(xy 263.077628 -320.051385) (xy 263.031433 -320.08685) (xy 262.981002 -320.115977) (xy 262.927198 -320.138266)
			(xy 262.870943 -320.153336) (xy 262.813201 -320.160928) (xy 262.784082 -320.161412) (xy 262.519414 -320.161412)
			(xy 262.489786 -320.160975) (xy 262.431042 -320.153203) (xy 262.40232 -320.145918) (xy 262.387704 -320.142503)
			(xy 262.357718 -320.14339) (xy 262.32928 -320.152946) (xy 262.304842 -320.170346) (xy 262.28651 -320.194092)
			(xy 262.275861 -320.222139) (xy 262.273815 -320.252069) (xy 262.27659 -320.266822) (xy 262.282183 -320.292428)
			(xy 262.288166 -320.344501) (xy 262.288528 -320.370708) (xy 262.288038 -320.400676) (xy 262.280215 -320.460098)
			(xy 262.264702 -320.517991) (xy 262.241766 -320.573364) (xy 262.211799 -320.62527) (xy 262.175312 -320.67282)
			(xy 262.132932 -320.7152) (xy 262.085382 -320.751687) (xy 262.033476 -320.781654) (xy 261.978103 -320.80459)
			(xy 261.92021 -320.820103) (xy 261.860788 -320.827926) (xy 261.800852 -320.827926) (xy 261.74143 -320.820103)
			(xy 261.683537 -320.80459) (xy 261.628164 -320.781654) (xy 261.576258 -320.751687) (xy 261.528708 -320.7152)
			(xy 261.486328 -320.67282) (xy 261.449841 -320.62527) (xy 261.419874 -320.573364) (xy 261.396938 -320.517991)
			(xy 261.381425 -320.460098) (xy 261.373602 -320.400676) (xy 261.373112 -320.370708) (xy 261.373112 -320.365882)
			(xy 261.372872 -320.352446) (xy 261.366192 -320.326426) (xy 261.352958 -320.303049) (xy 261.334084 -320.283933)
			(xy 261.310877 -320.270401) (xy 261.284944 -320.263391) (xy 261.271512 -320.263012) (xy 260.437376 -320.263012)
			(xy 260.412307 -320.262543) (xy 260.362786 -320.254694) (xy 260.315104 -320.239192) (xy 260.270434 -320.21642)
			(xy 260.229879 -320.186939) (xy 260.211824 -320.16954) (xy 260.047486 -320.005456) (xy 256.54127 -320.005456)
			(xy 256.219452 -320.327274) (xy 256.219452 -320.956936) (xy 264.955002 -320.956936) (xy 264.955002 -320.897)
			(xy 264.962825 -320.837578) (xy 264.978338 -320.779685) (xy 265.001274 -320.724312) (xy 265.031241 -320.672406)
			(xy 265.067728 -320.624856) (xy 265.110108 -320.582476) (xy 265.157658 -320.545989) (xy 265.209564 -320.516022)
			(xy 265.264937 -320.493086) (xy 265.32283 -320.477573) (xy 265.382252 -320.46975) (xy 265.442188 -320.46975)
			(xy 265.50161 -320.477573) (xy 265.559503 -320.493086) (xy 265.614876 -320.516022) (xy 265.666782 -320.545989)
			(xy 265.714332 -320.582476) (xy 265.756712 -320.624856) (xy 265.793199 -320.672406) (xy 265.823166 -320.724312)
			(xy 265.846102 -320.779685) (xy 265.861615 -320.837578) (xy 265.869438 -320.897) (xy 265.869928 -320.926968)
			(xy 265.869438 -320.956936) (xy 265.861615 -321.016358) (xy 265.846102 -321.074251) (xy 265.823166 -321.129624)
			(xy 265.793199 -321.18153) (xy 265.756712 -321.22908) (xy 265.714332 -321.27146) (xy 265.666782 -321.307947)
			(xy 265.614876 -321.337914) (xy 265.559503 -321.36085) (xy 265.50161 -321.376363) (xy 265.442188 -321.384186)
			(xy 265.382252 -321.384186) (xy 265.32283 -321.376363) (xy 265.264937 -321.36085) (xy 265.209564 -321.337914)
			(xy 265.157658 -321.307947) (xy 265.110108 -321.27146) (xy 265.067728 -321.22908) (xy 265.031241 -321.18153)
			(xy 265.001274 -321.129624) (xy 264.978338 -321.074251) (xy 264.962825 -321.016358) (xy 264.955002 -320.956936)
			(xy 256.219452 -320.956936) (xy 256.219452 -322.966334) (xy 256.234797 -322.989554) (xy 256.259087 -323.03963)
			(xy 256.2756 -323.092779) (xy 256.283964 -323.147802) (xy 256.284476 -323.17563) (xy 256.284476 -323.407786)
			(xy 256.866644 -323.407786) (xy 256.866644 -321.926966) (xy 257.142742 -321.650868) (xy 258.877562 -321.650868)
			(xy 259.089652 -321.863212) (xy 259.276342 -321.676268) (xy 261.011162 -321.676268) (xy 261.060671 -321.725777)
			(xy 261.46251 -321.725777) (xy 261.46251 -321.672479) (xy 261.470453 -321.619775) (xy 261.486163 -321.568845)
			(xy 261.509289 -321.520824) (xy 261.539313 -321.476787) (xy 261.575565 -321.437716) (xy 261.617236 -321.404485)
			(xy 261.663394 -321.377836) (xy 261.713008 -321.358364) (xy 261.76497 -321.346504) (xy 261.81812 -321.342521)
			(xy 261.87127 -321.346504) (xy 261.923232 -321.358364) (xy 261.972846 -321.377836) (xy 262.019004 -321.404485)
			(xy 262.060675 -321.437716) (xy 262.096927 -321.476787) (xy 262.126951 -321.520824) (xy 262.150077 -321.568845)
			(xy 262.165787 -321.619775) (xy 262.17373 -321.672479) (xy 262.174228 -321.699128) (xy 262.17373 -321.725777)
			(xy 262.165787 -321.778481) (xy 262.150077 -321.829411) (xy 262.126951 -321.877432) (xy 262.096927 -321.921469)
			(xy 262.060675 -321.96054) (xy 262.019004 -321.993771) (xy 261.972846 -322.02042) (xy 261.923232 -322.039892)
			(xy 261.87127 -322.051752) (xy 261.81812 -322.055736) (xy 261.76497 -322.051752) (xy 261.713008 -322.039892)
			(xy 261.663394 -322.02042) (xy 261.617236 -321.993771) (xy 261.575565 -321.96054) (xy 261.539313 -321.921469)
			(xy 261.509289 -321.877432) (xy 261.486163 -321.829411) (xy 261.470453 -321.778481) (xy 261.46251 -321.725777)
			(xy 261.060671 -321.725777) (xy 261.28726 -321.952366) (xy 261.28726 -323.433186) (xy 262.480044 -323.433186)
			(xy 262.480044 -321.952366) (xy 262.756142 -321.676268) (xy 264.490962 -321.676268) (xy 264.76706 -321.952366)
			(xy 264.76706 -323.433186) (xy 266.544044 -323.433186) (xy 266.544044 -321.952366) (xy 266.820142 -321.676268)
			(xy 268.554962 -321.676268) (xy 268.83106 -321.952366) (xy 268.83106 -323.433186) (xy 270.023844 -323.433186)
			(xy 270.023844 -321.952366) (xy 270.299942 -321.676268) (xy 272.034762 -321.676268) (xy 272.31086 -321.952366)
			(xy 272.31086 -323.433186) (xy 274.087844 -323.433186) (xy 274.087844 -321.952366) (xy 274.363942 -321.676268)
			(xy 276.098762 -321.676268) (xy 276.37486 -321.952366) (xy 276.37486 -323.433186) (xy 277.567644 -323.433186)
			(xy 277.567644 -321.952366) (xy 277.843742 -321.676268) (xy 279.578562 -321.676268) (xy 279.85466 -321.952366)
			(xy 279.85466 -323.433186) (xy 279.324562 -323.963284) (xy 278.097742 -323.963284) (xy 277.567644 -323.433186)
			(xy 276.37486 -323.433186) (xy 275.844762 -323.963284) (xy 274.617942 -323.963284) (xy 274.087844 -323.433186)
			(xy 272.31086 -323.433186) (xy 271.780762 -323.963284) (xy 270.553942 -323.963284) (xy 270.023844 -323.433186)
			(xy 268.83106 -323.433186) (xy 268.300962 -323.963284) (xy 267.074142 -323.963284) (xy 266.544044 -323.433186)
			(xy 264.76706 -323.433186) (xy 264.236962 -323.963284) (xy 263.010142 -323.963284) (xy 262.480044 -323.433186)
			(xy 261.28726 -323.433186) (xy 260.757162 -323.963284) (xy 259.530342 -323.963284) (xy 259.064252 -323.49694)
			(xy 258.623562 -323.937884) (xy 257.396742 -323.937884) (xy 256.866644 -323.407786) (xy 256.284476 -323.407786)
			(xy 256.284476 -324.2945) (xy 256.34823 -324.358254) (xy 311.806844 -324.358254) (xy 311.806844 -321.952366)
			(xy 312.082942 -321.676268) (xy 313.817762 -321.676268) (xy 314.09386 -321.952366) (xy 314.09386 -323.222366)
			(xy 314.10148 -323.229986) (xy 314.10148 -324.46468) (xy 313.840622 -324.725284) (xy 312.174128 -324.725284)
			(xy 311.806844 -324.358254) (xy 256.34823 -324.358254) (xy 256.644648 -324.654672) (xy 259.818378 -324.654672)
			(xy 259.847459 -324.655212) (xy 259.904904 -324.664315) (xy 259.960216 -324.6823) (xy 260.01203 -324.708724)
			(xy 260.059067 -324.742934) (xy 260.079998 -324.76313) (xy 261.159498 -325.84263) (xy 261.179684 -325.863568)
			(xy 261.213882 -325.910609) (xy 261.240299 -325.962422) (xy 261.258282 -326.01773) (xy 261.26739 -326.075171)
			(xy 261.267956 -326.10425) (xy 261.267956 -327.10898) (xy 264.137521 -327.10898) (xy 264.137521 -327.02442)
			(xy 264.145324 -326.94022) (xy 264.160862 -326.857099) (xy 264.184004 -326.775767) (xy 264.214552 -326.696917)
			(xy 264.252245 -326.621222) (xy 264.296762 -326.549328) (xy 264.347723 -326.481848) (xy 264.404692 -326.419358)
			(xy 264.467185 -326.362392) (xy 264.534667 -326.311435) (xy 264.606564 -326.266922) (xy 264.682261 -326.229233)
			(xy 264.761112 -326.198689) (xy 264.842446 -326.175551) (xy 264.925567 -326.160017) (xy 265.009768 -326.152219)
			(xy 265.052048 -326.151748) (xy 266.296648 -326.151748) (xy 266.338921 -326.152326) (xy 266.423105 -326.160131)
			(xy 266.50621 -326.17567) (xy 266.587527 -326.198811) (xy 266.666362 -326.229355) (xy 266.742043 -326.267043)
			(xy 266.813923 -326.311553) (xy 266.881391 -326.362505) (xy 266.943869 -326.419465) (xy 267.000825 -326.481946)
			(xy 267.051774 -326.549416) (xy 267.09628 -326.621299) (xy 267.133964 -326.696982) (xy 267.164504 -326.775818)
			(xy 267.187641 -326.857136) (xy 267.203175 -326.940242) (xy 267.210976 -327.024427) (xy 267.210976 -327.108973)
			(xy 267.210975 -327.10898) (xy 271.681321 -327.10898) (xy 271.681321 -327.02442) (xy 271.689124 -326.94022)
			(xy 271.704662 -326.857099) (xy 271.727804 -326.775767) (xy 271.758352 -326.696917) (xy 271.796045 -326.621222)
			(xy 271.840562 -326.549328) (xy 271.891523 -326.481848) (xy 271.948492 -326.419358) (xy 272.010985 -326.362392)
			(xy 272.078467 -326.311435) (xy 272.150364 -326.266922) (xy 272.226061 -326.229233) (xy 272.304912 -326.198689)
			(xy 272.386246 -326.175551) (xy 272.469367 -326.160017) (xy 272.553568 -326.152219) (xy 272.595848 -326.151748)
			(xy 273.840448 -326.151748) (xy 273.882721 -326.152326) (xy 273.966905 -326.160131) (xy 274.05001 -326.17567)
			(xy 274.131327 -326.198811) (xy 274.210162 -326.229355) (xy 274.285843 -326.267043) (xy 274.357723 -326.311553)
			(xy 274.425191 -326.362505) (xy 274.487669 -326.419465) (xy 274.544625 -326.481946) (xy 274.595574 -326.549416)
			(xy 274.64008 -326.621299) (xy 274.677764 -326.696982) (xy 274.708304 -326.775818) (xy 274.731441 -326.857136)
			(xy 274.746975 -326.940242) (xy 274.754776 -327.024427) (xy 274.754776 -327.108973) (xy 274.754775 -327.10898)
			(xy 279.225121 -327.10898) (xy 279.225121 -327.02442) (xy 279.232924 -326.94022) (xy 279.248462 -326.857099)
			(xy 279.271604 -326.775767) (xy 279.302152 -326.696917) (xy 279.339845 -326.621222) (xy 279.384362 -326.549328)
			(xy 279.435323 -326.481848) (xy 279.492292 -326.419358) (xy 279.554785 -326.362392) (xy 279.622267 -326.311435)
			(xy 279.694164 -326.266922) (xy 279.769861 -326.229233) (xy 279.848712 -326.198689) (xy 279.930046 -326.175551)
			(xy 280.013167 -326.160017) (xy 280.097368 -326.152219) (xy 280.139648 -326.151748) (xy 281.384248 -326.151748)
			(xy 281.426521 -326.152326) (xy 281.510705 -326.160131) (xy 281.59381 -326.17567) (xy 281.675127 -326.198811)
			(xy 281.753962 -326.229355) (xy 281.829643 -326.267043) (xy 281.901523 -326.311553) (xy 281.968991 -326.362505)
			(xy 282.031469 -326.419465) (xy 282.088425 -326.481946) (xy 282.139374 -326.549416) (xy 282.18388 -326.621299)
			(xy 282.221564 -326.696982) (xy 282.252104 -326.775818) (xy 282.275241 -326.857136) (xy 282.290775 -326.940242)
			(xy 282.298576 -327.024427) (xy 282.298576 -327.108973) (xy 282.298575 -327.10898) (xy 286.768921 -327.10898)
			(xy 286.768921 -327.02442) (xy 286.776724 -326.94022) (xy 286.792262 -326.857099) (xy 286.815404 -326.775767)
			(xy 286.845952 -326.696917) (xy 286.883645 -326.621222) (xy 286.928162 -326.549328) (xy 286.979123 -326.481848)
			(xy 287.036092 -326.419358) (xy 287.098585 -326.362392) (xy 287.166067 -326.311435) (xy 287.237964 -326.266922)
			(xy 287.313661 -326.229233) (xy 287.392512 -326.198689) (xy 287.473846 -326.175551) (xy 287.556967 -326.160017)
			(xy 287.641168 -326.152219) (xy 287.683448 -326.151748) (xy 288.928048 -326.151748) (xy 288.970321 -326.152326)
			(xy 289.054505 -326.160131) (xy 289.13761 -326.17567) (xy 289.218927 -326.198811) (xy 289.297762 -326.229355)
			(xy 289.373443 -326.267043) (xy 289.445323 -326.311553) (xy 289.512791 -326.362505) (xy 289.575269 -326.419465)
			(xy 289.632225 -326.481946) (xy 289.683174 -326.549416) (xy 289.72768 -326.621299) (xy 289.765364 -326.696982)
			(xy 289.795904 -326.775818) (xy 289.807903 -326.81799) (xy 293.396668 -326.81799) (xy 293.400739 -326.762368)
			(xy 293.412865 -326.707931) (xy 293.432788 -326.65584) (xy 293.460084 -326.607205) (xy 293.49417 -326.563062)
			(xy 293.534319 -326.524353) (xy 293.579677 -326.491902) (xy 293.629277 -326.466401) (xy 293.682061 -326.448394)
			(xy 293.736904 -326.438264) (xy 293.792638 -326.436227) (xy 293.848075 -326.442327) (xy 293.902032 -326.456433)
			(xy 293.953361 -326.478245) (xy 294.000967 -326.507299) (xy 294.043835 -326.542974) (xy 294.081052 -326.584511)
			(xy 294.111825 -326.631024) (xy 294.135497 -326.681521) (xy 294.151565 -326.734928) (xy 294.159685 -326.790104)
			(xy 294.160194 -326.81799) (xy 294.159685 -326.845876) (xy 294.151565 -326.901052) (xy 294.135497 -326.954459)
			(xy 294.111825 -327.004956) (xy 294.081052 -327.051469) (xy 294.043835 -327.093006) (xy 294.02464 -327.10898)
			(xy 294.312721 -327.10898) (xy 294.312721 -327.02442) (xy 294.320524 -326.94022) (xy 294.336062 -326.857099)
			(xy 294.359204 -326.775767) (xy 294.389752 -326.696917) (xy 294.427445 -326.621222) (xy 294.471962 -326.549328)
			(xy 294.522923 -326.481848) (xy 294.579892 -326.419358) (xy 294.642385 -326.362392) (xy 294.709867 -326.311435)
			(xy 294.781764 -326.266922) (xy 294.857461 -326.229233) (xy 294.936312 -326.198689) (xy 295.017646 -326.175551)
			(xy 295.100767 -326.160017) (xy 295.184968 -326.152219) (xy 295.227248 -326.151748) (xy 296.471848 -326.151748)
			(xy 296.514121 -326.152326) (xy 296.598305 -326.160131) (xy 296.68141 -326.17567) (xy 296.762727 -326.198811)
			(xy 296.841562 -326.229355) (xy 296.917243 -326.267043) (xy 296.989123 -326.311553) (xy 297.056591 -326.362505)
			(xy 297.119069 -326.419465) (xy 297.176025 -326.481946) (xy 297.226974 -326.549416) (xy 297.27148 -326.621299)
			(xy 297.309164 -326.696982) (xy 297.339704 -326.775818) (xy 297.362841 -326.857136) (xy 297.378375 -326.940242)
			(xy 297.386176 -327.024427) (xy 297.386176 -327.108973) (xy 297.386175 -327.10898) (xy 301.856521 -327.10898)
			(xy 301.856521 -327.02442) (xy 301.864324 -326.94022) (xy 301.879862 -326.857099) (xy 301.903004 -326.775767)
			(xy 301.933552 -326.696917) (xy 301.971245 -326.621222) (xy 302.015762 -326.549328) (xy 302.066723 -326.481848)
			(xy 302.123692 -326.419358) (xy 302.186185 -326.362392) (xy 302.253667 -326.311435) (xy 302.325564 -326.266922)
			(xy 302.401261 -326.229233) (xy 302.480112 -326.198689) (xy 302.561446 -326.175551) (xy 302.644567 -326.160017)
			(xy 302.728768 -326.152219) (xy 302.771048 -326.151748) (xy 304.015648 -326.151748) (xy 304.057921 -326.152326)
			(xy 304.142105 -326.160131) (xy 304.22521 -326.17567) (xy 304.306527 -326.198811) (xy 304.385362 -326.229355)
			(xy 304.461043 -326.267043) (xy 304.532923 -326.311553) (xy 304.600391 -326.362505) (xy 304.662869 -326.419465)
			(xy 304.719825 -326.481946) (xy 304.770774 -326.549416) (xy 304.81528 -326.621299) (xy 304.852964 -326.696982)
			(xy 304.883504 -326.775818) (xy 304.906641 -326.857136) (xy 304.922175 -326.940242) (xy 304.929976 -327.024427)
			(xy 304.929976 -327.108973) (xy 304.929975 -327.10898) (xy 309.400321 -327.10898) (xy 309.400321 -327.02442)
			(xy 309.408124 -326.94022) (xy 309.423662 -326.857099) (xy 309.446804 -326.775767) (xy 309.477352 -326.696917)
			(xy 309.515045 -326.621222) (xy 309.559562 -326.549328) (xy 309.610523 -326.481848) (xy 309.667492 -326.419358)
			(xy 309.729985 -326.362392) (xy 309.797467 -326.311435) (xy 309.869364 -326.266922) (xy 309.945061 -326.229233)
			(xy 310.023912 -326.198689) (xy 310.105246 -326.175551) (xy 310.188367 -326.160017) (xy 310.272568 -326.152219)
			(xy 310.314848 -326.151748) (xy 311.559448 -326.151748) (xy 311.601721 -326.152326) (xy 311.685905 -326.160131)
			(xy 311.76901 -326.17567) (xy 311.850327 -326.198811) (xy 311.929162 -326.229355) (xy 312.004843 -326.267043)
			(xy 312.076723 -326.311553) (xy 312.144191 -326.362505) (xy 312.206669 -326.419465) (xy 312.263625 -326.481946)
			(xy 312.314574 -326.549416) (xy 312.35908 -326.621299) (xy 312.396764 -326.696982) (xy 312.427304 -326.775818)
			(xy 312.450441 -326.857136) (xy 312.465975 -326.940242) (xy 312.473776 -327.024427) (xy 312.473776 -327.108973)
			(xy 312.465975 -327.193158) (xy 312.450441 -327.276264) (xy 312.427304 -327.357582) (xy 312.396764 -327.436418)
			(xy 312.35908 -327.512101) (xy 312.314574 -327.583984) (xy 312.263625 -327.651454) (xy 312.206669 -327.713935)
			(xy 312.144191 -327.770895) (xy 312.076724 -327.821847) (xy 312.004843 -327.866357) (xy 311.929162 -327.904045)
			(xy 311.850327 -327.934589) (xy 311.76901 -327.95773) (xy 311.685905 -327.973269) (xy 311.601721 -327.981074)
			(xy 311.559448 -327.981564) (xy 310.314848 -327.981564) (xy 310.272568 -327.981181) (xy 310.188367 -327.973383)
			(xy 310.105246 -327.957849) (xy 310.023912 -327.934711) (xy 309.945061 -327.904167) (xy 309.869364 -327.866478)
			(xy 309.797467 -327.821965) (xy 309.729985 -327.771008) (xy 309.667492 -327.714042) (xy 309.610523 -327.651552)
			(xy 309.559562 -327.584072) (xy 309.515045 -327.512178) (xy 309.477352 -327.436483) (xy 309.446804 -327.357633)
			(xy 309.423662 -327.276301) (xy 309.408124 -327.19318) (xy 309.400321 -327.10898) (xy 304.929975 -327.10898)
			(xy 304.922175 -327.193158) (xy 304.906641 -327.276264) (xy 304.883504 -327.357582) (xy 304.852964 -327.436418)
			(xy 304.81528 -327.512101) (xy 304.770774 -327.583984) (xy 304.719825 -327.651454) (xy 304.662869 -327.713935)
			(xy 304.600391 -327.770895) (xy 304.532924 -327.821847) (xy 304.461043 -327.866357) (xy 304.385362 -327.904045)
			(xy 304.306527 -327.934589) (xy 304.22521 -327.95773) (xy 304.142105 -327.973269) (xy 304.057921 -327.981074)
			(xy 304.015648 -327.981564) (xy 302.771048 -327.981564) (xy 302.728768 -327.981181) (xy 302.644567 -327.973383)
			(xy 302.561446 -327.957849) (xy 302.480112 -327.934711) (xy 302.401261 -327.904167) (xy 302.325564 -327.866478)
			(xy 302.253667 -327.821965) (xy 302.186185 -327.771008) (xy 302.123692 -327.714042) (xy 302.066723 -327.651552)
			(xy 302.015762 -327.584072) (xy 301.971245 -327.512178) (xy 301.933552 -327.436483) (xy 301.903004 -327.357633)
			(xy 301.879862 -327.276301) (xy 301.864324 -327.19318) (xy 301.856521 -327.10898) (xy 297.386175 -327.10898)
			(xy 297.378375 -327.193158) (xy 297.362841 -327.276264) (xy 297.339704 -327.357582) (xy 297.309164 -327.436418)
			(xy 297.27148 -327.512101) (xy 297.226974 -327.583984) (xy 297.176025 -327.651454) (xy 297.119069 -327.713935)
			(xy 297.056591 -327.770895) (xy 296.989124 -327.821847) (xy 296.917243 -327.866357) (xy 296.841562 -327.904045)
			(xy 296.762727 -327.934589) (xy 296.68141 -327.95773) (xy 296.598305 -327.973269) (xy 296.514121 -327.981074)
			(xy 296.471848 -327.981564) (xy 295.227248 -327.981564) (xy 295.184968 -327.981181) (xy 295.100767 -327.973383)
			(xy 295.017646 -327.957849) (xy 294.936312 -327.934711) (xy 294.857461 -327.904167) (xy 294.781764 -327.866478)
			(xy 294.709867 -327.821965) (xy 294.642385 -327.771008) (xy 294.579892 -327.714042) (xy 294.522923 -327.651552)
			(xy 294.471962 -327.584072) (xy 294.427445 -327.512178) (xy 294.389752 -327.436483) (xy 294.359204 -327.357633)
			(xy 294.336062 -327.276301) (xy 294.320524 -327.19318) (xy 294.312721 -327.10898) (xy 294.02464 -327.10898)
			(xy 294.000967 -327.128681) (xy 293.953361 -327.157735) (xy 293.902032 -327.179547) (xy 293.848075 -327.193653)
			(xy 293.792638 -327.199753) (xy 293.736904 -327.197716) (xy 293.682061 -327.187586) (xy 293.629277 -327.169579)
			(xy 293.579677 -327.144078) (xy 293.534319 -327.111627) (xy 293.49417 -327.072918) (xy 293.460084 -327.028775)
			(xy 293.432788 -326.98014) (xy 293.412865 -326.928049) (xy 293.400739 -326.873612) (xy 293.396668 -326.81799)
			(xy 289.807903 -326.81799) (xy 289.819041 -326.857136) (xy 289.834575 -326.940242) (xy 289.842376 -327.024427)
			(xy 289.842376 -327.108973) (xy 289.834575 -327.193158) (xy 289.819041 -327.276264) (xy 289.795904 -327.357582)
			(xy 289.765364 -327.436418) (xy 289.72768 -327.512101) (xy 289.683174 -327.583984) (xy 289.632225 -327.651454)
			(xy 289.575269 -327.713935) (xy 289.512791 -327.770895) (xy 289.445324 -327.821847) (xy 289.373443 -327.866357)
			(xy 289.297762 -327.904045) (xy 289.218927 -327.934589) (xy 289.13761 -327.95773) (xy 289.054505 -327.973269)
			(xy 288.970321 -327.981074) (xy 288.928048 -327.981564) (xy 287.683448 -327.981564) (xy 287.641168 -327.981181)
			(xy 287.556967 -327.973383) (xy 287.473846 -327.957849) (xy 287.392512 -327.934711) (xy 287.313661 -327.904167)
			(xy 287.237964 -327.866478) (xy 287.166067 -327.821965) (xy 287.098585 -327.771008) (xy 287.036092 -327.714042)
			(xy 286.979123 -327.651552) (xy 286.928162 -327.584072) (xy 286.883645 -327.512178) (xy 286.845952 -327.436483)
			(xy 286.815404 -327.357633) (xy 286.792262 -327.276301) (xy 286.776724 -327.19318) (xy 286.768921 -327.10898)
			(xy 282.298575 -327.10898) (xy 282.290775 -327.193158) (xy 282.275241 -327.276264) (xy 282.252104 -327.357582)
			(xy 282.221564 -327.436418) (xy 282.18388 -327.512101) (xy 282.139374 -327.583984) (xy 282.088425 -327.651454)
			(xy 282.031469 -327.713935) (xy 281.968991 -327.770895) (xy 281.901524 -327.821847) (xy 281.829643 -327.866357)
			(xy 281.753962 -327.904045) (xy 281.675127 -327.934589) (xy 281.59381 -327.95773) (xy 281.510705 -327.973269)
			(xy 281.426521 -327.981074) (xy 281.384248 -327.981564) (xy 280.139648 -327.981564) (xy 280.097368 -327.981181)
			(xy 280.013167 -327.973383) (xy 279.930046 -327.957849) (xy 279.848712 -327.934711) (xy 279.769861 -327.904167)
			(xy 279.694164 -327.866478) (xy 279.622267 -327.821965) (xy 279.554785 -327.771008) (xy 279.492292 -327.714042)
			(xy 279.435323 -327.651552) (xy 279.384362 -327.584072) (xy 279.339845 -327.512178) (xy 279.302152 -327.436483)
			(xy 279.271604 -327.357633) (xy 279.248462 -327.276301) (xy 279.232924 -327.19318) (xy 279.225121 -327.10898)
			(xy 274.754775 -327.10898) (xy 274.746975 -327.193158) (xy 274.731441 -327.276264) (xy 274.708304 -327.357582)
			(xy 274.677764 -327.436418) (xy 274.64008 -327.512101) (xy 274.595574 -327.583984) (xy 274.544625 -327.651454)
			(xy 274.487669 -327.713935) (xy 274.425191 -327.770895) (xy 274.357724 -327.821847) (xy 274.285843 -327.866357)
			(xy 274.210162 -327.904045) (xy 274.131327 -327.934589) (xy 274.05001 -327.95773) (xy 273.966905 -327.973269)
			(xy 273.882721 -327.981074) (xy 273.840448 -327.981564) (xy 272.595848 -327.981564) (xy 272.553568 -327.981181)
			(xy 272.469367 -327.973383) (xy 272.386246 -327.957849) (xy 272.304912 -327.934711) (xy 272.226061 -327.904167)
			(xy 272.150364 -327.866478) (xy 272.078467 -327.821965) (xy 272.010985 -327.771008) (xy 271.948492 -327.714042)
			(xy 271.891523 -327.651552) (xy 271.840562 -327.584072) (xy 271.796045 -327.512178) (xy 271.758352 -327.436483)
			(xy 271.727804 -327.357633) (xy 271.704662 -327.276301) (xy 271.689124 -327.19318) (xy 271.681321 -327.10898)
			(xy 267.210975 -327.10898) (xy 267.203175 -327.193158) (xy 267.187641 -327.276264) (xy 267.164504 -327.357582)
			(xy 267.133964 -327.436418) (xy 267.09628 -327.512101) (xy 267.051774 -327.583984) (xy 267.000825 -327.651454)
			(xy 266.943869 -327.713935) (xy 266.881391 -327.770895) (xy 266.813924 -327.821847) (xy 266.742043 -327.866357)
			(xy 266.666362 -327.904045) (xy 266.587527 -327.934589) (xy 266.50621 -327.95773) (xy 266.423105 -327.973269)
			(xy 266.338921 -327.981074) (xy 266.296648 -327.981564) (xy 265.052048 -327.981564) (xy 265.009768 -327.981181)
			(xy 264.925567 -327.973383) (xy 264.842446 -327.957849) (xy 264.761112 -327.934711) (xy 264.682261 -327.904167)
			(xy 264.606564 -327.866478) (xy 264.534667 -327.821965) (xy 264.467185 -327.771008) (xy 264.404692 -327.714042)
			(xy 264.347723 -327.651552) (xy 264.296762 -327.584072) (xy 264.252245 -327.512178) (xy 264.214552 -327.436483)
			(xy 264.184004 -327.357633) (xy 264.160862 -327.276301) (xy 264.145324 -327.19318) (xy 264.137521 -327.10898)
			(xy 261.267956 -327.10898) (xy 261.267956 -327.586848) (xy 264.806684 -331.125576) (xy 265.33094 -331.125576)
			(xy 274.324572 -340.119208) (xy 316.41288 -340.119208)
		)
		(stroke
			(width 0)
			(type solid)
		)
		(fill yes)
		(layer "B.Cu")
		(net "P12V_S3_AUX_CPU0_NVDIMM")
	)
	(gr_poly
		(pts
			(xy 218.6432 -332.958948) (xy 218.6432 -320.101468) (xy 218.572588 -320.030856) (xy 214.783162 -320.030856)
			(xy 214.772494 -320.03619) (xy 214.747865 -320.047738) (xy 214.695977 -320.064053) (xy 214.642211 -320.072284)
			(xy 214.615014 -320.072766) (xy 214.587819 -320.072268) (xy 214.534055 -320.064033) (xy 214.482169 -320.047722)
			(xy 214.457534 -320.03619) (xy 214.446866 -320.030856) (xy 211.099654 -320.030856) (xy 211.078718 -320.051171)
			(xy 211.032453 -320.086707) (xy 210.981942 -320.115892) (xy 210.92805 -320.138228) (xy 210.871701 -320.153329)
			(xy 210.813863 -320.160938) (xy 210.784694 -320.161412) (xy 210.514946 -320.161412) (xy 210.504261 -320.161356)
			(xy 210.482916 -320.160342) (xy 210.472274 -320.15938) (xy 210.457994 -320.158513) (xy 210.429891 -320.163809)
			(xy 210.404353 -320.176677) (xy 210.383374 -320.196112) (xy 210.368595 -320.220594) (xy 210.36117 -320.248211)
			(xy 210.361681 -320.276803) (xy 210.370086 -320.304137) (xy 210.377532 -320.316352) (xy 210.395171 -320.344416)
			(xy 210.42306 -320.404547) (xy 210.441996 -320.468068) (xy 210.451587 -320.533655) (xy 210.452208 -320.566796)
			(xy 210.451718 -320.596764) (xy 210.443895 -320.656186) (xy 210.428382 -320.714079) (xy 210.405446 -320.769452)
			(xy 210.375479 -320.821358) (xy 210.338992 -320.868908) (xy 210.296612 -320.911288) (xy 210.249062 -320.947775)
			(xy 210.197156 -320.977742) (xy 210.141783 -321.000678) (xy 210.08389 -321.016191) (xy 210.024468 -321.024014)
			(xy 209.964532 -321.024014) (xy 209.90511 -321.016191) (xy 209.847217 -321.000678) (xy 209.791844 -320.977742)
			(xy 209.739938 -320.947775) (xy 209.692388 -320.911288) (xy 209.650008 -320.868908) (xy 209.613521 -320.821358)
			(xy 209.583554 -320.769452) (xy 209.560618 -320.714079) (xy 209.545105 -320.656186) (xy 209.537282 -320.596764)
			(xy 209.536792 -320.566796) (xy 209.537246 -320.537718) (xy 209.54462 -320.480031) (xy 209.559248 -320.423744)
			(xy 209.580894 -320.369766) (xy 209.609209 -320.318968) (xy 209.643736 -320.27217) (xy 209.683918 -320.230127)
			(xy 209.70621 -320.21145) (xy 209.716759 -320.202356) (xy 209.732863 -320.179642) (xy 209.742231 -320.153422)
			(xy 209.744168 -320.125647) (xy 209.738528 -320.098381) (xy 209.725732 -320.073652) (xy 209.706732 -320.0533)
			(xy 209.682939 -320.038838) (xy 209.656124 -320.031342) (xy 209.642202 -320.030856) (xy 207.508856 -320.030856)
			(xy 207.504792 -320.031618) (xy 207.491869 -320.033633) (xy 207.465801 -320.035798) (xy 207.452722 -320.035936)
			(xy 206.687928 -320.035936) (xy 206.666291 -320.057434) (xy 206.618313 -320.095095) (xy 206.56576 -320.126052)
			(xy 206.509561 -320.149758) (xy 206.450713 -320.165793) (xy 206.390257 -320.173873) (xy 206.35976 -320.174366)
			(xy 206.3287 -320.173844) (xy 206.267151 -320.165434) (xy 206.207307 -320.148774) (xy 206.150266 -320.124172)
			(xy 206.097078 -320.092078) (xy 206.048722 -320.053083) (xy 206.02702 -320.030856) (xy 203.555854 -320.030856)
			(xy 203.534918 -320.051171) (xy 203.488653 -320.086707) (xy 203.438142 -320.115892) (xy 203.38425 -320.138228)
			(xy 203.327901 -320.153329) (xy 203.270063 -320.160938) (xy 203.240894 -320.161412) (xy 202.971146 -320.161412)
			(xy 202.943593 -320.161013) (xy 202.888907 -320.154235) (xy 202.835477 -320.140752) (xy 202.784122 -320.120772)
			(xy 202.735629 -320.094599) (xy 202.690742 -320.062636) (xy 202.670156 -320.044318) (xy 202.655678 -320.030856)
			(xy 202.50912 -320.030856) (xy 202.50912 -320.118994) (xy 202.54468 -320.13017) (xy 202.572201 -320.139289)
			(xy 202.624874 -320.163519) (xy 202.674066 -320.194207) (xy 202.718989 -320.23086) (xy 202.758925 -320.272891)
			(xy 202.793234 -320.319629) (xy 202.821367 -320.370325) (xy 202.842875 -320.424167) (xy 202.857411 -320.480294)
			(xy 202.864745 -320.537807) (xy 202.865228 -320.566796) (xy 202.864738 -320.596764) (xy 202.856915 -320.656186)
			(xy 202.841402 -320.714079) (xy 202.818466 -320.769452) (xy 202.788499 -320.821358) (xy 202.752012 -320.868908)
			(xy 202.709632 -320.911288) (xy 202.662082 -320.947775) (xy 202.610176 -320.977742) (xy 202.554803 -321.000678)
			(xy 202.49691 -321.016191) (xy 202.437488 -321.024014) (xy 202.377552 -321.024014) (xy 202.31813 -321.016191)
			(xy 202.260237 -321.000678) (xy 202.204864 -320.977742) (xy 202.152958 -320.947775) (xy 202.105408 -320.911288)
			(xy 202.063028 -320.868908) (xy 202.026541 -320.821358) (xy 201.996574 -320.769452) (xy 201.973638 -320.714079)
			(xy 201.958125 -320.656186) (xy 201.950302 -320.596764) (xy 201.949812 -320.566796) (xy 201.950266 -320.537718)
			(xy 201.95764 -320.480031) (xy 201.972269 -320.423745) (xy 201.993916 -320.369768) (xy 202.022232 -320.318971)
			(xy 202.05676 -320.272174) (xy 202.096942 -320.230132) (xy 202.11923 -320.21145) (xy 202.129778 -320.202354)
			(xy 202.145879 -320.179639) (xy 202.155245 -320.153419) (xy 202.15718 -320.125644) (xy 202.151541 -320.098379)
			(xy 202.138746 -320.07365) (xy 202.119747 -320.053297) (xy 202.095957 -320.038833) (xy 202.069144 -320.031332)
			(xy 202.055222 -320.030856) (xy 200.128124 -320.030856) (xy 200.12406 -320.031618) (xy 200.111137 -320.033632)
			(xy 200.085069 -320.035794) (xy 200.07199 -320.035936) (xy 199.34682 -320.035936) (xy 199.333358 -320.065908)
			(xy 199.321071 -320.092558) (xy 199.290651 -320.142745) (xy 199.254062 -320.188629) (xy 199.211905 -320.229455)
			(xy 199.164872 -320.264555) (xy 199.113736 -320.29335) (xy 199.059337 -320.315368) (xy 199.002568 -320.330247)
			(xy 198.944363 -320.337743) (xy 198.91502 -320.338196) (xy 198.885408 -320.337731) (xy 198.826679 -320.330096)
			(xy 198.769425 -320.314951) (xy 198.714602 -320.29255) (xy 198.663125 -320.263266) (xy 198.615855 -320.227587)
			(xy 198.57358 -320.186111) (xy 198.537007 -320.13953) (xy 198.506747 -320.088621) (xy 198.49465 -320.06159)
			(xy 198.481442 -320.030856) (xy 196.012054 -320.030856) (xy 195.991118 -320.051171) (xy 195.944853 -320.086707)
			(xy 195.894342 -320.115892) (xy 195.84045 -320.138228) (xy 195.784101 -320.153329) (xy 195.726263 -320.160938)
			(xy 195.697094 -320.161412) (xy 195.427346 -320.161412) (xy 195.399793 -320.161013) (xy 195.345107 -320.154235)
			(xy 195.291677 -320.140752) (xy 195.240322 -320.120772) (xy 195.191829 -320.094599) (xy 195.146942 -320.062636)
			(xy 195.126356 -320.044318) (xy 195.111878 -320.030856) (xy 194.93992 -320.030856) (xy 194.93992 -320.118994)
			(xy 194.97548 -320.13017) (xy 195.003001 -320.139289) (xy 195.055674 -320.163519) (xy 195.104866 -320.194207)
			(xy 195.149789 -320.23086) (xy 195.189725 -320.272891) (xy 195.224034 -320.319629) (xy 195.252167 -320.370325)
			(xy 195.273675 -320.424167) (xy 195.288211 -320.480294) (xy 195.295545 -320.537807) (xy 195.296028 -320.566796)
			(xy 195.295538 -320.596764) (xy 195.287715 -320.656186) (xy 195.272202 -320.714079) (xy 195.249266 -320.769452)
			(xy 195.219299 -320.821358) (xy 195.182812 -320.868908) (xy 195.140432 -320.911288) (xy 195.092882 -320.947775)
			(xy 195.040976 -320.977742) (xy 194.985603 -321.000678) (xy 194.92771 -321.016191) (xy 194.868288 -321.024014)
			(xy 194.808352 -321.024014) (xy 194.74893 -321.016191) (xy 194.691037 -321.000678) (xy 194.635664 -320.977742)
			(xy 194.583758 -320.947775) (xy 194.536208 -320.911288) (xy 194.493828 -320.868908) (xy 194.457341 -320.821358)
			(xy 194.427374 -320.769452) (xy 194.404438 -320.714079) (xy 194.388925 -320.656186) (xy 194.381102 -320.596764)
			(xy 194.380612 -320.566796) (xy 194.381066 -320.537718) (xy 194.38844 -320.480031) (xy 194.403069 -320.423745)
			(xy 194.424716 -320.369768) (xy 194.453032 -320.318971) (xy 194.48756 -320.272174) (xy 194.527742 -320.230132)
			(xy 194.55003 -320.21145) (xy 194.560578 -320.202354) (xy 194.576679 -320.179639) (xy 194.586045 -320.153419)
			(xy 194.58798 -320.125644) (xy 194.582341 -320.098379) (xy 194.569546 -320.07365) (xy 194.550547 -320.053297)
			(xy 194.526757 -320.038833) (xy 194.499944 -320.031332) (xy 194.486022 -320.030856) (xy 192.945258 -320.030856)
			(xy 192.848992 -320.126868) (xy 192.830945 -320.144279) (xy 192.790394 -320.173774) (xy 192.745724 -320.196555)
			(xy 192.698038 -320.212058) (xy 192.648512 -320.219902) (xy 192.62344 -320.22034) (xy 191.876172 -320.22034)
			(xy 191.720216 -320.37655) (xy 191.719454 -320.39687) (xy 191.718135 -320.42625) (xy 191.70889 -320.48433)
			(xy 191.692282 -320.540747) (xy 191.668585 -320.594573) (xy 191.63819 -320.64492) (xy 191.601596 -320.69096)
			(xy 191.559407 -320.731934) (xy 191.512318 -320.767168) (xy 191.461104 -320.79608) (xy 191.406609 -320.818194)
			(xy 191.349731 -320.833147) (xy 191.291406 -320.840692) (xy 191.262 -320.841116) (xy 191.232032 -320.840626)
			(xy 191.172609 -320.832803) (xy 191.114716 -320.817291) (xy 191.059342 -320.794354) (xy 191.007436 -320.764387)
			(xy 190.959886 -320.727901) (xy 190.917505 -320.68552) (xy 190.881018 -320.63797) (xy 190.851049 -320.586065)
			(xy 190.828112 -320.530692) (xy 190.812599 -320.472799) (xy 190.804775 -320.413376) (xy 190.804292 -320.383408)
			(xy 190.804661 -320.356759) (xy 190.810849 -320.303823) (xy 190.823155 -320.251965) (xy 190.84141 -320.201892)
			(xy 190.85306 -320.177922) (xy 190.859226 -320.164461) (xy 190.864316 -320.135308) (xy 190.860836 -320.105919)
			(xy 190.849077 -320.07876) (xy 190.830027 -320.056112) (xy 190.805284 -320.039876) (xy 190.776926 -320.031412)
			(xy 190.762128 -320.030856) (xy 188.468254 -320.030856) (xy 188.447318 -320.051171) (xy 188.401053 -320.086707)
			(xy 188.350542 -320.115892) (xy 188.29665 -320.138228) (xy 188.240301 -320.153329) (xy 188.182463 -320.160938)
			(xy 188.153294 -320.161412) (xy 187.814966 -320.161412) (xy 187.80131 -320.161855) (xy 187.774976 -320.1691)
			(xy 187.751502 -320.183063) (xy 187.732567 -320.202746) (xy 187.719522 -320.226742) (xy 187.713302 -320.253336)
			(xy 187.714349 -320.280629) (xy 187.72259 -320.306668) (xy 187.729622 -320.318384) (xy 187.74699 -320.346265)
			(xy 187.774422 -320.405949) (xy 187.793035 -320.468944) (xy 187.802446 -320.533953) (xy 187.803028 -320.566796)
			(xy 187.802538 -320.596764) (xy 187.794715 -320.656186) (xy 187.779202 -320.714079) (xy 187.756266 -320.769452)
			(xy 187.726299 -320.821358) (xy 187.689812 -320.868908) (xy 187.647432 -320.911288) (xy 187.599882 -320.947775)
			(xy 187.547976 -320.977742) (xy 187.492603 -321.000678) (xy 187.43471 -321.016191) (xy 187.375288 -321.024014)
			(xy 187.315352 -321.024014) (xy 187.25593 -321.016191) (xy 187.198037 -321.000678) (xy 187.142664 -320.977742)
			(xy 187.090758 -320.947775) (xy 187.043208 -320.911288) (xy 187.000828 -320.868908) (xy 186.964341 -320.821358)
			(xy 186.934374 -320.769452) (xy 186.911438 -320.714079) (xy 186.895925 -320.656186) (xy 186.888102 -320.596764)
			(xy 186.887612 -320.566796) (xy 186.888199 -320.533954) (xy 186.897624 -320.468949) (xy 186.916237 -320.405956)
			(xy 186.943656 -320.346268) (xy 186.961018 -320.318384) (xy 186.968097 -320.306682) (xy 186.976379 -320.280627)
			(xy 186.977451 -320.253309) (xy 186.971237 -320.226686) (xy 186.958181 -320.202665) (xy 186.93922 -320.18297)
			(xy 186.915712 -320.169011) (xy 186.889344 -320.16179) (xy 186.875674 -320.161412) (xy 186.597036 -320.161412)
			(xy 186.567864 -320.160974) (xy 186.510017 -320.153383) (xy 186.45366 -320.138289) (xy 186.399763 -320.115949)
			(xy 186.349252 -320.086749) (xy 186.302997 -320.05119) (xy 186.282076 -320.030856) (xy 184.741566 -320.030856)
			(xy 184.737502 -320.031618) (xy 184.724579 -320.033633) (xy 184.698511 -320.035799) (xy 184.685432 -320.035936)
			(xy 184.147968 -320.035936) (xy 184.126332 -320.057436) (xy 184.078355 -320.095101) (xy 184.025802 -320.126063)
			(xy 183.969604 -320.149774) (xy 183.910755 -320.165814) (xy 183.850298 -320.173899) (xy 183.8198 -320.174366)
			(xy 183.788739 -320.173846) (xy 183.727188 -320.165441) (xy 183.667339 -320.148786) (xy 183.610295 -320.124186)
			(xy 183.557103 -320.092095) (xy 183.508743 -320.053103) (xy 183.48706 -320.030856) (xy 180.924454 -320.030856)
			(xy 180.903518 -320.051171) (xy 180.857253 -320.086707) (xy 180.806742 -320.115892) (xy 180.75285 -320.138228)
			(xy 180.696501 -320.153329) (xy 180.638663 -320.160938) (xy 180.609494 -320.161412) (xy 180.339746 -320.161412)
			(xy 180.3273 -320.161412) (xy 180.313475 -320.161493) (xy 180.286658 -320.168167) (xy 180.262613 -320.181789)
			(xy 180.243102 -320.20136) (xy 180.229553 -320.225446) (xy 180.22296 -320.252283) (xy 180.223805 -320.279905)
			(xy 180.232027 -320.306289) (xy 180.239162 -320.31813) (xy 180.256539 -320.346043) (xy 180.283984 -320.405791)
			(xy 180.302606 -320.468849) (xy 180.312021 -320.533921) (xy 180.312568 -320.566796) (xy 180.312078 -320.596764)
			(xy 180.304255 -320.656186) (xy 180.288742 -320.714079) (xy 180.265806 -320.769452) (xy 180.235839 -320.821358)
			(xy 180.199352 -320.868908) (xy 180.156972 -320.911288) (xy 180.109422 -320.947775) (xy 180.057516 -320.977742)
			(xy 180.002143 -321.000678) (xy 179.94425 -321.016191) (xy 179.884828 -321.024014) (xy 179.824892 -321.024014)
			(xy 179.76547 -321.016191) (xy 179.707577 -321.000678) (xy 179.652204 -320.977742) (xy 179.600298 -320.947775)
			(xy 179.552748 -320.911288) (xy 179.510368 -320.868908) (xy 179.473881 -320.821358) (xy 179.443914 -320.769452)
			(xy 179.420978 -320.714079) (xy 179.405465 -320.656186) (xy 179.397642 -320.596764) (xy 179.397152 -320.566796)
			(xy 179.397627 -320.536639) (xy 179.405536 -320.476845) (xy 179.421229 -320.418608) (xy 179.444434 -320.362936)
			(xy 179.47475 -320.310794) (xy 179.511651 -320.263084) (xy 179.554498 -320.220635) (xy 179.578254 -320.202052)
			(xy 179.585756 -320.195777) (xy 179.595732 -320.178976) (xy 179.598692 -320.159661) (xy 179.594205 -320.140643)
			(xy 179.582924 -320.124688) (xy 179.56649 -320.114117) (xy 179.547294 -320.110468) (xy 179.537614 -320.111882)
			(xy 179.522335 -320.114654) (xy 179.491419 -320.117579) (xy 179.475892 -320.117724) (xy 179.056538 -320.117724)
			(xy 179.032402 -320.117277) (xy 178.984681 -320.110005) (xy 178.938598 -320.095634) (xy 178.895202 -320.074493)
			(xy 178.855481 -320.047063) (xy 178.83759 -320.030856) (xy 178.166776 -320.030856) (xy 178.125882 -320.071496)
			(xy 178.107837 -320.08891) (xy 178.067288 -320.11841) (xy 178.022618 -320.141194) (xy 177.97493 -320.1567)
			(xy 177.925403 -320.164544) (xy 177.90033 -320.164968) (xy 177.024284 -320.164968) (xy 176.759616 -320.42989)
			(xy 176.758854 -320.45021) (xy 176.757533 -320.479588) (xy 176.748283 -320.537664) (xy 176.731672 -320.594077)
			(xy 176.707973 -320.647899) (xy 176.677576 -320.698242) (xy 176.640982 -320.744277) (xy 176.598794 -320.785247)
			(xy 176.551706 -320.820477) (xy 176.500494 -320.849386) (xy 176.446002 -320.871498) (xy 176.389126 -320.886449)
			(xy 176.330804 -320.893994) (xy 176.3014 -320.894456) (xy 176.271431 -320.893966) (xy 176.212006 -320.886143)
			(xy 176.154111 -320.870631) (xy 176.098735 -320.847695) (xy 176.046827 -320.817728) (xy 175.999273 -320.781243)
			(xy 175.956889 -320.738863) (xy 175.920398 -320.691313) (xy 175.890426 -320.639408) (xy 175.867484 -320.584035)
			(xy 175.851966 -320.526141) (xy 175.844137 -320.466717) (xy 175.843692 -320.436748) (xy 175.844261 -320.403831)
			(xy 175.853693 -320.338675) (xy 175.872368 -320.275545) (xy 175.899901 -320.215744) (xy 175.917352 -320.187828)
			(xy 175.924425 -320.176132) (xy 175.932698 -320.150091) (xy 175.933763 -320.122789) (xy 175.927543 -320.096183)
			(xy 175.914486 -320.072182) (xy 175.895528 -320.052507) (xy 175.872027 -320.038569) (xy 175.84567 -320.031367)
			(xy 175.832008 -320.030856) (xy 173.380654 -320.030856) (xy 173.359718 -320.051171) (xy 173.313453 -320.086707)
			(xy 173.262942 -320.115892) (xy 173.20905 -320.138228) (xy 173.152701 -320.153329) (xy 173.094863 -320.160938)
			(xy 173.065694 -320.161412) (xy 172.795946 -320.161412) (xy 172.768393 -320.161013) (xy 172.713707 -320.154235)
			(xy 172.660277 -320.140752) (xy 172.608922 -320.120772) (xy 172.560429 -320.094599) (xy 172.515542 -320.062636)
			(xy 172.494956 -320.044318) (xy 172.480478 -320.030856) (xy 172.30852 -320.030856) (xy 172.30852 -320.118994)
			(xy 172.34408 -320.13017) (xy 172.371601 -320.139289) (xy 172.424274 -320.163519) (xy 172.473466 -320.194207)
			(xy 172.518389 -320.23086) (xy 172.558325 -320.272891) (xy 172.592634 -320.319629) (xy 172.620767 -320.370325)
			(xy 172.642275 -320.424167) (xy 172.656811 -320.480294) (xy 172.664145 -320.537807) (xy 172.664628 -320.566796)
			(xy 172.664138 -320.596764) (xy 172.656315 -320.656186) (xy 172.640802 -320.714079) (xy 172.617866 -320.769452)
			(xy 172.587899 -320.821358) (xy 172.551412 -320.868908) (xy 172.509032 -320.911288) (xy 172.461482 -320.947775)
			(xy 172.409576 -320.977742) (xy 172.354203 -321.000678) (xy 172.29631 -321.016191) (xy 172.236888 -321.024014)
			(xy 172.176952 -321.024014) (xy 172.11753 -321.016191) (xy 172.059637 -321.000678) (xy 172.004264 -320.977742)
			(xy 171.952358 -320.947775) (xy 171.904808 -320.911288) (xy 171.862428 -320.868908) (xy 171.825941 -320.821358)
			(xy 171.795974 -320.769452) (xy 171.773038 -320.714079) (xy 171.757525 -320.656186) (xy 171.749702 -320.596764)
			(xy 171.749212 -320.566796) (xy 171.749666 -320.537718) (xy 171.75704 -320.480031) (xy 171.771669 -320.423745)
			(xy 171.793316 -320.369768) (xy 171.821632 -320.318971) (xy 171.85616 -320.272174) (xy 171.896342 -320.230132)
			(xy 171.91863 -320.21145) (xy 171.929178 -320.202354) (xy 171.945279 -320.179639) (xy 171.954645 -320.153419)
			(xy 171.95658 -320.125644) (xy 171.950941 -320.098379) (xy 171.938146 -320.07365) (xy 171.919147 -320.053297)
			(xy 171.895357 -320.038833) (xy 171.868544 -320.031332) (xy 171.854622 -320.030856) (xy 169.25544 -320.030856)
			(xy 169.242994 -320.063368) (xy 169.231492 -320.091704) (xy 169.202039 -320.145297) (xy 169.165713 -320.194493)
			(xy 169.12316 -320.238413) (xy 169.075139 -320.276278) (xy 169.022503 -320.307412) (xy 168.966192 -320.33126)
			(xy 168.907206 -320.347399) (xy 168.846597 -320.355541) (xy 168.785443 -320.355541) (xy 168.724834 -320.347399)
			(xy 168.665848 -320.33126) (xy 168.609537 -320.307412) (xy 168.556901 -320.276278) (xy 168.50888 -320.238413)
			(xy 168.466327 -320.194493) (xy 168.430001 -320.145297) (xy 168.400548 -320.091704) (xy 168.389046 -320.063368)
			(xy 168.3766 -320.030856) (xy 165.836854 -320.030856) (xy 165.815918 -320.051171) (xy 165.769653 -320.086707)
			(xy 165.719142 -320.115892) (xy 165.66525 -320.138228) (xy 165.608901 -320.153329) (xy 165.551063 -320.160938)
			(xy 165.521894 -320.161412) (xy 165.252146 -320.161412) (xy 165.214858 -320.16067) (xy 165.141319 -320.148279)
			(xy 165.105842 -320.136774) (xy 165.092441 -320.132562) (xy 165.064412 -320.130861) (xy 165.036978 -320.136858)
			(xy 165.012215 -320.150098) (xy 164.991992 -320.169581) (xy 164.977839 -320.193834) (xy 164.970826 -320.221025)
			(xy 164.970714 -320.235072) (xy 164.970968 -320.246248) (xy 164.970475 -320.276213) (xy 164.962646 -320.335629)
			(xy 164.94713 -320.393514) (xy 164.92419 -320.44888) (xy 164.89422 -320.500777) (xy 164.857733 -320.548319)
			(xy 164.815352 -320.590691) (xy 164.767804 -320.627169) (xy 164.715901 -320.657129) (xy 164.660531 -320.680058)
			(xy 164.602642 -320.695564) (xy 164.543225 -320.703381) (xy 164.51326 -320.703956) (xy 164.483852 -320.703506)
			(xy 164.425518 -320.695978) (xy 164.36863 -320.681039) (xy 164.314125 -320.658935) (xy 164.262901 -320.63003)
			(xy 164.215802 -320.594801) (xy 164.173604 -320.553828) (xy 164.137004 -320.507786) (xy 164.106604 -320.457435)
			(xy 164.082905 -320.403604) (xy 164.066298 -320.347181) (xy 164.057056 -320.289094) (xy 164.055806 -320.25971)
			(xy 164.055044 -320.23939) (xy 163.84651 -320.030856) (xy 161.392362 -320.030856) (xy 161.371754 -320.049373)
			(xy 161.326748 -320.081683) (xy 161.278073 -320.108144) (xy 161.226484 -320.128345) (xy 161.172783 -320.141972)
			(xy 161.117804 -320.148814) (xy 161.090102 -320.14922) (xy 161.058694 -320.148699) (xy 160.996499 -320.139892)
			(xy 160.936164 -320.122411) (xy 160.878894 -320.096605) (xy 160.82583 -320.062989) (xy 160.801558 -320.043048)
			(xy 160.787334 -320.030856) (xy 160.64992 -320.030856) (xy 160.64992 -320.118994) (xy 160.68548 -320.13017)
			(xy 160.713001 -320.139289) (xy 160.765674 -320.163519) (xy 160.814866 -320.194207) (xy 160.859789 -320.23086)
			(xy 160.899725 -320.272891) (xy 160.934034 -320.319629) (xy 160.962167 -320.370325) (xy 160.983675 -320.424167)
			(xy 160.998211 -320.480294) (xy 161.005545 -320.537807) (xy 161.006028 -320.566796) (xy 161.005538 -320.596764)
			(xy 160.997715 -320.656186) (xy 160.982202 -320.714079) (xy 160.959266 -320.769452) (xy 160.929299 -320.821358)
			(xy 160.892812 -320.868908) (xy 160.850432 -320.911288) (xy 160.802882 -320.947775) (xy 160.773816 -320.964556)
			(xy 167.538382 -320.964556) (xy 167.538382 -320.90462) (xy 167.546205 -320.845198) (xy 167.561718 -320.787305)
			(xy 167.584654 -320.731932) (xy 167.614621 -320.680026) (xy 167.651108 -320.632476) (xy 167.693488 -320.590096)
			(xy 167.741038 -320.553609) (xy 167.792944 -320.523642) (xy 167.848317 -320.500706) (xy 167.90621 -320.485193)
			(xy 167.965632 -320.47737) (xy 168.025568 -320.47737) (xy 168.08499 -320.485193) (xy 168.142883 -320.500706)
			(xy 168.198256 -320.523642) (xy 168.250162 -320.553609) (xy 168.297712 -320.590096) (xy 168.340092 -320.632476)
			(xy 168.376579 -320.680026) (xy 168.406546 -320.731932) (xy 168.429482 -320.787305) (xy 168.444995 -320.845198)
			(xy 168.452818 -320.90462) (xy 168.453308 -320.934588) (xy 168.452818 -320.964556) (xy 168.444995 -321.023978)
			(xy 168.429482 -321.081871) (xy 168.406546 -321.137244) (xy 168.376579 -321.18915) (xy 168.340092 -321.2367)
			(xy 168.297712 -321.27908) (xy 168.250162 -321.315567) (xy 168.198256 -321.345534) (xy 168.142883 -321.36847)
			(xy 168.08499 -321.383983) (xy 168.025568 -321.391806) (xy 167.965632 -321.391806) (xy 167.90621 -321.383983)
			(xy 167.848317 -321.36847) (xy 167.792944 -321.345534) (xy 167.741038 -321.315567) (xy 167.693488 -321.27908)
			(xy 167.651108 -321.2367) (xy 167.614621 -321.18915) (xy 167.584654 -321.137244) (xy 167.561718 -321.081871)
			(xy 167.546205 -321.023978) (xy 167.538382 -320.964556) (xy 160.773816 -320.964556) (xy 160.750976 -320.977742)
			(xy 160.695603 -321.000678) (xy 160.63771 -321.016191) (xy 160.578288 -321.024014) (xy 160.518352 -321.024014)
			(xy 160.45893 -321.016191) (xy 160.401037 -321.000678) (xy 160.345664 -320.977742) (xy 160.293758 -320.947775)
			(xy 160.246208 -320.911288) (xy 160.203828 -320.868908) (xy 160.167341 -320.821358) (xy 160.137374 -320.769452)
			(xy 160.114438 -320.714079) (xy 160.098925 -320.656186) (xy 160.091102 -320.596764) (xy 160.090612 -320.566796)
			(xy 160.09106 -320.537805) (xy 160.098385 -320.480288) (xy 160.112918 -320.424156) (xy 160.134425 -320.370311)
			(xy 160.162562 -320.319613) (xy 160.196878 -320.272877) (xy 160.236823 -320.23085) (xy 160.281758 -320.194206)
			(xy 160.330962 -320.163531) (xy 160.383646 -320.139319) (xy 160.41116 -320.13017) (xy 160.44672 -320.118994)
			(xy 160.44672 -320.030856) (xy 160.317942 -320.030856) (xy 160.303464 -320.044318) (xy 160.282885 -320.062643)
			(xy 160.237994 -320.094603) (xy 160.1895 -320.120772) (xy 160.138144 -320.140751) (xy 160.084713 -320.154233)
			(xy 160.030027 -320.161013) (xy 160.002474 -320.161412) (xy 159.973262 -320.160949) (xy 159.915341 -320.153299)
			(xy 159.85892 -320.138134) (xy 159.804969 -320.115714) (xy 159.779462 -320.101468) (xy 159.47009 -320.101468)
			(xy 159.438277 -320.100941) (xy 159.375295 -320.091911) (xy 159.31424 -320.074009) (xy 159.256354 -320.047598)
			(xy 159.229298 -320.030856) (xy 157.90672 -320.030856) (xy 157.904942 -320.032634) (xy 157.3149 -320.032634)
			(xy 157.291344 -320.044764) (xy 157.241911 -320.063837) (xy 157.190519 -320.076736) (xy 157.137938 -320.083268)
			(xy 157.111446 -320.083688) (xy 157.000956 -320.083688) (xy 156.969968 -320.082418) (xy 156.946854 -320.080894)
			(xy 156.694378 -320.33337) (xy 156.694378 -323.438266) (xy 157.668976 -323.438266) (xy 157.668976 -321.957446)
			(xy 157.945074 -321.681348) (xy 159.679894 -321.681348) (xy 159.955992 -321.957446) (xy 159.955992 -323.438266)
			(xy 161.732976 -323.438266) (xy 161.732976 -321.957446) (xy 162.009074 -321.681348) (xy 163.743894 -321.681348)
			(xy 164.019992 -321.957446) (xy 164.019992 -323.438266) (xy 165.212776 -323.438266) (xy 165.212776 -321.957446)
			(xy 165.488874 -321.681348) (xy 167.223694 -321.681348) (xy 167.499792 -321.957446) (xy 167.499792 -323.438266)
			(xy 169.276776 -323.438266) (xy 169.276776 -321.957446) (xy 169.552874 -321.681348) (xy 171.287694 -321.681348)
			(xy 171.563792 -321.957446) (xy 171.563792 -323.438266) (xy 172.756576 -323.438266) (xy 172.756576 -321.957446)
			(xy 173.032674 -321.681348) (xy 174.767494 -321.681348) (xy 175.043592 -321.957446) (xy 175.043592 -323.438266)
			(xy 176.820576 -323.438266) (xy 176.820576 -321.957446) (xy 177.096674 -321.681348) (xy 178.831494 -321.681348)
			(xy 179.107592 -321.957446) (xy 179.107592 -323.438266) (xy 180.300376 -323.438266) (xy 180.300376 -321.957446)
			(xy 180.576474 -321.681348) (xy 182.311294 -321.681348) (xy 182.587392 -321.957446) (xy 182.587392 -323.438266)
			(xy 184.364376 -323.438266) (xy 184.364376 -321.957446) (xy 184.640474 -321.681348) (xy 186.375294 -321.681348)
			(xy 186.651392 -321.957446) (xy 186.651392 -323.438266) (xy 187.844176 -323.438266) (xy 187.844176 -321.957446)
			(xy 188.120274 -321.681348) (xy 189.855094 -321.681348) (xy 190.131192 -321.957446) (xy 190.131192 -323.438266)
			(xy 191.908176 -323.438266) (xy 191.908176 -321.957446) (xy 192.184274 -321.681348) (xy 193.919094 -321.681348)
			(xy 194.195192 -321.957446) (xy 194.195192 -323.438266) (xy 195.387976 -323.438266) (xy 195.387976 -321.957446)
			(xy 195.664074 -321.681348) (xy 197.398894 -321.681348) (xy 197.674992 -321.957446) (xy 197.674992 -323.438266)
			(xy 199.451976 -323.438266) (xy 199.451976 -321.957446) (xy 199.728074 -321.681348) (xy 201.462894 -321.681348)
			(xy 201.738992 -321.957446) (xy 201.738992 -323.438266) (xy 202.931776 -323.438266) (xy 202.931776 -321.957446)
			(xy 203.207874 -321.681348) (xy 204.942694 -321.681348) (xy 205.218792 -321.957446) (xy 205.218792 -323.438266)
			(xy 206.995776 -323.438266) (xy 206.995776 -321.957446) (xy 207.271874 -321.681348) (xy 209.006694 -321.681348)
			(xy 209.282792 -321.957446) (xy 209.282792 -323.438266) (xy 210.475576 -323.438266) (xy 210.475576 -321.957446)
			(xy 210.827874 -321.605148) (xy 214.391494 -321.605148) (xy 214.642192 -321.855846) (xy 214.642192 -323.387466)
			(xy 214.061294 -323.968364) (xy 211.005674 -323.968364) (xy 210.475576 -323.438266) (xy 209.282792 -323.438266)
			(xy 208.752694 -323.968364) (xy 207.525874 -323.968364) (xy 206.995776 -323.438266) (xy 205.218792 -323.438266)
			(xy 204.688694 -323.968364) (xy 203.461874 -323.968364) (xy 202.931776 -323.438266) (xy 201.738992 -323.438266)
			(xy 201.208894 -323.968364) (xy 199.982074 -323.968364) (xy 199.451976 -323.438266) (xy 197.674992 -323.438266)
			(xy 197.144894 -323.968364) (xy 195.918074 -323.968364) (xy 195.387976 -323.438266) (xy 194.195192 -323.438266)
			(xy 193.665094 -323.968364) (xy 192.438274 -323.968364) (xy 191.908176 -323.438266) (xy 190.131192 -323.438266)
			(xy 189.601094 -323.968364) (xy 188.374274 -323.968364) (xy 187.844176 -323.438266) (xy 186.651392 -323.438266)
			(xy 186.121294 -323.968364) (xy 184.894474 -323.968364) (xy 184.364376 -323.438266) (xy 182.587392 -323.438266)
			(xy 182.057294 -323.968364) (xy 180.830474 -323.968364) (xy 180.300376 -323.438266) (xy 179.107592 -323.438266)
			(xy 178.577494 -323.968364) (xy 177.350674 -323.968364) (xy 176.820576 -323.438266) (xy 175.043592 -323.438266)
			(xy 174.513494 -323.968364) (xy 173.286674 -323.968364) (xy 172.756576 -323.438266) (xy 171.563792 -323.438266)
			(xy 171.033694 -323.968364) (xy 169.806874 -323.968364) (xy 169.276776 -323.438266) (xy 167.499792 -323.438266)
			(xy 166.969694 -323.968364) (xy 165.742874 -323.968364) (xy 165.212776 -323.438266) (xy 164.019992 -323.438266)
			(xy 163.489894 -323.968364) (xy 162.263074 -323.968364) (xy 161.732976 -323.438266) (xy 159.955992 -323.438266)
			(xy 159.425894 -323.968364) (xy 158.199074 -323.968364) (xy 157.668976 -323.438266) (xy 156.694378 -323.438266)
			(xy 156.694378 -327.108978) (xy 159.326536 -327.108978) (xy 159.326536 -327.024422) (xy 159.334338 -326.940228)
			(xy 159.349875 -326.857112) (xy 159.373014 -326.775785) (xy 159.403559 -326.696939) (xy 159.441248 -326.621248)
			(xy 159.48576 -326.549358) (xy 159.536715 -326.481881) (xy 159.593679 -326.419393) (xy 159.656165 -326.362428)
			(xy 159.723641 -326.311471) (xy 159.795531 -326.266957) (xy 159.871221 -326.229267) (xy 159.950066 -326.19872)
			(xy 160.031393 -326.175579) (xy 160.114508 -326.160041) (xy 160.198702 -326.152237) (xy 160.24098 -326.151748)
			(xy 161.48558 -326.151748) (xy 161.527855 -326.152308) (xy 161.612046 -326.160108) (xy 161.695157 -326.175643)
			(xy 161.776481 -326.19878) (xy 161.855323 -326.229321) (xy 161.93101 -326.267008) (xy 162.002897 -326.311517)
			(xy 162.070371 -326.36247) (xy 162.132855 -326.41943) (xy 162.189818 -326.481914) (xy 162.240772 -326.549386)
			(xy 162.285282 -326.621272) (xy 162.32297 -326.696959) (xy 162.353514 -326.7758) (xy 162.376653 -326.857123)
			(xy 162.392189 -326.940234) (xy 162.399991 -327.024425) (xy 162.399991 -327.108975) (xy 162.399991 -327.108978)
			(xy 166.870336 -327.108978) (xy 166.870336 -327.024422) (xy 166.878138 -326.940228) (xy 166.893675 -326.857112)
			(xy 166.916814 -326.775785) (xy 166.947359 -326.696939) (xy 166.985048 -326.621248) (xy 167.02956 -326.549358)
			(xy 167.080515 -326.481881) (xy 167.137479 -326.419393) (xy 167.199965 -326.362428) (xy 167.267441 -326.311471)
			(xy 167.339331 -326.266957) (xy 167.415021 -326.229267) (xy 167.493866 -326.19872) (xy 167.575193 -326.175579)
			(xy 167.658308 -326.160041) (xy 167.742502 -326.152237) (xy 167.78478 -326.151748) (xy 169.02938 -326.151748)
			(xy 169.071655 -326.152308) (xy 169.155846 -326.160108) (xy 169.238957 -326.175643) (xy 169.320281 -326.19878)
			(xy 169.399123 -326.229321) (xy 169.47481 -326.267008) (xy 169.546697 -326.311517) (xy 169.614171 -326.36247)
			(xy 169.676655 -326.41943) (xy 169.733618 -326.481914) (xy 169.784572 -326.549386) (xy 169.829082 -326.621272)
			(xy 169.86677 -326.696959) (xy 169.897314 -326.7758) (xy 169.920453 -326.857123) (xy 169.935989 -326.940234)
			(xy 169.943791 -327.024425) (xy 169.943791 -327.108975) (xy 169.943791 -327.108978) (xy 174.414136 -327.108978)
			(xy 174.414136 -327.024422) (xy 174.421938 -326.940228) (xy 174.437475 -326.857112) (xy 174.460614 -326.775785)
			(xy 174.491159 -326.696939) (xy 174.528848 -326.621248) (xy 174.57336 -326.549358) (xy 174.624315 -326.481881)
			(xy 174.681279 -326.419393) (xy 174.743765 -326.362428) (xy 174.811241 -326.311471) (xy 174.883131 -326.266957)
			(xy 174.958821 -326.229267) (xy 175.037666 -326.19872) (xy 175.118993 -326.175579) (xy 175.202108 -326.160041)
			(xy 175.286302 -326.152237) (xy 175.32858 -326.151748) (xy 176.57318 -326.151748) (xy 176.615455 -326.152308)
			(xy 176.699646 -326.160108) (xy 176.782757 -326.175643) (xy 176.864081 -326.19878) (xy 176.942923 -326.229321)
			(xy 177.01861 -326.267008) (xy 177.090497 -326.311517) (xy 177.157971 -326.36247) (xy 177.220455 -326.41943)
			(xy 177.277418 -326.481914) (xy 177.328372 -326.549386) (xy 177.372882 -326.621272) (xy 177.41057 -326.696959)
			(xy 177.441114 -326.7758) (xy 177.464253 -326.857123) (xy 177.479789 -326.940234) (xy 177.487591 -327.024425)
			(xy 177.487591 -327.108975) (xy 177.479789 -327.193166) (xy 177.464253 -327.276277) (xy 177.441114 -327.3576)
			(xy 177.41057 -327.436441) (xy 177.372882 -327.512128) (xy 177.328372 -327.584014) (xy 177.277418 -327.651486)
			(xy 177.220455 -327.71397) (xy 177.157971 -327.77093) (xy 177.090497 -327.821883) (xy 177.01861 -327.866392)
			(xy 176.942923 -327.904079) (xy 176.864081 -327.93462) (xy 176.782757 -327.957757) (xy 176.699646 -327.973292)
			(xy 176.615455 -327.981092) (xy 176.57318 -327.981564) (xy 175.32858 -327.981564) (xy 175.286302 -327.981163)
			(xy 175.202108 -327.973359) (xy 175.118993 -327.957821) (xy 175.037666 -327.93468) (xy 174.958821 -327.904133)
			(xy 174.883131 -327.866443) (xy 174.811241 -327.821929) (xy 174.743765 -327.770972) (xy 174.681279 -327.714007)
			(xy 174.624315 -327.651519) (xy 174.57336 -327.584042) (xy 174.528848 -327.512152) (xy 174.491159 -327.436461)
			(xy 174.460614 -327.357615) (xy 174.437475 -327.276288) (xy 174.421938 -327.193172) (xy 174.414136 -327.108978)
			(xy 169.943791 -327.108978) (xy 169.935989 -327.193166) (xy 169.920453 -327.276277) (xy 169.897314 -327.3576)
			(xy 169.86677 -327.436441) (xy 169.829082 -327.512128) (xy 169.784572 -327.584014) (xy 169.733618 -327.651486)
			(xy 169.676655 -327.71397) (xy 169.614171 -327.77093) (xy 169.546697 -327.821883) (xy 169.47481 -327.866392)
			(xy 169.399123 -327.904079) (xy 169.320281 -327.93462) (xy 169.238957 -327.957757) (xy 169.155846 -327.973292)
			(xy 169.071655 -327.981092) (xy 169.02938 -327.981564) (xy 167.78478 -327.981564) (xy 167.742502 -327.981163)
			(xy 167.658308 -327.973359) (xy 167.575193 -327.957821) (xy 167.493866 -327.93468) (xy 167.415021 -327.904133)
			(xy 167.339331 -327.866443) (xy 167.267441 -327.821929) (xy 167.199965 -327.770972) (xy 167.137479 -327.714007)
			(xy 167.080515 -327.651519) (xy 167.02956 -327.584042) (xy 166.985048 -327.512152) (xy 166.947359 -327.436461)
			(xy 166.916814 -327.357615) (xy 166.893675 -327.276288) (xy 166.878138 -327.193172) (xy 166.870336 -327.108978)
			(xy 162.399991 -327.108978) (xy 162.392189 -327.193166) (xy 162.376653 -327.276277) (xy 162.353514 -327.3576)
			(xy 162.32297 -327.436441) (xy 162.285282 -327.512128) (xy 162.240772 -327.584014) (xy 162.189818 -327.651486)
			(xy 162.132855 -327.71397) (xy 162.070371 -327.77093) (xy 162.002897 -327.821883) (xy 161.93101 -327.866392)
			(xy 161.855323 -327.904079) (xy 161.776481 -327.93462) (xy 161.695157 -327.957757) (xy 161.612046 -327.973292)
			(xy 161.527855 -327.981092) (xy 161.48558 -327.981564) (xy 160.24098 -327.981564) (xy 160.198702 -327.981163)
			(xy 160.114508 -327.973359) (xy 160.031393 -327.957821) (xy 159.950066 -327.93468) (xy 159.871221 -327.904133)
			(xy 159.795531 -327.866443) (xy 159.723641 -327.821929) (xy 159.656165 -327.770972) (xy 159.593679 -327.714007)
			(xy 159.536715 -327.651519) (xy 159.48576 -327.584042) (xy 159.441248 -327.512152) (xy 159.403559 -327.436461)
			(xy 159.373014 -327.357615) (xy 159.349875 -327.276288) (xy 159.334338 -327.193172) (xy 159.326536 -327.108978)
			(xy 156.694378 -327.108978) (xy 156.694378 -329.90663) (xy 175.585118 -329.90663) (xy 175.589189 -329.851008)
			(xy 175.601315 -329.796571) (xy 175.621238 -329.74448) (xy 175.648534 -329.695845) (xy 175.68262 -329.651702)
			(xy 175.722769 -329.612993) (xy 175.768127 -329.580542) (xy 175.817727 -329.555041) (xy 175.870511 -329.537034)
			(xy 175.925354 -329.526904) (xy 175.981088 -329.524867) (xy 176.036525 -329.530967) (xy 176.090482 -329.545073)
			(xy 176.141811 -329.566885) (xy 176.189417 -329.595939) (xy 176.232285 -329.631614) (xy 176.269502 -329.673151)
			(xy 176.300275 -329.719664) (xy 176.323947 -329.770161) (xy 176.340015 -329.823568) (xy 176.348135 -329.878744)
			(xy 176.348644 -329.90663) (xy 176.348135 -329.934516) (xy 176.340015 -329.989692) (xy 176.323947 -330.043099)
			(xy 176.300275 -330.093596) (xy 176.269502 -330.140109) (xy 176.232285 -330.181646) (xy 176.189417 -330.217321)
			(xy 176.141811 -330.246375) (xy 176.090482 -330.268187) (xy 176.036525 -330.282293) (xy 175.981088 -330.288393)
			(xy 175.925354 -330.286356) (xy 175.870511 -330.276226) (xy 175.817727 -330.258219) (xy 175.768127 -330.232718)
			(xy 175.722769 -330.200267) (xy 175.68262 -330.161558) (xy 175.648534 -330.117415) (xy 175.621238 -330.06878)
			(xy 175.601315 -330.016689) (xy 175.589189 -329.962252) (xy 175.585118 -329.90663) (xy 156.694378 -329.90663)
			(xy 156.694378 -330.843128) (xy 175.381412 -330.843128) (xy 175.381887 -330.813159) (xy 175.389708 -330.753733)
			(xy 175.405218 -330.695836) (xy 175.428154 -330.640459) (xy 175.458122 -330.58855) (xy 175.494609 -330.540998)
			(xy 175.536992 -330.498614) (xy 175.584544 -330.462126) (xy 175.636452 -330.432157) (xy 175.691828 -330.409221)
			(xy 175.749725 -330.393709) (xy 175.809151 -330.385888) (xy 175.83912 -330.38542) (xy 175.868523 -330.385887)
			(xy 175.926844 -330.393433) (xy 175.983719 -330.408386) (xy 176.03821 -330.430499) (xy 176.089421 -330.459408)
			(xy 176.136508 -330.494637) (xy 176.178695 -330.535606) (xy 176.215289 -330.581641) (xy 176.245687 -330.631982)
			(xy 176.269387 -330.685802) (xy 176.286 -330.742214) (xy 176.295252 -330.800289) (xy 176.296574 -330.829666)
			(xy 176.297336 -330.849986) (xy 176.89322 -331.446124) (xy 177.898552 -331.446124) (xy 177.898552 -330.770738)
			(xy 177.891948 -330.759054) (xy 177.882371 -330.741549) (xy 177.86882 -330.704023) (xy 177.86204 -330.664705)
			(xy 177.861722 -330.644754) (xy 177.861976 -330.644754) (xy 177.861976 -330.345542) (xy 177.861722 -330.345542)
			(xy 177.862058 -330.323213) (xy 177.870473 -330.279361) (xy 177.887321 -330.23801) (xy 177.911948 -330.200763)
			(xy 177.943399 -330.169067) (xy 177.980452 -330.144151) (xy 178.021671 -330.126981) (xy 178.065456 -330.118225)
			(xy 178.087782 -330.117704) (xy 178.171094 -330.117704) (xy 178.181069 -330.117162) (xy 178.199483 -330.109476)
			(xy 178.213569 -330.095344) (xy 178.221195 -330.076905) (xy 178.221206 -330.056952) (xy 178.213601 -330.038504)
			(xy 178.206908 -330.03109) (xy 178.023012 -329.847194) (xy 178.012344 -329.843384) (xy 177.995471 -329.837058)
			(xy 177.963823 -329.819832) (xy 177.949352 -329.809094) (xy 177.935636 -329.798172) (xy 177.88382 -329.798172)
			(xy 177.447956 -330.23429) (xy 177.447194 -330.25461) (xy 177.445944 -330.283994) (xy 177.436702 -330.342081)
			(xy 177.420095 -330.398504) (xy 177.396396 -330.452335) (xy 177.365996 -330.502686) (xy 177.329396 -330.548728)
			(xy 177.287198 -330.589701) (xy 177.240099 -330.62493) (xy 177.188875 -330.653835) (xy 177.13437 -330.675939)
			(xy 177.077482 -330.690878) (xy 177.019148 -330.698406) (xy 176.98974 -330.698856) (xy 176.959775 -330.698281)
			(xy 176.900358 -330.690464) (xy 176.842469 -330.674958) (xy 176.787099 -330.652029) (xy 176.735196 -330.622069)
			(xy 176.687648 -330.585591) (xy 176.645267 -330.543219) (xy 176.60878 -330.495677) (xy 176.57881 -330.44378)
			(xy 176.55587 -330.388414) (xy 176.540354 -330.330529) (xy 176.532525 -330.271113) (xy 176.532032 -330.241148)
			(xy 176.532551 -330.211746) (xy 176.540089 -330.153426) (xy 176.555034 -330.096552) (xy 176.577141 -330.042061)
			(xy 176.606044 -329.990849) (xy 176.641268 -329.943761) (xy 176.682233 -329.901573) (xy 176.728264 -329.864978)
			(xy 176.778602 -329.83458) (xy 176.83242 -329.810879) (xy 176.888829 -329.794267) (xy 176.946902 -329.785016)
			(xy 176.976278 -329.783694) (xy 176.996598 -329.782932) (xy 177.526188 -329.253596) (xy 177.544248 -329.236203)
			(xy 177.584803 -329.206723) (xy 177.629471 -329.183951) (xy 177.677152 -329.168448) (xy 177.726671 -329.160595)
			(xy 177.75174 -329.160124) (xy 177.936652 -329.160124) (xy 177.950771 -329.147778) (xy 177.98231 -329.127485)
			(xy 177.99939 -329.119738) (xy 178.030378 -329.106784) (xy 178.030378 -327.681336) (xy 178.87188 -326.839834)
			(xy 178.871372 -326.818498) (xy 178.871372 -326.812148) (xy 178.8719 -326.784897) (xy 178.87965 -326.73095)
			(xy 178.894999 -326.678654) (xy 178.917634 -326.629076) (xy 178.947095 -326.583223) (xy 178.982782 -326.54203)
			(xy 179.023969 -326.506336) (xy 179.069816 -326.476867) (xy 179.11939 -326.454223) (xy 179.171683 -326.438864)
			(xy 179.225629 -326.431105) (xy 179.25288 -326.43064) (xy 179.281313 -326.431174) (xy 179.337549 -326.439607)
			(xy 179.391908 -326.456304) (xy 179.443181 -326.480894) (xy 179.467002 -326.496426) (xy 179.949856 -326.496426)
			(xy 180.222144 -326.768714) (xy 180.233254 -326.779011) (xy 180.260006 -326.793188) (xy 180.289738 -326.798894)
			(xy 180.319837 -326.795629) (xy 180.347654 -326.783679) (xy 180.370743 -326.764096) (xy 180.387073 -326.738601)
			(xy 180.395206 -326.709439) (xy 180.395372 -326.694292) (xy 180.395372 -326.685148) (xy 180.3959 -326.657897)
			(xy 180.40365 -326.60395) (xy 180.418999 -326.551654) (xy 180.441634 -326.502076) (xy 180.471095 -326.456223)
			(xy 180.506782 -326.41503) (xy 180.547969 -326.379336) (xy 180.593816 -326.349867) (xy 180.64339 -326.327223)
			(xy 180.695683 -326.311864) (xy 180.749629 -326.304105) (xy 180.77688 -326.30364) (xy 180.792509 -326.303797)
			(xy 180.823663 -326.306341) (xy 180.83911 -326.30872) (xy 180.853915 -326.310687) (xy 180.883515 -326.306789)
			(xy 180.910729 -326.29451) (xy 180.933239 -326.274897) (xy 180.949128 -326.249619) (xy 180.957041 -326.220831)
			(xy 180.956306 -326.190984) (xy 180.95214 -326.17664) (xy 180.943146 -326.147552) (xy 180.93345 -326.087447)
			(xy 180.932836 -326.057006) (xy 180.933322 -326.029755) (xy 180.941078 -325.975807) (xy 180.956433 -325.923512)
			(xy 180.979075 -325.873935) (xy 181.008541 -325.828085) (xy 181.044232 -325.786894) (xy 181.085423 -325.751203)
			(xy 181.131273 -325.721737) (xy 181.18085 -325.699095) (xy 181.233145 -325.68374) (xy 181.287093 -325.675984)
			(xy 181.341595 -325.675984) (xy 181.395543 -325.68374) (xy 181.447838 -325.699095) (xy 181.497415 -325.721737)
			(xy 181.543265 -325.751203) (xy 181.584456 -325.786894) (xy 181.620147 -325.828085) (xy 181.649613 -325.873935)
			(xy 181.672255 -325.923512) (xy 181.68761 -325.975807) (xy 181.695366 -326.029755) (xy 181.695852 -326.057006)
			(xy 181.695398 -326.083657) (xy 181.687974 -326.13644) (xy 181.673273 -326.187675) (xy 181.662832 -326.2122)
			(xy 181.657016 -326.226601) (xy 181.653488 -326.257443) (xy 181.659384 -326.287921) (xy 181.674158 -326.315223)
			(xy 181.696449 -326.336828) (xy 181.710076 -326.34428) (xy 181.732863 -326.356168) (xy 181.775287 -326.385182)
			(xy 181.813428 -326.419634) (xy 181.846594 -326.458898) (xy 181.874184 -326.502261) (xy 181.895698 -326.548939)
			(xy 181.903624 -326.573388) (xy 181.9083 -326.587317) (xy 181.924494 -326.611825) (xy 181.946989 -326.630716)
			(xy 181.973927 -326.64243) (xy 182.003084 -326.646) (xy 182.032053 -326.64113) (xy 182.058441 -326.628225)
			(xy 182.080069 -326.608348) (xy 182.088028 -326.595994) (xy 182.110525 -326.559521) (xy 182.161296 -326.490479)
			(xy 182.2183 -326.426486) (xy 182.281037 -326.368104) (xy 182.348958 -326.315843) (xy 182.421469 -326.270162)
			(xy 182.497933 -326.231461) (xy 182.57768 -326.200079) (xy 182.660012 -326.176291) (xy 182.744208 -326.160306)
			(xy 182.82953 -326.152263) (xy 182.87238 -326.151748) (xy 184.11698 -326.151748) (xy 184.159255 -326.152308)
			(xy 184.243446 -326.160108) (xy 184.326557 -326.175643) (xy 184.407881 -326.19878) (xy 184.486723 -326.229321)
			(xy 184.56241 -326.267008) (xy 184.634297 -326.311517) (xy 184.701771 -326.36247) (xy 184.764255 -326.41943)
			(xy 184.821218 -326.481914) (xy 184.872172 -326.549386) (xy 184.916682 -326.621272) (xy 184.95437 -326.696959)
			(xy 184.984914 -326.7758) (xy 185.008053 -326.857123) (xy 185.023589 -326.940234) (xy 185.031391 -327.024425)
			(xy 185.031391 -327.108975) (xy 185.031391 -327.108978) (xy 189.501736 -327.108978) (xy 189.501736 -327.024422)
			(xy 189.509538 -326.940228) (xy 189.525075 -326.857112) (xy 189.548214 -326.775785) (xy 189.578759 -326.696939)
			(xy 189.616448 -326.621248) (xy 189.66096 -326.549358) (xy 189.711915 -326.481881) (xy 189.768879 -326.419393)
			(xy 189.831365 -326.362428) (xy 189.898841 -326.311471) (xy 189.970731 -326.266957) (xy 190.046421 -326.229267)
			(xy 190.125266 -326.19872) (xy 190.206593 -326.175579) (xy 190.289708 -326.160041) (xy 190.373902 -326.152237)
			(xy 190.41618 -326.151748) (xy 191.66078 -326.151748) (xy 191.703055 -326.152308) (xy 191.787246 -326.160108)
			(xy 191.870357 -326.175643) (xy 191.951681 -326.19878) (xy 192.030523 -326.229321) (xy 192.10621 -326.267008)
			(xy 192.178097 -326.311517) (xy 192.245571 -326.36247) (xy 192.308055 -326.41943) (xy 192.365018 -326.481914)
			(xy 192.415972 -326.549386) (xy 192.460482 -326.621272) (xy 192.49817 -326.696959) (xy 192.528714 -326.7758)
			(xy 192.551853 -326.857123) (xy 192.567389 -326.940234) (xy 192.575191 -327.024425) (xy 192.575191 -327.108975)
			(xy 192.575191 -327.108978) (xy 197.045536 -327.108978) (xy 197.045536 -327.024422) (xy 197.053338 -326.940228)
			(xy 197.068875 -326.857112) (xy 197.092014 -326.775785) (xy 197.122559 -326.696939) (xy 197.160248 -326.621248)
			(xy 197.20476 -326.549358) (xy 197.255715 -326.481881) (xy 197.312679 -326.419393) (xy 197.375165 -326.362428)
			(xy 197.442641 -326.311471) (xy 197.514531 -326.266957) (xy 197.590221 -326.229267) (xy 197.669066 -326.19872)
			(xy 197.750393 -326.175579) (xy 197.833508 -326.160041) (xy 197.917702 -326.152237) (xy 197.95998 -326.151748)
			(xy 199.20458 -326.151748) (xy 199.246855 -326.152308) (xy 199.331046 -326.160108) (xy 199.414157 -326.175643)
			(xy 199.495481 -326.19878) (xy 199.574323 -326.229321) (xy 199.65001 -326.267008) (xy 199.721897 -326.311517)
			(xy 199.789371 -326.36247) (xy 199.851855 -326.41943) (xy 199.908818 -326.481914) (xy 199.959772 -326.549386)
			(xy 200.004282 -326.621272) (xy 200.04197 -326.696959) (xy 200.072514 -326.7758) (xy 200.095653 -326.857123)
			(xy 200.111189 -326.940234) (xy 200.118991 -327.024425) (xy 200.118991 -327.108975) (xy 200.118991 -327.108978)
			(xy 204.589336 -327.108978) (xy 204.589336 -327.024422) (xy 204.597138 -326.940228) (xy 204.612675 -326.857112)
			(xy 204.635814 -326.775785) (xy 204.666359 -326.696939) (xy 204.704048 -326.621248) (xy 204.74856 -326.549358)
			(xy 204.799515 -326.481881) (xy 204.856479 -326.419393) (xy 204.918965 -326.362428) (xy 204.986441 -326.311471)
			(xy 205.058331 -326.266957) (xy 205.134021 -326.229267) (xy 205.212866 -326.19872) (xy 205.294193 -326.175579)
			(xy 205.377308 -326.160041) (xy 205.461502 -326.152237) (xy 205.50378 -326.151748) (xy 206.74838 -326.151748)
			(xy 206.790655 -326.152308) (xy 206.874846 -326.160108) (xy 206.957957 -326.175643) (xy 207.039281 -326.19878)
			(xy 207.118123 -326.229321) (xy 207.19381 -326.267008) (xy 207.265697 -326.311517) (xy 207.333171 -326.36247)
			(xy 207.395655 -326.41943) (xy 207.452618 -326.481914) (xy 207.503572 -326.549386) (xy 207.548082 -326.621272)
			(xy 207.58577 -326.696959) (xy 207.616314 -326.7758) (xy 207.639453 -326.857123) (xy 207.654989 -326.940234)
			(xy 207.662791 -327.024425) (xy 207.662791 -327.108975) (xy 207.662791 -327.108978) (xy 212.133136 -327.108978)
			(xy 212.133136 -327.024422) (xy 212.140938 -326.940228) (xy 212.156475 -326.857112) (xy 212.179614 -326.775785)
			(xy 212.210159 -326.696939) (xy 212.247848 -326.621248) (xy 212.29236 -326.549358) (xy 212.343315 -326.481881)
			(xy 212.400279 -326.419393) (xy 212.462765 -326.362428) (xy 212.530241 -326.311471) (xy 212.602131 -326.266957)
			(xy 212.677821 -326.229267) (xy 212.756666 -326.19872) (xy 212.837993 -326.175579) (xy 212.921108 -326.160041)
			(xy 213.005302 -326.152237) (xy 213.04758 -326.151748) (xy 214.29218 -326.151748) (xy 214.334455 -326.152308)
			(xy 214.418646 -326.160108) (xy 214.501757 -326.175643) (xy 214.583081 -326.19878) (xy 214.661923 -326.229321)
			(xy 214.73761 -326.267008) (xy 214.809497 -326.311517) (xy 214.876971 -326.36247) (xy 214.939455 -326.41943)
			(xy 214.996418 -326.481914) (xy 215.047372 -326.549386) (xy 215.091882 -326.621272) (xy 215.12957 -326.696959)
			(xy 215.160114 -326.7758) (xy 215.183253 -326.857123) (xy 215.198789 -326.940234) (xy 215.206591 -327.024425)
			(xy 215.206591 -327.108975) (xy 215.198789 -327.193166) (xy 215.183253 -327.276277) (xy 215.160114 -327.3576)
			(xy 215.12957 -327.436441) (xy 215.091882 -327.512128) (xy 215.047372 -327.584014) (xy 214.996418 -327.651486)
			(xy 214.939455 -327.71397) (xy 214.876971 -327.77093) (xy 214.809497 -327.821883) (xy 214.73761 -327.866392)
			(xy 214.661923 -327.904079) (xy 214.583081 -327.93462) (xy 214.501757 -327.957757) (xy 214.418646 -327.973292)
			(xy 214.334455 -327.981092) (xy 214.29218 -327.981564) (xy 213.04758 -327.981564) (xy 213.005302 -327.981163)
			(xy 212.921108 -327.973359) (xy 212.837993 -327.957821) (xy 212.756666 -327.93468) (xy 212.677821 -327.904133)
			(xy 212.602131 -327.866443) (xy 212.530241 -327.821929) (xy 212.462765 -327.770972) (xy 212.400279 -327.714007)
			(xy 212.343315 -327.651519) (xy 212.29236 -327.584042) (xy 212.247848 -327.512152) (xy 212.210159 -327.436461)
			(xy 212.179614 -327.357615) (xy 212.156475 -327.276288) (xy 212.140938 -327.193172) (xy 212.133136 -327.108978)
			(xy 207.662791 -327.108978) (xy 207.654989 -327.193166) (xy 207.639453 -327.276277) (xy 207.616314 -327.3576)
			(xy 207.58577 -327.436441) (xy 207.548082 -327.512128) (xy 207.503572 -327.584014) (xy 207.452618 -327.651486)
			(xy 207.395655 -327.71397) (xy 207.333171 -327.77093) (xy 207.265697 -327.821883) (xy 207.19381 -327.866392)
			(xy 207.118123 -327.904079) (xy 207.039281 -327.93462) (xy 206.957957 -327.957757) (xy 206.874846 -327.973292)
			(xy 206.790655 -327.981092) (xy 206.74838 -327.981564) (xy 205.50378 -327.981564) (xy 205.461502 -327.981163)
			(xy 205.377308 -327.973359) (xy 205.294193 -327.957821) (xy 205.212866 -327.93468) (xy 205.134021 -327.904133)
			(xy 205.058331 -327.866443) (xy 204.986441 -327.821929) (xy 204.918965 -327.770972) (xy 204.856479 -327.714007)
			(xy 204.799515 -327.651519) (xy 204.74856 -327.584042) (xy 204.704048 -327.512152) (xy 204.666359 -327.436461)
			(xy 204.635814 -327.357615) (xy 204.612675 -327.276288) (xy 204.597138 -327.193172) (xy 204.589336 -327.108978)
			(xy 200.118991 -327.108978) (xy 200.111189 -327.193166) (xy 200.095653 -327.276277) (xy 200.072514 -327.3576)
			(xy 200.04197 -327.436441) (xy 200.004282 -327.512128) (xy 199.959772 -327.584014) (xy 199.908818 -327.651486)
			(xy 199.851855 -327.71397) (xy 199.789371 -327.77093) (xy 199.721897 -327.821883) (xy 199.65001 -327.866392)
			(xy 199.574323 -327.904079) (xy 199.495481 -327.93462) (xy 199.414157 -327.957757) (xy 199.331046 -327.973292)
			(xy 199.246855 -327.981092) (xy 199.20458 -327.981564) (xy 197.95998 -327.981564) (xy 197.917702 -327.981163)
			(xy 197.833508 -327.973359) (xy 197.750393 -327.957821) (xy 197.669066 -327.93468) (xy 197.590221 -327.904133)
			(xy 197.514531 -327.866443) (xy 197.442641 -327.821929) (xy 197.375165 -327.770972) (xy 197.312679 -327.714007)
			(xy 197.255715 -327.651519) (xy 197.20476 -327.584042) (xy 197.160248 -327.512152) (xy 197.122559 -327.436461)
			(xy 197.092014 -327.357615) (xy 197.068875 -327.276288) (xy 197.053338 -327.193172) (xy 197.045536 -327.108978)
			(xy 192.575191 -327.108978) (xy 192.567389 -327.193166) (xy 192.551853 -327.276277) (xy 192.528714 -327.3576)
			(xy 192.49817 -327.436441) (xy 192.460482 -327.512128) (xy 192.415972 -327.584014) (xy 192.365018 -327.651486)
			(xy 192.308055 -327.71397) (xy 192.245571 -327.77093) (xy 192.178097 -327.821883) (xy 192.10621 -327.866392)
			(xy 192.030523 -327.904079) (xy 191.951681 -327.93462) (xy 191.870357 -327.957757) (xy 191.787246 -327.973292)
			(xy 191.703055 -327.981092) (xy 191.66078 -327.981564) (xy 190.41618 -327.981564) (xy 190.373902 -327.981163)
			(xy 190.289708 -327.973359) (xy 190.206593 -327.957821) (xy 190.125266 -327.93468) (xy 190.046421 -327.904133)
			(xy 189.970731 -327.866443) (xy 189.898841 -327.821929) (xy 189.831365 -327.770972) (xy 189.768879 -327.714007)
			(xy 189.711915 -327.651519) (xy 189.66096 -327.584042) (xy 189.616448 -327.512152) (xy 189.578759 -327.436461)
			(xy 189.548214 -327.357615) (xy 189.525075 -327.276288) (xy 189.509538 -327.193172) (xy 189.501736 -327.108978)
			(xy 185.031391 -327.108978) (xy 185.023589 -327.193166) (xy 185.008053 -327.276277) (xy 184.984914 -327.3576)
			(xy 184.95437 -327.436441) (xy 184.916682 -327.512128) (xy 184.872172 -327.584014) (xy 184.821218 -327.651486)
			(xy 184.764255 -327.71397) (xy 184.701771 -327.77093) (xy 184.634297 -327.821883) (xy 184.56241 -327.866392)
			(xy 184.486723 -327.904079) (xy 184.407881 -327.93462) (xy 184.326557 -327.957757) (xy 184.243446 -327.973292)
			(xy 184.159255 -327.981092) (xy 184.11698 -327.981564) (xy 182.87238 -327.981564) (xy 182.829521 -327.981071)
			(xy 182.74418 -327.97305) (xy 182.659963 -327.957079) (xy 182.57761 -327.933299) (xy 182.497843 -327.901918)
			(xy 182.459376 -327.883012) (xy 182.445921 -327.876832) (xy 182.41679 -327.871632) (xy 182.38739 -327.875003)
			(xy 182.360192 -327.886662) (xy 182.337478 -327.90563) (xy 182.321157 -327.930314) (xy 182.312599 -327.958641)
			(xy 182.312056 -327.973436) (xy 182.312056 -328.192638) (xy 182.311547 -328.217715) (xy 182.303637 -328.267242)
			(xy 182.288079 -328.314922) (xy 182.265258 -328.359584) (xy 182.235733 -328.400128) (xy 182.21833 -328.41819)
			(xy 182.099712 -328.537062) (xy 182.21833 -328.655934) (xy 182.235759 -328.673975) (xy 182.265302 -328.714514)
			(xy 182.28813 -328.759179) (xy 182.303681 -328.806869) (xy 182.311571 -328.856406) (xy 182.312056 -328.881486)
			(xy 182.312056 -328.958448) (xy 182.312509 -328.96784) (xy 182.319291 -328.985357) (xy 182.331928 -328.999255)
			(xy 182.348722 -329.007668) (xy 182.35803 -329.008994) (xy 182.38551 -329.012143) (xy 182.438868 -329.026698)
			(xy 182.488918 -329.050233) (xy 182.53416 -329.082045) (xy 182.554118 -329.101196) (xy 182.681372 -329.22845)
			(xy 182.698789 -329.246488) (xy 182.728267 -329.287049) (xy 182.751035 -329.331722) (xy 182.766533 -329.379408)
			(xy 182.774378 -329.428932) (xy 182.774844 -329.454002) (xy 182.774844 -329.633834) (xy 182.774401 -329.658906)
			(xy 182.766558 -329.708431) (xy 182.751056 -329.756118) (xy 182.728276 -329.800788) (xy 182.698782 -329.841339)
			(xy 182.681372 -329.859386) (xy 182.554118 -329.98664) (xy 182.534173 -330.005803) (xy 182.488919 -330.037599)
			(xy 182.438866 -330.061127) (xy 182.385509 -330.075683) (xy 182.35803 -330.078842) (xy 182.348723 -330.08019)
			(xy 182.331916 -330.088584) (xy 182.31927 -330.102476) (xy 182.312488 -330.119995) (xy 182.312056 -330.129388)
			(xy 182.312056 -330.227178) (xy 182.311509 -330.252253) (xy 182.303608 -330.301778) (xy 182.28806 -330.349459)
			(xy 182.265246 -330.394121) (xy 182.23573 -330.434667) (xy 182.21833 -330.45273) (xy 181.95036 -330.7207)
			(xy 181.932322 -330.738117) (xy 181.891761 -330.767594) (xy 181.847087 -330.790362) (xy 181.799402 -330.805859)
			(xy 181.749878 -330.813705) (xy 181.724808 -330.814172) (xy 181.585108 -330.814172) (xy 181.569433 -330.827746)
			(xy 181.534132 -330.849491) (xy 181.495458 -330.864437) (xy 181.454708 -330.872081) (xy 181.433978 -330.872592)
			(xy 181.166516 -330.872592) (xy 181.166516 -330.812648) (xy 180.641244 -330.812648) (xy 180.641244 -330.872592)
			(xy 180.487574 -330.872592) (xy 180.473626 -330.873049) (xy 180.446784 -330.880658) (xy 180.423003 -330.895245)
			(xy 180.404056 -330.915724) (xy 180.391358 -330.940565) (xy 180.385854 -330.967915) (xy 180.387956 -330.995735)
			(xy 180.392324 -331.00899) (xy 180.403148 -331.040666) (xy 180.414766 -331.106586) (xy 180.415438 -331.140054)
			(xy 180.414952 -331.167305) (xy 180.407196 -331.221253) (xy 180.391841 -331.273548) (xy 180.369199 -331.323125)
			(xy 180.339733 -331.368975) (xy 180.304042 -331.410166) (xy 180.262851 -331.445857) (xy 180.217001 -331.475323)
			(xy 180.167424 -331.497965) (xy 180.115129 -331.51332) (xy 180.061181 -331.521076) (xy 180.006679 -331.521076)
			(xy 179.952731 -331.51332) (xy 179.900436 -331.497965) (xy 179.850859 -331.475323) (xy 179.805009 -331.445857)
			(xy 179.763818 -331.410166) (xy 179.728127 -331.368975) (xy 179.698661 -331.323125) (xy 179.676019 -331.273548)
			(xy 179.660664 -331.221253) (xy 179.652908 -331.167305) (xy 179.652422 -331.140054) (xy 179.653154 -331.106109)
			(xy 179.665169 -331.03929) (xy 179.676298 -331.007212) (xy 179.681015 -330.993003) (xy 179.682872 -330.963137)
			(xy 179.675994 -330.934014) (xy 179.660971 -330.908135) (xy 179.639092 -330.88772) (xy 179.612237 -330.874522)
			(xy 179.597558 -330.871576) (xy 179.573691 -330.867267) (xy 179.527217 -330.853396) (xy 179.48287 -330.83376)
			(xy 179.461922 -330.821538) (xy 179.44973 -330.814172) (xy 179.299108 -330.814172) (xy 179.283433 -330.827746)
			(xy 179.248132 -330.849491) (xy 179.209458 -330.864437) (xy 179.168708 -330.872081) (xy 179.147978 -330.872592)
			(xy 178.880516 -330.872592) (xy 178.880516 -330.812648) (xy 178.537108 -330.812648) (xy 178.537108 -331.638148)
			(xy 178.53659 -331.663224) (xy 178.52868 -331.71275) (xy 178.513124 -331.76043) (xy 178.490304 -331.805092)
			(xy 178.460783 -331.845637) (xy 178.443382 -331.8637) (xy 178.316382 -331.9907) (xy 178.298335 -332.008107)
			(xy 178.257776 -332.037585) (xy 178.213105 -332.060354) (xy 178.165421 -332.075854) (xy 178.1159 -332.083704)
			(xy 178.09083 -332.084172) (xy 176.76114 -332.084172) (xy 176.736069 -332.083703) (xy 176.686544 -332.075869)
			(xy 176.638857 -332.060374) (xy 176.594186 -332.0376) (xy 176.553635 -332.008109) (xy 176.535588 -331.9907)
			(xy 175.845978 -331.301344) (xy 175.825658 -331.300582) (xy 175.796276 -331.299282) (xy 175.738191 -331.290049)
			(xy 175.681767 -331.273449) (xy 175.627936 -331.249756) (xy 175.577583 -331.219362) (xy 175.531541 -331.182766)
			(xy 175.490567 -331.140573) (xy 175.455336 -331.093477) (xy 175.426431 -331.042255) (xy 175.404327 -330.987752)
			(xy 175.389388 -330.930867) (xy 175.381861 -330.872535) (xy 175.381412 -330.843128) (xy 156.694378 -330.843128)
			(xy 156.694378 -332.805786) (xy 157.66542 -333.776828) (xy 217.82532 -333.776828)
		)
		(stroke
			(width 0)
			(type solid)
		)
		(fill yes)
		(layer "B.Cu")
		(net "P12V_S3_AUX_CPU1_NVDIMM")
	)
	(gr_poly
		(pts
			(xy 355.472238 -219.35186) (xy 355.483814 -219.326855) (xy 355.513099 -219.280181) (xy 355.548793 -219.238205)
			(xy 355.590154 -219.2018) (xy 355.636322 -219.171723) (xy 355.686336 -219.148601) (xy 355.739156 -219.132913)
			(xy 355.793684 -219.124987) (xy 355.848784 -219.124987) (xy 355.903312 -219.132913) (xy 355.956132 -219.148601)
			(xy 356.006146 -219.171723) (xy 356.052314 -219.2018) (xy 356.093675 -219.238205) (xy 356.129369 -219.280181)
			(xy 356.158654 -219.326855) (xy 356.17023 -219.35186) (xy 356.183692 -219.382086) (xy 356.398576 -219.382086)
			(xy 356.412038 -219.35186) (xy 356.423614 -219.326855) (xy 356.452899 -219.280181) (xy 356.488593 -219.238205)
			(xy 356.529954 -219.2018) (xy 356.576122 -219.171723) (xy 356.626136 -219.148601) (xy 356.678956 -219.132913)
			(xy 356.733484 -219.124987) (xy 356.788584 -219.124987) (xy 356.843112 -219.132913) (xy 356.895932 -219.148601)
			(xy 356.945946 -219.171723) (xy 356.992114 -219.2018) (xy 357.033475 -219.238205) (xy 357.069169 -219.280181)
			(xy 357.098454 -219.326855) (xy 357.11003 -219.35186) (xy 357.123492 -219.382086) (xy 357.338376 -219.382086)
			(xy 357.351838 -219.35186) (xy 357.363414 -219.326855) (xy 357.392699 -219.280181) (xy 357.428393 -219.238205)
			(xy 357.469754 -219.2018) (xy 357.515922 -219.171723) (xy 357.565936 -219.148601) (xy 357.618756 -219.132913)
			(xy 357.673284 -219.124987) (xy 357.728384 -219.124987) (xy 357.782912 -219.132913) (xy 357.835732 -219.148601)
			(xy 357.885746 -219.171723) (xy 357.931914 -219.2018) (xy 357.973275 -219.238205) (xy 358.008969 -219.280181)
			(xy 358.038254 -219.326855) (xy 358.04983 -219.35186) (xy 358.063292 -219.382086) (xy 358.278176 -219.382086)
			(xy 358.291638 -219.35186) (xy 358.303214 -219.326855) (xy 358.332499 -219.280181) (xy 358.368193 -219.238205)
			(xy 358.409554 -219.2018) (xy 358.455722 -219.171723) (xy 358.505736 -219.148601) (xy 358.558556 -219.132913)
			(xy 358.613084 -219.124987) (xy 358.668184 -219.124987) (xy 358.722712 -219.132913) (xy 358.775532 -219.148601)
			(xy 358.825546 -219.171723) (xy 358.871714 -219.2018) (xy 358.913075 -219.238205) (xy 358.948769 -219.280181)
			(xy 358.978054 -219.326855) (xy 358.98963 -219.35186) (xy 359.003092 -219.382086) (xy 359.217722 -219.382086)
			(xy 359.231184 -219.35186) (xy 359.243434 -219.325455) (xy 359.274751 -219.276393) (xy 359.313164 -219.232662)
			(xy 359.35778 -219.195281) (xy 359.40756 -219.165117) (xy 359.461348 -219.142874) (xy 359.517893 -219.129067)
			(xy 359.575879 -219.124018) (xy 359.633959 -219.127844) (xy 359.662476 -219.133674) (xy 359.689654 -219.13977)
			(xy 359.765854 -219.06357) (xy 359.896156 -219.06357) (xy 359.896156 -218.98483) (xy 359.872788 -218.969844)
			(xy 359.849851 -218.954574) (xy 359.808954 -218.917652) (xy 359.774772 -218.874437) (xy 359.74826 -218.826137)
			(xy 359.730156 -218.774098) (xy 359.720965 -218.719771) (xy 359.720388 -218.692222) (xy 359.720852 -218.666875)
			(xy 359.728612 -218.61678) (xy 359.743953 -218.568464) (xy 359.766513 -218.523067) (xy 359.795759 -218.481661)
			(xy 359.831002 -218.445223) (xy 359.871409 -218.414612) (xy 359.916028 -218.39055) (xy 359.963806 -218.373606)
			(xy 359.988612 -218.368372) (xy 360.011472 -218.364054) (xy 360.216704 -218.008708) (xy 360.20883 -217.98661)
			(xy 360.200369 -217.960365) (xy 360.191308 -217.905976) (xy 360.190796 -217.878406) (xy 360.191304 -217.852519)
			(xy 360.199403 -217.801381) (xy 360.215402 -217.752141) (xy 360.238908 -217.706009) (xy 360.26934 -217.664122)
			(xy 360.30595 -217.627512) (xy 360.347837 -217.59708) (xy 360.393969 -217.573574) (xy 360.443209 -217.557575)
			(xy 360.494347 -217.549476) (xy 360.546121 -217.549476) (xy 360.597259 -217.557575) (xy 360.646499 -217.573574)
			(xy 360.692631 -217.59708) (xy 360.734518 -217.627512) (xy 360.771128 -217.664122) (xy 360.80156 -217.706009)
			(xy 360.825066 -217.752141) (xy 360.841065 -217.801381) (xy 360.849164 -217.852519) (xy 360.849672 -217.878406)
			(xy 360.849204 -217.90378) (xy 360.841424 -217.953929) (xy 360.826048 -218.002293) (xy 360.803441 -218.047728)
			(xy 360.774136 -218.08916) (xy 360.738826 -218.12561) (xy 360.698345 -218.156217) (xy 360.653652 -218.180257)
			(xy 360.605801 -218.197162) (xy 360.58094 -218.202256) (xy 360.55808 -218.206574) (xy 360.353356 -218.561412)
			(xy 360.36123 -218.583256) (xy 360.369875 -218.609664) (xy 360.379195 -218.66444) (xy 360.379772 -218.692222)
			(xy 360.37934 -218.715997) (xy 360.372456 -218.763046) (xy 360.366056 -218.785948) (xy 360.36261 -218.799023)
			(xy 360.361978 -218.826045) (xy 360.368457 -218.852286) (xy 360.381592 -218.875909) (xy 360.400465 -218.895259)
			(xy 360.423752 -218.90898) (xy 360.449824 -218.916112) (xy 360.463338 -218.916504) (xy 361.516676 -218.916504)
			(xy 361.530195 -218.916084) (xy 361.556283 -218.908986) (xy 361.579589 -218.895281) (xy 361.598475 -218.875934)
			(xy 361.611614 -218.852303) (xy 361.61808 -218.826051) (xy 361.617422 -218.799022) (xy 361.613958 -218.785948)
			(xy 361.607629 -218.763037) (xy 361.600863 -218.715989) (xy 361.600496 -218.692222) (xy 361.600958 -218.666885)
			(xy 361.608708 -218.616807) (xy 361.624029 -218.568504) (xy 361.64656 -218.523115) (xy 361.675771 -218.481707)
			(xy 361.710974 -218.445257) (xy 361.751339 -218.414621) (xy 361.795916 -218.390523) (xy 361.843656 -218.373529)
			(xy 361.868466 -218.368372) (xy 361.891326 -218.364054) (xy 362.096304 -218.008962) (xy 362.088684 -217.986864)
			(xy 362.080141 -217.960568) (xy 362.070953 -217.90605) (xy 362.070396 -217.878406) (xy 362.070904 -217.852519)
			(xy 362.079003 -217.801381) (xy 362.095002 -217.752141) (xy 362.118508 -217.706009) (xy 362.14894 -217.664122)
			(xy 362.18555 -217.627512) (xy 362.227437 -217.59708) (xy 362.273569 -217.573574) (xy 362.322809 -217.557575)
			(xy 362.373947 -217.549476) (xy 362.425721 -217.549476) (xy 362.476859 -217.557575) (xy 362.526099 -217.573574)
			(xy 362.572231 -217.59708) (xy 362.614118 -217.627512) (xy 362.650728 -217.664122) (xy 362.68116 -217.706009)
			(xy 362.704666 -217.752141) (xy 362.720665 -217.801381) (xy 362.728764 -217.852519) (xy 362.729272 -217.878406)
			(xy 362.728798 -217.903764) (xy 362.721015 -217.95388) (xy 362.705648 -218.002212) (xy 362.683061 -218.047621)
			(xy 362.653786 -218.089035) (xy 362.618514 -218.125477) (xy 362.578076 -218.156088) (xy 362.533428 -218.180144)
			(xy 362.485623 -218.197079) (xy 362.460794 -218.202256) (xy 362.437934 -218.206574) (xy 362.23321 -218.561412)
			(xy 362.241084 -218.583256) (xy 362.249664 -218.609675) (xy 362.258863 -218.66445) (xy 362.259372 -218.692222)
			(xy 362.258991 -218.715988) (xy 362.252231 -218.763035) (xy 362.24591 -218.785948) (xy 362.242463 -218.79902)
			(xy 362.24183 -218.826038) (xy 362.248309 -218.852276) (xy 362.261446 -218.875893) (xy 362.28032 -218.895236)
			(xy 362.303609 -218.908947) (xy 362.32968 -218.916067) (xy 362.343192 -218.916504) (xy 362.977176 -218.916504)
			(xy 363.207554 -218.686126) (xy 363.207554 -218.210638) (xy 363.179614 -218.196414) (xy 363.154732 -218.183321)
			(xy 363.109086 -218.150497) (xy 363.069171 -218.110903) (xy 363.03598 -218.065523) (xy 363.010339 -218.015488)
			(xy 362.992888 -217.962042) (xy 362.984059 -217.906517) (xy 362.983526 -217.878406) (xy 362.983901 -217.855161)
			(xy 362.989946 -217.809066) (xy 363.001933 -217.764148) (xy 363.01045 -217.742516) (xy 363.020102 -217.719402)
			(xy 362.847636 -217.420698) (xy 362.822744 -217.417396) (xy 362.797383 -217.413593) (xy 362.748032 -217.399649)
			(xy 362.701193 -217.37877) (xy 362.657833 -217.351387) (xy 362.618851 -217.318067) (xy 362.585051 -217.2795)
			(xy 362.557134 -217.236482) (xy 362.535677 -217.189904) (xy 362.521124 -217.14073) (xy 362.513777 -217.089977)
			(xy 362.513372 -217.064336) (xy 362.513551 -217.048179) (xy 362.516472 -217.015998) (xy 362.519214 -217.000074)
			(xy 362.52404 -216.973912) (xy 362.371894 -216.821766) (xy 362.371894 -216.633298) (xy 362.330238 -216.625678)
			(xy 362.302367 -216.61996) (xy 362.248598 -216.601365) (xy 362.198186 -216.574992) (xy 362.15225 -216.541424)
			(xy 362.111808 -216.501407) (xy 362.077758 -216.455828) (xy 362.050853 -216.405698) (xy 362.031692 -216.352128)
			(xy 362.020699 -216.296307) (xy 362.018117 -216.239472) (xy 362.024004 -216.182884) (xy 362.038229 -216.127797)
			(xy 362.060477 -216.075434) (xy 362.090255 -216.026955) (xy 362.126902 -215.983437) (xy 362.169605 -215.945843)
			(xy 362.217418 -215.915007) (xy 362.243116 -215.902794) (xy 362.273088 -215.889078) (xy 362.273088 -214.648034)
			(xy 362.371894 -214.549228) (xy 362.371894 -214.292942) (xy 362.617766 -214.04707) (xy 362.617766 -209.673698)
			(xy 362.247942 -209.303874) (xy 359.70845 -209.303874) (xy 359.452672 -209.559652) (xy 359.452672 -213.699852)
			(xy 360.070146 -214.317326) (xy 360.070146 -214.32647) (xy 360.142028 -214.398098) (xy 360.142028 -214.714836)
			(xy 360.070146 -214.786464) (xy 360.070146 -215.053164) (xy 360.112564 -215.060276) (xy 360.138973 -215.065116)
			(xy 360.190185 -215.081234) (xy 360.238632 -215.104374) (xy 360.283355 -215.134078) (xy 360.323471 -215.16976)
			(xy 360.358188 -215.210715) (xy 360.386819 -215.256133) (xy 360.408799 -215.305117) (xy 360.423692 -215.356699)
			(xy 360.431206 -215.409859) (xy 360.431588 -215.436704) (xy 360.431134 -215.463353) (xy 360.63427 -215.463353)
			(xy 360.63427 -215.410055) (xy 360.642213 -215.357351) (xy 360.657923 -215.306421) (xy 360.681049 -215.2584)
			(xy 360.711073 -215.214363) (xy 360.747325 -215.175292) (xy 360.788996 -215.142061) (xy 360.835154 -215.115412)
			(xy 360.884768 -215.09594) (xy 360.93673 -215.08408) (xy 360.98988 -215.080097) (xy 361.04303 -215.08408)
			(xy 361.094992 -215.09594) (xy 361.144606 -215.115412) (xy 361.190764 -215.142061) (xy 361.232435 -215.175292)
			(xy 361.268687 -215.214363) (xy 361.298711 -215.2584) (xy 361.321837 -215.306421) (xy 361.337547 -215.357351)
			(xy 361.34549 -215.410055) (xy 361.345988 -215.436704) (xy 361.34549 -215.463353) (xy 361.337547 -215.516057)
			(xy 361.321837 -215.566987) (xy 361.298711 -215.615008) (xy 361.268687 -215.659045) (xy 361.232435 -215.698116)
			(xy 361.190764 -215.731347) (xy 361.144606 -215.757996) (xy 361.094992 -215.777468) (xy 361.04303 -215.789328)
			(xy 360.98988 -215.793312) (xy 360.93673 -215.789328) (xy 360.884768 -215.777468) (xy 360.835154 -215.757996)
			(xy 360.788996 -215.731347) (xy 360.747325 -215.698116) (xy 360.711073 -215.659045) (xy 360.681049 -215.615008)
			(xy 360.657923 -215.566987) (xy 360.642213 -215.516057) (xy 360.63427 -215.463353) (xy 360.431134 -215.463353)
			(xy 360.431124 -215.463956) (xy 360.423367 -215.517906) (xy 360.40801 -215.570202) (xy 360.385367 -215.61978)
			(xy 360.355899 -215.665631) (xy 360.320205 -215.706822) (xy 360.279012 -215.742513) (xy 360.233159 -215.771979)
			(xy 360.183579 -215.794619) (xy 360.131282 -215.809972) (xy 360.077332 -215.817726) (xy 360.05008 -215.818212)
			(xy 360.020568 -215.817659) (xy 359.962248 -215.808566) (xy 359.906025 -215.790599) (xy 359.853239 -215.764187)
			(xy 359.805151 -215.729961) (xy 359.783634 -215.709754) (xy 359.773879 -215.700794) (xy 359.750834 -215.687757)
			(xy 359.725212 -215.681082) (xy 359.698735 -215.68122) (xy 359.673183 -215.688161) (xy 359.650275 -215.701437)
			(xy 359.640632 -215.710516) (xy 359.601008 -215.75014) (xy 359.212388 -215.75014) (xy 359.205276 -215.752172)
			(xy 359.182077 -215.758751) (xy 359.134389 -215.76589) (xy 359.11028 -215.766396) (xy 359.086169 -215.765921)
			(xy 359.038477 -215.758779) (xy 359.015284 -215.752172) (xy 359.008172 -215.75014) (xy 358.272588 -215.75014)
			(xy 358.265476 -215.752172) (xy 358.242277 -215.758751) (xy 358.194589 -215.76589) (xy 358.17048 -215.766396)
			(xy 358.146369 -215.765921) (xy 358.098677 -215.758779) (xy 358.075484 -215.752172) (xy 358.068372 -215.75014)
			(xy 357.332788 -215.75014) (xy 357.325676 -215.752172) (xy 357.302477 -215.758751) (xy 357.254789 -215.76589)
			(xy 357.23068 -215.766396) (xy 357.206569 -215.765921) (xy 357.158877 -215.758779) (xy 357.135684 -215.752172)
			(xy 357.128572 -215.75014) (xy 356.392988 -215.75014) (xy 356.385876 -215.752172) (xy 356.362677 -215.758751)
			(xy 356.314989 -215.76589) (xy 356.29088 -215.766396) (xy 356.264974 -215.765886) (xy 356.213799 -215.757778)
			(xy 356.164523 -215.741765) (xy 356.118358 -215.71824) (xy 356.076442 -215.687784) (xy 356.039805 -215.651146)
			(xy 356.009351 -215.609228) (xy 355.985829 -215.563062) (xy 355.969818 -215.513785) (xy 355.961713 -215.46261)
			(xy 355.961188 -215.436704) (xy 355.961442 -215.431878) (xy 355.961696 -215.410288) (xy 355.798374 -215.246966)
			(xy 354.748592 -215.246966) (xy 354.714556 -215.305894) (xy 354.72243 -215.327738) (xy 354.731077 -215.354146)
			(xy 354.740399 -215.408922) (xy 354.740972 -215.436704) (xy 354.740464 -215.462611) (xy 354.732358 -215.513788)
			(xy 354.716346 -215.563067) (xy 354.692823 -215.609234) (xy 354.662367 -215.651153) (xy 354.625729 -215.687791)
			(xy 354.58381 -215.718247) (xy 354.537643 -215.74177) (xy 354.488364 -215.757782) (xy 354.437187 -215.765888)
			(xy 354.385373 -215.765888) (xy 354.334196 -215.757782) (xy 354.284917 -215.74177) (xy 354.23875 -215.718247)
			(xy 354.196831 -215.687791) (xy 354.160193 -215.651153) (xy 354.129737 -215.609234) (xy 354.106214 -215.563067)
			(xy 354.090202 -215.513788) (xy 354.082096 -215.462611) (xy 354.081588 -215.436704) (xy 354.081835 -215.419749)
			(xy 354.085396 -215.386026) (xy 354.0887 -215.369394) (xy 354.091269 -215.354511) (xy 354.088573 -215.324446)
			(xy 354.077208 -215.296481) (xy 354.058165 -215.273059) (xy 354.033108 -215.256226) (xy 354.004226 -215.247451)
			(xy 353.989132 -215.246966) (xy 352.868992 -215.246966) (xy 352.834956 -215.305894) (xy 352.84283 -215.327738)
			(xy 352.851477 -215.354146) (xy 352.860799 -215.408922) (xy 352.861372 -215.436704) (xy 352.860864 -215.462611)
			(xy 352.852758 -215.513788) (xy 352.836746 -215.563067) (xy 352.813223 -215.609234) (xy 352.782767 -215.651153)
			(xy 352.746129 -215.687791) (xy 352.70421 -215.718247) (xy 352.658043 -215.74177) (xy 352.608764 -215.757782)
			(xy 352.557587 -215.765888) (xy 352.505773 -215.765888) (xy 352.454596 -215.757782) (xy 352.405317 -215.74177)
			(xy 352.35915 -215.718247) (xy 352.317231 -215.687791) (xy 352.280593 -215.651153) (xy 352.250137 -215.609234)
			(xy 352.226614 -215.563067) (xy 352.210602 -215.513788) (xy 352.202496 -215.462611) (xy 352.201988 -215.436704)
			(xy 352.202235 -215.419749) (xy 352.205796 -215.386026) (xy 352.2091 -215.369394) (xy 352.211669 -215.354511)
			(xy 352.208973 -215.324446) (xy 352.197608 -215.296481) (xy 352.178565 -215.273059) (xy 352.153508 -215.256226)
			(xy 352.124626 -215.247451) (xy 352.109532 -215.246966) (xy 350.989392 -215.246966) (xy 350.955356 -215.305894)
			(xy 350.96323 -215.327738) (xy 350.971877 -215.354146) (xy 350.981199 -215.408922) (xy 350.981772 -215.436704)
			(xy 350.981264 -215.462611) (xy 350.973158 -215.513788) (xy 350.957146 -215.563067) (xy 350.933623 -215.609234)
			(xy 350.903167 -215.651153) (xy 350.866529 -215.687791) (xy 350.82461 -215.718247) (xy 350.778443 -215.74177)
			(xy 350.729164 -215.757782) (xy 350.677987 -215.765888) (xy 350.626173 -215.765888) (xy 350.574996 -215.757782)
			(xy 350.525717 -215.74177) (xy 350.47955 -215.718247) (xy 350.437631 -215.687791) (xy 350.400993 -215.651153)
			(xy 350.370537 -215.609234) (xy 350.347014 -215.563067) (xy 350.331002 -215.513788) (xy 350.322896 -215.462611)
			(xy 350.322388 -215.436704) (xy 350.322635 -215.419749) (xy 350.326196 -215.386026) (xy 350.3295 -215.369394)
			(xy 350.332069 -215.354511) (xy 350.329373 -215.324446) (xy 350.318008 -215.296481) (xy 350.298965 -215.273059)
			(xy 350.273908 -215.256226) (xy 350.245026 -215.247451) (xy 350.229932 -215.246966) (xy 349.238062 -215.246966)
			(xy 349.09887 -215.386158) (xy 349.100902 -215.409526) (xy 349.102172 -215.436704) (xy 349.101684 -215.462242)
			(xy 349.093791 -215.512706) (xy 349.078208 -215.561348) (xy 349.055311 -215.607005) (xy 349.025645 -215.648585)
			(xy 348.989921 -215.685091) (xy 348.948995 -215.715651) (xy 348.926658 -215.728042) (xy 348.89948 -215.742266)
			(xy 348.89948 -215.861646) (xy 348.899908 -215.875168) (xy 348.907021 -215.901261) (xy 348.920734 -215.92457)
			(xy 348.940087 -215.943462) (xy 348.963721 -215.956609) (xy 348.989977 -215.96309) (xy 349.017014 -215.96245)
			(xy 349.042934 -215.954733) (xy 349.054674 -215.948006) (xy 349.075933 -215.935308) (xy 349.121214 -215.915267)
			(xy 349.168834 -215.901689) (xy 349.217875 -215.894837) (xy 349.242634 -215.894412) (xy 349.26928 -215.894913)
			(xy 349.321977 -215.90286) (xy 349.3729 -215.918572) (xy 349.420913 -215.941698) (xy 349.464944 -215.971721)
			(xy 349.504008 -216.007971) (xy 349.537233 -216.049638) (xy 349.563878 -216.095791) (xy 349.583347 -216.1454)
			(xy 349.595205 -216.197357) (xy 349.599187 -216.2505) (xy 349.597189 -216.277169) (xy 349.826824 -216.277169)
			(xy 349.826824 -216.223871) (xy 349.834767 -216.171167) (xy 349.850477 -216.120237) (xy 349.873603 -216.072216)
			(xy 349.903627 -216.028179) (xy 349.939879 -215.989108) (xy 349.98155 -215.955877) (xy 350.027708 -215.929228)
			(xy 350.077322 -215.909756) (xy 350.129284 -215.897896) (xy 350.182434 -215.893913) (xy 350.235584 -215.897896)
			(xy 350.287546 -215.909756) (xy 350.33716 -215.929228) (xy 350.383318 -215.955877) (xy 350.424989 -215.989108)
			(xy 350.461241 -216.028179) (xy 350.491265 -216.072216) (xy 350.514391 -216.120237) (xy 350.530101 -216.171167)
			(xy 350.538044 -216.223871) (xy 350.538542 -216.25052) (xy 350.538044 -216.277169) (xy 350.766624 -216.277169)
			(xy 350.766624 -216.223871) (xy 350.774567 -216.171167) (xy 350.790277 -216.120237) (xy 350.813403 -216.072216)
			(xy 350.843427 -216.028179) (xy 350.879679 -215.989108) (xy 350.92135 -215.955877) (xy 350.967508 -215.929228)
			(xy 351.017122 -215.909756) (xy 351.069084 -215.897896) (xy 351.122234 -215.893913) (xy 351.175384 -215.897896)
			(xy 351.227346 -215.909756) (xy 351.27696 -215.929228) (xy 351.323118 -215.955877) (xy 351.364789 -215.989108)
			(xy 351.401041 -216.028179) (xy 351.431065 -216.072216) (xy 351.454191 -216.120237) (xy 351.469901 -216.171167)
			(xy 351.477844 -216.223871) (xy 351.478342 -216.25052) (xy 351.477844 -216.277169) (xy 351.706424 -216.277169)
			(xy 351.706424 -216.223871) (xy 351.714367 -216.171167) (xy 351.730077 -216.120237) (xy 351.753203 -216.072216)
			(xy 351.783227 -216.028179) (xy 351.819479 -215.989108) (xy 351.86115 -215.955877) (xy 351.907308 -215.929228)
			(xy 351.956922 -215.909756) (xy 352.008884 -215.897896) (xy 352.062034 -215.893913) (xy 352.115184 -215.897896)
			(xy 352.167146 -215.909756) (xy 352.21676 -215.929228) (xy 352.262918 -215.955877) (xy 352.304589 -215.989108)
			(xy 352.340841 -216.028179) (xy 352.370865 -216.072216) (xy 352.393991 -216.120237) (xy 352.409701 -216.171167)
			(xy 352.417644 -216.223871) (xy 352.418142 -216.25052) (xy 352.417644 -216.277169) (xy 352.646224 -216.277169)
			(xy 352.646224 -216.223871) (xy 352.654167 -216.171167) (xy 352.669877 -216.120237) (xy 352.693003 -216.072216)
			(xy 352.723027 -216.028179) (xy 352.759279 -215.989108) (xy 352.80095 -215.955877) (xy 352.847108 -215.929228)
			(xy 352.896722 -215.909756) (xy 352.948684 -215.897896) (xy 353.001834 -215.893913) (xy 353.054984 -215.897896)
			(xy 353.106946 -215.909756) (xy 353.15656 -215.929228) (xy 353.202718 -215.955877) (xy 353.244389 -215.989108)
			(xy 353.280641 -216.028179) (xy 353.310665 -216.072216) (xy 353.333791 -216.120237) (xy 353.349501 -216.171167)
			(xy 353.357444 -216.223871) (xy 353.357942 -216.25052) (xy 353.357444 -216.277169) (xy 353.586024 -216.277169)
			(xy 353.586024 -216.223871) (xy 353.593967 -216.171167) (xy 353.609677 -216.120237) (xy 353.632803 -216.072216)
			(xy 353.662827 -216.028179) (xy 353.699079 -215.989108) (xy 353.74075 -215.955877) (xy 353.786908 -215.929228)
			(xy 353.836522 -215.909756) (xy 353.888484 -215.897896) (xy 353.941634 -215.893913) (xy 353.994784 -215.897896)
			(xy 354.046746 -215.909756) (xy 354.09636 -215.929228) (xy 354.142518 -215.955877) (xy 354.184189 -215.989108)
			(xy 354.220441 -216.028179) (xy 354.250465 -216.072216) (xy 354.273591 -216.120237) (xy 354.289301 -216.171167)
			(xy 354.297244 -216.223871) (xy 354.297742 -216.25052) (xy 354.297244 -216.277169) (xy 354.525824 -216.277169)
			(xy 354.525824 -216.223871) (xy 354.533767 -216.171167) (xy 354.549477 -216.120237) (xy 354.572603 -216.072216)
			(xy 354.602627 -216.028179) (xy 354.638879 -215.989108) (xy 354.68055 -215.955877) (xy 354.726708 -215.929228)
			(xy 354.776322 -215.909756) (xy 354.828284 -215.897896) (xy 354.881434 -215.893913) (xy 354.934584 -215.897896)
			(xy 354.986546 -215.909756) (xy 355.03616 -215.929228) (xy 355.082318 -215.955877) (xy 355.123989 -215.989108)
			(xy 355.160241 -216.028179) (xy 355.190265 -216.072216) (xy 355.213391 -216.120237) (xy 355.229101 -216.171167)
			(xy 355.237044 -216.223871) (xy 355.237542 -216.25052) (xy 355.237044 -216.277169) (xy 355.465624 -216.277169)
			(xy 355.465624 -216.223871) (xy 355.473567 -216.171167) (xy 355.489277 -216.120237) (xy 355.512403 -216.072216)
			(xy 355.542427 -216.028179) (xy 355.578679 -215.989108) (xy 355.62035 -215.955877) (xy 355.666508 -215.929228)
			(xy 355.716122 -215.909756) (xy 355.768084 -215.897896) (xy 355.821234 -215.893913) (xy 355.874384 -215.897896)
			(xy 355.926346 -215.909756) (xy 355.97596 -215.929228) (xy 356.022118 -215.955877) (xy 356.063789 -215.989108)
			(xy 356.100041 -216.028179) (xy 356.130065 -216.072216) (xy 356.153191 -216.120237) (xy 356.168901 -216.171167)
			(xy 356.176844 -216.223871) (xy 356.177342 -216.25052) (xy 356.176844 -216.277169) (xy 356.405424 -216.277169)
			(xy 356.405424 -216.223871) (xy 356.413367 -216.171167) (xy 356.429077 -216.120237) (xy 356.452203 -216.072216)
			(xy 356.482227 -216.028179) (xy 356.518479 -215.989108) (xy 356.56015 -215.955877) (xy 356.606308 -215.929228)
			(xy 356.655922 -215.909756) (xy 356.707884 -215.897896) (xy 356.761034 -215.893913) (xy 356.814184 -215.897896)
			(xy 356.866146 -215.909756) (xy 356.91576 -215.929228) (xy 356.961918 -215.955877) (xy 357.003589 -215.989108)
			(xy 357.039841 -216.028179) (xy 357.069865 -216.072216) (xy 357.092991 -216.120237) (xy 357.108701 -216.171167)
			(xy 357.116644 -216.223871) (xy 357.117142 -216.25052) (xy 357.116644 -216.277169) (xy 357.345224 -216.277169)
			(xy 357.345224 -216.223871) (xy 357.353167 -216.171167) (xy 357.368877 -216.120237) (xy 357.392003 -216.072216)
			(xy 357.422027 -216.028179) (xy 357.458279 -215.989108) (xy 357.49995 -215.955877) (xy 357.546108 -215.929228)
			(xy 357.595722 -215.909756) (xy 357.647684 -215.897896) (xy 357.700834 -215.893913) (xy 357.753984 -215.897896)
			(xy 357.805946 -215.909756) (xy 357.85556 -215.929228) (xy 357.901718 -215.955877) (xy 357.943389 -215.989108)
			(xy 357.979641 -216.028179) (xy 358.009665 -216.072216) (xy 358.032791 -216.120237) (xy 358.048501 -216.171167)
			(xy 358.056444 -216.223871) (xy 358.056942 -216.25052) (xy 358.056444 -216.277169) (xy 358.285024 -216.277169)
			(xy 358.285024 -216.223871) (xy 358.292967 -216.171167) (xy 358.308677 -216.120237) (xy 358.331803 -216.072216)
			(xy 358.361827 -216.028179) (xy 358.398079 -215.989108) (xy 358.43975 -215.955877) (xy 358.485908 -215.929228)
			(xy 358.535522 -215.909756) (xy 358.587484 -215.897896) (xy 358.640634 -215.893913) (xy 358.693784 -215.897896)
			(xy 358.745746 -215.909756) (xy 358.79536 -215.929228) (xy 358.841518 -215.955877) (xy 358.883189 -215.989108)
			(xy 358.919441 -216.028179) (xy 358.949465 -216.072216) (xy 358.972591 -216.120237) (xy 358.988301 -216.171167)
			(xy 358.996244 -216.223871) (xy 358.996742 -216.25052) (xy 358.996244 -216.277169) (xy 359.224824 -216.277169)
			(xy 359.224824 -216.223871) (xy 359.232767 -216.171167) (xy 359.248477 -216.120237) (xy 359.271603 -216.072216)
			(xy 359.301627 -216.028179) (xy 359.337879 -215.989108) (xy 359.37955 -215.955877) (xy 359.425708 -215.929228)
			(xy 359.475322 -215.909756) (xy 359.527284 -215.897896) (xy 359.580434 -215.893913) (xy 359.633584 -215.897896)
			(xy 359.685546 -215.909756) (xy 359.73516 -215.929228) (xy 359.781318 -215.955877) (xy 359.822989 -215.989108)
			(xy 359.859241 -216.028179) (xy 359.889265 -216.072216) (xy 359.912391 -216.120237) (xy 359.928101 -216.171167)
			(xy 359.936044 -216.223871) (xy 359.936542 -216.25052) (xy 359.936044 -216.277169) (xy 360.16437 -216.277169)
			(xy 360.16437 -216.223871) (xy 360.172313 -216.171167) (xy 360.188023 -216.120237) (xy 360.211149 -216.072216)
			(xy 360.241173 -216.028179) (xy 360.277425 -215.989108) (xy 360.319096 -215.955877) (xy 360.365254 -215.929228)
			(xy 360.414868 -215.909756) (xy 360.46683 -215.897896) (xy 360.51998 -215.893913) (xy 360.57313 -215.897896)
			(xy 360.625092 -215.909756) (xy 360.674706 -215.929228) (xy 360.720864 -215.955877) (xy 360.762535 -215.989108)
			(xy 360.798787 -216.028179) (xy 360.828811 -216.072216) (xy 360.851937 -216.120237) (xy 360.867647 -216.171167)
			(xy 360.87559 -216.223871) (xy 360.876088 -216.25052) (xy 360.87559 -216.277169) (xy 361.10417 -216.277169)
			(xy 361.10417 -216.223871) (xy 361.112113 -216.171167) (xy 361.127823 -216.120237) (xy 361.150949 -216.072216)
			(xy 361.180973 -216.028179) (xy 361.217225 -215.989108) (xy 361.258896 -215.955877) (xy 361.305054 -215.929228)
			(xy 361.354668 -215.909756) (xy 361.40663 -215.897896) (xy 361.45978 -215.893913) (xy 361.51293 -215.897896)
			(xy 361.564892 -215.909756) (xy 361.614506 -215.929228) (xy 361.660664 -215.955877) (xy 361.702335 -215.989108)
			(xy 361.738587 -216.028179) (xy 361.768611 -216.072216) (xy 361.791737 -216.120237) (xy 361.807447 -216.171167)
			(xy 361.81539 -216.223871) (xy 361.815888 -216.25052) (xy 361.81539 -216.277169) (xy 361.807447 -216.329873)
			(xy 361.791737 -216.380803) (xy 361.768611 -216.428824) (xy 361.738587 -216.472861) (xy 361.702335 -216.511932)
			(xy 361.660664 -216.545163) (xy 361.614506 -216.571812) (xy 361.564892 -216.591284) (xy 361.51293 -216.603144)
			(xy 361.45978 -216.607128) (xy 361.40663 -216.603144) (xy 361.354668 -216.591284) (xy 361.305054 -216.571812)
			(xy 361.258896 -216.545163) (xy 361.217225 -216.511932) (xy 361.180973 -216.472861) (xy 361.150949 -216.428824)
			(xy 361.127823 -216.380803) (xy 361.112113 -216.329873) (xy 361.10417 -216.277169) (xy 360.87559 -216.277169)
			(xy 360.867647 -216.329873) (xy 360.851937 -216.380803) (xy 360.828811 -216.428824) (xy 360.798787 -216.472861)
			(xy 360.762535 -216.511932) (xy 360.720864 -216.545163) (xy 360.674706 -216.571812) (xy 360.625092 -216.591284)
			(xy 360.57313 -216.603144) (xy 360.51998 -216.607128) (xy 360.46683 -216.603144) (xy 360.414868 -216.591284)
			(xy 360.365254 -216.571812) (xy 360.319096 -216.545163) (xy 360.277425 -216.511932) (xy 360.241173 -216.472861)
			(xy 360.211149 -216.428824) (xy 360.188023 -216.380803) (xy 360.172313 -216.329873) (xy 360.16437 -216.277169)
			(xy 359.936044 -216.277169) (xy 359.928101 -216.329873) (xy 359.912391 -216.380803) (xy 359.889265 -216.428824)
			(xy 359.859241 -216.472861) (xy 359.822989 -216.511932) (xy 359.781318 -216.545163) (xy 359.73516 -216.571812)
			(xy 359.685546 -216.591284) (xy 359.633584 -216.603144) (xy 359.580434 -216.607128) (xy 359.527284 -216.603144)
			(xy 359.475322 -216.591284) (xy 359.425708 -216.571812) (xy 359.37955 -216.545163) (xy 359.337879 -216.511932)
			(xy 359.301627 -216.472861) (xy 359.271603 -216.428824) (xy 359.248477 -216.380803) (xy 359.232767 -216.329873)
			(xy 359.224824 -216.277169) (xy 358.996244 -216.277169) (xy 358.988301 -216.329873) (xy 358.972591 -216.380803)
			(xy 358.949465 -216.428824) (xy 358.919441 -216.472861) (xy 358.883189 -216.511932) (xy 358.841518 -216.545163)
			(xy 358.79536 -216.571812) (xy 358.745746 -216.591284) (xy 358.693784 -216.603144) (xy 358.640634 -216.607128)
			(xy 358.587484 -216.603144) (xy 358.535522 -216.591284) (xy 358.485908 -216.571812) (xy 358.43975 -216.545163)
			(xy 358.398079 -216.511932) (xy 358.361827 -216.472861) (xy 358.331803 -216.428824) (xy 358.308677 -216.380803)
			(xy 358.292967 -216.329873) (xy 358.285024 -216.277169) (xy 358.056444 -216.277169) (xy 358.048501 -216.329873)
			(xy 358.032791 -216.380803) (xy 358.009665 -216.428824) (xy 357.979641 -216.472861) (xy 357.943389 -216.511932)
			(xy 357.901718 -216.545163) (xy 357.85556 -216.571812) (xy 357.805946 -216.591284) (xy 357.753984 -216.603144)
			(xy 357.700834 -216.607128) (xy 357.647684 -216.603144) (xy 357.595722 -216.591284) (xy 357.546108 -216.571812)
			(xy 357.49995 -216.545163) (xy 357.458279 -216.511932) (xy 357.422027 -216.472861) (xy 357.392003 -216.428824)
			(xy 357.368877 -216.380803) (xy 357.353167 -216.329873) (xy 357.345224 -216.277169) (xy 357.116644 -216.277169)
			(xy 357.108701 -216.329873) (xy 357.092991 -216.380803) (xy 357.069865 -216.428824) (xy 357.039841 -216.472861)
			(xy 357.003589 -216.511932) (xy 356.961918 -216.545163) (xy 356.91576 -216.571812) (xy 356.866146 -216.591284)
			(xy 356.814184 -216.603144) (xy 356.761034 -216.607128) (xy 356.707884 -216.603144) (xy 356.655922 -216.591284)
			(xy 356.606308 -216.571812) (xy 356.56015 -216.545163) (xy 356.518479 -216.511932) (xy 356.482227 -216.472861)
			(xy 356.452203 -216.428824) (xy 356.429077 -216.380803) (xy 356.413367 -216.329873) (xy 356.405424 -216.277169)
			(xy 356.176844 -216.277169) (xy 356.168901 -216.329873) (xy 356.153191 -216.380803) (xy 356.130065 -216.428824)
			(xy 356.100041 -216.472861) (xy 356.063789 -216.511932) (xy 356.022118 -216.545163) (xy 355.97596 -216.571812)
			(xy 355.926346 -216.591284) (xy 355.874384 -216.603144) (xy 355.821234 -216.607128) (xy 355.768084 -216.603144)
			(xy 355.716122 -216.591284) (xy 355.666508 -216.571812) (xy 355.62035 -216.545163) (xy 355.578679 -216.511932)
			(xy 355.542427 -216.472861) (xy 355.512403 -216.428824) (xy 355.489277 -216.380803) (xy 355.473567 -216.329873)
			(xy 355.465624 -216.277169) (xy 355.237044 -216.277169) (xy 355.229101 -216.329873) (xy 355.213391 -216.380803)
			(xy 355.190265 -216.428824) (xy 355.160241 -216.472861) (xy 355.123989 -216.511932) (xy 355.082318 -216.545163)
			(xy 355.03616 -216.571812) (xy 354.986546 -216.591284) (xy 354.934584 -216.603144) (xy 354.881434 -216.607128)
			(xy 354.828284 -216.603144) (xy 354.776322 -216.591284) (xy 354.726708 -216.571812) (xy 354.68055 -216.545163)
			(xy 354.638879 -216.511932) (xy 354.602627 -216.472861) (xy 354.572603 -216.428824) (xy 354.549477 -216.380803)
			(xy 354.533767 -216.329873) (xy 354.525824 -216.277169) (xy 354.297244 -216.277169) (xy 354.289301 -216.329873)
			(xy 354.273591 -216.380803) (xy 354.250465 -216.428824) (xy 354.220441 -216.472861) (xy 354.184189 -216.511932)
			(xy 354.142518 -216.545163) (xy 354.09636 -216.571812) (xy 354.046746 -216.591284) (xy 353.994784 -216.603144)
			(xy 353.941634 -216.607128) (xy 353.888484 -216.603144) (xy 353.836522 -216.591284) (xy 353.786908 -216.571812)
			(xy 353.74075 -216.545163) (xy 353.699079 -216.511932) (xy 353.662827 -216.472861) (xy 353.632803 -216.428824)
			(xy 353.609677 -216.380803) (xy 353.593967 -216.329873) (xy 353.586024 -216.277169) (xy 353.357444 -216.277169)
			(xy 353.349501 -216.329873) (xy 353.333791 -216.380803) (xy 353.310665 -216.428824) (xy 353.280641 -216.472861)
			(xy 353.244389 -216.511932) (xy 353.202718 -216.545163) (xy 353.15656 -216.571812) (xy 353.106946 -216.591284)
			(xy 353.054984 -216.603144) (xy 353.001834 -216.607128) (xy 352.948684 -216.603144) (xy 352.896722 -216.591284)
			(xy 352.847108 -216.571812) (xy 352.80095 -216.545163) (xy 352.759279 -216.511932) (xy 352.723027 -216.472861)
			(xy 352.693003 -216.428824) (xy 352.669877 -216.380803) (xy 352.654167 -216.329873) (xy 352.646224 -216.277169)
			(xy 352.417644 -216.277169) (xy 352.409701 -216.329873) (xy 352.393991 -216.380803) (xy 352.370865 -216.428824)
			(xy 352.340841 -216.472861) (xy 352.304589 -216.511932) (xy 352.262918 -216.545163) (xy 352.21676 -216.571812)
			(xy 352.167146 -216.591284) (xy 352.115184 -216.603144) (xy 352.062034 -216.607128) (xy 352.008884 -216.603144)
			(xy 351.956922 -216.591284) (xy 351.907308 -216.571812) (xy 351.86115 -216.545163) (xy 351.819479 -216.511932)
			(xy 351.783227 -216.472861) (xy 351.753203 -216.428824) (xy 351.730077 -216.380803) (xy 351.714367 -216.329873)
			(xy 351.706424 -216.277169) (xy 351.477844 -216.277169) (xy 351.469901 -216.329873) (xy 351.454191 -216.380803)
			(xy 351.431065 -216.428824) (xy 351.401041 -216.472861) (xy 351.364789 -216.511932) (xy 351.323118 -216.545163)
			(xy 351.27696 -216.571812) (xy 351.227346 -216.591284) (xy 351.175384 -216.603144) (xy 351.122234 -216.607128)
			(xy 351.069084 -216.603144) (xy 351.017122 -216.591284) (xy 350.967508 -216.571812) (xy 350.92135 -216.545163)
			(xy 350.879679 -216.511932) (xy 350.843427 -216.472861) (xy 350.813403 -216.428824) (xy 350.790277 -216.380803)
			(xy 350.774567 -216.329873) (xy 350.766624 -216.277169) (xy 350.538044 -216.277169) (xy 350.530101 -216.329873)
			(xy 350.514391 -216.380803) (xy 350.491265 -216.428824) (xy 350.461241 -216.472861) (xy 350.424989 -216.511932)
			(xy 350.383318 -216.545163) (xy 350.33716 -216.571812) (xy 350.287546 -216.591284) (xy 350.235584 -216.603144)
			(xy 350.182434 -216.607128) (xy 350.129284 -216.603144) (xy 350.077322 -216.591284) (xy 350.027708 -216.571812)
			(xy 349.98155 -216.545163) (xy 349.939879 -216.511932) (xy 349.903627 -216.472861) (xy 349.873603 -216.428824)
			(xy 349.850477 -216.380803) (xy 349.834767 -216.329873) (xy 349.826824 -216.277169) (xy 349.597189 -216.277169)
			(xy 349.595205 -216.303643) (xy 349.583347 -216.3556) (xy 349.563878 -216.405209) (xy 349.537233 -216.451362)
			(xy 349.504008 -216.493029) (xy 349.464944 -216.529279) (xy 349.420913 -216.559302) (xy 349.3729 -216.582428)
			(xy 349.321977 -216.59814) (xy 349.26928 -216.606087) (xy 349.242634 -216.606628) (xy 349.217874 -216.606205)
			(xy 349.168832 -216.599355) (xy 349.121209 -216.585782) (xy 349.075924 -216.565748) (xy 349.054674 -216.553034)
			(xy 349.042956 -216.546262) (xy 349.017026 -216.538539) (xy 348.989978 -216.537897) (xy 348.96371 -216.544381)
			(xy 348.940068 -216.557536) (xy 348.920711 -216.576438) (xy 348.906997 -216.599761) (xy 348.89989 -216.625866)
			(xy 348.89948 -216.639394) (xy 348.89948 -216.730072) (xy 348.928182 -216.743788) (xy 348.951881 -216.755847)
			(xy 348.995727 -216.785929) (xy 349.034616 -216.822192) (xy 349.067684 -216.863832) (xy 349.094197 -216.909923)
			(xy 349.113566 -216.959442) (xy 349.125361 -217.011291) (xy 349.129321 -217.064316) (xy 349.125357 -217.117341)
			(xy 349.113557 -217.169188) (xy 349.094183 -217.218705) (xy 349.067666 -217.264795) (xy 349.034594 -217.306431)
			(xy 348.995703 -217.342691) (xy 348.951854 -217.372769) (xy 348.928182 -217.384884) (xy 348.89948 -217.3986)
			(xy 348.89948 -217.521282) (xy 348.899934 -217.535052) (xy 348.907297 -217.561589) (xy 348.921492 -217.585189)
			(xy 348.941483 -217.604132) (xy 348.965813 -217.617035) (xy 348.992708 -217.622959) (xy 349.020207 -217.621472)
			(xy 349.046307 -217.612682) (xy 349.057976 -217.605356) (xy 349.076717 -217.593132) (xy 349.11683 -217.573309)
			(xy 349.159255 -217.559091) (xy 349.181166 -217.554556) (xy 349.204026 -217.550238) (xy 349.409004 -217.195146)
			(xy 349.40113 -217.173302) (xy 349.392481 -217.146894) (xy 349.383153 -217.092118) (xy 349.382588 -217.064336)
			(xy 349.383096 -217.038429) (xy 349.391202 -216.987252) (xy 349.407214 -216.937973) (xy 349.430737 -216.891806)
			(xy 349.461193 -216.849887) (xy 349.497831 -216.813249) (xy 349.53975 -216.782793) (xy 349.585917 -216.75927)
			(xy 349.635196 -216.743258) (xy 349.686373 -216.735152) (xy 349.738187 -216.735152) (xy 349.789364 -216.743258)
			(xy 349.838643 -216.75927) (xy 349.88481 -216.782793) (xy 349.926729 -216.813249) (xy 349.963367 -216.849887)
			(xy 349.993823 -216.891806) (xy 350.017346 -216.937973) (xy 350.033358 -216.987252) (xy 350.041464 -217.038429)
			(xy 350.041972 -217.064336) (xy 350.041512 -217.089686) (xy 350.041311 -217.090985) (xy 350.296724 -217.090985)
			(xy 350.296724 -217.037687) (xy 350.304667 -216.984983) (xy 350.320377 -216.934053) (xy 350.343503 -216.886032)
			(xy 350.373527 -216.841995) (xy 350.409779 -216.802924) (xy 350.45145 -216.769693) (xy 350.497608 -216.743044)
			(xy 350.547222 -216.723572) (xy 350.599184 -216.711712) (xy 350.652334 -216.707729) (xy 350.705484 -216.711712)
			(xy 350.757446 -216.723572) (xy 350.80706 -216.743044) (xy 350.853218 -216.769693) (xy 350.894889 -216.802924)
			(xy 350.931141 -216.841995) (xy 350.961165 -216.886032) (xy 350.984291 -216.934053) (xy 351.000001 -216.984983)
			(xy 351.007944 -217.037687) (xy 351.008442 -217.064336) (xy 351.007944 -217.090985) (xy 351.000001 -217.143689)
			(xy 350.984291 -217.194619) (xy 350.961165 -217.24264) (xy 350.931141 -217.286677) (xy 350.894889 -217.325748)
			(xy 350.853218 -217.358979) (xy 350.80706 -217.385628) (xy 350.757446 -217.4051) (xy 350.705484 -217.41696)
			(xy 350.652334 -217.420944) (xy 350.599184 -217.41696) (xy 350.547222 -217.4051) (xy 350.497608 -217.385628)
			(xy 350.45145 -217.358979) (xy 350.409779 -217.325748) (xy 350.373527 -217.286677) (xy 350.343503 -217.24264)
			(xy 350.320377 -217.194619) (xy 350.304667 -217.143689) (xy 350.296724 -217.090985) (xy 350.041311 -217.090985)
			(xy 350.033757 -217.139789) (xy 350.018421 -217.188114) (xy 349.995865 -217.233519) (xy 349.966622 -217.274935)
			(xy 349.931381 -217.311384) (xy 349.890973 -217.342006) (xy 349.846353 -217.366079) (xy 349.798573 -217.383035)
			(xy 349.773748 -217.388186) (xy 349.750888 -217.392504) (xy 349.54591 -217.747596) (xy 349.553784 -217.76944)
			(xy 349.562358 -217.79586) (xy 349.571542 -217.850635) (xy 349.572072 -217.878406) (xy 349.571564 -217.904294)
			(xy 349.563464 -217.955433) (xy 349.547465 -218.004675) (xy 349.52396 -218.050808) (xy 349.493528 -218.092697)
			(xy 349.456918 -218.129309) (xy 349.415032 -218.159745) (xy 349.368901 -218.183254) (xy 349.31966 -218.199258)
			(xy 349.268522 -218.207362) (xy 349.242634 -218.207844) (xy 349.21813 -218.207407) (xy 349.169659 -218.200177)
			(xy 349.122791 -218.185858) (xy 349.078556 -218.164764) (xy 349.057976 -218.151456) (xy 349.04632 -218.144126)
			(xy 349.020226 -218.135368) (xy 348.992741 -218.133902) (xy 348.965864 -218.139836) (xy 348.94155 -218.152738)
			(xy 348.92157 -218.171668) (xy 348.907376 -218.19525) (xy 348.900001 -218.221768) (xy 348.89948 -218.23553)
			(xy 348.89948 -218.328748) (xy 349.13062 -218.559888) (xy 349.407734 -218.559888) (xy 349.422212 -218.533472)
			(xy 349.434773 -218.511521) (xy 349.465524 -218.471373) (xy 349.502029 -218.436375) (xy 349.543438 -218.407344)
			(xy 349.588785 -218.384956) (xy 349.637012 -218.369735) (xy 349.686994 -218.362034) (xy 349.737566 -218.362034)
			(xy 349.787548 -218.369735) (xy 349.835775 -218.384956) (xy 349.881122 -218.407344) (xy 349.922531 -218.436375)
			(xy 349.959036 -218.471373) (xy 349.989787 -218.511521) (xy 350.002348 -218.533472) (xy 350.016826 -218.559888)
			(xy 350.17202 -218.559888) (xy 350.18726 -218.559389) (xy 350.216388 -218.550417) (xy 350.241571 -218.533249)
			(xy 350.260566 -218.509413) (xy 350.271681 -218.481033) (xy 350.273925 -218.450637) (xy 350.267099 -218.420932)
			(xy 350.259904 -218.407488) (xy 350.143826 -218.206574) (xy 350.120966 -218.202256) (xy 350.096166 -218.197056)
			(xy 350.048431 -218.180065) (xy 350.003858 -218.155971) (xy 349.963496 -218.12534) (xy 349.928295 -218.088895)
			(xy 349.899085 -218.047493) (xy 349.876553 -218.002109) (xy 349.86123 -217.953813) (xy 349.853477 -217.90374)
			(xy 349.852996 -217.878406) (xy 349.853504 -217.852519) (xy 349.861603 -217.801381) (xy 349.877602 -217.752141)
			(xy 349.901108 -217.706009) (xy 349.93154 -217.664122) (xy 349.96815 -217.627512) (xy 350.010037 -217.59708)
			(xy 350.056169 -217.573574) (xy 350.105409 -217.557575) (xy 350.156547 -217.549476) (xy 350.208321 -217.549476)
			(xy 350.259459 -217.557575) (xy 350.308699 -217.573574) (xy 350.354831 -217.59708) (xy 350.396718 -217.627512)
			(xy 350.433328 -217.664122) (xy 350.46376 -217.706009) (xy 350.487266 -217.752141) (xy 350.503265 -217.801381)
			(xy 350.511364 -217.852519) (xy 350.511872 -217.878406) (xy 350.792796 -217.878406) (xy 350.793288 -217.853072)
			(xy 350.801039 -217.803) (xy 350.81636 -217.754704) (xy 350.838891 -217.70932) (xy 350.868099 -217.667918)
			(xy 350.903299 -217.631473) (xy 350.94366 -217.600842) (xy 350.988233 -217.576747) (xy 351.035967 -217.559756)
			(xy 351.060766 -217.554556) (xy 351.083626 -217.550238) (xy 351.288604 -217.195146) (xy 351.28073 -217.173302)
			(xy 351.272091 -217.146892) (xy 351.262767 -217.092117) (xy 351.262188 -217.064336) (xy 351.262696 -217.038429)
			(xy 351.270802 -216.987252) (xy 351.286814 -216.937973) (xy 351.310337 -216.891806) (xy 351.340793 -216.849887)
			(xy 351.377431 -216.813249) (xy 351.41935 -216.782793) (xy 351.465517 -216.75927) (xy 351.514796 -216.743258)
			(xy 351.565973 -216.735152) (xy 351.617787 -216.735152) (xy 351.668964 -216.743258) (xy 351.718243 -216.75927)
			(xy 351.76441 -216.782793) (xy 351.806329 -216.813249) (xy 351.842967 -216.849887) (xy 351.873423 -216.891806)
			(xy 351.896946 -216.937973) (xy 351.912958 -216.987252) (xy 351.921064 -217.038429) (xy 351.921572 -217.064336)
			(xy 351.921106 -217.089682) (xy 351.920904 -217.090985) (xy 352.176324 -217.090985) (xy 352.176324 -217.037687)
			(xy 352.184267 -216.984983) (xy 352.199977 -216.934053) (xy 352.223103 -216.886032) (xy 352.253127 -216.841995)
			(xy 352.289379 -216.802924) (xy 352.33105 -216.769693) (xy 352.377208 -216.743044) (xy 352.426822 -216.723572)
			(xy 352.478784 -216.711712) (xy 352.531934 -216.707729) (xy 352.585084 -216.711712) (xy 352.637046 -216.723572)
			(xy 352.68666 -216.743044) (xy 352.732818 -216.769693) (xy 352.774489 -216.802924) (xy 352.810741 -216.841995)
			(xy 352.840765 -216.886032) (xy 352.863891 -216.934053) (xy 352.879601 -216.984983) (xy 352.887544 -217.037687)
			(xy 352.888042 -217.064336) (xy 352.887544 -217.090985) (xy 352.879601 -217.143689) (xy 352.863891 -217.194619)
			(xy 352.840765 -217.24264) (xy 352.810741 -217.286677) (xy 352.774489 -217.325748) (xy 352.732818 -217.358979)
			(xy 352.68666 -217.385628) (xy 352.637046 -217.4051) (xy 352.585084 -217.41696) (xy 352.531934 -217.420944)
			(xy 352.478784 -217.41696) (xy 352.426822 -217.4051) (xy 352.377208 -217.385628) (xy 352.33105 -217.358979)
			(xy 352.289379 -217.325748) (xy 352.253127 -217.286677) (xy 352.223103 -217.24264) (xy 352.199977 -217.194619)
			(xy 352.184267 -217.143689) (xy 352.176324 -217.090985) (xy 351.920904 -217.090985) (xy 351.913328 -217.139773)
			(xy 351.897977 -217.188085) (xy 351.875413 -217.233478) (xy 351.846169 -217.274884) (xy 351.810934 -217.311328)
			(xy 351.770536 -217.34195) (xy 351.725929 -217.36603) (xy 351.678162 -217.383) (xy 351.653348 -217.388186)
			(xy 351.630488 -217.392504) (xy 351.42551 -217.747596) (xy 351.433384 -217.76944) (xy 351.441973 -217.795856)
			(xy 351.451163 -217.850633) (xy 351.451672 -217.878406) (xy 351.451164 -217.904293) (xy 351.443065 -217.955431)
			(xy 351.427066 -218.004671) (xy 351.40356 -218.050803) (xy 351.373128 -218.09269) (xy 351.336518 -218.1293)
			(xy 351.294631 -218.159732) (xy 351.248499 -218.183238) (xy 351.199259 -218.199237) (xy 351.148121 -218.207336)
			(xy 351.096347 -218.207336) (xy 351.045209 -218.199237) (xy 350.995969 -218.183238) (xy 350.949837 -218.159732)
			(xy 350.90795 -218.1293) (xy 350.87134 -218.09269) (xy 350.840908 -218.050803) (xy 350.817402 -218.004671)
			(xy 350.801403 -217.955431) (xy 350.793304 -217.904293) (xy 350.792796 -217.878406) (xy 350.511872 -217.878406)
			(xy 350.511342 -217.906114) (xy 350.502142 -217.960759) (xy 350.493584 -217.987118) (xy 350.48571 -218.009216)
			(xy 350.690688 -218.364054) (xy 350.713548 -218.368372) (xy 350.737244 -218.373302) (xy 350.782961 -218.389187)
			(xy 350.82586 -218.411594) (xy 350.865016 -218.440041) (xy 350.899585 -218.473915) (xy 350.928821 -218.512485)
			(xy 350.940878 -218.533472) (xy 350.955356 -218.559888) (xy 351.287334 -218.559888) (xy 351.301812 -218.533472)
			(xy 351.314373 -218.511521) (xy 351.345124 -218.471373) (xy 351.381629 -218.436375) (xy 351.423038 -218.407344)
			(xy 351.468385 -218.384956) (xy 351.516612 -218.369735) (xy 351.566594 -218.362034) (xy 351.617166 -218.362034)
			(xy 351.667148 -218.369735) (xy 351.715375 -218.384956) (xy 351.760722 -218.407344) (xy 351.802131 -218.436375)
			(xy 351.838636 -218.471373) (xy 351.869387 -218.511521) (xy 351.881948 -218.533472) (xy 351.896426 -218.559888)
			(xy 352.05162 -218.559888) (xy 352.06686 -218.559389) (xy 352.095988 -218.550417) (xy 352.121171 -218.533249)
			(xy 352.140166 -218.509413) (xy 352.151281 -218.481033) (xy 352.153525 -218.450637) (xy 352.146699 -218.420932)
			(xy 352.139504 -218.407488) (xy 352.023426 -218.206574) (xy 352.000566 -218.202256) (xy 351.975766 -218.197056)
			(xy 351.928031 -218.180065) (xy 351.883458 -218.155971) (xy 351.843096 -218.12534) (xy 351.807895 -218.088895)
			(xy 351.778685 -218.047493) (xy 351.756153 -218.002109) (xy 351.74083 -217.953813) (xy 351.733077 -217.90374)
			(xy 351.732596 -217.878406) (xy 351.733104 -217.852519) (xy 351.741203 -217.801381) (xy 351.757202 -217.752141)
			(xy 351.780708 -217.706009) (xy 351.81114 -217.664122) (xy 351.84775 -217.627512) (xy 351.889637 -217.59708)
			(xy 351.935769 -217.573574) (xy 351.985009 -217.557575) (xy 352.036147 -217.549476) (xy 352.087921 -217.549476)
			(xy 352.139059 -217.557575) (xy 352.188299 -217.573574) (xy 352.234431 -217.59708) (xy 352.276318 -217.627512)
			(xy 352.312928 -217.664122) (xy 352.34336 -217.706009) (xy 352.366866 -217.752141) (xy 352.382865 -217.801381)
			(xy 352.390964 -217.852519) (xy 352.391472 -217.878406) (xy 352.672396 -217.878406) (xy 352.672888 -217.853072)
			(xy 352.680639 -217.803) (xy 352.69596 -217.754704) (xy 352.718491 -217.70932) (xy 352.747699 -217.667918)
			(xy 352.782899 -217.631473) (xy 352.82326 -217.600842) (xy 352.867833 -217.576747) (xy 352.915567 -217.559756)
			(xy 352.940366 -217.554556) (xy 352.963226 -217.550238) (xy 353.168204 -217.195146) (xy 353.16033 -217.173302)
			(xy 353.151691 -217.146892) (xy 353.142367 -217.092117) (xy 353.141788 -217.064336) (xy 353.142296 -217.038429)
			(xy 353.150402 -216.987252) (xy 353.166414 -216.937973) (xy 353.189937 -216.891806) (xy 353.220393 -216.849887)
			(xy 353.257031 -216.813249) (xy 353.29895 -216.782793) (xy 353.345117 -216.75927) (xy 353.394396 -216.743258)
			(xy 353.445573 -216.735152) (xy 353.497387 -216.735152) (xy 353.548564 -216.743258) (xy 353.597843 -216.75927)
			(xy 353.64401 -216.782793) (xy 353.685929 -216.813249) (xy 353.722567 -216.849887) (xy 353.753023 -216.891806)
			(xy 353.776546 -216.937973) (xy 353.792558 -216.987252) (xy 353.800664 -217.038429) (xy 353.801172 -217.064336)
			(xy 353.800706 -217.089682) (xy 353.800504 -217.090985) (xy 354.055924 -217.090985) (xy 354.055924 -217.037687)
			(xy 354.063867 -216.984983) (xy 354.079577 -216.934053) (xy 354.102703 -216.886032) (xy 354.132727 -216.841995)
			(xy 354.168979 -216.802924) (xy 354.21065 -216.769693) (xy 354.256808 -216.743044) (xy 354.306422 -216.723572)
			(xy 354.358384 -216.711712) (xy 354.411534 -216.707729) (xy 354.464684 -216.711712) (xy 354.516646 -216.723572)
			(xy 354.56626 -216.743044) (xy 354.612418 -216.769693) (xy 354.654089 -216.802924) (xy 354.690341 -216.841995)
			(xy 354.720365 -216.886032) (xy 354.743491 -216.934053) (xy 354.759201 -216.984983) (xy 354.767144 -217.037687)
			(xy 354.767642 -217.064336) (xy 354.767144 -217.090985) (xy 354.759201 -217.143689) (xy 354.743491 -217.194619)
			(xy 354.720365 -217.24264) (xy 354.690341 -217.286677) (xy 354.654089 -217.325748) (xy 354.612418 -217.358979)
			(xy 354.56626 -217.385628) (xy 354.516646 -217.4051) (xy 354.464684 -217.41696) (xy 354.411534 -217.420944)
			(xy 354.358384 -217.41696) (xy 354.306422 -217.4051) (xy 354.256808 -217.385628) (xy 354.21065 -217.358979)
			(xy 354.168979 -217.325748) (xy 354.132727 -217.286677) (xy 354.102703 -217.24264) (xy 354.079577 -217.194619)
			(xy 354.063867 -217.143689) (xy 354.055924 -217.090985) (xy 353.800504 -217.090985) (xy 353.792928 -217.139773)
			(xy 353.777577 -217.188085) (xy 353.755013 -217.233478) (xy 353.725769 -217.274884) (xy 353.690534 -217.311328)
			(xy 353.650136 -217.34195) (xy 353.605529 -217.36603) (xy 353.557762 -217.383) (xy 353.532948 -217.388186)
			(xy 353.510088 -217.392504) (xy 353.30511 -217.747596) (xy 353.312984 -217.76944) (xy 353.321573 -217.795856)
			(xy 353.330763 -217.850633) (xy 353.331272 -217.878406) (xy 353.612196 -217.878406) (xy 353.612704 -217.852519)
			(xy 353.620803 -217.801381) (xy 353.636802 -217.752141) (xy 353.660308 -217.706009) (xy 353.69074 -217.664122)
			(xy 353.72735 -217.627512) (xy 353.769237 -217.59708) (xy 353.815369 -217.573574) (xy 353.864609 -217.557575)
			(xy 353.915747 -217.549476) (xy 353.967521 -217.549476) (xy 354.018659 -217.557575) (xy 354.067899 -217.573574)
			(xy 354.114031 -217.59708) (xy 354.155918 -217.627512) (xy 354.192528 -217.664122) (xy 354.22296 -217.706009)
			(xy 354.246466 -217.752141) (xy 354.262465 -217.801381) (xy 354.270564 -217.852519) (xy 354.271072 -217.878406)
			(xy 354.551996 -217.878406) (xy 354.552488 -217.853072) (xy 354.560239 -217.803) (xy 354.57556 -217.754704)
			(xy 354.598091 -217.70932) (xy 354.627299 -217.667918) (xy 354.662499 -217.631473) (xy 354.70286 -217.600842)
			(xy 354.747433 -217.576747) (xy 354.795167 -217.559756) (xy 354.819966 -217.554556) (xy 354.842826 -217.550238)
			(xy 355.047804 -217.195146) (xy 355.03993 -217.173302) (xy 355.031291 -217.146892) (xy 355.021967 -217.092117)
			(xy 355.021388 -217.064336) (xy 355.021896 -217.038429) (xy 355.030002 -216.987252) (xy 355.046014 -216.937973)
			(xy 355.069537 -216.891806) (xy 355.099993 -216.849887) (xy 355.136631 -216.813249) (xy 355.17855 -216.782793)
			(xy 355.224717 -216.75927) (xy 355.273996 -216.743258) (xy 355.325173 -216.735152) (xy 355.376987 -216.735152)
			(xy 355.428164 -216.743258) (xy 355.477443 -216.75927) (xy 355.52361 -216.782793) (xy 355.565529 -216.813249)
			(xy 355.602167 -216.849887) (xy 355.632623 -216.891806) (xy 355.656146 -216.937973) (xy 355.672158 -216.987252)
			(xy 355.680264 -217.038429) (xy 355.680772 -217.064336) (xy 355.680306 -217.089682) (xy 355.680104 -217.090985)
			(xy 355.935524 -217.090985) (xy 355.935524 -217.037687) (xy 355.943467 -216.984983) (xy 355.959177 -216.934053)
			(xy 355.982303 -216.886032) (xy 356.012327 -216.841995) (xy 356.048579 -216.802924) (xy 356.09025 -216.769693)
			(xy 356.136408 -216.743044) (xy 356.186022 -216.723572) (xy 356.237984 -216.711712) (xy 356.291134 -216.707729)
			(xy 356.344284 -216.711712) (xy 356.396246 -216.723572) (xy 356.44586 -216.743044) (xy 356.492018 -216.769693)
			(xy 356.533689 -216.802924) (xy 356.569941 -216.841995) (xy 356.599965 -216.886032) (xy 356.623091 -216.934053)
			(xy 356.638801 -216.984983) (xy 356.646744 -217.037687) (xy 356.647242 -217.064336) (xy 356.646744 -217.090985)
			(xy 356.638801 -217.143689) (xy 356.623091 -217.194619) (xy 356.599965 -217.24264) (xy 356.569941 -217.286677)
			(xy 356.533689 -217.325748) (xy 356.492018 -217.358979) (xy 356.44586 -217.385628) (xy 356.396246 -217.4051)
			(xy 356.344284 -217.41696) (xy 356.291134 -217.420944) (xy 356.237984 -217.41696) (xy 356.186022 -217.4051)
			(xy 356.136408 -217.385628) (xy 356.09025 -217.358979) (xy 356.048579 -217.325748) (xy 356.012327 -217.286677)
			(xy 355.982303 -217.24264) (xy 355.959177 -217.194619) (xy 355.943467 -217.143689) (xy 355.935524 -217.090985)
			(xy 355.680104 -217.090985) (xy 355.672528 -217.139773) (xy 355.657177 -217.188085) (xy 355.634613 -217.233478)
			(xy 355.605369 -217.274884) (xy 355.570134 -217.311328) (xy 355.529736 -217.34195) (xy 355.485129 -217.36603)
			(xy 355.437362 -217.383) (xy 355.412548 -217.388186) (xy 355.389688 -217.392504) (xy 355.18471 -217.747596)
			(xy 355.192584 -217.76944) (xy 355.201173 -217.795856) (xy 355.210363 -217.850633) (xy 355.210872 -217.878406)
			(xy 355.491796 -217.878406) (xy 355.492304 -217.852519) (xy 355.500403 -217.801381) (xy 355.516402 -217.752141)
			(xy 355.539908 -217.706009) (xy 355.57034 -217.664122) (xy 355.60695 -217.627512) (xy 355.648837 -217.59708)
			(xy 355.694969 -217.573574) (xy 355.744209 -217.557575) (xy 355.795347 -217.549476) (xy 355.847121 -217.549476)
			(xy 355.898259 -217.557575) (xy 355.947499 -217.573574) (xy 355.993631 -217.59708) (xy 356.035518 -217.627512)
			(xy 356.072128 -217.664122) (xy 356.10256 -217.706009) (xy 356.126066 -217.752141) (xy 356.142065 -217.801381)
			(xy 356.150164 -217.852519) (xy 356.150672 -217.878406) (xy 356.431596 -217.878406) (xy 356.432088 -217.853072)
			(xy 356.439839 -217.803) (xy 356.45516 -217.754704) (xy 356.477691 -217.70932) (xy 356.506899 -217.667918)
			(xy 356.542099 -217.631473) (xy 356.58246 -217.600842) (xy 356.627033 -217.576747) (xy 356.674767 -217.559756)
			(xy 356.699566 -217.554556) (xy 356.722426 -217.550238) (xy 356.927404 -217.195146) (xy 356.91953 -217.173302)
			(xy 356.910891 -217.146892) (xy 356.901567 -217.092117) (xy 356.900988 -217.064336) (xy 356.901496 -217.038429)
			(xy 356.909602 -216.987252) (xy 356.925614 -216.937973) (xy 356.949137 -216.891806) (xy 356.979593 -216.849887)
			(xy 357.016231 -216.813249) (xy 357.05815 -216.782793) (xy 357.104317 -216.75927) (xy 357.153596 -216.743258)
			(xy 357.204773 -216.735152) (xy 357.256587 -216.735152) (xy 357.307764 -216.743258) (xy 357.357043 -216.75927)
			(xy 357.40321 -216.782793) (xy 357.445129 -216.813249) (xy 357.481767 -216.849887) (xy 357.512223 -216.891806)
			(xy 357.535746 -216.937973) (xy 357.551758 -216.987252) (xy 357.559864 -217.038429) (xy 357.560372 -217.064336)
			(xy 357.559906 -217.089682) (xy 357.559704 -217.090985) (xy 357.815124 -217.090985) (xy 357.815124 -217.037687)
			(xy 357.823067 -216.984983) (xy 357.838777 -216.934053) (xy 357.861903 -216.886032) (xy 357.891927 -216.841995)
			(xy 357.928179 -216.802924) (xy 357.96985 -216.769693) (xy 358.016008 -216.743044) (xy 358.065622 -216.723572)
			(xy 358.117584 -216.711712) (xy 358.170734 -216.707729) (xy 358.223884 -216.711712) (xy 358.275846 -216.723572)
			(xy 358.32546 -216.743044) (xy 358.371618 -216.769693) (xy 358.413289 -216.802924) (xy 358.449541 -216.841995)
			(xy 358.479565 -216.886032) (xy 358.502691 -216.934053) (xy 358.518401 -216.984983) (xy 358.526344 -217.037687)
			(xy 358.526842 -217.064336) (xy 358.526344 -217.090985) (xy 358.518401 -217.143689) (xy 358.502691 -217.194619)
			(xy 358.479565 -217.24264) (xy 358.449541 -217.286677) (xy 358.413289 -217.325748) (xy 358.371618 -217.358979)
			(xy 358.32546 -217.385628) (xy 358.275846 -217.4051) (xy 358.223884 -217.41696) (xy 358.170734 -217.420944)
			(xy 358.117584 -217.41696) (xy 358.065622 -217.4051) (xy 358.016008 -217.385628) (xy 357.96985 -217.358979)
			(xy 357.928179 -217.325748) (xy 357.891927 -217.286677) (xy 357.861903 -217.24264) (xy 357.838777 -217.194619)
			(xy 357.823067 -217.143689) (xy 357.815124 -217.090985) (xy 357.559704 -217.090985) (xy 357.552128 -217.139773)
			(xy 357.536777 -217.188085) (xy 357.514213 -217.233478) (xy 357.484969 -217.274884) (xy 357.449734 -217.311328)
			(xy 357.409336 -217.34195) (xy 357.364729 -217.36603) (xy 357.316962 -217.383) (xy 357.292148 -217.388186)
			(xy 357.269288 -217.392504) (xy 357.06431 -217.747596) (xy 357.072184 -217.76944) (xy 357.080773 -217.795856)
			(xy 357.089963 -217.850633) (xy 357.090472 -217.878406) (xy 357.371396 -217.878406) (xy 357.371904 -217.852519)
			(xy 357.380003 -217.801381) (xy 357.396002 -217.752141) (xy 357.419508 -217.706009) (xy 357.44994 -217.664122)
			(xy 357.48655 -217.627512) (xy 357.528437 -217.59708) (xy 357.574569 -217.573574) (xy 357.623809 -217.557575)
			(xy 357.674947 -217.549476) (xy 357.726721 -217.549476) (xy 357.777859 -217.557575) (xy 357.827099 -217.573574)
			(xy 357.873231 -217.59708) (xy 357.915118 -217.627512) (xy 357.951728 -217.664122) (xy 357.98216 -217.706009)
			(xy 358.005666 -217.752141) (xy 358.021665 -217.801381) (xy 358.029764 -217.852519) (xy 358.030272 -217.878406)
			(xy 358.311196 -217.878406) (xy 358.311688 -217.853072) (xy 358.319439 -217.803) (xy 358.33476 -217.754704)
			(xy 358.357291 -217.70932) (xy 358.386499 -217.667918) (xy 358.421699 -217.631473) (xy 358.46206 -217.600842)
			(xy 358.506633 -217.576747) (xy 358.554367 -217.559756) (xy 358.579166 -217.554556) (xy 358.602026 -217.550238)
			(xy 358.807004 -217.194892) (xy 358.799384 -217.173048) (xy 358.790811 -217.146694) (xy 358.78162 -217.092045)
			(xy 358.781096 -217.064336) (xy 358.781604 -217.038449) (xy 358.789703 -216.987311) (xy 358.805702 -216.938071)
			(xy 358.829208 -216.891939) (xy 358.85964 -216.850052) (xy 358.89625 -216.813442) (xy 358.938137 -216.78301)
			(xy 358.984269 -216.759504) (xy 359.033509 -216.743505) (xy 359.084647 -216.735406) (xy 359.136421 -216.735406)
			(xy 359.187559 -216.743505) (xy 359.236799 -216.759504) (xy 359.282931 -216.78301) (xy 359.324818 -216.813442)
			(xy 359.361428 -216.850052) (xy 359.39186 -216.891939) (xy 359.415366 -216.938071) (xy 359.431365 -216.987311)
			(xy 359.439464 -217.038449) (xy 359.439972 -217.064336) (xy 359.439506 -217.089682) (xy 359.439304 -217.090985)
			(xy 359.694724 -217.090985) (xy 359.694724 -217.037687) (xy 359.702667 -216.984983) (xy 359.718377 -216.934053)
			(xy 359.741503 -216.886032) (xy 359.771527 -216.841995) (xy 359.807779 -216.802924) (xy 359.84945 -216.769693)
			(xy 359.895608 -216.743044) (xy 359.945222 -216.723572) (xy 359.997184 -216.711712) (xy 360.050334 -216.707729)
			(xy 360.103484 -216.711712) (xy 360.155446 -216.723572) (xy 360.20506 -216.743044) (xy 360.251218 -216.769693)
			(xy 360.292889 -216.802924) (xy 360.329141 -216.841995) (xy 360.359165 -216.886032) (xy 360.382291 -216.934053)
			(xy 360.398001 -216.984983) (xy 360.405944 -217.037687) (xy 360.406442 -217.064336) (xy 360.660188 -217.064336)
			(xy 360.660696 -217.038429) (xy 360.668802 -216.987252) (xy 360.684814 -216.937973) (xy 360.708337 -216.891806)
			(xy 360.738793 -216.849887) (xy 360.775431 -216.813249) (xy 360.81735 -216.782793) (xy 360.863517 -216.75927)
			(xy 360.912796 -216.743258) (xy 360.963973 -216.735152) (xy 361.015787 -216.735152) (xy 361.066964 -216.743258)
			(xy 361.116243 -216.75927) (xy 361.16241 -216.782793) (xy 361.204329 -216.813249) (xy 361.240967 -216.849887)
			(xy 361.271423 -216.891806) (xy 361.294946 -216.937973) (xy 361.310958 -216.987252) (xy 361.319064 -217.038429)
			(xy 361.319572 -217.064336) (xy 361.318981 -217.090985) (xy 361.574324 -217.090985) (xy 361.574324 -217.037687)
			(xy 361.582267 -216.984983) (xy 361.597977 -216.934053) (xy 361.621103 -216.886032) (xy 361.651127 -216.841995)
			(xy 361.687379 -216.802924) (xy 361.72905 -216.769693) (xy 361.775208 -216.743044) (xy 361.824822 -216.723572)
			(xy 361.876784 -216.711712) (xy 361.929934 -216.707729) (xy 361.983084 -216.711712) (xy 362.035046 -216.723572)
			(xy 362.08466 -216.743044) (xy 362.130818 -216.769693) (xy 362.172489 -216.802924) (xy 362.208741 -216.841995)
			(xy 362.238765 -216.886032) (xy 362.261891 -216.934053) (xy 362.277601 -216.984983) (xy 362.285544 -217.037687)
			(xy 362.286042 -217.064336) (xy 362.285544 -217.090985) (xy 362.277601 -217.143689) (xy 362.261891 -217.194619)
			(xy 362.238765 -217.24264) (xy 362.208741 -217.286677) (xy 362.172489 -217.325748) (xy 362.130818 -217.358979)
			(xy 362.08466 -217.385628) (xy 362.035046 -217.4051) (xy 361.983084 -217.41696) (xy 361.929934 -217.420944)
			(xy 361.876784 -217.41696) (xy 361.824822 -217.4051) (xy 361.775208 -217.385628) (xy 361.72905 -217.358979)
			(xy 361.687379 -217.325748) (xy 361.651127 -217.286677) (xy 361.621103 -217.24264) (xy 361.597977 -217.194619)
			(xy 361.582267 -217.143689) (xy 361.574324 -217.090985) (xy 361.318981 -217.090985) (xy 361.318959 -217.091989)
			(xy 361.309638 -217.146507) (xy 361.30103 -217.172794) (xy 361.29341 -217.194892) (xy 361.498642 -217.550238)
			(xy 361.521502 -217.554556) (xy 361.546303 -217.559751) (xy 361.594042 -217.57674) (xy 361.638619 -217.600833)
			(xy 361.678984 -217.631463) (xy 361.714188 -217.667908) (xy 361.7434 -217.709312) (xy 361.765933 -217.754697)
			(xy 361.781256 -217.802996) (xy 361.789008 -217.85307) (xy 361.789472 -217.878406) (xy 361.788964 -217.904293)
			(xy 361.780865 -217.955431) (xy 361.764866 -218.004671) (xy 361.74136 -218.050803) (xy 361.710928 -218.09269)
			(xy 361.674318 -218.1293) (xy 361.632431 -218.159732) (xy 361.586299 -218.183238) (xy 361.537059 -218.199237)
			(xy 361.485921 -218.207336) (xy 361.434147 -218.207336) (xy 361.383009 -218.199237) (xy 361.333769 -218.183238)
			(xy 361.287637 -218.159732) (xy 361.24575 -218.1293) (xy 361.20914 -218.09269) (xy 361.178708 -218.050803)
			(xy 361.155202 -218.004671) (xy 361.139203 -217.955431) (xy 361.131104 -217.904293) (xy 361.130596 -217.878406)
			(xy 361.131127 -217.850698) (xy 361.140321 -217.796051) (xy 361.148884 -217.769694) (xy 361.156758 -217.747596)
			(xy 360.95178 -217.392504) (xy 360.92892 -217.388186) (xy 360.904075 -217.38302) (xy 360.856226 -217.366126)
			(xy 360.811533 -217.342096) (xy 360.771053 -217.311499) (xy 360.735741 -217.275058) (xy 360.706433 -217.233634)
			(xy 360.683822 -217.188207) (xy 360.668443 -217.13985) (xy 360.660658 -217.089708) (xy 360.660188 -217.064336)
			(xy 360.406442 -217.064336) (xy 360.405944 -217.090985) (xy 360.398001 -217.143689) (xy 360.382291 -217.194619)
			(xy 360.359165 -217.24264) (xy 360.329141 -217.286677) (xy 360.292889 -217.325748) (xy 360.251218 -217.358979)
			(xy 360.20506 -217.385628) (xy 360.155446 -217.4051) (xy 360.103484 -217.41696) (xy 360.050334 -217.420944)
			(xy 359.997184 -217.41696) (xy 359.945222 -217.4051) (xy 359.895608 -217.385628) (xy 359.84945 -217.358979)
			(xy 359.807779 -217.325748) (xy 359.771527 -217.286677) (xy 359.741503 -217.24264) (xy 359.718377 -217.194619)
			(xy 359.702667 -217.143689) (xy 359.694724 -217.090985) (xy 359.439304 -217.090985) (xy 359.431728 -217.139773)
			(xy 359.416377 -217.188085) (xy 359.393813 -217.233478) (xy 359.364569 -217.274884) (xy 359.329334 -217.311328)
			(xy 359.288936 -217.34195) (xy 359.244329 -217.36603) (xy 359.196562 -217.383) (xy 359.171748 -217.388186)
			(xy 359.148888 -217.392504) (xy 358.94391 -217.747596) (xy 358.951784 -217.76944) (xy 358.960373 -217.795856)
			(xy 358.969563 -217.850633) (xy 358.970072 -217.878406) (xy 358.969564 -217.904293) (xy 358.969443 -217.905055)
			(xy 359.224824 -217.905055) (xy 359.224824 -217.851757) (xy 359.232767 -217.799053) (xy 359.248477 -217.748123)
			(xy 359.271603 -217.700102) (xy 359.301627 -217.656065) (xy 359.337879 -217.616994) (xy 359.37955 -217.583763)
			(xy 359.425708 -217.557114) (xy 359.475322 -217.537642) (xy 359.527284 -217.525782) (xy 359.580434 -217.521799)
			(xy 359.633584 -217.525782) (xy 359.685546 -217.537642) (xy 359.73516 -217.557114) (xy 359.781318 -217.583763)
			(xy 359.822989 -217.616994) (xy 359.859241 -217.656065) (xy 359.889265 -217.700102) (xy 359.912391 -217.748123)
			(xy 359.928101 -217.799053) (xy 359.936044 -217.851757) (xy 359.936542 -217.878406) (xy 359.936044 -217.905055)
			(xy 359.928101 -217.957759) (xy 359.912391 -218.008689) (xy 359.889265 -218.05671) (xy 359.859241 -218.100747)
			(xy 359.822989 -218.139818) (xy 359.781318 -218.173049) (xy 359.73516 -218.199698) (xy 359.685546 -218.21917)
			(xy 359.633584 -218.23103) (xy 359.580434 -218.235014) (xy 359.527284 -218.23103) (xy 359.475322 -218.21917)
			(xy 359.425708 -218.199698) (xy 359.37955 -218.173049) (xy 359.337879 -218.139818) (xy 359.301627 -218.100747)
			(xy 359.271603 -218.05671) (xy 359.248477 -218.008689) (xy 359.232767 -217.957759) (xy 359.224824 -217.905055)
			(xy 358.969443 -217.905055) (xy 358.961465 -217.955431) (xy 358.945466 -218.004671) (xy 358.92196 -218.050803)
			(xy 358.891528 -218.09269) (xy 358.854918 -218.1293) (xy 358.813031 -218.159732) (xy 358.766899 -218.183238)
			(xy 358.717659 -218.199237) (xy 358.666521 -218.207336) (xy 358.614747 -218.207336) (xy 358.563609 -218.199237)
			(xy 358.514369 -218.183238) (xy 358.468237 -218.159732) (xy 358.42635 -218.1293) (xy 358.38974 -218.09269)
			(xy 358.359308 -218.050803) (xy 358.335802 -218.004671) (xy 358.319803 -217.955431) (xy 358.311704 -217.904293)
			(xy 358.311196 -217.878406) (xy 358.030272 -217.878406) (xy 358.029741 -217.906114) (xy 358.020546 -217.960761)
			(xy 358.011984 -217.987118) (xy 358.004364 -218.008962) (xy 358.209342 -218.364054) (xy 358.232202 -218.368372)
			(xy 358.257007 -218.373552) (xy 358.304747 -218.390542) (xy 358.349324 -218.414636) (xy 358.38969 -218.445268)
			(xy 358.424894 -218.481716) (xy 358.454106 -218.523121) (xy 358.476638 -218.568508) (xy 358.491959 -218.616809)
			(xy 358.49971 -218.666886) (xy 358.500172 -218.692222) (xy 358.499664 -218.718109) (xy 358.499543 -218.718871)
			(xy 358.755178 -218.718871) (xy 358.755178 -218.665573) (xy 358.763121 -218.612869) (xy 358.778831 -218.561939)
			(xy 358.801957 -218.513918) (xy 358.831981 -218.469881) (xy 358.868233 -218.43081) (xy 358.909904 -218.397579)
			(xy 358.956062 -218.37093) (xy 359.005676 -218.351458) (xy 359.057638 -218.339598) (xy 359.110788 -218.335615)
			(xy 359.163938 -218.339598) (xy 359.2159 -218.351458) (xy 359.265514 -218.37093) (xy 359.311672 -218.397579)
			(xy 359.353343 -218.43081) (xy 359.389595 -218.469881) (xy 359.419619 -218.513918) (xy 359.442745 -218.561939)
			(xy 359.458455 -218.612869) (xy 359.466398 -218.665573) (xy 359.466896 -218.692222) (xy 359.466398 -218.718871)
			(xy 359.458455 -218.771575) (xy 359.442745 -218.822505) (xy 359.419619 -218.870526) (xy 359.389595 -218.914563)
			(xy 359.353343 -218.953634) (xy 359.311672 -218.986865) (xy 359.265514 -219.013514) (xy 359.2159 -219.032986)
			(xy 359.163938 -219.044846) (xy 359.110788 -219.04883) (xy 359.057638 -219.044846) (xy 359.005676 -219.032986)
			(xy 358.956062 -219.013514) (xy 358.909904 -218.986865) (xy 358.868233 -218.953634) (xy 358.831981 -218.914563)
			(xy 358.801957 -218.870526) (xy 358.778831 -218.822505) (xy 358.763121 -218.771575) (xy 358.755178 -218.718871)
			(xy 358.499543 -218.718871) (xy 358.491565 -218.769247) (xy 358.475566 -218.818487) (xy 358.45206 -218.864619)
			(xy 358.421628 -218.906506) (xy 358.385018 -218.943116) (xy 358.343131 -218.973548) (xy 358.296999 -218.997054)
			(xy 358.247759 -219.013053) (xy 358.196621 -219.021152) (xy 358.144847 -219.021152) (xy 358.093709 -219.013053)
			(xy 358.044469 -218.997054) (xy 357.998337 -218.973548) (xy 357.95645 -218.943116) (xy 357.91984 -218.906506)
			(xy 357.889408 -218.864619) (xy 357.865902 -218.818487) (xy 357.849903 -218.769247) (xy 357.841804 -218.718109)
			(xy 357.841296 -218.692222) (xy 357.841831 -218.664514) (xy 357.851023 -218.609867) (xy 357.859584 -218.58351)
			(xy 357.867458 -218.561412) (xy 357.66248 -218.206574) (xy 357.63962 -218.202256) (xy 357.614783 -218.197156)
			(xy 357.567001 -218.180194) (xy 357.52238 -218.156114) (xy 357.481972 -218.125486) (xy 357.446732 -218.08903)
			(xy 357.417491 -218.047608) (xy 357.394937 -218.002196) (xy 357.379605 -217.953866) (xy 357.371854 -217.903758)
			(xy 357.371396 -217.878406) (xy 357.090472 -217.878406) (xy 357.089964 -217.904293) (xy 357.081865 -217.955431)
			(xy 357.065866 -218.004671) (xy 357.04236 -218.050803) (xy 357.011928 -218.09269) (xy 356.975318 -218.1293)
			(xy 356.933431 -218.159732) (xy 356.887299 -218.183238) (xy 356.838059 -218.199237) (xy 356.786921 -218.207336)
			(xy 356.735147 -218.207336) (xy 356.684009 -218.199237) (xy 356.634769 -218.183238) (xy 356.588637 -218.159732)
			(xy 356.54675 -218.1293) (xy 356.51014 -218.09269) (xy 356.479708 -218.050803) (xy 356.456202 -218.004671)
			(xy 356.440203 -217.955431) (xy 356.432104 -217.904293) (xy 356.431596 -217.878406) (xy 356.150672 -217.878406)
			(xy 356.150141 -217.906114) (xy 356.140946 -217.960761) (xy 356.132384 -217.987118) (xy 356.12451 -218.009216)
			(xy 356.329488 -218.364054) (xy 356.352348 -218.368372) (xy 356.377163 -218.373563) (xy 356.424941 -218.390515)
			(xy 356.469559 -218.414584) (xy 356.509965 -218.445202) (xy 356.545206 -218.481645) (xy 356.57445 -218.523056)
			(xy 356.597009 -218.568456) (xy 356.612349 -218.616776) (xy 356.620108 -218.666874) (xy 356.620572 -218.692222)
			(xy 356.620064 -218.718129) (xy 356.611958 -218.769306) (xy 356.595946 -218.818585) (xy 356.572423 -218.864752)
			(xy 356.541967 -218.906671) (xy 356.505329 -218.943309) (xy 356.46341 -218.973765) (xy 356.417243 -218.997288)
			(xy 356.367964 -219.0133) (xy 356.316787 -219.021406) (xy 356.264973 -219.021406) (xy 356.213796 -219.0133)
			(xy 356.164517 -218.997288) (xy 356.11835 -218.973765) (xy 356.076431 -218.943309) (xy 356.039793 -218.906671)
			(xy 356.009337 -218.864752) (xy 355.985814 -218.818585) (xy 355.969802 -218.769306) (xy 355.961696 -218.718129)
			(xy 355.961188 -218.692222) (xy 355.961788 -218.664505) (xy 355.971107 -218.609859) (xy 355.97973 -218.58351)
			(xy 355.987604 -218.561412) (xy 355.782626 -218.206574) (xy 355.759766 -218.202256) (xy 355.734962 -218.197073)
			(xy 355.687224 -218.180081) (xy 355.642649 -218.155985) (xy 355.602284 -218.125353) (xy 355.567082 -218.088906)
			(xy 355.53787 -218.047502) (xy 355.515337 -218.002116) (xy 355.500013 -217.953817) (xy 355.49226 -217.903742)
			(xy 355.491796 -217.878406) (xy 355.210872 -217.878406) (xy 355.210364 -217.904293) (xy 355.202265 -217.955431)
			(xy 355.186266 -218.004671) (xy 355.16276 -218.050803) (xy 355.132328 -218.09269) (xy 355.095718 -218.1293)
			(xy 355.053831 -218.159732) (xy 355.007699 -218.183238) (xy 354.958459 -218.199237) (xy 354.907321 -218.207336)
			(xy 354.855547 -218.207336) (xy 354.804409 -218.199237) (xy 354.755169 -218.183238) (xy 354.709037 -218.159732)
			(xy 354.66715 -218.1293) (xy 354.63054 -218.09269) (xy 354.600108 -218.050803) (xy 354.576602 -218.004671)
			(xy 354.560603 -217.955431) (xy 354.552504 -217.904293) (xy 354.551996 -217.878406) (xy 354.271072 -217.878406)
			(xy 354.270541 -217.906114) (xy 354.261346 -217.960761) (xy 354.252784 -217.987118) (xy 354.24491 -218.009216)
			(xy 354.449888 -218.364054) (xy 354.472748 -218.368372) (xy 354.497563 -218.373563) (xy 354.545341 -218.390515)
			(xy 354.589959 -218.414584) (xy 354.630365 -218.445202) (xy 354.665606 -218.481645) (xy 354.69485 -218.523056)
			(xy 354.717409 -218.568456) (xy 354.732749 -218.616776) (xy 354.740508 -218.666874) (xy 354.740972 -218.692222)
			(xy 354.740464 -218.718129) (xy 354.732358 -218.769306) (xy 354.716346 -218.818585) (xy 354.692823 -218.864752)
			(xy 354.662367 -218.906671) (xy 354.625729 -218.943309) (xy 354.58381 -218.973765) (xy 354.537643 -218.997288)
			(xy 354.488364 -219.0133) (xy 354.437187 -219.021406) (xy 354.385373 -219.021406) (xy 354.334196 -219.0133)
			(xy 354.284917 -218.997288) (xy 354.23875 -218.973765) (xy 354.196831 -218.943309) (xy 354.160193 -218.906671)
			(xy 354.129737 -218.864752) (xy 354.106214 -218.818585) (xy 354.090202 -218.769306) (xy 354.082096 -218.718129)
			(xy 354.081588 -218.692222) (xy 354.082188 -218.664505) (xy 354.091507 -218.609859) (xy 354.10013 -218.58351)
			(xy 354.108004 -218.561412) (xy 353.903026 -218.206574) (xy 353.880166 -218.202256) (xy 353.855362 -218.197073)
			(xy 353.807624 -218.180081) (xy 353.763049 -218.155985) (xy 353.722684 -218.125353) (xy 353.687482 -218.088906)
			(xy 353.65827 -218.047502) (xy 353.635737 -218.002116) (xy 353.620413 -217.953817) (xy 353.61266 -217.903742)
			(xy 353.612196 -217.878406) (xy 353.331272 -217.878406) (xy 353.330764 -217.904293) (xy 353.322665 -217.955431)
			(xy 353.306666 -218.004671) (xy 353.28316 -218.050803) (xy 353.252728 -218.09269) (xy 353.216118 -218.1293)
			(xy 353.174231 -218.159732) (xy 353.128099 -218.183238) (xy 353.078859 -218.199237) (xy 353.027721 -218.207336)
			(xy 352.975947 -218.207336) (xy 352.924809 -218.199237) (xy 352.875569 -218.183238) (xy 352.829437 -218.159732)
			(xy 352.78755 -218.1293) (xy 352.75094 -218.09269) (xy 352.720508 -218.050803) (xy 352.697002 -218.004671)
			(xy 352.681003 -217.955431) (xy 352.672904 -217.904293) (xy 352.672396 -217.878406) (xy 352.391472 -217.878406)
			(xy 352.390942 -217.906114) (xy 352.381742 -217.960759) (xy 352.373184 -217.987118) (xy 352.36531 -218.009216)
			(xy 352.570288 -218.364054) (xy 352.593148 -218.368372) (xy 352.61796 -218.373559) (xy 352.665723 -218.39053)
			(xy 352.710326 -218.414611) (xy 352.750718 -218.445234) (xy 352.785948 -218.481679) (xy 352.815185 -218.523085)
			(xy 352.837741 -218.568478) (xy 352.853084 -218.616789) (xy 352.860853 -218.666878) (xy 352.861372 -218.692222)
			(xy 352.861241 -218.702603) (xy 352.859841 -218.723319) (xy 352.858578 -218.733624) (xy 352.85553 -218.758262)
			(xy 353.457764 -219.360496) (xy 353.589082 -219.360496) (xy 353.600279 -219.33469) (xy 353.629148 -219.286411)
			(xy 353.664796 -219.242896) (xy 353.706447 -219.205089) (xy 353.753201 -219.173809) (xy 353.804041 -219.149736)
			(xy 353.857866 -219.133391) (xy 353.913508 -219.125129) (xy 353.96976 -219.125129) (xy 354.025402 -219.133391)
			(xy 354.079227 -219.149736) (xy 354.130067 -219.173809) (xy 354.176821 -219.205089) (xy 354.218472 -219.242896)
			(xy 354.25412 -219.286411) (xy 354.282989 -219.33469) (xy 354.294186 -219.360496) (xy 354.528882 -219.360496)
			(xy 354.540065 -219.334677) (xy 354.568913 -219.286372) (xy 354.60455 -219.242832) (xy 354.646199 -219.205004)
			(xy 354.692957 -219.17371) (xy 354.743808 -219.149629) (xy 354.797646 -219.133286) (xy 354.853302 -219.125034)
			(xy 354.881434 -219.12453) (xy 354.908982 -219.125016) (xy 354.963504 -219.132945) (xy 355.01632 -219.148634)
			(xy 355.066329 -219.171755) (xy 355.112494 -219.201828) (xy 355.153853 -219.238229) (xy 355.189547 -219.280199)
			(xy 355.218833 -219.326867) (xy 355.23043 -219.35186) (xy 355.243892 -219.382086) (xy 355.458776 -219.382086)
		)
		(stroke
			(width 0)
			(type solid)
		)
		(fill yes)
		(layer "B.Cu")
		(net "PVCCD_HV_CPU0")
	)
	(gr_poly
		(pts
			(xy 107.532424 -219.352114) (xy 107.544 -219.327109) (xy 107.573285 -219.280435) (xy 107.608979 -219.238459)
			(xy 107.65034 -219.202054) (xy 107.696508 -219.171977) (xy 107.746522 -219.148855) (xy 107.799342 -219.133167)
			(xy 107.85387 -219.125241) (xy 107.90897 -219.125241) (xy 107.963498 -219.133167) (xy 108.016318 -219.148855)
			(xy 108.066332 -219.171977) (xy 108.1125 -219.202054) (xy 108.153861 -219.238459) (xy 108.189555 -219.280435)
			(xy 108.21884 -219.327109) (xy 108.230416 -219.352114) (xy 108.243878 -219.38234) (xy 108.458762 -219.38234)
			(xy 108.472224 -219.352114) (xy 108.4838 -219.327109) (xy 108.513085 -219.280435) (xy 108.548779 -219.238459)
			(xy 108.59014 -219.202054) (xy 108.636308 -219.171977) (xy 108.686322 -219.148855) (xy 108.739142 -219.133167)
			(xy 108.79367 -219.125241) (xy 108.84877 -219.125241) (xy 108.903298 -219.133167) (xy 108.956118 -219.148855)
			(xy 109.006132 -219.171977) (xy 109.0523 -219.202054) (xy 109.093661 -219.238459) (xy 109.129355 -219.280435)
			(xy 109.15864 -219.327109) (xy 109.170216 -219.352114) (xy 109.183678 -219.38234) (xy 109.398562 -219.38234)
			(xy 109.412024 -219.352114) (xy 109.4236 -219.327109) (xy 109.452885 -219.280435) (xy 109.488579 -219.238459)
			(xy 109.52994 -219.202054) (xy 109.576108 -219.171977) (xy 109.626122 -219.148855) (xy 109.678942 -219.133167)
			(xy 109.73347 -219.125241) (xy 109.78857 -219.125241) (xy 109.843098 -219.133167) (xy 109.895918 -219.148855)
			(xy 109.945932 -219.171977) (xy 109.9921 -219.202054) (xy 110.033461 -219.238459) (xy 110.069155 -219.280435)
			(xy 110.09844 -219.327109) (xy 110.110016 -219.352114) (xy 110.123478 -219.38234) (xy 110.338362 -219.38234)
			(xy 110.351824 -219.352114) (xy 110.3634 -219.327109) (xy 110.392685 -219.280435) (xy 110.428379 -219.238459)
			(xy 110.46974 -219.202054) (xy 110.515908 -219.171977) (xy 110.565922 -219.148855) (xy 110.618742 -219.133167)
			(xy 110.67327 -219.125241) (xy 110.72837 -219.125241) (xy 110.782898 -219.133167) (xy 110.835718 -219.148855)
			(xy 110.885732 -219.171977) (xy 110.9319 -219.202054) (xy 110.973261 -219.238459) (xy 111.008955 -219.280435)
			(xy 111.03824 -219.327109) (xy 111.049816 -219.352114) (xy 111.063278 -219.38234) (xy 111.277908 -219.38234)
			(xy 111.29137 -219.352114) (xy 111.303622 -219.325711) (xy 111.334942 -219.276653) (xy 111.373357 -219.232926)
			(xy 111.417972 -219.195547) (xy 111.467752 -219.165386) (xy 111.521538 -219.143144) (xy 111.578081 -219.129337)
			(xy 111.636065 -219.124286) (xy 111.694143 -219.12811) (xy 111.722662 -219.133928) (xy 111.74984 -219.140024)
			(xy 111.82604 -219.063824) (xy 111.956342 -219.063824) (xy 111.956342 -218.985084) (xy 111.932974 -218.970098)
			(xy 111.910008 -218.954818) (xy 111.869056 -218.917868) (xy 111.834825 -218.874617) (xy 111.80827 -218.826273)
			(xy 111.790131 -218.774183) (xy 111.780915 -218.7198) (xy 111.78032 -218.692222) (xy 111.780784 -218.666874)
			(xy 111.788543 -218.616775) (xy 111.803883 -218.568455) (xy 111.826441 -218.523054) (xy 111.855686 -218.481643)
			(xy 111.890926 -218.445199) (xy 111.931332 -218.414581) (xy 111.97595 -218.390511) (xy 112.023727 -218.373557)
			(xy 112.048544 -218.368372) (xy 112.071404 -218.364054) (xy 112.276636 -218.008708) (xy 112.268762 -217.98661)
			(xy 112.2603 -217.960365) (xy 112.251238 -217.905976) (xy 112.250728 -217.878406) (xy 112.251236 -217.852519)
			(xy 112.259335 -217.801381) (xy 112.275334 -217.752141) (xy 112.29884 -217.706009) (xy 112.329272 -217.664122)
			(xy 112.365882 -217.627512) (xy 112.407769 -217.59708) (xy 112.453901 -217.573574) (xy 112.503141 -217.557575)
			(xy 112.554279 -217.549476) (xy 112.606053 -217.549476) (xy 112.657191 -217.557575) (xy 112.706431 -217.573574)
			(xy 112.752563 -217.59708) (xy 112.79445 -217.627512) (xy 112.83106 -217.664122) (xy 112.861492 -217.706009)
			(xy 112.884998 -217.752141) (xy 112.900997 -217.801381) (xy 112.909096 -217.852519) (xy 112.909604 -217.878406)
			(xy 112.909136 -217.903779) (xy 112.901355 -217.953924) (xy 112.885978 -218.002284) (xy 112.863369 -218.047715)
			(xy 112.834062 -218.089142) (xy 112.79875 -218.125586) (xy 112.758268 -218.156186) (xy 112.713573 -218.180218)
			(xy 112.665723 -218.197113) (xy 112.640872 -218.202256) (xy 112.618012 -218.206574) (xy 112.413288 -218.561412)
			(xy 112.421162 -218.583256) (xy 112.429807 -218.609665) (xy 112.439125 -218.66444) (xy 112.439704 -218.692222)
			(xy 112.439282 -218.71606) (xy 112.432389 -218.763235) (xy 112.425988 -218.786202) (xy 112.422549 -218.799271)
			(xy 112.421928 -218.82628) (xy 112.428414 -218.852505) (xy 112.441552 -218.876111) (xy 112.460422 -218.895444)
			(xy 112.483702 -218.909151) (xy 112.509763 -218.916271) (xy 112.52327 -218.916758) (xy 113.576608 -218.916758)
			(xy 113.59013 -218.916346) (xy 113.616228 -218.909259) (xy 113.639544 -218.895558) (xy 113.658437 -218.876208)
			(xy 113.671577 -218.852571) (xy 113.678039 -218.826311) (xy 113.677368 -218.799276) (xy 113.67389 -218.786202)
			(xy 113.667551 -218.763228) (xy 113.660794 -218.716052) (xy 113.660428 -218.692222) (xy 113.66089 -218.666886)
			(xy 113.668641 -218.616809) (xy 113.683962 -218.568508) (xy 113.706494 -218.523121) (xy 113.735706 -218.481716)
			(xy 113.77091 -218.445268) (xy 113.811276 -218.414636) (xy 113.855853 -218.390542) (xy 113.903593 -218.373552)
			(xy 113.928398 -218.368372) (xy 113.951258 -218.364054) (xy 114.156236 -218.008962) (xy 114.148616 -217.986864)
			(xy 114.140072 -217.960568) (xy 114.130884 -217.90605) (xy 114.130328 -217.878406) (xy 114.130836 -217.852519)
			(xy 114.138935 -217.801381) (xy 114.154934 -217.752141) (xy 114.17844 -217.706009) (xy 114.208872 -217.664122)
			(xy 114.245482 -217.627512) (xy 114.287369 -217.59708) (xy 114.333501 -217.573574) (xy 114.382741 -217.557575)
			(xy 114.433879 -217.549476) (xy 114.485653 -217.549476) (xy 114.536791 -217.557575) (xy 114.586031 -217.573574)
			(xy 114.632163 -217.59708) (xy 114.67405 -217.627512) (xy 114.71066 -217.664122) (xy 114.741092 -217.706009)
			(xy 114.764598 -217.752141) (xy 114.780597 -217.801381) (xy 114.788696 -217.852519) (xy 114.789204 -217.878406)
			(xy 114.788731 -217.903765) (xy 114.780948 -217.953882) (xy 114.765582 -218.002216) (xy 114.742995 -218.047627)
			(xy 114.713721 -218.089044) (xy 114.67845 -218.125489) (xy 114.638013 -218.156103) (xy 114.593365 -218.180163)
			(xy 114.54556 -218.197102) (xy 114.520726 -218.202256) (xy 114.497866 -218.206574) (xy 114.293142 -218.561412)
			(xy 114.301016 -218.583256) (xy 114.309597 -218.609674) (xy 114.318798 -218.66445) (xy 114.319304 -218.692222)
			(xy 114.318939 -218.716052) (xy 114.312185 -218.763229) (xy 114.305842 -218.786202) (xy 114.302404 -218.799273)
			(xy 114.301784 -218.826285) (xy 114.30827 -218.852514) (xy 114.321406 -218.876125) (xy 114.340275 -218.895464)
			(xy 114.363554 -218.909179) (xy 114.389615 -218.916309) (xy 114.403124 -218.916758) (xy 115.037362 -218.916758)
			(xy 115.26774 -218.68638) (xy 115.26774 -218.210892) (xy 115.2398 -218.196668) (xy 115.214917 -218.183576)
			(xy 115.169267 -218.150753) (xy 115.129347 -218.111159) (xy 115.09615 -218.06578) (xy 115.070503 -218.015745)
			(xy 115.053045 -217.962299) (xy 115.044209 -217.906773) (xy 115.043712 -217.87866) (xy 115.04409 -217.855416)
			(xy 115.05014 -217.809322) (xy 115.062132 -217.764407) (xy 115.070636 -217.74277) (xy 115.080034 -217.719656)
			(xy 114.907568 -217.420952) (xy 114.88293 -217.41765) (xy 114.857568 -217.413847) (xy 114.808215 -217.399903)
			(xy 114.761374 -217.379023) (xy 114.718012 -217.351641) (xy 114.679026 -217.318322) (xy 114.645223 -217.279755)
			(xy 114.617301 -217.236738) (xy 114.595839 -217.19016) (xy 114.58128 -217.140986) (xy 114.573925 -217.090232)
			(xy 114.573558 -217.06459) (xy 114.57374 -217.048433) (xy 114.576664 -217.016252) (xy 114.5794 -217.000328)
			(xy 114.584226 -216.974166) (xy 114.43208 -216.82202) (xy 114.43208 -216.633552) (xy 114.390424 -216.625932)
			(xy 114.36255 -216.620213) (xy 114.308775 -216.601616) (xy 114.258358 -216.57524) (xy 114.212417 -216.541669)
			(xy 114.171971 -216.501649) (xy 114.137916 -216.456066) (xy 114.111007 -216.405931) (xy 114.091842 -216.352356)
			(xy 114.080845 -216.296529) (xy 114.07826 -216.239688) (xy 114.084145 -216.183094) (xy 114.098369 -216.128001)
			(xy 114.120617 -216.07563) (xy 114.150394 -216.027145) (xy 114.187042 -215.983619) (xy 114.229747 -215.946017)
			(xy 114.277562 -215.915174) (xy 114.303302 -215.903048) (xy 114.33302 -215.889332) (xy 114.33302 -215.793574)
			(xy 114.332573 -215.779798) (xy 114.325218 -215.753247) (xy 114.311026 -215.729633) (xy 114.291032 -215.710679)
			(xy 114.266694 -215.697767) (xy 114.239788 -215.69184) (xy 114.212278 -215.693331) (xy 114.18617 -215.702129)
			(xy 114.174524 -215.7095) (xy 114.153952 -215.722918) (xy 114.109674 -215.744168) (xy 114.062733 -215.758612)
			(xy 114.014168 -215.765931) (xy 113.989612 -215.766396) (xy 113.963702 -215.765915) (xy 113.912519 -215.757811)
			(xy 113.863235 -215.741799) (xy 113.817062 -215.718274) (xy 113.775138 -215.687816) (xy 113.738494 -215.651175)
			(xy 113.708034 -215.609252) (xy 113.684507 -215.56308) (xy 113.668493 -215.513796) (xy 113.660386 -215.462614)
			(xy 113.65992 -215.436704) (xy 113.660385 -215.411357) (xy 113.668147 -215.36126) (xy 113.683488 -215.312942)
			(xy 113.706048 -215.267544) (xy 113.735292 -215.226135) (xy 113.770533 -215.189693) (xy 113.810938 -215.159077)
			(xy 113.855555 -215.135008) (xy 113.903331 -215.118056) (xy 113.928144 -215.112854) (xy 113.951004 -215.108536)
			(xy 114.156236 -214.753444) (xy 114.148362 -214.731346) (xy 114.139742 -214.704997) (xy 114.130429 -214.650351)
			(xy 114.12982 -214.622634) (xy 114.130329 -214.596359) (xy 114.138665 -214.544474) (xy 114.155131 -214.49457)
			(xy 114.17931 -214.447912) (xy 114.210588 -214.405684) (xy 114.248172 -214.368956) (xy 114.29111 -214.338659)
			(xy 114.338312 -214.315562) (xy 114.388582 -214.30025) (xy 114.414554 -214.296244) (xy 114.431572 -214.293704)
			(xy 114.677952 -214.047324) (xy 114.677952 -213.945978) (xy 114.667538 -213.932516) (xy 114.651682 -213.910833)
			(xy 114.626496 -213.863391) (xy 114.609352 -213.812488) (xy 114.600704 -213.759475) (xy 114.600228 -213.732618)
			(xy 114.600604 -213.709476) (xy 114.607045 -213.663642) (xy 114.619832 -213.619159) (xy 114.638714 -213.576901)
			(xy 114.663319 -213.537699) (xy 114.677952 -213.519766) (xy 114.677952 -209.673952) (xy 114.308128 -209.304128)
			(xy 111.768636 -209.304128) (xy 111.512858 -209.559906) (xy 111.512858 -213.034626) (xy 111.518446 -213.03996)
			(xy 111.518446 -213.72322) (xy 110.932976 -214.30869) (xy 110.960662 -214.343996) (xy 110.976975 -214.365844)
			(xy 111.002898 -214.413809) (xy 111.02057 -214.465388) (xy 111.029509 -214.519173) (xy 111.030004 -214.546434)
			(xy 111.029626 -214.569368) (xy 111.029109 -214.573083) (xy 111.284756 -214.573083) (xy 111.284756 -214.519785)
			(xy 111.292699 -214.467081) (xy 111.308409 -214.416151) (xy 111.331535 -214.36813) (xy 111.361559 -214.324093)
			(xy 111.397811 -214.285022) (xy 111.439482 -214.251791) (xy 111.48564 -214.225142) (xy 111.535254 -214.20567)
			(xy 111.587216 -214.19381) (xy 111.640366 -214.189827) (xy 111.693516 -214.19381) (xy 111.745478 -214.20567)
			(xy 111.795092 -214.225142) (xy 111.84125 -214.251791) (xy 111.882921 -214.285022) (xy 111.919173 -214.324093)
			(xy 111.949197 -214.36813) (xy 111.972323 -214.416151) (xy 111.988033 -214.467081) (xy 111.995976 -214.519785)
			(xy 111.996474 -214.546434) (xy 111.995991 -214.572283) (xy 112.250803 -214.572283) (xy 112.250803 -214.520517)
			(xy 112.258901 -214.469389) (xy 112.274896 -214.420157) (xy 112.298395 -214.374033) (xy 112.32882 -214.332153)
			(xy 112.365421 -214.295547) (xy 112.407297 -214.265117) (xy 112.453418 -214.241612) (xy 112.502648 -214.22561)
			(xy 112.553775 -214.217507) (xy 112.579658 -214.216996) (xy 112.605169 -214.217509) (xy 112.655581 -214.225363)
			(xy 112.704182 -214.24089) (xy 112.749811 -214.263719) (xy 112.791377 -214.293306) (xy 112.827889 -214.328944)
			(xy 112.843564 -214.349076) (xy 113.255552 -214.349076) (xy 113.271247 -214.328958) (xy 113.307753 -214.293314)
			(xy 113.349314 -214.263719) (xy 113.394938 -214.24088) (xy 113.443536 -214.225342) (xy 113.493947 -214.217476)
			(xy 113.519458 -214.216996) (xy 113.545352 -214.217406) (xy 113.596504 -214.225502) (xy 113.645759 -214.2415)
			(xy 113.691905 -214.265008) (xy 113.733805 -214.295445) (xy 113.770428 -214.332063) (xy 113.80087 -214.373959)
			(xy 113.824384 -214.420102) (xy 113.840388 -214.469355) (xy 113.848491 -214.520506) (xy 113.848491 -214.572294)
			(xy 113.840388 -214.623445) (xy 113.824384 -214.672698) (xy 113.80087 -214.718841) (xy 113.770428 -214.760737)
			(xy 113.733805 -214.797355) (xy 113.691905 -214.827792) (xy 113.645759 -214.8513) (xy 113.596504 -214.867298)
			(xy 113.545352 -214.875394) (xy 113.519458 -214.875872) (xy 113.493944 -214.875433) (xy 113.443527 -214.867566)
			(xy 113.394925 -214.852025) (xy 113.349296 -214.829181) (xy 113.307732 -214.799581) (xy 113.271224 -214.763931)
			(xy 113.255552 -214.743792) (xy 112.843564 -214.743792) (xy 112.827909 -214.763943) (xy 112.791396 -214.799586)
			(xy 112.749827 -214.829178) (xy 112.704195 -214.852012) (xy 112.655589 -214.867542) (xy 112.605171 -214.875398)
			(xy 112.579658 -214.875872) (xy 112.553775 -214.875293) (xy 112.502648 -214.86719) (xy 112.453418 -214.851188)
			(xy 112.407297 -214.827683) (xy 112.365421 -214.797253) (xy 112.32882 -214.760647) (xy 112.298395 -214.718767)
			(xy 112.274896 -214.672643) (xy 112.258901 -214.623411) (xy 112.250803 -214.572283) (xy 111.995991 -214.572283)
			(xy 111.995976 -214.573083) (xy 111.988033 -214.625787) (xy 111.972323 -214.676717) (xy 111.949197 -214.724738)
			(xy 111.919173 -214.768775) (xy 111.882921 -214.807846) (xy 111.84125 -214.841077) (xy 111.795092 -214.867726)
			(xy 111.745478 -214.887198) (xy 111.693516 -214.899058) (xy 111.640366 -214.903042) (xy 111.587216 -214.899058)
			(xy 111.535254 -214.887198) (xy 111.48564 -214.867726) (xy 111.439482 -214.841077) (xy 111.397811 -214.807846)
			(xy 111.361559 -214.768775) (xy 111.331535 -214.724738) (xy 111.308409 -214.676717) (xy 111.292699 -214.625787)
			(xy 111.284756 -214.573083) (xy 111.029109 -214.573083) (xy 111.0233 -214.614796) (xy 111.010732 -214.658907)
			(xy 111.00181 -214.680038) (xy 110.991904 -214.702644) (xy 111.205772 -215.108028) (xy 111.229902 -215.1126)
			(xy 111.254847 -215.117655) (xy 111.302899 -215.134423) (xy 111.347801 -215.158383) (xy 111.388483 -215.188963)
			(xy 111.423978 -215.225438) (xy 111.45344 -215.266937) (xy 111.476169 -215.312474) (xy 111.491623 -215.360966)
			(xy 111.499435 -215.411257) (xy 111.499904 -215.436704) (xy 111.499396 -215.462611) (xy 111.499278 -215.463353)
			(xy 111.754402 -215.463353) (xy 111.754402 -215.410055) (xy 111.762345 -215.357351) (xy 111.778055 -215.306421)
			(xy 111.801181 -215.2584) (xy 111.831205 -215.214363) (xy 111.867457 -215.175292) (xy 111.909128 -215.142061)
			(xy 111.955286 -215.115412) (xy 112.0049 -215.09594) (xy 112.056862 -215.08408) (xy 112.110012 -215.080097)
			(xy 112.163162 -215.08408) (xy 112.215124 -215.09594) (xy 112.264738 -215.115412) (xy 112.310896 -215.142061)
			(xy 112.352567 -215.175292) (xy 112.388819 -215.214363) (xy 112.418843 -215.2584) (xy 112.441969 -215.306421)
			(xy 112.457679 -215.357351) (xy 112.465622 -215.410055) (xy 112.46612 -215.436704) (xy 112.465622 -215.463353)
			(xy 112.694202 -215.463353) (xy 112.694202 -215.410055) (xy 112.702145 -215.357351) (xy 112.717855 -215.306421)
			(xy 112.740981 -215.2584) (xy 112.771005 -215.214363) (xy 112.807257 -215.175292) (xy 112.848928 -215.142061)
			(xy 112.895086 -215.115412) (xy 112.9447 -215.09594) (xy 112.996662 -215.08408) (xy 113.049812 -215.080097)
			(xy 113.102962 -215.08408) (xy 113.154924 -215.09594) (xy 113.204538 -215.115412) (xy 113.250696 -215.142061)
			(xy 113.292367 -215.175292) (xy 113.328619 -215.214363) (xy 113.358643 -215.2584) (xy 113.381769 -215.306421)
			(xy 113.397479 -215.357351) (xy 113.405422 -215.410055) (xy 113.40592 -215.436704) (xy 113.405422 -215.463353)
			(xy 113.397479 -215.516057) (xy 113.381769 -215.566987) (xy 113.358643 -215.615008) (xy 113.328619 -215.659045)
			(xy 113.292367 -215.698116) (xy 113.250696 -215.731347) (xy 113.204538 -215.757996) (xy 113.154924 -215.777468)
			(xy 113.102962 -215.789328) (xy 113.049812 -215.793312) (xy 112.996662 -215.789328) (xy 112.9447 -215.777468)
			(xy 112.895086 -215.757996) (xy 112.848928 -215.731347) (xy 112.807257 -215.698116) (xy 112.771005 -215.659045)
			(xy 112.740981 -215.615008) (xy 112.717855 -215.566987) (xy 112.702145 -215.516057) (xy 112.694202 -215.463353)
			(xy 112.465622 -215.463353) (xy 112.457679 -215.516057) (xy 112.441969 -215.566987) (xy 112.418843 -215.615008)
			(xy 112.388819 -215.659045) (xy 112.352567 -215.698116) (xy 112.310896 -215.731347) (xy 112.264738 -215.757996)
			(xy 112.215124 -215.777468) (xy 112.163162 -215.789328) (xy 112.110012 -215.793312) (xy 112.056862 -215.789328)
			(xy 112.0049 -215.777468) (xy 111.955286 -215.757996) (xy 111.909128 -215.731347) (xy 111.867457 -215.698116)
			(xy 111.831205 -215.659045) (xy 111.801181 -215.615008) (xy 111.778055 -215.566987) (xy 111.762345 -215.516057)
			(xy 111.754402 -215.463353) (xy 111.499278 -215.463353) (xy 111.49129 -215.513788) (xy 111.475278 -215.563067)
			(xy 111.451755 -215.609234) (xy 111.421299 -215.651153) (xy 111.384661 -215.687791) (xy 111.342742 -215.718247)
			(xy 111.296575 -215.74177) (xy 111.247296 -215.757782) (xy 111.196119 -215.765888) (xy 111.144305 -215.765888)
			(xy 111.093128 -215.757782) (xy 111.043849 -215.74177) (xy 110.997682 -215.718247) (xy 110.955763 -215.687791)
			(xy 110.919125 -215.651153) (xy 110.888669 -215.609234) (xy 110.865146 -215.563067) (xy 110.849134 -215.513788)
			(xy 110.841028 -215.462611) (xy 110.84052 -215.436704) (xy 110.840927 -215.41376) (xy 110.847325 -215.368322)
			(xy 110.859983 -215.324215) (xy 110.868968 -215.3031) (xy 110.878874 -215.280494) (xy 110.78337 -215.099138)
			(xy 110.776634 -215.08731) (xy 110.758024 -215.067459) (xy 110.734832 -215.053228) (xy 110.708706 -215.045628)
			(xy 110.681499 -215.045197) (xy 110.655145 -215.051966) (xy 110.631514 -215.065456) (xy 110.621572 -215.074754)
			(xy 110.477554 -215.218772) (xy 110.493008 -215.236915) (xy 110.519072 -215.276814) (xy 110.539123 -215.320049)
			(xy 110.552741 -215.36572) (xy 110.559643 -215.412875) (xy 110.560104 -215.436704) (xy 110.559596 -215.462611)
			(xy 110.55149 -215.513788) (xy 110.535478 -215.563067) (xy 110.511955 -215.609235) (xy 110.481499 -215.651154)
			(xy 110.44486 -215.687794) (xy 110.402942 -215.71825) (xy 110.356775 -215.741775) (xy 110.307496 -215.757788)
			(xy 110.256319 -215.765895) (xy 110.230412 -215.766396) (xy 110.2049 -215.765919) (xy 110.154484 -215.75806)
			(xy 110.105881 -215.742528) (xy 110.060251 -215.719693) (xy 110.018684 -215.6901) (xy 109.982172 -215.654458)
			(xy 109.966506 -215.634316) (xy 109.554518 -215.634316) (xy 109.538845 -215.654452) (xy 109.502335 -215.690096)
			(xy 109.46077 -215.719691) (xy 109.415141 -215.742528) (xy 109.366539 -215.758064) (xy 109.316124 -215.765926)
			(xy 109.290612 -215.766396) (xy 109.264702 -215.765915) (xy 109.213519 -215.757811) (xy 109.164235 -215.741799)
			(xy 109.118062 -215.718274) (xy 109.076138 -215.687816) (xy 109.039494 -215.651175) (xy 109.009034 -215.609252)
			(xy 108.985507 -215.56308) (xy 108.969493 -215.513796) (xy 108.961386 -215.462614) (xy 108.96092 -215.436704)
			(xy 108.961187 -215.419813) (xy 108.964754 -215.38622) (xy 108.968032 -215.369648) (xy 108.970594 -215.354768)
			(xy 108.967888 -215.32471) (xy 108.956518 -215.296755) (xy 108.937478 -215.273341) (xy 108.912428 -215.25651)
			(xy 108.883554 -215.247732) (xy 108.868464 -215.24722) (xy 108.688124 -215.24722) (xy 108.654088 -215.305894)
			(xy 108.661962 -215.327738) (xy 108.670608 -215.354146) (xy 108.67993 -215.408922) (xy 108.680504 -215.436704)
			(xy 108.679996 -215.462611) (xy 108.67189 -215.513788) (xy 108.655878 -215.563067) (xy 108.632355 -215.609234)
			(xy 108.601899 -215.651153) (xy 108.565261 -215.687791) (xy 108.523342 -215.718247) (xy 108.477175 -215.74177)
			(xy 108.427896 -215.757782) (xy 108.376719 -215.765888) (xy 108.324905 -215.765888) (xy 108.273728 -215.757782)
			(xy 108.224449 -215.74177) (xy 108.178282 -215.718247) (xy 108.136363 -215.687791) (xy 108.099725 -215.651153)
			(xy 108.069269 -215.609234) (xy 108.045746 -215.563067) (xy 108.029734 -215.513788) (xy 108.021628 -215.462611)
			(xy 108.02112 -215.436704) (xy 108.021387 -215.419813) (xy 108.024954 -215.38622) (xy 108.028232 -215.369648)
			(xy 108.030794 -215.354768) (xy 108.028088 -215.32471) (xy 108.016718 -215.296755) (xy 107.997678 -215.273341)
			(xy 107.972628 -215.25651) (xy 107.943754 -215.247732) (xy 107.928664 -215.24722) (xy 106.808524 -215.24722)
			(xy 106.774488 -215.305894) (xy 106.782362 -215.327738) (xy 106.791008 -215.354146) (xy 106.80033 -215.408922)
			(xy 106.800904 -215.436704) (xy 106.800396 -215.462611) (xy 106.79229 -215.513788) (xy 106.776278 -215.563067)
			(xy 106.752755 -215.609234) (xy 106.722299 -215.651153) (xy 106.685661 -215.687791) (xy 106.643742 -215.718247)
			(xy 106.597575 -215.74177) (xy 106.548296 -215.757782) (xy 106.497119 -215.765888) (xy 106.445305 -215.765888)
			(xy 106.394128 -215.757782) (xy 106.344849 -215.74177) (xy 106.298682 -215.718247) (xy 106.256763 -215.687791)
			(xy 106.220125 -215.651153) (xy 106.189669 -215.609234) (xy 106.166146 -215.563067) (xy 106.150134 -215.513788)
			(xy 106.142028 -215.462611) (xy 106.14152 -215.436704) (xy 106.141787 -215.419813) (xy 106.145354 -215.38622)
			(xy 106.148632 -215.369648) (xy 106.151194 -215.354768) (xy 106.148488 -215.32471) (xy 106.137118 -215.296755)
			(xy 106.118078 -215.273341) (xy 106.093028 -215.25651) (xy 106.064154 -215.247732) (xy 106.049064 -215.24722)
			(xy 104.928924 -215.24722) (xy 104.894888 -215.305894) (xy 104.902762 -215.327738) (xy 104.911408 -215.354146)
			(xy 104.92073 -215.408922) (xy 104.921304 -215.436704) (xy 104.920796 -215.462611) (xy 104.91269 -215.513788)
			(xy 104.896678 -215.563067) (xy 104.873155 -215.609234) (xy 104.842699 -215.651153) (xy 104.806061 -215.687791)
			(xy 104.764142 -215.718247) (xy 104.717975 -215.74177) (xy 104.668696 -215.757782) (xy 104.617519 -215.765888)
			(xy 104.565705 -215.765888) (xy 104.514528 -215.757782) (xy 104.465249 -215.74177) (xy 104.419082 -215.718247)
			(xy 104.377163 -215.687791) (xy 104.340525 -215.651153) (xy 104.310069 -215.609234) (xy 104.286546 -215.563067)
			(xy 104.270534 -215.513788) (xy 104.262428 -215.462611) (xy 104.26192 -215.436704) (xy 104.262187 -215.419813)
			(xy 104.265754 -215.38622) (xy 104.269032 -215.369648) (xy 104.271594 -215.354768) (xy 104.268888 -215.32471)
			(xy 104.257518 -215.296755) (xy 104.238478 -215.273341) (xy 104.213428 -215.25651) (xy 104.184554 -215.247732)
			(xy 104.169464 -215.24722) (xy 103.049324 -215.24722) (xy 103.015288 -215.305894) (xy 103.023162 -215.327738)
			(xy 103.031808 -215.354146) (xy 103.04113 -215.408922) (xy 103.041704 -215.436704) (xy 103.041196 -215.462611)
			(xy 103.03309 -215.513788) (xy 103.017078 -215.563067) (xy 102.993555 -215.609234) (xy 102.963099 -215.651153)
			(xy 102.926461 -215.687791) (xy 102.884542 -215.718247) (xy 102.838375 -215.74177) (xy 102.789096 -215.757782)
			(xy 102.737919 -215.765888) (xy 102.686105 -215.765888) (xy 102.634928 -215.757782) (xy 102.585649 -215.74177)
			(xy 102.539482 -215.718247) (xy 102.497563 -215.687791) (xy 102.460925 -215.651153) (xy 102.430469 -215.609234)
			(xy 102.406946 -215.563067) (xy 102.390934 -215.513788) (xy 102.382828 -215.462611) (xy 102.38232 -215.436704)
			(xy 102.382587 -215.419813) (xy 102.386154 -215.38622) (xy 102.389432 -215.369648) (xy 102.391994 -215.354768)
			(xy 102.389288 -215.32471) (xy 102.377918 -215.296755) (xy 102.358878 -215.273341) (xy 102.333828 -215.25651)
			(xy 102.304954 -215.247732) (xy 102.289864 -215.24722) (xy 101.69906 -215.24722) (xy 101.45776 -215.48852)
			(xy 101.45776 -215.929972) (xy 101.481489 -215.942007) (xy 101.525395 -215.972055) (xy 101.564341 -216.008301)
			(xy 101.597462 -216.049938) (xy 101.62402 -216.096039) (xy 101.643423 -216.145579) (xy 101.65524 -216.197453)
			(xy 101.659207 -216.250509) (xy 101.657212 -216.277169) (xy 101.886756 -216.277169) (xy 101.886756 -216.223871)
			(xy 101.894699 -216.171167) (xy 101.910409 -216.120237) (xy 101.933535 -216.072216) (xy 101.963559 -216.028179)
			(xy 101.999811 -215.989108) (xy 102.041482 -215.955877) (xy 102.08764 -215.929228) (xy 102.137254 -215.909756)
			(xy 102.189216 -215.897896) (xy 102.242366 -215.893913) (xy 102.295516 -215.897896) (xy 102.347478 -215.909756)
			(xy 102.397092 -215.929228) (xy 102.44325 -215.955877) (xy 102.484921 -215.989108) (xy 102.521173 -216.028179)
			(xy 102.551197 -216.072216) (xy 102.574323 -216.120237) (xy 102.590033 -216.171167) (xy 102.597976 -216.223871)
			(xy 102.598474 -216.25052) (xy 102.597976 -216.277169) (xy 102.826556 -216.277169) (xy 102.826556 -216.223871)
			(xy 102.834499 -216.171167) (xy 102.850209 -216.120237) (xy 102.873335 -216.072216) (xy 102.903359 -216.028179)
			(xy 102.939611 -215.989108) (xy 102.981282 -215.955877) (xy 103.02744 -215.929228) (xy 103.077054 -215.909756)
			(xy 103.129016 -215.897896) (xy 103.182166 -215.893913) (xy 103.235316 -215.897896) (xy 103.287278 -215.909756)
			(xy 103.336892 -215.929228) (xy 103.38305 -215.955877) (xy 103.424721 -215.989108) (xy 103.460973 -216.028179)
			(xy 103.490997 -216.072216) (xy 103.514123 -216.120237) (xy 103.529833 -216.171167) (xy 103.537776 -216.223871)
			(xy 103.538274 -216.25052) (xy 103.537776 -216.277169) (xy 103.766356 -216.277169) (xy 103.766356 -216.223871)
			(xy 103.774299 -216.171167) (xy 103.790009 -216.120237) (xy 103.813135 -216.072216) (xy 103.843159 -216.028179)
			(xy 103.879411 -215.989108) (xy 103.921082 -215.955877) (xy 103.96724 -215.929228) (xy 104.016854 -215.909756)
			(xy 104.068816 -215.897896) (xy 104.121966 -215.893913) (xy 104.175116 -215.897896) (xy 104.227078 -215.909756)
			(xy 104.276692 -215.929228) (xy 104.32285 -215.955877) (xy 104.364521 -215.989108) (xy 104.400773 -216.028179)
			(xy 104.430797 -216.072216) (xy 104.453923 -216.120237) (xy 104.469633 -216.171167) (xy 104.477576 -216.223871)
			(xy 104.478074 -216.25052) (xy 104.477576 -216.277169) (xy 104.706156 -216.277169) (xy 104.706156 -216.223871)
			(xy 104.714099 -216.171167) (xy 104.729809 -216.120237) (xy 104.752935 -216.072216) (xy 104.782959 -216.028179)
			(xy 104.819211 -215.989108) (xy 104.860882 -215.955877) (xy 104.90704 -215.929228) (xy 104.956654 -215.909756)
			(xy 105.008616 -215.897896) (xy 105.061766 -215.893913) (xy 105.114916 -215.897896) (xy 105.166878 -215.909756)
			(xy 105.216492 -215.929228) (xy 105.26265 -215.955877) (xy 105.304321 -215.989108) (xy 105.340573 -216.028179)
			(xy 105.370597 -216.072216) (xy 105.393723 -216.120237) (xy 105.409433 -216.171167) (xy 105.417376 -216.223871)
			(xy 105.417874 -216.25052) (xy 105.417376 -216.277169) (xy 105.645956 -216.277169) (xy 105.645956 -216.223871)
			(xy 105.653899 -216.171167) (xy 105.669609 -216.120237) (xy 105.692735 -216.072216) (xy 105.722759 -216.028179)
			(xy 105.759011 -215.989108) (xy 105.800682 -215.955877) (xy 105.84684 -215.929228) (xy 105.896454 -215.909756)
			(xy 105.948416 -215.897896) (xy 106.001566 -215.893913) (xy 106.054716 -215.897896) (xy 106.106678 -215.909756)
			(xy 106.156292 -215.929228) (xy 106.20245 -215.955877) (xy 106.244121 -215.989108) (xy 106.280373 -216.028179)
			(xy 106.310397 -216.072216) (xy 106.333523 -216.120237) (xy 106.349233 -216.171167) (xy 106.357176 -216.223871)
			(xy 106.357674 -216.25052) (xy 106.357176 -216.277169) (xy 106.585756 -216.277169) (xy 106.585756 -216.223871)
			(xy 106.593699 -216.171167) (xy 106.609409 -216.120237) (xy 106.632535 -216.072216) (xy 106.662559 -216.028179)
			(xy 106.698811 -215.989108) (xy 106.740482 -215.955877) (xy 106.78664 -215.929228) (xy 106.836254 -215.909756)
			(xy 106.888216 -215.897896) (xy 106.941366 -215.893913) (xy 106.994516 -215.897896) (xy 107.046478 -215.909756)
			(xy 107.096092 -215.929228) (xy 107.14225 -215.955877) (xy 107.183921 -215.989108) (xy 107.220173 -216.028179)
			(xy 107.250197 -216.072216) (xy 107.273323 -216.120237) (xy 107.289033 -216.171167) (xy 107.296976 -216.223871)
			(xy 107.297474 -216.25052) (xy 107.296976 -216.277169) (xy 107.525556 -216.277169) (xy 107.525556 -216.223871)
			(xy 107.533499 -216.171167) (xy 107.549209 -216.120237) (xy 107.572335 -216.072216) (xy 107.602359 -216.028179)
			(xy 107.638611 -215.989108) (xy 107.680282 -215.955877) (xy 107.72644 -215.929228) (xy 107.776054 -215.909756)
			(xy 107.828016 -215.897896) (xy 107.881166 -215.893913) (xy 107.934316 -215.897896) (xy 107.986278 -215.909756)
			(xy 108.035892 -215.929228) (xy 108.08205 -215.955877) (xy 108.123721 -215.989108) (xy 108.159973 -216.028179)
			(xy 108.189997 -216.072216) (xy 108.213123 -216.120237) (xy 108.228833 -216.171167) (xy 108.236776 -216.223871)
			(xy 108.237274 -216.25052) (xy 108.236776 -216.277169) (xy 108.465356 -216.277169) (xy 108.465356 -216.223871)
			(xy 108.473299 -216.171167) (xy 108.489009 -216.120237) (xy 108.512135 -216.072216) (xy 108.542159 -216.028179)
			(xy 108.578411 -215.989108) (xy 108.620082 -215.955877) (xy 108.66624 -215.929228) (xy 108.715854 -215.909756)
			(xy 108.767816 -215.897896) (xy 108.820966 -215.893913) (xy 108.874116 -215.897896) (xy 108.926078 -215.909756)
			(xy 108.975692 -215.929228) (xy 109.02185 -215.955877) (xy 109.063521 -215.989108) (xy 109.099773 -216.028179)
			(xy 109.129797 -216.072216) (xy 109.152923 -216.120237) (xy 109.168633 -216.171167) (xy 109.176576 -216.223871)
			(xy 109.177074 -216.25052) (xy 109.176576 -216.277169) (xy 109.405156 -216.277169) (xy 109.405156 -216.223871)
			(xy 109.413099 -216.171167) (xy 109.428809 -216.120237) (xy 109.451935 -216.072216) (xy 109.481959 -216.028179)
			(xy 109.518211 -215.989108) (xy 109.559882 -215.955877) (xy 109.60604 -215.929228) (xy 109.655654 -215.909756)
			(xy 109.707616 -215.897896) (xy 109.760766 -215.893913) (xy 109.813916 -215.897896) (xy 109.865878 -215.909756)
			(xy 109.915492 -215.929228) (xy 109.96165 -215.955877) (xy 110.003321 -215.989108) (xy 110.039573 -216.028179)
			(xy 110.069597 -216.072216) (xy 110.092723 -216.120237) (xy 110.108433 -216.171167) (xy 110.116376 -216.223871)
			(xy 110.116874 -216.25052) (xy 110.116376 -216.277169) (xy 110.344956 -216.277169) (xy 110.344956 -216.223871)
			(xy 110.352899 -216.171167) (xy 110.368609 -216.120237) (xy 110.391735 -216.072216) (xy 110.421759 -216.028179)
			(xy 110.458011 -215.989108) (xy 110.499682 -215.955877) (xy 110.54584 -215.929228) (xy 110.595454 -215.909756)
			(xy 110.647416 -215.897896) (xy 110.700566 -215.893913) (xy 110.753716 -215.897896) (xy 110.805678 -215.909756)
			(xy 110.855292 -215.929228) (xy 110.90145 -215.955877) (xy 110.943121 -215.989108) (xy 110.979373 -216.028179)
			(xy 111.009397 -216.072216) (xy 111.032523 -216.120237) (xy 111.048233 -216.171167) (xy 111.056176 -216.223871)
			(xy 111.056674 -216.25052) (xy 111.056176 -216.277169) (xy 111.284756 -216.277169) (xy 111.284756 -216.223871)
			(xy 111.292699 -216.171167) (xy 111.308409 -216.120237) (xy 111.331535 -216.072216) (xy 111.361559 -216.028179)
			(xy 111.397811 -215.989108) (xy 111.439482 -215.955877) (xy 111.48564 -215.929228) (xy 111.535254 -215.909756)
			(xy 111.587216 -215.897896) (xy 111.640366 -215.893913) (xy 111.693516 -215.897896) (xy 111.745478 -215.909756)
			(xy 111.795092 -215.929228) (xy 111.84125 -215.955877) (xy 111.882921 -215.989108) (xy 111.919173 -216.028179)
			(xy 111.949197 -216.072216) (xy 111.972323 -216.120237) (xy 111.988033 -216.171167) (xy 111.995976 -216.223871)
			(xy 111.996474 -216.25052) (xy 111.995976 -216.277169) (xy 112.224302 -216.277169) (xy 112.224302 -216.223871)
			(xy 112.232245 -216.171167) (xy 112.247955 -216.120237) (xy 112.271081 -216.072216) (xy 112.301105 -216.028179)
			(xy 112.337357 -215.989108) (xy 112.379028 -215.955877) (xy 112.425186 -215.929228) (xy 112.4748 -215.909756)
			(xy 112.526762 -215.897896) (xy 112.579912 -215.893913) (xy 112.633062 -215.897896) (xy 112.685024 -215.909756)
			(xy 112.734638 -215.929228) (xy 112.780796 -215.955877) (xy 112.822467 -215.989108) (xy 112.858719 -216.028179)
			(xy 112.888743 -216.072216) (xy 112.911869 -216.120237) (xy 112.927579 -216.171167) (xy 112.935522 -216.223871)
			(xy 112.93602 -216.25052) (xy 112.935522 -216.277169) (xy 113.164356 -216.277169) (xy 113.164356 -216.223871)
			(xy 113.172299 -216.171167) (xy 113.188009 -216.120237) (xy 113.211135 -216.072216) (xy 113.241159 -216.028179)
			(xy 113.277411 -215.989108) (xy 113.319082 -215.955877) (xy 113.36524 -215.929228) (xy 113.414854 -215.909756)
			(xy 113.466816 -215.897896) (xy 113.519966 -215.893913) (xy 113.573116 -215.897896) (xy 113.625078 -215.909756)
			(xy 113.674692 -215.929228) (xy 113.72085 -215.955877) (xy 113.762521 -215.989108) (xy 113.798773 -216.028179)
			(xy 113.828797 -216.072216) (xy 113.851923 -216.120237) (xy 113.867633 -216.171167) (xy 113.875576 -216.223871)
			(xy 113.876074 -216.25052) (xy 113.875576 -216.277169) (xy 113.867633 -216.329873) (xy 113.851923 -216.380803)
			(xy 113.828797 -216.428824) (xy 113.798773 -216.472861) (xy 113.762521 -216.511932) (xy 113.72085 -216.545163)
			(xy 113.674692 -216.571812) (xy 113.625078 -216.591284) (xy 113.573116 -216.603144) (xy 113.519966 -216.607128)
			(xy 113.466816 -216.603144) (xy 113.414854 -216.591284) (xy 113.36524 -216.571812) (xy 113.319082 -216.545163)
			(xy 113.277411 -216.511932) (xy 113.241159 -216.472861) (xy 113.211135 -216.428824) (xy 113.188009 -216.380803)
			(xy 113.172299 -216.329873) (xy 113.164356 -216.277169) (xy 112.935522 -216.277169) (xy 112.927579 -216.329873)
			(xy 112.911869 -216.380803) (xy 112.888743 -216.428824) (xy 112.858719 -216.472861) (xy 112.822467 -216.511932)
			(xy 112.780796 -216.545163) (xy 112.734638 -216.571812) (xy 112.685024 -216.591284) (xy 112.633062 -216.603144)
			(xy 112.579912 -216.607128) (xy 112.526762 -216.603144) (xy 112.4748 -216.591284) (xy 112.425186 -216.571812)
			(xy 112.379028 -216.545163) (xy 112.337357 -216.511932) (xy 112.301105 -216.472861) (xy 112.271081 -216.428824)
			(xy 112.247955 -216.380803) (xy 112.232245 -216.329873) (xy 112.224302 -216.277169) (xy 111.995976 -216.277169)
			(xy 111.988033 -216.329873) (xy 111.972323 -216.380803) (xy 111.949197 -216.428824) (xy 111.919173 -216.472861)
			(xy 111.882921 -216.511932) (xy 111.84125 -216.545163) (xy 111.795092 -216.571812) (xy 111.745478 -216.591284)
			(xy 111.693516 -216.603144) (xy 111.640366 -216.607128) (xy 111.587216 -216.603144) (xy 111.535254 -216.591284)
			(xy 111.48564 -216.571812) (xy 111.439482 -216.545163) (xy 111.397811 -216.511932) (xy 111.361559 -216.472861)
			(xy 111.331535 -216.428824) (xy 111.308409 -216.380803) (xy 111.292699 -216.329873) (xy 111.284756 -216.277169)
			(xy 111.056176 -216.277169) (xy 111.048233 -216.329873) (xy 111.032523 -216.380803) (xy 111.009397 -216.428824)
			(xy 110.979373 -216.472861) (xy 110.943121 -216.511932) (xy 110.90145 -216.545163) (xy 110.855292 -216.571812)
			(xy 110.805678 -216.591284) (xy 110.753716 -216.603144) (xy 110.700566 -216.607128) (xy 110.647416 -216.603144)
			(xy 110.595454 -216.591284) (xy 110.54584 -216.571812) (xy 110.499682 -216.545163) (xy 110.458011 -216.511932)
			(xy 110.421759 -216.472861) (xy 110.391735 -216.428824) (xy 110.368609 -216.380803) (xy 110.352899 -216.329873)
			(xy 110.344956 -216.277169) (xy 110.116376 -216.277169) (xy 110.108433 -216.329873) (xy 110.092723 -216.380803)
			(xy 110.069597 -216.428824) (xy 110.039573 -216.472861) (xy 110.003321 -216.511932) (xy 109.96165 -216.545163)
			(xy 109.915492 -216.571812) (xy 109.865878 -216.591284) (xy 109.813916 -216.603144) (xy 109.760766 -216.607128)
			(xy 109.707616 -216.603144) (xy 109.655654 -216.591284) (xy 109.60604 -216.571812) (xy 109.559882 -216.545163)
			(xy 109.518211 -216.511932) (xy 109.481959 -216.472861) (xy 109.451935 -216.428824) (xy 109.428809 -216.380803)
			(xy 109.413099 -216.329873) (xy 109.405156 -216.277169) (xy 109.176576 -216.277169) (xy 109.168633 -216.329873)
			(xy 109.152923 -216.380803) (xy 109.129797 -216.428824) (xy 109.099773 -216.472861) (xy 109.063521 -216.511932)
			(xy 109.02185 -216.545163) (xy 108.975692 -216.571812) (xy 108.926078 -216.591284) (xy 108.874116 -216.603144)
			(xy 108.820966 -216.607128) (xy 108.767816 -216.603144) (xy 108.715854 -216.591284) (xy 108.66624 -216.571812)
			(xy 108.620082 -216.545163) (xy 108.578411 -216.511932) (xy 108.542159 -216.472861) (xy 108.512135 -216.428824)
			(xy 108.489009 -216.380803) (xy 108.473299 -216.329873) (xy 108.465356 -216.277169) (xy 108.236776 -216.277169)
			(xy 108.228833 -216.329873) (xy 108.213123 -216.380803) (xy 108.189997 -216.428824) (xy 108.159973 -216.472861)
			(xy 108.123721 -216.511932) (xy 108.08205 -216.545163) (xy 108.035892 -216.571812) (xy 107.986278 -216.591284)
			(xy 107.934316 -216.603144) (xy 107.881166 -216.607128) (xy 107.828016 -216.603144) (xy 107.776054 -216.591284)
			(xy 107.72644 -216.571812) (xy 107.680282 -216.545163) (xy 107.638611 -216.511932) (xy 107.602359 -216.472861)
			(xy 107.572335 -216.428824) (xy 107.549209 -216.380803) (xy 107.533499 -216.329873) (xy 107.525556 -216.277169)
			(xy 107.296976 -216.277169) (xy 107.289033 -216.329873) (xy 107.273323 -216.380803) (xy 107.250197 -216.428824)
			(xy 107.220173 -216.472861) (xy 107.183921 -216.511932) (xy 107.14225 -216.545163) (xy 107.096092 -216.571812)
			(xy 107.046478 -216.591284) (xy 106.994516 -216.603144) (xy 106.941366 -216.607128) (xy 106.888216 -216.603144)
			(xy 106.836254 -216.591284) (xy 106.78664 -216.571812) (xy 106.740482 -216.545163) (xy 106.698811 -216.511932)
			(xy 106.662559 -216.472861) (xy 106.632535 -216.428824) (xy 106.609409 -216.380803) (xy 106.593699 -216.329873)
			(xy 106.585756 -216.277169) (xy 106.357176 -216.277169) (xy 106.349233 -216.329873) (xy 106.333523 -216.380803)
			(xy 106.310397 -216.428824) (xy 106.280373 -216.472861) (xy 106.244121 -216.511932) (xy 106.20245 -216.545163)
			(xy 106.156292 -216.571812) (xy 106.106678 -216.591284) (xy 106.054716 -216.603144) (xy 106.001566 -216.607128)
			(xy 105.948416 -216.603144) (xy 105.896454 -216.591284) (xy 105.84684 -216.571812) (xy 105.800682 -216.545163)
			(xy 105.759011 -216.511932) (xy 105.722759 -216.472861) (xy 105.692735 -216.428824) (xy 105.669609 -216.380803)
			(xy 105.653899 -216.329873) (xy 105.645956 -216.277169) (xy 105.417376 -216.277169) (xy 105.409433 -216.329873)
			(xy 105.393723 -216.380803) (xy 105.370597 -216.428824) (xy 105.340573 -216.472861) (xy 105.304321 -216.511932)
			(xy 105.26265 -216.545163) (xy 105.216492 -216.571812) (xy 105.166878 -216.591284) (xy 105.114916 -216.603144)
			(xy 105.061766 -216.607128) (xy 105.008616 -216.603144) (xy 104.956654 -216.591284) (xy 104.90704 -216.571812)
			(xy 104.860882 -216.545163) (xy 104.819211 -216.511932) (xy 104.782959 -216.472861) (xy 104.752935 -216.428824)
			(xy 104.729809 -216.380803) (xy 104.714099 -216.329873) (xy 104.706156 -216.277169) (xy 104.477576 -216.277169)
			(xy 104.469633 -216.329873) (xy 104.453923 -216.380803) (xy 104.430797 -216.428824) (xy 104.400773 -216.472861)
			(xy 104.364521 -216.511932) (xy 104.32285 -216.545163) (xy 104.276692 -216.571812) (xy 104.227078 -216.591284)
			(xy 104.175116 -216.603144) (xy 104.121966 -216.607128) (xy 104.068816 -216.603144) (xy 104.016854 -216.591284)
			(xy 103.96724 -216.571812) (xy 103.921082 -216.545163) (xy 103.879411 -216.511932) (xy 103.843159 -216.472861)
			(xy 103.813135 -216.428824) (xy 103.790009 -216.380803) (xy 103.774299 -216.329873) (xy 103.766356 -216.277169)
			(xy 103.537776 -216.277169) (xy 103.529833 -216.329873) (xy 103.514123 -216.380803) (xy 103.490997 -216.428824)
			(xy 103.460973 -216.472861) (xy 103.424721 -216.511932) (xy 103.38305 -216.545163) (xy 103.336892 -216.571812)
			(xy 103.287278 -216.591284) (xy 103.235316 -216.603144) (xy 103.182166 -216.607128) (xy 103.129016 -216.603144)
			(xy 103.077054 -216.591284) (xy 103.02744 -216.571812) (xy 102.981282 -216.545163) (xy 102.939611 -216.511932)
			(xy 102.903359 -216.472861) (xy 102.873335 -216.428824) (xy 102.850209 -216.380803) (xy 102.834499 -216.329873)
			(xy 102.826556 -216.277169) (xy 102.597976 -216.277169) (xy 102.590033 -216.329873) (xy 102.574323 -216.380803)
			(xy 102.551197 -216.428824) (xy 102.521173 -216.472861) (xy 102.484921 -216.511932) (xy 102.44325 -216.545163)
			(xy 102.397092 -216.571812) (xy 102.347478 -216.591284) (xy 102.295516 -216.603144) (xy 102.242366 -216.607128)
			(xy 102.189216 -216.603144) (xy 102.137254 -216.591284) (xy 102.08764 -216.571812) (xy 102.041482 -216.545163)
			(xy 101.999811 -216.511932) (xy 101.963559 -216.472861) (xy 101.933535 -216.428824) (xy 101.910409 -216.380803)
			(xy 101.894699 -216.329873) (xy 101.886756 -216.277169) (xy 101.657212 -216.277169) (xy 101.655237 -216.303564)
			(xy 101.643418 -216.355438) (xy 101.624012 -216.404976) (xy 101.597453 -216.451076) (xy 101.56433 -216.492712)
			(xy 101.525381 -216.528955) (xy 101.481474 -216.559001) (xy 101.45776 -216.571068) (xy 101.45776 -216.689432)
			(xy 101.458323 -216.70459) (xy 101.467233 -216.733568) (xy 101.484258 -216.758652) (xy 101.507898 -216.777633)
			(xy 101.536069 -216.788836) (xy 101.566288 -216.791274) (xy 101.59589 -216.784733) (xy 101.609398 -216.777824)
			(xy 101.634381 -216.764292) (xy 101.687843 -216.745067) (xy 101.743806 -216.735276) (xy 101.772212 -216.734644)
			(xy 101.79812 -216.735127) (xy 101.849297 -216.743235) (xy 101.898576 -216.759249) (xy 101.944742 -216.782776)
			(xy 101.98666 -216.813235) (xy 102.023296 -216.849877) (xy 102.053749 -216.891799) (xy 102.077269 -216.937969)
			(xy 102.093276 -216.98725) (xy 102.101377 -217.038428) (xy 102.101904 -217.064336) (xy 102.101444 -217.089687)
			(xy 102.101243 -217.090985) (xy 102.356656 -217.090985) (xy 102.356656 -217.037687) (xy 102.364599 -216.984983)
			(xy 102.380309 -216.934053) (xy 102.403435 -216.886032) (xy 102.433459 -216.841995) (xy 102.469711 -216.802924)
			(xy 102.511382 -216.769693) (xy 102.55754 -216.743044) (xy 102.607154 -216.723572) (xy 102.659116 -216.711712)
			(xy 102.712266 -216.707729) (xy 102.765416 -216.711712) (xy 102.817378 -216.723572) (xy 102.866992 -216.743044)
			(xy 102.91315 -216.769693) (xy 102.954821 -216.802924) (xy 102.991073 -216.841995) (xy 103.021097 -216.886032)
			(xy 103.044223 -216.934053) (xy 103.059933 -216.984983) (xy 103.067876 -217.037687) (xy 103.068374 -217.064336)
			(xy 103.067876 -217.090985) (xy 103.059933 -217.143689) (xy 103.044223 -217.194619) (xy 103.021097 -217.24264)
			(xy 102.991073 -217.286677) (xy 102.954821 -217.325748) (xy 102.91315 -217.358979) (xy 102.866992 -217.385628)
			(xy 102.817378 -217.4051) (xy 102.765416 -217.41696) (xy 102.712266 -217.420944) (xy 102.659116 -217.41696)
			(xy 102.607154 -217.4051) (xy 102.55754 -217.385628) (xy 102.511382 -217.358979) (xy 102.469711 -217.325748)
			(xy 102.433459 -217.286677) (xy 102.403435 -217.24264) (xy 102.380309 -217.194619) (xy 102.364599 -217.143689)
			(xy 102.356656 -217.090985) (xy 102.101243 -217.090985) (xy 102.093689 -217.139791) (xy 102.078354 -217.188117)
			(xy 102.055799 -217.233525) (xy 102.026556 -217.274944) (xy 101.991316 -217.311396) (xy 101.95091 -217.342021)
			(xy 101.90629 -217.366098) (xy 101.85851 -217.383058) (xy 101.83368 -217.388186) (xy 101.81082 -217.392504)
			(xy 101.605842 -217.747596) (xy 101.613716 -217.76944) (xy 101.622291 -217.795859) (xy 101.631477 -217.850635)
			(xy 101.632004 -217.878406) (xy 101.631553 -217.903859) (xy 101.623766 -217.954166) (xy 101.608333 -218.002676)
			(xy 101.585621 -218.048234) (xy 101.556171 -218.089756) (xy 101.520684 -218.126253) (xy 101.480004 -218.156856)
			(xy 101.45776 -218.169236) (xy 101.45776 -218.49461) (xy 101.72192 -218.75877) (xy 101.861112 -218.75877)
			(xy 101.87178 -218.753436) (xy 101.907461 -218.736387) (xy 101.981392 -218.708301) (xy 102.057638 -218.687299)
			(xy 102.135522 -218.673564) (xy 102.214353 -218.66722) (xy 102.293431 -218.668323) (xy 102.33279 -218.672156)
			(xy 102.342292 -218.672762) (xy 102.360645 -218.66774) (xy 102.375924 -218.6564) (xy 102.386046 -218.640289)
			(xy 102.388162 -218.631008) (xy 102.390559 -218.618939) (xy 102.396914 -218.595164) (xy 102.400862 -218.58351)
			(xy 102.408736 -218.561412) (xy 102.203758 -218.206574) (xy 102.180898 -218.202256) (xy 102.156097 -218.197058)
			(xy 102.108358 -218.18007) (xy 102.06378 -218.155978) (xy 102.023414 -218.125348) (xy 101.98821 -218.088903)
			(xy 101.958996 -218.0475) (xy 101.936462 -218.002115) (xy 101.921137 -217.953817) (xy 101.913383 -217.903742)
			(xy 101.912928 -217.878406) (xy 101.913436 -217.852519) (xy 101.921535 -217.801381) (xy 101.937534 -217.752141)
			(xy 101.96104 -217.706009) (xy 101.991472 -217.664122) (xy 102.028082 -217.627512) (xy 102.069969 -217.59708)
			(xy 102.116101 -217.573574) (xy 102.165341 -217.557575) (xy 102.216479 -217.549476) (xy 102.268253 -217.549476)
			(xy 102.319391 -217.557575) (xy 102.368631 -217.573574) (xy 102.414763 -217.59708) (xy 102.45665 -217.627512)
			(xy 102.49326 -217.664122) (xy 102.523692 -217.706009) (xy 102.547198 -217.752141) (xy 102.563197 -217.801381)
			(xy 102.571296 -217.852519) (xy 102.571804 -217.878406) (xy 102.852728 -217.878406) (xy 102.853194 -217.853071)
			(xy 102.860946 -217.802996) (xy 102.876269 -217.754698) (xy 102.898802 -217.709313) (xy 102.928014 -217.66791)
			(xy 102.963217 -217.631464) (xy 103.003582 -217.600835) (xy 103.048159 -217.576742) (xy 103.095897 -217.559754)
			(xy 103.120698 -217.554556) (xy 103.143558 -217.550238) (xy 103.348536 -217.195146) (xy 103.340662 -217.173302)
			(xy 103.332024 -217.146891) (xy 103.322699 -217.092117) (xy 103.32212 -217.064336) (xy 103.322628 -217.038429)
			(xy 103.330734 -216.987252) (xy 103.346746 -216.937973) (xy 103.370269 -216.891806) (xy 103.400725 -216.849887)
			(xy 103.437363 -216.813249) (xy 103.479282 -216.782793) (xy 103.525449 -216.75927) (xy 103.574728 -216.743258)
			(xy 103.625905 -216.735152) (xy 103.677719 -216.735152) (xy 103.728896 -216.743258) (xy 103.778175 -216.75927)
			(xy 103.824342 -216.782793) (xy 103.866261 -216.813249) (xy 103.902899 -216.849887) (xy 103.933355 -216.891806)
			(xy 103.956878 -216.937973) (xy 103.97289 -216.987252) (xy 103.980996 -217.038429) (xy 103.981504 -217.064336)
			(xy 103.981012 -217.08968) (xy 103.980809 -217.090985) (xy 104.236256 -217.090985) (xy 104.236256 -217.037687)
			(xy 104.244199 -216.984983) (xy 104.259909 -216.934053) (xy 104.283035 -216.886032) (xy 104.313059 -216.841995)
			(xy 104.349311 -216.802924) (xy 104.390982 -216.769693) (xy 104.43714 -216.743044) (xy 104.486754 -216.723572)
			(xy 104.538716 -216.711712) (xy 104.591866 -216.707729) (xy 104.645016 -216.711712) (xy 104.696978 -216.723572)
			(xy 104.746592 -216.743044) (xy 104.79275 -216.769693) (xy 104.834421 -216.802924) (xy 104.870673 -216.841995)
			(xy 104.900697 -216.886032) (xy 104.923823 -216.934053) (xy 104.939533 -216.984983) (xy 104.947476 -217.037687)
			(xy 104.947974 -217.064336) (xy 104.947476 -217.090985) (xy 104.939533 -217.143689) (xy 104.923823 -217.194619)
			(xy 104.900697 -217.24264) (xy 104.870673 -217.286677) (xy 104.834421 -217.325748) (xy 104.79275 -217.358979)
			(xy 104.746592 -217.385628) (xy 104.696978 -217.4051) (xy 104.645016 -217.41696) (xy 104.591866 -217.420944)
			(xy 104.538716 -217.41696) (xy 104.486754 -217.4051) (xy 104.43714 -217.385628) (xy 104.390982 -217.358979)
			(xy 104.349311 -217.325748) (xy 104.313059 -217.286677) (xy 104.283035 -217.24264) (xy 104.259909 -217.194619)
			(xy 104.244199 -217.143689) (xy 104.236256 -217.090985) (xy 103.980809 -217.090985) (xy 103.973235 -217.13977)
			(xy 103.957886 -217.188079) (xy 103.935325 -217.233471) (xy 103.906084 -217.274876) (xy 103.870852 -217.311319)
			(xy 103.830459 -217.341943) (xy 103.785855 -217.366024) (xy 103.738092 -217.382998) (xy 103.71328 -217.388186)
			(xy 103.69042 -217.392504) (xy 103.485442 -217.747596) (xy 103.493316 -217.76944) (xy 103.501906 -217.795856)
			(xy 103.511095 -217.850633) (xy 103.511604 -217.878406) (xy 103.511096 -217.904293) (xy 103.502997 -217.955431)
			(xy 103.486998 -218.004671) (xy 103.463492 -218.050803) (xy 103.43306 -218.09269) (xy 103.39645 -218.1293)
			(xy 103.354563 -218.159732) (xy 103.308431 -218.183238) (xy 103.259191 -218.199237) (xy 103.208053 -218.207336)
			(xy 103.156279 -218.207336) (xy 103.105141 -218.199237) (xy 103.055901 -218.183238) (xy 103.009769 -218.159732)
			(xy 102.967882 -218.1293) (xy 102.931272 -218.09269) (xy 102.90084 -218.050803) (xy 102.877334 -218.004671)
			(xy 102.861335 -217.955431) (xy 102.853236 -217.904293) (xy 102.852728 -217.878406) (xy 102.571804 -217.878406)
			(xy 102.571274 -217.906114) (xy 102.562072 -217.960759) (xy 102.553516 -217.987118) (xy 102.545642 -218.009216)
			(xy 102.75062 -218.364054) (xy 102.77348 -218.368372) (xy 102.797629 -218.373396) (xy 102.844178 -218.389705)
			(xy 102.887777 -218.412771) (xy 102.92745 -218.442077) (xy 102.962312 -218.47697) (xy 102.991583 -218.516669)
			(xy 103.014611 -218.560287) (xy 103.030879 -218.606851) (xy 103.035862 -218.631008) (xy 103.037994 -218.640297)
			(xy 103.048074 -218.656456) (xy 103.063355 -218.667824) (xy 103.081729 -218.672834) (xy 103.091234 -218.672156)
			(xy 103.130657 -218.66831) (xy 103.209862 -218.667164) (xy 103.288824 -218.673485) (xy 103.366839 -218.687216)
			(xy 103.443213 -218.708237) (xy 103.517267 -218.736359) (xy 103.553006 -218.753436) (xy 103.563674 -218.75877)
			(xy 103.740712 -218.75877) (xy 103.75138 -218.753436) (xy 103.787061 -218.736387) (xy 103.860992 -218.708301)
			(xy 103.937238 -218.687299) (xy 104.015122 -218.673564) (xy 104.093953 -218.66722) (xy 104.173031 -218.668323)
			(xy 104.21239 -218.672156) (xy 104.221892 -218.672762) (xy 104.240245 -218.66774) (xy 104.255524 -218.6564)
			(xy 104.265646 -218.640289) (xy 104.267762 -218.631008) (xy 104.270159 -218.618939) (xy 104.276514 -218.595164)
			(xy 104.280462 -218.58351) (xy 104.288336 -218.561412) (xy 104.083358 -218.206574) (xy 104.060498 -218.202256)
			(xy 104.035697 -218.197058) (xy 103.987958 -218.18007) (xy 103.94338 -218.155978) (xy 103.903014 -218.125348)
			(xy 103.86781 -218.088903) (xy 103.838596 -218.0475) (xy 103.816062 -218.002115) (xy 103.800737 -217.953817)
			(xy 103.792983 -217.903742) (xy 103.792528 -217.878406) (xy 103.793036 -217.852519) (xy 103.801135 -217.801381)
			(xy 103.817134 -217.752141) (xy 103.84064 -217.706009) (xy 103.871072 -217.664122) (xy 103.907682 -217.627512)
			(xy 103.949569 -217.59708) (xy 103.995701 -217.573574) (xy 104.044941 -217.557575) (xy 104.096079 -217.549476)
			(xy 104.147853 -217.549476) (xy 104.198991 -217.557575) (xy 104.248231 -217.573574) (xy 104.294363 -217.59708)
			(xy 104.33625 -217.627512) (xy 104.37286 -217.664122) (xy 104.403292 -217.706009) (xy 104.426798 -217.752141)
			(xy 104.442797 -217.801381) (xy 104.450896 -217.852519) (xy 104.451404 -217.878406) (xy 104.732328 -217.878406)
			(xy 104.732794 -217.853071) (xy 104.740546 -217.802996) (xy 104.755869 -217.754698) (xy 104.778402 -217.709313)
			(xy 104.807614 -217.66791) (xy 104.842817 -217.631464) (xy 104.883182 -217.600835) (xy 104.927759 -217.576742)
			(xy 104.975497 -217.559754) (xy 105.000298 -217.554556) (xy 105.023158 -217.550238) (xy 105.228136 -217.195146)
			(xy 105.220262 -217.173302) (xy 105.211624 -217.146891) (xy 105.202299 -217.092117) (xy 105.20172 -217.064336)
			(xy 105.202228 -217.038429) (xy 105.210334 -216.987252) (xy 105.226346 -216.937973) (xy 105.249869 -216.891806)
			(xy 105.280325 -216.849887) (xy 105.316963 -216.813249) (xy 105.358882 -216.782793) (xy 105.405049 -216.75927)
			(xy 105.454328 -216.743258) (xy 105.505505 -216.735152) (xy 105.557319 -216.735152) (xy 105.608496 -216.743258)
			(xy 105.657775 -216.75927) (xy 105.703942 -216.782793) (xy 105.745861 -216.813249) (xy 105.782499 -216.849887)
			(xy 105.812955 -216.891806) (xy 105.836478 -216.937973) (xy 105.85249 -216.987252) (xy 105.860596 -217.038429)
			(xy 105.861104 -217.064336) (xy 105.860612 -217.08968) (xy 105.860409 -217.090985) (xy 106.115856 -217.090985)
			(xy 106.115856 -217.037687) (xy 106.123799 -216.984983) (xy 106.139509 -216.934053) (xy 106.162635 -216.886032)
			(xy 106.192659 -216.841995) (xy 106.228911 -216.802924) (xy 106.270582 -216.769693) (xy 106.31674 -216.743044)
			(xy 106.366354 -216.723572) (xy 106.418316 -216.711712) (xy 106.471466 -216.707729) (xy 106.524616 -216.711712)
			(xy 106.576578 -216.723572) (xy 106.626192 -216.743044) (xy 106.67235 -216.769693) (xy 106.714021 -216.802924)
			(xy 106.750273 -216.841995) (xy 106.780297 -216.886032) (xy 106.803423 -216.934053) (xy 106.819133 -216.984983)
			(xy 106.827076 -217.037687) (xy 106.827574 -217.064336) (xy 106.827076 -217.090985) (xy 106.819133 -217.143689)
			(xy 106.803423 -217.194619) (xy 106.780297 -217.24264) (xy 106.750273 -217.286677) (xy 106.714021 -217.325748)
			(xy 106.67235 -217.358979) (xy 106.626192 -217.385628) (xy 106.576578 -217.4051) (xy 106.524616 -217.41696)
			(xy 106.471466 -217.420944) (xy 106.418316 -217.41696) (xy 106.366354 -217.4051) (xy 106.31674 -217.385628)
			(xy 106.270582 -217.358979) (xy 106.228911 -217.325748) (xy 106.192659 -217.286677) (xy 106.162635 -217.24264)
			(xy 106.139509 -217.194619) (xy 106.123799 -217.143689) (xy 106.115856 -217.090985) (xy 105.860409 -217.090985)
			(xy 105.852835 -217.13977) (xy 105.837486 -217.188079) (xy 105.814925 -217.233471) (xy 105.785684 -217.274876)
			(xy 105.750452 -217.311319) (xy 105.710059 -217.341943) (xy 105.665455 -217.366024) (xy 105.617692 -217.382998)
			(xy 105.59288 -217.388186) (xy 105.57002 -217.392504) (xy 105.365042 -217.747596) (xy 105.372916 -217.76944)
			(xy 105.381506 -217.795856) (xy 105.390695 -217.850633) (xy 105.391204 -217.878406) (xy 105.672128 -217.878406)
			(xy 105.672636 -217.852519) (xy 105.680735 -217.801381) (xy 105.696734 -217.752141) (xy 105.72024 -217.706009)
			(xy 105.750672 -217.664122) (xy 105.787282 -217.627512) (xy 105.829169 -217.59708) (xy 105.875301 -217.573574)
			(xy 105.924541 -217.557575) (xy 105.975679 -217.549476) (xy 106.027453 -217.549476) (xy 106.078591 -217.557575)
			(xy 106.127831 -217.573574) (xy 106.173963 -217.59708) (xy 106.21585 -217.627512) (xy 106.25246 -217.664122)
			(xy 106.282892 -217.706009) (xy 106.306398 -217.752141) (xy 106.322397 -217.801381) (xy 106.330496 -217.852519)
			(xy 106.331004 -217.878406) (xy 106.611928 -217.878406) (xy 106.612394 -217.853071) (xy 106.620146 -217.802996)
			(xy 106.635469 -217.754698) (xy 106.658002 -217.709313) (xy 106.687214 -217.66791) (xy 106.722417 -217.631464)
			(xy 106.762782 -217.600835) (xy 106.807359 -217.576742) (xy 106.855097 -217.559754) (xy 106.879898 -217.554556)
			(xy 106.902758 -217.550238) (xy 107.107736 -217.195146) (xy 107.099862 -217.173302) (xy 107.091224 -217.146891)
			(xy 107.081899 -217.092117) (xy 107.08132 -217.064336) (xy 107.081828 -217.038429) (xy 107.089934 -216.987252)
			(xy 107.105946 -216.937973) (xy 107.129469 -216.891806) (xy 107.159925 -216.849887) (xy 107.196563 -216.813249)
			(xy 107.238482 -216.782793) (xy 107.284649 -216.75927) (xy 107.333928 -216.743258) (xy 107.385105 -216.735152)
			(xy 107.436919 -216.735152) (xy 107.488096 -216.743258) (xy 107.537375 -216.75927) (xy 107.583542 -216.782793)
			(xy 107.625461 -216.813249) (xy 107.662099 -216.849887) (xy 107.692555 -216.891806) (xy 107.716078 -216.937973)
			(xy 107.73209 -216.987252) (xy 107.740196 -217.038429) (xy 107.740704 -217.064336) (xy 107.740212 -217.08968)
			(xy 107.740009 -217.090985) (xy 107.995456 -217.090985) (xy 107.995456 -217.037687) (xy 108.003399 -216.984983)
			(xy 108.019109 -216.934053) (xy 108.042235 -216.886032) (xy 108.072259 -216.841995) (xy 108.108511 -216.802924)
			(xy 108.150182 -216.769693) (xy 108.19634 -216.743044) (xy 108.245954 -216.723572) (xy 108.297916 -216.711712)
			(xy 108.351066 -216.707729) (xy 108.404216 -216.711712) (xy 108.456178 -216.723572) (xy 108.505792 -216.743044)
			(xy 108.55195 -216.769693) (xy 108.593621 -216.802924) (xy 108.629873 -216.841995) (xy 108.659897 -216.886032)
			(xy 108.683023 -216.934053) (xy 108.698733 -216.984983) (xy 108.706676 -217.037687) (xy 108.707174 -217.064336)
			(xy 108.706676 -217.090985) (xy 108.698733 -217.143689) (xy 108.683023 -217.194619) (xy 108.659897 -217.24264)
			(xy 108.629873 -217.286677) (xy 108.593621 -217.325748) (xy 108.55195 -217.358979) (xy 108.505792 -217.385628)
			(xy 108.456178 -217.4051) (xy 108.404216 -217.41696) (xy 108.351066 -217.420944) (xy 108.297916 -217.41696)
			(xy 108.245954 -217.4051) (xy 108.19634 -217.385628) (xy 108.150182 -217.358979) (xy 108.108511 -217.325748)
			(xy 108.072259 -217.286677) (xy 108.042235 -217.24264) (xy 108.019109 -217.194619) (xy 108.003399 -217.143689)
			(xy 107.995456 -217.090985) (xy 107.740009 -217.090985) (xy 107.732435 -217.13977) (xy 107.717086 -217.188079)
			(xy 107.694525 -217.233471) (xy 107.665284 -217.274876) (xy 107.630052 -217.311319) (xy 107.589659 -217.341943)
			(xy 107.545055 -217.366024) (xy 107.497292 -217.382998) (xy 107.47248 -217.388186) (xy 107.44962 -217.392504)
			(xy 107.244642 -217.747596) (xy 107.252516 -217.76944) (xy 107.261106 -217.795856) (xy 107.270295 -217.850633)
			(xy 107.270804 -217.878406) (xy 107.551728 -217.878406) (xy 107.552236 -217.852519) (xy 107.560335 -217.801381)
			(xy 107.576334 -217.752141) (xy 107.59984 -217.706009) (xy 107.630272 -217.664122) (xy 107.666882 -217.627512)
			(xy 107.708769 -217.59708) (xy 107.754901 -217.573574) (xy 107.804141 -217.557575) (xy 107.855279 -217.549476)
			(xy 107.907053 -217.549476) (xy 107.958191 -217.557575) (xy 108.007431 -217.573574) (xy 108.053563 -217.59708)
			(xy 108.09545 -217.627512) (xy 108.13206 -217.664122) (xy 108.162492 -217.706009) (xy 108.185998 -217.752141)
			(xy 108.201997 -217.801381) (xy 108.210096 -217.852519) (xy 108.210604 -217.878406) (xy 108.491528 -217.878406)
			(xy 108.491994 -217.853071) (xy 108.499746 -217.802996) (xy 108.515069 -217.754698) (xy 108.537602 -217.709313)
			(xy 108.566814 -217.66791) (xy 108.602017 -217.631464) (xy 108.642382 -217.600835) (xy 108.686959 -217.576742)
			(xy 108.734697 -217.559754) (xy 108.759498 -217.554556) (xy 108.782358 -217.550238) (xy 108.987336 -217.195146)
			(xy 108.979462 -217.173302) (xy 108.970824 -217.146891) (xy 108.961499 -217.092117) (xy 108.96092 -217.064336)
			(xy 108.961428 -217.038429) (xy 108.969534 -216.987252) (xy 108.985546 -216.937973) (xy 109.009069 -216.891806)
			(xy 109.039525 -216.849887) (xy 109.076163 -216.813249) (xy 109.118082 -216.782793) (xy 109.164249 -216.75927)
			(xy 109.213528 -216.743258) (xy 109.264705 -216.735152) (xy 109.316519 -216.735152) (xy 109.367696 -216.743258)
			(xy 109.416975 -216.75927) (xy 109.463142 -216.782793) (xy 109.505061 -216.813249) (xy 109.541699 -216.849887)
			(xy 109.572155 -216.891806) (xy 109.595678 -216.937973) (xy 109.61169 -216.987252) (xy 109.619796 -217.038429)
			(xy 109.620304 -217.064336) (xy 109.619812 -217.08968) (xy 109.619609 -217.090985) (xy 109.875056 -217.090985)
			(xy 109.875056 -217.037687) (xy 109.882999 -216.984983) (xy 109.898709 -216.934053) (xy 109.921835 -216.886032)
			(xy 109.951859 -216.841995) (xy 109.988111 -216.802924) (xy 110.029782 -216.769693) (xy 110.07594 -216.743044)
			(xy 110.125554 -216.723572) (xy 110.177516 -216.711712) (xy 110.230666 -216.707729) (xy 110.283816 -216.711712)
			(xy 110.335778 -216.723572) (xy 110.385392 -216.743044) (xy 110.43155 -216.769693) (xy 110.473221 -216.802924)
			(xy 110.509473 -216.841995) (xy 110.539497 -216.886032) (xy 110.562623 -216.934053) (xy 110.578333 -216.984983)
			(xy 110.586276 -217.037687) (xy 110.586774 -217.064336) (xy 110.586276 -217.090985) (xy 110.578333 -217.143689)
			(xy 110.562623 -217.194619) (xy 110.539497 -217.24264) (xy 110.509473 -217.286677) (xy 110.473221 -217.325748)
			(xy 110.43155 -217.358979) (xy 110.385392 -217.385628) (xy 110.335778 -217.4051) (xy 110.283816 -217.41696)
			(xy 110.230666 -217.420944) (xy 110.177516 -217.41696) (xy 110.125554 -217.4051) (xy 110.07594 -217.385628)
			(xy 110.029782 -217.358979) (xy 109.988111 -217.325748) (xy 109.951859 -217.286677) (xy 109.921835 -217.24264)
			(xy 109.898709 -217.194619) (xy 109.882999 -217.143689) (xy 109.875056 -217.090985) (xy 109.619609 -217.090985)
			(xy 109.612035 -217.13977) (xy 109.596686 -217.188079) (xy 109.574125 -217.233471) (xy 109.544884 -217.274876)
			(xy 109.509652 -217.311319) (xy 109.469259 -217.341943) (xy 109.424655 -217.366024) (xy 109.376892 -217.382998)
			(xy 109.35208 -217.388186) (xy 109.32922 -217.392504) (xy 109.124242 -217.747596) (xy 109.132116 -217.76944)
			(xy 109.140706 -217.795856) (xy 109.149895 -217.850633) (xy 109.150404 -217.878406) (xy 109.431328 -217.878406)
			(xy 109.431836 -217.852519) (xy 109.439935 -217.801381) (xy 109.455934 -217.752141) (xy 109.47944 -217.706009)
			(xy 109.509872 -217.664122) (xy 109.546482 -217.627512) (xy 109.588369 -217.59708) (xy 109.634501 -217.573574)
			(xy 109.683741 -217.557575) (xy 109.734879 -217.549476) (xy 109.786653 -217.549476) (xy 109.837791 -217.557575)
			(xy 109.887031 -217.573574) (xy 109.933163 -217.59708) (xy 109.97505 -217.627512) (xy 110.01166 -217.664122)
			(xy 110.042092 -217.706009) (xy 110.065598 -217.752141) (xy 110.081597 -217.801381) (xy 110.089696 -217.852519)
			(xy 110.090204 -217.878406) (xy 110.371128 -217.878406) (xy 110.371594 -217.853071) (xy 110.379346 -217.802996)
			(xy 110.394669 -217.754698) (xy 110.417202 -217.709313) (xy 110.446414 -217.66791) (xy 110.481617 -217.631464)
			(xy 110.521982 -217.600835) (xy 110.566559 -217.576742) (xy 110.614297 -217.559754) (xy 110.639098 -217.554556)
			(xy 110.661958 -217.550238) (xy 110.866936 -217.194892) (xy 110.859316 -217.173048) (xy 110.850741 -217.146694)
			(xy 110.841552 -217.092045) (xy 110.841028 -217.064336) (xy 110.841536 -217.038449) (xy 110.849635 -216.987311)
			(xy 110.865634 -216.938071) (xy 110.88914 -216.891939) (xy 110.919572 -216.850052) (xy 110.956182 -216.813442)
			(xy 110.998069 -216.78301) (xy 111.044201 -216.759504) (xy 111.093441 -216.743505) (xy 111.144579 -216.735406)
			(xy 111.196353 -216.735406) (xy 111.247491 -216.743505) (xy 111.296731 -216.759504) (xy 111.342863 -216.78301)
			(xy 111.38475 -216.813442) (xy 111.42136 -216.850052) (xy 111.451792 -216.891939) (xy 111.475298 -216.938071)
			(xy 111.491297 -216.987311) (xy 111.499396 -217.038449) (xy 111.499904 -217.064336) (xy 111.499412 -217.08968)
			(xy 111.499209 -217.090985) (xy 111.754656 -217.090985) (xy 111.754656 -217.037687) (xy 111.762599 -216.984983)
			(xy 111.778309 -216.934053) (xy 111.801435 -216.886032) (xy 111.831459 -216.841995) (xy 111.867711 -216.802924)
			(xy 111.909382 -216.769693) (xy 111.95554 -216.743044) (xy 112.005154 -216.723572) (xy 112.057116 -216.711712)
			(xy 112.110266 -216.707729) (xy 112.163416 -216.711712) (xy 112.215378 -216.723572) (xy 112.264992 -216.743044)
			(xy 112.31115 -216.769693) (xy 112.352821 -216.802924) (xy 112.389073 -216.841995) (xy 112.419097 -216.886032)
			(xy 112.442223 -216.934053) (xy 112.457933 -216.984983) (xy 112.465876 -217.037687) (xy 112.466374 -217.064336)
			(xy 112.72012 -217.064336) (xy 112.720628 -217.038429) (xy 112.728734 -216.987252) (xy 112.744746 -216.937973)
			(xy 112.768269 -216.891806) (xy 112.798725 -216.849887) (xy 112.835363 -216.813249) (xy 112.877282 -216.782793)
			(xy 112.923449 -216.75927) (xy 112.972728 -216.743258) (xy 113.023905 -216.735152) (xy 113.075719 -216.735152)
			(xy 113.126896 -216.743258) (xy 113.176175 -216.75927) (xy 113.222342 -216.782793) (xy 113.264261 -216.813249)
			(xy 113.300899 -216.849887) (xy 113.331355 -216.891806) (xy 113.354878 -216.937973) (xy 113.37089 -216.987252)
			(xy 113.378996 -217.038429) (xy 113.379504 -217.064336) (xy 113.378911 -217.090985) (xy 113.634256 -217.090985)
			(xy 113.634256 -217.037687) (xy 113.642199 -216.984983) (xy 113.657909 -216.934053) (xy 113.681035 -216.886032)
			(xy 113.711059 -216.841995) (xy 113.747311 -216.802924) (xy 113.788982 -216.769693) (xy 113.83514 -216.743044)
			(xy 113.884754 -216.723572) (xy 113.936716 -216.711712) (xy 113.989866 -216.707729) (xy 114.043016 -216.711712)
			(xy 114.094978 -216.723572) (xy 114.144592 -216.743044) (xy 114.19075 -216.769693) (xy 114.232421 -216.802924)
			(xy 114.268673 -216.841995) (xy 114.298697 -216.886032) (xy 114.321823 -216.934053) (xy 114.337533 -216.984983)
			(xy 114.345476 -217.037687) (xy 114.345974 -217.064336) (xy 114.345476 -217.090985) (xy 114.337533 -217.143689)
			(xy 114.321823 -217.194619) (xy 114.298697 -217.24264) (xy 114.268673 -217.286677) (xy 114.232421 -217.325748)
			(xy 114.19075 -217.358979) (xy 114.144592 -217.385628) (xy 114.094978 -217.4051) (xy 114.043016 -217.41696)
			(xy 113.989866 -217.420944) (xy 113.936716 -217.41696) (xy 113.884754 -217.4051) (xy 113.83514 -217.385628)
			(xy 113.788982 -217.358979) (xy 113.747311 -217.325748) (xy 113.711059 -217.286677) (xy 113.681035 -217.24264)
			(xy 113.657909 -217.194619) (xy 113.642199 -217.143689) (xy 113.634256 -217.090985) (xy 113.378911 -217.090985)
			(xy 113.378889 -217.091989) (xy 113.369569 -217.146507) (xy 113.360962 -217.172794) (xy 113.353342 -217.194892)
			(xy 113.558574 -217.550238) (xy 113.581434 -217.554556) (xy 113.606241 -217.559728) (xy 113.653979 -217.576721)
			(xy 113.698556 -217.600818) (xy 113.73892 -217.631451) (xy 113.774123 -217.6679) (xy 113.803334 -217.709305)
			(xy 113.825866 -217.754693) (xy 113.841189 -217.802993) (xy 113.848941 -217.85307) (xy 113.849404 -217.878406)
			(xy 113.848896 -217.904293) (xy 113.840797 -217.955431) (xy 113.824798 -218.004671) (xy 113.801292 -218.050803)
			(xy 113.77086 -218.09269) (xy 113.73425 -218.1293) (xy 113.692363 -218.159732) (xy 113.646231 -218.183238)
			(xy 113.596991 -218.199237) (xy 113.545853 -218.207336) (xy 113.494079 -218.207336) (xy 113.442941 -218.199237)
			(xy 113.393701 -218.183238) (xy 113.347569 -218.159732) (xy 113.305682 -218.1293) (xy 113.269072 -218.09269)
			(xy 113.23864 -218.050803) (xy 113.215134 -218.004671) (xy 113.199135 -217.955431) (xy 113.191036 -217.904293)
			(xy 113.190528 -217.878406) (xy 113.191062 -217.850698) (xy 113.200255 -217.796051) (xy 113.208816 -217.769694)
			(xy 113.21669 -217.747596) (xy 113.011712 -217.392504) (xy 112.988852 -217.388186) (xy 112.963996 -217.383069)
			(xy 112.916148 -217.366166) (xy 112.871456 -217.342128) (xy 112.830977 -217.311523) (xy 112.795667 -217.275076)
			(xy 112.766361 -217.233647) (xy 112.743752 -217.188215) (xy 112.728374 -217.139855) (xy 112.72059 -217.089709)
			(xy 112.72012 -217.064336) (xy 112.466374 -217.064336) (xy 112.465876 -217.090985) (xy 112.457933 -217.143689)
			(xy 112.442223 -217.194619) (xy 112.419097 -217.24264) (xy 112.389073 -217.286677) (xy 112.352821 -217.325748)
			(xy 112.31115 -217.358979) (xy 112.264992 -217.385628) (xy 112.215378 -217.4051) (xy 112.163416 -217.41696)
			(xy 112.110266 -217.420944) (xy 112.057116 -217.41696) (xy 112.005154 -217.4051) (xy 111.95554 -217.385628)
			(xy 111.909382 -217.358979) (xy 111.867711 -217.325748) (xy 111.831459 -217.286677) (xy 111.801435 -217.24264)
			(xy 111.778309 -217.194619) (xy 111.762599 -217.143689) (xy 111.754656 -217.090985) (xy 111.499209 -217.090985)
			(xy 111.491635 -217.13977) (xy 111.476286 -217.188079) (xy 111.453725 -217.233471) (xy 111.424484 -217.274876)
			(xy 111.389252 -217.311319) (xy 111.348859 -217.341943) (xy 111.304255 -217.366024) (xy 111.256492 -217.382998)
			(xy 111.23168 -217.388186) (xy 111.20882 -217.392504) (xy 111.003842 -217.747596) (xy 111.011716 -217.76944)
			(xy 111.020306 -217.795856) (xy 111.029495 -217.850633) (xy 111.030004 -217.878406) (xy 111.029496 -217.904293)
			(xy 111.029375 -217.905055) (xy 111.284502 -217.905055) (xy 111.284502 -217.851757) (xy 111.292445 -217.799053)
			(xy 111.308155 -217.748123) (xy 111.331281 -217.700102) (xy 111.361305 -217.656065) (xy 111.397557 -217.616994)
			(xy 111.439228 -217.583763) (xy 111.485386 -217.557114) (xy 111.535 -217.537642) (xy 111.586962 -217.525782)
			(xy 111.640112 -217.521799) (xy 111.693262 -217.525782) (xy 111.745224 -217.537642) (xy 111.794838 -217.557114)
			(xy 111.840996 -217.583763) (xy 111.882667 -217.616994) (xy 111.918919 -217.656065) (xy 111.948943 -217.700102)
			(xy 111.972069 -217.748123) (xy 111.987779 -217.799053) (xy 111.995722 -217.851757) (xy 111.99622 -217.878406)
			(xy 111.995722 -217.905055) (xy 111.987779 -217.957759) (xy 111.972069 -218.008689) (xy 111.948943 -218.05671)
			(xy 111.918919 -218.100747) (xy 111.882667 -218.139818) (xy 111.840996 -218.173049) (xy 111.794838 -218.199698)
			(xy 111.745224 -218.21917) (xy 111.693262 -218.23103) (xy 111.640112 -218.235014) (xy 111.586962 -218.23103)
			(xy 111.535 -218.21917) (xy 111.485386 -218.199698) (xy 111.439228 -218.173049) (xy 111.397557 -218.139818)
			(xy 111.361305 -218.100747) (xy 111.331281 -218.05671) (xy 111.308155 -218.008689) (xy 111.292445 -217.957759)
			(xy 111.284502 -217.905055) (xy 111.029375 -217.905055) (xy 111.021397 -217.955431) (xy 111.005398 -218.004671)
			(xy 110.981892 -218.050803) (xy 110.95146 -218.09269) (xy 110.91485 -218.1293) (xy 110.872963 -218.159732)
			(xy 110.826831 -218.183238) (xy 110.777591 -218.199237) (xy 110.726453 -218.207336) (xy 110.674679 -218.207336)
			(xy 110.623541 -218.199237) (xy 110.574301 -218.183238) (xy 110.528169 -218.159732) (xy 110.486282 -218.1293)
			(xy 110.449672 -218.09269) (xy 110.41924 -218.050803) (xy 110.395734 -218.004671) (xy 110.379735 -217.955431)
			(xy 110.371636 -217.904293) (xy 110.371128 -217.878406) (xy 110.090204 -217.878406) (xy 110.089676 -217.906114)
			(xy 110.08048 -217.960761) (xy 110.071916 -217.987118) (xy 110.064296 -218.008962) (xy 110.269274 -218.364054)
			(xy 110.292134 -218.368372) (xy 110.316944 -218.373529) (xy 110.364684 -218.390523) (xy 110.409261 -218.414621)
			(xy 110.449626 -218.445257) (xy 110.484829 -218.481707) (xy 110.51404 -218.523115) (xy 110.536571 -218.568504)
			(xy 110.551892 -218.616807) (xy 110.559642 -218.666885) (xy 110.560104 -218.692222) (xy 110.559596 -218.718109)
			(xy 110.559516 -218.718617) (xy 110.81511 -218.718617) (xy 110.81511 -218.665319) (xy 110.823053 -218.612615)
			(xy 110.838763 -218.561685) (xy 110.861889 -218.513664) (xy 110.891913 -218.469627) (xy 110.928165 -218.430556)
			(xy 110.969836 -218.397325) (xy 111.015994 -218.370676) (xy 111.065608 -218.351204) (xy 111.11757 -218.339344)
			(xy 111.17072 -218.335361) (xy 111.22387 -218.339344) (xy 111.275832 -218.351204) (xy 111.325446 -218.370676)
			(xy 111.371604 -218.397325) (xy 111.413275 -218.430556) (xy 111.449527 -218.469627) (xy 111.479551 -218.513664)
			(xy 111.502677 -218.561685) (xy 111.518387 -218.612615) (xy 111.52633 -218.665319) (xy 111.526828 -218.691968)
			(xy 111.52633 -218.718617) (xy 111.518387 -218.771321) (xy 111.502677 -218.822251) (xy 111.479551 -218.870272)
			(xy 111.449527 -218.914309) (xy 111.413275 -218.95338) (xy 111.371604 -218.986611) (xy 111.325446 -219.01326)
			(xy 111.275832 -219.032732) (xy 111.22387 -219.044592) (xy 111.17072 -219.048576) (xy 111.11757 -219.044592)
			(xy 111.065608 -219.032732) (xy 111.015994 -219.01326) (xy 110.969836 -218.986611) (xy 110.928165 -218.95338)
			(xy 110.891913 -218.914309) (xy 110.861889 -218.870272) (xy 110.838763 -218.822251) (xy 110.823053 -218.771321)
			(xy 110.81511 -218.718617) (xy 110.559516 -218.718617) (xy 110.551497 -218.769247) (xy 110.535498 -218.818487)
			(xy 110.511992 -218.864619) (xy 110.48156 -218.906506) (xy 110.44495 -218.943116) (xy 110.403063 -218.973548)
			(xy 110.356931 -218.997054) (xy 110.307691 -219.013053) (xy 110.256553 -219.021152) (xy 110.204779 -219.021152)
			(xy 110.153641 -219.013053) (xy 110.104401 -218.997054) (xy 110.058269 -218.973548) (xy 110.016382 -218.943116)
			(xy 109.979772 -218.906506) (xy 109.94934 -218.864619) (xy 109.925834 -218.818487) (xy 109.909835 -218.769247)
			(xy 109.901736 -218.718109) (xy 109.901228 -218.692222) (xy 109.901766 -218.664514) (xy 109.910956 -218.609868)
			(xy 109.919516 -218.58351) (xy 109.92739 -218.561412) (xy 109.722412 -218.206574) (xy 109.699552 -218.202256)
			(xy 109.67472 -218.197133) (xy 109.626938 -218.180175) (xy 109.582316 -218.1561) (xy 109.541908 -218.125474)
			(xy 109.506667 -218.089022) (xy 109.477424 -218.047602) (xy 109.45487 -218.002192) (xy 109.439537 -217.953864)
			(xy 109.431786 -217.903757) (xy 109.431328 -217.878406) (xy 109.150404 -217.878406) (xy 109.149896 -217.904293)
			(xy 109.141797 -217.955431) (xy 109.125798 -218.004671) (xy 109.102292 -218.050803) (xy 109.07186 -218.09269)
			(xy 109.03525 -218.1293) (xy 108.993363 -218.159732) (xy 108.947231 -218.183238) (xy 108.897991 -218.199237)
			(xy 108.846853 -218.207336) (xy 108.795079 -218.207336) (xy 108.743941 -218.199237) (xy 108.694701 -218.183238)
			(xy 108.648569 -218.159732) (xy 108.606682 -218.1293) (xy 108.570072 -218.09269) (xy 108.53964 -218.050803)
			(xy 108.516134 -218.004671) (xy 108.500135 -217.955431) (xy 108.492036 -217.904293) (xy 108.491528 -217.878406)
			(xy 108.210604 -217.878406) (xy 108.210076 -217.906114) (xy 108.20088 -217.960761) (xy 108.192316 -217.987118)
			(xy 108.184442 -218.009216) (xy 108.38942 -218.364054) (xy 108.41228 -218.368372) (xy 108.4371 -218.37354)
			(xy 108.484878 -218.390497) (xy 108.529495 -218.41457) (xy 108.5699 -218.44519) (xy 108.60514 -218.481637)
			(xy 108.634384 -218.52305) (xy 108.656942 -218.568452) (xy 108.672281 -218.616773) (xy 108.680041 -218.666873)
			(xy 108.680504 -218.692222) (xy 108.679996 -218.718129) (xy 108.67189 -218.769306) (xy 108.655878 -218.818585)
			(xy 108.632355 -218.864752) (xy 108.601899 -218.906671) (xy 108.565261 -218.943309) (xy 108.523342 -218.973765)
			(xy 108.477175 -218.997288) (xy 108.427896 -219.0133) (xy 108.376719 -219.021406) (xy 108.324905 -219.021406)
			(xy 108.273728 -219.0133) (xy 108.224449 -218.997288) (xy 108.178282 -218.973765) (xy 108.136363 -218.943309)
			(xy 108.099725 -218.906671) (xy 108.069269 -218.864752) (xy 108.045746 -218.818585) (xy 108.029734 -218.769306)
			(xy 108.021628 -218.718129) (xy 108.02112 -218.692222) (xy 108.021718 -218.664505) (xy 108.031039 -218.609858)
			(xy 108.039662 -218.58351) (xy 108.047536 -218.561412) (xy 107.842558 -218.206574) (xy 107.819698 -218.202256)
			(xy 107.794899 -218.197049) (xy 107.747162 -218.180062) (xy 107.702585 -218.15597) (xy 107.66222 -218.125341)
			(xy 107.627017 -218.088897) (xy 107.597804 -218.047495) (xy 107.575271 -218.002112) (xy 107.559946 -217.953814)
			(xy 107.552192 -217.903741) (xy 107.551728 -217.878406) (xy 107.270804 -217.878406) (xy 107.270296 -217.904293)
			(xy 107.262197 -217.955431) (xy 107.246198 -218.004671) (xy 107.222692 -218.050803) (xy 107.19226 -218.09269)
			(xy 107.15565 -218.1293) (xy 107.113763 -218.159732) (xy 107.067631 -218.183238) (xy 107.018391 -218.199237)
			(xy 106.967253 -218.207336) (xy 106.915479 -218.207336) (xy 106.864341 -218.199237) (xy 106.815101 -218.183238)
			(xy 106.768969 -218.159732) (xy 106.727082 -218.1293) (xy 106.690472 -218.09269) (xy 106.66004 -218.050803)
			(xy 106.636534 -218.004671) (xy 106.620535 -217.955431) (xy 106.612436 -217.904293) (xy 106.611928 -217.878406)
			(xy 106.331004 -217.878406) (xy 106.330476 -217.906114) (xy 106.32128 -217.960761) (xy 106.312716 -217.987118)
			(xy 106.304842 -218.009216) (xy 106.50982 -218.364054) (xy 106.53268 -218.368372) (xy 106.5575 -218.37354)
			(xy 106.605278 -218.390497) (xy 106.649895 -218.41457) (xy 106.6903 -218.44519) (xy 106.72554 -218.481637)
			(xy 106.754784 -218.52305) (xy 106.777342 -218.568452) (xy 106.792681 -218.616773) (xy 106.800441 -218.666873)
			(xy 106.800904 -218.692222) (xy 106.800396 -218.718129) (xy 106.79229 -218.769306) (xy 106.776278 -218.818585)
			(xy 106.752755 -218.864752) (xy 106.722299 -218.906671) (xy 106.685661 -218.943309) (xy 106.643742 -218.973765)
			(xy 106.597575 -218.997288) (xy 106.548296 -219.0133) (xy 106.497119 -219.021406) (xy 106.445305 -219.021406)
			(xy 106.394128 -219.0133) (xy 106.344849 -218.997288) (xy 106.298682 -218.973765) (xy 106.256763 -218.943309)
			(xy 106.220125 -218.906671) (xy 106.189669 -218.864752) (xy 106.166146 -218.818585) (xy 106.150134 -218.769306)
			(xy 106.142028 -218.718129) (xy 106.14152 -218.692222) (xy 106.142118 -218.664505) (xy 106.151439 -218.609858)
			(xy 106.160062 -218.58351) (xy 106.167936 -218.561412) (xy 105.962958 -218.206574) (xy 105.940098 -218.202256)
			(xy 105.915299 -218.197049) (xy 105.867562 -218.180062) (xy 105.822985 -218.15597) (xy 105.78262 -218.125341)
			(xy 105.747417 -218.088897) (xy 105.718204 -218.047495) (xy 105.695671 -218.002112) (xy 105.680346 -217.953814)
			(xy 105.672592 -217.903741) (xy 105.672128 -217.878406) (xy 105.391204 -217.878406) (xy 105.390696 -217.904293)
			(xy 105.382597 -217.955431) (xy 105.366598 -218.004671) (xy 105.343092 -218.050803) (xy 105.31266 -218.09269)
			(xy 105.27605 -218.1293) (xy 105.234163 -218.159732) (xy 105.188031 -218.183238) (xy 105.138791 -218.199237)
			(xy 105.087653 -218.207336) (xy 105.035879 -218.207336) (xy 104.984741 -218.199237) (xy 104.935501 -218.183238)
			(xy 104.889369 -218.159732) (xy 104.847482 -218.1293) (xy 104.810872 -218.09269) (xy 104.78044 -218.050803)
			(xy 104.756934 -218.004671) (xy 104.740935 -217.955431) (xy 104.732836 -217.904293) (xy 104.732328 -217.878406)
			(xy 104.451404 -217.878406) (xy 104.450874 -217.906114) (xy 104.441672 -217.960759) (xy 104.433116 -217.987118)
			(xy 104.425242 -218.009216) (xy 104.63022 -218.364054) (xy 104.65308 -218.368372) (xy 104.679355 -218.373888)
			(xy 104.729782 -218.392303) (xy 104.776555 -218.418654) (xy 104.818433 -218.452244) (xy 104.854308 -218.492182)
			(xy 104.883229 -218.537411) (xy 104.90443 -218.586732) (xy 104.917349 -218.638839) (xy 104.920034 -218.665552)
			(xy 104.921615 -218.679451) (xy 104.931388 -218.705651) (xy 104.94792 -218.728204) (xy 104.969963 -218.74541)
			(xy 104.995855 -218.75597) (xy 105.009696 -218.758008) (xy 105.437178 -219.18549) (xy 105.795318 -219.18549)
			(xy 105.817913 -219.171486) (xy 105.866169 -219.14919) (xy 105.917053 -219.133811) (xy 105.96958 -219.125649)
			(xy 106.022732 -219.124862) (xy 106.075478 -219.131464) (xy 106.126796 -219.145327) (xy 106.175691 -219.166184)
			(xy 106.221216 -219.19363) (xy 106.262487 -219.227132) (xy 106.298705 -219.266042) (xy 106.329169 -219.309604)
			(xy 106.341672 -219.333064) (xy 106.355896 -219.36075) (xy 106.587544 -219.36075) (xy 106.601768 -219.333064)
			(xy 106.614066 -219.309898) (xy 106.64406 -219.266872) (xy 106.679663 -219.228358) (xy 106.720205 -219.195083)
			(xy 106.764921 -219.167672) (xy 106.812969 -219.146642) (xy 106.863444 -219.13239) (xy 106.915396 -219.125184)
			(xy 106.94162 -219.124784) (xy 106.969169 -219.125269) (xy 107.023694 -219.133196) (xy 107.076513 -219.148882)
			(xy 107.126526 -219.172001) (xy 107.172695 -219.202072) (xy 107.214059 -219.23847) (xy 107.249759 -219.280439)
			(xy 107.279052 -219.327105) (xy 107.290616 -219.352114) (xy 107.304078 -219.38234) (xy 107.518962 -219.38234)
		)
		(stroke
			(width 0)
			(type solid)
		)
		(fill yes)
		(layer "B.Cu")
		(net "PVCCD_HV_CPU1")
	)
	(gr_poly
		(pts
			(xy 98.773488 -250.039378) (xy 98.783538 -250.028666) (xy 98.797566 -250.002873) (xy 98.803673 -249.974155)
			(xy 98.801354 -249.944886) (xy 98.790801 -249.917487) (xy 98.772886 -249.894225) (xy 98.761296 -249.8852)
			(xy 98.740681 -249.869708) (xy 98.704138 -249.833327) (xy 98.673751 -249.791666) (xy 98.650273 -249.745755)
			(xy 98.634283 -249.696731) (xy 98.626179 -249.645807) (xy 98.62566 -249.620024) (xy 98.626188 -249.593417)
			(xy 98.634815 -249.540907) (xy 98.65183 -249.490487) (xy 98.676784 -249.443486) (xy 98.709018 -249.401146)
			(xy 98.747681 -249.364582) (xy 98.791754 -249.334761) (xy 98.840073 -249.312468) (xy 98.891364 -249.298293)
			(xy 98.91776 -249.294904) (xy 98.963226 -249.290078) (xy 98.963226 -248.322084) (xy 98.918014 -248.317258)
			(xy 98.893008 -248.314092) (xy 98.844318 -248.30106) (xy 98.798205 -248.280712) (xy 98.755759 -248.253531)
			(xy 98.717986 -248.220159) (xy 98.68578 -248.181387) (xy 98.659904 -248.138133) (xy 98.64097 -248.091421)
			(xy 98.629428 -248.042358) (xy 98.625549 -247.992104) (xy 98.629426 -247.94185) (xy 98.640968 -247.892786)
			(xy 98.6599 -247.846074) (xy 98.685775 -247.802819) (xy 98.71798 -247.764047) (xy 98.755752 -247.730674)
			(xy 98.798198 -247.703491) (xy 98.844311 -247.683143) (xy 98.893 -247.67011) (xy 98.918014 -247.667018)
			(xy 98.963226 -247.662192) (xy 98.963226 -246.694452) (xy 98.91776 -246.689626) (xy 98.892743 -246.686476)
			(xy 98.844029 -246.673472) (xy 98.797888 -246.653145) (xy 98.755415 -246.625976) (xy 98.717615 -246.592609)
			(xy 98.685385 -246.553835) (xy 98.659489 -246.510574) (xy 98.64054 -246.46385) (xy 98.628988 -246.414771)
			(xy 98.625107 -246.364501) (xy 98.628988 -246.31423) (xy 98.64054 -246.265152) (xy 98.659488 -246.218428)
			(xy 98.685384 -246.175166) (xy 98.717614 -246.136392) (xy 98.755414 -246.103025) (xy 98.797887 -246.075856)
			(xy 98.844028 -246.055528) (xy 98.892742 -246.042524) (xy 98.91776 -246.039386) (xy 98.963226 -246.03456)
			(xy 98.963226 -245.066566) (xy 98.91776 -245.06174) (xy 98.892742 -245.05859) (xy 98.844026 -245.045586)
			(xy 98.797883 -245.025258) (xy 98.755408 -244.998088) (xy 98.717606 -244.96472) (xy 98.685375 -244.925944)
			(xy 98.659477 -244.882681) (xy 98.640528 -244.835955) (xy 98.628975 -244.786875) (xy 98.625093 -244.736602)
			(xy 98.628974 -244.68633) (xy 98.640526 -244.637249) (xy 98.659475 -244.590523) (xy 98.685372 -244.547259)
			(xy 98.717603 -244.508483) (xy 98.755404 -244.475115) (xy 98.797879 -244.447944) (xy 98.844022 -244.427615)
			(xy 98.892738 -244.414611) (xy 98.91776 -244.4115) (xy 98.963226 -244.406674) (xy 98.963226 -243.438934)
			(xy 98.91776 -243.434108) (xy 98.892745 -243.430958) (xy 98.844033 -243.417955) (xy 98.797895 -243.397628)
			(xy 98.755424 -243.37046) (xy 98.717627 -243.337095) (xy 98.685399 -243.298323) (xy 98.659504 -243.255064)
			(xy 98.640557 -243.208342) (xy 98.629006 -243.159266) (xy 98.625125 -243.108999) (xy 98.629006 -243.058731)
			(xy 98.640558 -243.009655) (xy 98.659505 -242.962934) (xy 98.6854 -242.919675) (xy 98.717628 -242.880903)
			(xy 98.755426 -242.847538) (xy 98.797897 -242.820371) (xy 98.844036 -242.800044) (xy 98.892747 -242.787041)
			(xy 98.91776 -242.783868) (xy 98.963226 -242.779042) (xy 98.963226 -241.811048) (xy 98.91776 -241.806222)
			(xy 98.892744 -241.803072) (xy 98.84403 -241.790068) (xy 98.79789 -241.769741) (xy 98.755417 -241.742572)
			(xy 98.717618 -241.709206) (xy 98.685388 -241.670432) (xy 98.659492 -241.627171) (xy 98.640544 -241.580448)
			(xy 98.628992 -241.53137) (xy 98.625111 -241.4811) (xy 98.628992 -241.43083) (xy 98.640544 -241.381752)
			(xy 98.659492 -241.335029) (xy 98.685388 -241.291768) (xy 98.717617 -241.252995) (xy 98.755416 -241.219628)
			(xy 98.797889 -241.192459) (xy 98.84403 -241.172132) (xy 98.892743 -241.159128) (xy 98.91776 -241.155982)
			(xy 98.963226 -241.151156) (xy 98.963226 -240.183162) (xy 98.91776 -240.178336) (xy 98.892742 -240.175186)
			(xy 98.844027 -240.162182) (xy 98.797885 -240.141854) (xy 98.75541 -240.114684) (xy 98.717609 -240.081317)
			(xy 98.685378 -240.042542) (xy 98.659481 -239.999279) (xy 98.640531 -239.952554) (xy 98.628979 -239.903474)
			(xy 98.625097 -239.853202) (xy 98.628978 -239.80293) (xy 98.64053 -239.75385) (xy 98.659479 -239.707124)
			(xy 98.685376 -239.663861) (xy 98.717606 -239.625086) (xy 98.755407 -239.591718) (xy 98.797882 -239.564547)
			(xy 98.844024 -239.544219) (xy 98.892739 -239.531214) (xy 98.91776 -239.528096) (xy 98.963226 -239.52327)
			(xy 98.963226 -239.15878) (xy 98.946462 -239.142016) (xy 98.936191 -239.132364) (xy 98.911596 -239.11862)
			(xy 98.88418 -239.112126) (xy 98.856033 -239.113379) (xy 98.829302 -239.122283) (xy 98.806025 -239.138159)
			(xy 98.787979 -239.159795) (xy 98.78187 -239.172496) (xy 98.77043 -239.196875) (xy 98.740784 -239.241827)
			(xy 98.704171 -239.281313) (xy 98.661582 -239.314263) (xy 98.614167 -239.339788) (xy 98.563211 -239.357195)
			(xy 98.51009 -239.366016) (xy 98.483166 -239.366552) (xy 98.457467 -239.366071) (xy 98.406702 -239.358021)
			(xy 98.357823 -239.342124) (xy 98.312034 -239.318774) (xy 98.270464 -239.288544) (xy 98.234138 -239.252181)
			(xy 98.203951 -239.210581) (xy 98.180648 -239.164768) (xy 98.164801 -239.115873) (xy 98.156803 -239.0651)
			(xy 98.156268 -239.0394) (xy 98.156725 -239.014295) (xy 98.164397 -238.964674) (xy 98.179562 -238.916808)
			(xy 98.190304 -238.894112) (xy 98.196436 -238.880641) (xy 98.201457 -238.851486) (xy 98.197917 -238.822114)
			(xy 98.186111 -238.794987) (xy 98.16703 -238.772378) (xy 98.142271 -238.756184) (xy 98.113911 -238.74776)
			(xy 98.099118 -238.7473) (xy 96.987614 -238.7473) (xy 96.972817 -238.747759) (xy 96.944444 -238.756159)
			(xy 96.919672 -238.772344) (xy 96.900584 -238.794955) (xy 96.888783 -238.822091) (xy 96.885261 -238.851471)
			(xy 96.890315 -238.880627) (xy 96.896428 -238.894112) (xy 96.907164 -238.916809) (xy 96.922322 -238.964676)
			(xy 96.929991 -239.014296) (xy 96.930464 -239.0394) (xy 96.92996 -239.065088) (xy 96.921923 -239.115831)
			(xy 96.906047 -239.164692) (xy 96.882723 -239.210468) (xy 96.852526 -239.252032) (xy 96.816198 -239.28836)
			(xy 96.774634 -239.318557) (xy 96.728858 -239.341881) (xy 96.679997 -239.357757) (xy 96.629254 -239.365794)
			(xy 96.577878 -239.365794) (xy 96.527135 -239.357757) (xy 96.478274 -239.341881) (xy 96.432498 -239.318557)
			(xy 96.390934 -239.28836) (xy 96.354606 -239.252032) (xy 96.324409 -239.210468) (xy 96.301085 -239.164692)
			(xy 96.285209 -239.115831) (xy 96.277172 -239.065088) (xy 96.276668 -239.0394) (xy 96.277125 -239.014295)
			(xy 96.284797 -238.964674) (xy 96.299962 -238.916808) (xy 96.310704 -238.894112) (xy 96.316836 -238.880641)
			(xy 96.321857 -238.851486) (xy 96.318317 -238.822114) (xy 96.306511 -238.794987) (xy 96.28743 -238.772378)
			(xy 96.262671 -238.756184) (xy 96.234311 -238.74776) (xy 96.219518 -238.7473) (xy 96.047814 -238.7473)
			(xy 96.033017 -238.747759) (xy 96.004644 -238.756159) (xy 95.979872 -238.772344) (xy 95.960784 -238.794955)
			(xy 95.948983 -238.822091) (xy 95.945461 -238.851471) (xy 95.950515 -238.880627) (xy 95.956628 -238.894112)
			(xy 95.967364 -238.916809) (xy 95.982522 -238.964676) (xy 95.990191 -239.014296) (xy 95.990664 -239.0394)
			(xy 95.99016 -239.065088) (xy 95.982123 -239.115831) (xy 95.966247 -239.164692) (xy 95.942923 -239.210468)
			(xy 95.912726 -239.252032) (xy 95.876398 -239.28836) (xy 95.834834 -239.318557) (xy 95.789058 -239.341881)
			(xy 95.740197 -239.357757) (xy 95.689454 -239.365794) (xy 95.638078 -239.365794) (xy 95.587335 -239.357757)
			(xy 95.538474 -239.341881) (xy 95.492698 -239.318557) (xy 95.451134 -239.28836) (xy 95.414806 -239.252032)
			(xy 95.384609 -239.210468) (xy 95.361285 -239.164692) (xy 95.345409 -239.115831) (xy 95.337372 -239.065088)
			(xy 95.336868 -239.0394) (xy 95.337325 -239.014295) (xy 95.344997 -238.964674) (xy 95.360162 -238.916808)
			(xy 95.370904 -238.894112) (xy 95.377036 -238.880641) (xy 95.382057 -238.851486) (xy 95.378517 -238.822114)
			(xy 95.366711 -238.794987) (xy 95.34763 -238.772378) (xy 95.322871 -238.756184) (xy 95.294511 -238.74776)
			(xy 95.279718 -238.7473) (xy 94.168214 -238.7473) (xy 94.153417 -238.747759) (xy 94.125044 -238.756159)
			(xy 94.100272 -238.772344) (xy 94.081184 -238.794955) (xy 94.069383 -238.822091) (xy 94.065861 -238.851471)
			(xy 94.070915 -238.880627) (xy 94.077028 -238.894112) (xy 94.087764 -238.916809) (xy 94.102922 -238.964676)
			(xy 94.110591 -239.014296) (xy 94.111064 -239.0394) (xy 94.11056 -239.065088) (xy 94.102523 -239.115831)
			(xy 94.086647 -239.164692) (xy 94.063323 -239.210468) (xy 94.033126 -239.252032) (xy 93.996798 -239.28836)
			(xy 93.955234 -239.318557) (xy 93.909458 -239.341881) (xy 93.860597 -239.357757) (xy 93.809854 -239.365794)
			(xy 93.758478 -239.365794) (xy 93.707735 -239.357757) (xy 93.658874 -239.341881) (xy 93.613098 -239.318557)
			(xy 93.571534 -239.28836) (xy 93.535206 -239.252032) (xy 93.505009 -239.210468) (xy 93.481685 -239.164692)
			(xy 93.465809 -239.115831) (xy 93.457772 -239.065088) (xy 93.457268 -239.0394) (xy 93.457725 -239.014295)
			(xy 93.465397 -238.964674) (xy 93.480562 -238.916808) (xy 93.491304 -238.894112) (xy 93.497436 -238.880641)
			(xy 93.502457 -238.851486) (xy 93.498917 -238.822114) (xy 93.487111 -238.794987) (xy 93.46803 -238.772378)
			(xy 93.443271 -238.756184) (xy 93.414911 -238.74776) (xy 93.400118 -238.7473) (xy 92.288614 -238.7473)
			(xy 92.273817 -238.747759) (xy 92.245444 -238.756159) (xy 92.220672 -238.772344) (xy 92.201584 -238.794955)
			(xy 92.189783 -238.822091) (xy 92.186261 -238.851471) (xy 92.191315 -238.880627) (xy 92.197428 -238.894112)
			(xy 92.208164 -238.916809) (xy 92.223322 -238.964676) (xy 92.230991 -239.014296) (xy 92.231464 -239.0394)
			(xy 92.23096 -239.065088) (xy 92.222923 -239.115831) (xy 92.207047 -239.164692) (xy 92.183723 -239.210468)
			(xy 92.153526 -239.252032) (xy 92.117198 -239.28836) (xy 92.075634 -239.318557) (xy 92.029858 -239.341881)
			(xy 91.980997 -239.357757) (xy 91.930254 -239.365794) (xy 91.878878 -239.365794) (xy 91.828135 -239.357757)
			(xy 91.779274 -239.341881) (xy 91.733498 -239.318557) (xy 91.691934 -239.28836) (xy 91.655606 -239.252032)
			(xy 91.625409 -239.210468) (xy 91.602085 -239.164692) (xy 91.586209 -239.115831) (xy 91.578172 -239.065088)
			(xy 91.577668 -239.0394) (xy 91.578125 -239.014295) (xy 91.585797 -238.964674) (xy 91.600962 -238.916808)
			(xy 91.611704 -238.894112) (xy 91.617836 -238.880641) (xy 91.622857 -238.851486) (xy 91.619317 -238.822114)
			(xy 91.607511 -238.794987) (xy 91.58843 -238.772378) (xy 91.563671 -238.756184) (xy 91.535311 -238.74776)
			(xy 91.520518 -238.7473) (xy 90.409014 -238.7473) (xy 90.394217 -238.747759) (xy 90.365844 -238.756159)
			(xy 90.341072 -238.772344) (xy 90.321984 -238.794955) (xy 90.310183 -238.822091) (xy 90.306661 -238.851471)
			(xy 90.311715 -238.880627) (xy 90.317828 -238.894112) (xy 90.328564 -238.916809) (xy 90.343722 -238.964676)
			(xy 90.351391 -239.014296) (xy 90.351864 -239.0394) (xy 90.35136 -239.065088) (xy 90.343323 -239.115831)
			(xy 90.327447 -239.164692) (xy 90.304123 -239.210468) (xy 90.273926 -239.252032) (xy 90.237598 -239.28836)
			(xy 90.196034 -239.318557) (xy 90.150258 -239.341881) (xy 90.101397 -239.357757) (xy 90.050654 -239.365794)
			(xy 89.999278 -239.365794) (xy 89.948535 -239.357757) (xy 89.899674 -239.341881) (xy 89.853898 -239.318557)
			(xy 89.812334 -239.28836) (xy 89.776006 -239.252032) (xy 89.745809 -239.210468) (xy 89.722485 -239.164692)
			(xy 89.706609 -239.115831) (xy 89.698572 -239.065088) (xy 89.698068 -239.0394) (xy 89.698525 -239.014295)
			(xy 89.706197 -238.964674) (xy 89.721362 -238.916808) (xy 89.732104 -238.894112) (xy 89.738236 -238.880641)
			(xy 89.743257 -238.851486) (xy 89.739717 -238.822114) (xy 89.727911 -238.794987) (xy 89.70883 -238.772378)
			(xy 89.684071 -238.756184) (xy 89.655711 -238.74776) (xy 89.640918 -238.7473) (xy 89.469214 -238.7473)
			(xy 89.454417 -238.747759) (xy 89.426044 -238.756159) (xy 89.401272 -238.772344) (xy 89.382184 -238.794955)
			(xy 89.370383 -238.822091) (xy 89.366861 -238.851471) (xy 89.371915 -238.880627) (xy 89.378028 -238.894112)
			(xy 89.388764 -238.916809) (xy 89.403922 -238.964676) (xy 89.411591 -239.014296) (xy 89.412064 -239.0394)
			(xy 89.41156 -239.065088) (xy 89.403523 -239.115831) (xy 89.387647 -239.164692) (xy 89.364323 -239.210468)
			(xy 89.334126 -239.252032) (xy 89.297798 -239.28836) (xy 89.256234 -239.318557) (xy 89.210458 -239.341881)
			(xy 89.161597 -239.357757) (xy 89.110854 -239.365794) (xy 89.059478 -239.365794) (xy 89.008735 -239.357757)
			(xy 88.959874 -239.341881) (xy 88.914098 -239.318557) (xy 88.872534 -239.28836) (xy 88.836206 -239.252032)
			(xy 88.806009 -239.210468) (xy 88.782685 -239.164692) (xy 88.766809 -239.115831) (xy 88.758772 -239.065088)
			(xy 88.758268 -239.0394) (xy 88.758725 -239.014295) (xy 88.766397 -238.964674) (xy 88.781562 -238.916808)
			(xy 88.792304 -238.894112) (xy 88.798436 -238.880641) (xy 88.803457 -238.851486) (xy 88.799917 -238.822114)
			(xy 88.788111 -238.794987) (xy 88.76903 -238.772378) (xy 88.744271 -238.756184) (xy 88.715911 -238.74776)
			(xy 88.701118 -238.7473) (xy 87.548466 -238.7473) (xy 86.416842 -239.878924) (xy 91.107764 -239.878924)
			(xy 91.107764 -239.827508) (xy 91.115807 -239.776726) (xy 91.131695 -239.727827) (xy 91.155038 -239.682015)
			(xy 91.185259 -239.640419) (xy 91.221615 -239.604063) (xy 91.263211 -239.573842) (xy 91.309023 -239.550499)
			(xy 91.357922 -239.534611) (xy 91.408704 -239.526568) (xy 91.46012 -239.526568) (xy 91.510902 -239.534611)
			(xy 91.559801 -239.550499) (xy 91.605613 -239.573842) (xy 91.647209 -239.604063) (xy 91.683565 -239.640419)
			(xy 91.713786 -239.682015) (xy 91.737129 -239.727827) (xy 91.753017 -239.776726) (xy 91.76106 -239.827508)
			(xy 91.761564 -239.853216) (xy 91.76106 -239.878924) (xy 92.047564 -239.878924) (xy 92.047564 -239.827508)
			(xy 92.055607 -239.776726) (xy 92.071495 -239.727827) (xy 92.094838 -239.682015) (xy 92.125059 -239.640419)
			(xy 92.161415 -239.604063) (xy 92.203011 -239.573842) (xy 92.248823 -239.550499) (xy 92.297722 -239.534611)
			(xy 92.348504 -239.526568) (xy 92.39992 -239.526568) (xy 92.450702 -239.534611) (xy 92.499601 -239.550499)
			(xy 92.545413 -239.573842) (xy 92.587009 -239.604063) (xy 92.623365 -239.640419) (xy 92.653586 -239.682015)
			(xy 92.676929 -239.727827) (xy 92.692817 -239.776726) (xy 92.70086 -239.827508) (xy 92.701364 -239.853216)
			(xy 92.70086 -239.878924) (xy 92.987364 -239.878924) (xy 92.987364 -239.827508) (xy 92.995407 -239.776726)
			(xy 93.011295 -239.727827) (xy 93.034638 -239.682015) (xy 93.064859 -239.640419) (xy 93.101215 -239.604063)
			(xy 93.142811 -239.573842) (xy 93.188623 -239.550499) (xy 93.237522 -239.534611) (xy 93.288304 -239.526568)
			(xy 93.33972 -239.526568) (xy 93.390502 -239.534611) (xy 93.439401 -239.550499) (xy 93.485213 -239.573842)
			(xy 93.526809 -239.604063) (xy 93.563165 -239.640419) (xy 93.593386 -239.682015) (xy 93.616729 -239.727827)
			(xy 93.632617 -239.776726) (xy 93.64066 -239.827508) (xy 93.641164 -239.853216) (xy 93.64066 -239.878924)
			(xy 93.927164 -239.878924) (xy 93.927164 -239.827508) (xy 93.935207 -239.776726) (xy 93.951095 -239.727827)
			(xy 93.974438 -239.682015) (xy 94.004659 -239.640419) (xy 94.041015 -239.604063) (xy 94.082611 -239.573842)
			(xy 94.128423 -239.550499) (xy 94.177322 -239.534611) (xy 94.228104 -239.526568) (xy 94.27952 -239.526568)
			(xy 94.330302 -239.534611) (xy 94.379201 -239.550499) (xy 94.425013 -239.573842) (xy 94.466609 -239.604063)
			(xy 94.502965 -239.640419) (xy 94.533186 -239.682015) (xy 94.556529 -239.727827) (xy 94.572417 -239.776726)
			(xy 94.58046 -239.827508) (xy 94.580964 -239.853216) (xy 94.58046 -239.878924) (xy 97.686364 -239.878924)
			(xy 97.686364 -239.827508) (xy 97.694407 -239.776726) (xy 97.710295 -239.727827) (xy 97.733638 -239.682015)
			(xy 97.763859 -239.640419) (xy 97.800215 -239.604063) (xy 97.841811 -239.573842) (xy 97.887623 -239.550499)
			(xy 97.936522 -239.534611) (xy 97.987304 -239.526568) (xy 98.03872 -239.526568) (xy 98.089502 -239.534611)
			(xy 98.138401 -239.550499) (xy 98.184213 -239.573842) (xy 98.225809 -239.604063) (xy 98.262165 -239.640419)
			(xy 98.292386 -239.682015) (xy 98.315729 -239.727827) (xy 98.331617 -239.776726) (xy 98.33966 -239.827508)
			(xy 98.340164 -239.853216) (xy 98.33966 -239.878924) (xy 98.331617 -239.929706) (xy 98.315729 -239.978605)
			(xy 98.292386 -240.024417) (xy 98.262165 -240.066013) (xy 98.225809 -240.102369) (xy 98.184213 -240.13259)
			(xy 98.138401 -240.155933) (xy 98.089502 -240.171821) (xy 98.03872 -240.179864) (xy 97.987304 -240.179864)
			(xy 97.936522 -240.171821) (xy 97.887623 -240.155933) (xy 97.841811 -240.13259) (xy 97.800215 -240.102369)
			(xy 97.763859 -240.066013) (xy 97.733638 -240.024417) (xy 97.710295 -239.978605) (xy 97.694407 -239.929706)
			(xy 97.686364 -239.878924) (xy 94.58046 -239.878924) (xy 94.572417 -239.929706) (xy 94.556529 -239.978605)
			(xy 94.533186 -240.024417) (xy 94.502965 -240.066013) (xy 94.466609 -240.102369) (xy 94.425013 -240.13259)
			(xy 94.379201 -240.155933) (xy 94.330302 -240.171821) (xy 94.27952 -240.179864) (xy 94.228104 -240.179864)
			(xy 94.177322 -240.171821) (xy 94.128423 -240.155933) (xy 94.082611 -240.13259) (xy 94.041015 -240.102369)
			(xy 94.004659 -240.066013) (xy 93.974438 -240.024417) (xy 93.951095 -239.978605) (xy 93.935207 -239.929706)
			(xy 93.927164 -239.878924) (xy 93.64066 -239.878924) (xy 93.632617 -239.929706) (xy 93.616729 -239.978605)
			(xy 93.593386 -240.024417) (xy 93.563165 -240.066013) (xy 93.526809 -240.102369) (xy 93.485213 -240.13259)
			(xy 93.439401 -240.155933) (xy 93.390502 -240.171821) (xy 93.33972 -240.179864) (xy 93.288304 -240.179864)
			(xy 93.237522 -240.171821) (xy 93.188623 -240.155933) (xy 93.142811 -240.13259) (xy 93.101215 -240.102369)
			(xy 93.064859 -240.066013) (xy 93.034638 -240.024417) (xy 93.011295 -239.978605) (xy 92.995407 -239.929706)
			(xy 92.987364 -239.878924) (xy 92.70086 -239.878924) (xy 92.692817 -239.929706) (xy 92.676929 -239.978605)
			(xy 92.653586 -240.024417) (xy 92.623365 -240.066013) (xy 92.587009 -240.102369) (xy 92.545413 -240.13259)
			(xy 92.499601 -240.155933) (xy 92.450702 -240.171821) (xy 92.39992 -240.179864) (xy 92.348504 -240.179864)
			(xy 92.297722 -240.171821) (xy 92.248823 -240.155933) (xy 92.203011 -240.13259) (xy 92.161415 -240.102369)
			(xy 92.125059 -240.066013) (xy 92.094838 -240.024417) (xy 92.071495 -239.978605) (xy 92.055607 -239.929706)
			(xy 92.047564 -239.878924) (xy 91.76106 -239.878924) (xy 91.753017 -239.929706) (xy 91.737129 -239.978605)
			(xy 91.713786 -240.024417) (xy 91.683565 -240.066013) (xy 91.647209 -240.102369) (xy 91.605613 -240.13259)
			(xy 91.559801 -240.155933) (xy 91.510902 -240.171821) (xy 91.46012 -240.179864) (xy 91.408704 -240.179864)
			(xy 91.357922 -240.171821) (xy 91.309023 -240.155933) (xy 91.263211 -240.13259) (xy 91.221615 -240.102369)
			(xy 91.185259 -240.066013) (xy 91.155038 -240.024417) (xy 91.131695 -239.978605) (xy 91.115807 -239.929706)
			(xy 91.107764 -239.878924) (xy 86.416842 -239.878924) (xy 85.602772 -240.692994) (xy 88.758518 -240.692994)
			(xy 88.758518 -240.641578) (xy 88.766561 -240.590796) (xy 88.782449 -240.541897) (xy 88.805792 -240.496085)
			(xy 88.836013 -240.454489) (xy 88.872369 -240.418133) (xy 88.913965 -240.387912) (xy 88.959777 -240.364569)
			(xy 89.008676 -240.348681) (xy 89.059458 -240.340638) (xy 89.110874 -240.340638) (xy 89.161656 -240.348681)
			(xy 89.210555 -240.364569) (xy 89.256367 -240.387912) (xy 89.297963 -240.418133) (xy 89.334319 -240.454489)
			(xy 89.36454 -240.496085) (xy 89.387883 -240.541897) (xy 89.403771 -240.590796) (xy 89.411814 -240.641578)
			(xy 89.412318 -240.667286) (xy 89.411814 -240.692994) (xy 89.698318 -240.692994) (xy 89.698318 -240.641578)
			(xy 89.706361 -240.590796) (xy 89.722249 -240.541897) (xy 89.745592 -240.496085) (xy 89.775813 -240.454489)
			(xy 89.812169 -240.418133) (xy 89.853765 -240.387912) (xy 89.899577 -240.364569) (xy 89.948476 -240.348681)
			(xy 89.999258 -240.340638) (xy 90.050674 -240.340638) (xy 90.101456 -240.348681) (xy 90.150355 -240.364569)
			(xy 90.196167 -240.387912) (xy 90.237763 -240.418133) (xy 90.274119 -240.454489) (xy 90.30434 -240.496085)
			(xy 90.327683 -240.541897) (xy 90.343571 -240.590796) (xy 90.351614 -240.641578) (xy 90.352118 -240.667286)
			(xy 90.351614 -240.692994) (xy 91.577918 -240.692994) (xy 91.577918 -240.641578) (xy 91.585961 -240.590796)
			(xy 91.601849 -240.541897) (xy 91.625192 -240.496085) (xy 91.655413 -240.454489) (xy 91.691769 -240.418133)
			(xy 91.733365 -240.387912) (xy 91.779177 -240.364569) (xy 91.828076 -240.348681) (xy 91.878858 -240.340638)
			(xy 91.930274 -240.340638) (xy 91.981056 -240.348681) (xy 92.029955 -240.364569) (xy 92.075767 -240.387912)
			(xy 92.117363 -240.418133) (xy 92.153719 -240.454489) (xy 92.18394 -240.496085) (xy 92.207283 -240.541897)
			(xy 92.223171 -240.590796) (xy 92.231214 -240.641578) (xy 92.231718 -240.667286) (xy 92.231214 -240.692994)
			(xy 93.457518 -240.692994) (xy 93.457518 -240.641578) (xy 93.465561 -240.590796) (xy 93.481449 -240.541897)
			(xy 93.504792 -240.496085) (xy 93.535013 -240.454489) (xy 93.571369 -240.418133) (xy 93.612965 -240.387912)
			(xy 93.658777 -240.364569) (xy 93.707676 -240.348681) (xy 93.758458 -240.340638) (xy 93.809874 -240.340638)
			(xy 93.860656 -240.348681) (xy 93.909555 -240.364569) (xy 93.955367 -240.387912) (xy 93.996963 -240.418133)
			(xy 94.033319 -240.454489) (xy 94.06354 -240.496085) (xy 94.086883 -240.541897) (xy 94.102771 -240.590796)
			(xy 94.110814 -240.641578) (xy 94.111318 -240.667286) (xy 94.110814 -240.692994) (xy 95.337118 -240.692994)
			(xy 95.337118 -240.641578) (xy 95.345161 -240.590796) (xy 95.361049 -240.541897) (xy 95.384392 -240.496085)
			(xy 95.414613 -240.454489) (xy 95.450969 -240.418133) (xy 95.492565 -240.387912) (xy 95.538377 -240.364569)
			(xy 95.587276 -240.348681) (xy 95.638058 -240.340638) (xy 95.689474 -240.340638) (xy 95.740256 -240.348681)
			(xy 95.789155 -240.364569) (xy 95.834967 -240.387912) (xy 95.876563 -240.418133) (xy 95.912919 -240.454489)
			(xy 95.94314 -240.496085) (xy 95.966483 -240.541897) (xy 95.982371 -240.590796) (xy 95.990414 -240.641578)
			(xy 95.990918 -240.667286) (xy 95.990414 -240.692994) (xy 96.276918 -240.692994) (xy 96.276918 -240.641578)
			(xy 96.284961 -240.590796) (xy 96.300849 -240.541897) (xy 96.324192 -240.496085) (xy 96.354413 -240.454489)
			(xy 96.390769 -240.418133) (xy 96.432365 -240.387912) (xy 96.478177 -240.364569) (xy 96.527076 -240.348681)
			(xy 96.577858 -240.340638) (xy 96.629274 -240.340638) (xy 96.680056 -240.348681) (xy 96.728955 -240.364569)
			(xy 96.774767 -240.387912) (xy 96.816363 -240.418133) (xy 96.852719 -240.454489) (xy 96.88294 -240.496085)
			(xy 96.906283 -240.541897) (xy 96.922171 -240.590796) (xy 96.930214 -240.641578) (xy 96.930718 -240.667286)
			(xy 96.930214 -240.692994) (xy 98.156518 -240.692994) (xy 98.156518 -240.641578) (xy 98.164561 -240.590796)
			(xy 98.180449 -240.541897) (xy 98.203792 -240.496085) (xy 98.234013 -240.454489) (xy 98.270369 -240.418133)
			(xy 98.311965 -240.387912) (xy 98.357777 -240.364569) (xy 98.406676 -240.348681) (xy 98.457458 -240.340638)
			(xy 98.508874 -240.340638) (xy 98.559656 -240.348681) (xy 98.608555 -240.364569) (xy 98.654367 -240.387912)
			(xy 98.695963 -240.418133) (xy 98.732319 -240.454489) (xy 98.76254 -240.496085) (xy 98.785883 -240.541897)
			(xy 98.801771 -240.590796) (xy 98.809814 -240.641578) (xy 98.810318 -240.667286) (xy 98.809814 -240.692994)
			(xy 98.801771 -240.743776) (xy 98.785883 -240.792675) (xy 98.76254 -240.838487) (xy 98.732319 -240.880083)
			(xy 98.695963 -240.916439) (xy 98.654367 -240.94666) (xy 98.608555 -240.970003) (xy 98.559656 -240.985891)
			(xy 98.508874 -240.993934) (xy 98.457458 -240.993934) (xy 98.406676 -240.985891) (xy 98.357777 -240.970003)
			(xy 98.311965 -240.94666) (xy 98.270369 -240.916439) (xy 98.234013 -240.880083) (xy 98.203792 -240.838487)
			(xy 98.180449 -240.792675) (xy 98.164561 -240.743776) (xy 98.156518 -240.692994) (xy 96.930214 -240.692994)
			(xy 96.922171 -240.743776) (xy 96.906283 -240.792675) (xy 96.88294 -240.838487) (xy 96.852719 -240.880083)
			(xy 96.816363 -240.916439) (xy 96.774767 -240.94666) (xy 96.728955 -240.970003) (xy 96.680056 -240.985891)
			(xy 96.629274 -240.993934) (xy 96.577858 -240.993934) (xy 96.527076 -240.985891) (xy 96.478177 -240.970003)
			(xy 96.432365 -240.94666) (xy 96.390769 -240.916439) (xy 96.354413 -240.880083) (xy 96.324192 -240.838487)
			(xy 96.300849 -240.792675) (xy 96.284961 -240.743776) (xy 96.276918 -240.692994) (xy 95.990414 -240.692994)
			(xy 95.982371 -240.743776) (xy 95.966483 -240.792675) (xy 95.94314 -240.838487) (xy 95.912919 -240.880083)
			(xy 95.876563 -240.916439) (xy 95.834967 -240.94666) (xy 95.789155 -240.970003) (xy 95.740256 -240.985891)
			(xy 95.689474 -240.993934) (xy 95.638058 -240.993934) (xy 95.587276 -240.985891) (xy 95.538377 -240.970003)
			(xy 95.492565 -240.94666) (xy 95.450969 -240.916439) (xy 95.414613 -240.880083) (xy 95.384392 -240.838487)
			(xy 95.361049 -240.792675) (xy 95.345161 -240.743776) (xy 95.337118 -240.692994) (xy 94.110814 -240.692994)
			(xy 94.102771 -240.743776) (xy 94.086883 -240.792675) (xy 94.06354 -240.838487) (xy 94.033319 -240.880083)
			(xy 93.996963 -240.916439) (xy 93.955367 -240.94666) (xy 93.909555 -240.970003) (xy 93.860656 -240.985891)
			(xy 93.809874 -240.993934) (xy 93.758458 -240.993934) (xy 93.707676 -240.985891) (xy 93.658777 -240.970003)
			(xy 93.612965 -240.94666) (xy 93.571369 -240.916439) (xy 93.535013 -240.880083) (xy 93.504792 -240.838487)
			(xy 93.481449 -240.792675) (xy 93.465561 -240.743776) (xy 93.457518 -240.692994) (xy 92.231214 -240.692994)
			(xy 92.223171 -240.743776) (xy 92.207283 -240.792675) (xy 92.18394 -240.838487) (xy 92.153719 -240.880083)
			(xy 92.117363 -240.916439) (xy 92.075767 -240.94666) (xy 92.029955 -240.970003) (xy 91.981056 -240.985891)
			(xy 91.930274 -240.993934) (xy 91.878858 -240.993934) (xy 91.828076 -240.985891) (xy 91.779177 -240.970003)
			(xy 91.733365 -240.94666) (xy 91.691769 -240.916439) (xy 91.655413 -240.880083) (xy 91.625192 -240.838487)
			(xy 91.601849 -240.792675) (xy 91.585961 -240.743776) (xy 91.577918 -240.692994) (xy 90.351614 -240.692994)
			(xy 90.343571 -240.743776) (xy 90.327683 -240.792675) (xy 90.30434 -240.838487) (xy 90.274119 -240.880083)
			(xy 90.237763 -240.916439) (xy 90.196167 -240.94666) (xy 90.150355 -240.970003) (xy 90.101456 -240.985891)
			(xy 90.050674 -240.993934) (xy 89.999258 -240.993934) (xy 89.948476 -240.985891) (xy 89.899577 -240.970003)
			(xy 89.853765 -240.94666) (xy 89.812169 -240.916439) (xy 89.775813 -240.880083) (xy 89.745592 -240.838487)
			(xy 89.722249 -240.792675) (xy 89.706361 -240.743776) (xy 89.698318 -240.692994) (xy 89.411814 -240.692994)
			(xy 89.403771 -240.743776) (xy 89.387883 -240.792675) (xy 89.36454 -240.838487) (xy 89.334319 -240.880083)
			(xy 89.297963 -240.916439) (xy 89.256367 -240.94666) (xy 89.210555 -240.970003) (xy 89.161656 -240.985891)
			(xy 89.110874 -240.993934) (xy 89.059458 -240.993934) (xy 89.008676 -240.985891) (xy 88.959777 -240.970003)
			(xy 88.913965 -240.94666) (xy 88.872369 -240.916439) (xy 88.836013 -240.880083) (xy 88.805792 -240.838487)
			(xy 88.782449 -240.792675) (xy 88.766561 -240.743776) (xy 88.758518 -240.692994) (xy 85.602772 -240.692994)
			(xy 85.310726 -240.98504) (xy 83.385406 -240.98504) (xy 82.863636 -241.50681) (xy 88.288364 -241.50681)
			(xy 88.288364 -241.455394) (xy 88.296407 -241.404612) (xy 88.312295 -241.355713) (xy 88.335638 -241.309901)
			(xy 88.365859 -241.268305) (xy 88.402215 -241.231949) (xy 88.443811 -241.201728) (xy 88.489623 -241.178385)
			(xy 88.538522 -241.162497) (xy 88.589304 -241.154454) (xy 88.64072 -241.154454) (xy 88.691502 -241.162497)
			(xy 88.740401 -241.178385) (xy 88.786213 -241.201728) (xy 88.827809 -241.231949) (xy 88.864165 -241.268305)
			(xy 88.894386 -241.309901) (xy 88.917729 -241.355713) (xy 88.933617 -241.404612) (xy 88.94166 -241.455394)
			(xy 88.942164 -241.481102) (xy 88.94166 -241.50681) (xy 90.167964 -241.50681) (xy 90.167964 -241.455394)
			(xy 90.176007 -241.404612) (xy 90.191895 -241.355713) (xy 90.215238 -241.309901) (xy 90.245459 -241.268305)
			(xy 90.281815 -241.231949) (xy 90.323411 -241.201728) (xy 90.369223 -241.178385) (xy 90.418122 -241.162497)
			(xy 90.468904 -241.154454) (xy 90.52032 -241.154454) (xy 90.571102 -241.162497) (xy 90.620001 -241.178385)
			(xy 90.665813 -241.201728) (xy 90.707409 -241.231949) (xy 90.743765 -241.268305) (xy 90.773986 -241.309901)
			(xy 90.797329 -241.355713) (xy 90.813217 -241.404612) (xy 90.82126 -241.455394) (xy 90.821764 -241.481102)
			(xy 90.82126 -241.50681) (xy 92.047564 -241.50681) (xy 92.047564 -241.455394) (xy 92.055607 -241.404612)
			(xy 92.071495 -241.355713) (xy 92.094838 -241.309901) (xy 92.125059 -241.268305) (xy 92.161415 -241.231949)
			(xy 92.203011 -241.201728) (xy 92.248823 -241.178385) (xy 92.297722 -241.162497) (xy 92.348504 -241.154454)
			(xy 92.39992 -241.154454) (xy 92.450702 -241.162497) (xy 92.499601 -241.178385) (xy 92.545413 -241.201728)
			(xy 92.587009 -241.231949) (xy 92.623365 -241.268305) (xy 92.653586 -241.309901) (xy 92.676929 -241.355713)
			(xy 92.692817 -241.404612) (xy 92.70086 -241.455394) (xy 92.701364 -241.481102) (xy 92.70086 -241.50681)
			(xy 92.987364 -241.50681) (xy 92.987364 -241.455394) (xy 92.995407 -241.404612) (xy 93.011295 -241.355713)
			(xy 93.034638 -241.309901) (xy 93.064859 -241.268305) (xy 93.101215 -241.231949) (xy 93.142811 -241.201728)
			(xy 93.188623 -241.178385) (xy 93.237522 -241.162497) (xy 93.288304 -241.154454) (xy 93.33972 -241.154454)
			(xy 93.390502 -241.162497) (xy 93.439401 -241.178385) (xy 93.485213 -241.201728) (xy 93.526809 -241.231949)
			(xy 93.563165 -241.268305) (xy 93.593386 -241.309901) (xy 93.616729 -241.355713) (xy 93.632617 -241.404612)
			(xy 93.64066 -241.455394) (xy 93.641164 -241.481102) (xy 93.64066 -241.50681) (xy 94.866964 -241.50681)
			(xy 94.866964 -241.455394) (xy 94.875007 -241.404612) (xy 94.890895 -241.355713) (xy 94.914238 -241.309901)
			(xy 94.944459 -241.268305) (xy 94.980815 -241.231949) (xy 95.022411 -241.201728) (xy 95.068223 -241.178385)
			(xy 95.117122 -241.162497) (xy 95.167904 -241.154454) (xy 95.21932 -241.154454) (xy 95.270102 -241.162497)
			(xy 95.319001 -241.178385) (xy 95.364813 -241.201728) (xy 95.406409 -241.231949) (xy 95.442765 -241.268305)
			(xy 95.472986 -241.309901) (xy 95.496329 -241.355713) (xy 95.512217 -241.404612) (xy 95.52026 -241.455394)
			(xy 95.520764 -241.481102) (xy 95.52026 -241.50681) (xy 96.746564 -241.50681) (xy 96.746564 -241.455394)
			(xy 96.754607 -241.404612) (xy 96.770495 -241.355713) (xy 96.793838 -241.309901) (xy 96.824059 -241.268305)
			(xy 96.860415 -241.231949) (xy 96.902011 -241.201728) (xy 96.947823 -241.178385) (xy 96.996722 -241.162497)
			(xy 97.047504 -241.154454) (xy 97.09892 -241.154454) (xy 97.149702 -241.162497) (xy 97.198601 -241.178385)
			(xy 97.244413 -241.201728) (xy 97.286009 -241.231949) (xy 97.322365 -241.268305) (xy 97.352586 -241.309901)
			(xy 97.375929 -241.355713) (xy 97.391817 -241.404612) (xy 97.39986 -241.455394) (xy 97.400364 -241.481102)
			(xy 97.39986 -241.50681) (xy 97.391817 -241.557592) (xy 97.375929 -241.606491) (xy 97.352586 -241.652303)
			(xy 97.322365 -241.693899) (xy 97.286009 -241.730255) (xy 97.244413 -241.760476) (xy 97.198601 -241.783819)
			(xy 97.149702 -241.799707) (xy 97.09892 -241.80775) (xy 97.047504 -241.80775) (xy 96.996722 -241.799707)
			(xy 96.947823 -241.783819) (xy 96.902011 -241.760476) (xy 96.860415 -241.730255) (xy 96.824059 -241.693899)
			(xy 96.793838 -241.652303) (xy 96.770495 -241.606491) (xy 96.754607 -241.557592) (xy 96.746564 -241.50681)
			(xy 95.52026 -241.50681) (xy 95.512217 -241.557592) (xy 95.496329 -241.606491) (xy 95.472986 -241.652303)
			(xy 95.442765 -241.693899) (xy 95.406409 -241.730255) (xy 95.364813 -241.760476) (xy 95.319001 -241.783819)
			(xy 95.270102 -241.799707) (xy 95.21932 -241.80775) (xy 95.167904 -241.80775) (xy 95.117122 -241.799707)
			(xy 95.068223 -241.783819) (xy 95.022411 -241.760476) (xy 94.980815 -241.730255) (xy 94.944459 -241.693899)
			(xy 94.914238 -241.652303) (xy 94.890895 -241.606491) (xy 94.875007 -241.557592) (xy 94.866964 -241.50681)
			(xy 93.64066 -241.50681) (xy 93.632617 -241.557592) (xy 93.616729 -241.606491) (xy 93.593386 -241.652303)
			(xy 93.563165 -241.693899) (xy 93.526809 -241.730255) (xy 93.485213 -241.760476) (xy 93.439401 -241.783819)
			(xy 93.390502 -241.799707) (xy 93.33972 -241.80775) (xy 93.288304 -241.80775) (xy 93.237522 -241.799707)
			(xy 93.188623 -241.783819) (xy 93.142811 -241.760476) (xy 93.101215 -241.730255) (xy 93.064859 -241.693899)
			(xy 93.034638 -241.652303) (xy 93.011295 -241.606491) (xy 92.995407 -241.557592) (xy 92.987364 -241.50681)
			(xy 92.70086 -241.50681) (xy 92.692817 -241.557592) (xy 92.676929 -241.606491) (xy 92.653586 -241.652303)
			(xy 92.623365 -241.693899) (xy 92.587009 -241.730255) (xy 92.545413 -241.760476) (xy 92.499601 -241.783819)
			(xy 92.450702 -241.799707) (xy 92.39992 -241.80775) (xy 92.348504 -241.80775) (xy 92.297722 -241.799707)
			(xy 92.248823 -241.783819) (xy 92.203011 -241.760476) (xy 92.161415 -241.730255) (xy 92.125059 -241.693899)
			(xy 92.094838 -241.652303) (xy 92.071495 -241.606491) (xy 92.055607 -241.557592) (xy 92.047564 -241.50681)
			(xy 90.82126 -241.50681) (xy 90.813217 -241.557592) (xy 90.797329 -241.606491) (xy 90.773986 -241.652303)
			(xy 90.743765 -241.693899) (xy 90.707409 -241.730255) (xy 90.665813 -241.760476) (xy 90.620001 -241.783819)
			(xy 90.571102 -241.799707) (xy 90.52032 -241.80775) (xy 90.468904 -241.80775) (xy 90.418122 -241.799707)
			(xy 90.369223 -241.783819) (xy 90.323411 -241.760476) (xy 90.281815 -241.730255) (xy 90.245459 -241.693899)
			(xy 90.215238 -241.652303) (xy 90.191895 -241.606491) (xy 90.176007 -241.557592) (xy 90.167964 -241.50681)
			(xy 88.94166 -241.50681) (xy 88.933617 -241.557592) (xy 88.917729 -241.606491) (xy 88.894386 -241.652303)
			(xy 88.864165 -241.693899) (xy 88.827809 -241.730255) (xy 88.786213 -241.760476) (xy 88.740401 -241.783819)
			(xy 88.691502 -241.799707) (xy 88.64072 -241.80775) (xy 88.589304 -241.80775) (xy 88.538522 -241.799707)
			(xy 88.489623 -241.783819) (xy 88.443811 -241.760476) (xy 88.402215 -241.730255) (xy 88.365859 -241.693899)
			(xy 88.335638 -241.652303) (xy 88.312295 -241.606491) (xy 88.296407 -241.557592) (xy 88.288364 -241.50681)
			(xy 82.863636 -241.50681) (xy 82.732626 -241.63782) (xy 82.732626 -242.320626) (xy 87.818972 -242.320626)
			(xy 87.818972 -242.26921) (xy 87.827015 -242.218428) (xy 87.842903 -242.169529) (xy 87.866246 -242.123717)
			(xy 87.896467 -242.082121) (xy 87.932823 -242.045765) (xy 87.974419 -242.015544) (xy 88.020231 -241.992201)
			(xy 88.06913 -241.976313) (xy 88.119912 -241.96827) (xy 88.171328 -241.96827) (xy 88.22211 -241.976313)
			(xy 88.271009 -241.992201) (xy 88.316821 -242.015544) (xy 88.358417 -242.045765) (xy 88.394773 -242.082121)
			(xy 88.424994 -242.123717) (xy 88.448337 -242.169529) (xy 88.464225 -242.218428) (xy 88.472268 -242.26921)
			(xy 88.472772 -242.294918) (xy 88.472268 -242.320626) (xy 88.758518 -242.320626) (xy 88.758518 -242.26921)
			(xy 88.766561 -242.218428) (xy 88.782449 -242.169529) (xy 88.805792 -242.123717) (xy 88.836013 -242.082121)
			(xy 88.872369 -242.045765) (xy 88.913965 -242.015544) (xy 88.959777 -241.992201) (xy 89.008676 -241.976313)
			(xy 89.059458 -241.96827) (xy 89.110874 -241.96827) (xy 89.161656 -241.976313) (xy 89.210555 -241.992201)
			(xy 89.256367 -242.015544) (xy 89.297963 -242.045765) (xy 89.334319 -242.082121) (xy 89.36454 -242.123717)
			(xy 89.387883 -242.169529) (xy 89.403771 -242.218428) (xy 89.411814 -242.26921) (xy 89.412318 -242.294918)
			(xy 89.411814 -242.320626) (xy 89.698318 -242.320626) (xy 89.698318 -242.26921) (xy 89.706361 -242.218428)
			(xy 89.722249 -242.169529) (xy 89.745592 -242.123717) (xy 89.775813 -242.082121) (xy 89.812169 -242.045765)
			(xy 89.853765 -242.015544) (xy 89.899577 -241.992201) (xy 89.948476 -241.976313) (xy 89.999258 -241.96827)
			(xy 90.050674 -241.96827) (xy 90.101456 -241.976313) (xy 90.150355 -241.992201) (xy 90.196167 -242.015544)
			(xy 90.237763 -242.045765) (xy 90.274119 -242.082121) (xy 90.30434 -242.123717) (xy 90.327683 -242.169529)
			(xy 90.343571 -242.218428) (xy 90.351614 -242.26921) (xy 90.352118 -242.294918) (xy 90.351614 -242.320626)
			(xy 90.638118 -242.320626) (xy 90.638118 -242.26921) (xy 90.646161 -242.218428) (xy 90.662049 -242.169529)
			(xy 90.685392 -242.123717) (xy 90.715613 -242.082121) (xy 90.751969 -242.045765) (xy 90.793565 -242.015544)
			(xy 90.839377 -241.992201) (xy 90.888276 -241.976313) (xy 90.939058 -241.96827) (xy 90.990474 -241.96827)
			(xy 91.041256 -241.976313) (xy 91.090155 -241.992201) (xy 91.135967 -242.015544) (xy 91.177563 -242.045765)
			(xy 91.213919 -242.082121) (xy 91.24414 -242.123717) (xy 91.267483 -242.169529) (xy 91.283371 -242.218428)
			(xy 91.291414 -242.26921) (xy 91.291918 -242.294918) (xy 91.291414 -242.320626) (xy 94.397318 -242.320626)
			(xy 94.397318 -242.26921) (xy 94.405361 -242.218428) (xy 94.421249 -242.169529) (xy 94.444592 -242.123717)
			(xy 94.474813 -242.082121) (xy 94.511169 -242.045765) (xy 94.552765 -242.015544) (xy 94.598577 -241.992201)
			(xy 94.647476 -241.976313) (xy 94.698258 -241.96827) (xy 94.749674 -241.96827) (xy 94.800456 -241.976313)
			(xy 94.849355 -241.992201) (xy 94.895167 -242.015544) (xy 94.936763 -242.045765) (xy 94.973119 -242.082121)
			(xy 95.00334 -242.123717) (xy 95.026683 -242.169529) (xy 95.042571 -242.218428) (xy 95.050614 -242.26921)
			(xy 95.051118 -242.294918) (xy 95.050614 -242.320626) (xy 95.337118 -242.320626) (xy 95.337118 -242.26921)
			(xy 95.345161 -242.218428) (xy 95.361049 -242.169529) (xy 95.384392 -242.123717) (xy 95.414613 -242.082121)
			(xy 95.450969 -242.045765) (xy 95.492565 -242.015544) (xy 95.538377 -241.992201) (xy 95.587276 -241.976313)
			(xy 95.638058 -241.96827) (xy 95.689474 -241.96827) (xy 95.740256 -241.976313) (xy 95.789155 -241.992201)
			(xy 95.834967 -242.015544) (xy 95.876563 -242.045765) (xy 95.912919 -242.082121) (xy 95.94314 -242.123717)
			(xy 95.966483 -242.169529) (xy 95.982371 -242.218428) (xy 95.990414 -242.26921) (xy 95.990918 -242.294918)
			(xy 95.990414 -242.320626) (xy 96.276918 -242.320626) (xy 96.276918 -242.26921) (xy 96.284961 -242.218428)
			(xy 96.300849 -242.169529) (xy 96.324192 -242.123717) (xy 96.354413 -242.082121) (xy 96.390769 -242.045765)
			(xy 96.432365 -242.015544) (xy 96.478177 -241.992201) (xy 96.527076 -241.976313) (xy 96.577858 -241.96827)
			(xy 96.629274 -241.96827) (xy 96.680056 -241.976313) (xy 96.728955 -241.992201) (xy 96.774767 -242.015544)
			(xy 96.816363 -242.045765) (xy 96.852719 -242.082121) (xy 96.88294 -242.123717) (xy 96.906283 -242.169529)
			(xy 96.922171 -242.218428) (xy 96.930214 -242.26921) (xy 96.930718 -242.294918) (xy 96.930214 -242.320626)
			(xy 97.216718 -242.320626) (xy 97.216718 -242.26921) (xy 97.224761 -242.218428) (xy 97.240649 -242.169529)
			(xy 97.263992 -242.123717) (xy 97.294213 -242.082121) (xy 97.330569 -242.045765) (xy 97.372165 -242.015544)
			(xy 97.417977 -241.992201) (xy 97.466876 -241.976313) (xy 97.517658 -241.96827) (xy 97.569074 -241.96827)
			(xy 97.619856 -241.976313) (xy 97.668755 -241.992201) (xy 97.714567 -242.015544) (xy 97.756163 -242.045765)
			(xy 97.792519 -242.082121) (xy 97.82274 -242.123717) (xy 97.846083 -242.169529) (xy 97.861971 -242.218428)
			(xy 97.870014 -242.26921) (xy 97.870518 -242.294918) (xy 97.870014 -242.320626) (xy 97.861971 -242.371408)
			(xy 97.846083 -242.420307) (xy 97.82274 -242.466119) (xy 97.792519 -242.507715) (xy 97.756163 -242.544071)
			(xy 97.714567 -242.574292) (xy 97.668755 -242.597635) (xy 97.619856 -242.613523) (xy 97.569074 -242.621566)
			(xy 97.517658 -242.621566) (xy 97.466876 -242.613523) (xy 97.417977 -242.597635) (xy 97.372165 -242.574292)
			(xy 97.330569 -242.544071) (xy 97.294213 -242.507715) (xy 97.263992 -242.466119) (xy 97.240649 -242.420307)
			(xy 97.224761 -242.371408) (xy 97.216718 -242.320626) (xy 96.930214 -242.320626) (xy 96.922171 -242.371408)
			(xy 96.906283 -242.420307) (xy 96.88294 -242.466119) (xy 96.852719 -242.507715) (xy 96.816363 -242.544071)
			(xy 96.774767 -242.574292) (xy 96.728955 -242.597635) (xy 96.680056 -242.613523) (xy 96.629274 -242.621566)
			(xy 96.577858 -242.621566) (xy 96.527076 -242.613523) (xy 96.478177 -242.597635) (xy 96.432365 -242.574292)
			(xy 96.390769 -242.544071) (xy 96.354413 -242.507715) (xy 96.324192 -242.466119) (xy 96.300849 -242.420307)
			(xy 96.284961 -242.371408) (xy 96.276918 -242.320626) (xy 95.990414 -242.320626) (xy 95.982371 -242.371408)
			(xy 95.966483 -242.420307) (xy 95.94314 -242.466119) (xy 95.912919 -242.507715) (xy 95.876563 -242.544071)
			(xy 95.834967 -242.574292) (xy 95.789155 -242.597635) (xy 95.740256 -242.613523) (xy 95.689474 -242.621566)
			(xy 95.638058 -242.621566) (xy 95.587276 -242.613523) (xy 95.538377 -242.597635) (xy 95.492565 -242.574292)
			(xy 95.450969 -242.544071) (xy 95.414613 -242.507715) (xy 95.384392 -242.466119) (xy 95.361049 -242.420307)
			(xy 95.345161 -242.371408) (xy 95.337118 -242.320626) (xy 95.050614 -242.320626) (xy 95.042571 -242.371408)
			(xy 95.026683 -242.420307) (xy 95.00334 -242.466119) (xy 94.973119 -242.507715) (xy 94.936763 -242.544071)
			(xy 94.895167 -242.574292) (xy 94.849355 -242.597635) (xy 94.800456 -242.613523) (xy 94.749674 -242.621566)
			(xy 94.698258 -242.621566) (xy 94.647476 -242.613523) (xy 94.598577 -242.597635) (xy 94.552765 -242.574292)
			(xy 94.511169 -242.544071) (xy 94.474813 -242.507715) (xy 94.444592 -242.466119) (xy 94.421249 -242.420307)
			(xy 94.405361 -242.371408) (xy 94.397318 -242.320626) (xy 91.291414 -242.320626) (xy 91.283371 -242.371408)
			(xy 91.267483 -242.420307) (xy 91.24414 -242.466119) (xy 91.213919 -242.507715) (xy 91.177563 -242.544071)
			(xy 91.135967 -242.574292) (xy 91.090155 -242.597635) (xy 91.041256 -242.613523) (xy 90.990474 -242.621566)
			(xy 90.939058 -242.621566) (xy 90.888276 -242.613523) (xy 90.839377 -242.597635) (xy 90.793565 -242.574292)
			(xy 90.751969 -242.544071) (xy 90.715613 -242.507715) (xy 90.685392 -242.466119) (xy 90.662049 -242.420307)
			(xy 90.646161 -242.371408) (xy 90.638118 -242.320626) (xy 90.351614 -242.320626) (xy 90.343571 -242.371408)
			(xy 90.327683 -242.420307) (xy 90.30434 -242.466119) (xy 90.274119 -242.507715) (xy 90.237763 -242.544071)
			(xy 90.196167 -242.574292) (xy 90.150355 -242.597635) (xy 90.101456 -242.613523) (xy 90.050674 -242.621566)
			(xy 89.999258 -242.621566) (xy 89.948476 -242.613523) (xy 89.899577 -242.597635) (xy 89.853765 -242.574292)
			(xy 89.812169 -242.544071) (xy 89.775813 -242.507715) (xy 89.745592 -242.466119) (xy 89.722249 -242.420307)
			(xy 89.706361 -242.371408) (xy 89.698318 -242.320626) (xy 89.411814 -242.320626) (xy 89.403771 -242.371408)
			(xy 89.387883 -242.420307) (xy 89.36454 -242.466119) (xy 89.334319 -242.507715) (xy 89.297963 -242.544071)
			(xy 89.256367 -242.574292) (xy 89.210555 -242.597635) (xy 89.161656 -242.613523) (xy 89.110874 -242.621566)
			(xy 89.059458 -242.621566) (xy 89.008676 -242.613523) (xy 88.959777 -242.597635) (xy 88.913965 -242.574292)
			(xy 88.872369 -242.544071) (xy 88.836013 -242.507715) (xy 88.805792 -242.466119) (xy 88.782449 -242.420307)
			(xy 88.766561 -242.371408) (xy 88.758518 -242.320626) (xy 88.472268 -242.320626) (xy 88.464225 -242.371408)
			(xy 88.448337 -242.420307) (xy 88.424994 -242.466119) (xy 88.394773 -242.507715) (xy 88.358417 -242.544071)
			(xy 88.316821 -242.574292) (xy 88.271009 -242.597635) (xy 88.22211 -242.613523) (xy 88.171328 -242.621566)
			(xy 88.119912 -242.621566) (xy 88.06913 -242.613523) (xy 88.020231 -242.597635) (xy 87.974419 -242.574292)
			(xy 87.932823 -242.544071) (xy 87.896467 -242.507715) (xy 87.866246 -242.466119) (xy 87.842903 -242.420307)
			(xy 87.827015 -242.371408) (xy 87.818972 -242.320626) (xy 82.732626 -242.320626) (xy 82.732626 -243.134696)
			(xy 88.288364 -243.134696) (xy 88.288364 -243.08328) (xy 88.296407 -243.032498) (xy 88.312295 -242.983599)
			(xy 88.335638 -242.937787) (xy 88.365859 -242.896191) (xy 88.402215 -242.859835) (xy 88.443811 -242.829614)
			(xy 88.489623 -242.806271) (xy 88.538522 -242.790383) (xy 88.589304 -242.78234) (xy 88.64072 -242.78234)
			(xy 88.691502 -242.790383) (xy 88.740401 -242.806271) (xy 88.786213 -242.829614) (xy 88.827809 -242.859835)
			(xy 88.864165 -242.896191) (xy 88.894386 -242.937787) (xy 88.917729 -242.983599) (xy 88.933617 -243.032498)
			(xy 88.94166 -243.08328) (xy 88.942164 -243.108988) (xy 88.94166 -243.134696) (xy 90.167964 -243.134696)
			(xy 90.167964 -243.08328) (xy 90.176007 -243.032498) (xy 90.191895 -242.983599) (xy 90.215238 -242.937787)
			(xy 90.245459 -242.896191) (xy 90.281815 -242.859835) (xy 90.323411 -242.829614) (xy 90.369223 -242.806271)
			(xy 90.418122 -242.790383) (xy 90.468904 -242.78234) (xy 90.52032 -242.78234) (xy 90.571102 -242.790383)
			(xy 90.620001 -242.806271) (xy 90.665813 -242.829614) (xy 90.707409 -242.859835) (xy 90.743765 -242.896191)
			(xy 90.773986 -242.937787) (xy 90.797329 -242.983599) (xy 90.813217 -243.032498) (xy 90.82126 -243.08328)
			(xy 90.821764 -243.108988) (xy 90.82126 -243.134696) (xy 92.047564 -243.134696) (xy 92.047564 -243.08328)
			(xy 92.055607 -243.032498) (xy 92.071495 -242.983599) (xy 92.094838 -242.937787) (xy 92.125059 -242.896191)
			(xy 92.161415 -242.859835) (xy 92.203011 -242.829614) (xy 92.248823 -242.806271) (xy 92.297722 -242.790383)
			(xy 92.348504 -242.78234) (xy 92.39992 -242.78234) (xy 92.450702 -242.790383) (xy 92.499601 -242.806271)
			(xy 92.545413 -242.829614) (xy 92.587009 -242.859835) (xy 92.623365 -242.896191) (xy 92.653586 -242.937787)
			(xy 92.676929 -242.983599) (xy 92.692817 -243.032498) (xy 92.70086 -243.08328) (xy 92.701364 -243.108988)
			(xy 92.70086 -243.134696) (xy 92.987364 -243.134696) (xy 92.987364 -243.08328) (xy 92.995407 -243.032498)
			(xy 93.011295 -242.983599) (xy 93.034638 -242.937787) (xy 93.064859 -242.896191) (xy 93.101215 -242.859835)
			(xy 93.142811 -242.829614) (xy 93.188623 -242.806271) (xy 93.237522 -242.790383) (xy 93.288304 -242.78234)
			(xy 93.33972 -242.78234) (xy 93.390502 -242.790383) (xy 93.439401 -242.806271) (xy 93.485213 -242.829614)
			(xy 93.526809 -242.859835) (xy 93.563165 -242.896191) (xy 93.593386 -242.937787) (xy 93.616729 -242.983599)
			(xy 93.632617 -243.032498) (xy 93.64066 -243.08328) (xy 93.641164 -243.108988) (xy 93.64066 -243.134696)
			(xy 94.866964 -243.134696) (xy 94.866964 -243.08328) (xy 94.875007 -243.032498) (xy 94.890895 -242.983599)
			(xy 94.914238 -242.937787) (xy 94.944459 -242.896191) (xy 94.980815 -242.859835) (xy 95.022411 -242.829614)
			(xy 95.068223 -242.806271) (xy 95.117122 -242.790383) (xy 95.167904 -242.78234) (xy 95.21932 -242.78234)
			(xy 95.270102 -242.790383) (xy 95.319001 -242.806271) (xy 95.364813 -242.829614) (xy 95.406409 -242.859835)
			(xy 95.442765 -242.896191) (xy 95.472986 -242.937787) (xy 95.496329 -242.983599) (xy 95.512217 -243.032498)
			(xy 95.52026 -243.08328) (xy 95.520764 -243.108988) (xy 95.52026 -243.134696) (xy 96.746564 -243.134696)
			(xy 96.746564 -243.08328) (xy 96.754607 -243.032498) (xy 96.770495 -242.983599) (xy 96.793838 -242.937787)
			(xy 96.824059 -242.896191) (xy 96.860415 -242.859835) (xy 96.902011 -242.829614) (xy 96.947823 -242.806271)
			(xy 96.996722 -242.790383) (xy 97.047504 -242.78234) (xy 97.09892 -242.78234) (xy 97.149702 -242.790383)
			(xy 97.198601 -242.806271) (xy 97.244413 -242.829614) (xy 97.286009 -242.859835) (xy 97.322365 -242.896191)
			(xy 97.352586 -242.937787) (xy 97.375929 -242.983599) (xy 97.391817 -243.032498) (xy 97.39986 -243.08328)
			(xy 97.400364 -243.108988) (xy 97.39986 -243.134696) (xy 97.391817 -243.185478) (xy 97.375929 -243.234377)
			(xy 97.352586 -243.280189) (xy 97.322365 -243.321785) (xy 97.286009 -243.358141) (xy 97.244413 -243.388362)
			(xy 97.198601 -243.411705) (xy 97.149702 -243.427593) (xy 97.09892 -243.435636) (xy 97.047504 -243.435636)
			(xy 96.996722 -243.427593) (xy 96.947823 -243.411705) (xy 96.902011 -243.388362) (xy 96.860415 -243.358141)
			(xy 96.824059 -243.321785) (xy 96.793838 -243.280189) (xy 96.770495 -243.234377) (xy 96.754607 -243.185478)
			(xy 96.746564 -243.134696) (xy 95.52026 -243.134696) (xy 95.512217 -243.185478) (xy 95.496329 -243.234377)
			(xy 95.472986 -243.280189) (xy 95.442765 -243.321785) (xy 95.406409 -243.358141) (xy 95.364813 -243.388362)
			(xy 95.319001 -243.411705) (xy 95.270102 -243.427593) (xy 95.21932 -243.435636) (xy 95.167904 -243.435636)
			(xy 95.117122 -243.427593) (xy 95.068223 -243.411705) (xy 95.022411 -243.388362) (xy 94.980815 -243.358141)
			(xy 94.944459 -243.321785) (xy 94.914238 -243.280189) (xy 94.890895 -243.234377) (xy 94.875007 -243.185478)
			(xy 94.866964 -243.134696) (xy 93.64066 -243.134696) (xy 93.632617 -243.185478) (xy 93.616729 -243.234377)
			(xy 93.593386 -243.280189) (xy 93.563165 -243.321785) (xy 93.526809 -243.358141) (xy 93.485213 -243.388362)
			(xy 93.439401 -243.411705) (xy 93.390502 -243.427593) (xy 93.33972 -243.435636) (xy 93.288304 -243.435636)
			(xy 93.237522 -243.427593) (xy 93.188623 -243.411705) (xy 93.142811 -243.388362) (xy 93.101215 -243.358141)
			(xy 93.064859 -243.321785) (xy 93.034638 -243.280189) (xy 93.011295 -243.234377) (xy 92.995407 -243.185478)
			(xy 92.987364 -243.134696) (xy 92.70086 -243.134696) (xy 92.692817 -243.185478) (xy 92.676929 -243.234377)
			(xy 92.653586 -243.280189) (xy 92.623365 -243.321785) (xy 92.587009 -243.358141) (xy 92.545413 -243.388362)
			(xy 92.499601 -243.411705) (xy 92.450702 -243.427593) (xy 92.39992 -243.435636) (xy 92.348504 -243.435636)
			(xy 92.297722 -243.427593) (xy 92.248823 -243.411705) (xy 92.203011 -243.388362) (xy 92.161415 -243.358141)
			(xy 92.125059 -243.321785) (xy 92.094838 -243.280189) (xy 92.071495 -243.234377) (xy 92.055607 -243.185478)
			(xy 92.047564 -243.134696) (xy 90.82126 -243.134696) (xy 90.813217 -243.185478) (xy 90.797329 -243.234377)
			(xy 90.773986 -243.280189) (xy 90.743765 -243.321785) (xy 90.707409 -243.358141) (xy 90.665813 -243.388362)
			(xy 90.620001 -243.411705) (xy 90.571102 -243.427593) (xy 90.52032 -243.435636) (xy 90.468904 -243.435636)
			(xy 90.418122 -243.427593) (xy 90.369223 -243.411705) (xy 90.323411 -243.388362) (xy 90.281815 -243.358141)
			(xy 90.245459 -243.321785) (xy 90.215238 -243.280189) (xy 90.191895 -243.234377) (xy 90.176007 -243.185478)
			(xy 90.167964 -243.134696) (xy 88.94166 -243.134696) (xy 88.933617 -243.185478) (xy 88.917729 -243.234377)
			(xy 88.894386 -243.280189) (xy 88.864165 -243.321785) (xy 88.827809 -243.358141) (xy 88.786213 -243.388362)
			(xy 88.740401 -243.411705) (xy 88.691502 -243.427593) (xy 88.64072 -243.435636) (xy 88.589304 -243.435636)
			(xy 88.538522 -243.427593) (xy 88.489623 -243.411705) (xy 88.443811 -243.388362) (xy 88.402215 -243.358141)
			(xy 88.365859 -243.321785) (xy 88.335638 -243.280189) (xy 88.312295 -243.234377) (xy 88.296407 -243.185478)
			(xy 88.288364 -243.134696) (xy 82.732626 -243.134696) (xy 82.732626 -243.948512) (xy 88.758518 -243.948512)
			(xy 88.758518 -243.897096) (xy 88.766561 -243.846314) (xy 88.782449 -243.797415) (xy 88.805792 -243.751603)
			(xy 88.836013 -243.710007) (xy 88.872369 -243.673651) (xy 88.913965 -243.64343) (xy 88.959777 -243.620087)
			(xy 89.008676 -243.604199) (xy 89.059458 -243.596156) (xy 89.110874 -243.596156) (xy 89.161656 -243.604199)
			(xy 89.210555 -243.620087) (xy 89.256367 -243.64343) (xy 89.297963 -243.673651) (xy 89.334319 -243.710007)
			(xy 89.36454 -243.751603) (xy 89.387883 -243.797415) (xy 89.403771 -243.846314) (xy 89.411814 -243.897096)
			(xy 89.412318 -243.922804) (xy 89.411814 -243.948512) (xy 89.698318 -243.948512) (xy 89.698318 -243.897096)
			(xy 89.706361 -243.846314) (xy 89.722249 -243.797415) (xy 89.745592 -243.751603) (xy 89.775813 -243.710007)
			(xy 89.812169 -243.673651) (xy 89.853765 -243.64343) (xy 89.899577 -243.620087) (xy 89.948476 -243.604199)
			(xy 89.999258 -243.596156) (xy 90.050674 -243.596156) (xy 90.101456 -243.604199) (xy 90.150355 -243.620087)
			(xy 90.196167 -243.64343) (xy 90.237763 -243.673651) (xy 90.274119 -243.710007) (xy 90.30434 -243.751603)
			(xy 90.327683 -243.797415) (xy 90.343571 -243.846314) (xy 90.351614 -243.897096) (xy 90.352118 -243.922804)
			(xy 90.351614 -243.948512) (xy 91.577918 -243.948512) (xy 91.577918 -243.897096) (xy 91.585961 -243.846314)
			(xy 91.601849 -243.797415) (xy 91.625192 -243.751603) (xy 91.655413 -243.710007) (xy 91.691769 -243.673651)
			(xy 91.733365 -243.64343) (xy 91.779177 -243.620087) (xy 91.828076 -243.604199) (xy 91.878858 -243.596156)
			(xy 91.930274 -243.596156) (xy 91.981056 -243.604199) (xy 92.029955 -243.620087) (xy 92.075767 -243.64343)
			(xy 92.117363 -243.673651) (xy 92.153719 -243.710007) (xy 92.18394 -243.751603) (xy 92.207283 -243.797415)
			(xy 92.223171 -243.846314) (xy 92.231214 -243.897096) (xy 92.231718 -243.922804) (xy 92.231214 -243.948512)
			(xy 93.457518 -243.948512) (xy 93.457518 -243.897096) (xy 93.465561 -243.846314) (xy 93.481449 -243.797415)
			(xy 93.504792 -243.751603) (xy 93.535013 -243.710007) (xy 93.571369 -243.673651) (xy 93.612965 -243.64343)
			(xy 93.658777 -243.620087) (xy 93.707676 -243.604199) (xy 93.758458 -243.596156) (xy 93.809874 -243.596156)
			(xy 93.860656 -243.604199) (xy 93.909555 -243.620087) (xy 93.955367 -243.64343) (xy 93.996963 -243.673651)
			(xy 94.033319 -243.710007) (xy 94.06354 -243.751603) (xy 94.086883 -243.797415) (xy 94.102771 -243.846314)
			(xy 94.110814 -243.897096) (xy 94.111318 -243.922804) (xy 94.110814 -243.948512) (xy 95.337118 -243.948512)
			(xy 95.337118 -243.897096) (xy 95.345161 -243.846314) (xy 95.361049 -243.797415) (xy 95.384392 -243.751603)
			(xy 95.414613 -243.710007) (xy 95.450969 -243.673651) (xy 95.492565 -243.64343) (xy 95.538377 -243.620087)
			(xy 95.587276 -243.604199) (xy 95.638058 -243.596156) (xy 95.689474 -243.596156) (xy 95.740256 -243.604199)
			(xy 95.789155 -243.620087) (xy 95.834967 -243.64343) (xy 95.876563 -243.673651) (xy 95.912919 -243.710007)
			(xy 95.94314 -243.751603) (xy 95.966483 -243.797415) (xy 95.982371 -243.846314) (xy 95.990414 -243.897096)
			(xy 95.990918 -243.922804) (xy 95.990414 -243.948512) (xy 96.276918 -243.948512) (xy 96.276918 -243.897096)
			(xy 96.284961 -243.846314) (xy 96.300849 -243.797415) (xy 96.324192 -243.751603) (xy 96.354413 -243.710007)
			(xy 96.390769 -243.673651) (xy 96.432365 -243.64343) (xy 96.478177 -243.620087) (xy 96.527076 -243.604199)
			(xy 96.577858 -243.596156) (xy 96.629274 -243.596156) (xy 96.680056 -243.604199) (xy 96.728955 -243.620087)
			(xy 96.774767 -243.64343) (xy 96.816363 -243.673651) (xy 96.852719 -243.710007) (xy 96.88294 -243.751603)
			(xy 96.906283 -243.797415) (xy 96.922171 -243.846314) (xy 96.930214 -243.897096) (xy 96.930718 -243.922804)
			(xy 96.930214 -243.948512) (xy 98.156518 -243.948512) (xy 98.156518 -243.897096) (xy 98.164561 -243.846314)
			(xy 98.180449 -243.797415) (xy 98.203792 -243.751603) (xy 98.234013 -243.710007) (xy 98.270369 -243.673651)
			(xy 98.311965 -243.64343) (xy 98.357777 -243.620087) (xy 98.406676 -243.604199) (xy 98.457458 -243.596156)
			(xy 98.508874 -243.596156) (xy 98.559656 -243.604199) (xy 98.608555 -243.620087) (xy 98.654367 -243.64343)
			(xy 98.695963 -243.673651) (xy 98.732319 -243.710007) (xy 98.76254 -243.751603) (xy 98.785883 -243.797415)
			(xy 98.801771 -243.846314) (xy 98.809814 -243.897096) (xy 98.810318 -243.922804) (xy 98.809814 -243.948512)
			(xy 98.801771 -243.999294) (xy 98.785883 -244.048193) (xy 98.76254 -244.094005) (xy 98.732319 -244.135601)
			(xy 98.695963 -244.171957) (xy 98.654367 -244.202178) (xy 98.608555 -244.225521) (xy 98.559656 -244.241409)
			(xy 98.508874 -244.249452) (xy 98.457458 -244.249452) (xy 98.406676 -244.241409) (xy 98.357777 -244.225521)
			(xy 98.311965 -244.202178) (xy 98.270369 -244.171957) (xy 98.234013 -244.135601) (xy 98.203792 -244.094005)
			(xy 98.180449 -244.048193) (xy 98.164561 -243.999294) (xy 98.156518 -243.948512) (xy 96.930214 -243.948512)
			(xy 96.922171 -243.999294) (xy 96.906283 -244.048193) (xy 96.88294 -244.094005) (xy 96.852719 -244.135601)
			(xy 96.816363 -244.171957) (xy 96.774767 -244.202178) (xy 96.728955 -244.225521) (xy 96.680056 -244.241409)
			(xy 96.629274 -244.249452) (xy 96.577858 -244.249452) (xy 96.527076 -244.241409) (xy 96.478177 -244.225521)
			(xy 96.432365 -244.202178) (xy 96.390769 -244.171957) (xy 96.354413 -244.135601) (xy 96.324192 -244.094005)
			(xy 96.300849 -244.048193) (xy 96.284961 -243.999294) (xy 96.276918 -243.948512) (xy 95.990414 -243.948512)
			(xy 95.982371 -243.999294) (xy 95.966483 -244.048193) (xy 95.94314 -244.094005) (xy 95.912919 -244.135601)
			(xy 95.876563 -244.171957) (xy 95.834967 -244.202178) (xy 95.789155 -244.225521) (xy 95.740256 -244.241409)
			(xy 95.689474 -244.249452) (xy 95.638058 -244.249452) (xy 95.587276 -244.241409) (xy 95.538377 -244.225521)
			(xy 95.492565 -244.202178) (xy 95.450969 -244.171957) (xy 95.414613 -244.135601) (xy 95.384392 -244.094005)
			(xy 95.361049 -244.048193) (xy 95.345161 -243.999294) (xy 95.337118 -243.948512) (xy 94.110814 -243.948512)
			(xy 94.102771 -243.999294) (xy 94.086883 -244.048193) (xy 94.06354 -244.094005) (xy 94.033319 -244.135601)
			(xy 93.996963 -244.171957) (xy 93.955367 -244.202178) (xy 93.909555 -244.225521) (xy 93.860656 -244.241409)
			(xy 93.809874 -244.249452) (xy 93.758458 -244.249452) (xy 93.707676 -244.241409) (xy 93.658777 -244.225521)
			(xy 93.612965 -244.202178) (xy 93.571369 -244.171957) (xy 93.535013 -244.135601) (xy 93.504792 -244.094005)
			(xy 93.481449 -244.048193) (xy 93.465561 -243.999294) (xy 93.457518 -243.948512) (xy 92.231214 -243.948512)
			(xy 92.223171 -243.999294) (xy 92.207283 -244.048193) (xy 92.18394 -244.094005) (xy 92.153719 -244.135601)
			(xy 92.117363 -244.171957) (xy 92.075767 -244.202178) (xy 92.029955 -244.225521) (xy 91.981056 -244.241409)
			(xy 91.930274 -244.249452) (xy 91.878858 -244.249452) (xy 91.828076 -244.241409) (xy 91.779177 -244.225521)
			(xy 91.733365 -244.202178) (xy 91.691769 -244.171957) (xy 91.655413 -244.135601) (xy 91.625192 -244.094005)
			(xy 91.601849 -244.048193) (xy 91.585961 -243.999294) (xy 91.577918 -243.948512) (xy 90.351614 -243.948512)
			(xy 90.343571 -243.999294) (xy 90.327683 -244.048193) (xy 90.30434 -244.094005) (xy 90.274119 -244.135601)
			(xy 90.237763 -244.171957) (xy 90.196167 -244.202178) (xy 90.150355 -244.225521) (xy 90.101456 -244.241409)
			(xy 90.050674 -244.249452) (xy 89.999258 -244.249452) (xy 89.948476 -244.241409) (xy 89.899577 -244.225521)
			(xy 89.853765 -244.202178) (xy 89.812169 -244.171957) (xy 89.775813 -244.135601) (xy 89.745592 -244.094005)
			(xy 89.722249 -244.048193) (xy 89.706361 -243.999294) (xy 89.698318 -243.948512) (xy 89.411814 -243.948512)
			(xy 89.403771 -243.999294) (xy 89.387883 -244.048193) (xy 89.36454 -244.094005) (xy 89.334319 -244.135601)
			(xy 89.297963 -244.171957) (xy 89.256367 -244.202178) (xy 89.210555 -244.225521) (xy 89.161656 -244.241409)
			(xy 89.110874 -244.249452) (xy 89.059458 -244.249452) (xy 89.008676 -244.241409) (xy 88.959777 -244.225521)
			(xy 88.913965 -244.202178) (xy 88.872369 -244.171957) (xy 88.836013 -244.135601) (xy 88.805792 -244.094005)
			(xy 88.782449 -244.048193) (xy 88.766561 -243.999294) (xy 88.758518 -243.948512) (xy 82.732626 -243.948512)
			(xy 82.732626 -244.762328) (xy 91.107764 -244.762328) (xy 91.107764 -244.710912) (xy 91.115807 -244.66013)
			(xy 91.131695 -244.611231) (xy 91.155038 -244.565419) (xy 91.185259 -244.523823) (xy 91.221615 -244.487467)
			(xy 91.263211 -244.457246) (xy 91.309023 -244.433903) (xy 91.357922 -244.418015) (xy 91.408704 -244.409972)
			(xy 91.46012 -244.409972) (xy 91.510902 -244.418015) (xy 91.559801 -244.433903) (xy 91.605613 -244.457246)
			(xy 91.647209 -244.487467) (xy 91.683565 -244.523823) (xy 91.713786 -244.565419) (xy 91.737129 -244.611231)
			(xy 91.753017 -244.66013) (xy 91.76106 -244.710912) (xy 91.761564 -244.73662) (xy 91.76106 -244.762328)
			(xy 93.927164 -244.762328) (xy 93.927164 -244.710912) (xy 93.935207 -244.66013) (xy 93.951095 -244.611231)
			(xy 93.974438 -244.565419) (xy 94.004659 -244.523823) (xy 94.041015 -244.487467) (xy 94.082611 -244.457246)
			(xy 94.128423 -244.433903) (xy 94.177322 -244.418015) (xy 94.228104 -244.409972) (xy 94.27952 -244.409972)
			(xy 94.330302 -244.418015) (xy 94.379201 -244.433903) (xy 94.425013 -244.457246) (xy 94.466609 -244.487467)
			(xy 94.502965 -244.523823) (xy 94.533186 -244.565419) (xy 94.556529 -244.611231) (xy 94.572417 -244.66013)
			(xy 94.58046 -244.710912) (xy 94.580964 -244.73662) (xy 94.58046 -244.762328) (xy 97.686364 -244.762328)
			(xy 97.686364 -244.710912) (xy 97.694407 -244.66013) (xy 97.710295 -244.611231) (xy 97.733638 -244.565419)
			(xy 97.763859 -244.523823) (xy 97.800215 -244.487467) (xy 97.841811 -244.457246) (xy 97.887623 -244.433903)
			(xy 97.936522 -244.418015) (xy 97.987304 -244.409972) (xy 98.03872 -244.409972) (xy 98.089502 -244.418015)
			(xy 98.138401 -244.433903) (xy 98.184213 -244.457246) (xy 98.225809 -244.487467) (xy 98.262165 -244.523823)
			(xy 98.292386 -244.565419) (xy 98.315729 -244.611231) (xy 98.331617 -244.66013) (xy 98.33966 -244.710912)
			(xy 98.340164 -244.73662) (xy 98.33966 -244.762328) (xy 98.331617 -244.81311) (xy 98.315729 -244.862009)
			(xy 98.292386 -244.907821) (xy 98.262165 -244.949417) (xy 98.225809 -244.985773) (xy 98.184213 -245.015994)
			(xy 98.138401 -245.039337) (xy 98.089502 -245.055225) (xy 98.03872 -245.063268) (xy 97.987304 -245.063268)
			(xy 97.936522 -245.055225) (xy 97.887623 -245.039337) (xy 97.841811 -245.015994) (xy 97.800215 -244.985773)
			(xy 97.763859 -244.949417) (xy 97.733638 -244.907821) (xy 97.710295 -244.862009) (xy 97.694407 -244.81311)
			(xy 97.686364 -244.762328) (xy 94.58046 -244.762328) (xy 94.572417 -244.81311) (xy 94.556529 -244.862009)
			(xy 94.533186 -244.907821) (xy 94.502965 -244.949417) (xy 94.466609 -244.985773) (xy 94.425013 -245.015994)
			(xy 94.379201 -245.039337) (xy 94.330302 -245.055225) (xy 94.27952 -245.063268) (xy 94.228104 -245.063268)
			(xy 94.177322 -245.055225) (xy 94.128423 -245.039337) (xy 94.082611 -245.015994) (xy 94.041015 -244.985773)
			(xy 94.004659 -244.949417) (xy 93.974438 -244.907821) (xy 93.951095 -244.862009) (xy 93.935207 -244.81311)
			(xy 93.927164 -244.762328) (xy 91.76106 -244.762328) (xy 91.753017 -244.81311) (xy 91.737129 -244.862009)
			(xy 91.713786 -244.907821) (xy 91.683565 -244.949417) (xy 91.647209 -244.985773) (xy 91.605613 -245.015994)
			(xy 91.559801 -245.039337) (xy 91.510902 -245.055225) (xy 91.46012 -245.063268) (xy 91.408704 -245.063268)
			(xy 91.357922 -245.055225) (xy 91.309023 -245.039337) (xy 91.263211 -245.015994) (xy 91.221615 -244.985773)
			(xy 91.185259 -244.949417) (xy 91.155038 -244.907821) (xy 91.131695 -244.862009) (xy 91.115807 -244.81311)
			(xy 91.107764 -244.762328) (xy 82.732626 -244.762328) (xy 82.732626 -245.576398) (xy 88.758518 -245.576398)
			(xy 88.758518 -245.524982) (xy 88.766561 -245.4742) (xy 88.782449 -245.425301) (xy 88.805792 -245.379489)
			(xy 88.836013 -245.337893) (xy 88.872369 -245.301537) (xy 88.913965 -245.271316) (xy 88.959777 -245.247973)
			(xy 89.008676 -245.232085) (xy 89.059458 -245.224042) (xy 89.110874 -245.224042) (xy 89.161656 -245.232085)
			(xy 89.210555 -245.247973) (xy 89.256367 -245.271316) (xy 89.297963 -245.301537) (xy 89.334319 -245.337893)
			(xy 89.36454 -245.379489) (xy 89.387883 -245.425301) (xy 89.403771 -245.4742) (xy 89.411814 -245.524982)
			(xy 89.412318 -245.55069) (xy 89.411814 -245.576398) (xy 89.698318 -245.576398) (xy 89.698318 -245.524982)
			(xy 89.706361 -245.4742) (xy 89.722249 -245.425301) (xy 89.745592 -245.379489) (xy 89.775813 -245.337893)
			(xy 89.812169 -245.301537) (xy 89.853765 -245.271316) (xy 89.899577 -245.247973) (xy 89.948476 -245.232085)
			(xy 89.999258 -245.224042) (xy 90.050674 -245.224042) (xy 90.101456 -245.232085) (xy 90.150355 -245.247973)
			(xy 90.196167 -245.271316) (xy 90.237763 -245.301537) (xy 90.274119 -245.337893) (xy 90.30434 -245.379489)
			(xy 90.327683 -245.425301) (xy 90.343571 -245.4742) (xy 90.351614 -245.524982) (xy 90.352118 -245.55069)
			(xy 90.351614 -245.576398) (xy 91.577918 -245.576398) (xy 91.577918 -245.524982) (xy 91.585961 -245.4742)
			(xy 91.601849 -245.425301) (xy 91.625192 -245.379489) (xy 91.655413 -245.337893) (xy 91.691769 -245.301537)
			(xy 91.733365 -245.271316) (xy 91.779177 -245.247973) (xy 91.828076 -245.232085) (xy 91.878858 -245.224042)
			(xy 91.930274 -245.224042) (xy 91.981056 -245.232085) (xy 92.029955 -245.247973) (xy 92.075767 -245.271316)
			(xy 92.117363 -245.301537) (xy 92.153719 -245.337893) (xy 92.18394 -245.379489) (xy 92.207283 -245.425301)
			(xy 92.223171 -245.4742) (xy 92.231214 -245.524982) (xy 92.231718 -245.55069) (xy 92.231214 -245.576398)
			(xy 93.457518 -245.576398) (xy 93.457518 -245.524982) (xy 93.465561 -245.4742) (xy 93.481449 -245.425301)
			(xy 93.504792 -245.379489) (xy 93.535013 -245.337893) (xy 93.571369 -245.301537) (xy 93.612965 -245.271316)
			(xy 93.658777 -245.247973) (xy 93.707676 -245.232085) (xy 93.758458 -245.224042) (xy 93.809874 -245.224042)
			(xy 93.860656 -245.232085) (xy 93.909555 -245.247973) (xy 93.955367 -245.271316) (xy 93.996963 -245.301537)
			(xy 94.033319 -245.337893) (xy 94.06354 -245.379489) (xy 94.086883 -245.425301) (xy 94.102771 -245.4742)
			(xy 94.110814 -245.524982) (xy 94.111318 -245.55069) (xy 94.110814 -245.576398) (xy 95.337118 -245.576398)
			(xy 95.337118 -245.524982) (xy 95.345161 -245.4742) (xy 95.361049 -245.425301) (xy 95.384392 -245.379489)
			(xy 95.414613 -245.337893) (xy 95.450969 -245.301537) (xy 95.492565 -245.271316) (xy 95.538377 -245.247973)
			(xy 95.587276 -245.232085) (xy 95.638058 -245.224042) (xy 95.689474 -245.224042) (xy 95.740256 -245.232085)
			(xy 95.789155 -245.247973) (xy 95.834967 -245.271316) (xy 95.876563 -245.301537) (xy 95.912919 -245.337893)
			(xy 95.94314 -245.379489) (xy 95.966483 -245.425301) (xy 95.982371 -245.4742) (xy 95.990414 -245.524982)
			(xy 95.990918 -245.55069) (xy 95.990414 -245.576398) (xy 96.276918 -245.576398) (xy 96.276918 -245.524982)
			(xy 96.284961 -245.4742) (xy 96.300849 -245.425301) (xy 96.324192 -245.379489) (xy 96.354413 -245.337893)
			(xy 96.390769 -245.301537) (xy 96.432365 -245.271316) (xy 96.478177 -245.247973) (xy 96.527076 -245.232085)
			(xy 96.577858 -245.224042) (xy 96.629274 -245.224042) (xy 96.680056 -245.232085) (xy 96.728955 -245.247973)
			(xy 96.774767 -245.271316) (xy 96.816363 -245.301537) (xy 96.852719 -245.337893) (xy 96.88294 -245.379489)
			(xy 96.906283 -245.425301) (xy 96.922171 -245.4742) (xy 96.930214 -245.524982) (xy 96.930718 -245.55069)
			(xy 96.930214 -245.576398) (xy 98.156518 -245.576398) (xy 98.156518 -245.524982) (xy 98.164561 -245.4742)
			(xy 98.180449 -245.425301) (xy 98.203792 -245.379489) (xy 98.234013 -245.337893) (xy 98.270369 -245.301537)
			(xy 98.311965 -245.271316) (xy 98.357777 -245.247973) (xy 98.406676 -245.232085) (xy 98.457458 -245.224042)
			(xy 98.508874 -245.224042) (xy 98.559656 -245.232085) (xy 98.608555 -245.247973) (xy 98.654367 -245.271316)
			(xy 98.695963 -245.301537) (xy 98.732319 -245.337893) (xy 98.76254 -245.379489) (xy 98.785883 -245.425301)
			(xy 98.801771 -245.4742) (xy 98.809814 -245.524982) (xy 98.810318 -245.55069) (xy 98.809814 -245.576398)
			(xy 98.801771 -245.62718) (xy 98.785883 -245.676079) (xy 98.76254 -245.721891) (xy 98.732319 -245.763487)
			(xy 98.695963 -245.799843) (xy 98.654367 -245.830064) (xy 98.608555 -245.853407) (xy 98.559656 -245.869295)
			(xy 98.508874 -245.877338) (xy 98.457458 -245.877338) (xy 98.406676 -245.869295) (xy 98.357777 -245.853407)
			(xy 98.311965 -245.830064) (xy 98.270369 -245.799843) (xy 98.234013 -245.763487) (xy 98.203792 -245.721891)
			(xy 98.180449 -245.676079) (xy 98.164561 -245.62718) (xy 98.156518 -245.576398) (xy 96.930214 -245.576398)
			(xy 96.922171 -245.62718) (xy 96.906283 -245.676079) (xy 96.88294 -245.721891) (xy 96.852719 -245.763487)
			(xy 96.816363 -245.799843) (xy 96.774767 -245.830064) (xy 96.728955 -245.853407) (xy 96.680056 -245.869295)
			(xy 96.629274 -245.877338) (xy 96.577858 -245.877338) (xy 96.527076 -245.869295) (xy 96.478177 -245.853407)
			(xy 96.432365 -245.830064) (xy 96.390769 -245.799843) (xy 96.354413 -245.763487) (xy 96.324192 -245.721891)
			(xy 96.300849 -245.676079) (xy 96.284961 -245.62718) (xy 96.276918 -245.576398) (xy 95.990414 -245.576398)
			(xy 95.982371 -245.62718) (xy 95.966483 -245.676079) (xy 95.94314 -245.721891) (xy 95.912919 -245.763487)
			(xy 95.876563 -245.799843) (xy 95.834967 -245.830064) (xy 95.789155 -245.853407) (xy 95.740256 -245.869295)
			(xy 95.689474 -245.877338) (xy 95.638058 -245.877338) (xy 95.587276 -245.869295) (xy 95.538377 -245.853407)
			(xy 95.492565 -245.830064) (xy 95.450969 -245.799843) (xy 95.414613 -245.763487) (xy 95.384392 -245.721891)
			(xy 95.361049 -245.676079) (xy 95.345161 -245.62718) (xy 95.337118 -245.576398) (xy 94.110814 -245.576398)
			(xy 94.102771 -245.62718) (xy 94.086883 -245.676079) (xy 94.06354 -245.721891) (xy 94.033319 -245.763487)
			(xy 93.996963 -245.799843) (xy 93.955367 -245.830064) (xy 93.909555 -245.853407) (xy 93.860656 -245.869295)
			(xy 93.809874 -245.877338) (xy 93.758458 -245.877338) (xy 93.707676 -245.869295) (xy 93.658777 -245.853407)
			(xy 93.612965 -245.830064) (xy 93.571369 -245.799843) (xy 93.535013 -245.763487) (xy 93.504792 -245.721891)
			(xy 93.481449 -245.676079) (xy 93.465561 -245.62718) (xy 93.457518 -245.576398) (xy 92.231214 -245.576398)
			(xy 92.223171 -245.62718) (xy 92.207283 -245.676079) (xy 92.18394 -245.721891) (xy 92.153719 -245.763487)
			(xy 92.117363 -245.799843) (xy 92.075767 -245.830064) (xy 92.029955 -245.853407) (xy 91.981056 -245.869295)
			(xy 91.930274 -245.877338) (xy 91.878858 -245.877338) (xy 91.828076 -245.869295) (xy 91.779177 -245.853407)
			(xy 91.733365 -245.830064) (xy 91.691769 -245.799843) (xy 91.655413 -245.763487) (xy 91.625192 -245.721891)
			(xy 91.601849 -245.676079) (xy 91.585961 -245.62718) (xy 91.577918 -245.576398) (xy 90.351614 -245.576398)
			(xy 90.343571 -245.62718) (xy 90.327683 -245.676079) (xy 90.30434 -245.721891) (xy 90.274119 -245.763487)
			(xy 90.237763 -245.799843) (xy 90.196167 -245.830064) (xy 90.150355 -245.853407) (xy 90.101456 -245.869295)
			(xy 90.050674 -245.877338) (xy 89.999258 -245.877338) (xy 89.948476 -245.869295) (xy 89.899577 -245.853407)
			(xy 89.853765 -245.830064) (xy 89.812169 -245.799843) (xy 89.775813 -245.763487) (xy 89.745592 -245.721891)
			(xy 89.722249 -245.676079) (xy 89.706361 -245.62718) (xy 89.698318 -245.576398) (xy 89.411814 -245.576398)
			(xy 89.403771 -245.62718) (xy 89.387883 -245.676079) (xy 89.36454 -245.721891) (xy 89.334319 -245.763487)
			(xy 89.297963 -245.799843) (xy 89.256367 -245.830064) (xy 89.210555 -245.853407) (xy 89.161656 -245.869295)
			(xy 89.110874 -245.877338) (xy 89.059458 -245.877338) (xy 89.008676 -245.869295) (xy 88.959777 -245.853407)
			(xy 88.913965 -245.830064) (xy 88.872369 -245.799843) (xy 88.836013 -245.763487) (xy 88.805792 -245.721891)
			(xy 88.782449 -245.676079) (xy 88.766561 -245.62718) (xy 88.758518 -245.576398) (xy 82.732626 -245.576398)
			(xy 82.732626 -246.17426) (xy 82.948501 -246.390214) (xy 88.288364 -246.390214) (xy 88.288364 -246.338798)
			(xy 88.296407 -246.288016) (xy 88.312295 -246.239117) (xy 88.335638 -246.193305) (xy 88.365859 -246.151709)
			(xy 88.402215 -246.115353) (xy 88.443811 -246.085132) (xy 88.489623 -246.061789) (xy 88.538522 -246.045901)
			(xy 88.589304 -246.037858) (xy 88.64072 -246.037858) (xy 88.691502 -246.045901) (xy 88.740401 -246.061789)
			(xy 88.786213 -246.085132) (xy 88.827809 -246.115353) (xy 88.864165 -246.151709) (xy 88.894386 -246.193305)
			(xy 88.917729 -246.239117) (xy 88.933617 -246.288016) (xy 88.94166 -246.338798) (xy 88.942164 -246.364506)
			(xy 88.94166 -246.390214) (xy 90.167964 -246.390214) (xy 90.167964 -246.338798) (xy 90.176007 -246.288016)
			(xy 90.191895 -246.239117) (xy 90.215238 -246.193305) (xy 90.245459 -246.151709) (xy 90.281815 -246.115353)
			(xy 90.323411 -246.085132) (xy 90.369223 -246.061789) (xy 90.418122 -246.045901) (xy 90.468904 -246.037858)
			(xy 90.52032 -246.037858) (xy 90.571102 -246.045901) (xy 90.620001 -246.061789) (xy 90.665813 -246.085132)
			(xy 90.707409 -246.115353) (xy 90.743765 -246.151709) (xy 90.773986 -246.193305) (xy 90.797329 -246.239117)
			(xy 90.813217 -246.288016) (xy 90.82126 -246.338798) (xy 90.821764 -246.364506) (xy 90.82126 -246.390214)
			(xy 92.047564 -246.390214) (xy 92.047564 -246.338798) (xy 92.055607 -246.288016) (xy 92.071495 -246.239117)
			(xy 92.094838 -246.193305) (xy 92.125059 -246.151709) (xy 92.161415 -246.115353) (xy 92.203011 -246.085132)
			(xy 92.248823 -246.061789) (xy 92.297722 -246.045901) (xy 92.348504 -246.037858) (xy 92.39992 -246.037858)
			(xy 92.450702 -246.045901) (xy 92.499601 -246.061789) (xy 92.545413 -246.085132) (xy 92.587009 -246.115353)
			(xy 92.623365 -246.151709) (xy 92.653586 -246.193305) (xy 92.676929 -246.239117) (xy 92.692817 -246.288016)
			(xy 92.70086 -246.338798) (xy 92.701364 -246.364506) (xy 92.70086 -246.390214) (xy 92.987364 -246.390214)
			(xy 92.987364 -246.338798) (xy 92.995407 -246.288016) (xy 93.011295 -246.239117) (xy 93.034638 -246.193305)
			(xy 93.064859 -246.151709) (xy 93.101215 -246.115353) (xy 93.142811 -246.085132) (xy 93.188623 -246.061789)
			(xy 93.237522 -246.045901) (xy 93.288304 -246.037858) (xy 93.33972 -246.037858) (xy 93.390502 -246.045901)
			(xy 93.439401 -246.061789) (xy 93.485213 -246.085132) (xy 93.526809 -246.115353) (xy 93.563165 -246.151709)
			(xy 93.593386 -246.193305) (xy 93.616729 -246.239117) (xy 93.632617 -246.288016) (xy 93.64066 -246.338798)
			(xy 93.641164 -246.364506) (xy 93.64066 -246.390214) (xy 94.866964 -246.390214) (xy 94.866964 -246.338798)
			(xy 94.875007 -246.288016) (xy 94.890895 -246.239117) (xy 94.914238 -246.193305) (xy 94.944459 -246.151709)
			(xy 94.980815 -246.115353) (xy 95.022411 -246.085132) (xy 95.068223 -246.061789) (xy 95.117122 -246.045901)
			(xy 95.167904 -246.037858) (xy 95.21932 -246.037858) (xy 95.270102 -246.045901) (xy 95.319001 -246.061789)
			(xy 95.364813 -246.085132) (xy 95.406409 -246.115353) (xy 95.442765 -246.151709) (xy 95.472986 -246.193305)
			(xy 95.496329 -246.239117) (xy 95.512217 -246.288016) (xy 95.52026 -246.338798) (xy 95.520764 -246.364506)
			(xy 95.52026 -246.390214) (xy 96.746564 -246.390214) (xy 96.746564 -246.338798) (xy 96.754607 -246.288016)
			(xy 96.770495 -246.239117) (xy 96.793838 -246.193305) (xy 96.824059 -246.151709) (xy 96.860415 -246.115353)
			(xy 96.902011 -246.085132) (xy 96.947823 -246.061789) (xy 96.996722 -246.045901) (xy 97.047504 -246.037858)
			(xy 97.09892 -246.037858) (xy 97.149702 -246.045901) (xy 97.198601 -246.061789) (xy 97.244413 -246.085132)
			(xy 97.286009 -246.115353) (xy 97.322365 -246.151709) (xy 97.352586 -246.193305) (xy 97.375929 -246.239117)
			(xy 97.391817 -246.288016) (xy 97.39986 -246.338798) (xy 97.400364 -246.364506) (xy 97.39986 -246.390214)
			(xy 97.391817 -246.440996) (xy 97.375929 -246.489895) (xy 97.352586 -246.535707) (xy 97.322365 -246.577303)
			(xy 97.286009 -246.613659) (xy 97.244413 -246.64388) (xy 97.198601 -246.667223) (xy 97.149702 -246.683111)
			(xy 97.09892 -246.691154) (xy 97.047504 -246.691154) (xy 96.996722 -246.683111) (xy 96.947823 -246.667223)
			(xy 96.902011 -246.64388) (xy 96.860415 -246.613659) (xy 96.824059 -246.577303) (xy 96.793838 -246.535707)
			(xy 96.770495 -246.489895) (xy 96.754607 -246.440996) (xy 96.746564 -246.390214) (xy 95.52026 -246.390214)
			(xy 95.512217 -246.440996) (xy 95.496329 -246.489895) (xy 95.472986 -246.535707) (xy 95.442765 -246.577303)
			(xy 95.406409 -246.613659) (xy 95.364813 -246.64388) (xy 95.319001 -246.667223) (xy 95.270102 -246.683111)
			(xy 95.21932 -246.691154) (xy 95.167904 -246.691154) (xy 95.117122 -246.683111) (xy 95.068223 -246.667223)
			(xy 95.022411 -246.64388) (xy 94.980815 -246.613659) (xy 94.944459 -246.577303) (xy 94.914238 -246.535707)
			(xy 94.890895 -246.489895) (xy 94.875007 -246.440996) (xy 94.866964 -246.390214) (xy 93.64066 -246.390214)
			(xy 93.632617 -246.440996) (xy 93.616729 -246.489895) (xy 93.593386 -246.535707) (xy 93.563165 -246.577303)
			(xy 93.526809 -246.613659) (xy 93.485213 -246.64388) (xy 93.439401 -246.667223) (xy 93.390502 -246.683111)
			(xy 93.33972 -246.691154) (xy 93.288304 -246.691154) (xy 93.237522 -246.683111) (xy 93.188623 -246.667223)
			(xy 93.142811 -246.64388) (xy 93.101215 -246.613659) (xy 93.064859 -246.577303) (xy 93.034638 -246.535707)
			(xy 93.011295 -246.489895) (xy 92.995407 -246.440996) (xy 92.987364 -246.390214) (xy 92.70086 -246.390214)
			(xy 92.692817 -246.440996) (xy 92.676929 -246.489895) (xy 92.653586 -246.535707) (xy 92.623365 -246.577303)
			(xy 92.587009 -246.613659) (xy 92.545413 -246.64388) (xy 92.499601 -246.667223) (xy 92.450702 -246.683111)
			(xy 92.39992 -246.691154) (xy 92.348504 -246.691154) (xy 92.297722 -246.683111) (xy 92.248823 -246.667223)
			(xy 92.203011 -246.64388) (xy 92.161415 -246.613659) (xy 92.125059 -246.577303) (xy 92.094838 -246.535707)
			(xy 92.071495 -246.489895) (xy 92.055607 -246.440996) (xy 92.047564 -246.390214) (xy 90.82126 -246.390214)
			(xy 90.813217 -246.440996) (xy 90.797329 -246.489895) (xy 90.773986 -246.535707) (xy 90.743765 -246.577303)
			(xy 90.707409 -246.613659) (xy 90.665813 -246.64388) (xy 90.620001 -246.667223) (xy 90.571102 -246.683111)
			(xy 90.52032 -246.691154) (xy 90.468904 -246.691154) (xy 90.418122 -246.683111) (xy 90.369223 -246.667223)
			(xy 90.323411 -246.64388) (xy 90.281815 -246.613659) (xy 90.245459 -246.577303) (xy 90.215238 -246.535707)
			(xy 90.191895 -246.489895) (xy 90.176007 -246.440996) (xy 90.167964 -246.390214) (xy 88.94166 -246.390214)
			(xy 88.933617 -246.440996) (xy 88.917729 -246.489895) (xy 88.894386 -246.535707) (xy 88.864165 -246.577303)
			(xy 88.827809 -246.613659) (xy 88.786213 -246.64388) (xy 88.740401 -246.667223) (xy 88.691502 -246.683111)
			(xy 88.64072 -246.691154) (xy 88.589304 -246.691154) (xy 88.538522 -246.683111) (xy 88.489623 -246.667223)
			(xy 88.443811 -246.64388) (xy 88.402215 -246.613659) (xy 88.365859 -246.577303) (xy 88.335638 -246.535707)
			(xy 88.312295 -246.489895) (xy 88.296407 -246.440996) (xy 88.288364 -246.390214) (xy 82.948501 -246.390214)
			(xy 83.422744 -246.864632) (xy 83.457288 -246.864632) (xy 83.48636 -246.865149) (xy 83.543793 -246.874202)
			(xy 83.599101 -246.892135) (xy 83.650919 -246.918504) (xy 83.697971 -246.95266) (xy 83.718908 -246.972836)
			(xy 83.950102 -247.20403) (xy 87.818718 -247.20403) (xy 87.818718 -247.152614) (xy 87.826761 -247.101832)
			(xy 87.842649 -247.052933) (xy 87.865992 -247.007121) (xy 87.896213 -246.965525) (xy 87.932569 -246.929169)
			(xy 87.974165 -246.898948) (xy 88.019977 -246.875605) (xy 88.068876 -246.859717) (xy 88.119658 -246.851674)
			(xy 88.171074 -246.851674) (xy 88.221856 -246.859717) (xy 88.270755 -246.875605) (xy 88.316567 -246.898948)
			(xy 88.358163 -246.929169) (xy 88.394519 -246.965525) (xy 88.42474 -247.007121) (xy 88.448083 -247.052933)
			(xy 88.463971 -247.101832) (xy 88.472014 -247.152614) (xy 88.472518 -247.178322) (xy 88.472014 -247.20403)
			(xy 90.638118 -247.20403) (xy 90.638118 -247.152614) (xy 90.646161 -247.101832) (xy 90.662049 -247.052933)
			(xy 90.685392 -247.007121) (xy 90.715613 -246.965525) (xy 90.751969 -246.929169) (xy 90.793565 -246.898948)
			(xy 90.839377 -246.875605) (xy 90.888276 -246.859717) (xy 90.939058 -246.851674) (xy 90.990474 -246.851674)
			(xy 91.041256 -246.859717) (xy 91.090155 -246.875605) (xy 91.135967 -246.898948) (xy 91.177563 -246.929169)
			(xy 91.213919 -246.965525) (xy 91.24414 -247.007121) (xy 91.267483 -247.052933) (xy 91.283371 -247.101832)
			(xy 91.291414 -247.152614) (xy 91.291918 -247.178322) (xy 91.291414 -247.20403) (xy 94.397318 -247.20403)
			(xy 94.397318 -247.152614) (xy 94.405361 -247.101832) (xy 94.421249 -247.052933) (xy 94.444592 -247.007121)
			(xy 94.474813 -246.965525) (xy 94.511169 -246.929169) (xy 94.552765 -246.898948) (xy 94.598577 -246.875605)
			(xy 94.647476 -246.859717) (xy 94.698258 -246.851674) (xy 94.749674 -246.851674) (xy 94.800456 -246.859717)
			(xy 94.849355 -246.875605) (xy 94.895167 -246.898948) (xy 94.936763 -246.929169) (xy 94.973119 -246.965525)
			(xy 95.00334 -247.007121) (xy 95.026683 -247.052933) (xy 95.042571 -247.101832) (xy 95.050614 -247.152614)
			(xy 95.051118 -247.178322) (xy 95.050614 -247.20403) (xy 97.216718 -247.20403) (xy 97.216718 -247.152614)
			(xy 97.224761 -247.101832) (xy 97.240649 -247.052933) (xy 97.263992 -247.007121) (xy 97.294213 -246.965525)
			(xy 97.330569 -246.929169) (xy 97.372165 -246.898948) (xy 97.417977 -246.875605) (xy 97.466876 -246.859717)
			(xy 97.517658 -246.851674) (xy 97.569074 -246.851674) (xy 97.619856 -246.859717) (xy 97.668755 -246.875605)
			(xy 97.714567 -246.898948) (xy 97.756163 -246.929169) (xy 97.792519 -246.965525) (xy 97.82274 -247.007121)
			(xy 97.846083 -247.052933) (xy 97.861971 -247.101832) (xy 97.870014 -247.152614) (xy 97.870518 -247.178322)
			(xy 97.870014 -247.20403) (xy 97.861971 -247.254812) (xy 97.846083 -247.303711) (xy 97.82274 -247.349523)
			(xy 97.792519 -247.391119) (xy 97.756163 -247.427475) (xy 97.714567 -247.457696) (xy 97.668755 -247.481039)
			(xy 97.619856 -247.496927) (xy 97.569074 -247.50497) (xy 97.517658 -247.50497) (xy 97.466876 -247.496927)
			(xy 97.417977 -247.481039) (xy 97.372165 -247.457696) (xy 97.330569 -247.427475) (xy 97.294213 -247.391119)
			(xy 97.263992 -247.349523) (xy 97.240649 -247.303711) (xy 97.224761 -247.254812) (xy 97.216718 -247.20403)
			(xy 95.050614 -247.20403) (xy 95.042571 -247.254812) (xy 95.026683 -247.303711) (xy 95.00334 -247.349523)
			(xy 94.973119 -247.391119) (xy 94.936763 -247.427475) (xy 94.895167 -247.457696) (xy 94.849355 -247.481039)
			(xy 94.800456 -247.496927) (xy 94.749674 -247.50497) (xy 94.698258 -247.50497) (xy 94.647476 -247.496927)
			(xy 94.598577 -247.481039) (xy 94.552765 -247.457696) (xy 94.511169 -247.427475) (xy 94.474813 -247.391119)
			(xy 94.444592 -247.349523) (xy 94.421249 -247.303711) (xy 94.405361 -247.254812) (xy 94.397318 -247.20403)
			(xy 91.291414 -247.20403) (xy 91.283371 -247.254812) (xy 91.267483 -247.303711) (xy 91.24414 -247.349523)
			(xy 91.213919 -247.391119) (xy 91.177563 -247.427475) (xy 91.135967 -247.457696) (xy 91.090155 -247.481039)
			(xy 91.041256 -247.496927) (xy 90.990474 -247.50497) (xy 90.939058 -247.50497) (xy 90.888276 -247.496927)
			(xy 90.839377 -247.481039) (xy 90.793565 -247.457696) (xy 90.751969 -247.427475) (xy 90.715613 -247.391119)
			(xy 90.685392 -247.349523) (xy 90.662049 -247.303711) (xy 90.646161 -247.254812) (xy 90.638118 -247.20403)
			(xy 88.472014 -247.20403) (xy 88.463971 -247.254812) (xy 88.448083 -247.303711) (xy 88.42474 -247.349523)
			(xy 88.394519 -247.391119) (xy 88.358163 -247.427475) (xy 88.316567 -247.457696) (xy 88.270755 -247.481039)
			(xy 88.221856 -247.496927) (xy 88.171074 -247.50497) (xy 88.119658 -247.50497) (xy 88.068876 -247.496927)
			(xy 88.019977 -247.481039) (xy 87.974165 -247.457696) (xy 87.932569 -247.427475) (xy 87.896213 -247.391119)
			(xy 87.865992 -247.349523) (xy 87.842649 -247.303711) (xy 87.826761 -247.254812) (xy 87.818718 -247.20403)
			(xy 83.950102 -247.20403) (xy 84.763918 -248.017846) (xy 88.288364 -248.017846) (xy 88.288364 -247.96643)
			(xy 88.296407 -247.915648) (xy 88.312295 -247.866749) (xy 88.335638 -247.820937) (xy 88.365859 -247.779341)
			(xy 88.402215 -247.742985) (xy 88.443811 -247.712764) (xy 88.489623 -247.689421) (xy 88.538522 -247.673533)
			(xy 88.589304 -247.66549) (xy 88.64072 -247.66549) (xy 88.691502 -247.673533) (xy 88.740401 -247.689421)
			(xy 88.786213 -247.712764) (xy 88.827809 -247.742985) (xy 88.864165 -247.779341) (xy 88.894386 -247.820937)
			(xy 88.917729 -247.866749) (xy 88.933617 -247.915648) (xy 88.94166 -247.96643) (xy 88.942164 -247.992138)
			(xy 88.94166 -248.017846) (xy 90.167964 -248.017846) (xy 90.167964 -247.96643) (xy 90.176007 -247.915648)
			(xy 90.191895 -247.866749) (xy 90.215238 -247.820937) (xy 90.245459 -247.779341) (xy 90.281815 -247.742985)
			(xy 90.323411 -247.712764) (xy 90.369223 -247.689421) (xy 90.418122 -247.673533) (xy 90.468904 -247.66549)
			(xy 90.52032 -247.66549) (xy 90.571102 -247.673533) (xy 90.620001 -247.689421) (xy 90.665813 -247.712764)
			(xy 90.707409 -247.742985) (xy 90.743765 -247.779341) (xy 90.773986 -247.820937) (xy 90.797329 -247.866749)
			(xy 90.813217 -247.915648) (xy 90.82126 -247.96643) (xy 90.821764 -247.992138) (xy 90.82126 -248.017846)
			(xy 92.047564 -248.017846) (xy 92.047564 -247.96643) (xy 92.055607 -247.915648) (xy 92.071495 -247.866749)
			(xy 92.094838 -247.820937) (xy 92.125059 -247.779341) (xy 92.161415 -247.742985) (xy 92.203011 -247.712764)
			(xy 92.248823 -247.689421) (xy 92.297722 -247.673533) (xy 92.348504 -247.66549) (xy 92.39992 -247.66549)
			(xy 92.450702 -247.673533) (xy 92.499601 -247.689421) (xy 92.545413 -247.712764) (xy 92.587009 -247.742985)
			(xy 92.623365 -247.779341) (xy 92.653586 -247.820937) (xy 92.676929 -247.866749) (xy 92.692817 -247.915648)
			(xy 92.70086 -247.96643) (xy 92.701364 -247.992138) (xy 92.70086 -248.017846) (xy 92.987364 -248.017846)
			(xy 92.987364 -247.96643) (xy 92.995407 -247.915648) (xy 93.011295 -247.866749) (xy 93.034638 -247.820937)
			(xy 93.064859 -247.779341) (xy 93.101215 -247.742985) (xy 93.142811 -247.712764) (xy 93.188623 -247.689421)
			(xy 93.237522 -247.673533) (xy 93.288304 -247.66549) (xy 93.33972 -247.66549) (xy 93.390502 -247.673533)
			(xy 93.439401 -247.689421) (xy 93.485213 -247.712764) (xy 93.526809 -247.742985) (xy 93.563165 -247.779341)
			(xy 93.593386 -247.820937) (xy 93.616729 -247.866749) (xy 93.632617 -247.915648) (xy 93.64066 -247.96643)
			(xy 93.641164 -247.992138) (xy 93.64066 -248.017846) (xy 94.866964 -248.017846) (xy 94.866964 -247.96643)
			(xy 94.875007 -247.915648) (xy 94.890895 -247.866749) (xy 94.914238 -247.820937) (xy 94.944459 -247.779341)
			(xy 94.980815 -247.742985) (xy 95.022411 -247.712764) (xy 95.068223 -247.689421) (xy 95.117122 -247.673533)
			(xy 95.167904 -247.66549) (xy 95.21932 -247.66549) (xy 95.270102 -247.673533) (xy 95.319001 -247.689421)
			(xy 95.364813 -247.712764) (xy 95.406409 -247.742985) (xy 95.442765 -247.779341) (xy 95.472986 -247.820937)
			(xy 95.496329 -247.866749) (xy 95.512217 -247.915648) (xy 95.52026 -247.96643) (xy 95.520764 -247.992138)
			(xy 95.52026 -248.017846) (xy 96.746564 -248.017846) (xy 96.746564 -247.96643) (xy 96.754607 -247.915648)
			(xy 96.770495 -247.866749) (xy 96.793838 -247.820937) (xy 96.824059 -247.779341) (xy 96.860415 -247.742985)
			(xy 96.902011 -247.712764) (xy 96.947823 -247.689421) (xy 96.996722 -247.673533) (xy 97.047504 -247.66549)
			(xy 97.09892 -247.66549) (xy 97.149702 -247.673533) (xy 97.198601 -247.689421) (xy 97.244413 -247.712764)
			(xy 97.286009 -247.742985) (xy 97.322365 -247.779341) (xy 97.352586 -247.820937) (xy 97.375929 -247.866749)
			(xy 97.391817 -247.915648) (xy 97.39986 -247.96643) (xy 97.400364 -247.992138) (xy 97.39986 -248.017846)
			(xy 97.391817 -248.068628) (xy 97.375929 -248.117527) (xy 97.352586 -248.163339) (xy 97.322365 -248.204935)
			(xy 97.286009 -248.241291) (xy 97.244413 -248.271512) (xy 97.198601 -248.294855) (xy 97.149702 -248.310743)
			(xy 97.09892 -248.318786) (xy 97.047504 -248.318786) (xy 96.996722 -248.310743) (xy 96.947823 -248.294855)
			(xy 96.902011 -248.271512) (xy 96.860415 -248.241291) (xy 96.824059 -248.204935) (xy 96.793838 -248.163339)
			(xy 96.770495 -248.117527) (xy 96.754607 -248.068628) (xy 96.746564 -248.017846) (xy 95.52026 -248.017846)
			(xy 95.512217 -248.068628) (xy 95.496329 -248.117527) (xy 95.472986 -248.163339) (xy 95.442765 -248.204935)
			(xy 95.406409 -248.241291) (xy 95.364813 -248.271512) (xy 95.319001 -248.294855) (xy 95.270102 -248.310743)
			(xy 95.21932 -248.318786) (xy 95.167904 -248.318786) (xy 95.117122 -248.310743) (xy 95.068223 -248.294855)
			(xy 95.022411 -248.271512) (xy 94.980815 -248.241291) (xy 94.944459 -248.204935) (xy 94.914238 -248.163339)
			(xy 94.890895 -248.117527) (xy 94.875007 -248.068628) (xy 94.866964 -248.017846) (xy 93.64066 -248.017846)
			(xy 93.632617 -248.068628) (xy 93.616729 -248.117527) (xy 93.593386 -248.163339) (xy 93.563165 -248.204935)
			(xy 93.526809 -248.241291) (xy 93.485213 -248.271512) (xy 93.439401 -248.294855) (xy 93.390502 -248.310743)
			(xy 93.33972 -248.318786) (xy 93.288304 -248.318786) (xy 93.237522 -248.310743) (xy 93.188623 -248.294855)
			(xy 93.142811 -248.271512) (xy 93.101215 -248.241291) (xy 93.064859 -248.204935) (xy 93.034638 -248.163339)
			(xy 93.011295 -248.117527) (xy 92.995407 -248.068628) (xy 92.987364 -248.017846) (xy 92.70086 -248.017846)
			(xy 92.692817 -248.068628) (xy 92.676929 -248.117527) (xy 92.653586 -248.163339) (xy 92.623365 -248.204935)
			(xy 92.587009 -248.241291) (xy 92.545413 -248.271512) (xy 92.499601 -248.294855) (xy 92.450702 -248.310743)
			(xy 92.39992 -248.318786) (xy 92.348504 -248.318786) (xy 92.297722 -248.310743) (xy 92.248823 -248.294855)
			(xy 92.203011 -248.271512) (xy 92.161415 -248.241291) (xy 92.125059 -248.204935) (xy 92.094838 -248.163339)
			(xy 92.071495 -248.117527) (xy 92.055607 -248.068628) (xy 92.047564 -248.017846) (xy 90.82126 -248.017846)
			(xy 90.813217 -248.068628) (xy 90.797329 -248.117527) (xy 90.773986 -248.163339) (xy 90.743765 -248.204935)
			(xy 90.707409 -248.241291) (xy 90.665813 -248.271512) (xy 90.620001 -248.294855) (xy 90.571102 -248.310743)
			(xy 90.52032 -248.318786) (xy 90.468904 -248.318786) (xy 90.418122 -248.310743) (xy 90.369223 -248.294855)
			(xy 90.323411 -248.271512) (xy 90.281815 -248.241291) (xy 90.245459 -248.204935) (xy 90.215238 -248.163339)
			(xy 90.191895 -248.117527) (xy 90.176007 -248.068628) (xy 90.167964 -248.017846) (xy 88.94166 -248.017846)
			(xy 88.933617 -248.068628) (xy 88.917729 -248.117527) (xy 88.894386 -248.163339) (xy 88.864165 -248.204935)
			(xy 88.827809 -248.241291) (xy 88.786213 -248.271512) (xy 88.740401 -248.294855) (xy 88.691502 -248.310743)
			(xy 88.64072 -248.318786) (xy 88.589304 -248.318786) (xy 88.538522 -248.310743) (xy 88.489623 -248.294855)
			(xy 88.443811 -248.271512) (xy 88.402215 -248.241291) (xy 88.365859 -248.204935) (xy 88.335638 -248.163339)
			(xy 88.312295 -248.117527) (xy 88.296407 -248.068628) (xy 88.288364 -248.017846) (xy 84.763918 -248.017846)
			(xy 85.577988 -248.831916) (xy 88.758518 -248.831916) (xy 88.758518 -248.7805) (xy 88.766561 -248.729718)
			(xy 88.782449 -248.680819) (xy 88.805792 -248.635007) (xy 88.836013 -248.593411) (xy 88.872369 -248.557055)
			(xy 88.913965 -248.526834) (xy 88.959777 -248.503491) (xy 89.008676 -248.487603) (xy 89.059458 -248.47956)
			(xy 89.110874 -248.47956) (xy 89.161656 -248.487603) (xy 89.210555 -248.503491) (xy 89.256367 -248.526834)
			(xy 89.297963 -248.557055) (xy 89.334319 -248.593411) (xy 89.36454 -248.635007) (xy 89.387883 -248.680819)
			(xy 89.403771 -248.729718) (xy 89.411814 -248.7805) (xy 89.412318 -248.806208) (xy 89.411814 -248.831916)
			(xy 89.698318 -248.831916) (xy 89.698318 -248.7805) (xy 89.706361 -248.729718) (xy 89.722249 -248.680819)
			(xy 89.745592 -248.635007) (xy 89.775813 -248.593411) (xy 89.812169 -248.557055) (xy 89.853765 -248.526834)
			(xy 89.899577 -248.503491) (xy 89.948476 -248.487603) (xy 89.999258 -248.47956) (xy 90.050674 -248.47956)
			(xy 90.101456 -248.487603) (xy 90.150355 -248.503491) (xy 90.196167 -248.526834) (xy 90.237763 -248.557055)
			(xy 90.274119 -248.593411) (xy 90.30434 -248.635007) (xy 90.327683 -248.680819) (xy 90.343571 -248.729718)
			(xy 90.351614 -248.7805) (xy 90.352118 -248.806208) (xy 90.351614 -248.831916) (xy 91.577918 -248.831916)
			(xy 91.577918 -248.7805) (xy 91.585961 -248.729718) (xy 91.601849 -248.680819) (xy 91.625192 -248.635007)
			(xy 91.655413 -248.593411) (xy 91.691769 -248.557055) (xy 91.733365 -248.526834) (xy 91.779177 -248.503491)
			(xy 91.828076 -248.487603) (xy 91.878858 -248.47956) (xy 91.930274 -248.47956) (xy 91.981056 -248.487603)
			(xy 92.029955 -248.503491) (xy 92.075767 -248.526834) (xy 92.117363 -248.557055) (xy 92.153719 -248.593411)
			(xy 92.18394 -248.635007) (xy 92.207283 -248.680819) (xy 92.223171 -248.729718) (xy 92.231214 -248.7805)
			(xy 92.231718 -248.806208) (xy 92.231214 -248.831916) (xy 93.457518 -248.831916) (xy 93.457518 -248.7805)
			(xy 93.465561 -248.729718) (xy 93.481449 -248.680819) (xy 93.504792 -248.635007) (xy 93.535013 -248.593411)
			(xy 93.571369 -248.557055) (xy 93.612965 -248.526834) (xy 93.658777 -248.503491) (xy 93.707676 -248.487603)
			(xy 93.758458 -248.47956) (xy 93.809874 -248.47956) (xy 93.860656 -248.487603) (xy 93.909555 -248.503491)
			(xy 93.955367 -248.526834) (xy 93.996963 -248.557055) (xy 94.033319 -248.593411) (xy 94.06354 -248.635007)
			(xy 94.086883 -248.680819) (xy 94.102771 -248.729718) (xy 94.110814 -248.7805) (xy 94.111318 -248.806208)
			(xy 94.110814 -248.831916) (xy 95.337118 -248.831916) (xy 95.337118 -248.7805) (xy 95.345161 -248.729718)
			(xy 95.361049 -248.680819) (xy 95.384392 -248.635007) (xy 95.414613 -248.593411) (xy 95.450969 -248.557055)
			(xy 95.492565 -248.526834) (xy 95.538377 -248.503491) (xy 95.587276 -248.487603) (xy 95.638058 -248.47956)
			(xy 95.689474 -248.47956) (xy 95.740256 -248.487603) (xy 95.789155 -248.503491) (xy 95.834967 -248.526834)
			(xy 95.876563 -248.557055) (xy 95.912919 -248.593411) (xy 95.94314 -248.635007) (xy 95.966483 -248.680819)
			(xy 95.982371 -248.729718) (xy 95.990414 -248.7805) (xy 95.990918 -248.806208) (xy 95.990414 -248.831916)
			(xy 96.276918 -248.831916) (xy 96.276918 -248.7805) (xy 96.284961 -248.729718) (xy 96.300849 -248.680819)
			(xy 96.324192 -248.635007) (xy 96.354413 -248.593411) (xy 96.390769 -248.557055) (xy 96.432365 -248.526834)
			(xy 96.478177 -248.503491) (xy 96.527076 -248.487603) (xy 96.577858 -248.47956) (xy 96.629274 -248.47956)
			(xy 96.680056 -248.487603) (xy 96.728955 -248.503491) (xy 96.774767 -248.526834) (xy 96.816363 -248.557055)
			(xy 96.852719 -248.593411) (xy 96.88294 -248.635007) (xy 96.906283 -248.680819) (xy 96.922171 -248.729718)
			(xy 96.930214 -248.7805) (xy 96.930718 -248.806208) (xy 96.930214 -248.831916) (xy 98.156518 -248.831916)
			(xy 98.156518 -248.7805) (xy 98.164561 -248.729718) (xy 98.180449 -248.680819) (xy 98.203792 -248.635007)
			(xy 98.234013 -248.593411) (xy 98.270369 -248.557055) (xy 98.311965 -248.526834) (xy 98.357777 -248.503491)
			(xy 98.406676 -248.487603) (xy 98.457458 -248.47956) (xy 98.508874 -248.47956) (xy 98.559656 -248.487603)
			(xy 98.608555 -248.503491) (xy 98.654367 -248.526834) (xy 98.695963 -248.557055) (xy 98.732319 -248.593411)
			(xy 98.76254 -248.635007) (xy 98.785883 -248.680819) (xy 98.801771 -248.729718) (xy 98.809814 -248.7805)
			(xy 98.810318 -248.806208) (xy 98.809814 -248.831916) (xy 98.801771 -248.882698) (xy 98.785883 -248.931597)
			(xy 98.76254 -248.977409) (xy 98.732319 -249.019005) (xy 98.695963 -249.055361) (xy 98.654367 -249.085582)
			(xy 98.608555 -249.108925) (xy 98.559656 -249.124813) (xy 98.508874 -249.132856) (xy 98.457458 -249.132856)
			(xy 98.406676 -249.124813) (xy 98.357777 -249.108925) (xy 98.311965 -249.085582) (xy 98.270369 -249.055361)
			(xy 98.234013 -249.019005) (xy 98.203792 -248.977409) (xy 98.180449 -248.931597) (xy 98.164561 -248.882698)
			(xy 98.156518 -248.831916) (xy 96.930214 -248.831916) (xy 96.922171 -248.882698) (xy 96.906283 -248.931597)
			(xy 96.88294 -248.977409) (xy 96.852719 -249.019005) (xy 96.816363 -249.055361) (xy 96.774767 -249.085582)
			(xy 96.728955 -249.108925) (xy 96.680056 -249.124813) (xy 96.629274 -249.132856) (xy 96.577858 -249.132856)
			(xy 96.527076 -249.124813) (xy 96.478177 -249.108925) (xy 96.432365 -249.085582) (xy 96.390769 -249.055361)
			(xy 96.354413 -249.019005) (xy 96.324192 -248.977409) (xy 96.300849 -248.931597) (xy 96.284961 -248.882698)
			(xy 96.276918 -248.831916) (xy 95.990414 -248.831916) (xy 95.982371 -248.882698) (xy 95.966483 -248.931597)
			(xy 95.94314 -248.977409) (xy 95.912919 -249.019005) (xy 95.876563 -249.055361) (xy 95.834967 -249.085582)
			(xy 95.789155 -249.108925) (xy 95.740256 -249.124813) (xy 95.689474 -249.132856) (xy 95.638058 -249.132856)
			(xy 95.587276 -249.124813) (xy 95.538377 -249.108925) (xy 95.492565 -249.085582) (xy 95.450969 -249.055361)
			(xy 95.414613 -249.019005) (xy 95.384392 -248.977409) (xy 95.361049 -248.931597) (xy 95.345161 -248.882698)
			(xy 95.337118 -248.831916) (xy 94.110814 -248.831916) (xy 94.102771 -248.882698) (xy 94.086883 -248.931597)
			(xy 94.06354 -248.977409) (xy 94.033319 -249.019005) (xy 93.996963 -249.055361) (xy 93.955367 -249.085582)
			(xy 93.909555 -249.108925) (xy 93.860656 -249.124813) (xy 93.809874 -249.132856) (xy 93.758458 -249.132856)
			(xy 93.707676 -249.124813) (xy 93.658777 -249.108925) (xy 93.612965 -249.085582) (xy 93.571369 -249.055361)
			(xy 93.535013 -249.019005) (xy 93.504792 -248.977409) (xy 93.481449 -248.931597) (xy 93.465561 -248.882698)
			(xy 93.457518 -248.831916) (xy 92.231214 -248.831916) (xy 92.223171 -248.882698) (xy 92.207283 -248.931597)
			(xy 92.18394 -248.977409) (xy 92.153719 -249.019005) (xy 92.117363 -249.055361) (xy 92.075767 -249.085582)
			(xy 92.029955 -249.108925) (xy 91.981056 -249.124813) (xy 91.930274 -249.132856) (xy 91.878858 -249.132856)
			(xy 91.828076 -249.124813) (xy 91.779177 -249.108925) (xy 91.733365 -249.085582) (xy 91.691769 -249.055361)
			(xy 91.655413 -249.019005) (xy 91.625192 -248.977409) (xy 91.601849 -248.931597) (xy 91.585961 -248.882698)
			(xy 91.577918 -248.831916) (xy 90.351614 -248.831916) (xy 90.343571 -248.882698) (xy 90.327683 -248.931597)
			(xy 90.30434 -248.977409) (xy 90.274119 -249.019005) (xy 90.237763 -249.055361) (xy 90.196167 -249.085582)
			(xy 90.150355 -249.108925) (xy 90.101456 -249.124813) (xy 90.050674 -249.132856) (xy 89.999258 -249.132856)
			(xy 89.948476 -249.124813) (xy 89.899577 -249.108925) (xy 89.853765 -249.085582) (xy 89.812169 -249.055361)
			(xy 89.775813 -249.019005) (xy 89.745592 -248.977409) (xy 89.722249 -248.931597) (xy 89.706361 -248.882698)
			(xy 89.698318 -248.831916) (xy 89.411814 -248.831916) (xy 89.403771 -248.882698) (xy 89.387883 -248.931597)
			(xy 89.36454 -248.977409) (xy 89.334319 -249.019005) (xy 89.297963 -249.055361) (xy 89.256367 -249.085582)
			(xy 89.210555 -249.108925) (xy 89.161656 -249.124813) (xy 89.110874 -249.132856) (xy 89.059458 -249.132856)
			(xy 89.008676 -249.124813) (xy 88.959777 -249.108925) (xy 88.913965 -249.085582) (xy 88.872369 -249.055361)
			(xy 88.836013 -249.019005) (xy 88.805792 -248.977409) (xy 88.782449 -248.931597) (xy 88.766561 -248.882698)
			(xy 88.758518 -248.831916) (xy 85.577988 -248.831916) (xy 85.995002 -249.24893) (xy 86.015188 -249.269868)
			(xy 86.049386 -249.31691) (xy 86.075802 -249.368722) (xy 86.093785 -249.42403) (xy 86.102893 -249.481471)
			(xy 86.10346 -249.51055) (xy 86.10346 -249.54484) (xy 86.204335 -249.645732) (xy 91.107764 -249.645732)
			(xy 91.107764 -249.594316) (xy 91.115807 -249.543534) (xy 91.131695 -249.494635) (xy 91.155038 -249.448823)
			(xy 91.185259 -249.407227) (xy 91.221615 -249.370871) (xy 91.263211 -249.34065) (xy 91.309023 -249.317307)
			(xy 91.357922 -249.301419) (xy 91.408704 -249.293376) (xy 91.46012 -249.293376) (xy 91.510902 -249.301419)
			(xy 91.559801 -249.317307) (xy 91.605613 -249.34065) (xy 91.647209 -249.370871) (xy 91.683565 -249.407227)
			(xy 91.713786 -249.448823) (xy 91.737129 -249.494635) (xy 91.753017 -249.543534) (xy 91.76106 -249.594316)
			(xy 91.761564 -249.620024) (xy 91.76106 -249.645732) (xy 92.047564 -249.645732) (xy 92.047564 -249.594316)
			(xy 92.055607 -249.543534) (xy 92.071495 -249.494635) (xy 92.094838 -249.448823) (xy 92.125059 -249.407227)
			(xy 92.161415 -249.370871) (xy 92.203011 -249.34065) (xy 92.248823 -249.317307) (xy 92.297722 -249.301419)
			(xy 92.348504 -249.293376) (xy 92.39992 -249.293376) (xy 92.450702 -249.301419) (xy 92.499601 -249.317307)
			(xy 92.545413 -249.34065) (xy 92.587009 -249.370871) (xy 92.623365 -249.407227) (xy 92.653586 -249.448823)
			(xy 92.676929 -249.494635) (xy 92.692817 -249.543534) (xy 92.70086 -249.594316) (xy 92.701364 -249.620024)
			(xy 92.70086 -249.645732) (xy 92.987364 -249.645732) (xy 92.987364 -249.594316) (xy 92.995407 -249.543534)
			(xy 93.011295 -249.494635) (xy 93.034638 -249.448823) (xy 93.064859 -249.407227) (xy 93.101215 -249.370871)
			(xy 93.142811 -249.34065) (xy 93.188623 -249.317307) (xy 93.237522 -249.301419) (xy 93.288304 -249.293376)
			(xy 93.33972 -249.293376) (xy 93.390502 -249.301419) (xy 93.439401 -249.317307) (xy 93.485213 -249.34065)
			(xy 93.526809 -249.370871) (xy 93.563165 -249.407227) (xy 93.593386 -249.448823) (xy 93.616729 -249.494635)
			(xy 93.632617 -249.543534) (xy 93.64066 -249.594316) (xy 93.641164 -249.620024) (xy 93.64066 -249.645732)
			(xy 93.927164 -249.645732) (xy 93.927164 -249.594316) (xy 93.935207 -249.543534) (xy 93.951095 -249.494635)
			(xy 93.974438 -249.448823) (xy 94.004659 -249.407227) (xy 94.041015 -249.370871) (xy 94.082611 -249.34065)
			(xy 94.128423 -249.317307) (xy 94.177322 -249.301419) (xy 94.228104 -249.293376) (xy 94.27952 -249.293376)
			(xy 94.330302 -249.301419) (xy 94.379201 -249.317307) (xy 94.425013 -249.34065) (xy 94.466609 -249.370871)
			(xy 94.502965 -249.407227) (xy 94.533186 -249.448823) (xy 94.556529 -249.494635) (xy 94.572417 -249.543534)
			(xy 94.58046 -249.594316) (xy 94.580964 -249.620024) (xy 94.58046 -249.645732) (xy 97.686364 -249.645732)
			(xy 97.686364 -249.594316) (xy 97.694407 -249.543534) (xy 97.710295 -249.494635) (xy 97.733638 -249.448823)
			(xy 97.763859 -249.407227) (xy 97.800215 -249.370871) (xy 97.841811 -249.34065) (xy 97.887623 -249.317307)
			(xy 97.936522 -249.301419) (xy 97.987304 -249.293376) (xy 98.03872 -249.293376) (xy 98.089502 -249.301419)
			(xy 98.138401 -249.317307) (xy 98.184213 -249.34065) (xy 98.225809 -249.370871) (xy 98.262165 -249.407227)
			(xy 98.292386 -249.448823) (xy 98.315729 -249.494635) (xy 98.331617 -249.543534) (xy 98.33966 -249.594316)
			(xy 98.340164 -249.620024) (xy 98.33966 -249.645732) (xy 98.331617 -249.696514) (xy 98.315729 -249.745413)
			(xy 98.292386 -249.791225) (xy 98.262165 -249.832821) (xy 98.225809 -249.869177) (xy 98.184213 -249.899398)
			(xy 98.138401 -249.922741) (xy 98.089502 -249.938629) (xy 98.03872 -249.946672) (xy 97.987304 -249.946672)
			(xy 97.936522 -249.938629) (xy 97.887623 -249.922741) (xy 97.841811 -249.899398) (xy 97.800215 -249.869177)
			(xy 97.763859 -249.832821) (xy 97.733638 -249.791225) (xy 97.710295 -249.745413) (xy 97.694407 -249.696514)
			(xy 97.686364 -249.645732) (xy 94.58046 -249.645732) (xy 94.572417 -249.696514) (xy 94.556529 -249.745413)
			(xy 94.533186 -249.791225) (xy 94.502965 -249.832821) (xy 94.466609 -249.869177) (xy 94.425013 -249.899398)
			(xy 94.379201 -249.922741) (xy 94.330302 -249.938629) (xy 94.27952 -249.946672) (xy 94.228104 -249.946672)
			(xy 94.177322 -249.938629) (xy 94.128423 -249.922741) (xy 94.082611 -249.899398) (xy 94.041015 -249.869177)
			(xy 94.004659 -249.832821) (xy 93.974438 -249.791225) (xy 93.951095 -249.745413) (xy 93.935207 -249.696514)
			(xy 93.927164 -249.645732) (xy 93.64066 -249.645732) (xy 93.632617 -249.696514) (xy 93.616729 -249.745413)
			(xy 93.593386 -249.791225) (xy 93.563165 -249.832821) (xy 93.526809 -249.869177) (xy 93.485213 -249.899398)
			(xy 93.439401 -249.922741) (xy 93.390502 -249.938629) (xy 93.33972 -249.946672) (xy 93.288304 -249.946672)
			(xy 93.237522 -249.938629) (xy 93.188623 -249.922741) (xy 93.142811 -249.899398) (xy 93.101215 -249.869177)
			(xy 93.064859 -249.832821) (xy 93.034638 -249.791225) (xy 93.011295 -249.745413) (xy 92.995407 -249.696514)
			(xy 92.987364 -249.645732) (xy 92.70086 -249.645732) (xy 92.692817 -249.696514) (xy 92.676929 -249.745413)
			(xy 92.653586 -249.791225) (xy 92.623365 -249.832821) (xy 92.587009 -249.869177) (xy 92.545413 -249.899398)
			(xy 92.499601 -249.922741) (xy 92.450702 -249.938629) (xy 92.39992 -249.946672) (xy 92.348504 -249.946672)
			(xy 92.297722 -249.938629) (xy 92.248823 -249.922741) (xy 92.203011 -249.899398) (xy 92.161415 -249.869177)
			(xy 92.125059 -249.832821) (xy 92.094838 -249.791225) (xy 92.071495 -249.745413) (xy 92.055607 -249.696514)
			(xy 92.047564 -249.645732) (xy 91.76106 -249.645732) (xy 91.753017 -249.696514) (xy 91.737129 -249.745413)
			(xy 91.713786 -249.791225) (xy 91.683565 -249.832821) (xy 91.647209 -249.869177) (xy 91.605613 -249.899398)
			(xy 91.559801 -249.922741) (xy 91.510902 -249.938629) (xy 91.46012 -249.946672) (xy 91.408704 -249.946672)
			(xy 91.357922 -249.938629) (xy 91.309023 -249.922741) (xy 91.263211 -249.899398) (xy 91.221615 -249.869177)
			(xy 91.185259 -249.832821) (xy 91.155038 -249.791225) (xy 91.131695 -249.745413) (xy 91.115807 -249.696514)
			(xy 91.107764 -249.645732) (xy 86.204335 -249.645732) (xy 87.650066 -251.0917) (xy 97.721166 -251.0917)
		)
		(stroke
			(width 0)
			(type solid)
		)
		(fill yes)
		(layer "B.Cu")
		(net "GND")
	)
	(gr_poly
		(pts
			(xy 346.572586 -249.691144) (xy 346.56903 -249.665998) (xy 346.56749 -249.654567) (xy 346.565839 -249.631558)
			(xy 346.565728 -249.620024) (xy 346.566276 -249.592727) (xy 346.575345 -249.538891) (xy 346.593235 -249.487311)
			(xy 346.619448 -249.439421) (xy 346.653256 -249.396554) (xy 346.693717 -249.359901) (xy 346.739707 -249.330482)
			(xy 346.76461 -249.319288) (xy 346.795344 -249.30608) (xy 346.795344 -249.138694) (xy 346.794867 -249.124364)
			(xy 346.786917 -249.096829) (xy 346.771618 -249.072593) (xy 346.75018 -249.053573) (xy 346.724295 -249.04127)
			(xy 346.696009 -249.036656) (xy 346.667556 -249.040096) (xy 346.641185 -249.051318) (xy 346.629736 -249.059954)
			(xy 346.607695 -249.07716) (xy 346.558965 -249.104571) (xy 346.506286 -249.123303) (xy 346.451189 -249.13281)
			(xy 346.423234 -249.13336) (xy 346.397522 -249.132884) (xy 346.34673 -249.124845) (xy 346.297821 -249.108958)
			(xy 346.252 -249.085615) (xy 346.210395 -249.055391) (xy 346.174031 -249.019031) (xy 346.143803 -248.977429)
			(xy 346.120455 -248.93161) (xy 346.104563 -248.882703) (xy 346.096518 -248.831912) (xy 346.096518 -248.780488)
			(xy 346.104563 -248.729697) (xy 346.120455 -248.68079) (xy 346.143803 -248.634971) (xy 346.174031 -248.593369)
			(xy 346.210395 -248.557009) (xy 346.252 -248.526785) (xy 346.297821 -248.503442) (xy 346.34673 -248.487555)
			(xy 346.397522 -248.479516) (xy 346.423234 -248.479056) (xy 346.451187 -248.479628) (xy 346.50628 -248.489135)
			(xy 346.558955 -248.507866) (xy 346.607681 -248.535277) (xy 346.629736 -248.552462) (xy 346.641162 -248.561117)
			(xy 346.667544 -248.572294) (xy 346.695992 -248.575703) (xy 346.724268 -248.571076) (xy 346.750145 -248.558777)
			(xy 346.771588 -248.539774) (xy 346.786908 -248.515562) (xy 346.7949 -248.488047) (xy 346.795344 -248.473722)
			(xy 346.795344 -248.306082) (xy 346.76461 -248.292874) (xy 346.741404 -248.282411) (xy 346.698279 -248.25537)
			(xy 346.659862 -248.221976) (xy 346.62708 -248.183036) (xy 346.600723 -248.139489) (xy 346.581429 -248.092386)
			(xy 346.569662 -248.042863) (xy 346.565706 -247.992115) (xy 346.569657 -247.941367) (xy 346.58142 -247.891843)
			(xy 346.60071 -247.844737) (xy 346.627062 -247.801188) (xy 346.659841 -247.762245) (xy 346.698255 -247.728848)
			(xy 346.741378 -247.701803) (xy 346.76461 -247.691402) (xy 346.795344 -247.678194) (xy 346.795344 -246.67845)
			(xy 346.76461 -246.665242) (xy 346.741362 -246.654819) (xy 346.698147 -246.627836) (xy 346.659643 -246.594476)
			(xy 346.626781 -246.555545) (xy 346.600358 -246.511986) (xy 346.581013 -246.464856) (xy 346.569215 -246.415294)
			(xy 346.56525 -246.364502) (xy 346.569214 -246.31371) (xy 346.581011 -246.264149) (xy 346.600355 -246.217018)
			(xy 346.626778 -246.173459) (xy 346.65964 -246.134528) (xy 346.698144 -246.101166) (xy 346.741358 -246.074184)
			(xy 346.76461 -246.06377) (xy 346.795344 -246.050562) (xy 346.795344 -245.883176) (xy 346.794865 -245.868848)
			(xy 346.786912 -245.841317) (xy 346.771612 -245.817087) (xy 346.750175 -245.79807) (xy 346.724293 -245.78577)
			(xy 346.696011 -245.781156) (xy 346.667562 -245.784595) (xy 346.641193 -245.795814) (xy 346.629736 -245.804436)
			(xy 346.607685 -245.821608) (xy 346.558943 -245.848946) (xy 346.506262 -245.867599) (xy 346.451177 -245.877023)
			(xy 346.423234 -245.877588) (xy 346.397543 -245.877113) (xy 346.346794 -245.86908) (xy 346.297926 -245.853206)
			(xy 346.252143 -245.829883) (xy 346.210572 -245.799684) (xy 346.174238 -245.763354) (xy 346.144035 -245.721786)
			(xy 346.120707 -245.676006) (xy 346.104828 -245.62714) (xy 346.09679 -245.576391) (xy 346.09679 -245.525009)
			(xy 346.104828 -245.47426) (xy 346.120707 -245.425394) (xy 346.144035 -245.379614) (xy 346.174238 -245.338046)
			(xy 346.210572 -245.301716) (xy 346.252143 -245.271517) (xy 346.297926 -245.248194) (xy 346.346794 -245.23232)
			(xy 346.397543 -245.224287) (xy 346.423234 -245.223792) (xy 346.451176 -245.224344) (xy 346.506253 -245.233799)
			(xy 346.558927 -245.252462) (xy 346.60767 -245.279793) (xy 346.629736 -245.296944) (xy 346.641161 -245.3056)
			(xy 346.667542 -245.316779) (xy 346.69599 -245.320189) (xy 346.724265 -245.315562) (xy 346.750142 -245.303262)
			(xy 346.771583 -245.284258) (xy 346.7869 -245.260045) (xy 346.794888 -245.232529) (xy 346.795344 -245.218204)
			(xy 346.795344 -245.050564) (xy 346.76461 -245.037356) (xy 346.741361 -245.026933) (xy 346.698144 -244.99995)
			(xy 346.659638 -244.966589) (xy 346.626774 -244.927657) (xy 346.600349 -244.884097) (xy 346.581002 -244.836965)
			(xy 346.569203 -244.787402) (xy 346.565237 -244.736608) (xy 346.569201 -244.685814) (xy 346.580997 -244.63625)
			(xy 346.600341 -244.589117) (xy 346.626765 -244.545556) (xy 346.659627 -244.506622) (xy 346.698132 -244.473259)
			(xy 346.741347 -244.446275) (xy 346.76461 -244.435884) (xy 346.795344 -244.422676) (xy 346.795344 -244.25529)
			(xy 346.794866 -244.24096) (xy 346.786916 -244.213426) (xy 346.771617 -244.189192) (xy 346.750179 -244.170172)
			(xy 346.724294 -244.15787) (xy 346.696009 -244.153256) (xy 346.667557 -244.156696) (xy 346.641187 -244.167917)
			(xy 346.629736 -244.17655) (xy 346.607695 -244.193756) (xy 346.558965 -244.221168) (xy 346.506286 -244.2399)
			(xy 346.451189 -244.249407) (xy 346.423234 -244.249956) (xy 346.397522 -244.24948) (xy 346.346731 -244.241441)
			(xy 346.297823 -244.225554) (xy 346.252002 -244.202212) (xy 346.210398 -244.171988) (xy 346.174034 -244.135628)
			(xy 346.143806 -244.094027) (xy 346.120459 -244.048209) (xy 346.104567 -243.999302) (xy 346.096522 -243.948512)
			(xy 346.096522 -243.897088) (xy 346.104567 -243.846298) (xy 346.120459 -243.797391) (xy 346.143806 -243.751573)
			(xy 346.174034 -243.709972) (xy 346.210398 -243.673612) (xy 346.252002 -243.643388) (xy 346.297823 -243.620046)
			(xy 346.346731 -243.604159) (xy 346.397522 -243.59612) (xy 346.423234 -243.595652) (xy 346.451187 -243.596224)
			(xy 346.50628 -243.605731) (xy 346.558955 -243.624462) (xy 346.607681 -243.651872) (xy 346.629736 -243.669058)
			(xy 346.641162 -243.677713) (xy 346.667544 -243.688891) (xy 346.695991 -243.6923) (xy 346.724267 -243.687673)
			(xy 346.750144 -243.675374) (xy 346.771587 -243.65637) (xy 346.786906 -243.632158) (xy 346.794897 -243.604643)
			(xy 346.795344 -243.590318) (xy 346.795344 -243.422932) (xy 346.76461 -243.409724) (xy 346.741363 -243.399301)
			(xy 346.698152 -243.372319) (xy 346.65965 -243.338959) (xy 346.62679 -243.300029) (xy 346.600369 -243.256473)
			(xy 346.581026 -243.209344) (xy 346.56923 -243.159785) (xy 346.565267 -243.108995) (xy 346.569232 -243.058206)
			(xy 346.581029 -243.008647) (xy 346.600373 -242.961519) (xy 346.626796 -242.917963) (xy 346.659656 -242.879034)
			(xy 346.698159 -242.845675) (xy 346.741372 -242.818695) (xy 346.76461 -242.808252) (xy 346.795344 -242.795044)
			(xy 346.795344 -241.795046) (xy 346.76461 -241.781838) (xy 346.741362 -241.771415) (xy 346.698148 -241.744433)
			(xy 346.659644 -241.711072) (xy 346.626783 -241.672141) (xy 346.60036 -241.628583) (xy 346.581016 -241.581453)
			(xy 346.569218 -241.531892) (xy 346.565254 -241.481101) (xy 346.569218 -241.430309) (xy 346.581015 -241.380748)
			(xy 346.600359 -241.333618) (xy 346.626782 -241.29006) (xy 346.659643 -241.251129) (xy 346.698147 -241.217768)
			(xy 346.741361 -241.190786) (xy 346.76461 -241.180366) (xy 346.795344 -241.167158) (xy 346.795344 -240.999772)
			(xy 346.794864 -240.985444) (xy 346.78691 -240.957915) (xy 346.771611 -240.933685) (xy 346.750174 -240.91467)
			(xy 346.724293 -240.902369) (xy 346.696011 -240.897756) (xy 346.667563 -240.901194) (xy 346.641195 -240.912412)
			(xy 346.629736 -240.921032) (xy 346.607685 -240.938204) (xy 346.558943 -240.965543) (xy 346.506263 -240.984196)
			(xy 346.451178 -240.993619) (xy 346.423234 -240.994184) (xy 346.397544 -240.993709) (xy 346.346795 -240.985676)
			(xy 346.297927 -240.969802) (xy 346.252145 -240.946479) (xy 346.210575 -240.916281) (xy 346.174241 -240.879951)
			(xy 346.144039 -240.838384) (xy 346.120711 -240.792604) (xy 346.104832 -240.743739) (xy 346.096794 -240.69299)
			(xy 346.096794 -240.64161) (xy 346.104832 -240.590861) (xy 346.120711 -240.541996) (xy 346.144039 -240.496216)
			(xy 346.174241 -240.454649) (xy 346.210575 -240.418319) (xy 346.252145 -240.388121) (xy 346.297927 -240.364798)
			(xy 346.346795 -240.348924) (xy 346.397544 -240.340891) (xy 346.423234 -240.340388) (xy 346.451176 -240.34094)
			(xy 346.506253 -240.350395) (xy 346.558927 -240.369058) (xy 346.607671 -240.396388) (xy 346.629736 -240.41354)
			(xy 346.641161 -240.422196) (xy 346.667541 -240.433376) (xy 346.695989 -240.436786) (xy 346.724264 -240.432159)
			(xy 346.750141 -240.419859) (xy 346.771582 -240.400854) (xy 346.786899 -240.376641) (xy 346.794886 -240.349125)
			(xy 346.795344 -240.3348) (xy 346.795344 -240.16716) (xy 346.76461 -240.153952) (xy 346.741361 -240.143529)
			(xy 346.698145 -240.116546) (xy 346.659639 -240.083185) (xy 346.626776 -240.044253) (xy 346.600351 -240.000694)
			(xy 346.581005 -239.953562) (xy 346.569207 -239.903999) (xy 346.565241 -239.853206) (xy 346.569205 -239.802413)
			(xy 346.581001 -239.75285) (xy 346.600345 -239.705717) (xy 346.626768 -239.662157) (xy 346.65963 -239.623224)
			(xy 346.698135 -239.589861) (xy 346.74135 -239.562877) (xy 346.76461 -239.55248) (xy 346.795344 -239.539272)
			(xy 346.795344 -239.371886) (xy 346.794866 -239.357556) (xy 346.786914 -239.330023) (xy 346.771616 -239.30579)
			(xy 346.750178 -239.286772) (xy 346.724294 -239.27447) (xy 346.69601 -239.269856) (xy 346.667559 -239.273296)
			(xy 346.641188 -239.284516) (xy 346.629736 -239.293146) (xy 346.607695 -239.310352) (xy 346.558966 -239.337764)
			(xy 346.506286 -239.356497) (xy 346.451189 -239.366004) (xy 346.423234 -239.366552) (xy 346.397531 -239.366076)
			(xy 346.346758 -239.358034) (xy 346.29787 -239.342144) (xy 346.252072 -239.318797) (xy 346.210493 -239.288569)
			(xy 346.174158 -239.252205) (xy 346.143964 -239.210601) (xy 346.120654 -239.164784) (xy 346.104804 -239.115883)
			(xy 346.096804 -239.065103) (xy 346.096336 -239.0394) (xy 346.096684 -239.016943) (xy 346.102791 -238.972447)
			(xy 346.114947 -238.92921) (xy 346.132919 -238.88805) (xy 346.144342 -238.868712) (xy 346.151037 -238.856991)
			(xy 346.15862 -238.831095) (xy 346.159155 -238.804116) (xy 346.152604 -238.77794) (xy 346.139424 -238.754394)
			(xy 346.120536 -238.735122) (xy 346.097259 -238.721472) (xy 346.07122 -238.714396) (xy 346.057728 -238.714026)
			(xy 344.90914 -238.714026) (xy 344.895648 -238.714439) (xy 344.869606 -238.721501) (xy 344.846324 -238.735141)
			(xy 344.827431 -238.754406) (xy 344.814248 -238.777949) (xy 344.807696 -238.804125) (xy 344.808233 -238.831103)
			(xy 344.815822 -238.856997) (xy 344.822526 -238.868712) (xy 344.833912 -238.888068) (xy 344.85186 -238.929232)
			(xy 344.864015 -238.972462) (xy 344.87015 -239.016947) (xy 344.870532 -239.0394) (xy 344.870028 -239.065088)
			(xy 344.861991 -239.115831) (xy 344.846115 -239.164692) (xy 344.822791 -239.210468) (xy 344.792594 -239.252032)
			(xy 344.756266 -239.28836) (xy 344.714702 -239.318557) (xy 344.668926 -239.341881) (xy 344.620065 -239.357757)
			(xy 344.569322 -239.365794) (xy 344.517946 -239.365794) (xy 344.467203 -239.357757) (xy 344.418342 -239.341881)
			(xy 344.372566 -239.318557) (xy 344.331002 -239.28836) (xy 344.294674 -239.252032) (xy 344.264477 -239.210468)
			(xy 344.241153 -239.164692) (xy 344.225277 -239.115831) (xy 344.21724 -239.065088) (xy 344.216736 -239.0394)
			(xy 344.217084 -239.016943) (xy 344.223191 -238.972447) (xy 344.235347 -238.92921) (xy 344.253319 -238.88805)
			(xy 344.264742 -238.868712) (xy 344.271437 -238.856991) (xy 344.27902 -238.831095) (xy 344.279555 -238.804116)
			(xy 344.273004 -238.77794) (xy 344.259824 -238.754394) (xy 344.240936 -238.735122) (xy 344.217659 -238.721472)
			(xy 344.19162 -238.714396) (xy 344.178128 -238.714026) (xy 343.96934 -238.714026) (xy 343.955848 -238.714439)
			(xy 343.929806 -238.721501) (xy 343.906524 -238.735141) (xy 343.887631 -238.754406) (xy 343.874448 -238.777949)
			(xy 343.867896 -238.804125) (xy 343.868433 -238.831103) (xy 343.876022 -238.856997) (xy 343.882726 -238.868712)
			(xy 343.894112 -238.888068) (xy 343.91206 -238.929232) (xy 343.924215 -238.972462) (xy 343.93035 -239.016947)
			(xy 343.930732 -239.0394) (xy 343.930228 -239.065088) (xy 343.922191 -239.115831) (xy 343.906315 -239.164692)
			(xy 343.882991 -239.210468) (xy 343.852794 -239.252032) (xy 343.816466 -239.28836) (xy 343.774902 -239.318557)
			(xy 343.729126 -239.341881) (xy 343.680265 -239.357757) (xy 343.629522 -239.365794) (xy 343.578146 -239.365794)
			(xy 343.527403 -239.357757) (xy 343.478542 -239.341881) (xy 343.432766 -239.318557) (xy 343.391202 -239.28836)
			(xy 343.354874 -239.252032) (xy 343.324677 -239.210468) (xy 343.301353 -239.164692) (xy 343.285477 -239.115831)
			(xy 343.27744 -239.065088) (xy 343.276936 -239.0394) (xy 343.277284 -239.016943) (xy 343.283391 -238.972447)
			(xy 343.295547 -238.92921) (xy 343.313519 -238.88805) (xy 343.324942 -238.868712) (xy 343.331637 -238.856991)
			(xy 343.33922 -238.831095) (xy 343.339755 -238.804116) (xy 343.333204 -238.77794) (xy 343.320024 -238.754394)
			(xy 343.301136 -238.735122) (xy 343.277859 -238.721472) (xy 343.25182 -238.714396) (xy 343.238328 -238.714026)
			(xy 342.08974 -238.714026) (xy 342.076248 -238.714439) (xy 342.050206 -238.721501) (xy 342.026924 -238.735141)
			(xy 342.008031 -238.754406) (xy 341.994848 -238.777949) (xy 341.988296 -238.804125) (xy 341.988833 -238.831103)
			(xy 341.996422 -238.856997) (xy 342.003126 -238.868712) (xy 342.014512 -238.888068) (xy 342.03246 -238.929232)
			(xy 342.044615 -238.972462) (xy 342.05075 -239.016947) (xy 342.051132 -239.0394) (xy 342.050628 -239.065088)
			(xy 342.042591 -239.115831) (xy 342.026715 -239.164692) (xy 342.003391 -239.210468) (xy 341.973194 -239.252032)
			(xy 341.936866 -239.28836) (xy 341.895302 -239.318557) (xy 341.849526 -239.341881) (xy 341.800665 -239.357757)
			(xy 341.749922 -239.365794) (xy 341.698546 -239.365794) (xy 341.647803 -239.357757) (xy 341.598942 -239.341881)
			(xy 341.553166 -239.318557) (xy 341.511602 -239.28836) (xy 341.475274 -239.252032) (xy 341.445077 -239.210468)
			(xy 341.421753 -239.164692) (xy 341.405877 -239.115831) (xy 341.39784 -239.065088) (xy 341.397336 -239.0394)
			(xy 341.397684 -239.016943) (xy 341.403791 -238.972447) (xy 341.415947 -238.92921) (xy 341.433919 -238.88805)
			(xy 341.445342 -238.868712) (xy 341.452037 -238.856991) (xy 341.45962 -238.831095) (xy 341.460155 -238.804116)
			(xy 341.453604 -238.77794) (xy 341.440424 -238.754394) (xy 341.421536 -238.735122) (xy 341.398259 -238.721472)
			(xy 341.37222 -238.714396) (xy 341.358728 -238.714026) (xy 340.21014 -238.714026) (xy 340.196648 -238.714439)
			(xy 340.170606 -238.721501) (xy 340.147324 -238.735141) (xy 340.128431 -238.754406) (xy 340.115248 -238.777949)
			(xy 340.108696 -238.804125) (xy 340.109233 -238.831103) (xy 340.116822 -238.856997) (xy 340.123526 -238.868712)
			(xy 340.134912 -238.888068) (xy 340.15286 -238.929232) (xy 340.165015 -238.972462) (xy 340.17115 -239.016947)
			(xy 340.171532 -239.0394) (xy 340.171028 -239.065088) (xy 340.162991 -239.115831) (xy 340.147115 -239.164692)
			(xy 340.123791 -239.210468) (xy 340.093594 -239.252032) (xy 340.057266 -239.28836) (xy 340.015702 -239.318557)
			(xy 339.969926 -239.341881) (xy 339.921065 -239.357757) (xy 339.870322 -239.365794) (xy 339.818946 -239.365794)
			(xy 339.768203 -239.357757) (xy 339.719342 -239.341881) (xy 339.673566 -239.318557) (xy 339.632002 -239.28836)
			(xy 339.595674 -239.252032) (xy 339.565477 -239.210468) (xy 339.542153 -239.164692) (xy 339.526277 -239.115831)
			(xy 339.51824 -239.065088) (xy 339.517736 -239.0394) (xy 339.518084 -239.016943) (xy 339.524191 -238.972447)
			(xy 339.536347 -238.92921) (xy 339.554319 -238.88805) (xy 339.565742 -238.868712) (xy 339.572437 -238.856991)
			(xy 339.58002 -238.831095) (xy 339.580555 -238.804116) (xy 339.574004 -238.77794) (xy 339.560824 -238.754394)
			(xy 339.541936 -238.735122) (xy 339.518659 -238.721472) (xy 339.49262 -238.714396) (xy 339.479128 -238.714026)
			(xy 338.33054 -238.714026) (xy 338.317048 -238.714439) (xy 338.291006 -238.721501) (xy 338.267724 -238.735141)
			(xy 338.248831 -238.754406) (xy 338.235648 -238.777949) (xy 338.229096 -238.804125) (xy 338.229633 -238.831103)
			(xy 338.237222 -238.856997) (xy 338.243926 -238.868712) (xy 338.255312 -238.888068) (xy 338.27326 -238.929232)
			(xy 338.285415 -238.972462) (xy 338.29155 -239.016947) (xy 338.291932 -239.0394) (xy 338.291428 -239.065088)
			(xy 338.283391 -239.115831) (xy 338.267515 -239.164692) (xy 338.244191 -239.210468) (xy 338.213994 -239.252032)
			(xy 338.177666 -239.28836) (xy 338.136102 -239.318557) (xy 338.090326 -239.341881) (xy 338.041465 -239.357757)
			(xy 337.990722 -239.365794) (xy 337.939346 -239.365794) (xy 337.888603 -239.357757) (xy 337.839742 -239.341881)
			(xy 337.793966 -239.318557) (xy 337.752402 -239.28836) (xy 337.716074 -239.252032) (xy 337.685877 -239.210468)
			(xy 337.662553 -239.164692) (xy 337.646677 -239.115831) (xy 337.63864 -239.065088) (xy 337.638136 -239.0394)
			(xy 337.638484 -239.016943) (xy 337.644591 -238.972447) (xy 337.656747 -238.92921) (xy 337.674719 -238.88805)
			(xy 337.686142 -238.868712) (xy 337.692837 -238.856991) (xy 337.70042 -238.831095) (xy 337.700955 -238.804116)
			(xy 337.694404 -238.77794) (xy 337.681224 -238.754394) (xy 337.662336 -238.735122) (xy 337.639059 -238.721472)
			(xy 337.61302 -238.714396) (xy 337.599528 -238.714026) (xy 337.39074 -238.714026) (xy 337.377248 -238.714439)
			(xy 337.351206 -238.721501) (xy 337.327924 -238.735141) (xy 337.309031 -238.754406) (xy 337.295848 -238.777949)
			(xy 337.289296 -238.804125) (xy 337.289833 -238.831103) (xy 337.297422 -238.856997) (xy 337.304126 -238.868712)
			(xy 337.315512 -238.888068) (xy 337.33346 -238.929232) (xy 337.345615 -238.972462) (xy 337.35175 -239.016947)
			(xy 337.352132 -239.0394) (xy 337.351628 -239.065088) (xy 337.343591 -239.115831) (xy 337.327715 -239.164692)
			(xy 337.304391 -239.210468) (xy 337.274194 -239.252032) (xy 337.237866 -239.28836) (xy 337.196302 -239.318557)
			(xy 337.150526 -239.341881) (xy 337.101665 -239.357757) (xy 337.050922 -239.365794) (xy 336.999546 -239.365794)
			(xy 336.948803 -239.357757) (xy 336.899942 -239.341881) (xy 336.854166 -239.318557) (xy 336.812602 -239.28836)
			(xy 336.776274 -239.252032) (xy 336.746077 -239.210468) (xy 336.722753 -239.164692) (xy 336.706877 -239.115831)
			(xy 336.69884 -239.065088) (xy 336.698336 -239.0394) (xy 336.698684 -239.016943) (xy 336.704791 -238.972447)
			(xy 336.716947 -238.92921) (xy 336.734919 -238.88805) (xy 336.746342 -238.868712) (xy 336.753037 -238.856991)
			(xy 336.76062 -238.831095) (xy 336.761155 -238.804116) (xy 336.754604 -238.77794) (xy 336.741424 -238.754394)
			(xy 336.722536 -238.735122) (xy 336.699259 -238.721472) (xy 336.67322 -238.714396) (xy 336.659728 -238.714026)
			(xy 335.449164 -238.714026) (xy 334.284266 -239.878924) (xy 339.047832 -239.878924) (xy 339.047832 -239.827508)
			(xy 339.055875 -239.776726) (xy 339.071763 -239.727827) (xy 339.095106 -239.682015) (xy 339.125327 -239.640419)
			(xy 339.161683 -239.604063) (xy 339.203279 -239.573842) (xy 339.249091 -239.550499) (xy 339.29799 -239.534611)
			(xy 339.348772 -239.526568) (xy 339.400188 -239.526568) (xy 339.45097 -239.534611) (xy 339.499869 -239.550499)
			(xy 339.545681 -239.573842) (xy 339.587277 -239.604063) (xy 339.623633 -239.640419) (xy 339.653854 -239.682015)
			(xy 339.677197 -239.727827) (xy 339.693085 -239.776726) (xy 339.701128 -239.827508) (xy 339.701632 -239.853216)
			(xy 339.701128 -239.878924) (xy 339.987632 -239.878924) (xy 339.987632 -239.827508) (xy 339.995675 -239.776726)
			(xy 340.011563 -239.727827) (xy 340.034906 -239.682015) (xy 340.065127 -239.640419) (xy 340.101483 -239.604063)
			(xy 340.143079 -239.573842) (xy 340.188891 -239.550499) (xy 340.23779 -239.534611) (xy 340.288572 -239.526568)
			(xy 340.339988 -239.526568) (xy 340.39077 -239.534611) (xy 340.439669 -239.550499) (xy 340.485481 -239.573842)
			(xy 340.527077 -239.604063) (xy 340.563433 -239.640419) (xy 340.593654 -239.682015) (xy 340.616997 -239.727827)
			(xy 340.632885 -239.776726) (xy 340.640928 -239.827508) (xy 340.641432 -239.853216) (xy 340.640928 -239.878924)
			(xy 340.927432 -239.878924) (xy 340.927432 -239.827508) (xy 340.935475 -239.776726) (xy 340.951363 -239.727827)
			(xy 340.974706 -239.682015) (xy 341.004927 -239.640419) (xy 341.041283 -239.604063) (xy 341.082879 -239.573842)
			(xy 341.128691 -239.550499) (xy 341.17759 -239.534611) (xy 341.228372 -239.526568) (xy 341.279788 -239.526568)
			(xy 341.33057 -239.534611) (xy 341.379469 -239.550499) (xy 341.425281 -239.573842) (xy 341.466877 -239.604063)
			(xy 341.503233 -239.640419) (xy 341.533454 -239.682015) (xy 341.556797 -239.727827) (xy 341.572685 -239.776726)
			(xy 341.580728 -239.827508) (xy 341.581232 -239.853216) (xy 341.580728 -239.878924) (xy 341.867232 -239.878924)
			(xy 341.867232 -239.827508) (xy 341.875275 -239.776726) (xy 341.891163 -239.727827) (xy 341.914506 -239.682015)
			(xy 341.944727 -239.640419) (xy 341.981083 -239.604063) (xy 342.022679 -239.573842) (xy 342.068491 -239.550499)
			(xy 342.11739 -239.534611) (xy 342.168172 -239.526568) (xy 342.219588 -239.526568) (xy 342.27037 -239.534611)
			(xy 342.319269 -239.550499) (xy 342.365081 -239.573842) (xy 342.406677 -239.604063) (xy 342.443033 -239.640419)
			(xy 342.473254 -239.682015) (xy 342.496597 -239.727827) (xy 342.512485 -239.776726) (xy 342.520528 -239.827508)
			(xy 342.521032 -239.853216) (xy 342.520528 -239.878924) (xy 345.626432 -239.878924) (xy 345.626432 -239.827508)
			(xy 345.634475 -239.776726) (xy 345.650363 -239.727827) (xy 345.673706 -239.682015) (xy 345.703927 -239.640419)
			(xy 345.740283 -239.604063) (xy 345.781879 -239.573842) (xy 345.827691 -239.550499) (xy 345.87659 -239.534611)
			(xy 345.927372 -239.526568) (xy 345.978788 -239.526568) (xy 346.02957 -239.534611) (xy 346.078469 -239.550499)
			(xy 346.124281 -239.573842) (xy 346.165877 -239.604063) (xy 346.202233 -239.640419) (xy 346.232454 -239.682015)
			(xy 346.255797 -239.727827) (xy 346.271685 -239.776726) (xy 346.279728 -239.827508) (xy 346.280232 -239.853216)
			(xy 346.279728 -239.878924) (xy 346.271685 -239.929706) (xy 346.255797 -239.978605) (xy 346.232454 -240.024417)
			(xy 346.202233 -240.066013) (xy 346.165877 -240.102369) (xy 346.124281 -240.13259) (xy 346.078469 -240.155933)
			(xy 346.02957 -240.171821) (xy 345.978788 -240.179864) (xy 345.927372 -240.179864) (xy 345.87659 -240.171821)
			(xy 345.827691 -240.155933) (xy 345.781879 -240.13259) (xy 345.740283 -240.102369) (xy 345.703927 -240.066013)
			(xy 345.673706 -240.024417) (xy 345.650363 -239.978605) (xy 345.634475 -239.929706) (xy 345.626432 -239.878924)
			(xy 342.520528 -239.878924) (xy 342.512485 -239.929706) (xy 342.496597 -239.978605) (xy 342.473254 -240.024417)
			(xy 342.443033 -240.066013) (xy 342.406677 -240.102369) (xy 342.365081 -240.13259) (xy 342.319269 -240.155933)
			(xy 342.27037 -240.171821) (xy 342.219588 -240.179864) (xy 342.168172 -240.179864) (xy 342.11739 -240.171821)
			(xy 342.068491 -240.155933) (xy 342.022679 -240.13259) (xy 341.981083 -240.102369) (xy 341.944727 -240.066013)
			(xy 341.914506 -240.024417) (xy 341.891163 -239.978605) (xy 341.875275 -239.929706) (xy 341.867232 -239.878924)
			(xy 341.580728 -239.878924) (xy 341.572685 -239.929706) (xy 341.556797 -239.978605) (xy 341.533454 -240.024417)
			(xy 341.503233 -240.066013) (xy 341.466877 -240.102369) (xy 341.425281 -240.13259) (xy 341.379469 -240.155933)
			(xy 341.33057 -240.171821) (xy 341.279788 -240.179864) (xy 341.228372 -240.179864) (xy 341.17759 -240.171821)
			(xy 341.128691 -240.155933) (xy 341.082879 -240.13259) (xy 341.041283 -240.102369) (xy 341.004927 -240.066013)
			(xy 340.974706 -240.024417) (xy 340.951363 -239.978605) (xy 340.935475 -239.929706) (xy 340.927432 -239.878924)
			(xy 340.640928 -239.878924) (xy 340.632885 -239.929706) (xy 340.616997 -239.978605) (xy 340.593654 -240.024417)
			(xy 340.563433 -240.066013) (xy 340.527077 -240.102369) (xy 340.485481 -240.13259) (xy 340.439669 -240.155933)
			(xy 340.39077 -240.171821) (xy 340.339988 -240.179864) (xy 340.288572 -240.179864) (xy 340.23779 -240.171821)
			(xy 340.188891 -240.155933) (xy 340.143079 -240.13259) (xy 340.101483 -240.102369) (xy 340.065127 -240.066013)
			(xy 340.034906 -240.024417) (xy 340.011563 -239.978605) (xy 339.995675 -239.929706) (xy 339.987632 -239.878924)
			(xy 339.701128 -239.878924) (xy 339.693085 -239.929706) (xy 339.677197 -239.978605) (xy 339.653854 -240.024417)
			(xy 339.623633 -240.066013) (xy 339.587277 -240.102369) (xy 339.545681 -240.13259) (xy 339.499869 -240.155933)
			(xy 339.45097 -240.171821) (xy 339.400188 -240.179864) (xy 339.348772 -240.179864) (xy 339.29799 -240.171821)
			(xy 339.249091 -240.155933) (xy 339.203279 -240.13259) (xy 339.161683 -240.102369) (xy 339.125327 -240.066013)
			(xy 339.095106 -240.024417) (xy 339.071763 -239.978605) (xy 339.055875 -239.929706) (xy 339.047832 -239.878924)
			(xy 334.284266 -239.878924) (xy 333.630524 -240.532666) (xy 331.847444 -240.532666) (xy 331.687116 -240.692994)
			(xy 336.698586 -240.692994) (xy 336.698586 -240.641578) (xy 336.706629 -240.590796) (xy 336.722517 -240.541897)
			(xy 336.74586 -240.496085) (xy 336.776081 -240.454489) (xy 336.812437 -240.418133) (xy 336.854033 -240.387912)
			(xy 336.899845 -240.364569) (xy 336.948744 -240.348681) (xy 336.999526 -240.340638) (xy 337.050942 -240.340638)
			(xy 337.101724 -240.348681) (xy 337.150623 -240.364569) (xy 337.196435 -240.387912) (xy 337.238031 -240.418133)
			(xy 337.274387 -240.454489) (xy 337.304608 -240.496085) (xy 337.327951 -240.541897) (xy 337.343839 -240.590796)
			(xy 337.351882 -240.641578) (xy 337.352386 -240.667286) (xy 337.351882 -240.692994) (xy 337.638386 -240.692994)
			(xy 337.638386 -240.641578) (xy 337.646429 -240.590796) (xy 337.662317 -240.541897) (xy 337.68566 -240.496085)
			(xy 337.715881 -240.454489) (xy 337.752237 -240.418133) (xy 337.793833 -240.387912) (xy 337.839645 -240.364569)
			(xy 337.888544 -240.348681) (xy 337.939326 -240.340638) (xy 337.990742 -240.340638) (xy 338.041524 -240.348681)
			(xy 338.090423 -240.364569) (xy 338.136235 -240.387912) (xy 338.177831 -240.418133) (xy 338.214187 -240.454489)
			(xy 338.244408 -240.496085) (xy 338.267751 -240.541897) (xy 338.283639 -240.590796) (xy 338.291682 -240.641578)
			(xy 338.292186 -240.667286) (xy 338.291682 -240.692994) (xy 339.517986 -240.692994) (xy 339.517986 -240.641578)
			(xy 339.526029 -240.590796) (xy 339.541917 -240.541897) (xy 339.56526 -240.496085) (xy 339.595481 -240.454489)
			(xy 339.631837 -240.418133) (xy 339.673433 -240.387912) (xy 339.719245 -240.364569) (xy 339.768144 -240.348681)
			(xy 339.818926 -240.340638) (xy 339.870342 -240.340638) (xy 339.921124 -240.348681) (xy 339.970023 -240.364569)
			(xy 340.015835 -240.387912) (xy 340.057431 -240.418133) (xy 340.093787 -240.454489) (xy 340.124008 -240.496085)
			(xy 340.147351 -240.541897) (xy 340.163239 -240.590796) (xy 340.171282 -240.641578) (xy 340.171786 -240.667286)
			(xy 340.171282 -240.692994) (xy 341.397586 -240.692994) (xy 341.397586 -240.641578) (xy 341.405629 -240.590796)
			(xy 341.421517 -240.541897) (xy 341.44486 -240.496085) (xy 341.475081 -240.454489) (xy 341.511437 -240.418133)
			(xy 341.553033 -240.387912) (xy 341.598845 -240.364569) (xy 341.647744 -240.348681) (xy 341.698526 -240.340638)
			(xy 341.749942 -240.340638) (xy 341.800724 -240.348681) (xy 341.849623 -240.364569) (xy 341.895435 -240.387912)
			(xy 341.937031 -240.418133) (xy 341.973387 -240.454489) (xy 342.003608 -240.496085) (xy 342.026951 -240.541897)
			(xy 342.042839 -240.590796) (xy 342.050882 -240.641578) (xy 342.051386 -240.667286) (xy 342.050882 -240.692994)
			(xy 343.277186 -240.692994) (xy 343.277186 -240.641578) (xy 343.285229 -240.590796) (xy 343.301117 -240.541897)
			(xy 343.32446 -240.496085) (xy 343.354681 -240.454489) (xy 343.391037 -240.418133) (xy 343.432633 -240.387912)
			(xy 343.478445 -240.364569) (xy 343.527344 -240.348681) (xy 343.578126 -240.340638) (xy 343.629542 -240.340638)
			(xy 343.680324 -240.348681) (xy 343.729223 -240.364569) (xy 343.775035 -240.387912) (xy 343.816631 -240.418133)
			(xy 343.852987 -240.454489) (xy 343.883208 -240.496085) (xy 343.906551 -240.541897) (xy 343.922439 -240.590796)
			(xy 343.930482 -240.641578) (xy 343.930986 -240.667286) (xy 343.930482 -240.692994) (xy 344.216986 -240.692994)
			(xy 344.216986 -240.641578) (xy 344.225029 -240.590796) (xy 344.240917 -240.541897) (xy 344.26426 -240.496085)
			(xy 344.294481 -240.454489) (xy 344.330837 -240.418133) (xy 344.372433 -240.387912) (xy 344.418245 -240.364569)
			(xy 344.467144 -240.348681) (xy 344.517926 -240.340638) (xy 344.569342 -240.340638) (xy 344.620124 -240.348681)
			(xy 344.669023 -240.364569) (xy 344.714835 -240.387912) (xy 344.756431 -240.418133) (xy 344.792787 -240.454489)
			(xy 344.823008 -240.496085) (xy 344.846351 -240.541897) (xy 344.862239 -240.590796) (xy 344.870282 -240.641578)
			(xy 344.870786 -240.667286) (xy 344.870282 -240.692994) (xy 344.862239 -240.743776) (xy 344.846351 -240.792675)
			(xy 344.823008 -240.838487) (xy 344.792787 -240.880083) (xy 344.756431 -240.916439) (xy 344.714835 -240.94666)
			(xy 344.669023 -240.970003) (xy 344.620124 -240.985891) (xy 344.569342 -240.993934) (xy 344.517926 -240.993934)
			(xy 344.467144 -240.985891) (xy 344.418245 -240.970003) (xy 344.372433 -240.94666) (xy 344.330837 -240.916439)
			(xy 344.294481 -240.880083) (xy 344.26426 -240.838487) (xy 344.240917 -240.792675) (xy 344.225029 -240.743776)
			(xy 344.216986 -240.692994) (xy 343.930482 -240.692994) (xy 343.922439 -240.743776) (xy 343.906551 -240.792675)
			(xy 343.883208 -240.838487) (xy 343.852987 -240.880083) (xy 343.816631 -240.916439) (xy 343.775035 -240.94666)
			(xy 343.729223 -240.970003) (xy 343.680324 -240.985891) (xy 343.629542 -240.993934) (xy 343.578126 -240.993934)
			(xy 343.527344 -240.985891) (xy 343.478445 -240.970003) (xy 343.432633 -240.94666) (xy 343.391037 -240.916439)
			(xy 343.354681 -240.880083) (xy 343.32446 -240.838487) (xy 343.301117 -240.792675) (xy 343.285229 -240.743776)
			(xy 343.277186 -240.692994) (xy 342.050882 -240.692994) (xy 342.042839 -240.743776) (xy 342.026951 -240.792675)
			(xy 342.003608 -240.838487) (xy 341.973387 -240.880083) (xy 341.937031 -240.916439) (xy 341.895435 -240.94666)
			(xy 341.849623 -240.970003) (xy 341.800724 -240.985891) (xy 341.749942 -240.993934) (xy 341.698526 -240.993934)
			(xy 341.647744 -240.985891) (xy 341.598845 -240.970003) (xy 341.553033 -240.94666) (xy 341.511437 -240.916439)
			(xy 341.475081 -240.880083) (xy 341.44486 -240.838487) (xy 341.421517 -240.792675) (xy 341.405629 -240.743776)
			(xy 341.397586 -240.692994) (xy 340.171282 -240.692994) (xy 340.163239 -240.743776) (xy 340.147351 -240.792675)
			(xy 340.124008 -240.838487) (xy 340.093787 -240.880083) (xy 340.057431 -240.916439) (xy 340.015835 -240.94666)
			(xy 339.970023 -240.970003) (xy 339.921124 -240.985891) (xy 339.870342 -240.993934) (xy 339.818926 -240.993934)
			(xy 339.768144 -240.985891) (xy 339.719245 -240.970003) (xy 339.673433 -240.94666) (xy 339.631837 -240.916439)
			(xy 339.595481 -240.880083) (xy 339.56526 -240.838487) (xy 339.541917 -240.792675) (xy 339.526029 -240.743776)
			(xy 339.517986 -240.692994) (xy 338.291682 -240.692994) (xy 338.283639 -240.743776) (xy 338.267751 -240.792675)
			(xy 338.244408 -240.838487) (xy 338.214187 -240.880083) (xy 338.177831 -240.916439) (xy 338.136235 -240.94666)
			(xy 338.090423 -240.970003) (xy 338.041524 -240.985891) (xy 337.990742 -240.993934) (xy 337.939326 -240.993934)
			(xy 337.888544 -240.985891) (xy 337.839645 -240.970003) (xy 337.793833 -240.94666) (xy 337.752237 -240.916439)
			(xy 337.715881 -240.880083) (xy 337.68566 -240.838487) (xy 337.662317 -240.792675) (xy 337.646429 -240.743776)
			(xy 337.638386 -240.692994) (xy 337.351882 -240.692994) (xy 337.343839 -240.743776) (xy 337.327951 -240.792675)
			(xy 337.304608 -240.838487) (xy 337.274387 -240.880083) (xy 337.238031 -240.916439) (xy 337.196435 -240.94666)
			(xy 337.150623 -240.970003) (xy 337.101724 -240.985891) (xy 337.050942 -240.993934) (xy 336.999526 -240.993934)
			(xy 336.948744 -240.985891) (xy 336.899845 -240.970003) (xy 336.854033 -240.94666) (xy 336.812437 -240.916439)
			(xy 336.776081 -240.880083) (xy 336.74586 -240.838487) (xy 336.722517 -240.792675) (xy 336.706629 -240.743776)
			(xy 336.698586 -240.692994) (xy 331.687116 -240.692994) (xy 331.100684 -241.279426) (xy 331.100684 -241.50681)
			(xy 336.228432 -241.50681) (xy 336.228432 -241.455394) (xy 336.236475 -241.404612) (xy 336.252363 -241.355713)
			(xy 336.275706 -241.309901) (xy 336.305927 -241.268305) (xy 336.342283 -241.231949) (xy 336.383879 -241.201728)
			(xy 336.429691 -241.178385) (xy 336.47859 -241.162497) (xy 336.529372 -241.154454) (xy 336.580788 -241.154454)
			(xy 336.63157 -241.162497) (xy 336.680469 -241.178385) (xy 336.726281 -241.201728) (xy 336.767877 -241.231949)
			(xy 336.804233 -241.268305) (xy 336.834454 -241.309901) (xy 336.857797 -241.355713) (xy 336.873685 -241.404612)
			(xy 336.881728 -241.455394) (xy 336.882232 -241.481102) (xy 336.881728 -241.50681) (xy 338.108032 -241.50681)
			(xy 338.108032 -241.455394) (xy 338.116075 -241.404612) (xy 338.131963 -241.355713) (xy 338.155306 -241.309901)
			(xy 338.185527 -241.268305) (xy 338.221883 -241.231949) (xy 338.263479 -241.201728) (xy 338.309291 -241.178385)
			(xy 338.35819 -241.162497) (xy 338.408972 -241.154454) (xy 338.460388 -241.154454) (xy 338.51117 -241.162497)
			(xy 338.560069 -241.178385) (xy 338.605881 -241.201728) (xy 338.647477 -241.231949) (xy 338.683833 -241.268305)
			(xy 338.714054 -241.309901) (xy 338.737397 -241.355713) (xy 338.753285 -241.404612) (xy 338.761328 -241.455394)
			(xy 338.761832 -241.481102) (xy 338.761328 -241.50681) (xy 339.987632 -241.50681) (xy 339.987632 -241.455394)
			(xy 339.995675 -241.404612) (xy 340.011563 -241.355713) (xy 340.034906 -241.309901) (xy 340.065127 -241.268305)
			(xy 340.101483 -241.231949) (xy 340.143079 -241.201728) (xy 340.188891 -241.178385) (xy 340.23779 -241.162497)
			(xy 340.288572 -241.154454) (xy 340.339988 -241.154454) (xy 340.39077 -241.162497) (xy 340.439669 -241.178385)
			(xy 340.485481 -241.201728) (xy 340.527077 -241.231949) (xy 340.563433 -241.268305) (xy 340.593654 -241.309901)
			(xy 340.616997 -241.355713) (xy 340.632885 -241.404612) (xy 340.640928 -241.455394) (xy 340.641432 -241.481102)
			(xy 340.640928 -241.50681) (xy 340.927432 -241.50681) (xy 340.927432 -241.455394) (xy 340.935475 -241.404612)
			(xy 340.951363 -241.355713) (xy 340.974706 -241.309901) (xy 341.004927 -241.268305) (xy 341.041283 -241.231949)
			(xy 341.082879 -241.201728) (xy 341.128691 -241.178385) (xy 341.17759 -241.162497) (xy 341.228372 -241.154454)
			(xy 341.279788 -241.154454) (xy 341.33057 -241.162497) (xy 341.379469 -241.178385) (xy 341.425281 -241.201728)
			(xy 341.466877 -241.231949) (xy 341.503233 -241.268305) (xy 341.533454 -241.309901) (xy 341.556797 -241.355713)
			(xy 341.572685 -241.404612) (xy 341.580728 -241.455394) (xy 341.581232 -241.481102) (xy 341.580728 -241.50681)
			(xy 342.807032 -241.50681) (xy 342.807032 -241.455394) (xy 342.815075 -241.404612) (xy 342.830963 -241.355713)
			(xy 342.854306 -241.309901) (xy 342.884527 -241.268305) (xy 342.920883 -241.231949) (xy 342.962479 -241.201728)
			(xy 343.008291 -241.178385) (xy 343.05719 -241.162497) (xy 343.107972 -241.154454) (xy 343.159388 -241.154454)
			(xy 343.21017 -241.162497) (xy 343.259069 -241.178385) (xy 343.304881 -241.201728) (xy 343.346477 -241.231949)
			(xy 343.382833 -241.268305) (xy 343.413054 -241.309901) (xy 343.436397 -241.355713) (xy 343.452285 -241.404612)
			(xy 343.460328 -241.455394) (xy 343.460832 -241.481102) (xy 343.460328 -241.50681) (xy 344.686632 -241.50681)
			(xy 344.686632 -241.455394) (xy 344.694675 -241.404612) (xy 344.710563 -241.355713) (xy 344.733906 -241.309901)
			(xy 344.764127 -241.268305) (xy 344.800483 -241.231949) (xy 344.842079 -241.201728) (xy 344.887891 -241.178385)
			(xy 344.93679 -241.162497) (xy 344.987572 -241.154454) (xy 345.038988 -241.154454) (xy 345.08977 -241.162497)
			(xy 345.138669 -241.178385) (xy 345.184481 -241.201728) (xy 345.226077 -241.231949) (xy 345.262433 -241.268305)
			(xy 345.292654 -241.309901) (xy 345.315997 -241.355713) (xy 345.331885 -241.404612) (xy 345.339928 -241.455394)
			(xy 345.340432 -241.481102) (xy 345.339928 -241.50681) (xy 345.331885 -241.557592) (xy 345.315997 -241.606491)
			(xy 345.292654 -241.652303) (xy 345.262433 -241.693899) (xy 345.226077 -241.730255) (xy 345.184481 -241.760476)
			(xy 345.138669 -241.783819) (xy 345.08977 -241.799707) (xy 345.038988 -241.80775) (xy 344.987572 -241.80775)
			(xy 344.93679 -241.799707) (xy 344.887891 -241.783819) (xy 344.842079 -241.760476) (xy 344.800483 -241.730255)
			(xy 344.764127 -241.693899) (xy 344.733906 -241.652303) (xy 344.710563 -241.606491) (xy 344.694675 -241.557592)
			(xy 344.686632 -241.50681) (xy 343.460328 -241.50681) (xy 343.452285 -241.557592) (xy 343.436397 -241.606491)
			(xy 343.413054 -241.652303) (xy 343.382833 -241.693899) (xy 343.346477 -241.730255) (xy 343.304881 -241.760476)
			(xy 343.259069 -241.783819) (xy 343.21017 -241.799707) (xy 343.159388 -241.80775) (xy 343.107972 -241.80775)
			(xy 343.05719 -241.799707) (xy 343.008291 -241.783819) (xy 342.962479 -241.760476) (xy 342.920883 -241.730255)
			(xy 342.884527 -241.693899) (xy 342.854306 -241.652303) (xy 342.830963 -241.606491) (xy 342.815075 -241.557592)
			(xy 342.807032 -241.50681) (xy 341.580728 -241.50681) (xy 341.572685 -241.557592) (xy 341.556797 -241.606491)
			(xy 341.533454 -241.652303) (xy 341.503233 -241.693899) (xy 341.466877 -241.730255) (xy 341.425281 -241.760476)
			(xy 341.379469 -241.783819) (xy 341.33057 -241.799707) (xy 341.279788 -241.80775) (xy 341.228372 -241.80775)
			(xy 341.17759 -241.799707) (xy 341.128691 -241.783819) (xy 341.082879 -241.760476) (xy 341.041283 -241.730255)
			(xy 341.004927 -241.693899) (xy 340.974706 -241.652303) (xy 340.951363 -241.606491) (xy 340.935475 -241.557592)
			(xy 340.927432 -241.50681) (xy 340.640928 -241.50681) (xy 340.632885 -241.557592) (xy 340.616997 -241.606491)
			(xy 340.593654 -241.652303) (xy 340.563433 -241.693899) (xy 340.527077 -241.730255) (xy 340.485481 -241.760476)
			(xy 340.439669 -241.783819) (xy 340.39077 -241.799707) (xy 340.339988 -241.80775) (xy 340.288572 -241.80775)
			(xy 340.23779 -241.799707) (xy 340.188891 -241.783819) (xy 340.143079 -241.760476) (xy 340.101483 -241.730255)
			(xy 340.065127 -241.693899) (xy 340.034906 -241.652303) (xy 340.011563 -241.606491) (xy 339.995675 -241.557592)
			(xy 339.987632 -241.50681) (xy 338.761328 -241.50681) (xy 338.753285 -241.557592) (xy 338.737397 -241.606491)
			(xy 338.714054 -241.652303) (xy 338.683833 -241.693899) (xy 338.647477 -241.730255) (xy 338.605881 -241.760476)
			(xy 338.560069 -241.783819) (xy 338.51117 -241.799707) (xy 338.460388 -241.80775) (xy 338.408972 -241.80775)
			(xy 338.35819 -241.799707) (xy 338.309291 -241.783819) (xy 338.263479 -241.760476) (xy 338.221883 -241.730255)
			(xy 338.185527 -241.693899) (xy 338.155306 -241.652303) (xy 338.131963 -241.606491) (xy 338.116075 -241.557592)
			(xy 338.108032 -241.50681) (xy 336.881728 -241.50681) (xy 336.873685 -241.557592) (xy 336.857797 -241.606491)
			(xy 336.834454 -241.652303) (xy 336.804233 -241.693899) (xy 336.767877 -241.730255) (xy 336.726281 -241.760476)
			(xy 336.680469 -241.783819) (xy 336.63157 -241.799707) (xy 336.580788 -241.80775) (xy 336.529372 -241.80775)
			(xy 336.47859 -241.799707) (xy 336.429691 -241.783819) (xy 336.383879 -241.760476) (xy 336.342283 -241.730255)
			(xy 336.305927 -241.693899) (xy 336.275706 -241.652303) (xy 336.252363 -241.606491) (xy 336.236475 -241.557592)
			(xy 336.228432 -241.50681) (xy 331.100684 -241.50681) (xy 331.100684 -242.320626) (xy 335.75904 -242.320626)
			(xy 335.75904 -242.26921) (xy 335.767083 -242.218428) (xy 335.782971 -242.169529) (xy 335.806314 -242.123717)
			(xy 335.836535 -242.082121) (xy 335.872891 -242.045765) (xy 335.914487 -242.015544) (xy 335.960299 -241.992201)
			(xy 336.009198 -241.976313) (xy 336.05998 -241.96827) (xy 336.111396 -241.96827) (xy 336.162178 -241.976313)
			(xy 336.211077 -241.992201) (xy 336.256889 -242.015544) (xy 336.298485 -242.045765) (xy 336.334841 -242.082121)
			(xy 336.365062 -242.123717) (xy 336.388405 -242.169529) (xy 336.404293 -242.218428) (xy 336.412336 -242.26921)
			(xy 336.41284 -242.294918) (xy 336.412336 -242.320626) (xy 336.698586 -242.320626) (xy 336.698586 -242.26921)
			(xy 336.706629 -242.218428) (xy 336.722517 -242.169529) (xy 336.74586 -242.123717) (xy 336.776081 -242.082121)
			(xy 336.812437 -242.045765) (xy 336.854033 -242.015544) (xy 336.899845 -241.992201) (xy 336.948744 -241.976313)
			(xy 336.999526 -241.96827) (xy 337.050942 -241.96827) (xy 337.101724 -241.976313) (xy 337.150623 -241.992201)
			(xy 337.196435 -242.015544) (xy 337.238031 -242.045765) (xy 337.274387 -242.082121) (xy 337.304608 -242.123717)
			(xy 337.327951 -242.169529) (xy 337.343839 -242.218428) (xy 337.351882 -242.26921) (xy 337.352386 -242.294918)
			(xy 337.351882 -242.320626) (xy 337.638386 -242.320626) (xy 337.638386 -242.26921) (xy 337.646429 -242.218428)
			(xy 337.662317 -242.169529) (xy 337.68566 -242.123717) (xy 337.715881 -242.082121) (xy 337.752237 -242.045765)
			(xy 337.793833 -242.015544) (xy 337.839645 -241.992201) (xy 337.888544 -241.976313) (xy 337.939326 -241.96827)
			(xy 337.990742 -241.96827) (xy 338.041524 -241.976313) (xy 338.090423 -241.992201) (xy 338.136235 -242.015544)
			(xy 338.177831 -242.045765) (xy 338.214187 -242.082121) (xy 338.244408 -242.123717) (xy 338.267751 -242.169529)
			(xy 338.283639 -242.218428) (xy 338.291682 -242.26921) (xy 338.292186 -242.294918) (xy 338.291682 -242.320626)
			(xy 338.578186 -242.320626) (xy 338.578186 -242.26921) (xy 338.586229 -242.218428) (xy 338.602117 -242.169529)
			(xy 338.62546 -242.123717) (xy 338.655681 -242.082121) (xy 338.692037 -242.045765) (xy 338.733633 -242.015544)
			(xy 338.779445 -241.992201) (xy 338.828344 -241.976313) (xy 338.879126 -241.96827) (xy 338.930542 -241.96827)
			(xy 338.981324 -241.976313) (xy 339.030223 -241.992201) (xy 339.076035 -242.015544) (xy 339.117631 -242.045765)
			(xy 339.153987 -242.082121) (xy 339.184208 -242.123717) (xy 339.207551 -242.169529) (xy 339.223439 -242.218428)
			(xy 339.231482 -242.26921) (xy 339.231986 -242.294918) (xy 339.231482 -242.320626) (xy 342.337386 -242.320626)
			(xy 342.337386 -242.26921) (xy 342.345429 -242.218428) (xy 342.361317 -242.169529) (xy 342.38466 -242.123717)
			(xy 342.414881 -242.082121) (xy 342.451237 -242.045765) (xy 342.492833 -242.015544) (xy 342.538645 -241.992201)
			(xy 342.587544 -241.976313) (xy 342.638326 -241.96827) (xy 342.689742 -241.96827) (xy 342.740524 -241.976313)
			(xy 342.789423 -241.992201) (xy 342.835235 -242.015544) (xy 342.876831 -242.045765) (xy 342.913187 -242.082121)
			(xy 342.943408 -242.123717) (xy 342.966751 -242.169529) (xy 342.982639 -242.218428) (xy 342.990682 -242.26921)
			(xy 342.991186 -242.294918) (xy 342.990682 -242.320626) (xy 343.277186 -242.320626) (xy 343.277186 -242.26921)
			(xy 343.285229 -242.218428) (xy 343.301117 -242.169529) (xy 343.32446 -242.123717) (xy 343.354681 -242.082121)
			(xy 343.391037 -242.045765) (xy 343.432633 -242.015544) (xy 343.478445 -241.992201) (xy 343.527344 -241.976313)
			(xy 343.578126 -241.96827) (xy 343.629542 -241.96827) (xy 343.680324 -241.976313) (xy 343.729223 -241.992201)
			(xy 343.775035 -242.015544) (xy 343.816631 -242.045765) (xy 343.852987 -242.082121) (xy 343.883208 -242.123717)
			(xy 343.906551 -242.169529) (xy 343.922439 -242.218428) (xy 343.930482 -242.26921) (xy 343.930986 -242.294918)
			(xy 343.930482 -242.320626) (xy 344.216986 -242.320626) (xy 344.216986 -242.26921) (xy 344.225029 -242.218428)
			(xy 344.240917 -242.169529) (xy 344.26426 -242.123717) (xy 344.294481 -242.082121) (xy 344.330837 -242.045765)
			(xy 344.372433 -242.015544) (xy 344.418245 -241.992201) (xy 344.467144 -241.976313) (xy 344.517926 -241.96827)
			(xy 344.569342 -241.96827) (xy 344.620124 -241.976313) (xy 344.669023 -241.992201) (xy 344.714835 -242.015544)
			(xy 344.756431 -242.045765) (xy 344.792787 -242.082121) (xy 344.823008 -242.123717) (xy 344.846351 -242.169529)
			(xy 344.862239 -242.218428) (xy 344.870282 -242.26921) (xy 344.870786 -242.294918) (xy 344.870282 -242.320626)
			(xy 345.156786 -242.320626) (xy 345.156786 -242.26921) (xy 345.164829 -242.218428) (xy 345.180717 -242.169529)
			(xy 345.20406 -242.123717) (xy 345.234281 -242.082121) (xy 345.270637 -242.045765) (xy 345.312233 -242.015544)
			(xy 345.358045 -241.992201) (xy 345.406944 -241.976313) (xy 345.457726 -241.96827) (xy 345.509142 -241.96827)
			(xy 345.559924 -241.976313) (xy 345.608823 -241.992201) (xy 345.654635 -242.015544) (xy 345.696231 -242.045765)
			(xy 345.732587 -242.082121) (xy 345.762808 -242.123717) (xy 345.786151 -242.169529) (xy 345.802039 -242.218428)
			(xy 345.810082 -242.26921) (xy 345.810586 -242.294918) (xy 345.810082 -242.320626) (xy 345.802039 -242.371408)
			(xy 345.786151 -242.420307) (xy 345.762808 -242.466119) (xy 345.732587 -242.507715) (xy 345.696231 -242.544071)
			(xy 345.654635 -242.574292) (xy 345.608823 -242.597635) (xy 345.559924 -242.613523) (xy 345.509142 -242.621566)
			(xy 345.457726 -242.621566) (xy 345.406944 -242.613523) (xy 345.358045 -242.597635) (xy 345.312233 -242.574292)
			(xy 345.270637 -242.544071) (xy 345.234281 -242.507715) (xy 345.20406 -242.466119) (xy 345.180717 -242.420307)
			(xy 345.164829 -242.371408) (xy 345.156786 -242.320626) (xy 344.870282 -242.320626) (xy 344.862239 -242.371408)
			(xy 344.846351 -242.420307) (xy 344.823008 -242.466119) (xy 344.792787 -242.507715) (xy 344.756431 -242.544071)
			(xy 344.714835 -242.574292) (xy 344.669023 -242.597635) (xy 344.620124 -242.613523) (xy 344.569342 -242.621566)
			(xy 344.517926 -242.621566) (xy 344.467144 -242.613523) (xy 344.418245 -242.597635) (xy 344.372433 -242.574292)
			(xy 344.330837 -242.544071) (xy 344.294481 -242.507715) (xy 344.26426 -242.466119) (xy 344.240917 -242.420307)
			(xy 344.225029 -242.371408) (xy 344.216986 -242.320626) (xy 343.930482 -242.320626) (xy 343.922439 -242.371408)
			(xy 343.906551 -242.420307) (xy 343.883208 -242.466119) (xy 343.852987 -242.507715) (xy 343.816631 -242.544071)
			(xy 343.775035 -242.574292) (xy 343.729223 -242.597635) (xy 343.680324 -242.613523) (xy 343.629542 -242.621566)
			(xy 343.578126 -242.621566) (xy 343.527344 -242.613523) (xy 343.478445 -242.597635) (xy 343.432633 -242.574292)
			(xy 343.391037 -242.544071) (xy 343.354681 -242.507715) (xy 343.32446 -242.466119) (xy 343.301117 -242.420307)
			(xy 343.285229 -242.371408) (xy 343.277186 -242.320626) (xy 342.990682 -242.320626) (xy 342.982639 -242.371408)
			(xy 342.966751 -242.420307) (xy 342.943408 -242.466119) (xy 342.913187 -242.507715) (xy 342.876831 -242.544071)
			(xy 342.835235 -242.574292) (xy 342.789423 -242.597635) (xy 342.740524 -242.613523) (xy 342.689742 -242.621566)
			(xy 342.638326 -242.621566) (xy 342.587544 -242.613523) (xy 342.538645 -242.597635) (xy 342.492833 -242.574292)
			(xy 342.451237 -242.544071) (xy 342.414881 -242.507715) (xy 342.38466 -242.466119) (xy 342.361317 -242.420307)
			(xy 342.345429 -242.371408) (xy 342.337386 -242.320626) (xy 339.231482 -242.320626) (xy 339.223439 -242.371408)
			(xy 339.207551 -242.420307) (xy 339.184208 -242.466119) (xy 339.153987 -242.507715) (xy 339.117631 -242.544071)
			(xy 339.076035 -242.574292) (xy 339.030223 -242.597635) (xy 338.981324 -242.613523) (xy 338.930542 -242.621566)
			(xy 338.879126 -242.621566) (xy 338.828344 -242.613523) (xy 338.779445 -242.597635) (xy 338.733633 -242.574292)
			(xy 338.692037 -242.544071) (xy 338.655681 -242.507715) (xy 338.62546 -242.466119) (xy 338.602117 -242.420307)
			(xy 338.586229 -242.371408) (xy 338.578186 -242.320626) (xy 338.291682 -242.320626) (xy 338.283639 -242.371408)
			(xy 338.267751 -242.420307) (xy 338.244408 -242.466119) (xy 338.214187 -242.507715) (xy 338.177831 -242.544071)
			(xy 338.136235 -242.574292) (xy 338.090423 -242.597635) (xy 338.041524 -242.613523) (xy 337.990742 -242.621566)
			(xy 337.939326 -242.621566) (xy 337.888544 -242.613523) (xy 337.839645 -242.597635) (xy 337.793833 -242.574292)
			(xy 337.752237 -242.544071) (xy 337.715881 -242.507715) (xy 337.68566 -242.466119) (xy 337.662317 -242.420307)
			(xy 337.646429 -242.371408) (xy 337.638386 -242.320626) (xy 337.351882 -242.320626) (xy 337.343839 -242.371408)
			(xy 337.327951 -242.420307) (xy 337.304608 -242.466119) (xy 337.274387 -242.507715) (xy 337.238031 -242.544071)
			(xy 337.196435 -242.574292) (xy 337.150623 -242.597635) (xy 337.101724 -242.613523) (xy 337.050942 -242.621566)
			(xy 336.999526 -242.621566) (xy 336.948744 -242.613523) (xy 336.899845 -242.597635) (xy 336.854033 -242.574292)
			(xy 336.812437 -242.544071) (xy 336.776081 -242.507715) (xy 336.74586 -242.466119) (xy 336.722517 -242.420307)
			(xy 336.706629 -242.371408) (xy 336.698586 -242.320626) (xy 336.412336 -242.320626) (xy 336.404293 -242.371408)
			(xy 336.388405 -242.420307) (xy 336.365062 -242.466119) (xy 336.334841 -242.507715) (xy 336.298485 -242.544071)
			(xy 336.256889 -242.574292) (xy 336.211077 -242.597635) (xy 336.162178 -242.613523) (xy 336.111396 -242.621566)
			(xy 336.05998 -242.621566) (xy 336.009198 -242.613523) (xy 335.960299 -242.597635) (xy 335.914487 -242.574292)
			(xy 335.872891 -242.544071) (xy 335.836535 -242.507715) (xy 335.806314 -242.466119) (xy 335.782971 -242.420307)
			(xy 335.767083 -242.371408) (xy 335.75904 -242.320626) (xy 331.100684 -242.320626) (xy 331.100684 -243.134696)
			(xy 336.228432 -243.134696) (xy 336.228432 -243.08328) (xy 336.236475 -243.032498) (xy 336.252363 -242.983599)
			(xy 336.275706 -242.937787) (xy 336.305927 -242.896191) (xy 336.342283 -242.859835) (xy 336.383879 -242.829614)
			(xy 336.429691 -242.806271) (xy 336.47859 -242.790383) (xy 336.529372 -242.78234) (xy 336.580788 -242.78234)
			(xy 336.63157 -242.790383) (xy 336.680469 -242.806271) (xy 336.726281 -242.829614) (xy 336.767877 -242.859835)
			(xy 336.804233 -242.896191) (xy 336.834454 -242.937787) (xy 336.857797 -242.983599) (xy 336.873685 -243.032498)
			(xy 336.881728 -243.08328) (xy 336.882232 -243.108988) (xy 336.881728 -243.134696) (xy 338.108032 -243.134696)
			(xy 338.108032 -243.08328) (xy 338.116075 -243.032498) (xy 338.131963 -242.983599) (xy 338.155306 -242.937787)
			(xy 338.185527 -242.896191) (xy 338.221883 -242.859835) (xy 338.263479 -242.829614) (xy 338.309291 -242.806271)
			(xy 338.35819 -242.790383) (xy 338.408972 -242.78234) (xy 338.460388 -242.78234) (xy 338.51117 -242.790383)
			(xy 338.560069 -242.806271) (xy 338.605881 -242.829614) (xy 338.647477 -242.859835) (xy 338.683833 -242.896191)
			(xy 338.714054 -242.937787) (xy 338.737397 -242.983599) (xy 338.753285 -243.032498) (xy 338.761328 -243.08328)
			(xy 338.761832 -243.108988) (xy 338.761328 -243.134696) (xy 339.987632 -243.134696) (xy 339.987632 -243.08328)
			(xy 339.995675 -243.032498) (xy 340.011563 -242.983599) (xy 340.034906 -242.937787) (xy 340.065127 -242.896191)
			(xy 340.101483 -242.859835) (xy 340.143079 -242.829614) (xy 340.188891 -242.806271) (xy 340.23779 -242.790383)
			(xy 340.288572 -242.78234) (xy 340.339988 -242.78234) (xy 340.39077 -242.790383) (xy 340.439669 -242.806271)
			(xy 340.485481 -242.829614) (xy 340.527077 -242.859835) (xy 340.563433 -242.896191) (xy 340.593654 -242.937787)
			(xy 340.616997 -242.983599) (xy 340.632885 -243.032498) (xy 340.640928 -243.08328) (xy 340.641432 -243.108988)
			(xy 340.640928 -243.134696) (xy 340.927432 -243.134696) (xy 340.927432 -243.08328) (xy 340.935475 -243.032498)
			(xy 340.951363 -242.983599) (xy 340.974706 -242.937787) (xy 341.004927 -242.896191) (xy 341.041283 -242.859835)
			(xy 341.082879 -242.829614) (xy 341.128691 -242.806271) (xy 341.17759 -242.790383) (xy 341.228372 -242.78234)
			(xy 341.279788 -242.78234) (xy 341.33057 -242.790383) (xy 341.379469 -242.806271) (xy 341.425281 -242.829614)
			(xy 341.466877 -242.859835) (xy 341.503233 -242.896191) (xy 341.533454 -242.937787) (xy 341.556797 -242.983599)
			(xy 341.572685 -243.032498) (xy 341.580728 -243.08328) (xy 341.581232 -243.108988) (xy 341.580728 -243.134696)
			(xy 342.807032 -243.134696) (xy 342.807032 -243.08328) (xy 342.815075 -243.032498) (xy 342.830963 -242.983599)
			(xy 342.854306 -242.937787) (xy 342.884527 -242.896191) (xy 342.920883 -242.859835) (xy 342.962479 -242.829614)
			(xy 343.008291 -242.806271) (xy 343.05719 -242.790383) (xy 343.107972 -242.78234) (xy 343.159388 -242.78234)
			(xy 343.21017 -242.790383) (xy 343.259069 -242.806271) (xy 343.304881 -242.829614) (xy 343.346477 -242.859835)
			(xy 343.382833 -242.896191) (xy 343.413054 -242.937787) (xy 343.436397 -242.983599) (xy 343.452285 -243.032498)
			(xy 343.460328 -243.08328) (xy 343.460832 -243.108988) (xy 343.460328 -243.134696) (xy 344.686632 -243.134696)
			(xy 344.686632 -243.08328) (xy 344.694675 -243.032498) (xy 344.710563 -242.983599) (xy 344.733906 -242.937787)
			(xy 344.764127 -242.896191) (xy 344.800483 -242.859835) (xy 344.842079 -242.829614) (xy 344.887891 -242.806271)
			(xy 344.93679 -242.790383) (xy 344.987572 -242.78234) (xy 345.038988 -242.78234) (xy 345.08977 -242.790383)
			(xy 345.138669 -242.806271) (xy 345.184481 -242.829614) (xy 345.226077 -242.859835) (xy 345.262433 -242.896191)
			(xy 345.292654 -242.937787) (xy 345.315997 -242.983599) (xy 345.331885 -243.032498) (xy 345.339928 -243.08328)
			(xy 345.340432 -243.108988) (xy 345.339928 -243.134696) (xy 345.331885 -243.185478) (xy 345.315997 -243.234377)
			(xy 345.292654 -243.280189) (xy 345.262433 -243.321785) (xy 345.226077 -243.358141) (xy 345.184481 -243.388362)
			(xy 345.138669 -243.411705) (xy 345.08977 -243.427593) (xy 345.038988 -243.435636) (xy 344.987572 -243.435636)
			(xy 344.93679 -243.427593) (xy 344.887891 -243.411705) (xy 344.842079 -243.388362) (xy 344.800483 -243.358141)
			(xy 344.764127 -243.321785) (xy 344.733906 -243.280189) (xy 344.710563 -243.234377) (xy 344.694675 -243.185478)
			(xy 344.686632 -243.134696) (xy 343.460328 -243.134696) (xy 343.452285 -243.185478) (xy 343.436397 -243.234377)
			(xy 343.413054 -243.280189) (xy 343.382833 -243.321785) (xy 343.346477 -243.358141) (xy 343.304881 -243.388362)
			(xy 343.259069 -243.411705) (xy 343.21017 -243.427593) (xy 343.159388 -243.435636) (xy 343.107972 -243.435636)
			(xy 343.05719 -243.427593) (xy 343.008291 -243.411705) (xy 342.962479 -243.388362) (xy 342.920883 -243.358141)
			(xy 342.884527 -243.321785) (xy 342.854306 -243.280189) (xy 342.830963 -243.234377) (xy 342.815075 -243.185478)
			(xy 342.807032 -243.134696) (xy 341.580728 -243.134696) (xy 341.572685 -243.185478) (xy 341.556797 -243.234377)
			(xy 341.533454 -243.280189) (xy 341.503233 -243.321785) (xy 341.466877 -243.358141) (xy 341.425281 -243.388362)
			(xy 341.379469 -243.411705) (xy 341.33057 -243.427593) (xy 341.279788 -243.435636) (xy 341.228372 -243.435636)
			(xy 341.17759 -243.427593) (xy 341.128691 -243.411705) (xy 341.082879 -243.388362) (xy 341.041283 -243.358141)
			(xy 341.004927 -243.321785) (xy 340.974706 -243.280189) (xy 340.951363 -243.234377) (xy 340.935475 -243.185478)
			(xy 340.927432 -243.134696) (xy 340.640928 -243.134696) (xy 340.632885 -243.185478) (xy 340.616997 -243.234377)
			(xy 340.593654 -243.280189) (xy 340.563433 -243.321785) (xy 340.527077 -243.358141) (xy 340.485481 -243.388362)
			(xy 340.439669 -243.411705) (xy 340.39077 -243.427593) (xy 340.339988 -243.435636) (xy 340.288572 -243.435636)
			(xy 340.23779 -243.427593) (xy 340.188891 -243.411705) (xy 340.143079 -243.388362) (xy 340.101483 -243.358141)
			(xy 340.065127 -243.321785) (xy 340.034906 -243.280189) (xy 340.011563 -243.234377) (xy 339.995675 -243.185478)
			(xy 339.987632 -243.134696) (xy 338.761328 -243.134696) (xy 338.753285 -243.185478) (xy 338.737397 -243.234377)
			(xy 338.714054 -243.280189) (xy 338.683833 -243.321785) (xy 338.647477 -243.358141) (xy 338.605881 -243.388362)
			(xy 338.560069 -243.411705) (xy 338.51117 -243.427593) (xy 338.460388 -243.435636) (xy 338.408972 -243.435636)
			(xy 338.35819 -243.427593) (xy 338.309291 -243.411705) (xy 338.263479 -243.388362) (xy 338.221883 -243.358141)
			(xy 338.185527 -243.321785) (xy 338.155306 -243.280189) (xy 338.131963 -243.234377) (xy 338.116075 -243.185478)
			(xy 338.108032 -243.134696) (xy 336.881728 -243.134696) (xy 336.873685 -243.185478) (xy 336.857797 -243.234377)
			(xy 336.834454 -243.280189) (xy 336.804233 -243.321785) (xy 336.767877 -243.358141) (xy 336.726281 -243.388362)
			(xy 336.680469 -243.411705) (xy 336.63157 -243.427593) (xy 336.580788 -243.435636) (xy 336.529372 -243.435636)
			(xy 336.47859 -243.427593) (xy 336.429691 -243.411705) (xy 336.383879 -243.388362) (xy 336.342283 -243.358141)
			(xy 336.305927 -243.321785) (xy 336.275706 -243.280189) (xy 336.252363 -243.234377) (xy 336.236475 -243.185478)
			(xy 336.228432 -243.134696) (xy 331.100684 -243.134696) (xy 331.100684 -243.948512) (xy 336.698586 -243.948512)
			(xy 336.698586 -243.897096) (xy 336.706629 -243.846314) (xy 336.722517 -243.797415) (xy 336.74586 -243.751603)
			(xy 336.776081 -243.710007) (xy 336.812437 -243.673651) (xy 336.854033 -243.64343) (xy 336.899845 -243.620087)
			(xy 336.948744 -243.604199) (xy 336.999526 -243.596156) (xy 337.050942 -243.596156) (xy 337.101724 -243.604199)
			(xy 337.150623 -243.620087) (xy 337.196435 -243.64343) (xy 337.238031 -243.673651) (xy 337.274387 -243.710007)
			(xy 337.304608 -243.751603) (xy 337.327951 -243.797415) (xy 337.343839 -243.846314) (xy 337.351882 -243.897096)
			(xy 337.352386 -243.922804) (xy 337.351882 -243.948512) (xy 337.638386 -243.948512) (xy 337.638386 -243.897096)
			(xy 337.646429 -243.846314) (xy 337.662317 -243.797415) (xy 337.68566 -243.751603) (xy 337.715881 -243.710007)
			(xy 337.752237 -243.673651) (xy 337.793833 -243.64343) (xy 337.839645 -243.620087) (xy 337.888544 -243.604199)
			(xy 337.939326 -243.596156) (xy 337.990742 -243.596156) (xy 338.041524 -243.604199) (xy 338.090423 -243.620087)
			(xy 338.136235 -243.64343) (xy 338.177831 -243.673651) (xy 338.214187 -243.710007) (xy 338.244408 -243.751603)
			(xy 338.267751 -243.797415) (xy 338.283639 -243.846314) (xy 338.291682 -243.897096) (xy 338.292186 -243.922804)
			(xy 338.291682 -243.948512) (xy 339.517986 -243.948512) (xy 339.517986 -243.897096) (xy 339.526029 -243.846314)
			(xy 339.541917 -243.797415) (xy 339.56526 -243.751603) (xy 339.595481 -243.710007) (xy 339.631837 -243.673651)
			(xy 339.673433 -243.64343) (xy 339.719245 -243.620087) (xy 339.768144 -243.604199) (xy 339.818926 -243.596156)
			(xy 339.870342 -243.596156) (xy 339.921124 -243.604199) (xy 339.970023 -243.620087) (xy 340.015835 -243.64343)
			(xy 340.057431 -243.673651) (xy 340.093787 -243.710007) (xy 340.124008 -243.751603) (xy 340.147351 -243.797415)
			(xy 340.163239 -243.846314) (xy 340.171282 -243.897096) (xy 340.171786 -243.922804) (xy 340.171282 -243.948512)
			(xy 341.397586 -243.948512) (xy 341.397586 -243.897096) (xy 341.405629 -243.846314) (xy 341.421517 -243.797415)
			(xy 341.44486 -243.751603) (xy 341.475081 -243.710007) (xy 341.511437 -243.673651) (xy 341.553033 -243.64343)
			(xy 341.598845 -243.620087) (xy 341.647744 -243.604199) (xy 341.698526 -243.596156) (xy 341.749942 -243.596156)
			(xy 341.800724 -243.604199) (xy 341.849623 -243.620087) (xy 341.895435 -243.64343) (xy 341.937031 -243.673651)
			(xy 341.973387 -243.710007) (xy 342.003608 -243.751603) (xy 342.026951 -243.797415) (xy 342.042839 -243.846314)
			(xy 342.050882 -243.897096) (xy 342.051386 -243.922804) (xy 342.050882 -243.948512) (xy 343.277186 -243.948512)
			(xy 343.277186 -243.897096) (xy 343.285229 -243.846314) (xy 343.301117 -243.797415) (xy 343.32446 -243.751603)
			(xy 343.354681 -243.710007) (xy 343.391037 -243.673651) (xy 343.432633 -243.64343) (xy 343.478445 -243.620087)
			(xy 343.527344 -243.604199) (xy 343.578126 -243.596156) (xy 343.629542 -243.596156) (xy 343.680324 -243.604199)
			(xy 343.729223 -243.620087) (xy 343.775035 -243.64343) (xy 343.816631 -243.673651) (xy 343.852987 -243.710007)
			(xy 343.883208 -243.751603) (xy 343.906551 -243.797415) (xy 343.922439 -243.846314) (xy 343.930482 -243.897096)
			(xy 343.930986 -243.922804) (xy 343.930482 -243.948512) (xy 344.216986 -243.948512) (xy 344.216986 -243.897096)
			(xy 344.225029 -243.846314) (xy 344.240917 -243.797415) (xy 344.26426 -243.751603) (xy 344.294481 -243.710007)
			(xy 344.330837 -243.673651) (xy 344.372433 -243.64343) (xy 344.418245 -243.620087) (xy 344.467144 -243.604199)
			(xy 344.517926 -243.596156) (xy 344.569342 -243.596156) (xy 344.620124 -243.604199) (xy 344.669023 -243.620087)
			(xy 344.714835 -243.64343) (xy 344.756431 -243.673651) (xy 344.792787 -243.710007) (xy 344.823008 -243.751603)
			(xy 344.846351 -243.797415) (xy 344.862239 -243.846314) (xy 344.870282 -243.897096) (xy 344.870786 -243.922804)
			(xy 344.870282 -243.948512) (xy 344.862239 -243.999294) (xy 344.846351 -244.048193) (xy 344.823008 -244.094005)
			(xy 344.792787 -244.135601) (xy 344.756431 -244.171957) (xy 344.714835 -244.202178) (xy 344.669023 -244.225521)
			(xy 344.620124 -244.241409) (xy 344.569342 -244.249452) (xy 344.517926 -244.249452) (xy 344.467144 -244.241409)
			(xy 344.418245 -244.225521) (xy 344.372433 -244.202178) (xy 344.330837 -244.171957) (xy 344.294481 -244.135601)
			(xy 344.26426 -244.094005) (xy 344.240917 -244.048193) (xy 344.225029 -243.999294) (xy 344.216986 -243.948512)
			(xy 343.930482 -243.948512) (xy 343.922439 -243.999294) (xy 343.906551 -244.048193) (xy 343.883208 -244.094005)
			(xy 343.852987 -244.135601) (xy 343.816631 -244.171957) (xy 343.775035 -244.202178) (xy 343.729223 -244.225521)
			(xy 343.680324 -244.241409) (xy 343.629542 -244.249452) (xy 343.578126 -244.249452) (xy 343.527344 -244.241409)
			(xy 343.478445 -244.225521) (xy 343.432633 -244.202178) (xy 343.391037 -244.171957) (xy 343.354681 -244.135601)
			(xy 343.32446 -244.094005) (xy 343.301117 -244.048193) (xy 343.285229 -243.999294) (xy 343.277186 -243.948512)
			(xy 342.050882 -243.948512) (xy 342.042839 -243.999294) (xy 342.026951 -244.048193) (xy 342.003608 -244.094005)
			(xy 341.973387 -244.135601) (xy 341.937031 -244.171957) (xy 341.895435 -244.202178) (xy 341.849623 -244.225521)
			(xy 341.800724 -244.241409) (xy 341.749942 -244.249452) (xy 341.698526 -244.249452) (xy 341.647744 -244.241409)
			(xy 341.598845 -244.225521) (xy 341.553033 -244.202178) (xy 341.511437 -244.171957) (xy 341.475081 -244.135601)
			(xy 341.44486 -244.094005) (xy 341.421517 -244.048193) (xy 341.405629 -243.999294) (xy 341.397586 -243.948512)
			(xy 340.171282 -243.948512) (xy 340.163239 -243.999294) (xy 340.147351 -244.048193) (xy 340.124008 -244.094005)
			(xy 340.093787 -244.135601) (xy 340.057431 -244.171957) (xy 340.015835 -244.202178) (xy 339.970023 -244.225521)
			(xy 339.921124 -244.241409) (xy 339.870342 -244.249452) (xy 339.818926 -244.249452) (xy 339.768144 -244.241409)
			(xy 339.719245 -244.225521) (xy 339.673433 -244.202178) (xy 339.631837 -244.171957) (xy 339.595481 -244.135601)
			(xy 339.56526 -244.094005) (xy 339.541917 -244.048193) (xy 339.526029 -243.999294) (xy 339.517986 -243.948512)
			(xy 338.291682 -243.948512) (xy 338.283639 -243.999294) (xy 338.267751 -244.048193) (xy 338.244408 -244.094005)
			(xy 338.214187 -244.135601) (xy 338.177831 -244.171957) (xy 338.136235 -244.202178) (xy 338.090423 -244.225521)
			(xy 338.041524 -244.241409) (xy 337.990742 -244.249452) (xy 337.939326 -244.249452) (xy 337.888544 -244.241409)
			(xy 337.839645 -244.225521) (xy 337.793833 -244.202178) (xy 337.752237 -244.171957) (xy 337.715881 -244.135601)
			(xy 337.68566 -244.094005) (xy 337.662317 -244.048193) (xy 337.646429 -243.999294) (xy 337.638386 -243.948512)
			(xy 337.351882 -243.948512) (xy 337.343839 -243.999294) (xy 337.327951 -244.048193) (xy 337.304608 -244.094005)
			(xy 337.274387 -244.135601) (xy 337.238031 -244.171957) (xy 337.196435 -244.202178) (xy 337.150623 -244.225521)
			(xy 337.101724 -244.241409) (xy 337.050942 -244.249452) (xy 336.999526 -244.249452) (xy 336.948744 -244.241409)
			(xy 336.899845 -244.225521) (xy 336.854033 -244.202178) (xy 336.812437 -244.171957) (xy 336.776081 -244.135601)
			(xy 336.74586 -244.094005) (xy 336.722517 -244.048193) (xy 336.706629 -243.999294) (xy 336.698586 -243.948512)
			(xy 331.100684 -243.948512) (xy 331.100684 -244.762328) (xy 339.047832 -244.762328) (xy 339.047832 -244.710912)
			(xy 339.055875 -244.66013) (xy 339.071763 -244.611231) (xy 339.095106 -244.565419) (xy 339.125327 -244.523823)
			(xy 339.161683 -244.487467) (xy 339.203279 -244.457246) (xy 339.249091 -244.433903) (xy 339.29799 -244.418015)
			(xy 339.348772 -244.409972) (xy 339.400188 -244.409972) (xy 339.45097 -244.418015) (xy 339.499869 -244.433903)
			(xy 339.545681 -244.457246) (xy 339.587277 -244.487467) (xy 339.623633 -244.523823) (xy 339.653854 -244.565419)
			(xy 339.677197 -244.611231) (xy 339.693085 -244.66013) (xy 339.701128 -244.710912) (xy 339.701632 -244.73662)
			(xy 339.701128 -244.762328) (xy 341.867232 -244.762328) (xy 341.867232 -244.710912) (xy 341.875275 -244.66013)
			(xy 341.891163 -244.611231) (xy 341.914506 -244.565419) (xy 341.944727 -244.523823) (xy 341.981083 -244.487467)
			(xy 342.022679 -244.457246) (xy 342.068491 -244.433903) (xy 342.11739 -244.418015) (xy 342.168172 -244.409972)
			(xy 342.219588 -244.409972) (xy 342.27037 -244.418015) (xy 342.319269 -244.433903) (xy 342.365081 -244.457246)
			(xy 342.406677 -244.487467) (xy 342.443033 -244.523823) (xy 342.473254 -244.565419) (xy 342.496597 -244.611231)
			(xy 342.512485 -244.66013) (xy 342.520528 -244.710912) (xy 342.521032 -244.73662) (xy 342.520528 -244.762328)
			(xy 345.626432 -244.762328) (xy 345.626432 -244.710912) (xy 345.634475 -244.66013) (xy 345.650363 -244.611231)
			(xy 345.673706 -244.565419) (xy 345.703927 -244.523823) (xy 345.740283 -244.487467) (xy 345.781879 -244.457246)
			(xy 345.827691 -244.433903) (xy 345.87659 -244.418015) (xy 345.927372 -244.409972) (xy 345.978788 -244.409972)
			(xy 346.02957 -244.418015) (xy 346.078469 -244.433903) (xy 346.124281 -244.457246) (xy 346.165877 -244.487467)
			(xy 346.202233 -244.523823) (xy 346.232454 -244.565419) (xy 346.255797 -244.611231) (xy 346.271685 -244.66013)
			(xy 346.279728 -244.710912) (xy 346.280232 -244.73662) (xy 346.279728 -244.762328) (xy 346.271685 -244.81311)
			(xy 346.255797 -244.862009) (xy 346.232454 -244.907821) (xy 346.202233 -244.949417) (xy 346.165877 -244.985773)
			(xy 346.124281 -245.015994) (xy 346.078469 -245.039337) (xy 346.02957 -245.055225) (xy 345.978788 -245.063268)
			(xy 345.927372 -245.063268) (xy 345.87659 -245.055225) (xy 345.827691 -245.039337) (xy 345.781879 -245.015994)
			(xy 345.740283 -244.985773) (xy 345.703927 -244.949417) (xy 345.673706 -244.907821) (xy 345.650363 -244.862009)
			(xy 345.634475 -244.81311) (xy 345.626432 -244.762328) (xy 342.520528 -244.762328) (xy 342.512485 -244.81311)
			(xy 342.496597 -244.862009) (xy 342.473254 -244.907821) (xy 342.443033 -244.949417) (xy 342.406677 -244.985773)
			(xy 342.365081 -245.015994) (xy 342.319269 -245.039337) (xy 342.27037 -245.055225) (xy 342.219588 -245.063268)
			(xy 342.168172 -245.063268) (xy 342.11739 -245.055225) (xy 342.068491 -245.039337) (xy 342.022679 -245.015994)
			(xy 341.981083 -244.985773) (xy 341.944727 -244.949417) (xy 341.914506 -244.907821) (xy 341.891163 -244.862009)
			(xy 341.875275 -244.81311) (xy 341.867232 -244.762328) (xy 339.701128 -244.762328) (xy 339.693085 -244.81311)
			(xy 339.677197 -244.862009) (xy 339.653854 -244.907821) (xy 339.623633 -244.949417) (xy 339.587277 -244.985773)
			(xy 339.545681 -245.015994) (xy 339.499869 -245.039337) (xy 339.45097 -245.055225) (xy 339.400188 -245.063268)
			(xy 339.348772 -245.063268) (xy 339.29799 -245.055225) (xy 339.249091 -245.039337) (xy 339.203279 -245.015994)
			(xy 339.161683 -244.985773) (xy 339.125327 -244.949417) (xy 339.095106 -244.907821) (xy 339.071763 -244.862009)
			(xy 339.055875 -244.81311) (xy 339.047832 -244.762328) (xy 331.100684 -244.762328) (xy 331.100684 -245.576398)
			(xy 336.698586 -245.576398) (xy 336.698586 -245.524982) (xy 336.706629 -245.4742) (xy 336.722517 -245.425301)
			(xy 336.74586 -245.379489) (xy 336.776081 -245.337893) (xy 336.812437 -245.301537) (xy 336.854033 -245.271316)
			(xy 336.899845 -245.247973) (xy 336.948744 -245.232085) (xy 336.999526 -245.224042) (xy 337.050942 -245.224042)
			(xy 337.101724 -245.232085) (xy 337.150623 -245.247973) (xy 337.196435 -245.271316) (xy 337.238031 -245.301537)
			(xy 337.274387 -245.337893) (xy 337.304608 -245.379489) (xy 337.327951 -245.425301) (xy 337.343839 -245.4742)
			(xy 337.351882 -245.524982) (xy 337.352386 -245.55069) (xy 337.351882 -245.576398) (xy 337.638386 -245.576398)
			(xy 337.638386 -245.524982) (xy 337.646429 -245.4742) (xy 337.662317 -245.425301) (xy 337.68566 -245.379489)
			(xy 337.715881 -245.337893) (xy 337.752237 -245.301537) (xy 337.793833 -245.271316) (xy 337.839645 -245.247973)
			(xy 337.888544 -245.232085) (xy 337.939326 -245.224042) (xy 337.990742 -245.224042) (xy 338.041524 -245.232085)
			(xy 338.090423 -245.247973) (xy 338.136235 -245.271316) (xy 338.177831 -245.301537) (xy 338.214187 -245.337893)
			(xy 338.244408 -245.379489) (xy 338.267751 -245.425301) (xy 338.283639 -245.4742) (xy 338.291682 -245.524982)
			(xy 338.292186 -245.55069) (xy 338.291682 -245.576398) (xy 339.517986 -245.576398) (xy 339.517986 -245.524982)
			(xy 339.526029 -245.4742) (xy 339.541917 -245.425301) (xy 339.56526 -245.379489) (xy 339.595481 -245.337893)
			(xy 339.631837 -245.301537) (xy 339.673433 -245.271316) (xy 339.719245 -245.247973) (xy 339.768144 -245.232085)
			(xy 339.818926 -245.224042) (xy 339.870342 -245.224042) (xy 339.921124 -245.232085) (xy 339.970023 -245.247973)
			(xy 340.015835 -245.271316) (xy 340.057431 -245.301537) (xy 340.093787 -245.337893) (xy 340.124008 -245.379489)
			(xy 340.147351 -245.425301) (xy 340.163239 -245.4742) (xy 340.171282 -245.524982) (xy 340.171786 -245.55069)
			(xy 340.171282 -245.576398) (xy 341.397586 -245.576398) (xy 341.397586 -245.524982) (xy 341.405629 -245.4742)
			(xy 341.421517 -245.425301) (xy 341.44486 -245.379489) (xy 341.475081 -245.337893) (xy 341.511437 -245.301537)
			(xy 341.553033 -245.271316) (xy 341.598845 -245.247973) (xy 341.647744 -245.232085) (xy 341.698526 -245.224042)
			(xy 341.749942 -245.224042) (xy 341.800724 -245.232085) (xy 341.849623 -245.247973) (xy 341.895435 -245.271316)
			(xy 341.937031 -245.301537) (xy 341.973387 -245.337893) (xy 342.003608 -245.379489) (xy 342.026951 -245.425301)
			(xy 342.042839 -245.4742) (xy 342.050882 -245.524982) (xy 342.051386 -245.55069) (xy 342.050882 -245.576398)
			(xy 343.277186 -245.576398) (xy 343.277186 -245.524982) (xy 343.285229 -245.4742) (xy 343.301117 -245.425301)
			(xy 343.32446 -245.379489) (xy 343.354681 -245.337893) (xy 343.391037 -245.301537) (xy 343.432633 -245.271316)
			(xy 343.478445 -245.247973) (xy 343.527344 -245.232085) (xy 343.578126 -245.224042) (xy 343.629542 -245.224042)
			(xy 343.680324 -245.232085) (xy 343.729223 -245.247973) (xy 343.775035 -245.271316) (xy 343.816631 -245.301537)
			(xy 343.852987 -245.337893) (xy 343.883208 -245.379489) (xy 343.906551 -245.425301) (xy 343.922439 -245.4742)
			(xy 343.930482 -245.524982) (xy 343.930986 -245.55069) (xy 343.930482 -245.576398) (xy 344.216986 -245.576398)
			(xy 344.216986 -245.524982) (xy 344.225029 -245.4742) (xy 344.240917 -245.425301) (xy 344.26426 -245.379489)
			(xy 344.294481 -245.337893) (xy 344.330837 -245.301537) (xy 344.372433 -245.271316) (xy 344.418245 -245.247973)
			(xy 344.467144 -245.232085) (xy 344.517926 -245.224042) (xy 344.569342 -245.224042) (xy 344.620124 -245.232085)
			(xy 344.669023 -245.247973) (xy 344.714835 -245.271316) (xy 344.756431 -245.301537) (xy 344.792787 -245.337893)
			(xy 344.823008 -245.379489) (xy 344.846351 -245.425301) (xy 344.862239 -245.4742) (xy 344.870282 -245.524982)
			(xy 344.870786 -245.55069) (xy 344.870282 -245.576398) (xy 344.862239 -245.62718) (xy 344.846351 -245.676079)
			(xy 344.823008 -245.721891) (xy 344.792787 -245.763487) (xy 344.756431 -245.799843) (xy 344.714835 -245.830064)
			(xy 344.669023 -245.853407) (xy 344.620124 -245.869295) (xy 344.569342 -245.877338) (xy 344.517926 -245.877338)
			(xy 344.467144 -245.869295) (xy 344.418245 -245.853407) (xy 344.372433 -245.830064) (xy 344.330837 -245.799843)
			(xy 344.294481 -245.763487) (xy 344.26426 -245.721891) (xy 344.240917 -245.676079) (xy 344.225029 -245.62718)
			(xy 344.216986 -245.576398) (xy 343.930482 -245.576398) (xy 343.922439 -245.62718) (xy 343.906551 -245.676079)
			(xy 343.883208 -245.721891) (xy 343.852987 -245.763487) (xy 343.816631 -245.799843) (xy 343.775035 -245.830064)
			(xy 343.729223 -245.853407) (xy 343.680324 -245.869295) (xy 343.629542 -245.877338) (xy 343.578126 -245.877338)
			(xy 343.527344 -245.869295) (xy 343.478445 -245.853407) (xy 343.432633 -245.830064) (xy 343.391037 -245.799843)
			(xy 343.354681 -245.763487) (xy 343.32446 -245.721891) (xy 343.301117 -245.676079) (xy 343.285229 -245.62718)
			(xy 343.277186 -245.576398) (xy 342.050882 -245.576398) (xy 342.042839 -245.62718) (xy 342.026951 -245.676079)
			(xy 342.003608 -245.721891) (xy 341.973387 -245.763487) (xy 341.937031 -245.799843) (xy 341.895435 -245.830064)
			(xy 341.849623 -245.853407) (xy 341.800724 -245.869295) (xy 341.749942 -245.877338) (xy 341.698526 -245.877338)
			(xy 341.647744 -245.869295) (xy 341.598845 -245.853407) (xy 341.553033 -245.830064) (xy 341.511437 -245.799843)
			(xy 341.475081 -245.763487) (xy 341.44486 -245.721891) (xy 341.421517 -245.676079) (xy 341.405629 -245.62718)
			(xy 341.397586 -245.576398) (xy 340.171282 -245.576398) (xy 340.163239 -245.62718) (xy 340.147351 -245.676079)
			(xy 340.124008 -245.721891) (xy 340.093787 -245.763487) (xy 340.057431 -245.799843) (xy 340.015835 -245.830064)
			(xy 339.970023 -245.853407) (xy 339.921124 -245.869295) (xy 339.870342 -245.877338) (xy 339.818926 -245.877338)
			(xy 339.768144 -245.869295) (xy 339.719245 -245.853407) (xy 339.673433 -245.830064) (xy 339.631837 -245.799843)
			(xy 339.595481 -245.763487) (xy 339.56526 -245.721891) (xy 339.541917 -245.676079) (xy 339.526029 -245.62718)
			(xy 339.517986 -245.576398) (xy 338.291682 -245.576398) (xy 338.283639 -245.62718) (xy 338.267751 -245.676079)
			(xy 338.244408 -245.721891) (xy 338.214187 -245.763487) (xy 338.177831 -245.799843) (xy 338.136235 -245.830064)
			(xy 338.090423 -245.853407) (xy 338.041524 -245.869295) (xy 337.990742 -245.877338) (xy 337.939326 -245.877338)
			(xy 337.888544 -245.869295) (xy 337.839645 -245.853407) (xy 337.793833 -245.830064) (xy 337.752237 -245.799843)
			(xy 337.715881 -245.763487) (xy 337.68566 -245.721891) (xy 337.662317 -245.676079) (xy 337.646429 -245.62718)
			(xy 337.638386 -245.576398) (xy 337.351882 -245.576398) (xy 337.343839 -245.62718) (xy 337.327951 -245.676079)
			(xy 337.304608 -245.721891) (xy 337.274387 -245.763487) (xy 337.238031 -245.799843) (xy 337.196435 -245.830064)
			(xy 337.150623 -245.853407) (xy 337.101724 -245.869295) (xy 337.050942 -245.877338) (xy 336.999526 -245.877338)
			(xy 336.948744 -245.869295) (xy 336.899845 -245.853407) (xy 336.854033 -245.830064) (xy 336.812437 -245.799843)
			(xy 336.776081 -245.763487) (xy 336.74586 -245.721891) (xy 336.722517 -245.676079) (xy 336.706629 -245.62718)
			(xy 336.698586 -245.576398) (xy 331.100684 -245.576398) (xy 331.100684 -246.363744) (xy 331.127154 -246.390214)
			(xy 336.228432 -246.390214) (xy 336.228432 -246.338798) (xy 336.236475 -246.288016) (xy 336.252363 -246.239117)
			(xy 336.275706 -246.193305) (xy 336.305927 -246.151709) (xy 336.342283 -246.115353) (xy 336.383879 -246.085132)
			(xy 336.429691 -246.061789) (xy 336.47859 -246.045901) (xy 336.529372 -246.037858) (xy 336.580788 -246.037858)
			(xy 336.63157 -246.045901) (xy 336.680469 -246.061789) (xy 336.726281 -246.085132) (xy 336.767877 -246.115353)
			(xy 336.804233 -246.151709) (xy 336.834454 -246.193305) (xy 336.857797 -246.239117) (xy 336.873685 -246.288016)
			(xy 336.881728 -246.338798) (xy 336.882232 -246.364506) (xy 336.881728 -246.390214) (xy 338.108032 -246.390214)
			(xy 338.108032 -246.338798) (xy 338.116075 -246.288016) (xy 338.131963 -246.239117) (xy 338.155306 -246.193305)
			(xy 338.185527 -246.151709) (xy 338.221883 -246.115353) (xy 338.263479 -246.085132) (xy 338.309291 -246.061789)
			(xy 338.35819 -246.045901) (xy 338.408972 -246.037858) (xy 338.460388 -246.037858) (xy 338.51117 -246.045901)
			(xy 338.560069 -246.061789) (xy 338.605881 -246.085132) (xy 338.647477 -246.115353) (xy 338.683833 -246.151709)
			(xy 338.714054 -246.193305) (xy 338.737397 -246.239117) (xy 338.753285 -246.288016) (xy 338.761328 -246.338798)
			(xy 338.761832 -246.364506) (xy 338.761328 -246.390214) (xy 339.987632 -246.390214) (xy 339.987632 -246.338798)
			(xy 339.995675 -246.288016) (xy 340.011563 -246.239117) (xy 340.034906 -246.193305) (xy 340.065127 -246.151709)
			(xy 340.101483 -246.115353) (xy 340.143079 -246.085132) (xy 340.188891 -246.061789) (xy 340.23779 -246.045901)
			(xy 340.288572 -246.037858) (xy 340.339988 -246.037858) (xy 340.39077 -246.045901) (xy 340.439669 -246.061789)
			(xy 340.485481 -246.085132) (xy 340.527077 -246.115353) (xy 340.563433 -246.151709) (xy 340.593654 -246.193305)
			(xy 340.616997 -246.239117) (xy 340.632885 -246.288016) (xy 340.640928 -246.338798) (xy 340.641432 -246.364506)
			(xy 340.640928 -246.390214) (xy 340.927432 -246.390214) (xy 340.927432 -246.338798) (xy 340.935475 -246.288016)
			(xy 340.951363 -246.239117) (xy 340.974706 -246.193305) (xy 341.004927 -246.151709) (xy 341.041283 -246.115353)
			(xy 341.082879 -246.085132) (xy 341.128691 -246.061789) (xy 341.17759 -246.045901) (xy 341.228372 -246.037858)
			(xy 341.279788 -246.037858) (xy 341.33057 -246.045901) (xy 341.379469 -246.061789) (xy 341.425281 -246.085132)
			(xy 341.466877 -246.115353) (xy 341.503233 -246.151709) (xy 341.533454 -246.193305) (xy 341.556797 -246.239117)
			(xy 341.572685 -246.288016) (xy 341.580728 -246.338798) (xy 341.581232 -246.364506) (xy 341.580728 -246.390214)
			(xy 342.807032 -246.390214) (xy 342.807032 -246.338798) (xy 342.815075 -246.288016) (xy 342.830963 -246.239117)
			(xy 342.854306 -246.193305) (xy 342.884527 -246.151709) (xy 342.920883 -246.115353) (xy 342.962479 -246.085132)
			(xy 343.008291 -246.061789) (xy 343.05719 -246.045901) (xy 343.107972 -246.037858) (xy 343.159388 -246.037858)
			(xy 343.21017 -246.045901) (xy 343.259069 -246.061789) (xy 343.304881 -246.085132) (xy 343.346477 -246.115353)
			(xy 343.382833 -246.151709) (xy 343.413054 -246.193305) (xy 343.436397 -246.239117) (xy 343.452285 -246.288016)
			(xy 343.460328 -246.338798) (xy 343.460832 -246.364506) (xy 343.460328 -246.390214) (xy 344.686632 -246.390214)
			(xy 344.686632 -246.338798) (xy 344.694675 -246.288016) (xy 344.710563 -246.239117) (xy 344.733906 -246.193305)
			(xy 344.764127 -246.151709) (xy 344.800483 -246.115353) (xy 344.842079 -246.085132) (xy 344.887891 -246.061789)
			(xy 344.93679 -246.045901) (xy 344.987572 -246.037858) (xy 345.038988 -246.037858) (xy 345.08977 -246.045901)
			(xy 345.138669 -246.061789) (xy 345.184481 -246.085132) (xy 345.226077 -246.115353) (xy 345.262433 -246.151709)
			(xy 345.292654 -246.193305) (xy 345.315997 -246.239117) (xy 345.331885 -246.288016) (xy 345.339928 -246.338798)
			(xy 345.340432 -246.364506) (xy 345.339928 -246.390214) (xy 345.331885 -246.440996) (xy 345.315997 -246.489895)
			(xy 345.292654 -246.535707) (xy 345.262433 -246.577303) (xy 345.226077 -246.613659) (xy 345.184481 -246.64388)
			(xy 345.138669 -246.667223) (xy 345.08977 -246.683111) (xy 345.038988 -246.691154) (xy 344.987572 -246.691154)
			(xy 344.93679 -246.683111) (xy 344.887891 -246.667223) (xy 344.842079 -246.64388) (xy 344.800483 -246.613659)
			(xy 344.764127 -246.577303) (xy 344.733906 -246.535707) (xy 344.710563 -246.489895) (xy 344.694675 -246.440996)
			(xy 344.686632 -246.390214) (xy 343.460328 -246.390214) (xy 343.452285 -246.440996) (xy 343.436397 -246.489895)
			(xy 343.413054 -246.535707) (xy 343.382833 -246.577303) (xy 343.346477 -246.613659) (xy 343.304881 -246.64388)
			(xy 343.259069 -246.667223) (xy 343.21017 -246.683111) (xy 343.159388 -246.691154) (xy 343.107972 -246.691154)
			(xy 343.05719 -246.683111) (xy 343.008291 -246.667223) (xy 342.962479 -246.64388) (xy 342.920883 -246.613659)
			(xy 342.884527 -246.577303) (xy 342.854306 -246.535707) (xy 342.830963 -246.489895) (xy 342.815075 -246.440996)
			(xy 342.807032 -246.390214) (xy 341.580728 -246.390214) (xy 341.572685 -246.440996) (xy 341.556797 -246.489895)
			(xy 341.533454 -246.535707) (xy 341.503233 -246.577303) (xy 341.466877 -246.613659) (xy 341.425281 -246.64388)
			(xy 341.379469 -246.667223) (xy 341.33057 -246.683111) (xy 341.279788 -246.691154) (xy 341.228372 -246.691154)
			(xy 341.17759 -246.683111) (xy 341.128691 -246.667223) (xy 341.082879 -246.64388) (xy 341.041283 -246.613659)
			(xy 341.004927 -246.577303) (xy 340.974706 -246.535707) (xy 340.951363 -246.489895) (xy 340.935475 -246.440996)
			(xy 340.927432 -246.390214) (xy 340.640928 -246.390214) (xy 340.632885 -246.440996) (xy 340.616997 -246.489895)
			(xy 340.593654 -246.535707) (xy 340.563433 -246.577303) (xy 340.527077 -246.613659) (xy 340.485481 -246.64388)
			(xy 340.439669 -246.667223) (xy 340.39077 -246.683111) (xy 340.339988 -246.691154) (xy 340.288572 -246.691154)
			(xy 340.23779 -246.683111) (xy 340.188891 -246.667223) (xy 340.143079 -246.64388) (xy 340.101483 -246.613659)
			(xy 340.065127 -246.577303) (xy 340.034906 -246.535707) (xy 340.011563 -246.489895) (xy 339.995675 -246.440996)
			(xy 339.987632 -246.390214) (xy 338.761328 -246.390214) (xy 338.753285 -246.440996) (xy 338.737397 -246.489895)
			(xy 338.714054 -246.535707) (xy 338.683833 -246.577303) (xy 338.647477 -246.613659) (xy 338.605881 -246.64388)
			(xy 338.560069 -246.667223) (xy 338.51117 -246.683111) (xy 338.460388 -246.691154) (xy 338.408972 -246.691154)
			(xy 338.35819 -246.683111) (xy 338.309291 -246.667223) (xy 338.263479 -246.64388) (xy 338.221883 -246.613659)
			(xy 338.185527 -246.577303) (xy 338.155306 -246.535707) (xy 338.131963 -246.489895) (xy 338.116075 -246.440996)
			(xy 338.108032 -246.390214) (xy 336.881728 -246.390214) (xy 336.873685 -246.440996) (xy 336.857797 -246.489895)
			(xy 336.834454 -246.535707) (xy 336.804233 -246.577303) (xy 336.767877 -246.613659) (xy 336.726281 -246.64388)
			(xy 336.680469 -246.667223) (xy 336.63157 -246.683111) (xy 336.580788 -246.691154) (xy 336.529372 -246.691154)
			(xy 336.47859 -246.683111) (xy 336.429691 -246.667223) (xy 336.383879 -246.64388) (xy 336.342283 -246.613659)
			(xy 336.305927 -246.577303) (xy 336.275706 -246.535707) (xy 336.252363 -246.489895) (xy 336.236475 -246.440996)
			(xy 336.228432 -246.390214) (xy 331.127154 -246.390214) (xy 331.94097 -247.20403) (xy 335.758786 -247.20403)
			(xy 335.758786 -247.152614) (xy 335.766829 -247.101832) (xy 335.782717 -247.052933) (xy 335.80606 -247.007121)
			(xy 335.836281 -246.965525) (xy 335.872637 -246.929169) (xy 335.914233 -246.898948) (xy 335.960045 -246.875605)
			(xy 336.008944 -246.859717) (xy 336.059726 -246.851674) (xy 336.111142 -246.851674) (xy 336.161924 -246.859717)
			(xy 336.210823 -246.875605) (xy 336.256635 -246.898948) (xy 336.298231 -246.929169) (xy 336.334587 -246.965525)
			(xy 336.364808 -247.007121) (xy 336.388151 -247.052933) (xy 336.404039 -247.101832) (xy 336.412082 -247.152614)
			(xy 336.412586 -247.178322) (xy 336.412082 -247.20403) (xy 338.578186 -247.20403) (xy 338.578186 -247.152614)
			(xy 338.586229 -247.101832) (xy 338.602117 -247.052933) (xy 338.62546 -247.007121) (xy 338.655681 -246.965525)
			(xy 338.692037 -246.929169) (xy 338.733633 -246.898948) (xy 338.779445 -246.875605) (xy 338.828344 -246.859717)
			(xy 338.879126 -246.851674) (xy 338.930542 -246.851674) (xy 338.981324 -246.859717) (xy 339.030223 -246.875605)
			(xy 339.076035 -246.898948) (xy 339.117631 -246.929169) (xy 339.153987 -246.965525) (xy 339.184208 -247.007121)
			(xy 339.207551 -247.052933) (xy 339.223439 -247.101832) (xy 339.231482 -247.152614) (xy 339.231986 -247.178322)
			(xy 339.231482 -247.20403) (xy 342.337386 -247.20403) (xy 342.337386 -247.152614) (xy 342.345429 -247.101832)
			(xy 342.361317 -247.052933) (xy 342.38466 -247.007121) (xy 342.414881 -246.965525) (xy 342.451237 -246.929169)
			(xy 342.492833 -246.898948) (xy 342.538645 -246.875605) (xy 342.587544 -246.859717) (xy 342.638326 -246.851674)
			(xy 342.689742 -246.851674) (xy 342.740524 -246.859717) (xy 342.789423 -246.875605) (xy 342.835235 -246.898948)
			(xy 342.876831 -246.929169) (xy 342.913187 -246.965525) (xy 342.943408 -247.007121) (xy 342.966751 -247.052933)
			(xy 342.982639 -247.101832) (xy 342.990682 -247.152614) (xy 342.991186 -247.178322) (xy 342.990682 -247.20403)
			(xy 345.156786 -247.20403) (xy 345.156786 -247.152614) (xy 345.164829 -247.101832) (xy 345.180717 -247.052933)
			(xy 345.20406 -247.007121) (xy 345.234281 -246.965525) (xy 345.270637 -246.929169) (xy 345.312233 -246.898948)
			(xy 345.358045 -246.875605) (xy 345.406944 -246.859717) (xy 345.457726 -246.851674) (xy 345.509142 -246.851674)
			(xy 345.559924 -246.859717) (xy 345.608823 -246.875605) (xy 345.654635 -246.898948) (xy 345.696231 -246.929169)
			(xy 345.732587 -246.965525) (xy 345.762808 -247.007121) (xy 345.786151 -247.052933) (xy 345.802039 -247.101832)
			(xy 345.810082 -247.152614) (xy 345.810586 -247.178322) (xy 345.810082 -247.20403) (xy 345.802039 -247.254812)
			(xy 345.786151 -247.303711) (xy 345.762808 -247.349523) (xy 345.732587 -247.391119) (xy 345.696231 -247.427475)
			(xy 345.654635 -247.457696) (xy 345.608823 -247.481039) (xy 345.559924 -247.496927) (xy 345.509142 -247.50497)
			(xy 345.457726 -247.50497) (xy 345.406944 -247.496927) (xy 345.358045 -247.481039) (xy 345.312233 -247.457696)
			(xy 345.270637 -247.427475) (xy 345.234281 -247.391119) (xy 345.20406 -247.349523) (xy 345.180717 -247.303711)
			(xy 345.164829 -247.254812) (xy 345.156786 -247.20403) (xy 342.990682 -247.20403) (xy 342.982639 -247.254812)
			(xy 342.966751 -247.303711) (xy 342.943408 -247.349523) (xy 342.913187 -247.391119) (xy 342.876831 -247.427475)
			(xy 342.835235 -247.457696) (xy 342.789423 -247.481039) (xy 342.740524 -247.496927) (xy 342.689742 -247.50497)
			(xy 342.638326 -247.50497) (xy 342.587544 -247.496927) (xy 342.538645 -247.481039) (xy 342.492833 -247.457696)
			(xy 342.451237 -247.427475) (xy 342.414881 -247.391119) (xy 342.38466 -247.349523) (xy 342.361317 -247.303711)
			(xy 342.345429 -247.254812) (xy 342.337386 -247.20403) (xy 339.231482 -247.20403) (xy 339.223439 -247.254812)
			(xy 339.207551 -247.303711) (xy 339.184208 -247.349523) (xy 339.153987 -247.391119) (xy 339.117631 -247.427475)
			(xy 339.076035 -247.457696) (xy 339.030223 -247.481039) (xy 338.981324 -247.496927) (xy 338.930542 -247.50497)
			(xy 338.879126 -247.50497) (xy 338.828344 -247.496927) (xy 338.779445 -247.481039) (xy 338.733633 -247.457696)
			(xy 338.692037 -247.427475) (xy 338.655681 -247.391119) (xy 338.62546 -247.349523) (xy 338.602117 -247.303711)
			(xy 338.586229 -247.254812) (xy 338.578186 -247.20403) (xy 336.412082 -247.20403) (xy 336.404039 -247.254812)
			(xy 336.388151 -247.303711) (xy 336.364808 -247.349523) (xy 336.334587 -247.391119) (xy 336.298231 -247.427475)
			(xy 336.256635 -247.457696) (xy 336.210823 -247.481039) (xy 336.161924 -247.496927) (xy 336.111142 -247.50497)
			(xy 336.059726 -247.50497) (xy 336.008944 -247.496927) (xy 335.960045 -247.481039) (xy 335.914233 -247.457696)
			(xy 335.872637 -247.427475) (xy 335.836281 -247.391119) (xy 335.80606 -247.349523) (xy 335.782717 -247.303711)
			(xy 335.766829 -247.254812) (xy 335.758786 -247.20403) (xy 331.94097 -247.20403) (xy 332.386686 -247.649746)
			(xy 333.572104 -247.649746) (xy 333.940204 -248.017846) (xy 336.228432 -248.017846) (xy 336.228432 -247.96643)
			(xy 336.236475 -247.915648) (xy 336.252363 -247.866749) (xy 336.275706 -247.820937) (xy 336.305927 -247.779341)
			(xy 336.342283 -247.742985) (xy 336.383879 -247.712764) (xy 336.429691 -247.689421) (xy 336.47859 -247.673533)
			(xy 336.529372 -247.66549) (xy 336.580788 -247.66549) (xy 336.63157 -247.673533) (xy 336.680469 -247.689421)
			(xy 336.726281 -247.712764) (xy 336.767877 -247.742985) (xy 336.804233 -247.779341) (xy 336.834454 -247.820937)
			(xy 336.857797 -247.866749) (xy 336.873685 -247.915648) (xy 336.881728 -247.96643) (xy 336.882232 -247.992138)
			(xy 336.881728 -248.017846) (xy 338.108032 -248.017846) (xy 338.108032 -247.96643) (xy 338.116075 -247.915648)
			(xy 338.131963 -247.866749) (xy 338.155306 -247.820937) (xy 338.185527 -247.779341) (xy 338.221883 -247.742985)
			(xy 338.263479 -247.712764) (xy 338.309291 -247.689421) (xy 338.35819 -247.673533) (xy 338.408972 -247.66549)
			(xy 338.460388 -247.66549) (xy 338.51117 -247.673533) (xy 338.560069 -247.689421) (xy 338.605881 -247.712764)
			(xy 338.647477 -247.742985) (xy 338.683833 -247.779341) (xy 338.714054 -247.820937) (xy 338.737397 -247.866749)
			(xy 338.753285 -247.915648) (xy 338.761328 -247.96643) (xy 338.761832 -247.992138) (xy 338.761328 -248.017846)
			(xy 339.987632 -248.017846) (xy 339.987632 -247.96643) (xy 339.995675 -247.915648) (xy 340.011563 -247.866749)
			(xy 340.034906 -247.820937) (xy 340.065127 -247.779341) (xy 340.101483 -247.742985) (xy 340.143079 -247.712764)
			(xy 340.188891 -247.689421) (xy 340.23779 -247.673533) (xy 340.288572 -247.66549) (xy 340.339988 -247.66549)
			(xy 340.39077 -247.673533) (xy 340.439669 -247.689421) (xy 340.485481 -247.712764) (xy 340.527077 -247.742985)
			(xy 340.563433 -247.779341) (xy 340.593654 -247.820937) (xy 340.616997 -247.866749) (xy 340.632885 -247.915648)
			(xy 340.640928 -247.96643) (xy 340.641432 -247.992138) (xy 340.640928 -248.017846) (xy 340.927432 -248.017846)
			(xy 340.927432 -247.96643) (xy 340.935475 -247.915648) (xy 340.951363 -247.866749) (xy 340.974706 -247.820937)
			(xy 341.004927 -247.779341) (xy 341.041283 -247.742985) (xy 341.082879 -247.712764) (xy 341.128691 -247.689421)
			(xy 341.17759 -247.673533) (xy 341.228372 -247.66549) (xy 341.279788 -247.66549) (xy 341.33057 -247.673533)
			(xy 341.379469 -247.689421) (xy 341.425281 -247.712764) (xy 341.466877 -247.742985) (xy 341.503233 -247.779341)
			(xy 341.533454 -247.820937) (xy 341.556797 -247.866749) (xy 341.572685 -247.915648) (xy 341.580728 -247.96643)
			(xy 341.581232 -247.992138) (xy 341.580728 -248.017846) (xy 342.807032 -248.017846) (xy 342.807032 -247.96643)
			(xy 342.815075 -247.915648) (xy 342.830963 -247.866749) (xy 342.854306 -247.820937) (xy 342.884527 -247.779341)
			(xy 342.920883 -247.742985) (xy 342.962479 -247.712764) (xy 343.008291 -247.689421) (xy 343.05719 -247.673533)
			(xy 343.107972 -247.66549) (xy 343.159388 -247.66549) (xy 343.21017 -247.673533) (xy 343.259069 -247.689421)
			(xy 343.304881 -247.712764) (xy 343.346477 -247.742985) (xy 343.382833 -247.779341) (xy 343.413054 -247.820937)
			(xy 343.436397 -247.866749) (xy 343.452285 -247.915648) (xy 343.460328 -247.96643) (xy 343.460832 -247.992138)
			(xy 343.460328 -248.017846) (xy 344.686632 -248.017846) (xy 344.686632 -247.96643) (xy 344.694675 -247.915648)
			(xy 344.710563 -247.866749) (xy 344.733906 -247.820937) (xy 344.764127 -247.779341) (xy 344.800483 -247.742985)
			(xy 344.842079 -247.712764) (xy 344.887891 -247.689421) (xy 344.93679 -247.673533) (xy 344.987572 -247.66549)
			(xy 345.038988 -247.66549) (xy 345.08977 -247.673533) (xy 345.138669 -247.689421) (xy 345.184481 -247.712764)
			(xy 345.226077 -247.742985) (xy 345.262433 -247.779341) (xy 345.292654 -247.820937) (xy 345.315997 -247.866749)
			(xy 345.331885 -247.915648) (xy 345.339928 -247.96643) (xy 345.340432 -247.992138) (xy 345.339928 -248.017846)
			(xy 345.331885 -248.068628) (xy 345.315997 -248.117527) (xy 345.292654 -248.163339) (xy 345.262433 -248.204935)
			(xy 345.226077 -248.241291) (xy 345.184481 -248.271512) (xy 345.138669 -248.294855) (xy 345.08977 -248.310743)
			(xy 345.038988 -248.318786) (xy 344.987572 -248.318786) (xy 344.93679 -248.310743) (xy 344.887891 -248.294855)
			(xy 344.842079 -248.271512) (xy 344.800483 -248.241291) (xy 344.764127 -248.204935) (xy 344.733906 -248.163339)
			(xy 344.710563 -248.117527) (xy 344.694675 -248.068628) (xy 344.686632 -248.017846) (xy 343.460328 -248.017846)
			(xy 343.452285 -248.068628) (xy 343.436397 -248.117527) (xy 343.413054 -248.163339) (xy 343.382833 -248.204935)
			(xy 343.346477 -248.241291) (xy 343.304881 -248.271512) (xy 343.259069 -248.294855) (xy 343.21017 -248.310743)
			(xy 343.159388 -248.318786) (xy 343.107972 -248.318786) (xy 343.05719 -248.310743) (xy 343.008291 -248.294855)
			(xy 342.962479 -248.271512) (xy 342.920883 -248.241291) (xy 342.884527 -248.204935) (xy 342.854306 -248.163339)
			(xy 342.830963 -248.117527) (xy 342.815075 -248.068628) (xy 342.807032 -248.017846) (xy 341.580728 -248.017846)
			(xy 341.572685 -248.068628) (xy 341.556797 -248.117527) (xy 341.533454 -248.163339) (xy 341.503233 -248.204935)
			(xy 341.466877 -248.241291) (xy 341.425281 -248.271512) (xy 341.379469 -248.294855) (xy 341.33057 -248.310743)
			(xy 341.279788 -248.318786) (xy 341.228372 -248.318786) (xy 341.17759 -248.310743) (xy 341.128691 -248.294855)
			(xy 341.082879 -248.271512) (xy 341.041283 -248.241291) (xy 341.004927 -248.204935) (xy 340.974706 -248.163339)
			(xy 340.951363 -248.117527) (xy 340.935475 -248.068628) (xy 340.927432 -248.017846) (xy 340.640928 -248.017846)
			(xy 340.632885 -248.068628) (xy 340.616997 -248.117527) (xy 340.593654 -248.163339) (xy 340.563433 -248.204935)
			(xy 340.527077 -248.241291) (xy 340.485481 -248.271512) (xy 340.439669 -248.294855) (xy 340.39077 -248.310743)
			(xy 340.339988 -248.318786) (xy 340.288572 -248.318786) (xy 340.23779 -248.310743) (xy 340.188891 -248.294855)
			(xy 340.143079 -248.271512) (xy 340.101483 -248.241291) (xy 340.065127 -248.204935) (xy 340.034906 -248.163339)
			(xy 340.011563 -248.117527) (xy 339.995675 -248.068628) (xy 339.987632 -248.017846) (xy 338.761328 -248.017846)
			(xy 338.753285 -248.068628) (xy 338.737397 -248.117527) (xy 338.714054 -248.163339) (xy 338.683833 -248.204935)
			(xy 338.647477 -248.241291) (xy 338.605881 -248.271512) (xy 338.560069 -248.294855) (xy 338.51117 -248.310743)
			(xy 338.460388 -248.318786) (xy 338.408972 -248.318786) (xy 338.35819 -248.310743) (xy 338.309291 -248.294855)
			(xy 338.263479 -248.271512) (xy 338.221883 -248.241291) (xy 338.185527 -248.204935) (xy 338.155306 -248.163339)
			(xy 338.131963 -248.117527) (xy 338.116075 -248.068628) (xy 338.108032 -248.017846) (xy 336.881728 -248.017846)
			(xy 336.873685 -248.068628) (xy 336.857797 -248.117527) (xy 336.834454 -248.163339) (xy 336.804233 -248.204935)
			(xy 336.767877 -248.241291) (xy 336.726281 -248.271512) (xy 336.680469 -248.294855) (xy 336.63157 -248.310743)
			(xy 336.580788 -248.318786) (xy 336.529372 -248.318786) (xy 336.47859 -248.310743) (xy 336.429691 -248.294855)
			(xy 336.383879 -248.271512) (xy 336.342283 -248.241291) (xy 336.305927 -248.204935) (xy 336.275706 -248.163339)
			(xy 336.252363 -248.117527) (xy 336.236475 -248.068628) (xy 336.228432 -248.017846) (xy 333.940204 -248.017846)
			(xy 334.754274 -248.831916) (xy 336.698586 -248.831916) (xy 336.698586 -248.7805) (xy 336.706629 -248.729718)
			(xy 336.722517 -248.680819) (xy 336.74586 -248.635007) (xy 336.776081 -248.593411) (xy 336.812437 -248.557055)
			(xy 336.854033 -248.526834) (xy 336.899845 -248.503491) (xy 336.948744 -248.487603) (xy 336.999526 -248.47956)
			(xy 337.050942 -248.47956) (xy 337.101724 -248.487603) (xy 337.150623 -248.503491) (xy 337.196435 -248.526834)
			(xy 337.238031 -248.557055) (xy 337.274387 -248.593411) (xy 337.304608 -248.635007) (xy 337.327951 -248.680819)
			(xy 337.343839 -248.729718) (xy 337.351882 -248.7805) (xy 337.352386 -248.806208) (xy 337.351882 -248.831916)
			(xy 337.638386 -248.831916) (xy 337.638386 -248.7805) (xy 337.646429 -248.729718) (xy 337.662317 -248.680819)
			(xy 337.68566 -248.635007) (xy 337.715881 -248.593411) (xy 337.752237 -248.557055) (xy 337.793833 -248.526834)
			(xy 337.839645 -248.503491) (xy 337.888544 -248.487603) (xy 337.939326 -248.47956) (xy 337.990742 -248.47956)
			(xy 338.041524 -248.487603) (xy 338.090423 -248.503491) (xy 338.136235 -248.526834) (xy 338.177831 -248.557055)
			(xy 338.214187 -248.593411) (xy 338.244408 -248.635007) (xy 338.267751 -248.680819) (xy 338.283639 -248.729718)
			(xy 338.291682 -248.7805) (xy 338.292186 -248.806208) (xy 338.291682 -248.831916) (xy 339.517986 -248.831916)
			(xy 339.517986 -248.7805) (xy 339.526029 -248.729718) (xy 339.541917 -248.680819) (xy 339.56526 -248.635007)
			(xy 339.595481 -248.593411) (xy 339.631837 -248.557055) (xy 339.673433 -248.526834) (xy 339.719245 -248.503491)
			(xy 339.768144 -248.487603) (xy 339.818926 -248.47956) (xy 339.870342 -248.47956) (xy 339.921124 -248.487603)
			(xy 339.970023 -248.503491) (xy 340.015835 -248.526834) (xy 340.057431 -248.557055) (xy 340.093787 -248.593411)
			(xy 340.124008 -248.635007) (xy 340.147351 -248.680819) (xy 340.163239 -248.729718) (xy 340.171282 -248.7805)
			(xy 340.171786 -248.806208) (xy 340.171282 -248.831916) (xy 341.397586 -248.831916) (xy 341.397586 -248.7805)
			(xy 341.405629 -248.729718) (xy 341.421517 -248.680819) (xy 341.44486 -248.635007) (xy 341.475081 -248.593411)
			(xy 341.511437 -248.557055) (xy 341.553033 -248.526834) (xy 341.598845 -248.503491) (xy 341.647744 -248.487603)
			(xy 341.698526 -248.47956) (xy 341.749942 -248.47956) (xy 341.800724 -248.487603) (xy 341.849623 -248.503491)
			(xy 341.895435 -248.526834) (xy 341.937031 -248.557055) (xy 341.973387 -248.593411) (xy 342.003608 -248.635007)
			(xy 342.026951 -248.680819) (xy 342.042839 -248.729718) (xy 342.050882 -248.7805) (xy 342.051386 -248.806208)
			(xy 342.050882 -248.831916) (xy 343.277186 -248.831916) (xy 343.277186 -248.7805) (xy 343.285229 -248.729718)
			(xy 343.301117 -248.680819) (xy 343.32446 -248.635007) (xy 343.354681 -248.593411) (xy 343.391037 -248.557055)
			(xy 343.432633 -248.526834) (xy 343.478445 -248.503491) (xy 343.527344 -248.487603) (xy 343.578126 -248.47956)
			(xy 343.629542 -248.47956) (xy 343.680324 -248.487603) (xy 343.729223 -248.503491) (xy 343.775035 -248.526834)
			(xy 343.816631 -248.557055) (xy 343.852987 -248.593411) (xy 343.883208 -248.635007) (xy 343.906551 -248.680819)
			(xy 343.922439 -248.729718) (xy 343.930482 -248.7805) (xy 343.930986 -248.806208) (xy 343.930482 -248.831916)
			(xy 344.216986 -248.831916) (xy 344.216986 -248.7805) (xy 344.225029 -248.729718) (xy 344.240917 -248.680819)
			(xy 344.26426 -248.635007) (xy 344.294481 -248.593411) (xy 344.330837 -248.557055) (xy 344.372433 -248.526834)
			(xy 344.418245 -248.503491) (xy 344.467144 -248.487603) (xy 344.517926 -248.47956) (xy 344.569342 -248.47956)
			(xy 344.620124 -248.487603) (xy 344.669023 -248.503491) (xy 344.714835 -248.526834) (xy 344.756431 -248.557055)
			(xy 344.792787 -248.593411) (xy 344.823008 -248.635007) (xy 344.846351 -248.680819) (xy 344.862239 -248.729718)
			(xy 344.870282 -248.7805) (xy 344.870786 -248.806208) (xy 344.870282 -248.831916) (xy 344.862239 -248.882698)
			(xy 344.846351 -248.931597) (xy 344.823008 -248.977409) (xy 344.792787 -249.019005) (xy 344.756431 -249.055361)
			(xy 344.714835 -249.085582) (xy 344.669023 -249.108925) (xy 344.620124 -249.124813) (xy 344.569342 -249.132856)
			(xy 344.517926 -249.132856) (xy 344.467144 -249.124813) (xy 344.418245 -249.108925) (xy 344.372433 -249.085582)
			(xy 344.330837 -249.055361) (xy 344.294481 -249.019005) (xy 344.26426 -248.977409) (xy 344.240917 -248.931597)
			(xy 344.225029 -248.882698) (xy 344.216986 -248.831916) (xy 343.930482 -248.831916) (xy 343.922439 -248.882698)
			(xy 343.906551 -248.931597) (xy 343.883208 -248.977409) (xy 343.852987 -249.019005) (xy 343.816631 -249.055361)
			(xy 343.775035 -249.085582) (xy 343.729223 -249.108925) (xy 343.680324 -249.124813) (xy 343.629542 -249.132856)
			(xy 343.578126 -249.132856) (xy 343.527344 -249.124813) (xy 343.478445 -249.108925) (xy 343.432633 -249.085582)
			(xy 343.391037 -249.055361) (xy 343.354681 -249.019005) (xy 343.32446 -248.977409) (xy 343.301117 -248.931597)
			(xy 343.285229 -248.882698) (xy 343.277186 -248.831916) (xy 342.050882 -248.831916) (xy 342.042839 -248.882698)
			(xy 342.026951 -248.931597) (xy 342.003608 -248.977409) (xy 341.973387 -249.019005) (xy 341.937031 -249.055361)
			(xy 341.895435 -249.085582) (xy 341.849623 -249.108925) (xy 341.800724 -249.124813) (xy 341.749942 -249.132856)
			(xy 341.698526 -249.132856) (xy 341.647744 -249.124813) (xy 341.598845 -249.108925) (xy 341.553033 -249.085582)
			(xy 341.511437 -249.055361) (xy 341.475081 -249.019005) (xy 341.44486 -248.977409) (xy 341.421517 -248.931597)
			(xy 341.405629 -248.882698) (xy 341.397586 -248.831916) (xy 340.171282 -248.831916) (xy 340.163239 -248.882698)
			(xy 340.147351 -248.931597) (xy 340.124008 -248.977409) (xy 340.093787 -249.019005) (xy 340.057431 -249.055361)
			(xy 340.015835 -249.085582) (xy 339.970023 -249.108925) (xy 339.921124 -249.124813) (xy 339.870342 -249.132856)
			(xy 339.818926 -249.132856) (xy 339.768144 -249.124813) (xy 339.719245 -249.108925) (xy 339.673433 -249.085582)
			(xy 339.631837 -249.055361) (xy 339.595481 -249.019005) (xy 339.56526 -248.977409) (xy 339.541917 -248.931597)
			(xy 339.526029 -248.882698) (xy 339.517986 -248.831916) (xy 338.291682 -248.831916) (xy 338.283639 -248.882698)
			(xy 338.267751 -248.931597) (xy 338.244408 -248.977409) (xy 338.214187 -249.019005) (xy 338.177831 -249.055361)
			(xy 338.136235 -249.085582) (xy 338.090423 -249.108925) (xy 338.041524 -249.124813) (xy 337.990742 -249.132856)
			(xy 337.939326 -249.132856) (xy 337.888544 -249.124813) (xy 337.839645 -249.108925) (xy 337.793833 -249.085582)
			(xy 337.752237 -249.055361) (xy 337.715881 -249.019005) (xy 337.68566 -248.977409) (xy 337.662317 -248.931597)
			(xy 337.646429 -248.882698) (xy 337.638386 -248.831916) (xy 337.351882 -248.831916) (xy 337.343839 -248.882698)
			(xy 337.327951 -248.931597) (xy 337.304608 -248.977409) (xy 337.274387 -249.019005) (xy 337.238031 -249.055361)
			(xy 337.196435 -249.085582) (xy 337.150623 -249.108925) (xy 337.101724 -249.124813) (xy 337.050942 -249.132856)
			(xy 336.999526 -249.132856) (xy 336.948744 -249.124813) (xy 336.899845 -249.108925) (xy 336.854033 -249.085582)
			(xy 336.812437 -249.055361) (xy 336.776081 -249.019005) (xy 336.74586 -248.977409) (xy 336.722517 -248.931597)
			(xy 336.706629 -248.882698) (xy 336.698586 -248.831916) (xy 334.754274 -248.831916) (xy 335.56809 -249.645732)
			(xy 339.047832 -249.645732) (xy 339.047832 -249.594316) (xy 339.055875 -249.543534) (xy 339.071763 -249.494635)
			(xy 339.095106 -249.448823) (xy 339.125327 -249.407227) (xy 339.161683 -249.370871) (xy 339.203279 -249.34065)
			(xy 339.249091 -249.317307) (xy 339.29799 -249.301419) (xy 339.348772 -249.293376) (xy 339.400188 -249.293376)
			(xy 339.45097 -249.301419) (xy 339.499869 -249.317307) (xy 339.545681 -249.34065) (xy 339.587277 -249.370871)
			(xy 339.623633 -249.407227) (xy 339.653854 -249.448823) (xy 339.677197 -249.494635) (xy 339.693085 -249.543534)
			(xy 339.701128 -249.594316) (xy 339.701632 -249.620024) (xy 339.701128 -249.645732) (xy 339.987632 -249.645732)
			(xy 339.987632 -249.594316) (xy 339.995675 -249.543534) (xy 340.011563 -249.494635) (xy 340.034906 -249.448823)
			(xy 340.065127 -249.407227) (xy 340.101483 -249.370871) (xy 340.143079 -249.34065) (xy 340.188891 -249.317307)
			(xy 340.23779 -249.301419) (xy 340.288572 -249.293376) (xy 340.339988 -249.293376) (xy 340.39077 -249.301419)
			(xy 340.439669 -249.317307) (xy 340.485481 -249.34065) (xy 340.527077 -249.370871) (xy 340.563433 -249.407227)
			(xy 340.593654 -249.448823) (xy 340.616997 -249.494635) (xy 340.632885 -249.543534) (xy 340.640928 -249.594316)
			(xy 340.641432 -249.620024) (xy 340.640928 -249.645732) (xy 340.927432 -249.645732) (xy 340.927432 -249.594316)
			(xy 340.935475 -249.543534) (xy 340.951363 -249.494635) (xy 340.974706 -249.448823) (xy 341.004927 -249.407227)
			(xy 341.041283 -249.370871) (xy 341.082879 -249.34065) (xy 341.128691 -249.317307) (xy 341.17759 -249.301419)
			(xy 341.228372 -249.293376) (xy 341.279788 -249.293376) (xy 341.33057 -249.301419) (xy 341.379469 -249.317307)
			(xy 341.425281 -249.34065) (xy 341.466877 -249.370871) (xy 341.503233 -249.407227) (xy 341.533454 -249.448823)
			(xy 341.556797 -249.494635) (xy 341.572685 -249.543534) (xy 341.580728 -249.594316) (xy 341.581232 -249.620024)
			(xy 341.580728 -249.645732) (xy 341.867232 -249.645732) (xy 341.867232 -249.594316) (xy 341.875275 -249.543534)
			(xy 341.891163 -249.494635) (xy 341.914506 -249.448823) (xy 341.944727 -249.407227) (xy 341.981083 -249.370871)
			(xy 342.022679 -249.34065) (xy 342.068491 -249.317307) (xy 342.11739 -249.301419) (xy 342.168172 -249.293376)
			(xy 342.219588 -249.293376) (xy 342.27037 -249.301419) (xy 342.319269 -249.317307) (xy 342.365081 -249.34065)
			(xy 342.406677 -249.370871) (xy 342.443033 -249.407227) (xy 342.473254 -249.448823) (xy 342.496597 -249.494635)
			(xy 342.512485 -249.543534) (xy 342.520528 -249.594316) (xy 342.521032 -249.620024) (xy 342.520528 -249.645732)
			(xy 345.626432 -249.645732) (xy 345.626432 -249.594316) (xy 345.634475 -249.543534) (xy 345.650363 -249.494635)
			(xy 345.673706 -249.448823) (xy 345.703927 -249.407227) (xy 345.740283 -249.370871) (xy 345.781879 -249.34065)
			(xy 345.827691 -249.317307) (xy 345.87659 -249.301419) (xy 345.927372 -249.293376) (xy 345.978788 -249.293376)
			(xy 346.02957 -249.301419) (xy 346.078469 -249.317307) (xy 346.124281 -249.34065) (xy 346.165877 -249.370871)
			(xy 346.202233 -249.407227) (xy 346.232454 -249.448823) (xy 346.255797 -249.494635) (xy 346.271685 -249.543534)
			(xy 346.279728 -249.594316) (xy 346.280232 -249.620024) (xy 346.279728 -249.645732) (xy 346.271685 -249.696514)
			(xy 346.255797 -249.745413) (xy 346.232454 -249.791225) (xy 346.202233 -249.832821) (xy 346.165877 -249.869177)
			(xy 346.124281 -249.899398) (xy 346.078469 -249.922741) (xy 346.02957 -249.938629) (xy 345.978788 -249.946672)
			(xy 345.927372 -249.946672) (xy 345.87659 -249.938629) (xy 345.827691 -249.922741) (xy 345.781879 -249.899398)
			(xy 345.740283 -249.869177) (xy 345.703927 -249.832821) (xy 345.673706 -249.791225) (xy 345.650363 -249.745413)
			(xy 345.634475 -249.696514) (xy 345.626432 -249.645732) (xy 342.520528 -249.645732) (xy 342.512485 -249.696514)
			(xy 342.496597 -249.745413) (xy 342.473254 -249.791225) (xy 342.443033 -249.832821) (xy 342.406677 -249.869177)
			(xy 342.365081 -249.899398) (xy 342.319269 -249.922741) (xy 342.27037 -249.938629) (xy 342.219588 -249.946672)
			(xy 342.168172 -249.946672) (xy 342.11739 -249.938629) (xy 342.068491 -249.922741) (xy 342.022679 -249.899398)
			(xy 341.981083 -249.869177) (xy 341.944727 -249.832821) (xy 341.914506 -249.791225) (xy 341.891163 -249.745413)
			(xy 341.875275 -249.696514) (xy 341.867232 -249.645732) (xy 341.580728 -249.645732) (xy 341.572685 -249.696514)
			(xy 341.556797 -249.745413) (xy 341.533454 -249.791225) (xy 341.503233 -249.832821) (xy 341.466877 -249.869177)
			(xy 341.425281 -249.899398) (xy 341.379469 -249.922741) (xy 341.33057 -249.938629) (xy 341.279788 -249.946672)
			(xy 341.228372 -249.946672) (xy 341.17759 -249.938629) (xy 341.128691 -249.922741) (xy 341.082879 -249.899398)
			(xy 341.041283 -249.869177) (xy 341.004927 -249.832821) (xy 340.974706 -249.791225) (xy 340.951363 -249.745413)
			(xy 340.935475 -249.696514) (xy 340.927432 -249.645732) (xy 340.640928 -249.645732) (xy 340.632885 -249.696514)
			(xy 340.616997 -249.745413) (xy 340.593654 -249.791225) (xy 340.563433 -249.832821) (xy 340.527077 -249.869177)
			(xy 340.485481 -249.899398) (xy 340.439669 -249.922741) (xy 340.39077 -249.938629) (xy 340.339988 -249.946672)
			(xy 340.288572 -249.946672) (xy 340.23779 -249.938629) (xy 340.188891 -249.922741) (xy 340.143079 -249.899398)
			(xy 340.101483 -249.869177) (xy 340.065127 -249.832821) (xy 340.034906 -249.791225) (xy 340.011563 -249.745413)
			(xy 339.995675 -249.696514) (xy 339.987632 -249.645732) (xy 339.701128 -249.645732) (xy 339.693085 -249.696514)
			(xy 339.677197 -249.745413) (xy 339.653854 -249.791225) (xy 339.623633 -249.832821) (xy 339.587277 -249.869177)
			(xy 339.545681 -249.899398) (xy 339.499869 -249.922741) (xy 339.45097 -249.938629) (xy 339.400188 -249.946672)
			(xy 339.348772 -249.946672) (xy 339.29799 -249.938629) (xy 339.249091 -249.922741) (xy 339.203279 -249.899398)
			(xy 339.161683 -249.869177) (xy 339.125327 -249.832821) (xy 339.095106 -249.791225) (xy 339.071763 -249.745413)
			(xy 339.055875 -249.696514) (xy 339.047832 -249.645732) (xy 335.56809 -249.645732) (xy 336.414364 -250.492006)
			(xy 336.414364 -250.728226) (xy 345.535504 -250.728226)
		)
		(stroke
			(width 0)
			(type solid)
		)
		(fill yes)
		(layer "B.Cu")
		(net "GND")
	)
	(gr_poly
		(pts
			(xy 126.453392 -222.484696) (xy 126.475379 -222.467564) (xy 126.523605 -222.439622) (xy 126.549404 -222.42907)
			(xy 126.562933 -222.387031) (xy 126.595743 -222.305031) (xy 126.634922 -222.225876) (xy 126.680226 -222.150061)
			(xy 126.731372 -222.078057) (xy 126.788042 -222.010315) (xy 126.818644 -221.978474) (xy 126.81712 -221.94774)
			(xy 126.817649 -221.920868) (xy 126.82637 -221.867838) (xy 126.843587 -221.816927) (xy 126.868843 -221.769489)
			(xy 126.901467 -221.726781) (xy 126.940594 -221.689938) (xy 126.985184 -221.659938) (xy 127.009398 -221.648274)
			(xy 127.020492 -221.609661) (xy 127.047488 -221.533984) (xy 127.079836 -221.460436) (xy 127.098298 -221.424754)
			(xy 127.10414 -221.413832) (xy 127.10414 -221.139258) (xy 127.009652 -221.139258) (xy 127.003048 -221.182692)
			(xy 126.998722 -221.208397) (xy 126.983027 -221.258102) (xy 126.9597 -221.304715) (xy 126.929324 -221.347074)
			(xy 126.892657 -221.38412) (xy 126.850614 -221.41493) (xy 126.804243 -221.438735) (xy 126.754703 -221.454942)
			(xy 126.703228 -221.463144) (xy 126.677166 -221.463616) (xy 126.651266 -221.463131) (xy 126.600106 -221.455019)
			(xy 126.550845 -221.439) (xy 126.504699 -221.415468) (xy 126.462805 -221.385005) (xy 126.426194 -221.348359)
			(xy 126.39577 -221.306436) (xy 126.372282 -221.260268) (xy 126.356309 -221.210992) (xy 126.348245 -221.159824)
			(xy 126.347728 -221.133924) (xy 126.348255 -221.106216) (xy 126.35745 -221.051569) (xy 126.366016 -221.025212)
			(xy 126.37389 -221.003114) (xy 126.168912 -220.648022) (xy 126.146052 -220.643704) (xy 126.121199 -220.638571)
			(xy 126.073343 -220.621685) (xy 126.028644 -220.597658) (xy 125.98816 -220.567059) (xy 125.952849 -220.530612)
			(xy 125.923546 -220.48918) (xy 125.900946 -220.443744) (xy 125.885583 -220.395378) (xy 125.877821 -220.345228)
			(xy 125.87732 -220.319854) (xy 125.877828 -220.293947) (xy 125.885934 -220.24277) (xy 125.901946 -220.193491)
			(xy 125.925469 -220.147324) (xy 125.955925 -220.105405) (xy 125.992563 -220.068767) (xy 126.034482 -220.038311)
			(xy 126.080649 -220.014788) (xy 126.129928 -219.998776) (xy 126.181105 -219.99067) (xy 126.232919 -219.99067)
			(xy 126.284096 -219.998776) (xy 126.333375 -220.014788) (xy 126.379542 -220.038311) (xy 126.421461 -220.068767)
			(xy 126.458099 -220.105405) (xy 126.488555 -220.147324) (xy 126.512078 -220.193491) (xy 126.52809 -220.24277)
			(xy 126.536196 -220.293947) (xy 126.536704 -220.319854) (xy 126.536099 -220.347508) (xy 126.526781 -220.402028)
			(xy 126.518162 -220.428312) (xy 126.510542 -220.45041) (xy 126.715774 -220.805756) (xy 126.738634 -220.810074)
			(xy 126.763548 -220.81528) (xy 126.811498 -220.832341) (xy 126.856253 -220.856576) (xy 126.896745 -220.887409)
			(xy 126.932012 -220.924105) (xy 126.961212 -220.96579) (xy 126.983651 -221.011471) (xy 126.998794 -221.060061)
			(xy 127.003048 -221.085156) (xy 127.009652 -221.12859) (xy 127.10414 -221.12859) (xy 127.10414 -220.853762)
			(xy 127.098298 -220.84284) (xy 127.074644 -220.796838) (xy 127.034958 -220.701306) (xy 127.01905 -220.652086)
			(xy 126.994232 -220.642) (xy 126.947698 -220.615462) (xy 126.905662 -220.582256) (xy 126.869072 -220.54313)
			(xy 126.838752 -220.498967) (xy 126.815388 -220.450761) (xy 126.799504 -220.399601) (xy 126.79146 -220.346638)
			(xy 126.790958 -220.319854) (xy 126.791431 -220.29391) (xy 126.798969 -220.242574) (xy 126.813879 -220.192875)
			(xy 126.835845 -220.145867) (xy 126.864402 -220.102545) (xy 126.898944 -220.063827) (xy 126.938741 -220.030533)
			(xy 126.98295 -220.003368) (xy 127.006604 -219.992702) (xy 127.01776 -219.954065) (xy 127.045304 -219.878502)
			(xy 127.078658 -219.805317) (xy 127.09779 -219.769944) (xy 127.10414 -219.758514) (xy 127.10414 -219.610432)
			(xy 127.019304 -219.610432) (xy 127.00635 -219.641674) (xy 126.995904 -219.665783) (xy 126.968962 -219.710889)
			(xy 126.935686 -219.751549) (xy 126.896799 -219.786881) (xy 126.853145 -219.816118) (xy 126.805669 -219.838626)
			(xy 126.755403 -219.853916) (xy 126.703436 -219.861657) (xy 126.677166 -219.862146) (xy 126.650516 -219.861646)
			(xy 126.59781 -219.853697) (xy 126.546879 -219.837982) (xy 126.498858 -219.814853) (xy 126.45482 -219.784825)
			(xy 126.415749 -219.748569) (xy 126.382518 -219.706895) (xy 126.355869 -219.660734) (xy 126.336397 -219.611117)
			(xy 126.324537 -219.559152) (xy 126.320554 -219.506) (xy 126.324537 -219.452848) (xy 126.336397 -219.400883)
			(xy 126.355869 -219.351266) (xy 126.382518 -219.305105) (xy 126.415749 -219.263431) (xy 126.45482 -219.227175)
			(xy 126.498858 -219.197147) (xy 126.546879 -219.174018) (xy 126.59781 -219.158303) (xy 126.650516 -219.150354)
			(xy 126.677166 -219.14993) (xy 126.705351 -219.150463) (xy 126.761018 -219.159334) (xy 126.814594 -219.176861)
			(xy 126.864742 -219.202605) (xy 126.910209 -219.235926) (xy 126.930404 -219.255594) (xy 126.941351 -219.265887)
			(xy 126.967774 -219.280161) (xy 126.997206 -219.286137) (xy 127.027104 -219.283298) (xy 127.054885 -219.271889)
			(xy 127.078149 -219.252896) (xy 127.094887 -219.227961) (xy 127.103652 -219.199236) (xy 127.10414 -219.18422)
			(xy 127.10414 -219.021406) (xy 127.065786 -219.011754) (xy 127.041034 -219.004974) (xy 126.993844 -218.984807)
			(xy 126.950349 -218.95757) (xy 126.9116 -218.923922) (xy 126.878534 -218.884677) (xy 126.851948 -218.840781)
			(xy 126.832485 -218.793296) (xy 126.820616 -218.743369) (xy 126.816627 -218.692205) (xy 126.820614 -218.641042)
			(xy 126.832482 -218.591114) (xy 126.851943 -218.543628) (xy 126.878527 -218.499732) (xy 126.911593 -218.460485)
			(xy 126.95034 -218.426836) (xy 126.993834 -218.399598) (xy 127.041023 -218.379429) (xy 127.065786 -218.37269)
			(xy 127.10414 -218.363038) (xy 127.10414 -218.161362) (xy 127.103688 -218.147641) (xy 127.096377 -218.12119)
			(xy 127.082293 -218.097637) (xy 127.06245 -218.07868) (xy 127.038279 -218.065685) (xy 127.011522 -218.059589)
			(xy 126.984108 -218.060832) (xy 126.958012 -218.069322) (xy 126.935115 -218.08445) (xy 126.925832 -218.09456)
			(xy 126.906901 -218.115465) (xy 126.863201 -218.151111) (xy 126.814068 -218.178793) (xy 126.760938 -218.197702)
			(xy 126.705363 -218.207285) (xy 126.677166 -218.207844) (xy 126.65128 -218.207334) (xy 126.600147 -218.19923)
			(xy 126.55091 -218.183228) (xy 126.504783 -218.159721) (xy 126.4629 -218.129288) (xy 126.426294 -218.092679)
			(xy 126.395864 -218.050793) (xy 126.372361 -218.004664) (xy 126.356363 -217.955426) (xy 126.348264 -217.904292)
			(xy 126.347728 -217.878406) (xy 126.348257 -217.850698) (xy 126.357455 -217.796052) (xy 126.366016 -217.769694)
			(xy 126.37389 -217.747596) (xy 126.168912 -217.392504) (xy 126.146052 -217.388186) (xy 126.121196 -217.383054)
			(xy 126.073335 -217.36617) (xy 126.028629 -217.342145) (xy 125.988137 -217.311547) (xy 125.952818 -217.275102)
			(xy 125.923505 -217.23367) (xy 125.900895 -217.188233) (xy 125.88552 -217.139865) (xy 125.877746 -217.089712)
			(xy 125.87732 -217.064336) (xy 125.877828 -217.038429) (xy 125.885934 -216.987252) (xy 125.901946 -216.937973)
			(xy 125.925469 -216.891806) (xy 125.955925 -216.849887) (xy 125.992563 -216.813249) (xy 126.034482 -216.782793)
			(xy 126.080649 -216.75927) (xy 126.129928 -216.743258) (xy 126.181105 -216.735152) (xy 126.232919 -216.735152)
			(xy 126.284096 -216.743258) (xy 126.333375 -216.75927) (xy 126.379542 -216.782793) (xy 126.421461 -216.813249)
			(xy 126.458099 -216.849887) (xy 126.488555 -216.891806) (xy 126.512078 -216.937973) (xy 126.52809 -216.987252)
			(xy 126.536196 -217.038429) (xy 126.536704 -217.064336) (xy 126.536101 -217.091991) (xy 126.526785 -217.146511)
			(xy 126.518162 -217.172794) (xy 126.510542 -217.194892) (xy 126.715774 -217.550238) (xy 126.738634 -217.554556)
			(xy 126.763548 -217.559762) (xy 126.8115 -217.576822) (xy 126.856256 -217.601057) (xy 126.89675 -217.631889)
			(xy 126.932018 -217.668584) (xy 126.961221 -217.710269) (xy 126.983662 -217.755951) (xy 126.998808 -217.804541)
			(xy 127.003048 -217.829638) (xy 127.009652 -217.873072) (xy 127.10414 -217.873072) (xy 127.10414 -217.598244)
			(xy 127.098298 -217.587322) (xy 127.078246 -217.548549) (xy 127.043534 -217.468447) (xy 127.028956 -217.427302)
			(xy 127.002558 -217.418172) (xy 126.952554 -217.393283) (xy 126.906712 -217.361371) (xy 126.866011 -217.323118)
			(xy 126.83132 -217.279341) (xy 126.803381 -217.230975) (xy 126.78279 -217.179053) (xy 126.769987 -217.124685)
			(xy 126.765245 -217.069031) (xy 126.768666 -217.01328) (xy 126.77394 -216.98585) (xy 126.745815 -216.952967)
			(xy 126.694156 -216.883542) (xy 126.648029 -216.810325) (xy 126.60771 -216.733756) (xy 126.573442 -216.654294)
			(xy 126.559056 -216.613486) (xy 126.532416 -216.604261) (xy 126.48198 -216.579077) (xy 126.435798 -216.546745)
			(xy 126.394878 -216.507969) (xy 126.360109 -216.463594) (xy 126.332249 -216.414585) (xy 126.311904 -216.36201)
			(xy 126.299518 -216.307013) (xy 126.29536 -216.250792) (xy 126.29952 -216.194571) (xy 126.311909 -216.139575)
			(xy 126.332256 -216.087001) (xy 126.360118 -216.037993) (xy 126.394889 -215.993619) (xy 126.435811 -215.954845)
			(xy 126.481994 -215.922515) (xy 126.532431 -215.897333) (xy 126.559056 -215.888062) (xy 126.575726 -215.841058)
			(xy 126.616301 -215.749945) (xy 126.664826 -215.662806) (xy 126.720915 -215.580332) (xy 126.784124 -215.503179)
			(xy 126.818644 -215.467184) (xy 126.81712 -215.436704) (xy 126.817628 -215.410475) (xy 126.825942 -215.35868)
			(xy 126.842361 -215.308857) (xy 126.866469 -215.262267) (xy 126.897657 -215.220086) (xy 126.935136 -215.183382)
			(xy 126.977959 -215.153083) (xy 127.00127 -215.141048) (xy 127.012505 -215.098088) (xy 127.041317 -215.014088)
			(xy 127.077154 -214.932836) (xy 127.098044 -214.893652) (xy 127.10414 -214.882476) (xy 127.10414 -214.825072)
			(xy 127.011176 -214.732108) (xy 126.970028 -214.773256) (xy 126.966472 -214.779606) (xy 126.954002 -214.801625)
			(xy 126.923358 -214.841893) (xy 126.886922 -214.877006) (xy 126.845548 -214.906139) (xy 126.800208 -214.928608)
			(xy 126.751967 -214.943885) (xy 126.701959 -214.951611) (xy 126.676658 -214.952072) (xy 126.650772 -214.951561)
			(xy 126.599638 -214.943457) (xy 126.5504 -214.927454) (xy 126.504272 -214.903947) (xy 126.462388 -214.873515)
			(xy 126.42578 -214.836906) (xy 126.395348 -214.795021) (xy 126.371843 -214.748892) (xy 126.355841 -214.699655)
			(xy 126.347738 -214.64852) (xy 126.34722 -214.622634) (xy 126.347581 -214.599657) (xy 126.353893 -214.554141)
			(xy 126.366469 -214.509943) (xy 126.375414 -214.488776) (xy 126.38532 -214.466424) (xy 126.28626 -214.27821)
			(xy 126.09322 -214.27821) (xy 126.079433 -214.278677) (xy 126.052867 -214.286073) (xy 126.029247 -214.300304)
			(xy 126.010293 -214.320333) (xy 125.997387 -214.344702) (xy 125.991467 -214.371634) (xy 125.992966 -214.399169)
			(xy 126.001773 -214.4253) (xy 126.009146 -214.43696) (xy 126.022641 -214.457605) (xy 126.044007 -214.502058)
			(xy 126.058509 -214.549198) (xy 126.065824 -214.597973) (xy 126.066296 -214.622634) (xy 126.06583 -214.647968)
			(xy 126.058072 -214.69804) (xy 126.042746 -214.746335) (xy 126.020211 -214.791716) (xy 125.990999 -214.833116)
			(xy 125.955796 -214.869559) (xy 125.915432 -214.900187) (xy 125.870858 -214.924279) (xy 125.823122 -214.941268)
			(xy 125.798326 -214.946484) (xy 125.775466 -214.950802) (xy 125.570488 -215.305894) (xy 125.578362 -215.327738)
			(xy 125.587008 -215.354146) (xy 125.59633 -215.408922) (xy 125.596904 -215.436704) (xy 125.596396 -215.462611)
			(xy 125.58829 -215.513788) (xy 125.572278 -215.563067) (xy 125.548755 -215.609234) (xy 125.518299 -215.651153)
			(xy 125.481661 -215.687791) (xy 125.439742 -215.718247) (xy 125.393575 -215.74177) (xy 125.344296 -215.757782)
			(xy 125.293119 -215.765888) (xy 125.241305 -215.765888) (xy 125.190128 -215.757782) (xy 125.140849 -215.74177)
			(xy 125.094682 -215.718247) (xy 125.052763 -215.687791) (xy 125.016125 -215.651153) (xy 124.985669 -215.609234)
			(xy 124.962146 -215.563067) (xy 124.946134 -215.513788) (xy 124.938028 -215.462611) (xy 124.93752 -215.436704)
			(xy 124.937985 -215.411357) (xy 124.945747 -215.36126) (xy 124.961088 -215.312942) (xy 124.983648 -215.267544)
			(xy 125.012892 -215.226135) (xy 125.048133 -215.189693) (xy 125.088538 -215.159077) (xy 125.133155 -215.135008)
			(xy 125.180931 -215.118056) (xy 125.205744 -215.112854) (xy 125.228604 -215.108536) (xy 125.433582 -214.753444)
			(xy 125.425708 -214.7316) (xy 125.417131 -214.705181) (xy 125.407941 -214.650406) (xy 125.40742 -214.622634)
			(xy 125.408066 -214.591804) (xy 125.419448 -214.531204) (xy 125.430026 -214.502238) (xy 125.434797 -214.488899)
			(xy 125.43757 -214.460719) (xy 125.432501 -214.43286) (xy 125.419979 -214.407462) (xy 125.400965 -214.386478)
			(xy 125.376922 -214.371519) (xy 125.349696 -214.363736) (xy 125.335538 -214.3633) (xy 125.198378 -214.3633)
			(xy 125.184223 -214.363766) (xy 125.157002 -214.371545) (xy 125.132962 -214.386498) (xy 125.113952 -214.407476)
			(xy 125.101431 -214.432868) (xy 125.096363 -214.460721) (xy 125.099137 -214.488896) (xy 125.10389 -214.502238)
			(xy 125.114467 -214.531205) (xy 125.125853 -214.591804) (xy 125.126496 -214.622634) (xy 125.125988 -214.648521)
			(xy 125.117889 -214.699659) (xy 125.10189 -214.748899) (xy 125.078384 -214.795031) (xy 125.047952 -214.836918)
			(xy 125.011342 -214.873528) (xy 124.969455 -214.90396) (xy 124.923323 -214.927466) (xy 124.874083 -214.943465)
			(xy 124.822945 -214.951564) (xy 124.771171 -214.951564) (xy 124.720033 -214.943465) (xy 124.670793 -214.927466)
			(xy 124.624661 -214.90396) (xy 124.582774 -214.873528) (xy 124.546164 -214.836918) (xy 124.515732 -214.795031)
			(xy 124.492226 -214.748899) (xy 124.476227 -214.699659) (xy 124.468128 -214.648521) (xy 124.46762 -214.622634)
			(xy 124.468101 -214.597068) (xy 124.475999 -214.54655) (xy 124.491612 -214.49786) (xy 124.502672 -214.474806)
			(xy 124.514102 -214.451438) (xy 124.468382 -214.3633) (xy 124.258578 -214.3633) (xy 124.244423 -214.363766)
			(xy 124.217202 -214.371545) (xy 124.193162 -214.386498) (xy 124.174152 -214.407476) (xy 124.161631 -214.432868)
			(xy 124.156563 -214.460721) (xy 124.159337 -214.488896) (xy 124.16409 -214.502238) (xy 124.174667 -214.531205)
			(xy 124.186053 -214.591804) (xy 124.186696 -214.622634) (xy 124.18623 -214.647968) (xy 124.178472 -214.69804)
			(xy 124.163146 -214.746335) (xy 124.140611 -214.791716) (xy 124.111399 -214.833116) (xy 124.076196 -214.869559)
			(xy 124.035832 -214.900187) (xy 123.991258 -214.924279) (xy 123.943522 -214.941268) (xy 123.918726 -214.946484)
			(xy 123.895866 -214.950802) (xy 123.690888 -215.305894) (xy 123.698762 -215.327738) (xy 123.707408 -215.354146)
			(xy 123.71673 -215.408922) (xy 123.717304 -215.436704) (xy 123.716796 -215.462611) (xy 123.70869 -215.513788)
			(xy 123.692678 -215.563067) (xy 123.669155 -215.609234) (xy 123.638699 -215.651153) (xy 123.602061 -215.687791)
			(xy 123.560142 -215.718247) (xy 123.513975 -215.74177) (xy 123.464696 -215.757782) (xy 123.413519 -215.765888)
			(xy 123.361705 -215.765888) (xy 123.310528 -215.757782) (xy 123.261249 -215.74177) (xy 123.215082 -215.718247)
			(xy 123.173163 -215.687791) (xy 123.136525 -215.651153) (xy 123.106069 -215.609234) (xy 123.082546 -215.563067)
			(xy 123.066534 -215.513788) (xy 123.058428 -215.462611) (xy 123.05792 -215.436704) (xy 123.058385 -215.411357)
			(xy 123.066147 -215.36126) (xy 123.081488 -215.312942) (xy 123.104048 -215.267544) (xy 123.133292 -215.226135)
			(xy 123.168533 -215.189693) (xy 123.208938 -215.159077) (xy 123.253555 -215.135008) (xy 123.301331 -215.118056)
			(xy 123.326144 -215.112854) (xy 123.349004 -215.108536) (xy 123.553982 -214.753444) (xy 123.546108 -214.7316)
			(xy 123.537531 -214.705181) (xy 123.528341 -214.650406) (xy 123.52782 -214.622634) (xy 123.528466 -214.591804)
			(xy 123.539848 -214.531204) (xy 123.550426 -214.502238) (xy 123.555197 -214.488899) (xy 123.55797 -214.460719)
			(xy 123.552901 -214.43286) (xy 123.540379 -214.407462) (xy 123.521365 -214.386478) (xy 123.497322 -214.371519)
			(xy 123.470096 -214.363736) (xy 123.455938 -214.3633) (xy 123.318778 -214.3633) (xy 123.304623 -214.363766)
			(xy 123.277402 -214.371545) (xy 123.253362 -214.386498) (xy 123.234352 -214.407476) (xy 123.221831 -214.432868)
			(xy 123.216763 -214.460721) (xy 123.219537 -214.488896) (xy 123.22429 -214.502238) (xy 123.234867 -214.531205)
			(xy 123.246253 -214.591804) (xy 123.246896 -214.622634) (xy 123.246388 -214.648521) (xy 123.238289 -214.699659)
			(xy 123.22229 -214.748899) (xy 123.198784 -214.795031) (xy 123.168352 -214.836918) (xy 123.131742 -214.873528)
			(xy 123.089855 -214.90396) (xy 123.043723 -214.927466) (xy 122.994483 -214.943465) (xy 122.943345 -214.951564)
			(xy 122.891571 -214.951564) (xy 122.840433 -214.943465) (xy 122.791193 -214.927466) (xy 122.745061 -214.90396)
			(xy 122.703174 -214.873528) (xy 122.666564 -214.836918) (xy 122.636132 -214.795031) (xy 122.612626 -214.748899)
			(xy 122.596627 -214.699659) (xy 122.588528 -214.648521) (xy 122.58802 -214.622634) (xy 122.588381 -214.599657)
			(xy 122.594693 -214.554141) (xy 122.607269 -214.509943) (xy 122.616214 -214.488776) (xy 122.62612 -214.466424)
			(xy 122.572018 -214.3633) (xy 122.378978 -214.3633) (xy 122.364823 -214.363766) (xy 122.337602 -214.371545)
			(xy 122.313562 -214.386498) (xy 122.294552 -214.407476) (xy 122.282031 -214.432868) (xy 122.276963 -214.460721)
			(xy 122.279737 -214.488896) (xy 122.28449 -214.502238) (xy 122.295067 -214.531205) (xy 122.306453 -214.591804)
			(xy 122.307096 -214.622634) (xy 122.30663 -214.647968) (xy 122.298872 -214.69804) (xy 122.283546 -214.746335)
			(xy 122.261011 -214.791716) (xy 122.231799 -214.833116) (xy 122.196596 -214.869559) (xy 122.156232 -214.900187)
			(xy 122.111658 -214.924279) (xy 122.063922 -214.941268) (xy 122.039126 -214.946484) (xy 122.016266 -214.950802)
			(xy 121.811288 -215.305894) (xy 121.819162 -215.327738) (xy 121.827808 -215.354146) (xy 121.83713 -215.408922)
			(xy 121.837704 -215.436704) (xy 121.837196 -215.462611) (xy 121.82909 -215.513788) (xy 121.813078 -215.563067)
			(xy 121.789555 -215.609234) (xy 121.759099 -215.651153) (xy 121.722461 -215.687791) (xy 121.680542 -215.718247)
			(xy 121.634375 -215.74177) (xy 121.585096 -215.757782) (xy 121.533919 -215.765888) (xy 121.482105 -215.765888)
			(xy 121.430928 -215.757782) (xy 121.381649 -215.74177) (xy 121.335482 -215.718247) (xy 121.293563 -215.687791)
			(xy 121.256925 -215.651153) (xy 121.226469 -215.609234) (xy 121.202946 -215.563067) (xy 121.186934 -215.513788)
			(xy 121.178828 -215.462611) (xy 121.17832 -215.436704) (xy 121.178785 -215.411357) (xy 121.186547 -215.36126)
			(xy 121.201888 -215.312942) (xy 121.224448 -215.267544) (xy 121.253692 -215.226135) (xy 121.288933 -215.189693)
			(xy 121.329338 -215.159077) (xy 121.373955 -215.135008) (xy 121.421731 -215.118056) (xy 121.446544 -215.112854)
			(xy 121.469404 -215.108536) (xy 121.674382 -214.753444) (xy 121.666508 -214.7316) (xy 121.657931 -214.705181)
			(xy 121.648741 -214.650406) (xy 121.64822 -214.622634) (xy 121.648866 -214.591804) (xy 121.660248 -214.531204)
			(xy 121.670826 -214.502238) (xy 121.675597 -214.488899) (xy 121.67837 -214.460719) (xy 121.673301 -214.43286)
			(xy 121.660779 -214.407462) (xy 121.641765 -214.386478) (xy 121.617722 -214.371519) (xy 121.590496 -214.363736)
			(xy 121.576338 -214.3633) (xy 121.460006 -214.3633) (xy 121.013728 -213.917276) (xy 121.013728 -213.504272)
			(xy 121.299986 -213.218268) (xy 121.299986 -209.617818) (xy 121.110248 -209.42808) (xy 118.545356 -209.42808)
			(xy 118.47068 -209.502756) (xy 118.47068 -212.900768) (xy 118.017036 -213.354412) (xy 118.006538 -213.365741)
			(xy 117.992301 -213.393135) (xy 117.986879 -213.423528) (xy 117.990767 -213.454155) (xy 118.003609 -213.482229)
			(xy 118.01348 -213.494112) (xy 118.030653 -213.513836) (xy 118.059629 -213.557373) (xy 118.081927 -213.604678)
			(xy 118.097068 -213.654736) (xy 118.104727 -213.706469) (xy 118.105174 -213.732618) (xy 118.359428 -213.732618)
			(xy 118.359936 -213.706731) (xy 118.368035 -213.655593) (xy 118.384034 -213.606353) (xy 118.40754 -213.560221)
			(xy 118.437972 -213.518334) (xy 118.474582 -213.481724) (xy 118.516469 -213.451292) (xy 118.562601 -213.427786)
			(xy 118.611841 -213.411787) (xy 118.662979 -213.403688) (xy 118.714753 -213.403688) (xy 118.765891 -213.411787)
			(xy 118.815131 -213.427786) (xy 118.861263 -213.451292) (xy 118.90315 -213.481724) (xy 118.93976 -213.518334)
			(xy 118.970192 -213.560221) (xy 118.993698 -213.606353) (xy 119.009697 -213.655593) (xy 119.017796 -213.706731)
			(xy 119.018304 -213.732618) (xy 119.017953 -213.755595) (xy 119.017443 -213.759267) (xy 119.273056 -213.759267)
			(xy 119.273056 -213.705969) (xy 119.280999 -213.653265) (xy 119.296709 -213.602335) (xy 119.319835 -213.554314)
			(xy 119.349859 -213.510277) (xy 119.386111 -213.471206) (xy 119.427782 -213.437975) (xy 119.47394 -213.411326)
			(xy 119.523554 -213.391854) (xy 119.575516 -213.379994) (xy 119.628666 -213.376011) (xy 119.681816 -213.379994)
			(xy 119.733778 -213.391854) (xy 119.783392 -213.411326) (xy 119.82955 -213.437975) (xy 119.871221 -213.471206)
			(xy 119.907473 -213.510277) (xy 119.937497 -213.554314) (xy 119.960623 -213.602335) (xy 119.976333 -213.653265)
			(xy 119.984276 -213.705969) (xy 119.984774 -213.732618) (xy 120.239028 -213.732618) (xy 120.239536 -213.706731)
			(xy 120.247635 -213.655593) (xy 120.263634 -213.606353) (xy 120.28714 -213.560221) (xy 120.317572 -213.518334)
			(xy 120.354182 -213.481724) (xy 120.396069 -213.451292) (xy 120.442201 -213.427786) (xy 120.491441 -213.411787)
			(xy 120.542579 -213.403688) (xy 120.594353 -213.403688) (xy 120.645491 -213.411787) (xy 120.694731 -213.427786)
			(xy 120.740863 -213.451292) (xy 120.78275 -213.481724) (xy 120.81936 -213.518334) (xy 120.849792 -213.560221)
			(xy 120.873298 -213.606353) (xy 120.889297 -213.655593) (xy 120.897396 -213.706731) (xy 120.897904 -213.732618)
			(xy 120.897553 -213.755595) (xy 120.891232 -213.80111) (xy 120.878648 -213.845306) (xy 120.86971 -213.866476)
			(xy 120.859804 -213.888828) (xy 121.073418 -214.293958) (xy 121.097548 -214.29853) (xy 121.122467 -214.303641)
			(xy 121.170477 -214.320441) (xy 121.215336 -214.344419) (xy 121.255976 -214.375006) (xy 121.291434 -214.411476)
			(xy 121.320866 -214.452961) (xy 121.343573 -214.498476) (xy 121.359015 -214.54694) (xy 121.366827 -214.597201)
			(xy 121.367296 -214.622634) (xy 121.366788 -214.648521) (xy 121.358689 -214.699659) (xy 121.34269 -214.748899)
			(xy 121.319184 -214.795031) (xy 121.288752 -214.836918) (xy 121.252142 -214.873528) (xy 121.210255 -214.90396)
			(xy 121.164123 -214.927466) (xy 121.114883 -214.943465) (xy 121.063745 -214.951564) (xy 121.011971 -214.951564)
			(xy 120.960833 -214.943465) (xy 120.911593 -214.927466) (xy 120.865461 -214.90396) (xy 120.823574 -214.873528)
			(xy 120.786964 -214.836918) (xy 120.756532 -214.795031) (xy 120.733026 -214.748899) (xy 120.717027 -214.699659)
			(xy 120.708928 -214.648521) (xy 120.70842 -214.622634) (xy 120.708787 -214.599658) (xy 120.7151 -214.554143)
			(xy 120.727679 -214.509947) (xy 120.736614 -214.488776) (xy 120.74652 -214.466424) (xy 120.532906 -214.061294)
			(xy 120.508776 -214.056722) (xy 120.48385 -214.051639) (xy 120.435836 -214.034839) (xy 120.390975 -214.010859)
			(xy 120.350332 -213.980269) (xy 120.314874 -213.943796) (xy 120.285443 -213.902307) (xy 120.262738 -213.856787)
			(xy 120.2473 -213.808318) (xy 120.239494 -213.758052) (xy 120.239028 -213.732618) (xy 119.984774 -213.732618)
			(xy 119.984276 -213.759267) (xy 119.976333 -213.811971) (xy 119.960623 -213.862901) (xy 119.937497 -213.910922)
			(xy 119.907473 -213.954959) (xy 119.871221 -213.99403) (xy 119.82955 -214.027261) (xy 119.783392 -214.05391)
			(xy 119.733778 -214.073382) (xy 119.681816 -214.085242) (xy 119.628666 -214.089226) (xy 119.575516 -214.085242)
			(xy 119.523554 -214.073382) (xy 119.47394 -214.05391) (xy 119.427782 -214.027261) (xy 119.386111 -213.99403)
			(xy 119.349859 -213.954959) (xy 119.319835 -213.910922) (xy 119.296709 -213.862901) (xy 119.280999 -213.811971)
			(xy 119.273056 -213.759267) (xy 119.017443 -213.759267) (xy 119.011632 -213.80111) (xy 118.999048 -213.845306)
			(xy 118.99011 -213.866476) (xy 118.980204 -213.888828) (xy 119.193818 -214.293958) (xy 119.217948 -214.29853)
			(xy 119.242867 -214.303641) (xy 119.290877 -214.320441) (xy 119.335736 -214.344419) (xy 119.376376 -214.375006)
			(xy 119.411834 -214.411476) (xy 119.441266 -214.452961) (xy 119.463973 -214.498476) (xy 119.479415 -214.54694)
			(xy 119.487227 -214.597201) (xy 119.487696 -214.622634) (xy 119.487188 -214.648521) (xy 119.479089 -214.699659)
			(xy 119.46309 -214.748899) (xy 119.439584 -214.795031) (xy 119.409152 -214.836918) (xy 119.372542 -214.873528)
			(xy 119.330655 -214.90396) (xy 119.284523 -214.927466) (xy 119.235283 -214.943465) (xy 119.184145 -214.951564)
			(xy 119.132371 -214.951564) (xy 119.081233 -214.943465) (xy 119.031993 -214.927466) (xy 118.985861 -214.90396)
			(xy 118.943974 -214.873528) (xy 118.907364 -214.836918) (xy 118.876932 -214.795031) (xy 118.853426 -214.748899)
			(xy 118.837427 -214.699659) (xy 118.829328 -214.648521) (xy 118.82882 -214.622634) (xy 118.829187 -214.599658)
			(xy 118.8355 -214.554143) (xy 118.848079 -214.509947) (xy 118.857014 -214.488776) (xy 118.86692 -214.466424)
			(xy 118.653306 -214.061294) (xy 118.629176 -214.056722) (xy 118.60425 -214.051639) (xy 118.556236 -214.034839)
			(xy 118.511375 -214.010859) (xy 118.470732 -213.980269) (xy 118.435274 -213.943796) (xy 118.405843 -213.902307)
			(xy 118.383138 -213.856787) (xy 118.3677 -213.808318) (xy 118.359894 -213.758052) (xy 118.359428 -213.732618)
			(xy 118.105174 -213.732618) (xy 118.104652 -213.760601) (xy 118.095894 -213.815879) (xy 118.078596 -213.869106)
			(xy 118.053184 -213.918971) (xy 118.020285 -213.964247) (xy 117.980707 -214.003819) (xy 117.935426 -214.036712)
			(xy 117.885557 -214.062116) (xy 117.832328 -214.079406) (xy 117.77705 -214.088156) (xy 117.749066 -214.088726)
			(xy 117.722916 -214.088269) (xy 117.671179 -214.080626) (xy 117.621117 -214.065493) (xy 117.573809 -214.043198)
			(xy 117.530272 -214.01422) (xy 117.51056 -213.997032) (xy 117.498731 -213.987074) (xy 117.470649 -213.974167)
			(xy 117.439989 -213.970267) (xy 117.40957 -213.975731) (xy 117.382185 -213.990058) (xy 117.37086 -214.000588)
			(xy 117.23243 -214.139018) (xy 117.314218 -214.293958) (xy 117.338348 -214.29853) (xy 117.363266 -214.303623)
			(xy 117.41126 -214.320451) (xy 117.456101 -214.344447) (xy 117.496727 -214.375044) (xy 117.532174 -214.411514)
			(xy 117.561601 -214.452994) (xy 117.584312 -214.4985) (xy 117.599767 -214.546954) (xy 117.6076 -214.597205)
			(xy 117.608096 -214.622634) (xy 117.607612 -214.648521) (xy 117.599508 -214.699655) (xy 117.583504 -214.748893)
			(xy 117.559994 -214.79502) (xy 117.529558 -214.836902) (xy 117.492944 -214.873507) (xy 117.451056 -214.903934)
			(xy 117.404923 -214.927433) (xy 117.355681 -214.943425) (xy 117.304545 -214.951518) (xy 117.278658 -214.952072)
			(xy 117.251712 -214.951532) (xy 117.198538 -214.94276) (xy 117.147499 -214.925456) (xy 117.099954 -214.90008)
			(xy 117.057169 -214.867309) (xy 117.020285 -214.828016) (xy 116.990282 -214.783247) (xy 116.967961 -214.734194)
			(xy 116.953916 -214.682163) (xy 116.950744 -214.6554) (xy 116.948816 -214.641168) (xy 116.938104 -214.614534)
			(xy 116.920406 -214.591931) (xy 116.89712 -214.575143) (xy 116.870083 -214.565494) (xy 116.841429 -214.563748)
			(xy 116.81342 -214.57004) (xy 116.788266 -214.583876) (xy 116.77777 -214.593678) (xy 116.655088 -214.71636)
			(xy 116.651278 -214.72779) (xy 116.641762 -214.754289) (xy 116.615004 -214.803825) (xy 116.58021 -214.848086)
			(xy 116.538393 -214.885784) (xy 116.51488 -214.901272) (xy 116.51488 -215.65108) (xy 116.640102 -215.776048)
			(xy 117.389148 -215.776048) (xy 117.402845 -215.775609) (xy 117.429255 -215.768334) (xy 117.452777 -215.754295)
			(xy 117.471716 -215.734503) (xy 117.484706 -215.710385) (xy 117.490812 -215.683681) (xy 117.489592 -215.656315)
			(xy 117.481135 -215.630259) (xy 117.473984 -215.618568) (xy 117.461024 -215.598248) (xy 117.440539 -215.554622)
			(xy 117.426625 -215.508479) (xy 117.419578 -215.460801) (xy 117.41912 -215.436704) (xy 117.419585 -215.411357)
			(xy 117.427347 -215.36126) (xy 117.442688 -215.312942) (xy 117.465248 -215.267544) (xy 117.494492 -215.226135)
			(xy 117.529733 -215.189693) (xy 117.570138 -215.159077) (xy 117.614755 -215.135008) (xy 117.662531 -215.118056)
			(xy 117.687344 -215.112854) (xy 117.710204 -215.108536) (xy 117.915182 -214.753444) (xy 117.907308 -214.7316)
			(xy 117.898731 -214.705181) (xy 117.889541 -214.650406) (xy 117.88902 -214.622634) (xy 117.889528 -214.596747)
			(xy 117.897627 -214.545609) (xy 117.913626 -214.496369) (xy 117.937132 -214.450237) (xy 117.967564 -214.40835)
			(xy 118.004174 -214.37174) (xy 118.046061 -214.341308) (xy 118.092193 -214.317802) (xy 118.141433 -214.301803)
			(xy 118.192571 -214.293704) (xy 118.244345 -214.293704) (xy 118.295483 -214.301803) (xy 118.344723 -214.317802)
			(xy 118.390855 -214.341308) (xy 118.432742 -214.37174) (xy 118.469352 -214.40835) (xy 118.499784 -214.450237)
			(xy 118.52329 -214.496369) (xy 118.539289 -214.545609) (xy 118.547388 -214.596747) (xy 118.547896 -214.622634)
			(xy 118.54743 -214.647968) (xy 118.539672 -214.69804) (xy 118.524346 -214.746335) (xy 118.501811 -214.791716)
			(xy 118.472599 -214.833116) (xy 118.437396 -214.869559) (xy 118.397032 -214.900187) (xy 118.352458 -214.924279)
			(xy 118.304722 -214.941268) (xy 118.279926 -214.946484) (xy 118.257066 -214.950802) (xy 118.052088 -215.305894)
			(xy 118.059962 -215.327738) (xy 118.068608 -215.354146) (xy 118.07793 -215.408922) (xy 118.078504 -215.436704)
			(xy 119.29872 -215.436704) (xy 119.299229 -215.41136) (xy 119.307 -215.36127) (xy 119.322346 -215.31296)
			(xy 119.344903 -215.267567) (xy 119.374142 -215.226161) (xy 119.409373 -215.189717) (xy 119.449765 -215.159094)
			(xy 119.494369 -215.135013) (xy 119.542132 -215.118041) (xy 119.566944 -215.112854) (xy 119.589804 -215.108536)
			(xy 119.794782 -214.753444) (xy 119.786908 -214.7316) (xy 119.778329 -214.705181) (xy 119.769132 -214.650406)
			(xy 119.76862 -214.622634) (xy 119.769128 -214.596747) (xy 119.777227 -214.545609) (xy 119.793226 -214.496369)
			(xy 119.816732 -214.450237) (xy 119.847164 -214.40835) (xy 119.883774 -214.37174) (xy 119.925661 -214.341308)
			(xy 119.971793 -214.317802) (xy 120.021033 -214.301803) (xy 120.072171 -214.293704) (xy 120.123945 -214.293704)
			(xy 120.175083 -214.301803) (xy 120.224323 -214.317802) (xy 120.270455 -214.341308) (xy 120.312342 -214.37174)
			(xy 120.348952 -214.40835) (xy 120.379384 -214.450237) (xy 120.40289 -214.496369) (xy 120.418889 -214.545609)
			(xy 120.426988 -214.596747) (xy 120.427496 -214.622634) (xy 120.427047 -214.64797) (xy 120.41929 -214.698044)
			(xy 120.403963 -214.746341) (xy 120.381427 -214.791726) (xy 120.352212 -214.833128) (xy 120.317008 -214.869572)
			(xy 120.276642 -214.900202) (xy 120.232065 -214.924296) (xy 120.184327 -214.941286) (xy 120.159526 -214.946484)
			(xy 120.136666 -214.950802) (xy 119.931688 -215.305894) (xy 119.939562 -215.327738) (xy 119.94821 -215.354146)
			(xy 119.957529 -215.408922) (xy 119.958104 -215.436704) (xy 119.957596 -215.462611) (xy 119.94949 -215.513788)
			(xy 119.933478 -215.563067) (xy 119.909955 -215.609234) (xy 119.879499 -215.651153) (xy 119.842861 -215.687791)
			(xy 119.800942 -215.718247) (xy 119.754775 -215.74177) (xy 119.705496 -215.757782) (xy 119.654319 -215.765888)
			(xy 119.602505 -215.765888) (xy 119.551328 -215.757782) (xy 119.502049 -215.74177) (xy 119.455882 -215.718247)
			(xy 119.413963 -215.687791) (xy 119.377325 -215.651153) (xy 119.346869 -215.609234) (xy 119.323346 -215.563067)
			(xy 119.307334 -215.513788) (xy 119.299228 -215.462611) (xy 119.29872 -215.436704) (xy 118.078504 -215.436704)
			(xy 118.078052 -215.461535) (xy 118.070597 -215.510634) (xy 118.055855 -215.558058) (xy 118.034161 -215.602732)
			(xy 118.006007 -215.643642) (xy 117.972031 -215.679863) (xy 117.933002 -215.710573) (xy 117.911626 -215.723216)
			(xy 117.900234 -215.730188) (xy 117.881279 -215.748993) (xy 117.867844 -215.772067) (xy 117.860846 -215.797834)
			(xy 117.860763 -215.824534) (xy 117.8676 -215.850345) (xy 117.880891 -215.873502) (xy 117.890036 -215.883236)
			(xy 117.969284 -215.962484) (xy 117.990208 -215.945003) (xy 118.036079 -215.915532) (xy 118.085676 -215.892889)
			(xy 118.137991 -215.877534) (xy 118.191959 -215.869779) (xy 118.21922 -215.869266) (xy 118.246471 -215.869753)
			(xy 118.300418 -215.877512) (xy 118.352712 -215.892868) (xy 118.402288 -215.91551) (xy 118.448138 -215.944977)
			(xy 118.489328 -215.980668) (xy 118.52502 -216.021857) (xy 118.554487 -216.067707) (xy 118.577129 -216.117283)
			(xy 118.592487 -216.169576) (xy 118.600246 -216.223523) (xy 118.600728 -216.250774) (xy 118.600282 -216.277169)
			(xy 118.803156 -216.277169) (xy 118.803156 -216.223871) (xy 118.811099 -216.171167) (xy 118.826809 -216.120237)
			(xy 118.849935 -216.072216) (xy 118.879959 -216.028179) (xy 118.916211 -215.989108) (xy 118.957882 -215.955877)
			(xy 119.00404 -215.929228) (xy 119.053654 -215.909756) (xy 119.105616 -215.897896) (xy 119.158766 -215.893913)
			(xy 119.211916 -215.897896) (xy 119.263878 -215.909756) (xy 119.313492 -215.929228) (xy 119.35965 -215.955877)
			(xy 119.401321 -215.989108) (xy 119.437573 -216.028179) (xy 119.467597 -216.072216) (xy 119.490723 -216.120237)
			(xy 119.506433 -216.171167) (xy 119.514376 -216.223871) (xy 119.514874 -216.25052) (xy 119.514376 -216.277169)
			(xy 119.742956 -216.277169) (xy 119.742956 -216.223871) (xy 119.750899 -216.171167) (xy 119.766609 -216.120237)
			(xy 119.789735 -216.072216) (xy 119.819759 -216.028179) (xy 119.856011 -215.989108) (xy 119.897682 -215.955877)
			(xy 119.94384 -215.929228) (xy 119.993454 -215.909756) (xy 120.045416 -215.897896) (xy 120.098566 -215.893913)
			(xy 120.151716 -215.897896) (xy 120.203678 -215.909756) (xy 120.253292 -215.929228) (xy 120.29945 -215.955877)
			(xy 120.341121 -215.989108) (xy 120.377373 -216.028179) (xy 120.407397 -216.072216) (xy 120.430523 -216.120237)
			(xy 120.446233 -216.171167) (xy 120.454176 -216.223871) (xy 120.454674 -216.25052) (xy 120.454176 -216.277169)
			(xy 120.682756 -216.277169) (xy 120.682756 -216.223871) (xy 120.690699 -216.171167) (xy 120.706409 -216.120237)
			(xy 120.729535 -216.072216) (xy 120.759559 -216.028179) (xy 120.795811 -215.989108) (xy 120.837482 -215.955877)
			(xy 120.88364 -215.929228) (xy 120.933254 -215.909756) (xy 120.985216 -215.897896) (xy 121.038366 -215.893913)
			(xy 121.091516 -215.897896) (xy 121.143478 -215.909756) (xy 121.193092 -215.929228) (xy 121.23925 -215.955877)
			(xy 121.280921 -215.989108) (xy 121.317173 -216.028179) (xy 121.347197 -216.072216) (xy 121.370323 -216.120237)
			(xy 121.386033 -216.171167) (xy 121.393976 -216.223871) (xy 121.394474 -216.25052) (xy 121.393976 -216.277169)
			(xy 121.622556 -216.277169) (xy 121.622556 -216.223871) (xy 121.630499 -216.171167) (xy 121.646209 -216.120237)
			(xy 121.669335 -216.072216) (xy 121.699359 -216.028179) (xy 121.735611 -215.989108) (xy 121.777282 -215.955877)
			(xy 121.82344 -215.929228) (xy 121.873054 -215.909756) (xy 121.925016 -215.897896) (xy 121.978166 -215.893913)
			(xy 122.031316 -215.897896) (xy 122.083278 -215.909756) (xy 122.132892 -215.929228) (xy 122.17905 -215.955877)
			(xy 122.220721 -215.989108) (xy 122.256973 -216.028179) (xy 122.286997 -216.072216) (xy 122.310123 -216.120237)
			(xy 122.325833 -216.171167) (xy 122.333776 -216.223871) (xy 122.334274 -216.25052) (xy 122.333776 -216.277169)
			(xy 122.562356 -216.277169) (xy 122.562356 -216.223871) (xy 122.570299 -216.171167) (xy 122.586009 -216.120237)
			(xy 122.609135 -216.072216) (xy 122.639159 -216.028179) (xy 122.675411 -215.989108) (xy 122.717082 -215.955877)
			(xy 122.76324 -215.929228) (xy 122.812854 -215.909756) (xy 122.864816 -215.897896) (xy 122.917966 -215.893913)
			(xy 122.971116 -215.897896) (xy 123.023078 -215.909756) (xy 123.072692 -215.929228) (xy 123.11885 -215.955877)
			(xy 123.160521 -215.989108) (xy 123.196773 -216.028179) (xy 123.226797 -216.072216) (xy 123.249923 -216.120237)
			(xy 123.265633 -216.171167) (xy 123.273576 -216.223871) (xy 123.274074 -216.25052) (xy 123.273576 -216.277169)
			(xy 123.502156 -216.277169) (xy 123.502156 -216.223871) (xy 123.510099 -216.171167) (xy 123.525809 -216.120237)
			(xy 123.548935 -216.072216) (xy 123.578959 -216.028179) (xy 123.615211 -215.989108) (xy 123.656882 -215.955877)
			(xy 123.70304 -215.929228) (xy 123.752654 -215.909756) (xy 123.804616 -215.897896) (xy 123.857766 -215.893913)
			(xy 123.910916 -215.897896) (xy 123.962878 -215.909756) (xy 124.012492 -215.929228) (xy 124.05865 -215.955877)
			(xy 124.100321 -215.989108) (xy 124.136573 -216.028179) (xy 124.166597 -216.072216) (xy 124.189723 -216.120237)
			(xy 124.205433 -216.171167) (xy 124.213376 -216.223871) (xy 124.213874 -216.25052) (xy 124.213376 -216.277169)
			(xy 124.441956 -216.277169) (xy 124.441956 -216.223871) (xy 124.449899 -216.171167) (xy 124.465609 -216.120237)
			(xy 124.488735 -216.072216) (xy 124.518759 -216.028179) (xy 124.555011 -215.989108) (xy 124.596682 -215.955877)
			(xy 124.64284 -215.929228) (xy 124.692454 -215.909756) (xy 124.744416 -215.897896) (xy 124.797566 -215.893913)
			(xy 124.850716 -215.897896) (xy 124.902678 -215.909756) (xy 124.952292 -215.929228) (xy 124.99845 -215.955877)
			(xy 125.040121 -215.989108) (xy 125.076373 -216.028179) (xy 125.106397 -216.072216) (xy 125.129523 -216.120237)
			(xy 125.145233 -216.171167) (xy 125.153176 -216.223871) (xy 125.153674 -216.25052) (xy 125.153176 -216.277169)
			(xy 125.381756 -216.277169) (xy 125.381756 -216.223871) (xy 125.389699 -216.171167) (xy 125.405409 -216.120237)
			(xy 125.428535 -216.072216) (xy 125.458559 -216.028179) (xy 125.494811 -215.989108) (xy 125.536482 -215.955877)
			(xy 125.58264 -215.929228) (xy 125.632254 -215.909756) (xy 125.684216 -215.897896) (xy 125.737366 -215.893913)
			(xy 125.790516 -215.897896) (xy 125.842478 -215.909756) (xy 125.892092 -215.929228) (xy 125.93825 -215.955877)
			(xy 125.979921 -215.989108) (xy 126.016173 -216.028179) (xy 126.046197 -216.072216) (xy 126.069323 -216.120237)
			(xy 126.085033 -216.171167) (xy 126.092976 -216.223871) (xy 126.093474 -216.25052) (xy 126.092976 -216.277169)
			(xy 126.085033 -216.329873) (xy 126.069323 -216.380803) (xy 126.046197 -216.428824) (xy 126.016173 -216.472861)
			(xy 125.979921 -216.511932) (xy 125.93825 -216.545163) (xy 125.892092 -216.571812) (xy 125.842478 -216.591284)
			(xy 125.790516 -216.603144) (xy 125.737366 -216.607128) (xy 125.684216 -216.603144) (xy 125.632254 -216.591284)
			(xy 125.58264 -216.571812) (xy 125.536482 -216.545163) (xy 125.494811 -216.511932) (xy 125.458559 -216.472861)
			(xy 125.428535 -216.428824) (xy 125.405409 -216.380803) (xy 125.389699 -216.329873) (xy 125.381756 -216.277169)
			(xy 125.153176 -216.277169) (xy 125.145233 -216.329873) (xy 125.129523 -216.380803) (xy 125.106397 -216.428824)
			(xy 125.076373 -216.472861) (xy 125.040121 -216.511932) (xy 124.99845 -216.545163) (xy 124.952292 -216.571812)
			(xy 124.902678 -216.591284) (xy 124.850716 -216.603144) (xy 124.797566 -216.607128) (xy 124.744416 -216.603144)
			(xy 124.692454 -216.591284) (xy 124.64284 -216.571812) (xy 124.596682 -216.545163) (xy 124.555011 -216.511932)
			(xy 124.518759 -216.472861) (xy 124.488735 -216.428824) (xy 124.465609 -216.380803) (xy 124.449899 -216.329873)
			(xy 124.441956 -216.277169) (xy 124.213376 -216.277169) (xy 124.205433 -216.329873) (xy 124.189723 -216.380803)
			(xy 124.166597 -216.428824) (xy 124.136573 -216.472861) (xy 124.100321 -216.511932) (xy 124.05865 -216.545163)
			(xy 124.012492 -216.571812) (xy 123.962878 -216.591284) (xy 123.910916 -216.603144) (xy 123.857766 -216.607128)
			(xy 123.804616 -216.603144) (xy 123.752654 -216.591284) (xy 123.70304 -216.571812) (xy 123.656882 -216.545163)
			(xy 123.615211 -216.511932) (xy 123.578959 -216.472861) (xy 123.548935 -216.428824) (xy 123.525809 -216.380803)
			(xy 123.510099 -216.329873) (xy 123.502156 -216.277169) (xy 123.273576 -216.277169) (xy 123.265633 -216.329873)
			(xy 123.249923 -216.380803) (xy 123.226797 -216.428824) (xy 123.196773 -216.472861) (xy 123.160521 -216.511932)
			(xy 123.11885 -216.545163) (xy 123.072692 -216.571812) (xy 123.023078 -216.591284) (xy 122.971116 -216.603144)
			(xy 122.917966 -216.607128) (xy 122.864816 -216.603144) (xy 122.812854 -216.591284) (xy 122.76324 -216.571812)
			(xy 122.717082 -216.545163) (xy 122.675411 -216.511932) (xy 122.639159 -216.472861) (xy 122.609135 -216.428824)
			(xy 122.586009 -216.380803) (xy 122.570299 -216.329873) (xy 122.562356 -216.277169) (xy 122.333776 -216.277169)
			(xy 122.325833 -216.329873) (xy 122.310123 -216.380803) (xy 122.286997 -216.428824) (xy 122.256973 -216.472861)
			(xy 122.220721 -216.511932) (xy 122.17905 -216.545163) (xy 122.132892 -216.571812) (xy 122.083278 -216.591284)
			(xy 122.031316 -216.603144) (xy 121.978166 -216.607128) (xy 121.925016 -216.603144) (xy 121.873054 -216.591284)
			(xy 121.82344 -216.571812) (xy 121.777282 -216.545163) (xy 121.735611 -216.511932) (xy 121.699359 -216.472861)
			(xy 121.669335 -216.428824) (xy 121.646209 -216.380803) (xy 121.630499 -216.329873) (xy 121.622556 -216.277169)
			(xy 121.393976 -216.277169) (xy 121.386033 -216.329873) (xy 121.370323 -216.380803) (xy 121.347197 -216.428824)
			(xy 121.317173 -216.472861) (xy 121.280921 -216.511932) (xy 121.23925 -216.545163) (xy 121.193092 -216.571812)
			(xy 121.143478 -216.591284) (xy 121.091516 -216.603144) (xy 121.038366 -216.607128) (xy 120.985216 -216.603144)
			(xy 120.933254 -216.591284) (xy 120.88364 -216.571812) (xy 120.837482 -216.545163) (xy 120.795811 -216.511932)
			(xy 120.759559 -216.472861) (xy 120.729535 -216.428824) (xy 120.706409 -216.380803) (xy 120.690699 -216.329873)
			(xy 120.682756 -216.277169) (xy 120.454176 -216.277169) (xy 120.446233 -216.329873) (xy 120.430523 -216.380803)
			(xy 120.407397 -216.428824) (xy 120.377373 -216.472861) (xy 120.341121 -216.511932) (xy 120.29945 -216.545163)
			(xy 120.253292 -216.571812) (xy 120.203678 -216.591284) (xy 120.151716 -216.603144) (xy 120.098566 -216.607128)
			(xy 120.045416 -216.603144) (xy 119.993454 -216.591284) (xy 119.94384 -216.571812) (xy 119.897682 -216.545163)
			(xy 119.856011 -216.511932) (xy 119.819759 -216.472861) (xy 119.789735 -216.428824) (xy 119.766609 -216.380803)
			(xy 119.750899 -216.329873) (xy 119.742956 -216.277169) (xy 119.514376 -216.277169) (xy 119.506433 -216.329873)
			(xy 119.490723 -216.380803) (xy 119.467597 -216.428824) (xy 119.437573 -216.472861) (xy 119.401321 -216.511932)
			(xy 119.35965 -216.545163) (xy 119.313492 -216.571812) (xy 119.263878 -216.591284) (xy 119.211916 -216.603144)
			(xy 119.158766 -216.607128) (xy 119.105616 -216.603144) (xy 119.053654 -216.591284) (xy 119.00404 -216.571812)
			(xy 118.957882 -216.545163) (xy 118.916211 -216.511932) (xy 118.879959 -216.472861) (xy 118.849935 -216.428824)
			(xy 118.826809 -216.380803) (xy 118.811099 -216.329873) (xy 118.803156 -216.277169) (xy 118.600282 -216.277169)
			(xy 118.600277 -216.27747) (xy 118.592825 -216.330338) (xy 118.578076 -216.381652) (xy 118.556319 -216.430409)
			(xy 118.527979 -216.475658) (xy 118.493608 -216.516515) (xy 118.453879 -216.552182) (xy 118.409565 -216.581963)
			(xy 118.361533 -216.605277) (xy 118.31072 -216.621669) (xy 118.284498 -216.626694) (xy 118.242588 -216.63406)
			(xy 118.242588 -217.064336) (xy 118.35892 -217.064336) (xy 118.359428 -217.038429) (xy 118.367534 -216.987252)
			(xy 118.383546 -216.937973) (xy 118.407069 -216.891806) (xy 118.437525 -216.849887) (xy 118.474163 -216.813249)
			(xy 118.516082 -216.782793) (xy 118.562249 -216.75927) (xy 118.611528 -216.743258) (xy 118.662705 -216.735152)
			(xy 118.714519 -216.735152) (xy 118.765696 -216.743258) (xy 118.814975 -216.75927) (xy 118.861142 -216.782793)
			(xy 118.903061 -216.813249) (xy 118.939699 -216.849887) (xy 118.970155 -216.891806) (xy 118.993678 -216.937973)
			(xy 119.00969 -216.987252) (xy 119.017796 -217.038429) (xy 119.018304 -217.064336) (xy 119.017711 -217.090985)
			(xy 119.273056 -217.090985) (xy 119.273056 -217.037687) (xy 119.280999 -216.984983) (xy 119.296709 -216.934053)
			(xy 119.319835 -216.886032) (xy 119.349859 -216.841995) (xy 119.386111 -216.802924) (xy 119.427782 -216.769693)
			(xy 119.47394 -216.743044) (xy 119.523554 -216.723572) (xy 119.575516 -216.711712) (xy 119.628666 -216.707729)
			(xy 119.681816 -216.711712) (xy 119.733778 -216.723572) (xy 119.783392 -216.743044) (xy 119.82955 -216.769693)
			(xy 119.871221 -216.802924) (xy 119.907473 -216.841995) (xy 119.937497 -216.886032) (xy 119.960623 -216.934053)
			(xy 119.976333 -216.984983) (xy 119.984276 -217.037687) (xy 119.984774 -217.064336) (xy 120.23852 -217.064336)
			(xy 120.239028 -217.038429) (xy 120.247134 -216.987252) (xy 120.263146 -216.937973) (xy 120.286669 -216.891806)
			(xy 120.317125 -216.849887) (xy 120.353763 -216.813249) (xy 120.395682 -216.782793) (xy 120.441849 -216.75927)
			(xy 120.491128 -216.743258) (xy 120.542305 -216.735152) (xy 120.594119 -216.735152) (xy 120.645296 -216.743258)
			(xy 120.694575 -216.75927) (xy 120.740742 -216.782793) (xy 120.782661 -216.813249) (xy 120.819299 -216.849887)
			(xy 120.849755 -216.891806) (xy 120.873278 -216.937973) (xy 120.88929 -216.987252) (xy 120.897396 -217.038429)
			(xy 120.897904 -217.064336) (xy 120.897311 -217.090985) (xy 121.152656 -217.090985) (xy 121.152656 -217.037687)
			(xy 121.160599 -216.984983) (xy 121.176309 -216.934053) (xy 121.199435 -216.886032) (xy 121.229459 -216.841995)
			(xy 121.265711 -216.802924) (xy 121.307382 -216.769693) (xy 121.35354 -216.743044) (xy 121.403154 -216.723572)
			(xy 121.455116 -216.711712) (xy 121.508266 -216.707729) (xy 121.561416 -216.711712) (xy 121.613378 -216.723572)
			(xy 121.662992 -216.743044) (xy 121.70915 -216.769693) (xy 121.750821 -216.802924) (xy 121.787073 -216.841995)
			(xy 121.817097 -216.886032) (xy 121.840223 -216.934053) (xy 121.855933 -216.984983) (xy 121.863876 -217.037687)
			(xy 121.864374 -217.064336) (xy 122.11812 -217.064336) (xy 122.118628 -217.038429) (xy 122.126734 -216.987252)
			(xy 122.142746 -216.937973) (xy 122.166269 -216.891806) (xy 122.196725 -216.849887) (xy 122.233363 -216.813249)
			(xy 122.275282 -216.782793) (xy 122.321449 -216.75927) (xy 122.370728 -216.743258) (xy 122.421905 -216.735152)
			(xy 122.473719 -216.735152) (xy 122.524896 -216.743258) (xy 122.574175 -216.75927) (xy 122.620342 -216.782793)
			(xy 122.662261 -216.813249) (xy 122.698899 -216.849887) (xy 122.729355 -216.891806) (xy 122.752878 -216.937973)
			(xy 122.76889 -216.987252) (xy 122.776996 -217.038429) (xy 122.777504 -217.064336) (xy 122.776911 -217.090985)
			(xy 123.032256 -217.090985) (xy 123.032256 -217.037687) (xy 123.040199 -216.984983) (xy 123.055909 -216.934053)
			(xy 123.079035 -216.886032) (xy 123.109059 -216.841995) (xy 123.145311 -216.802924) (xy 123.186982 -216.769693)
			(xy 123.23314 -216.743044) (xy 123.282754 -216.723572) (xy 123.334716 -216.711712) (xy 123.387866 -216.707729)
			(xy 123.441016 -216.711712) (xy 123.492978 -216.723572) (xy 123.542592 -216.743044) (xy 123.58875 -216.769693)
			(xy 123.630421 -216.802924) (xy 123.666673 -216.841995) (xy 123.696697 -216.886032) (xy 123.719823 -216.934053)
			(xy 123.735533 -216.984983) (xy 123.743476 -217.037687) (xy 123.743974 -217.064336) (xy 123.99772 -217.064336)
			(xy 123.998228 -217.038429) (xy 124.006334 -216.987252) (xy 124.022346 -216.937973) (xy 124.045869 -216.891806)
			(xy 124.076325 -216.849887) (xy 124.112963 -216.813249) (xy 124.154882 -216.782793) (xy 124.201049 -216.75927)
			(xy 124.250328 -216.743258) (xy 124.301505 -216.735152) (xy 124.353319 -216.735152) (xy 124.404496 -216.743258)
			(xy 124.453775 -216.75927) (xy 124.499942 -216.782793) (xy 124.541861 -216.813249) (xy 124.578499 -216.849887)
			(xy 124.608955 -216.891806) (xy 124.632478 -216.937973) (xy 124.64849 -216.987252) (xy 124.656596 -217.038429)
			(xy 124.657104 -217.064336) (xy 124.656511 -217.090985) (xy 124.911856 -217.090985) (xy 124.911856 -217.037687)
			(xy 124.919799 -216.984983) (xy 124.935509 -216.934053) (xy 124.958635 -216.886032) (xy 124.988659 -216.841995)
			(xy 125.024911 -216.802924) (xy 125.066582 -216.769693) (xy 125.11274 -216.743044) (xy 125.162354 -216.723572)
			(xy 125.214316 -216.711712) (xy 125.267466 -216.707729) (xy 125.320616 -216.711712) (xy 125.372578 -216.723572)
			(xy 125.422192 -216.743044) (xy 125.46835 -216.769693) (xy 125.510021 -216.802924) (xy 125.546273 -216.841995)
			(xy 125.576297 -216.886032) (xy 125.599423 -216.934053) (xy 125.615133 -216.984983) (xy 125.623076 -217.037687)
			(xy 125.623574 -217.064336) (xy 125.623076 -217.090985) (xy 125.615133 -217.143689) (xy 125.599423 -217.194619)
			(xy 125.576297 -217.24264) (xy 125.546273 -217.286677) (xy 125.510021 -217.325748) (xy 125.46835 -217.358979)
			(xy 125.422192 -217.385628) (xy 125.372578 -217.4051) (xy 125.320616 -217.41696) (xy 125.267466 -217.420944)
			(xy 125.214316 -217.41696) (xy 125.162354 -217.4051) (xy 125.11274 -217.385628) (xy 125.066582 -217.358979)
			(xy 125.024911 -217.325748) (xy 124.988659 -217.286677) (xy 124.958635 -217.24264) (xy 124.935509 -217.194619)
			(xy 124.919799 -217.143689) (xy 124.911856 -217.090985) (xy 124.656511 -217.090985) (xy 124.656489 -217.091989)
			(xy 124.647169 -217.146507) (xy 124.638562 -217.172794) (xy 124.630942 -217.194892) (xy 124.836174 -217.550238)
			(xy 124.859034 -217.554556) (xy 124.883841 -217.559728) (xy 124.931579 -217.576721) (xy 124.976156 -217.600818)
			(xy 125.01652 -217.631451) (xy 125.051723 -217.6679) (xy 125.080934 -217.709305) (xy 125.103466 -217.754693)
			(xy 125.118789 -217.802993) (xy 125.126541 -217.85307) (xy 125.127004 -217.878406) (xy 125.126496 -217.904293)
			(xy 125.118397 -217.955431) (xy 125.102398 -218.004671) (xy 125.078892 -218.050803) (xy 125.04846 -218.09269)
			(xy 125.01185 -218.1293) (xy 124.969963 -218.159732) (xy 124.923831 -218.183238) (xy 124.874591 -218.199237)
			(xy 124.823453 -218.207336) (xy 124.771679 -218.207336) (xy 124.720541 -218.199237) (xy 124.671301 -218.183238)
			(xy 124.625169 -218.159732) (xy 124.583282 -218.1293) (xy 124.546672 -218.09269) (xy 124.51624 -218.050803)
			(xy 124.492734 -218.004671) (xy 124.476735 -217.955431) (xy 124.468636 -217.904293) (xy 124.468128 -217.878406)
			(xy 124.468662 -217.850698) (xy 124.477855 -217.796051) (xy 124.486416 -217.769694) (xy 124.49429 -217.747596)
			(xy 124.289312 -217.392504) (xy 124.266452 -217.388186) (xy 124.241596 -217.383069) (xy 124.193748 -217.366166)
			(xy 124.149056 -217.342128) (xy 124.108577 -217.311523) (xy 124.073267 -217.275076) (xy 124.043961 -217.233647)
			(xy 124.021352 -217.188215) (xy 124.005974 -217.139855) (xy 123.99819 -217.089709) (xy 123.99772 -217.064336)
			(xy 123.743974 -217.064336) (xy 123.743476 -217.090985) (xy 123.735533 -217.143689) (xy 123.719823 -217.194619)
			(xy 123.696697 -217.24264) (xy 123.666673 -217.286677) (xy 123.630421 -217.325748) (xy 123.58875 -217.358979)
			(xy 123.542592 -217.385628) (xy 123.492978 -217.4051) (xy 123.441016 -217.41696) (xy 123.387866 -217.420944)
			(xy 123.334716 -217.41696) (xy 123.282754 -217.4051) (xy 123.23314 -217.385628) (xy 123.186982 -217.358979)
			(xy 123.145311 -217.325748) (xy 123.109059 -217.286677) (xy 123.079035 -217.24264) (xy 123.055909 -217.194619)
			(xy 123.040199 -217.143689) (xy 123.032256 -217.090985) (xy 122.776911 -217.090985) (xy 122.776889 -217.091989)
			(xy 122.767569 -217.146507) (xy 122.758962 -217.172794) (xy 122.751342 -217.194892) (xy 122.956574 -217.550238)
			(xy 122.979434 -217.554556) (xy 123.004241 -217.559728) (xy 123.051979 -217.576721) (xy 123.096556 -217.600818)
			(xy 123.13692 -217.631451) (xy 123.172123 -217.6679) (xy 123.201334 -217.709305) (xy 123.223866 -217.754693)
			(xy 123.239189 -217.802993) (xy 123.246941 -217.85307) (xy 123.247404 -217.878406) (xy 123.246896 -217.904293)
			(xy 123.238797 -217.955431) (xy 123.222798 -218.004671) (xy 123.199292 -218.050803) (xy 123.16886 -218.09269)
			(xy 123.13225 -218.1293) (xy 123.090363 -218.159732) (xy 123.044231 -218.183238) (xy 122.994991 -218.199237)
			(xy 122.943853 -218.207336) (xy 122.892079 -218.207336) (xy 122.840941 -218.199237) (xy 122.791701 -218.183238)
			(xy 122.745569 -218.159732) (xy 122.703682 -218.1293) (xy 122.667072 -218.09269) (xy 122.63664 -218.050803)
			(xy 122.613134 -218.004671) (xy 122.597135 -217.955431) (xy 122.589036 -217.904293) (xy 122.588528 -217.878406)
			(xy 122.589062 -217.850698) (xy 122.598255 -217.796051) (xy 122.606816 -217.769694) (xy 122.61469 -217.747596)
			(xy 122.409712 -217.392504) (xy 122.386852 -217.388186) (xy 122.361996 -217.383069) (xy 122.314148 -217.366166)
			(xy 122.269456 -217.342128) (xy 122.228977 -217.311523) (xy 122.193667 -217.275076) (xy 122.164361 -217.233647)
			(xy 122.141752 -217.188215) (xy 122.126374 -217.139855) (xy 122.11859 -217.089709) (xy 122.11812 -217.064336)
			(xy 121.864374 -217.064336) (xy 121.863876 -217.090985) (xy 121.855933 -217.143689) (xy 121.840223 -217.194619)
			(xy 121.817097 -217.24264) (xy 121.787073 -217.286677) (xy 121.750821 -217.325748) (xy 121.70915 -217.358979)
			(xy 121.662992 -217.385628) (xy 121.613378 -217.4051) (xy 121.561416 -217.41696) (xy 121.508266 -217.420944)
			(xy 121.455116 -217.41696) (xy 121.403154 -217.4051) (xy 121.35354 -217.385628) (xy 121.307382 -217.358979)
			(xy 121.265711 -217.325748) (xy 121.229459 -217.286677) (xy 121.199435 -217.24264) (xy 121.176309 -217.194619)
			(xy 121.160599 -217.143689) (xy 121.152656 -217.090985) (xy 120.897311 -217.090985) (xy 120.897289 -217.091989)
			(xy 120.887969 -217.146507) (xy 120.879362 -217.172794) (xy 120.871742 -217.194892) (xy 121.076974 -217.550238)
			(xy 121.099834 -217.554556) (xy 121.124641 -217.559728) (xy 121.172379 -217.576721) (xy 121.216956 -217.600818)
			(xy 121.25732 -217.631451) (xy 121.292523 -217.6679) (xy 121.321734 -217.709305) (xy 121.344266 -217.754693)
			(xy 121.359589 -217.802993) (xy 121.367341 -217.85307) (xy 121.367804 -217.878406) (xy 121.367296 -217.904293)
			(xy 121.359197 -217.955431) (xy 121.343198 -218.004671) (xy 121.319692 -218.050803) (xy 121.28926 -218.09269)
			(xy 121.25265 -218.1293) (xy 121.210763 -218.159732) (xy 121.164631 -218.183238) (xy 121.115391 -218.199237)
			(xy 121.064253 -218.207336) (xy 121.012479 -218.207336) (xy 120.961341 -218.199237) (xy 120.912101 -218.183238)
			(xy 120.865969 -218.159732) (xy 120.824082 -218.1293) (xy 120.787472 -218.09269) (xy 120.75704 -218.050803)
			(xy 120.733534 -218.004671) (xy 120.717535 -217.955431) (xy 120.709436 -217.904293) (xy 120.708928 -217.878406)
			(xy 120.709462 -217.850698) (xy 120.718655 -217.796051) (xy 120.727216 -217.769694) (xy 120.73509 -217.747596)
			(xy 120.530112 -217.392504) (xy 120.507252 -217.388186) (xy 120.482396 -217.383069) (xy 120.434548 -217.366166)
			(xy 120.389856 -217.342128) (xy 120.349377 -217.311523) (xy 120.314067 -217.275076) (xy 120.284761 -217.233647)
			(xy 120.262152 -217.188215) (xy 120.246774 -217.139855) (xy 120.23899 -217.089709) (xy 120.23852 -217.064336)
			(xy 119.984774 -217.064336) (xy 119.984276 -217.090985) (xy 119.976333 -217.143689) (xy 119.960623 -217.194619)
			(xy 119.937497 -217.24264) (xy 119.907473 -217.286677) (xy 119.871221 -217.325748) (xy 119.82955 -217.358979)
			(xy 119.783392 -217.385628) (xy 119.733778 -217.4051) (xy 119.681816 -217.41696) (xy 119.628666 -217.420944)
			(xy 119.575516 -217.41696) (xy 119.523554 -217.4051) (xy 119.47394 -217.385628) (xy 119.427782 -217.358979)
			(xy 119.386111 -217.325748) (xy 119.349859 -217.286677) (xy 119.319835 -217.24264) (xy 119.296709 -217.194619)
			(xy 119.280999 -217.143689) (xy 119.273056 -217.090985) (xy 119.017711 -217.090985) (xy 119.017689 -217.091989)
			(xy 119.008369 -217.146507) (xy 118.999762 -217.172794) (xy 118.992142 -217.194892) (xy 119.197374 -217.550238)
			(xy 119.220234 -217.554556) (xy 119.245041 -217.559728) (xy 119.292779 -217.576721) (xy 119.337356 -217.600818)
			(xy 119.37772 -217.631451) (xy 119.412923 -217.6679) (xy 119.442134 -217.709305) (xy 119.464666 -217.754693)
			(xy 119.479989 -217.802993) (xy 119.487741 -217.85307) (xy 119.488204 -217.878406) (xy 119.487696 -217.904293)
			(xy 119.479597 -217.955431) (xy 119.463598 -218.004671) (xy 119.440092 -218.050803) (xy 119.40966 -218.09269)
			(xy 119.37305 -218.1293) (xy 119.331163 -218.159732) (xy 119.285031 -218.183238) (xy 119.235791 -218.199237)
			(xy 119.184653 -218.207336) (xy 119.132879 -218.207336) (xy 119.081741 -218.199237) (xy 119.032501 -218.183238)
			(xy 118.986369 -218.159732) (xy 118.944482 -218.1293) (xy 118.907872 -218.09269) (xy 118.87744 -218.050803)
			(xy 118.853934 -218.004671) (xy 118.837935 -217.955431) (xy 118.829836 -217.904293) (xy 118.829328 -217.878406)
			(xy 118.829862 -217.850698) (xy 118.839055 -217.796051) (xy 118.847616 -217.769694) (xy 118.85549 -217.747596)
			(xy 118.650512 -217.392504) (xy 118.627652 -217.388186) (xy 118.602796 -217.383069) (xy 118.554948 -217.366166)
			(xy 118.510256 -217.342128) (xy 118.469777 -217.311523) (xy 118.434467 -217.275076) (xy 118.405161 -217.233647)
			(xy 118.382552 -217.188215) (xy 118.367174 -217.139855) (xy 118.35939 -217.089709) (xy 118.35892 -217.064336)
			(xy 118.242588 -217.064336) (xy 118.242588 -217.292428) (xy 118.159276 -217.375486) (xy 118.149141 -217.386326)
			(xy 118.135056 -217.412431) (xy 118.129059 -217.441482) (xy 118.131657 -217.471031) (xy 118.14263 -217.498589)
			(xy 118.161054 -217.521837) (xy 118.185377 -217.538815) (xy 118.213551 -217.548094) (xy 118.228364 -217.548968)
			(xy 118.253756 -217.55019) (xy 118.303734 -217.559474) (xy 118.351696 -217.576318) (xy 118.396505 -217.600321)
			(xy 118.4371 -217.630917) (xy 118.47252 -217.66738) (xy 118.501924 -217.708845) (xy 118.524618 -217.754332)
			(xy 118.540062 -217.802763) (xy 118.547892 -217.85299) (xy 118.548404 -217.878406) (xy 118.547936 -217.903779)
			(xy 118.540155 -217.953924) (xy 118.524778 -218.002284) (xy 118.502169 -218.047715) (xy 118.472862 -218.089142)
			(xy 118.43755 -218.125586) (xy 118.397068 -218.156186) (xy 118.352373 -218.180218) (xy 118.304523 -218.197113)
			(xy 118.279672 -218.202256) (xy 118.256812 -218.206574) (xy 118.052088 -218.561412) (xy 118.059962 -218.583256)
			(xy 118.068607 -218.609665) (xy 118.077925 -218.66444) (xy 118.078504 -218.692222) (xy 119.29872 -218.692222)
			(xy 119.299245 -218.666878) (xy 119.307014 -218.616789) (xy 119.322357 -218.56848) (xy 119.344912 -218.523087)
			(xy 119.374149 -218.481681) (xy 119.409378 -218.445236) (xy 119.449769 -218.414613) (xy 119.49437 -218.390531)
			(xy 119.542132 -218.373559) (xy 119.566944 -218.368372) (xy 119.589804 -218.364054) (xy 119.795036 -218.008708)
			(xy 119.787162 -217.98661) (xy 119.778694 -217.960366) (xy 119.769624 -217.905977) (xy 119.769128 -217.878406)
			(xy 119.769636 -217.852519) (xy 119.777735 -217.801381) (xy 119.793734 -217.752141) (xy 119.81724 -217.706009)
			(xy 119.847672 -217.664122) (xy 119.884282 -217.627512) (xy 119.926169 -217.59708) (xy 119.972301 -217.573574)
			(xy 120.021541 -217.557575) (xy 120.072679 -217.549476) (xy 120.124453 -217.549476) (xy 120.175591 -217.557575)
			(xy 120.224831 -217.573574) (xy 120.270963 -217.59708) (xy 120.31285 -217.627512) (xy 120.34946 -217.664122)
			(xy 120.379892 -217.706009) (xy 120.403398 -217.752141) (xy 120.419397 -217.801381) (xy 120.427496 -217.852519)
			(xy 120.428004 -217.878406) (xy 120.427531 -217.90378) (xy 120.419762 -217.953931) (xy 120.404393 -218.002296)
			(xy 120.381788 -218.047732) (xy 120.352482 -218.089163) (xy 120.317168 -218.125609) (xy 120.276682 -218.156208)
			(xy 120.231982 -218.180235) (xy 120.184126 -218.197122) (xy 120.159272 -218.202256) (xy 120.136412 -218.206574)
			(xy 119.931688 -218.561412) (xy 119.939562 -218.583256) (xy 119.948214 -218.609662) (xy 119.95753 -218.66444)
			(xy 119.958104 -218.692222) (xy 121.17832 -218.692222) (xy 121.178845 -218.666878) (xy 121.186614 -218.616789)
			(xy 121.201957 -218.56848) (xy 121.224512 -218.523087) (xy 121.253749 -218.481681) (xy 121.288978 -218.445236)
			(xy 121.329369 -218.414613) (xy 121.37397 -218.390531) (xy 121.421732 -218.373559) (xy 121.446544 -218.368372)
			(xy 121.469404 -218.364054) (xy 121.674636 -218.008708) (xy 121.666762 -217.98661) (xy 121.658294 -217.960366)
			(xy 121.649224 -217.905977) (xy 121.648728 -217.878406) (xy 121.649236 -217.852519) (xy 121.657335 -217.801381)
			(xy 121.673334 -217.752141) (xy 121.69684 -217.706009) (xy 121.727272 -217.664122) (xy 121.763882 -217.627512)
			(xy 121.805769 -217.59708) (xy 121.851901 -217.573574) (xy 121.901141 -217.557575) (xy 121.952279 -217.549476)
			(xy 122.004053 -217.549476) (xy 122.055191 -217.557575) (xy 122.104431 -217.573574) (xy 122.150563 -217.59708)
			(xy 122.19245 -217.627512) (xy 122.22906 -217.664122) (xy 122.259492 -217.706009) (xy 122.282998 -217.752141)
			(xy 122.298997 -217.801381) (xy 122.307096 -217.852519) (xy 122.307604 -217.878406) (xy 122.307131 -217.90378)
			(xy 122.299362 -217.953931) (xy 122.283993 -218.002296) (xy 122.261388 -218.047732) (xy 122.232082 -218.089163)
			(xy 122.196768 -218.125609) (xy 122.156282 -218.156208) (xy 122.111582 -218.180235) (xy 122.063726 -218.197122)
			(xy 122.038872 -218.202256) (xy 122.016012 -218.206574) (xy 121.811288 -218.561412) (xy 121.819162 -218.583256)
			(xy 121.827814 -218.609662) (xy 121.83713 -218.66444) (xy 121.837704 -218.692222) (xy 123.05792 -218.692222)
			(xy 123.058445 -218.666878) (xy 123.066214 -218.616789) (xy 123.081557 -218.56848) (xy 123.104112 -218.523087)
			(xy 123.133349 -218.481681) (xy 123.168578 -218.445236) (xy 123.208969 -218.414613) (xy 123.25357 -218.390531)
			(xy 123.301332 -218.373559) (xy 123.326144 -218.368372) (xy 123.349004 -218.364054) (xy 123.554236 -218.008708)
			(xy 123.546362 -217.98661) (xy 123.537894 -217.960366) (xy 123.528824 -217.905977) (xy 123.528328 -217.878406)
			(xy 123.528836 -217.852519) (xy 123.536935 -217.801381) (xy 123.552934 -217.752141) (xy 123.57644 -217.706009)
			(xy 123.606872 -217.664122) (xy 123.643482 -217.627512) (xy 123.685369 -217.59708) (xy 123.731501 -217.573574)
			(xy 123.780741 -217.557575) (xy 123.831879 -217.549476) (xy 123.883653 -217.549476) (xy 123.934791 -217.557575)
			(xy 123.984031 -217.573574) (xy 124.030163 -217.59708) (xy 124.07205 -217.627512) (xy 124.10866 -217.664122)
			(xy 124.139092 -217.706009) (xy 124.162598 -217.752141) (xy 124.178597 -217.801381) (xy 124.186696 -217.852519)
			(xy 124.187204 -217.878406) (xy 124.186731 -217.90378) (xy 124.178962 -217.953931) (xy 124.163593 -218.002296)
			(xy 124.140988 -218.047732) (xy 124.111682 -218.089163) (xy 124.076368 -218.125609) (xy 124.035882 -218.156208)
			(xy 123.991182 -218.180235) (xy 123.943326 -218.197122) (xy 123.918472 -218.202256) (xy 123.895612 -218.206574)
			(xy 123.690888 -218.561412) (xy 123.698762 -218.583256) (xy 123.707414 -218.609662) (xy 123.71673 -218.66444)
			(xy 123.717304 -218.692222) (xy 124.93752 -218.692222) (xy 124.938045 -218.666878) (xy 124.945814 -218.616789)
			(xy 124.961157 -218.56848) (xy 124.983712 -218.523087) (xy 125.012949 -218.481681) (xy 125.048178 -218.445236)
			(xy 125.088569 -218.414613) (xy 125.13317 -218.390531) (xy 125.180932 -218.373559) (xy 125.205744 -218.368372)
			(xy 125.228604 -218.364054) (xy 125.433836 -218.008708) (xy 125.425962 -217.98661) (xy 125.417494 -217.960366)
			(xy 125.408424 -217.905977) (xy 125.407928 -217.878406) (xy 125.408436 -217.852519) (xy 125.416535 -217.801381)
			(xy 125.432534 -217.752141) (xy 125.45604 -217.706009) (xy 125.486472 -217.664122) (xy 125.523082 -217.627512)
			(xy 125.564969 -217.59708) (xy 125.611101 -217.573574) (xy 125.660341 -217.557575) (xy 125.711479 -217.549476)
			(xy 125.763253 -217.549476) (xy 125.814391 -217.557575) (xy 125.863631 -217.573574) (xy 125.909763 -217.59708)
			(xy 125.95165 -217.627512) (xy 125.98826 -217.664122) (xy 126.018692 -217.706009) (xy 126.042198 -217.752141)
			(xy 126.058197 -217.801381) (xy 126.066296 -217.852519) (xy 126.066804 -217.878406) (xy 126.066331 -217.90378)
			(xy 126.058562 -217.953931) (xy 126.043193 -218.002296) (xy 126.020588 -218.047732) (xy 125.991282 -218.089163)
			(xy 125.955968 -218.125609) (xy 125.915482 -218.156208) (xy 125.870782 -218.180235) (xy 125.822926 -218.197122)
			(xy 125.798072 -218.202256) (xy 125.775212 -218.206574) (xy 125.570488 -218.561412) (xy 125.578362 -218.583256)
			(xy 125.587014 -218.609662) (xy 125.59633 -218.66444) (xy 125.596904 -218.692222) (xy 125.596396 -218.718129)
			(xy 125.58829 -218.769306) (xy 125.572278 -218.818585) (xy 125.548755 -218.864752) (xy 125.518299 -218.906671)
			(xy 125.481661 -218.943309) (xy 125.439742 -218.973765) (xy 125.393575 -218.997288) (xy 125.344296 -219.0133)
			(xy 125.293119 -219.021406) (xy 125.241305 -219.021406) (xy 125.190128 -219.0133) (xy 125.140849 -218.997288)
			(xy 125.094682 -218.973765) (xy 125.052763 -218.943309) (xy 125.016125 -218.906671) (xy 124.985669 -218.864752)
			(xy 124.962146 -218.818585) (xy 124.946134 -218.769306) (xy 124.938028 -218.718129) (xy 124.93752 -218.692222)
			(xy 123.717304 -218.692222) (xy 123.716796 -218.718129) (xy 123.70869 -218.769306) (xy 123.692678 -218.818585)
			(xy 123.669155 -218.864752) (xy 123.638699 -218.906671) (xy 123.602061 -218.943309) (xy 123.560142 -218.973765)
			(xy 123.513975 -218.997288) (xy 123.464696 -219.0133) (xy 123.413519 -219.021406) (xy 123.361705 -219.021406)
			(xy 123.310528 -219.0133) (xy 123.261249 -218.997288) (xy 123.215082 -218.973765) (xy 123.173163 -218.943309)
			(xy 123.136525 -218.906671) (xy 123.106069 -218.864752) (xy 123.082546 -218.818585) (xy 123.066534 -218.769306)
			(xy 123.058428 -218.718129) (xy 123.05792 -218.692222) (xy 121.837704 -218.692222) (xy 121.837196 -218.718129)
			(xy 121.82909 -218.769306) (xy 121.813078 -218.818585) (xy 121.789555 -218.864752) (xy 121.759099 -218.906671)
			(xy 121.722461 -218.943309) (xy 121.680542 -218.973765) (xy 121.634375 -218.997288) (xy 121.585096 -219.0133)
			(xy 121.533919 -219.021406) (xy 121.482105 -219.021406) (xy 121.430928 -219.0133) (xy 121.381649 -218.997288)
			(xy 121.335482 -218.973765) (xy 121.293563 -218.943309) (xy 121.256925 -218.906671) (xy 121.226469 -218.864752)
			(xy 121.202946 -218.818585) (xy 121.186934 -218.769306) (xy 121.178828 -218.718129) (xy 121.17832 -218.692222)
			(xy 119.958104 -218.692222) (xy 119.957596 -218.718129) (xy 119.94949 -218.769306) (xy 119.933478 -218.818585)
			(xy 119.909955 -218.864752) (xy 119.879499 -218.906671) (xy 119.842861 -218.943309) (xy 119.800942 -218.973765)
			(xy 119.754775 -218.997288) (xy 119.705496 -219.0133) (xy 119.654319 -219.021406) (xy 119.602505 -219.021406)
			(xy 119.551328 -219.0133) (xy 119.502049 -218.997288) (xy 119.455882 -218.973765) (xy 119.413963 -218.943309)
			(xy 119.377325 -218.906671) (xy 119.346869 -218.864752) (xy 119.323346 -218.818585) (xy 119.307334 -218.769306)
			(xy 119.299228 -218.718129) (xy 119.29872 -218.692222) (xy 118.078504 -218.692222) (xy 118.077996 -218.718129)
			(xy 118.06989 -218.769306) (xy 118.053878 -218.818585) (xy 118.030355 -218.864752) (xy 117.999899 -218.906671)
			(xy 117.963261 -218.943309) (xy 117.921342 -218.973765) (xy 117.875175 -218.997288) (xy 117.825896 -219.0133)
			(xy 117.774719 -219.021406) (xy 117.722905 -219.021406) (xy 117.671728 -219.0133) (xy 117.622449 -218.997288)
			(xy 117.576282 -218.973765) (xy 117.534363 -218.943309) (xy 117.497725 -218.906671) (xy 117.467269 -218.864752)
			(xy 117.443746 -218.818585) (xy 117.427734 -218.769306) (xy 117.419628 -218.718129) (xy 117.41912 -218.692222)
			(xy 117.419584 -218.666874) (xy 117.427343 -218.616775) (xy 117.442683 -218.568455) (xy 117.465241 -218.523054)
			(xy 117.494486 -218.481643) (xy 117.529726 -218.445199) (xy 117.570132 -218.414581) (xy 117.61475 -218.390511)
			(xy 117.662527 -218.373557) (xy 117.687344 -218.368372) (xy 117.710204 -218.364054) (xy 117.915436 -218.008708)
			(xy 117.907562 -217.98661) (xy 117.899209 -217.960666) (xy 117.890148 -217.906925) (xy 117.889528 -217.879676)
			(xy 117.888924 -217.864717) (xy 117.880109 -217.836121) (xy 117.863391 -217.811304) (xy 117.8402 -217.792392)
			(xy 117.812527 -217.781008) (xy 117.782742 -217.778127) (xy 117.7534 -217.783996) (xy 117.727015 -217.798112)
			(xy 117.716046 -217.808302) (xy 117.679978 -217.84437) (xy 117.610636 -217.84437) (xy 117.60835 -217.892884)
			(xy 117.606768 -217.918006) (xy 117.596934 -217.967371) (xy 117.579707 -218.014666) (xy 117.555486 -218.058791)
			(xy 117.524837 -218.098718) (xy 117.488471 -218.13352) (xy 117.447235 -218.162385) (xy 117.402089 -218.184644)
			(xy 117.354083 -218.199777) (xy 117.304333 -218.207432) (xy 117.253999 -218.207432) (xy 117.204249 -218.199777)
			(xy 117.156243 -218.184644) (xy 117.111097 -218.162385) (xy 117.069861 -218.13352) (xy 117.033495 -218.098718)
			(xy 117.002846 -218.058791) (xy 116.978625 -218.014666) (xy 116.961398 -217.967371) (xy 116.951564 -217.918006)
			(xy 116.949982 -217.892884) (xy 116.947696 -217.84437) (xy 116.670836 -217.84437) (xy 116.66855 -217.892884)
			(xy 116.667016 -217.917409) (xy 116.657589 -217.965633) (xy 116.641105 -218.011922) (xy 116.617929 -218.05525)
			(xy 116.588574 -218.094655) (xy 116.553693 -218.129264) (xy 116.514059 -218.158308) (xy 116.47055 -218.181144)
			(xy 116.424133 -218.197264) (xy 116.400072 -218.202256) (xy 116.377212 -218.206574) (xy 116.172488 -218.561412)
			(xy 116.180362 -218.583256) (xy 116.189007 -218.609665) (xy 116.198325 -218.66444) (xy 116.198904 -218.692222)
			(xy 116.198444 -218.717241) (xy 116.190885 -218.766706) (xy 116.17593 -218.814457) (xy 116.153922 -218.859396)
			(xy 116.125369 -218.900489) (xy 116.090928 -218.936788) (xy 116.051391 -218.967459) (xy 116.02974 -218.980004)
			(xy 116.003578 -218.994736) (xy 116.003578 -219.112846) (xy 116.00398 -219.126264) (xy 116.010966 -219.152176)
			(xy 116.024468 -219.175368) (xy 116.043552 -219.194236) (xy 116.066896 -219.207474) (xy 116.092885 -219.214165)
			(xy 116.11972 -219.213846) (xy 116.145543 -219.206539) (xy 116.157248 -219.199968) (xy 116.177991 -219.188082)
			(xy 116.221982 -219.169362) (xy 116.268082 -219.156694) (xy 116.315462 -219.150308) (xy 116.339366 -219.14993)
			(xy 116.366016 -219.150401) (xy 116.418721 -219.15834) (xy 116.469654 -219.174047) (xy 116.517677 -219.197169)
			(xy 116.561718 -219.227191) (xy 116.600791 -219.263443) (xy 116.634024 -219.305113) (xy 116.660676 -219.351271)
			(xy 116.68015 -219.400886) (xy 116.692011 -219.452849) (xy 116.695994 -219.506) (xy 116.693994 -219.532687)
			(xy 116.923556 -219.532687) (xy 116.923556 -219.479389) (xy 116.931499 -219.426685) (xy 116.947209 -219.375755)
			(xy 116.970335 -219.327734) (xy 117.000359 -219.283697) (xy 117.036611 -219.244626) (xy 117.078282 -219.211395)
			(xy 117.12444 -219.184746) (xy 117.174054 -219.165274) (xy 117.226016 -219.153414) (xy 117.279166 -219.149431)
			(xy 117.332316 -219.153414) (xy 117.384278 -219.165274) (xy 117.433892 -219.184746) (xy 117.48005 -219.211395)
			(xy 117.521721 -219.244626) (xy 117.557973 -219.283697) (xy 117.587997 -219.327734) (xy 117.611123 -219.375755)
			(xy 117.626833 -219.426685) (xy 117.634776 -219.479389) (xy 117.635274 -219.506038) (xy 117.634776 -219.532687)
			(xy 117.863356 -219.532687) (xy 117.863356 -219.479389) (xy 117.871299 -219.426685) (xy 117.887009 -219.375755)
			(xy 117.910135 -219.327734) (xy 117.940159 -219.283697) (xy 117.976411 -219.244626) (xy 118.018082 -219.211395)
			(xy 118.06424 -219.184746) (xy 118.113854 -219.165274) (xy 118.165816 -219.153414) (xy 118.218966 -219.149431)
			(xy 118.272116 -219.153414) (xy 118.324078 -219.165274) (xy 118.373692 -219.184746) (xy 118.41985 -219.211395)
			(xy 118.461521 -219.244626) (xy 118.497773 -219.283697) (xy 118.527797 -219.327734) (xy 118.550923 -219.375755)
			(xy 118.566633 -219.426685) (xy 118.574576 -219.479389) (xy 118.575074 -219.506038) (xy 118.574576 -219.532687)
			(xy 118.803156 -219.532687) (xy 118.803156 -219.479389) (xy 118.811099 -219.426685) (xy 118.826809 -219.375755)
			(xy 118.849935 -219.327734) (xy 118.879959 -219.283697) (xy 118.916211 -219.244626) (xy 118.957882 -219.211395)
			(xy 119.00404 -219.184746) (xy 119.053654 -219.165274) (xy 119.105616 -219.153414) (xy 119.158766 -219.149431)
			(xy 119.211916 -219.153414) (xy 119.263878 -219.165274) (xy 119.313492 -219.184746) (xy 119.35965 -219.211395)
			(xy 119.401321 -219.244626) (xy 119.437573 -219.283697) (xy 119.467597 -219.327734) (xy 119.490723 -219.375755)
			(xy 119.506433 -219.426685) (xy 119.514376 -219.479389) (xy 119.514874 -219.506038) (xy 119.514376 -219.532687)
			(xy 119.742956 -219.532687) (xy 119.742956 -219.479389) (xy 119.750899 -219.426685) (xy 119.766609 -219.375755)
			(xy 119.789735 -219.327734) (xy 119.819759 -219.283697) (xy 119.856011 -219.244626) (xy 119.897682 -219.211395)
			(xy 119.94384 -219.184746) (xy 119.993454 -219.165274) (xy 120.045416 -219.153414) (xy 120.098566 -219.149431)
			(xy 120.151716 -219.153414) (xy 120.203678 -219.165274) (xy 120.253292 -219.184746) (xy 120.29945 -219.211395)
			(xy 120.341121 -219.244626) (xy 120.377373 -219.283697) (xy 120.407397 -219.327734) (xy 120.430523 -219.375755)
			(xy 120.446233 -219.426685) (xy 120.454176 -219.479389) (xy 120.454674 -219.506038) (xy 120.454176 -219.532687)
			(xy 120.682756 -219.532687) (xy 120.682756 -219.479389) (xy 120.690699 -219.426685) (xy 120.706409 -219.375755)
			(xy 120.729535 -219.327734) (xy 120.759559 -219.283697) (xy 120.795811 -219.244626) (xy 120.837482 -219.211395)
			(xy 120.88364 -219.184746) (xy 120.933254 -219.165274) (xy 120.985216 -219.153414) (xy 121.038366 -219.149431)
			(xy 121.091516 -219.153414) (xy 121.143478 -219.165274) (xy 121.193092 -219.184746) (xy 121.23925 -219.211395)
			(xy 121.280921 -219.244626) (xy 121.317173 -219.283697) (xy 121.347197 -219.327734) (xy 121.370323 -219.375755)
			(xy 121.386033 -219.426685) (xy 121.393976 -219.479389) (xy 121.394474 -219.506038) (xy 121.393976 -219.532687)
			(xy 121.622556 -219.532687) (xy 121.622556 -219.479389) (xy 121.630499 -219.426685) (xy 121.646209 -219.375755)
			(xy 121.669335 -219.327734) (xy 121.699359 -219.283697) (xy 121.735611 -219.244626) (xy 121.777282 -219.211395)
			(xy 121.82344 -219.184746) (xy 121.873054 -219.165274) (xy 121.925016 -219.153414) (xy 121.978166 -219.149431)
			(xy 122.031316 -219.153414) (xy 122.083278 -219.165274) (xy 122.132892 -219.184746) (xy 122.17905 -219.211395)
			(xy 122.220721 -219.244626) (xy 122.256973 -219.283697) (xy 122.286997 -219.327734) (xy 122.310123 -219.375755)
			(xy 122.325833 -219.426685) (xy 122.333776 -219.479389) (xy 122.334274 -219.506038) (xy 122.333776 -219.532687)
			(xy 122.562356 -219.532687) (xy 122.562356 -219.479389) (xy 122.570299 -219.426685) (xy 122.586009 -219.375755)
			(xy 122.609135 -219.327734) (xy 122.639159 -219.283697) (xy 122.675411 -219.244626) (xy 122.717082 -219.211395)
			(xy 122.76324 -219.184746) (xy 122.812854 -219.165274) (xy 122.864816 -219.153414) (xy 122.917966 -219.149431)
			(xy 122.971116 -219.153414) (xy 123.023078 -219.165274) (xy 123.072692 -219.184746) (xy 123.11885 -219.211395)
			(xy 123.160521 -219.244626) (xy 123.196773 -219.283697) (xy 123.226797 -219.327734) (xy 123.249923 -219.375755)
			(xy 123.265633 -219.426685) (xy 123.273576 -219.479389) (xy 123.274074 -219.506038) (xy 123.273576 -219.532687)
			(xy 123.502156 -219.532687) (xy 123.502156 -219.479389) (xy 123.510099 -219.426685) (xy 123.525809 -219.375755)
			(xy 123.548935 -219.327734) (xy 123.578959 -219.283697) (xy 123.615211 -219.244626) (xy 123.656882 -219.211395)
			(xy 123.70304 -219.184746) (xy 123.752654 -219.165274) (xy 123.804616 -219.153414) (xy 123.857766 -219.149431)
			(xy 123.910916 -219.153414) (xy 123.962878 -219.165274) (xy 124.012492 -219.184746) (xy 124.05865 -219.211395)
			(xy 124.100321 -219.244626) (xy 124.136573 -219.283697) (xy 124.166597 -219.327734) (xy 124.189723 -219.375755)
			(xy 124.205433 -219.426685) (xy 124.213376 -219.479389) (xy 124.213874 -219.506038) (xy 124.213376 -219.532687)
			(xy 124.441956 -219.532687) (xy 124.441956 -219.479389) (xy 124.449899 -219.426685) (xy 124.465609 -219.375755)
			(xy 124.488735 -219.327734) (xy 124.518759 -219.283697) (xy 124.555011 -219.244626) (xy 124.596682 -219.211395)
			(xy 124.64284 -219.184746) (xy 124.692454 -219.165274) (xy 124.744416 -219.153414) (xy 124.797566 -219.149431)
			(xy 124.850716 -219.153414) (xy 124.902678 -219.165274) (xy 124.952292 -219.184746) (xy 124.99845 -219.211395)
			(xy 125.040121 -219.244626) (xy 125.076373 -219.283697) (xy 125.106397 -219.327734) (xy 125.129523 -219.375755)
			(xy 125.145233 -219.426685) (xy 125.153176 -219.479389) (xy 125.153674 -219.506038) (xy 125.153176 -219.532687)
			(xy 125.381756 -219.532687) (xy 125.381756 -219.479389) (xy 125.389699 -219.426685) (xy 125.405409 -219.375755)
			(xy 125.428535 -219.327734) (xy 125.458559 -219.283697) (xy 125.494811 -219.244626) (xy 125.536482 -219.211395)
			(xy 125.58264 -219.184746) (xy 125.632254 -219.165274) (xy 125.684216 -219.153414) (xy 125.737366 -219.149431)
			(xy 125.790516 -219.153414) (xy 125.842478 -219.165274) (xy 125.892092 -219.184746) (xy 125.93825 -219.211395)
			(xy 125.979921 -219.244626) (xy 126.016173 -219.283697) (xy 126.046197 -219.327734) (xy 126.069323 -219.375755)
			(xy 126.085033 -219.426685) (xy 126.092976 -219.479389) (xy 126.093474 -219.506038) (xy 126.092976 -219.532687)
			(xy 126.085033 -219.585391) (xy 126.069323 -219.636321) (xy 126.046197 -219.684342) (xy 126.016173 -219.728379)
			(xy 125.979921 -219.76745) (xy 125.93825 -219.800681) (xy 125.892092 -219.82733) (xy 125.842478 -219.846802)
			(xy 125.790516 -219.858662) (xy 125.737366 -219.862646) (xy 125.684216 -219.858662) (xy 125.632254 -219.846802)
			(xy 125.58264 -219.82733) (xy 125.536482 -219.800681) (xy 125.494811 -219.76745) (xy 125.458559 -219.728379)
			(xy 125.428535 -219.684342) (xy 125.405409 -219.636321) (xy 125.389699 -219.585391) (xy 125.381756 -219.532687)
			(xy 125.153176 -219.532687) (xy 125.145233 -219.585391) (xy 125.129523 -219.636321) (xy 125.106397 -219.684342)
			(xy 125.076373 -219.728379) (xy 125.040121 -219.76745) (xy 124.99845 -219.800681) (xy 124.952292 -219.82733)
			(xy 124.902678 -219.846802) (xy 124.850716 -219.858662) (xy 124.797566 -219.862646) (xy 124.744416 -219.858662)
			(xy 124.692454 -219.846802) (xy 124.64284 -219.82733) (xy 124.596682 -219.800681) (xy 124.555011 -219.76745)
			(xy 124.518759 -219.728379) (xy 124.488735 -219.684342) (xy 124.465609 -219.636321) (xy 124.449899 -219.585391)
			(xy 124.441956 -219.532687) (xy 124.213376 -219.532687) (xy 124.205433 -219.585391) (xy 124.189723 -219.636321)
			(xy 124.166597 -219.684342) (xy 124.136573 -219.728379) (xy 124.100321 -219.76745) (xy 124.05865 -219.800681)
			(xy 124.012492 -219.82733) (xy 123.962878 -219.846802) (xy 123.910916 -219.858662) (xy 123.857766 -219.862646)
			(xy 123.804616 -219.858662) (xy 123.752654 -219.846802) (xy 123.70304 -219.82733) (xy 123.656882 -219.800681)
			(xy 123.615211 -219.76745) (xy 123.578959 -219.728379) (xy 123.548935 -219.684342) (xy 123.525809 -219.636321)
			(xy 123.510099 -219.585391) (xy 123.502156 -219.532687) (xy 123.273576 -219.532687) (xy 123.265633 -219.585391)
			(xy 123.249923 -219.636321) (xy 123.226797 -219.684342) (xy 123.196773 -219.728379) (xy 123.160521 -219.76745)
			(xy 123.11885 -219.800681) (xy 123.072692 -219.82733) (xy 123.023078 -219.846802) (xy 122.971116 -219.858662)
			(xy 122.917966 -219.862646) (xy 122.864816 -219.858662) (xy 122.812854 -219.846802) (xy 122.76324 -219.82733)
			(xy 122.717082 -219.800681) (xy 122.675411 -219.76745) (xy 122.639159 -219.728379) (xy 122.609135 -219.684342)
			(xy 122.586009 -219.636321) (xy 122.570299 -219.585391) (xy 122.562356 -219.532687) (xy 122.333776 -219.532687)
			(xy 122.325833 -219.585391) (xy 122.310123 -219.636321) (xy 122.286997 -219.684342) (xy 122.256973 -219.728379)
			(xy 122.220721 -219.76745) (xy 122.17905 -219.800681) (xy 122.132892 -219.82733) (xy 122.083278 -219.846802)
			(xy 122.031316 -219.858662) (xy 121.978166 -219.862646) (xy 121.925016 -219.858662) (xy 121.873054 -219.846802)
			(xy 121.82344 -219.82733) (xy 121.777282 -219.800681) (xy 121.735611 -219.76745) (xy 121.699359 -219.728379)
			(xy 121.669335 -219.684342) (xy 121.646209 -219.636321) (xy 121.630499 -219.585391) (xy 121.622556 -219.532687)
			(xy 121.393976 -219.532687) (xy 121.386033 -219.585391) (xy 121.370323 -219.636321) (xy 121.347197 -219.684342)
			(xy 121.317173 -219.728379) (xy 121.280921 -219.76745) (xy 121.23925 -219.800681) (xy 121.193092 -219.82733)
			(xy 121.143478 -219.846802) (xy 121.091516 -219.858662) (xy 121.038366 -219.862646) (xy 120.985216 -219.858662)
			(xy 120.933254 -219.846802) (xy 120.88364 -219.82733) (xy 120.837482 -219.800681) (xy 120.795811 -219.76745)
			(xy 120.759559 -219.728379) (xy 120.729535 -219.684342) (xy 120.706409 -219.636321) (xy 120.690699 -219.585391)
			(xy 120.682756 -219.532687) (xy 120.454176 -219.532687) (xy 120.446233 -219.585391) (xy 120.430523 -219.636321)
			(xy 120.407397 -219.684342) (xy 120.377373 -219.728379) (xy 120.341121 -219.76745) (xy 120.29945 -219.800681)
			(xy 120.253292 -219.82733) (xy 120.203678 -219.846802) (xy 120.151716 -219.858662) (xy 120.098566 -219.862646)
			(xy 120.045416 -219.858662) (xy 119.993454 -219.846802) (xy 119.94384 -219.82733) (xy 119.897682 -219.800681)
			(xy 119.856011 -219.76745) (xy 119.819759 -219.728379) (xy 119.789735 -219.684342) (xy 119.766609 -219.636321)
			(xy 119.750899 -219.585391) (xy 119.742956 -219.532687) (xy 119.514376 -219.532687) (xy 119.506433 -219.585391)
			(xy 119.490723 -219.636321) (xy 119.467597 -219.684342) (xy 119.437573 -219.728379) (xy 119.401321 -219.76745)
			(xy 119.35965 -219.800681) (xy 119.313492 -219.82733) (xy 119.263878 -219.846802) (xy 119.211916 -219.858662)
			(xy 119.158766 -219.862646) (xy 119.105616 -219.858662) (xy 119.053654 -219.846802) (xy 119.00404 -219.82733)
			(xy 118.957882 -219.800681) (xy 118.916211 -219.76745) (xy 118.879959 -219.728379) (xy 118.849935 -219.684342)
			(xy 118.826809 -219.636321) (xy 118.811099 -219.585391) (xy 118.803156 -219.532687) (xy 118.574576 -219.532687)
			(xy 118.566633 -219.585391) (xy 118.550923 -219.636321) (xy 118.527797 -219.684342) (xy 118.497773 -219.728379)
			(xy 118.461521 -219.76745) (xy 118.41985 -219.800681) (xy 118.373692 -219.82733) (xy 118.324078 -219.846802)
			(xy 118.272116 -219.858662) (xy 118.218966 -219.862646) (xy 118.165816 -219.858662) (xy 118.113854 -219.846802)
			(xy 118.06424 -219.82733) (xy 118.018082 -219.800681) (xy 117.976411 -219.76745) (xy 117.940159 -219.728379)
			(xy 117.910135 -219.684342) (xy 117.887009 -219.636321) (xy 117.871299 -219.585391) (xy 117.863356 -219.532687)
			(xy 117.634776 -219.532687) (xy 117.626833 -219.585391) (xy 117.611123 -219.636321) (xy 117.587997 -219.684342)
			(xy 117.557973 -219.728379) (xy 117.521721 -219.76745) (xy 117.48005 -219.800681) (xy 117.433892 -219.82733)
			(xy 117.384278 -219.846802) (xy 117.332316 -219.858662) (xy 117.279166 -219.862646) (xy 117.226016 -219.858662)
			(xy 117.174054 -219.846802) (xy 117.12444 -219.82733) (xy 117.078282 -219.800681) (xy 117.036611 -219.76745)
			(xy 117.000359 -219.728379) (xy 116.970335 -219.684342) (xy 116.947209 -219.636321) (xy 116.931499 -219.585391)
			(xy 116.923556 -219.532687) (xy 116.693994 -219.532687) (xy 116.692011 -219.559151) (xy 116.68015 -219.611114)
			(xy 116.660676 -219.660729) (xy 116.634024 -219.706887) (xy 116.600791 -219.748557) (xy 116.561718 -219.784809)
			(xy 116.517677 -219.814831) (xy 116.469654 -219.837953) (xy 116.418721 -219.85366) (xy 116.366016 -219.861599)
			(xy 116.339366 -219.862146) (xy 116.315463 -219.861759) (xy 116.268085 -219.855366) (xy 116.221987 -219.8427)
			(xy 116.177994 -219.823987) (xy 116.157248 -219.812108) (xy 116.14553 -219.805587) (xy 116.119726 -219.798317)
			(xy 116.092919 -219.798019) (xy 116.06696 -219.804715) (xy 116.043641 -219.817942) (xy 116.024573 -219.836787)
			(xy 116.011072 -219.859948) (xy 116.004071 -219.885826) (xy 116.003578 -219.89923) (xy 116.003578 -219.988384)
			(xy 116.031264 -220.002608) (xy 116.05432 -220.014877) (xy 116.096885 -220.045139) (xy 116.134575 -220.081293)
			(xy 116.16658 -220.122564) (xy 116.192214 -220.168066) (xy 116.210928 -220.216824) (xy 116.222321 -220.267793)
			(xy 116.226146 -220.319854) (xy 116.47932 -220.319854) (xy 116.479828 -220.293947) (xy 116.487934 -220.24277)
			(xy 116.503946 -220.193491) (xy 116.527469 -220.147324) (xy 116.557925 -220.105405) (xy 116.594563 -220.068767)
			(xy 116.636482 -220.038311) (xy 116.682649 -220.014788) (xy 116.731928 -219.998776) (xy 116.783105 -219.99067)
			(xy 116.834919 -219.99067) (xy 116.886096 -219.998776) (xy 116.935375 -220.014788) (xy 116.981542 -220.038311)
			(xy 117.023461 -220.068767) (xy 117.060099 -220.105405) (xy 117.090555 -220.147324) (xy 117.114078 -220.193491)
			(xy 117.13009 -220.24277) (xy 117.138196 -220.293947) (xy 117.138704 -220.319854) (xy 117.138116 -220.346503)
			(xy 117.393456 -220.346503) (xy 117.393456 -220.293205) (xy 117.401399 -220.240501) (xy 117.417109 -220.189571)
			(xy 117.440235 -220.14155) (xy 117.470259 -220.097513) (xy 117.506511 -220.058442) (xy 117.548182 -220.025211)
			(xy 117.59434 -219.998562) (xy 117.643954 -219.97909) (xy 117.695916 -219.96723) (xy 117.749066 -219.963247)
			(xy 117.802216 -219.96723) (xy 117.854178 -219.97909) (xy 117.903792 -219.998562) (xy 117.94995 -220.025211)
			(xy 117.991621 -220.058442) (xy 118.027873 -220.097513) (xy 118.057897 -220.14155) (xy 118.081023 -220.189571)
			(xy 118.096733 -220.240501) (xy 118.104676 -220.293205) (xy 118.105174 -220.319854) (xy 118.35892 -220.319854)
			(xy 118.359428 -220.293947) (xy 118.367534 -220.24277) (xy 118.383546 -220.193491) (xy 118.407069 -220.147324)
			(xy 118.437525 -220.105405) (xy 118.474163 -220.068767) (xy 118.516082 -220.038311) (xy 118.562249 -220.014788)
			(xy 118.611528 -219.998776) (xy 118.662705 -219.99067) (xy 118.714519 -219.99067) (xy 118.765696 -219.998776)
			(xy 118.814975 -220.014788) (xy 118.861142 -220.038311) (xy 118.903061 -220.068767) (xy 118.939699 -220.105405)
			(xy 118.970155 -220.147324) (xy 118.993678 -220.193491) (xy 119.00969 -220.24277) (xy 119.017796 -220.293947)
			(xy 119.018304 -220.319854) (xy 119.017716 -220.346503) (xy 119.273056 -220.346503) (xy 119.273056 -220.293205)
			(xy 119.280999 -220.240501) (xy 119.296709 -220.189571) (xy 119.319835 -220.14155) (xy 119.349859 -220.097513)
			(xy 119.386111 -220.058442) (xy 119.427782 -220.025211) (xy 119.47394 -219.998562) (xy 119.523554 -219.97909)
			(xy 119.575516 -219.96723) (xy 119.628666 -219.963247) (xy 119.681816 -219.96723) (xy 119.733778 -219.97909)
			(xy 119.783392 -219.998562) (xy 119.82955 -220.025211) (xy 119.871221 -220.058442) (xy 119.907473 -220.097513)
			(xy 119.937497 -220.14155) (xy 119.960623 -220.189571) (xy 119.976333 -220.240501) (xy 119.984276 -220.293205)
			(xy 119.984774 -220.319854) (xy 120.23852 -220.319854) (xy 120.239028 -220.293947) (xy 120.247134 -220.24277)
			(xy 120.263146 -220.193491) (xy 120.286669 -220.147324) (xy 120.317125 -220.105405) (xy 120.353763 -220.068767)
			(xy 120.395682 -220.038311) (xy 120.441849 -220.014788) (xy 120.491128 -219.998776) (xy 120.542305 -219.99067)
			(xy 120.594119 -219.99067) (xy 120.645296 -219.998776) (xy 120.694575 -220.014788) (xy 120.740742 -220.038311)
			(xy 120.782661 -220.068767) (xy 120.819299 -220.105405) (xy 120.849755 -220.147324) (xy 120.873278 -220.193491)
			(xy 120.88929 -220.24277) (xy 120.897396 -220.293947) (xy 120.897904 -220.319854) (xy 120.897316 -220.346503)
			(xy 121.152656 -220.346503) (xy 121.152656 -220.293205) (xy 121.160599 -220.240501) (xy 121.176309 -220.189571)
			(xy 121.199435 -220.14155) (xy 121.229459 -220.097513) (xy 121.265711 -220.058442) (xy 121.307382 -220.025211)
			(xy 121.35354 -219.998562) (xy 121.403154 -219.97909) (xy 121.455116 -219.96723) (xy 121.508266 -219.963247)
			(xy 121.561416 -219.96723) (xy 121.613378 -219.97909) (xy 121.662992 -219.998562) (xy 121.70915 -220.025211)
			(xy 121.750821 -220.058442) (xy 121.787073 -220.097513) (xy 121.817097 -220.14155) (xy 121.840223 -220.189571)
			(xy 121.855933 -220.240501) (xy 121.863876 -220.293205) (xy 121.864374 -220.319854) (xy 122.11812 -220.319854)
			(xy 122.118628 -220.293947) (xy 122.126734 -220.24277) (xy 122.142746 -220.193491) (xy 122.166269 -220.147324)
			(xy 122.196725 -220.105405) (xy 122.233363 -220.068767) (xy 122.275282 -220.038311) (xy 122.321449 -220.014788)
			(xy 122.370728 -219.998776) (xy 122.421905 -219.99067) (xy 122.473719 -219.99067) (xy 122.524896 -219.998776)
			(xy 122.574175 -220.014788) (xy 122.620342 -220.038311) (xy 122.662261 -220.068767) (xy 122.698899 -220.105405)
			(xy 122.729355 -220.147324) (xy 122.752878 -220.193491) (xy 122.76889 -220.24277) (xy 122.776996 -220.293947)
			(xy 122.777504 -220.319854) (xy 122.776916 -220.346503) (xy 123.032256 -220.346503) (xy 123.032256 -220.293205)
			(xy 123.040199 -220.240501) (xy 123.055909 -220.189571) (xy 123.079035 -220.14155) (xy 123.109059 -220.097513)
			(xy 123.145311 -220.058442) (xy 123.186982 -220.025211) (xy 123.23314 -219.998562) (xy 123.282754 -219.97909)
			(xy 123.334716 -219.96723) (xy 123.387866 -219.963247) (xy 123.441016 -219.96723) (xy 123.492978 -219.97909)
			(xy 123.542592 -219.998562) (xy 123.58875 -220.025211) (xy 123.630421 -220.058442) (xy 123.666673 -220.097513)
			(xy 123.696697 -220.14155) (xy 123.719823 -220.189571) (xy 123.735533 -220.240501) (xy 123.743476 -220.293205)
			(xy 123.743974 -220.319854) (xy 123.99772 -220.319854) (xy 123.998228 -220.293947) (xy 124.006334 -220.24277)
			(xy 124.022346 -220.193491) (xy 124.045869 -220.147324) (xy 124.076325 -220.105405) (xy 124.112963 -220.068767)
			(xy 124.154882 -220.038311) (xy 124.201049 -220.014788) (xy 124.250328 -219.998776) (xy 124.301505 -219.99067)
			(xy 124.353319 -219.99067) (xy 124.404496 -219.998776) (xy 124.453775 -220.014788) (xy 124.499942 -220.038311)
			(xy 124.541861 -220.068767) (xy 124.578499 -220.105405) (xy 124.608955 -220.147324) (xy 124.632478 -220.193491)
			(xy 124.64849 -220.24277) (xy 124.656596 -220.293947) (xy 124.657104 -220.319854) (xy 124.656516 -220.346503)
			(xy 124.911856 -220.346503) (xy 124.911856 -220.293205) (xy 124.919799 -220.240501) (xy 124.935509 -220.189571)
			(xy 124.958635 -220.14155) (xy 124.988659 -220.097513) (xy 125.024911 -220.058442) (xy 125.066582 -220.025211)
			(xy 125.11274 -219.998562) (xy 125.162354 -219.97909) (xy 125.214316 -219.96723) (xy 125.267466 -219.963247)
			(xy 125.320616 -219.96723) (xy 125.372578 -219.97909) (xy 125.422192 -219.998562) (xy 125.46835 -220.025211)
			(xy 125.510021 -220.058442) (xy 125.546273 -220.097513) (xy 125.576297 -220.14155) (xy 125.599423 -220.189571)
			(xy 125.615133 -220.240501) (xy 125.623076 -220.293205) (xy 125.623574 -220.319854) (xy 125.623076 -220.346503)
			(xy 125.615133 -220.399207) (xy 125.599423 -220.450137) (xy 125.576297 -220.498158) (xy 125.546273 -220.542195)
			(xy 125.510021 -220.581266) (xy 125.46835 -220.614497) (xy 125.422192 -220.641146) (xy 125.372578 -220.660618)
			(xy 125.320616 -220.672478) (xy 125.267466 -220.676462) (xy 125.214316 -220.672478) (xy 125.162354 -220.660618)
			(xy 125.11274 -220.641146) (xy 125.066582 -220.614497) (xy 125.024911 -220.581266) (xy 124.988659 -220.542195)
			(xy 124.958635 -220.498158) (xy 124.935509 -220.450137) (xy 124.919799 -220.399207) (xy 124.911856 -220.346503)
			(xy 124.656516 -220.346503) (xy 124.656494 -220.347507) (xy 124.647171 -220.402025) (xy 124.638562 -220.428312)
			(xy 124.630942 -220.45041) (xy 124.836174 -220.805756) (xy 124.859034 -220.810074) (xy 124.883845 -220.815229)
			(xy 124.931584 -220.832223) (xy 124.976162 -220.856322) (xy 125.016527 -220.886957) (xy 125.05173 -220.923408)
			(xy 125.08094 -220.964816) (xy 125.103472 -221.010206) (xy 125.118792 -221.058509) (xy 125.126542 -221.108587)
			(xy 125.127004 -221.133924) (xy 125.126496 -221.159811) (xy 125.118397 -221.210949) (xy 125.102398 -221.260189)
			(xy 125.078892 -221.306321) (xy 125.04846 -221.348208) (xy 125.01185 -221.384818) (xy 124.969963 -221.41525)
			(xy 124.923831 -221.438756) (xy 124.874591 -221.454755) (xy 124.823453 -221.462854) (xy 124.771679 -221.462854)
			(xy 124.720541 -221.454755) (xy 124.671301 -221.438756) (xy 124.625169 -221.41525) (xy 124.583282 -221.384818)
			(xy 124.546672 -221.348208) (xy 124.51624 -221.306321) (xy 124.492734 -221.260189) (xy 124.476735 -221.210949)
			(xy 124.468636 -221.159811) (xy 124.468128 -221.133924) (xy 124.468667 -221.106216) (xy 124.477856 -221.05157)
			(xy 124.486416 -221.025212) (xy 124.49429 -221.003114) (xy 124.289312 -220.648022) (xy 124.266452 -220.643704)
			(xy 124.2416 -220.63857) (xy 124.193753 -220.621668) (xy 124.149062 -220.597632) (xy 124.108584 -220.567029)
			(xy 124.073274 -220.530584) (xy 124.043968 -220.489157) (xy 124.021357 -220.443728) (xy 124.005977 -220.39537)
			(xy 123.998191 -220.345226) (xy 123.99772 -220.319854) (xy 123.743974 -220.319854) (xy 123.743476 -220.346503)
			(xy 123.735533 -220.399207) (xy 123.719823 -220.450137) (xy 123.696697 -220.498158) (xy 123.666673 -220.542195)
			(xy 123.630421 -220.581266) (xy 123.58875 -220.614497) (xy 123.542592 -220.641146) (xy 123.492978 -220.660618)
			(xy 123.441016 -220.672478) (xy 123.387866 -220.676462) (xy 123.334716 -220.672478) (xy 123.282754 -220.660618)
			(xy 123.23314 -220.641146) (xy 123.186982 -220.614497) (xy 123.145311 -220.581266) (xy 123.109059 -220.542195)
			(xy 123.079035 -220.498158) (xy 123.055909 -220.450137) (xy 123.040199 -220.399207) (xy 123.032256 -220.346503)
			(xy 122.776916 -220.346503) (xy 122.776894 -220.347507) (xy 122.767571 -220.402025) (xy 122.758962 -220.428312)
			(xy 122.751342 -220.45041) (xy 122.956574 -220.805756) (xy 122.979434 -220.810074) (xy 123.004245 -220.815229)
			(xy 123.051984 -220.832223) (xy 123.096562 -220.856322) (xy 123.136927 -220.886957) (xy 123.17213 -220.923408)
			(xy 123.20134 -220.964816) (xy 123.223872 -221.010206) (xy 123.239192 -221.058509) (xy 123.246942 -221.108587)
			(xy 123.247404 -221.133924) (xy 123.246896 -221.159811) (xy 123.238797 -221.210949) (xy 123.222798 -221.260189)
			(xy 123.199292 -221.306321) (xy 123.16886 -221.348208) (xy 123.13225 -221.384818) (xy 123.090363 -221.41525)
			(xy 123.044231 -221.438756) (xy 122.994991 -221.454755) (xy 122.943853 -221.462854) (xy 122.892079 -221.462854)
			(xy 122.840941 -221.454755) (xy 122.791701 -221.438756) (xy 122.745569 -221.41525) (xy 122.703682 -221.384818)
			(xy 122.667072 -221.348208) (xy 122.63664 -221.306321) (xy 122.613134 -221.260189) (xy 122.597135 -221.210949)
			(xy 122.589036 -221.159811) (xy 122.588528 -221.133924) (xy 122.589067 -221.106216) (xy 122.598256 -221.05157)
			(xy 122.606816 -221.025212) (xy 122.61469 -221.003114) (xy 122.409712 -220.648022) (xy 122.386852 -220.643704)
			(xy 122.362 -220.63857) (xy 122.314153 -220.621668) (xy 122.269462 -220.597632) (xy 122.228984 -220.567029)
			(xy 122.193674 -220.530584) (xy 122.164368 -220.489157) (xy 122.141757 -220.443728) (xy 122.126377 -220.39537)
			(xy 122.118591 -220.345226) (xy 122.11812 -220.319854) (xy 121.864374 -220.319854) (xy 121.863876 -220.346503)
			(xy 121.855933 -220.399207) (xy 121.840223 -220.450137) (xy 121.817097 -220.498158) (xy 121.787073 -220.542195)
			(xy 121.750821 -220.581266) (xy 121.70915 -220.614497) (xy 121.662992 -220.641146) (xy 121.613378 -220.660618)
			(xy 121.561416 -220.672478) (xy 121.508266 -220.676462) (xy 121.455116 -220.672478) (xy 121.403154 -220.660618)
			(xy 121.35354 -220.641146) (xy 121.307382 -220.614497) (xy 121.265711 -220.581266) (xy 121.229459 -220.542195)
			(xy 121.199435 -220.498158) (xy 121.176309 -220.450137) (xy 121.160599 -220.399207) (xy 121.152656 -220.346503)
			(xy 120.897316 -220.346503) (xy 120.897294 -220.347507) (xy 120.887971 -220.402025) (xy 120.879362 -220.428312)
			(xy 120.871742 -220.45041) (xy 121.076974 -220.805756) (xy 121.099834 -220.810074) (xy 121.124645 -220.815229)
			(xy 121.172384 -220.832223) (xy 121.216962 -220.856322) (xy 121.257327 -220.886957) (xy 121.29253 -220.923408)
			(xy 121.32174 -220.964816) (xy 121.344272 -221.010206) (xy 121.359592 -221.058509) (xy 121.367342 -221.108587)
			(xy 121.367804 -221.133924) (xy 121.367296 -221.159811) (xy 121.359197 -221.210949) (xy 121.343198 -221.260189)
			(xy 121.319692 -221.306321) (xy 121.28926 -221.348208) (xy 121.25265 -221.384818) (xy 121.210763 -221.41525)
			(xy 121.164631 -221.438756) (xy 121.115391 -221.454755) (xy 121.064253 -221.462854) (xy 121.012479 -221.462854)
			(xy 120.961341 -221.454755) (xy 120.912101 -221.438756) (xy 120.865969 -221.41525) (xy 120.824082 -221.384818)
			(xy 120.787472 -221.348208) (xy 120.75704 -221.306321) (xy 120.733534 -221.260189) (xy 120.717535 -221.210949)
			(xy 120.709436 -221.159811) (xy 120.708928 -221.133924) (xy 120.709467 -221.106216) (xy 120.718656 -221.05157)
			(xy 120.727216 -221.025212) (xy 120.73509 -221.003114) (xy 120.530112 -220.648022) (xy 120.507252 -220.643704)
			(xy 120.4824 -220.63857) (xy 120.434553 -220.621668) (xy 120.389862 -220.597632) (xy 120.349384 -220.567029)
			(xy 120.314074 -220.530584) (xy 120.284768 -220.489157) (xy 120.262157 -220.443728) (xy 120.246777 -220.39537)
			(xy 120.238991 -220.345226) (xy 120.23852 -220.319854) (xy 119.984774 -220.319854) (xy 119.984276 -220.346503)
			(xy 119.976333 -220.399207) (xy 119.960623 -220.450137) (xy 119.937497 -220.498158) (xy 119.907473 -220.542195)
			(xy 119.871221 -220.581266) (xy 119.82955 -220.614497) (xy 119.783392 -220.641146) (xy 119.733778 -220.660618)
			(xy 119.681816 -220.672478) (xy 119.628666 -220.676462) (xy 119.575516 -220.672478) (xy 119.523554 -220.660618)
			(xy 119.47394 -220.641146) (xy 119.427782 -220.614497) (xy 119.386111 -220.581266) (xy 119.349859 -220.542195)
			(xy 119.319835 -220.498158) (xy 119.296709 -220.450137) (xy 119.280999 -220.399207) (xy 119.273056 -220.346503)
			(xy 119.017716 -220.346503) (xy 119.017694 -220.347507) (xy 119.008371 -220.402025) (xy 118.999762 -220.428312)
			(xy 118.992142 -220.45041) (xy 119.197374 -220.805756) (xy 119.220234 -220.810074) (xy 119.245045 -220.815229)
			(xy 119.292784 -220.832223) (xy 119.337362 -220.856322) (xy 119.377727 -220.886957) (xy 119.41293 -220.923408)
			(xy 119.44214 -220.964816) (xy 119.464672 -221.010206) (xy 119.479992 -221.058509) (xy 119.487742 -221.108587)
			(xy 119.488204 -221.133924) (xy 119.487696 -221.159811) (xy 119.487575 -221.160573) (xy 119.742702 -221.160573)
			(xy 119.742702 -221.107275) (xy 119.750645 -221.054571) (xy 119.766355 -221.003641) (xy 119.789481 -220.95562)
			(xy 119.819505 -220.911583) (xy 119.855757 -220.872512) (xy 119.897428 -220.839281) (xy 119.943586 -220.812632)
			(xy 119.9932 -220.79316) (xy 120.045162 -220.7813) (xy 120.098312 -220.777317) (xy 120.151462 -220.7813)
			(xy 120.203424 -220.79316) (xy 120.253038 -220.812632) (xy 120.299196 -220.839281) (xy 120.340867 -220.872512)
			(xy 120.377119 -220.911583) (xy 120.407143 -220.95562) (xy 120.430269 -221.003641) (xy 120.445979 -221.054571)
			(xy 120.453922 -221.107275) (xy 120.45442 -221.133924) (xy 120.453922 -221.160573) (xy 120.445979 -221.213277)
			(xy 120.430269 -221.264207) (xy 120.407143 -221.312228) (xy 120.377119 -221.356265) (xy 120.340867 -221.395336)
			(xy 120.299196 -221.428567) (xy 120.253038 -221.455216) (xy 120.203424 -221.474688) (xy 120.151462 -221.486548)
			(xy 120.098312 -221.490532) (xy 120.045162 -221.486548) (xy 119.9932 -221.474688) (xy 119.943586 -221.455216)
			(xy 119.897428 -221.428567) (xy 119.855757 -221.395336) (xy 119.819505 -221.356265) (xy 119.789481 -221.312228)
			(xy 119.766355 -221.264207) (xy 119.750645 -221.213277) (xy 119.742702 -221.160573) (xy 119.487575 -221.160573)
			(xy 119.479597 -221.210949) (xy 119.463598 -221.260189) (xy 119.440092 -221.306321) (xy 119.40966 -221.348208)
			(xy 119.37305 -221.384818) (xy 119.331163 -221.41525) (xy 119.285031 -221.438756) (xy 119.235791 -221.454755)
			(xy 119.184653 -221.462854) (xy 119.132879 -221.462854) (xy 119.081741 -221.454755) (xy 119.032501 -221.438756)
			(xy 118.986369 -221.41525) (xy 118.944482 -221.384818) (xy 118.907872 -221.348208) (xy 118.87744 -221.306321)
			(xy 118.853934 -221.260189) (xy 118.837935 -221.210949) (xy 118.829836 -221.159811) (xy 118.829328 -221.133924)
			(xy 118.829867 -221.106216) (xy 118.839056 -221.05157) (xy 118.847616 -221.025212) (xy 118.85549 -221.003114)
			(xy 118.650512 -220.648022) (xy 118.627652 -220.643704) (xy 118.6028 -220.63857) (xy 118.554953 -220.621668)
			(xy 118.510262 -220.597632) (xy 118.469784 -220.567029) (xy 118.434474 -220.530584) (xy 118.405168 -220.489157)
			(xy 118.382557 -220.443728) (xy 118.367177 -220.39537) (xy 118.359391 -220.345226) (xy 118.35892 -220.319854)
			(xy 118.105174 -220.319854) (xy 118.104676 -220.346503) (xy 118.096733 -220.399207) (xy 118.081023 -220.450137)
			(xy 118.057897 -220.498158) (xy 118.027873 -220.542195) (xy 117.991621 -220.581266) (xy 117.94995 -220.614497)
			(xy 117.903792 -220.641146) (xy 117.854178 -220.660618) (xy 117.802216 -220.672478) (xy 117.749066 -220.676462)
			(xy 117.695916 -220.672478) (xy 117.643954 -220.660618) (xy 117.59434 -220.641146) (xy 117.548182 -220.614497)
			(xy 117.506511 -220.581266) (xy 117.470259 -220.542195) (xy 117.440235 -220.498158) (xy 117.417109 -220.450137)
			(xy 117.401399 -220.399207) (xy 117.393456 -220.346503) (xy 117.138116 -220.346503) (xy 117.138094 -220.347507)
			(xy 117.128771 -220.402025) (xy 117.120162 -220.428312) (xy 117.112542 -220.45041) (xy 117.317774 -220.805756)
			(xy 117.340634 -220.810074) (xy 117.365445 -220.815229) (xy 117.413184 -220.832223) (xy 117.457762 -220.856322)
			(xy 117.498127 -220.886957) (xy 117.53333 -220.923408) (xy 117.56254 -220.964816) (xy 117.585072 -221.010206)
			(xy 117.600392 -221.058509) (xy 117.608142 -221.108587) (xy 117.608604 -221.133924) (xy 117.608096 -221.159811)
			(xy 117.599997 -221.210949) (xy 117.583998 -221.260189) (xy 117.560492 -221.306321) (xy 117.53006 -221.348208)
			(xy 117.49345 -221.384818) (xy 117.451563 -221.41525) (xy 117.405431 -221.438756) (xy 117.356191 -221.454755)
			(xy 117.305053 -221.462854) (xy 117.253279 -221.462854) (xy 117.202141 -221.454755) (xy 117.152901 -221.438756)
			(xy 117.106769 -221.41525) (xy 117.064882 -221.384818) (xy 117.028272 -221.348208) (xy 116.99784 -221.306321)
			(xy 116.974334 -221.260189) (xy 116.958335 -221.210949) (xy 116.950236 -221.159811) (xy 116.949728 -221.133924)
			(xy 116.950267 -221.106216) (xy 116.959456 -221.05157) (xy 116.968016 -221.025212) (xy 116.97589 -221.003114)
			(xy 116.770912 -220.648022) (xy 116.748052 -220.643704) (xy 116.7232 -220.63857) (xy 116.675353 -220.621668)
			(xy 116.630662 -220.597632) (xy 116.590184 -220.567029) (xy 116.554874 -220.530584) (xy 116.525568 -220.489157)
			(xy 116.502957 -220.443728) (xy 116.487577 -220.39537) (xy 116.479791 -220.345226) (xy 116.47932 -220.319854)
			(xy 116.226146 -220.319854) (xy 116.226148 -220.319879) (xy 116.222327 -220.371966) (xy 116.21094 -220.422935)
			(xy 116.192232 -220.471696) (xy 116.166603 -220.517201) (xy 116.134603 -220.558476) (xy 116.096918 -220.594635)
			(xy 116.054356 -220.624902) (xy 116.031264 -220.6371) (xy 116.003578 -220.651324) (xy 116.003578 -220.771974)
			(xy 116.004013 -220.785617) (xy 116.011233 -220.811931) (xy 116.025165 -220.835393) (xy 116.044813 -220.854327)
			(xy 116.068775 -220.867381) (xy 116.095338 -220.873622) (xy 116.122606 -220.872605) (xy 116.14863 -220.864402)
			(xy 116.160296 -220.857318) (xy 116.180392 -220.844785) (xy 116.223412 -220.824979) (xy 116.268821 -220.811523)
			(xy 116.315686 -220.804694) (xy 116.339366 -220.804232) (xy 116.365271 -220.804712) (xy 116.416442 -220.812815)
			(xy 116.465715 -220.828828) (xy 116.511875 -220.852355) (xy 116.553783 -220.882816) (xy 116.590407 -220.919462)
			(xy 116.620845 -220.961388) (xy 116.644345 -221.007561) (xy 116.660329 -221.056843) (xy 116.668403 -221.108019)
			(xy 116.668804 -221.133924) (xy 116.668335 -221.159296) (xy 116.660552 -221.20944) (xy 116.645173 -221.257797)
			(xy 116.622563 -221.303226) (xy 116.593255 -221.34465) (xy 116.557943 -221.381092) (xy 116.517462 -221.41169)
			(xy 116.472768 -221.43572) (xy 116.424919 -221.452614) (xy 116.400072 -221.457774) (xy 116.377212 -221.462092)
			(xy 116.172488 -221.81693) (xy 116.180362 -221.838774) (xy 116.189005 -221.865183) (xy 116.198321 -221.919959)
			(xy 116.198904 -221.94774) (xy 117.41912 -221.94774) (xy 117.419571 -221.922394) (xy 117.427352 -221.872302)
			(xy 117.442706 -221.82399) (xy 117.465272 -221.778597) (xy 117.494518 -221.737192) (xy 117.529755 -221.700749)
			(xy 117.570154 -221.670127) (xy 117.614762 -221.646047) (xy 117.66253 -221.629076) (xy 117.687344 -221.62389)
			(xy 117.710204 -221.619572) (xy 117.915436 -221.264226) (xy 117.907562 -221.242128) (xy 117.899098 -221.215883)
			(xy 117.890025 -221.161495) (xy 117.889528 -221.133924) (xy 117.890036 -221.108037) (xy 117.898135 -221.056899)
			(xy 117.914134 -221.007659) (xy 117.93764 -220.961527) (xy 117.968072 -220.91964) (xy 118.004682 -220.88303)
			(xy 118.046569 -220.852598) (xy 118.092701 -220.829092) (xy 118.141941 -220.813093) (xy 118.193079 -220.804994)
			(xy 118.244853 -220.804994) (xy 118.295991 -220.813093) (xy 118.345231 -220.829092) (xy 118.391363 -220.852598)
			(xy 118.43325 -220.88303) (xy 118.46986 -220.91964) (xy 118.500292 -220.961527) (xy 118.523798 -221.007659)
			(xy 118.539797 -221.056899) (xy 118.547896 -221.108037) (xy 118.548404 -221.133924) (xy 118.547948 -221.159299)
			(xy 118.540176 -221.20945) (xy 118.524804 -221.257815) (xy 118.502197 -221.303251) (xy 118.472889 -221.344682)
			(xy 118.437573 -221.381128) (xy 118.397085 -221.411727) (xy 118.352384 -221.435754) (xy 118.304526 -221.452641)
			(xy 118.279672 -221.457774) (xy 118.256812 -221.462092) (xy 118.052088 -221.81693) (xy 118.059962 -221.838774)
			(xy 118.068619 -221.865179) (xy 118.077932 -221.919958) (xy 118.078504 -221.94774) (xy 118.077996 -221.973647)
			(xy 118.077878 -221.974389) (xy 119.273056 -221.974389) (xy 119.273056 -221.921091) (xy 119.280999 -221.868387)
			(xy 119.296709 -221.817457) (xy 119.319835 -221.769436) (xy 119.349859 -221.725399) (xy 119.386111 -221.686328)
			(xy 119.427782 -221.653097) (xy 119.47394 -221.626448) (xy 119.523554 -221.606976) (xy 119.575516 -221.595116)
			(xy 119.628666 -221.591133) (xy 119.681816 -221.595116) (xy 119.733778 -221.606976) (xy 119.783392 -221.626448)
			(xy 119.82955 -221.653097) (xy 119.871221 -221.686328) (xy 119.907473 -221.725399) (xy 119.937497 -221.769436)
			(xy 119.960623 -221.817457) (xy 119.976333 -221.868387) (xy 119.984276 -221.921091) (xy 119.984774 -221.94774)
			(xy 121.17832 -221.94774) (xy 121.178771 -221.922394) (xy 121.186552 -221.872302) (xy 121.201906 -221.82399)
			(xy 121.224472 -221.778597) (xy 121.253718 -221.737192) (xy 121.288955 -221.700749) (xy 121.329354 -221.670127)
			(xy 121.373962 -221.646047) (xy 121.42173 -221.629076) (xy 121.446544 -221.62389) (xy 121.469404 -221.619572)
			(xy 121.674636 -221.264226) (xy 121.666762 -221.242128) (xy 121.658298 -221.215883) (xy 121.649225 -221.161495)
			(xy 121.648728 -221.133924) (xy 121.649236 -221.108037) (xy 121.657335 -221.056899) (xy 121.673334 -221.007659)
			(xy 121.69684 -220.961527) (xy 121.727272 -220.91964) (xy 121.763882 -220.88303) (xy 121.805769 -220.852598)
			(xy 121.851901 -220.829092) (xy 121.901141 -220.813093) (xy 121.952279 -220.804994) (xy 122.004053 -220.804994)
			(xy 122.055191 -220.813093) (xy 122.104431 -220.829092) (xy 122.150563 -220.852598) (xy 122.19245 -220.88303)
			(xy 122.22906 -220.91964) (xy 122.259492 -220.961527) (xy 122.282998 -221.007659) (xy 122.298997 -221.056899)
			(xy 122.307096 -221.108037) (xy 122.307604 -221.133924) (xy 122.307148 -221.159299) (xy 122.299376 -221.20945)
			(xy 122.284004 -221.257815) (xy 122.261397 -221.303251) (xy 122.232089 -221.344682) (xy 122.196773 -221.381128)
			(xy 122.156285 -221.411727) (xy 122.111584 -221.435754) (xy 122.063726 -221.452641) (xy 122.038872 -221.457774)
			(xy 122.016012 -221.462092) (xy 121.811288 -221.81693) (xy 121.819162 -221.838774) (xy 121.827819 -221.865179)
			(xy 121.837132 -221.919958) (xy 121.837704 -221.94774) (xy 123.05792 -221.94774) (xy 123.058371 -221.922394)
			(xy 123.066152 -221.872302) (xy 123.081506 -221.82399) (xy 123.104072 -221.778597) (xy 123.133318 -221.737192)
			(xy 123.168555 -221.700749) (xy 123.208954 -221.670127) (xy 123.253562 -221.646047) (xy 123.30133 -221.629076)
			(xy 123.326144 -221.62389) (xy 123.349004 -221.619572) (xy 123.554236 -221.264226) (xy 123.546362 -221.242128)
			(xy 123.537898 -221.215883) (xy 123.528825 -221.161495) (xy 123.528328 -221.133924) (xy 123.528836 -221.108037)
			(xy 123.536935 -221.056899) (xy 123.552934 -221.007659) (xy 123.57644 -220.961527) (xy 123.606872 -220.91964)
			(xy 123.643482 -220.88303) (xy 123.685369 -220.852598) (xy 123.731501 -220.829092) (xy 123.780741 -220.813093)
			(xy 123.831879 -220.804994) (xy 123.883653 -220.804994) (xy 123.934791 -220.813093) (xy 123.984031 -220.829092)
			(xy 124.030163 -220.852598) (xy 124.07205 -220.88303) (xy 124.10866 -220.91964) (xy 124.139092 -220.961527)
			(xy 124.162598 -221.007659) (xy 124.178597 -221.056899) (xy 124.186696 -221.108037) (xy 124.187204 -221.133924)
			(xy 124.186748 -221.159299) (xy 124.178976 -221.20945) (xy 124.163604 -221.257815) (xy 124.140997 -221.303251)
			(xy 124.111689 -221.344682) (xy 124.076373 -221.381128) (xy 124.035885 -221.411727) (xy 123.991184 -221.435754)
			(xy 123.943326 -221.452641) (xy 123.918472 -221.457774) (xy 123.895612 -221.462092) (xy 123.690888 -221.81693)
			(xy 123.698762 -221.838774) (xy 123.707419 -221.865179) (xy 123.716732 -221.919958) (xy 123.717304 -221.94774)
			(xy 124.93752 -221.94774) (xy 124.937971 -221.922394) (xy 124.945752 -221.872302) (xy 124.961106 -221.82399)
			(xy 124.983672 -221.778597) (xy 125.012918 -221.737192) (xy 125.048155 -221.700749) (xy 125.088554 -221.670127)
			(xy 125.133162 -221.646047) (xy 125.18093 -221.629076) (xy 125.205744 -221.62389) (xy 125.228604 -221.619572)
			(xy 125.433836 -221.264226) (xy 125.425962 -221.242128) (xy 125.417498 -221.215883) (xy 125.408425 -221.161495)
			(xy 125.407928 -221.133924) (xy 125.408436 -221.108037) (xy 125.416535 -221.056899) (xy 125.432534 -221.007659)
			(xy 125.45604 -220.961527) (xy 125.486472 -220.91964) (xy 125.523082 -220.88303) (xy 125.564969 -220.852598)
			(xy 125.611101 -220.829092) (xy 125.660341 -220.813093) (xy 125.711479 -220.804994) (xy 125.763253 -220.804994)
			(xy 125.814391 -220.813093) (xy 125.863631 -220.829092) (xy 125.909763 -220.852598) (xy 125.95165 -220.88303)
			(xy 125.98826 -220.91964) (xy 126.018692 -220.961527) (xy 126.042198 -221.007659) (xy 126.058197 -221.056899)
			(xy 126.066296 -221.108037) (xy 126.066804 -221.133924) (xy 126.066348 -221.159299) (xy 126.058576 -221.20945)
			(xy 126.043204 -221.257815) (xy 126.020597 -221.303251) (xy 125.991289 -221.344682) (xy 125.955973 -221.381128)
			(xy 125.915485 -221.411727) (xy 125.870784 -221.435754) (xy 125.822926 -221.452641) (xy 125.798072 -221.457774)
			(xy 125.775212 -221.462092) (xy 125.570488 -221.81693) (xy 125.578362 -221.838774) (xy 125.587019 -221.865179)
			(xy 125.596332 -221.919958) (xy 125.596904 -221.94774) (xy 125.596396 -221.973647) (xy 125.58829 -222.024824)
			(xy 125.572278 -222.074103) (xy 125.548755 -222.12027) (xy 125.518299 -222.162189) (xy 125.481661 -222.198827)
			(xy 125.439742 -222.229283) (xy 125.393575 -222.252806) (xy 125.344296 -222.268818) (xy 125.293119 -222.276924)
			(xy 125.241305 -222.276924) (xy 125.190128 -222.268818) (xy 125.140849 -222.252806) (xy 125.094682 -222.229283)
			(xy 125.052763 -222.198827) (xy 125.016125 -222.162189) (xy 124.985669 -222.12027) (xy 124.962146 -222.074103)
			(xy 124.946134 -222.024824) (xy 124.938028 -221.973647) (xy 124.93752 -221.94774) (xy 123.717304 -221.94774)
			(xy 123.716796 -221.973647) (xy 123.70869 -222.024824) (xy 123.692678 -222.074103) (xy 123.669155 -222.12027)
			(xy 123.638699 -222.162189) (xy 123.602061 -222.198827) (xy 123.560142 -222.229283) (xy 123.513975 -222.252806)
			(xy 123.464696 -222.268818) (xy 123.413519 -222.276924) (xy 123.361705 -222.276924) (xy 123.310528 -222.268818)
			(xy 123.261249 -222.252806) (xy 123.215082 -222.229283) (xy 123.173163 -222.198827) (xy 123.136525 -222.162189)
			(xy 123.106069 -222.12027) (xy 123.082546 -222.074103) (xy 123.066534 -222.024824) (xy 123.058428 -221.973647)
			(xy 123.05792 -221.94774) (xy 121.837704 -221.94774) (xy 121.837196 -221.973647) (xy 121.82909 -222.024824)
			(xy 121.813078 -222.074103) (xy 121.789555 -222.12027) (xy 121.759099 -222.162189) (xy 121.722461 -222.198827)
			(xy 121.680542 -222.229283) (xy 121.634375 -222.252806) (xy 121.585096 -222.268818) (xy 121.533919 -222.276924)
			(xy 121.482105 -222.276924) (xy 121.430928 -222.268818) (xy 121.381649 -222.252806) (xy 121.335482 -222.229283)
			(xy 121.293563 -222.198827) (xy 121.256925 -222.162189) (xy 121.226469 -222.12027) (xy 121.202946 -222.074103)
			(xy 121.186934 -222.024824) (xy 121.178828 -221.973647) (xy 121.17832 -221.94774) (xy 119.984774 -221.94774)
			(xy 119.984276 -221.974389) (xy 119.976333 -222.027093) (xy 119.960623 -222.078023) (xy 119.937497 -222.126044)
			(xy 119.907473 -222.170081) (xy 119.871221 -222.209152) (xy 119.82955 -222.242383) (xy 119.783392 -222.269032)
			(xy 119.733778 -222.288504) (xy 119.681816 -222.300364) (xy 119.628666 -222.304348) (xy 119.575516 -222.300364)
			(xy 119.523554 -222.288504) (xy 119.47394 -222.269032) (xy 119.427782 -222.242383) (xy 119.386111 -222.209152)
			(xy 119.349859 -222.170081) (xy 119.319835 -222.126044) (xy 119.296709 -222.078023) (xy 119.280999 -222.027093)
			(xy 119.273056 -221.974389) (xy 118.077878 -221.974389) (xy 118.06989 -222.024824) (xy 118.053878 -222.074103)
			(xy 118.030355 -222.12027) (xy 117.999899 -222.162189) (xy 117.963261 -222.198827) (xy 117.921342 -222.229283)
			(xy 117.875175 -222.252806) (xy 117.825896 -222.268818) (xy 117.774719 -222.276924) (xy 117.722905 -222.276924)
			(xy 117.671728 -222.268818) (xy 117.622449 -222.252806) (xy 117.576282 -222.229283) (xy 117.534363 -222.198827)
			(xy 117.497725 -222.162189) (xy 117.467269 -222.12027) (xy 117.443746 -222.074103) (xy 117.427734 -222.024824)
			(xy 117.419628 -221.973647) (xy 117.41912 -221.94774) (xy 116.198904 -221.94774) (xy 116.198142 -221.968314)
			(xy 116.230751 -222.000593) (xy 116.290826 -222.069956) (xy 116.344622 -222.144295) (xy 116.391726 -222.223044)
			(xy 116.431782 -222.305602) (xy 116.448586 -222.348298) (xy 116.580666 -222.480378) (xy 116.606828 -222.475552)
			(xy 116.651345 -222.467834) (xy 116.741244 -222.458743) (xy 116.831583 -222.456934) (xy 116.921774 -222.462419)
			(xy 117.011229 -222.475162) (xy 117.055392 -222.484696) (xy 117.074469 -222.469778) (xy 117.115893 -222.444695)
			(xy 117.160335 -222.42546) (xy 117.206976 -222.41243) (xy 117.254953 -222.405845) (xy 117.279166 -222.405448)
			(xy 117.303404 -222.405854) (xy 117.351431 -222.412423) (xy 117.398125 -222.425443) (xy 117.442622 -222.444674)
			(xy 117.4841 -222.469762) (xy 117.503194 -222.484696) (xy 117.543587 -222.475973) (xy 117.625327 -222.463783)
			(xy 117.707744 -222.457654) (xy 117.749066 -222.457264) (xy 117.790389 -222.457643) (xy 117.872807 -222.463762)
			(xy 117.954549 -222.475954) (xy 117.994938 -222.484696) (xy 118.014043 -222.469778) (xy 118.055521 -222.444697)
			(xy 118.100016 -222.425469) (xy 118.146706 -222.412448) (xy 118.19473 -222.405875) (xy 118.218966 -222.405448)
			(xy 118.243167 -222.405857) (xy 118.291123 -222.412414) (xy 118.337752 -222.425398) (xy 118.382195 -222.444571)
			(xy 118.423636 -222.469579) (xy 118.44274 -222.484442) (xy 118.491286 -222.474064) (xy 118.589695 -222.460931)
			(xy 118.68888 -222.456577) (xy 118.788061 -222.461034) (xy 118.886456 -222.474269) (xy 118.934992 -222.484696)
			(xy 118.954069 -222.469778) (xy 118.995493 -222.444695) (xy 119.039935 -222.42546) (xy 119.086576 -222.41243)
			(xy 119.134553 -222.405845) (xy 119.158766 -222.405448) (xy 119.183004 -222.405854) (xy 119.231031 -222.412423)
			(xy 119.277725 -222.425443) (xy 119.322222 -222.444674) (xy 119.3637 -222.469762) (xy 119.382794 -222.484696)
			(xy 119.423187 -222.475973) (xy 119.504927 -222.463783) (xy 119.587344 -222.457654) (xy 119.628666 -222.457264)
			(xy 119.669989 -222.457643) (xy 119.752407 -222.463762) (xy 119.834149 -222.475954) (xy 119.874538 -222.484696)
			(xy 119.893643 -222.469778) (xy 119.935121 -222.444697) (xy 119.979616 -222.425469) (xy 120.026306 -222.412448)
			(xy 120.07433 -222.405875) (xy 120.098566 -222.405448) (xy 120.122767 -222.405857) (xy 120.170723 -222.412414)
			(xy 120.217352 -222.425398) (xy 120.261795 -222.444571) (xy 120.303236 -222.469579) (xy 120.32234 -222.484442)
			(xy 120.370886 -222.474064) (xy 120.469295 -222.460931) (xy 120.56848 -222.456577) (xy 120.667661 -222.461034)
			(xy 120.766056 -222.474269) (xy 120.814592 -222.484696) (xy 120.833669 -222.469778) (xy 120.875093 -222.444695)
			(xy 120.919535 -222.42546) (xy 120.966176 -222.41243) (xy 121.014153 -222.405845) (xy 121.038366 -222.405448)
			(xy 121.062604 -222.405854) (xy 121.110631 -222.412423) (xy 121.157325 -222.425443) (xy 121.201822 -222.444674)
			(xy 121.2433 -222.469762) (xy 121.262394 -222.484696) (xy 121.302787 -222.475973) (xy 121.384527 -222.463783)
			(xy 121.466944 -222.457654) (xy 121.508266 -222.457264) (xy 121.549589 -222.457643) (xy 121.632007 -222.463762)
			(xy 121.713749 -222.475954) (xy 121.754138 -222.484696) (xy 121.773243 -222.469778) (xy 121.814721 -222.444697)
			(xy 121.859216 -222.425469) (xy 121.905906 -222.412448) (xy 121.95393 -222.405875) (xy 121.978166 -222.405448)
			(xy 122.002367 -222.405857) (xy 122.050323 -222.412414) (xy 122.096952 -222.425398) (xy 122.141395 -222.444571)
			(xy 122.182836 -222.469579) (xy 122.20194 -222.484442) (xy 122.250486 -222.474064) (xy 122.348895 -222.460931)
			(xy 122.44808 -222.456577) (xy 122.547261 -222.461034) (xy 122.645656 -222.474269) (xy 122.694192 -222.484696)
			(xy 122.713269 -222.469778) (xy 122.754693 -222.444695) (xy 122.799135 -222.42546) (xy 122.845776 -222.41243)
			(xy 122.893753 -222.405845) (xy 122.917966 -222.405448) (xy 122.942204 -222.405854) (xy 122.990231 -222.412423)
			(xy 123.036925 -222.425443) (xy 123.081422 -222.444674) (xy 123.1229 -222.469762) (xy 123.141994 -222.484696)
			(xy 123.182387 -222.475973) (xy 123.264127 -222.463783) (xy 123.346544 -222.457654) (xy 123.387866 -222.457264)
			(xy 123.429189 -222.457643) (xy 123.511607 -222.463762) (xy 123.593349 -222.475954) (xy 123.633738 -222.484696)
			(xy 123.652843 -222.469778) (xy 123.694321 -222.444697) (xy 123.738816 -222.425469) (xy 123.785506 -222.412448)
			(xy 123.83353 -222.405875) (xy 123.857766 -222.405448) (xy 123.881967 -222.405857) (xy 123.929923 -222.412414)
			(xy 123.976552 -222.425398) (xy 124.020995 -222.444571) (xy 124.062436 -222.469579) (xy 124.08154 -222.484442)
			(xy 124.130086 -222.474064) (xy 124.228495 -222.460931) (xy 124.32768 -222.456577) (xy 124.426861 -222.461034)
			(xy 124.525256 -222.474269) (xy 124.573792 -222.484696) (xy 124.592869 -222.469778) (xy 124.634293 -222.444695)
			(xy 124.678735 -222.42546) (xy 124.725376 -222.41243) (xy 124.773353 -222.405845) (xy 124.797566 -222.405448)
			(xy 124.821804 -222.405854) (xy 124.869831 -222.412423) (xy 124.916525 -222.425443) (xy 124.961022 -222.444674)
			(xy 125.0025 -222.469762) (xy 125.021594 -222.484696) (xy 125.061987 -222.475973) (xy 125.143727 -222.463783)
			(xy 125.226144 -222.457654) (xy 125.267466 -222.457264) (xy 125.308789 -222.457643) (xy 125.391207 -222.463762)
			(xy 125.472949 -222.475954) (xy 125.513338 -222.484696) (xy 125.532443 -222.469778) (xy 125.573921 -222.444697)
			(xy 125.618416 -222.425469) (xy 125.665106 -222.412448) (xy 125.71313 -222.405875) (xy 125.737366 -222.405448)
			(xy 125.761567 -222.405857) (xy 125.809523 -222.412414) (xy 125.856152 -222.425398) (xy 125.900595 -222.444571)
			(xy 125.942036 -222.469579) (xy 125.96114 -222.484442) (xy 126.009686 -222.474064) (xy 126.108095 -222.460931)
			(xy 126.20728 -222.456577) (xy 126.306461 -222.461034) (xy 126.404856 -222.474269)
		)
		(stroke
			(width 0)
			(type solid)
		)
		(fill yes)
		(layer "B.Cu")
		(net "PVCCINFAON_CPU1")
	)
	(gr_poly
		(pts
			(xy 405.93264 -380.030228) (xy 405.93264 -340.666832) (xy 403.130258 -337.86445) (xy 403.110564 -337.844122)
			(xy 403.076085 -337.799237) (xy 403.047758 -337.750237) (xy 403.026068 -337.697959) (xy 403.011385 -337.643297)
			(xy 403.003962 -337.587187) (xy 403.003512 -337.558888) (xy 403.003512 -273.943318) (xy 402.47951 -273.419316)
			(xy 400.8501 -273.419316) (xy 400.821803 -273.418834) (xy 400.765697 -273.41141) (xy 400.71104 -273.396728)
			(xy 400.658766 -273.37504) (xy 400.609769 -273.346716) (xy 400.564887 -273.31224) (xy 400.544538 -273.29257)
			(xy 399.31721 -272.065496) (xy 387.45668 -272.065496) (xy 387.429431 -272.065065) (xy 387.375367 -272.058187)
			(xy 387.322593 -272.044582) (xy 387.271944 -272.024462) (xy 387.247892 -272.011648) (xy 387.23392 -272.033515)
			(xy 387.20064 -272.07333) (xy 387.161931 -272.107889) (xy 387.118613 -272.136459) (xy 387.071604 -272.158435)
			(xy 387.021903 -272.173351) (xy 386.970562 -272.18089) (xy 386.944616 -272.18132) (xy 386.91876 -272.180859)
			(xy 386.867593 -272.173382) (xy 386.818044 -272.158584) (xy 386.771157 -272.136775) (xy 386.727918 -272.108413)
			(xy 386.689234 -272.074097) (xy 386.655921 -272.034546) (xy 386.628679 -271.990593) (xy 386.608079 -271.943162)
			(xy 386.594557 -271.89325) (xy 386.591048 -271.86763) (xy 386.55254 -271.87246) (xy 386.475008 -271.876018)
			(xy 386.397468 -271.872605) (xy 386.320548 -271.862249) (xy 386.244867 -271.845034) (xy 386.171036 -271.821099)
			(xy 386.09965 -271.790636) (xy 386.065268 -271.772634) (xy 386.055616 -271.7673) (xy 386.042154 -271.759426)
			(xy 386.033498 -271.754864) (xy 386.014595 -271.74984) (xy 386.004816 -271.74952) (xy 385.994888 -271.749816)
			(xy 385.975712 -271.754965) (xy 385.96697 -271.75968) (xy 385.932143 -271.779281) (xy 385.859542 -271.812699)
			(xy 385.784165 -271.839273) (xy 385.706658 -271.858776) (xy 385.627681 -271.87104) (xy 385.54791 -271.875961)
			(xy 385.468024 -271.873497) (xy 385.388708 -271.863669) (xy 385.310637 -271.846562) (xy 385.234479 -271.82232)
			(xy 385.160883 -271.791151) (xy 385.125468 -271.772634) (xy 385.115816 -271.7673) (xy 385.102354 -271.759426)
			(xy 385.093698 -271.754864) (xy 385.074795 -271.74984) (xy 385.065016 -271.74952) (xy 385.055088 -271.749816)
			(xy 385.035912 -271.754965) (xy 385.02717 -271.75968) (xy 384.991732 -271.77963) (xy 384.917809 -271.813543)
			(xy 384.841027 -271.840358) (xy 384.762064 -271.85984) (xy 384.68162 -271.871814) (xy 384.600407 -271.876176)
			(xy 384.519143 -271.872887) (xy 384.478784 -271.867884) (xy 384.475228 -271.893483) (xy 384.461679 -271.943358)
			(xy 384.441062 -271.990749) (xy 384.41381 -272.034662) (xy 384.380495 -272.074173) (xy 384.341818 -272.108453)
			(xy 384.298591 -272.13678) (xy 384.251723 -272.158561) (xy 384.202198 -272.173336) (xy 384.151057 -272.180796)
			(xy 384.125216 -272.18132) (xy 384.097229 -272.180801) (xy 384.041945 -272.172047) (xy 383.988711 -272.154753)
			(xy 383.938837 -272.129344) (xy 383.893553 -272.096446) (xy 383.853973 -272.056868) (xy 383.821071 -272.011586)
			(xy 383.795658 -271.961715) (xy 383.778359 -271.908482) (xy 383.769601 -271.853199) (xy 383.769108 -271.825212)
			(xy 383.769622 -271.79767) (xy 383.778102 -271.743243) (xy 383.794863 -271.690771) (xy 383.819504 -271.641506)
			(xy 383.851437 -271.596623) (xy 383.889901 -271.557192) (xy 383.911602 -271.540224) (xy 383.888137 -271.509206)
			(xy 383.846248 -271.443665) (xy 383.810411 -271.374628) (xy 383.79527 -271.338802) (xy 383.773062 -271.347865)
			(xy 383.726827 -271.360632) (xy 383.679298 -271.367095) (xy 383.655316 -271.367504) (xy 383.655062 -271.367504)
			(xy 383.62922 -271.36704) (xy 383.578078 -271.359565) (xy 383.528554 -271.344777) (xy 383.481687 -271.322987)
			(xy 383.438461 -271.294652) (xy 383.399784 -271.260368) (xy 383.366468 -271.220853) (xy 383.339213 -271.176939)
			(xy 383.31859 -271.129546) (xy 383.305034 -271.079671) (xy 383.301494 -271.054068) (xy 383.251673 -271.060044)
			(xy 383.151344 -271.061822) (xy 383.101342 -271.057624) (xy 383.081276 -271.055592) (xy 383.032254 -271.093438)
			(xy 383.027428 -271.108932) (xy 383.019221 -271.133537) (xy 382.996133 -271.17998) (xy 382.966005 -271.222198)
			(xy 382.929591 -271.259131) (xy 382.887804 -271.289853) (xy 382.841692 -271.313596) (xy 382.79241 -271.329763)
			(xy 382.741195 -271.337949) (xy 382.689329 -271.337949) (xy 382.638114 -271.329763) (xy 382.588832 -271.313596)
			(xy 382.54272 -271.289853) (xy 382.500933 -271.259131) (xy 382.464519 -271.222198) (xy 382.434391 -271.17998)
			(xy 382.411303 -271.133537) (xy 382.403096 -271.108932) (xy 382.39827 -271.093438) (xy 382.349502 -271.055846)
			(xy 382.329436 -271.057878) (xy 382.287532 -271.061393) (xy 382.203435 -271.061265) (xy 382.161542 -271.057624)
			(xy 382.141476 -271.055592) (xy 382.092454 -271.093438) (xy 382.087628 -271.108932) (xy 382.079441 -271.133554)
			(xy 382.056385 -271.180036) (xy 382.026274 -271.222291) (xy 381.989864 -271.259256) (xy 381.948071 -271.290004)
			(xy 381.901944 -271.313762) (xy 381.852642 -271.329932) (xy 381.801405 -271.338109) (xy 381.775462 -271.338548)
			(xy 381.749514 -271.338047) (xy 381.69827 -271.32984) (xy 381.648967 -271.313638) (xy 381.602844 -271.289849)
			(xy 381.561059 -271.259071) (xy 381.524663 -271.222076) (xy 381.49457 -271.179795) (xy 381.471537 -271.133289)
			(xy 381.463296 -271.108678) (xy 381.45847 -271.093184) (xy 381.409702 -271.055592) (xy 381.389636 -271.057624)
			(xy 381.36886 -271.059526) (xy 381.327186 -271.061561) (xy 381.306324 -271.061688) (xy 381.305562 -271.061688)
			(xy 381.276387 -271.061448) (xy 381.218171 -271.057508) (xy 381.18923 -271.053814) (xy 381.185691 -271.079428)
			(xy 381.172171 -271.129336) (xy 381.151574 -271.176763) (xy 381.124334 -271.220713) (xy 381.091024 -271.26026)
			(xy 381.052344 -271.294573) (xy 381.009107 -271.322931) (xy 380.962224 -271.344737) (xy 380.912679 -271.359532)
			(xy 380.861515 -271.367005) (xy 380.835662 -271.367504) (xy 380.80982 -271.36704) (xy 380.758678 -271.359565)
			(xy 380.709154 -271.344777) (xy 380.662287 -271.322987) (xy 380.619061 -271.294652) (xy 380.580384 -271.260368)
			(xy 380.547068 -271.220853) (xy 380.519813 -271.176939) (xy 380.49919 -271.129546) (xy 380.485634 -271.079671)
			(xy 380.482094 -271.054068) (xy 380.432273 -271.060044) (xy 380.331944 -271.061822) (xy 380.281942 -271.057624)
			(xy 380.261876 -271.055592) (xy 380.212854 -271.093438) (xy 380.208028 -271.108932) (xy 380.199821 -271.133537)
			(xy 380.176733 -271.17998) (xy 380.146605 -271.222198) (xy 380.110191 -271.259131) (xy 380.068404 -271.289853)
			(xy 380.022292 -271.313596) (xy 379.97301 -271.329763) (xy 379.921795 -271.337949) (xy 379.869929 -271.337949)
			(xy 379.818714 -271.329763) (xy 379.769432 -271.313596) (xy 379.72332 -271.289853) (xy 379.681533 -271.259131)
			(xy 379.645119 -271.222198) (xy 379.614991 -271.17998) (xy 379.591903 -271.133537) (xy 379.583696 -271.108932)
			(xy 379.57887 -271.093438) (xy 379.530102 -271.055846) (xy 379.510036 -271.057878) (xy 379.459958 -271.061969)
			(xy 379.3595 -271.059936) (xy 379.30963 -271.053814) (xy 379.306091 -271.079428) (xy 379.292571 -271.129336)
			(xy 379.271974 -271.176763) (xy 379.244734 -271.220713) (xy 379.211424 -271.26026) (xy 379.172744 -271.294573)
			(xy 379.129507 -271.322931) (xy 379.082624 -271.344737) (xy 379.033079 -271.359532) (xy 378.981915 -271.367005)
			(xy 378.956062 -271.367504) (xy 378.93022 -271.36704) (xy 378.879078 -271.359565) (xy 378.829554 -271.344777)
			(xy 378.782687 -271.322987) (xy 378.739461 -271.294652) (xy 378.700784 -271.260368) (xy 378.667468 -271.220853)
			(xy 378.640213 -271.176939) (xy 378.61959 -271.129546) (xy 378.606034 -271.079671) (xy 378.602494 -271.054068)
			(xy 378.552673 -271.060044) (xy 378.452344 -271.061822) (xy 378.402342 -271.057624) (xy 378.382276 -271.055592)
			(xy 378.333254 -271.093438) (xy 378.328428 -271.108932) (xy 378.320221 -271.133537) (xy 378.297133 -271.17998)
			(xy 378.267005 -271.222198) (xy 378.230591 -271.259131) (xy 378.188804 -271.289853) (xy 378.142692 -271.313596)
			(xy 378.09341 -271.329763) (xy 378.042195 -271.337949) (xy 377.990329 -271.337949) (xy 377.939114 -271.329763)
			(xy 377.889832 -271.313596) (xy 377.84372 -271.289853) (xy 377.801933 -271.259131) (xy 377.765519 -271.222198)
			(xy 377.735391 -271.17998) (xy 377.712303 -271.133537) (xy 377.704096 -271.108932) (xy 377.69927 -271.093438)
			(xy 377.650502 -271.055846) (xy 377.630436 -271.057878) (xy 377.580358 -271.061969) (xy 377.4799 -271.059936)
			(xy 377.43003 -271.053814) (xy 377.426491 -271.079428) (xy 377.412971 -271.129336) (xy 377.392374 -271.176763)
			(xy 377.365134 -271.220713) (xy 377.331824 -271.26026) (xy 377.293144 -271.294573) (xy 377.249907 -271.322931)
			(xy 377.203024 -271.344737) (xy 377.153479 -271.359532) (xy 377.102315 -271.367005) (xy 377.076462 -271.367504)
			(xy 377.05062 -271.36704) (xy 376.999478 -271.359565) (xy 376.949954 -271.344777) (xy 376.903087 -271.322987)
			(xy 376.859861 -271.294652) (xy 376.821184 -271.260368) (xy 376.787868 -271.220853) (xy 376.760613 -271.176939)
			(xy 376.73999 -271.129546) (xy 376.726434 -271.079671) (xy 376.722894 -271.054068) (xy 376.673073 -271.060044)
			(xy 376.572744 -271.061822) (xy 376.522742 -271.057624) (xy 376.502676 -271.055592) (xy 376.453654 -271.093438)
			(xy 376.448828 -271.108932) (xy 376.440621 -271.133537) (xy 376.417533 -271.17998) (xy 376.387405 -271.222198)
			(xy 376.350991 -271.259131) (xy 376.309204 -271.289853) (xy 376.263092 -271.313596) (xy 376.21381 -271.329763)
			(xy 376.162595 -271.337949) (xy 376.110729 -271.337949) (xy 376.059514 -271.329763) (xy 376.010232 -271.313596)
			(xy 375.96412 -271.289853) (xy 375.922333 -271.259131) (xy 375.885919 -271.222198) (xy 375.855791 -271.17998)
			(xy 375.832703 -271.133537) (xy 375.824496 -271.108932) (xy 375.81967 -271.093438) (xy 375.770902 -271.055846)
			(xy 375.750836 -271.057878) (xy 375.708932 -271.061393) (xy 375.624835 -271.061265) (xy 375.582942 -271.057624)
			(xy 375.562876 -271.055592) (xy 375.513854 -271.093438) (xy 375.509028 -271.108932) (xy 375.500821 -271.133537)
			(xy 375.477733 -271.17998) (xy 375.447605 -271.222198) (xy 375.411191 -271.259131) (xy 375.369404 -271.289853)
			(xy 375.323292 -271.313596) (xy 375.27401 -271.329763) (xy 375.222795 -271.337949) (xy 375.170929 -271.337949)
			(xy 375.119714 -271.329763) (xy 375.070432 -271.313596) (xy 375.02432 -271.289853) (xy 374.982533 -271.259131)
			(xy 374.946119 -271.222198) (xy 374.915991 -271.17998) (xy 374.892903 -271.133537) (xy 374.884696 -271.108932)
			(xy 374.87987 -271.093438) (xy 374.831102 -271.055846) (xy 374.811036 -271.057878) (xy 374.760958 -271.061969)
			(xy 374.6605 -271.059936) (xy 374.61063 -271.053814) (xy 374.607091 -271.079428) (xy 374.593571 -271.129336)
			(xy 374.572974 -271.176763) (xy 374.545734 -271.220713) (xy 374.512424 -271.26026) (xy 374.473744 -271.294573)
			(xy 374.430507 -271.322931) (xy 374.383624 -271.344737) (xy 374.334079 -271.359532) (xy 374.282915 -271.367005)
			(xy 374.257062 -271.367504) (xy 374.23122 -271.36704) (xy 374.180078 -271.359565) (xy 374.130554 -271.344777)
			(xy 374.083687 -271.322987) (xy 374.040461 -271.294652) (xy 374.001784 -271.260368) (xy 373.968468 -271.220853)
			(xy 373.941213 -271.176939) (xy 373.92059 -271.129546) (xy 373.907034 -271.079671) (xy 373.903494 -271.054068)
			(xy 373.853673 -271.060044) (xy 373.753344 -271.061822) (xy 373.703342 -271.057624) (xy 373.683276 -271.055592)
			(xy 373.634254 -271.093438) (xy 373.629428 -271.108932) (xy 373.621221 -271.133537) (xy 373.598133 -271.17998)
			(xy 373.568005 -271.222198) (xy 373.531591 -271.259131) (xy 373.489804 -271.289853) (xy 373.443692 -271.313596)
			(xy 373.39441 -271.329763) (xy 373.343195 -271.337949) (xy 373.291329 -271.337949) (xy 373.240114 -271.329763)
			(xy 373.190832 -271.313596) (xy 373.14472 -271.289853) (xy 373.102933 -271.259131) (xy 373.066519 -271.222198)
			(xy 373.036391 -271.17998) (xy 373.013303 -271.133537) (xy 373.005096 -271.108932) (xy 373.00027 -271.093438)
			(xy 372.951502 -271.055846) (xy 372.931436 -271.057878) (xy 372.881358 -271.061969) (xy 372.7809 -271.059936)
			(xy 372.73103 -271.053814) (xy 372.727491 -271.079428) (xy 372.713971 -271.129336) (xy 372.693374 -271.176763)
			(xy 372.666134 -271.220713) (xy 372.632824 -271.26026) (xy 372.594144 -271.294573) (xy 372.550907 -271.322931)
			(xy 372.504024 -271.344737) (xy 372.454479 -271.359532) (xy 372.403315 -271.367005) (xy 372.377462 -271.367504)
			(xy 372.35162 -271.36704) (xy 372.300478 -271.359565) (xy 372.250954 -271.344777) (xy 372.204087 -271.322987)
			(xy 372.160861 -271.294652) (xy 372.122184 -271.260368) (xy 372.088868 -271.220853) (xy 372.061613 -271.176939)
			(xy 372.04099 -271.129546) (xy 372.027434 -271.079671) (xy 372.023894 -271.054068) (xy 371.974073 -271.060044)
			(xy 371.873744 -271.061822) (xy 371.823742 -271.057624) (xy 371.803676 -271.055592) (xy 371.754654 -271.093438)
			(xy 371.749828 -271.108932) (xy 371.741641 -271.133554) (xy 371.718585 -271.180036) (xy 371.688474 -271.222291)
			(xy 371.652064 -271.259256) (xy 371.610271 -271.290004) (xy 371.564144 -271.313762) (xy 371.514842 -271.329932)
			(xy 371.463605 -271.338109) (xy 371.437662 -271.338548) (xy 371.411714 -271.338047) (xy 371.36047 -271.32984)
			(xy 371.311167 -271.313638) (xy 371.265044 -271.289849) (xy 371.223259 -271.259071) (xy 371.186863 -271.222076)
			(xy 371.15677 -271.179795) (xy 371.133737 -271.133289) (xy 371.125496 -271.108678) (xy 371.12067 -271.093184)
			(xy 371.071902 -271.055592) (xy 371.051836 -271.057624) (xy 371.001828 -271.061769) (xy 370.901498 -271.059856)
			(xy 370.851684 -271.053814) (xy 370.848146 -271.07943) (xy 370.834627 -271.129341) (xy 370.814031 -271.176772)
			(xy 370.786792 -271.220726) (xy 370.753482 -271.260278) (xy 370.714803 -271.294596) (xy 370.671566 -271.32296)
			(xy 370.624682 -271.344772) (xy 370.575136 -271.359575) (xy 370.523971 -271.367056) (xy 370.498116 -271.367504)
			(xy 370.472271 -271.367044) (xy 370.421124 -271.359575) (xy 370.371593 -271.344792) (xy 370.324719 -271.323005)
			(xy 370.281487 -271.294672) (xy 370.242803 -271.260388) (xy 370.209482 -271.220872) (xy 370.182221 -271.176955)
			(xy 370.161595 -271.129559) (xy 370.148035 -271.079679) (xy 370.144548 -271.054068) (xy 370.105895 -271.058853)
			(xy 370.02808 -271.062281) (xy 369.950272 -271.058687) (xy 369.91163 -271.053814) (xy 369.908091 -271.079428)
			(xy 369.894571 -271.129336) (xy 369.873974 -271.176763) (xy 369.846734 -271.220713) (xy 369.813424 -271.26026)
			(xy 369.774744 -271.294573) (xy 369.731507 -271.322931) (xy 369.684624 -271.344737) (xy 369.635079 -271.359532)
			(xy 369.583915 -271.367005) (xy 369.558062 -271.367504) (xy 369.53222 -271.36704) (xy 369.481078 -271.359565)
			(xy 369.431554 -271.344777) (xy 369.384687 -271.322987) (xy 369.341461 -271.294652) (xy 369.302784 -271.260368)
			(xy 369.269468 -271.220853) (xy 369.242213 -271.176939) (xy 369.22159 -271.129546) (xy 369.208034 -271.079671)
			(xy 369.204494 -271.054068) (xy 369.165882 -271.058833) (xy 369.088153 -271.062244) (xy 369.010431 -271.058663)
			(xy 368.97183 -271.053814) (xy 368.968291 -271.079428) (xy 368.954771 -271.129336) (xy 368.934174 -271.176763)
			(xy 368.906934 -271.220713) (xy 368.873624 -271.26026) (xy 368.834944 -271.294573) (xy 368.791707 -271.322931)
			(xy 368.744824 -271.344737) (xy 368.695279 -271.359532) (xy 368.644115 -271.367005) (xy 368.618262 -271.367504)
			(xy 368.59242 -271.36704) (xy 368.541278 -271.359565) (xy 368.491754 -271.344777) (xy 368.444887 -271.322987)
			(xy 368.401661 -271.294652) (xy 368.362984 -271.260368) (xy 368.329668 -271.220853) (xy 368.302413 -271.176939)
			(xy 368.28179 -271.129546) (xy 368.268234 -271.079671) (xy 368.264694 -271.054068) (xy 368.226082 -271.058833)
			(xy 368.148353 -271.062244) (xy 368.070631 -271.058663) (xy 368.03203 -271.053814) (xy 368.028491 -271.079428)
			(xy 368.014971 -271.129336) (xy 367.994374 -271.176763) (xy 367.967134 -271.220713) (xy 367.933824 -271.26026)
			(xy 367.895144 -271.294573) (xy 367.851907 -271.322931) (xy 367.805024 -271.344737) (xy 367.755479 -271.359532)
			(xy 367.704315 -271.367005) (xy 367.678462 -271.367504) (xy 367.650542 -271.366958) (xy 367.595387 -271.358244)
			(xy 367.542266 -271.341035) (xy 367.492478 -271.315752) (xy 367.447243 -271.283014) (xy 367.407666 -271.243621)
			(xy 367.374718 -271.198539) (xy 367.36147 -271.173956) (xy 367.354071 -271.160597) (xy 367.332773 -271.138729)
			(xy 367.305963 -271.124135) (xy 367.276037 -271.118118) (xy 367.24567 -271.121216) (xy 367.231422 -271.126712)
			(xy 367.033556 -271.210786) (xy 367.019297 -271.231129) (xy 366.986039 -271.268032) (xy 366.947972 -271.299952)
			(xy 366.905836 -271.326268) (xy 366.86045 -271.346467) (xy 366.812696 -271.360159) (xy 366.763501 -271.367076)
			(xy 366.738662 -271.367504) (xy 366.710681 -271.366952) (xy 366.655409 -271.358192) (xy 366.602187 -271.340894)
			(xy 366.552326 -271.315484) (xy 366.507054 -271.282587) (xy 366.467485 -271.243014) (xy 366.434594 -271.197738)
			(xy 366.409189 -271.147874) (xy 366.391898 -271.09465) (xy 366.383144 -271.039377) (xy 366.382554 -271.011396)
			(xy 366.38357 -270.985234) (xy 366.384144 -270.971298) (xy 366.378561 -270.943979) (xy 366.3658 -270.919187)
			(xy 366.346811 -270.89877) (xy 366.323008 -270.884247) (xy 366.296165 -270.876702) (xy 366.282224 -270.876268)
			(xy 366.2553 -270.876268) (xy 366.241357 -270.876702) (xy 366.214509 -270.884243) (xy 366.190701 -270.898764)
			(xy 366.171708 -270.919182) (xy 366.158943 -270.943975) (xy 366.153359 -270.971297) (xy 366.153954 -270.985234)
			(xy 366.15497 -271.011396) (xy 366.154472 -271.038045) (xy 366.146529 -271.090749) (xy 366.130819 -271.141679)
			(xy 366.107693 -271.1897) (xy 366.077669 -271.233737) (xy 366.041417 -271.272808) (xy 365.999746 -271.306039)
			(xy 365.953588 -271.332688) (xy 365.903974 -271.35216) (xy 365.852012 -271.36402) (xy 365.798862 -271.368004)
			(xy 365.745712 -271.36402) (xy 365.69375 -271.35216) (xy 365.644136 -271.332688) (xy 365.597978 -271.306039)
			(xy 365.556307 -271.272808) (xy 365.520055 -271.233737) (xy 365.490031 -271.1897) (xy 365.466905 -271.141679)
			(xy 365.451195 -271.090749) (xy 365.443252 -271.038045) (xy 365.442754 -271.011396) (xy 365.44377 -270.985234)
			(xy 365.444344 -270.971298) (xy 365.438761 -270.943979) (xy 365.426 -270.919187) (xy 365.407011 -270.89877)
			(xy 365.383208 -270.884247) (xy 365.356365 -270.876702) (xy 365.342424 -270.876268) (xy 365.3155 -270.876268)
			(xy 365.301557 -270.876702) (xy 365.274709 -270.884243) (xy 365.250901 -270.898764) (xy 365.231908 -270.919182)
			(xy 365.219143 -270.943975) (xy 365.213559 -270.971297) (xy 365.214154 -270.985234) (xy 365.21517 -271.011396)
			(xy 365.214672 -271.038045) (xy 365.206729 -271.090749) (xy 365.191019 -271.141679) (xy 365.167893 -271.1897)
			(xy 365.137869 -271.233737) (xy 365.101617 -271.272808) (xy 365.059946 -271.306039) (xy 365.013788 -271.332688)
			(xy 364.964174 -271.35216) (xy 364.912212 -271.36402) (xy 364.859062 -271.368004) (xy 364.805912 -271.36402)
			(xy 364.75395 -271.35216) (xy 364.704336 -271.332688) (xy 364.658178 -271.306039) (xy 364.616507 -271.272808)
			(xy 364.580255 -271.233737) (xy 364.550231 -271.1897) (xy 364.527105 -271.141679) (xy 364.511395 -271.090749)
			(xy 364.503452 -271.038045) (xy 364.502954 -271.011396) (xy 364.502954 -271.010888) (xy 364.50349 -270.98372)
			(xy 364.511788 -270.930021) (xy 364.519464 -270.903954) (xy 364.528862 -270.87449) (xy 363.582458 -269.928086)
			(xy 362.695236 -269.928086) (xy 362.26242 -270.360902) (xy 362.253258 -270.397567) (xy 362.22821 -270.468875)
			(xy 362.195753 -270.53713) (xy 362.156252 -270.601566) (xy 362.110152 -270.661457) (xy 362.05797 -270.716131)
			(xy 362.000292 -270.764972) (xy 361.969304 -270.786606) (xy 361.969304 -271.116298) (xy 362.355638 -271.502632)
			(xy 362.386118 -271.491202) (xy 362.415874 -271.480921) (xy 362.477834 -271.469806) (xy 362.509308 -271.469104)
			(xy 362.509816 -271.469104) (xy 362.536464 -271.469603) (xy 362.589163 -271.477548) (xy 362.64009 -271.493259)
			(xy 362.688107 -271.516385) (xy 362.732141 -271.546408) (xy 362.771208 -271.582659) (xy 362.804436 -271.624328)
			(xy 362.831083 -271.670483) (xy 362.850554 -271.720095) (xy 362.862413 -271.772054) (xy 362.866396 -271.8252)
			(xy 362.864398 -271.851861) (xy 363.094006 -271.851861) (xy 363.094006 -271.798563) (xy 363.101949 -271.745859)
			(xy 363.117659 -271.694929) (xy 363.140785 -271.646908) (xy 363.170809 -271.602871) (xy 363.207061 -271.5638)
			(xy 363.248732 -271.530569) (xy 363.29489 -271.50392) (xy 363.344504 -271.484448) (xy 363.396466 -271.472588)
			(xy 363.449616 -271.468605) (xy 363.502766 -271.472588) (xy 363.554728 -271.484448) (xy 363.604342 -271.50392)
			(xy 363.6505 -271.530569) (xy 363.692171 -271.5638) (xy 363.728423 -271.602871) (xy 363.758447 -271.646908)
			(xy 363.781573 -271.694929) (xy 363.797283 -271.745859) (xy 363.805226 -271.798563) (xy 363.805724 -271.825212)
			(xy 363.805226 -271.851861) (xy 364.033298 -271.851861) (xy 364.033298 -271.798563) (xy 364.041241 -271.745859)
			(xy 364.056951 -271.694929) (xy 364.080077 -271.646908) (xy 364.110101 -271.602871) (xy 364.146353 -271.5638)
			(xy 364.188024 -271.530569) (xy 364.234182 -271.50392) (xy 364.283796 -271.484448) (xy 364.335758 -271.472588)
			(xy 364.388908 -271.468605) (xy 364.442058 -271.472588) (xy 364.49402 -271.484448) (xy 364.543634 -271.50392)
			(xy 364.589792 -271.530569) (xy 364.631463 -271.5638) (xy 364.667715 -271.602871) (xy 364.697739 -271.646908)
			(xy 364.720865 -271.694929) (xy 364.736575 -271.745859) (xy 364.744518 -271.798563) (xy 364.745016 -271.825212)
			(xy 364.744518 -271.851861) (xy 364.973606 -271.851861) (xy 364.973606 -271.798563) (xy 364.981549 -271.745859)
			(xy 364.997259 -271.694929) (xy 365.020385 -271.646908) (xy 365.050409 -271.602871) (xy 365.086661 -271.5638)
			(xy 365.128332 -271.530569) (xy 365.17449 -271.50392) (xy 365.224104 -271.484448) (xy 365.276066 -271.472588)
			(xy 365.329216 -271.468605) (xy 365.382366 -271.472588) (xy 365.434328 -271.484448) (xy 365.483942 -271.50392)
			(xy 365.5301 -271.530569) (xy 365.571771 -271.5638) (xy 365.608023 -271.602871) (xy 365.638047 -271.646908)
			(xy 365.661173 -271.694929) (xy 365.676883 -271.745859) (xy 365.684826 -271.798563) (xy 365.685324 -271.825212)
			(xy 365.684826 -271.851861) (xy 365.912898 -271.851861) (xy 365.912898 -271.798563) (xy 365.920841 -271.745859)
			(xy 365.936551 -271.694929) (xy 365.959677 -271.646908) (xy 365.989701 -271.602871) (xy 366.025953 -271.5638)
			(xy 366.067624 -271.530569) (xy 366.113782 -271.50392) (xy 366.163396 -271.484448) (xy 366.215358 -271.472588)
			(xy 366.268508 -271.468605) (xy 366.321658 -271.472588) (xy 366.37362 -271.484448) (xy 366.423234 -271.50392)
			(xy 366.469392 -271.530569) (xy 366.511063 -271.5638) (xy 366.547315 -271.602871) (xy 366.577339 -271.646908)
			(xy 366.600465 -271.694929) (xy 366.616175 -271.745859) (xy 366.624118 -271.798563) (xy 366.624616 -271.825212)
			(xy 366.624118 -271.851861) (xy 366.852698 -271.851861) (xy 366.852698 -271.798563) (xy 366.860641 -271.745859)
			(xy 366.876351 -271.694929) (xy 366.899477 -271.646908) (xy 366.929501 -271.602871) (xy 366.965753 -271.5638)
			(xy 367.007424 -271.530569) (xy 367.053582 -271.50392) (xy 367.103196 -271.484448) (xy 367.155158 -271.472588)
			(xy 367.208308 -271.468605) (xy 367.261458 -271.472588) (xy 367.31342 -271.484448) (xy 367.363034 -271.50392)
			(xy 367.409192 -271.530569) (xy 367.450863 -271.5638) (xy 367.487115 -271.602871) (xy 367.517139 -271.646908)
			(xy 367.540265 -271.694929) (xy 367.555975 -271.745859) (xy 367.563918 -271.798563) (xy 367.564416 -271.825212)
			(xy 367.563918 -271.851861) (xy 367.793006 -271.851861) (xy 367.793006 -271.798563) (xy 367.800949 -271.745859)
			(xy 367.816659 -271.694929) (xy 367.839785 -271.646908) (xy 367.869809 -271.602871) (xy 367.906061 -271.5638)
			(xy 367.947732 -271.530569) (xy 367.99389 -271.50392) (xy 368.043504 -271.484448) (xy 368.095466 -271.472588)
			(xy 368.148616 -271.468605) (xy 368.201766 -271.472588) (xy 368.253728 -271.484448) (xy 368.303342 -271.50392)
			(xy 368.3495 -271.530569) (xy 368.391171 -271.5638) (xy 368.427423 -271.602871) (xy 368.457447 -271.646908)
			(xy 368.480573 -271.694929) (xy 368.496283 -271.745859) (xy 368.504226 -271.798563) (xy 368.504724 -271.825212)
			(xy 368.504226 -271.851861) (xy 368.732806 -271.851861) (xy 368.732806 -271.798563) (xy 368.740749 -271.745859)
			(xy 368.756459 -271.694929) (xy 368.779585 -271.646908) (xy 368.809609 -271.602871) (xy 368.845861 -271.5638)
			(xy 368.887532 -271.530569) (xy 368.93369 -271.50392) (xy 368.983304 -271.484448) (xy 369.035266 -271.472588)
			(xy 369.088416 -271.468605) (xy 369.141566 -271.472588) (xy 369.193528 -271.484448) (xy 369.243142 -271.50392)
			(xy 369.2893 -271.530569) (xy 369.330971 -271.5638) (xy 369.367223 -271.602871) (xy 369.397247 -271.646908)
			(xy 369.420373 -271.694929) (xy 369.436083 -271.745859) (xy 369.444026 -271.798563) (xy 369.444524 -271.825212)
			(xy 369.444026 -271.851861) (xy 369.672606 -271.851861) (xy 369.672606 -271.798563) (xy 369.680549 -271.745859)
			(xy 369.696259 -271.694929) (xy 369.719385 -271.646908) (xy 369.749409 -271.602871) (xy 369.785661 -271.5638)
			(xy 369.827332 -271.530569) (xy 369.87349 -271.50392) (xy 369.923104 -271.484448) (xy 369.975066 -271.472588)
			(xy 370.028216 -271.468605) (xy 370.081366 -271.472588) (xy 370.133328 -271.484448) (xy 370.182942 -271.50392)
			(xy 370.2291 -271.530569) (xy 370.270771 -271.5638) (xy 370.307023 -271.602871) (xy 370.337047 -271.646908)
			(xy 370.360173 -271.694929) (xy 370.375883 -271.745859) (xy 370.383826 -271.798563) (xy 370.384324 -271.825212)
			(xy 370.383826 -271.851861) (xy 370.612406 -271.851861) (xy 370.612406 -271.798563) (xy 370.620349 -271.745859)
			(xy 370.636059 -271.694929) (xy 370.659185 -271.646908) (xy 370.689209 -271.602871) (xy 370.725461 -271.5638)
			(xy 370.767132 -271.530569) (xy 370.81329 -271.50392) (xy 370.862904 -271.484448) (xy 370.914866 -271.472588)
			(xy 370.968016 -271.468605) (xy 371.021166 -271.472588) (xy 371.073128 -271.484448) (xy 371.122742 -271.50392)
			(xy 371.1689 -271.530569) (xy 371.210571 -271.5638) (xy 371.246823 -271.602871) (xy 371.276847 -271.646908)
			(xy 371.299973 -271.694929) (xy 371.315683 -271.745859) (xy 371.323626 -271.798563) (xy 371.324124 -271.825212)
			(xy 371.323644 -271.85092) (xy 371.581168 -271.85092) (xy 371.581168 -271.799504) (xy 371.589211 -271.748722)
			(xy 371.605099 -271.699823) (xy 371.628442 -271.654011) (xy 371.658663 -271.612415) (xy 371.695019 -271.576059)
			(xy 371.736615 -271.545838) (xy 371.782427 -271.522495) (xy 371.831326 -271.506607) (xy 371.882108 -271.498564)
			(xy 371.933524 -271.498564) (xy 371.984306 -271.506607) (xy 372.033205 -271.522495) (xy 372.079017 -271.545838)
			(xy 372.120613 -271.576059) (xy 372.156969 -271.612415) (xy 372.18719 -271.654011) (xy 372.210533 -271.699823)
			(xy 372.226421 -271.748722) (xy 372.234464 -271.799504) (xy 372.234968 -271.825212) (xy 372.234464 -271.85092)
			(xy 372.520968 -271.85092) (xy 372.520968 -271.799504) (xy 372.529011 -271.748722) (xy 372.544899 -271.699823)
			(xy 372.568242 -271.654011) (xy 372.598463 -271.612415) (xy 372.634819 -271.576059) (xy 372.676415 -271.545838)
			(xy 372.722227 -271.522495) (xy 372.771126 -271.506607) (xy 372.821908 -271.498564) (xy 372.873324 -271.498564)
			(xy 372.924106 -271.506607) (xy 372.973005 -271.522495) (xy 373.018817 -271.545838) (xy 373.060413 -271.576059)
			(xy 373.096769 -271.612415) (xy 373.12699 -271.654011) (xy 373.150333 -271.699823) (xy 373.166221 -271.748722)
			(xy 373.174264 -271.799504) (xy 373.174768 -271.825212) (xy 373.174264 -271.85092) (xy 373.174115 -271.851861)
			(xy 373.431552 -271.851861) (xy 373.431552 -271.798563) (xy 373.439495 -271.745859) (xy 373.455205 -271.694929)
			(xy 373.478331 -271.646908) (xy 373.508355 -271.602871) (xy 373.544607 -271.5638) (xy 373.586278 -271.530569)
			(xy 373.632436 -271.50392) (xy 373.68205 -271.484448) (xy 373.734012 -271.472588) (xy 373.787162 -271.468605)
			(xy 373.840312 -271.472588) (xy 373.892274 -271.484448) (xy 373.941888 -271.50392) (xy 373.988046 -271.530569)
			(xy 374.029717 -271.5638) (xy 374.065969 -271.602871) (xy 374.095993 -271.646908) (xy 374.119119 -271.694929)
			(xy 374.134829 -271.745859) (xy 374.142772 -271.798563) (xy 374.14327 -271.825212) (xy 374.14279 -271.85092)
			(xy 374.400568 -271.85092) (xy 374.400568 -271.799504) (xy 374.408611 -271.748722) (xy 374.424499 -271.699823)
			(xy 374.447842 -271.654011) (xy 374.478063 -271.612415) (xy 374.514419 -271.576059) (xy 374.556015 -271.545838)
			(xy 374.601827 -271.522495) (xy 374.650726 -271.506607) (xy 374.701508 -271.498564) (xy 374.752924 -271.498564)
			(xy 374.803706 -271.506607) (xy 374.852605 -271.522495) (xy 374.898417 -271.545838) (xy 374.940013 -271.576059)
			(xy 374.976369 -271.612415) (xy 375.00659 -271.654011) (xy 375.029933 -271.699823) (xy 375.045821 -271.748722)
			(xy 375.053864 -271.799504) (xy 375.054368 -271.825212) (xy 375.053864 -271.85092) (xy 375.053715 -271.851861)
			(xy 375.311406 -271.851861) (xy 375.311406 -271.798563) (xy 375.319349 -271.745859) (xy 375.335059 -271.694929)
			(xy 375.358185 -271.646908) (xy 375.388209 -271.602871) (xy 375.424461 -271.5638) (xy 375.466132 -271.530569)
			(xy 375.51229 -271.50392) (xy 375.561904 -271.484448) (xy 375.613866 -271.472588) (xy 375.667016 -271.468605)
			(xy 375.720166 -271.472588) (xy 375.772128 -271.484448) (xy 375.821742 -271.50392) (xy 375.8679 -271.530569)
			(xy 375.909571 -271.5638) (xy 375.945823 -271.602871) (xy 375.975847 -271.646908) (xy 375.998973 -271.694929)
			(xy 376.014683 -271.745859) (xy 376.022626 -271.798563) (xy 376.023124 -271.825212) (xy 376.022644 -271.85092)
			(xy 376.280168 -271.85092) (xy 376.280168 -271.799504) (xy 376.288211 -271.748722) (xy 376.304099 -271.699823)
			(xy 376.327442 -271.654011) (xy 376.357663 -271.612415) (xy 376.394019 -271.576059) (xy 376.435615 -271.545838)
			(xy 376.481427 -271.522495) (xy 376.530326 -271.506607) (xy 376.581108 -271.498564) (xy 376.632524 -271.498564)
			(xy 376.683306 -271.506607) (xy 376.732205 -271.522495) (xy 376.778017 -271.545838) (xy 376.819613 -271.576059)
			(xy 376.855969 -271.612415) (xy 376.88619 -271.654011) (xy 376.909533 -271.699823) (xy 376.925421 -271.748722)
			(xy 376.933464 -271.799504) (xy 376.933968 -271.825212) (xy 376.933464 -271.85092) (xy 376.933315 -271.851861)
			(xy 377.191006 -271.851861) (xy 377.191006 -271.798563) (xy 377.198949 -271.745859) (xy 377.214659 -271.694929)
			(xy 377.237785 -271.646908) (xy 377.267809 -271.602871) (xy 377.304061 -271.5638) (xy 377.345732 -271.530569)
			(xy 377.39189 -271.50392) (xy 377.441504 -271.484448) (xy 377.493466 -271.472588) (xy 377.546616 -271.468605)
			(xy 377.599766 -271.472588) (xy 377.651728 -271.484448) (xy 377.701342 -271.50392) (xy 377.7475 -271.530569)
			(xy 377.789171 -271.5638) (xy 377.825423 -271.602871) (xy 377.855447 -271.646908) (xy 377.878573 -271.694929)
			(xy 377.894283 -271.745859) (xy 377.902226 -271.798563) (xy 377.902724 -271.825212) (xy 377.902244 -271.85092)
			(xy 378.159768 -271.85092) (xy 378.159768 -271.799504) (xy 378.167811 -271.748722) (xy 378.183699 -271.699823)
			(xy 378.207042 -271.654011) (xy 378.237263 -271.612415) (xy 378.273619 -271.576059) (xy 378.315215 -271.545838)
			(xy 378.361027 -271.522495) (xy 378.409926 -271.506607) (xy 378.460708 -271.498564) (xy 378.512124 -271.498564)
			(xy 378.562906 -271.506607) (xy 378.611805 -271.522495) (xy 378.657617 -271.545838) (xy 378.699213 -271.576059)
			(xy 378.735569 -271.612415) (xy 378.76579 -271.654011) (xy 378.789133 -271.699823) (xy 378.805021 -271.748722)
			(xy 378.813064 -271.799504) (xy 378.813568 -271.825212) (xy 378.813064 -271.85092) (xy 379.099568 -271.85092)
			(xy 379.099568 -271.799504) (xy 379.107611 -271.748722) (xy 379.123499 -271.699823) (xy 379.146842 -271.654011)
			(xy 379.177063 -271.612415) (xy 379.213419 -271.576059) (xy 379.255015 -271.545838) (xy 379.300827 -271.522495)
			(xy 379.349726 -271.506607) (xy 379.400508 -271.498564) (xy 379.451924 -271.498564) (xy 379.502706 -271.506607)
			(xy 379.551605 -271.522495) (xy 379.597417 -271.545838) (xy 379.639013 -271.576059) (xy 379.675369 -271.612415)
			(xy 379.70559 -271.654011) (xy 379.728933 -271.699823) (xy 379.744821 -271.748722) (xy 379.752864 -271.799504)
			(xy 379.753368 -271.825212) (xy 379.752864 -271.85092) (xy 379.752715 -271.851861) (xy 380.010152 -271.851861)
			(xy 380.010152 -271.798563) (xy 380.018095 -271.745859) (xy 380.033805 -271.694929) (xy 380.056931 -271.646908)
			(xy 380.086955 -271.602871) (xy 380.123207 -271.5638) (xy 380.164878 -271.530569) (xy 380.211036 -271.50392)
			(xy 380.26065 -271.484448) (xy 380.312612 -271.472588) (xy 380.365762 -271.468605) (xy 380.418912 -271.472588)
			(xy 380.470874 -271.484448) (xy 380.520488 -271.50392) (xy 380.566646 -271.530569) (xy 380.608317 -271.5638)
			(xy 380.644569 -271.602871) (xy 380.674593 -271.646908) (xy 380.697719 -271.694929) (xy 380.713429 -271.745859)
			(xy 380.721372 -271.798563) (xy 380.72187 -271.825212) (xy 380.72139 -271.85092) (xy 380.979168 -271.85092)
			(xy 380.979168 -271.799504) (xy 380.987211 -271.748722) (xy 381.003099 -271.699823) (xy 381.026442 -271.654011)
			(xy 381.056663 -271.612415) (xy 381.093019 -271.576059) (xy 381.134615 -271.545838) (xy 381.180427 -271.522495)
			(xy 381.229326 -271.506607) (xy 381.280108 -271.498564) (xy 381.331524 -271.498564) (xy 381.382306 -271.506607)
			(xy 381.431205 -271.522495) (xy 381.477017 -271.545838) (xy 381.518613 -271.576059) (xy 381.554969 -271.612415)
			(xy 381.58519 -271.654011) (xy 381.608533 -271.699823) (xy 381.624421 -271.748722) (xy 381.632464 -271.799504)
			(xy 381.632968 -271.825212) (xy 381.632464 -271.85092) (xy 381.632315 -271.851861) (xy 381.890006 -271.851861)
			(xy 381.890006 -271.798563) (xy 381.897949 -271.745859) (xy 381.913659 -271.694929) (xy 381.936785 -271.646908)
			(xy 381.966809 -271.602871) (xy 382.003061 -271.5638) (xy 382.044732 -271.530569) (xy 382.09089 -271.50392)
			(xy 382.140504 -271.484448) (xy 382.192466 -271.472588) (xy 382.245616 -271.468605) (xy 382.298766 -271.472588)
			(xy 382.350728 -271.484448) (xy 382.400342 -271.50392) (xy 382.4465 -271.530569) (xy 382.488171 -271.5638)
			(xy 382.524423 -271.602871) (xy 382.554447 -271.646908) (xy 382.577573 -271.694929) (xy 382.593283 -271.745859)
			(xy 382.601226 -271.798563) (xy 382.601724 -271.825212) (xy 382.601244 -271.85092) (xy 382.858768 -271.85092)
			(xy 382.858768 -271.799504) (xy 382.866811 -271.748722) (xy 382.882699 -271.699823) (xy 382.906042 -271.654011)
			(xy 382.936263 -271.612415) (xy 382.972619 -271.576059) (xy 383.014215 -271.545838) (xy 383.060027 -271.522495)
			(xy 383.108926 -271.506607) (xy 383.159708 -271.498564) (xy 383.211124 -271.498564) (xy 383.261906 -271.506607)
			(xy 383.310805 -271.522495) (xy 383.356617 -271.545838) (xy 383.398213 -271.576059) (xy 383.434569 -271.612415)
			(xy 383.46479 -271.654011) (xy 383.488133 -271.699823) (xy 383.504021 -271.748722) (xy 383.512064 -271.799504)
			(xy 383.512568 -271.825212) (xy 383.512064 -271.85092) (xy 383.504021 -271.901702) (xy 383.488133 -271.950601)
			(xy 383.46479 -271.996413) (xy 383.434569 -272.038009) (xy 383.398213 -272.074365) (xy 383.356617 -272.104586)
			(xy 383.310805 -272.127929) (xy 383.261906 -272.143817) (xy 383.211124 -272.15186) (xy 383.159708 -272.15186)
			(xy 383.108926 -272.143817) (xy 383.060027 -272.127929) (xy 383.014215 -272.104586) (xy 382.972619 -272.074365)
			(xy 382.936263 -272.038009) (xy 382.906042 -271.996413) (xy 382.882699 -271.950601) (xy 382.866811 -271.901702)
			(xy 382.858768 -271.85092) (xy 382.601244 -271.85092) (xy 382.601226 -271.851861) (xy 382.593283 -271.904565)
			(xy 382.577573 -271.955495) (xy 382.554447 -272.003516) (xy 382.524423 -272.047553) (xy 382.488171 -272.086624)
			(xy 382.4465 -272.119855) (xy 382.400342 -272.146504) (xy 382.350728 -272.165976) (xy 382.298766 -272.177836)
			(xy 382.245616 -272.18182) (xy 382.192466 -272.177836) (xy 382.140504 -272.165976) (xy 382.09089 -272.146504)
			(xy 382.044732 -272.119855) (xy 382.003061 -272.086624) (xy 381.966809 -272.047553) (xy 381.936785 -272.003516)
			(xy 381.913659 -271.955495) (xy 381.897949 -271.904565) (xy 381.890006 -271.851861) (xy 381.632315 -271.851861)
			(xy 381.624421 -271.901702) (xy 381.608533 -271.950601) (xy 381.58519 -271.996413) (xy 381.554969 -272.038009)
			(xy 381.518613 -272.074365) (xy 381.477017 -272.104586) (xy 381.431205 -272.127929) (xy 381.382306 -272.143817)
			(xy 381.331524 -272.15186) (xy 381.280108 -272.15186) (xy 381.229326 -272.143817) (xy 381.180427 -272.127929)
			(xy 381.134615 -272.104586) (xy 381.093019 -272.074365) (xy 381.056663 -272.038009) (xy 381.026442 -271.996413)
			(xy 381.003099 -271.950601) (xy 380.987211 -271.901702) (xy 380.979168 -271.85092) (xy 380.72139 -271.85092)
			(xy 380.721372 -271.851861) (xy 380.713429 -271.904565) (xy 380.697719 -271.955495) (xy 380.674593 -272.003516)
			(xy 380.644569 -272.047553) (xy 380.608317 -272.086624) (xy 380.566646 -272.119855) (xy 380.520488 -272.146504)
			(xy 380.470874 -272.165976) (xy 380.418912 -272.177836) (xy 380.365762 -272.18182) (xy 380.312612 -272.177836)
			(xy 380.26065 -272.165976) (xy 380.211036 -272.146504) (xy 380.164878 -272.119855) (xy 380.123207 -272.086624)
			(xy 380.086955 -272.047553) (xy 380.056931 -272.003516) (xy 380.033805 -271.955495) (xy 380.018095 -271.904565)
			(xy 380.010152 -271.851861) (xy 379.752715 -271.851861) (xy 379.744821 -271.901702) (xy 379.728933 -271.950601)
			(xy 379.70559 -271.996413) (xy 379.675369 -272.038009) (xy 379.639013 -272.074365) (xy 379.597417 -272.104586)
			(xy 379.551605 -272.127929) (xy 379.502706 -272.143817) (xy 379.451924 -272.15186) (xy 379.400508 -272.15186)
			(xy 379.349726 -272.143817) (xy 379.300827 -272.127929) (xy 379.255015 -272.104586) (xy 379.213419 -272.074365)
			(xy 379.177063 -272.038009) (xy 379.146842 -271.996413) (xy 379.123499 -271.950601) (xy 379.107611 -271.901702)
			(xy 379.099568 -271.85092) (xy 378.813064 -271.85092) (xy 378.805021 -271.901702) (xy 378.789133 -271.950601)
			(xy 378.76579 -271.996413) (xy 378.735569 -272.038009) (xy 378.699213 -272.074365) (xy 378.657617 -272.104586)
			(xy 378.611805 -272.127929) (xy 378.562906 -272.143817) (xy 378.512124 -272.15186) (xy 378.460708 -272.15186)
			(xy 378.409926 -272.143817) (xy 378.361027 -272.127929) (xy 378.315215 -272.104586) (xy 378.273619 -272.074365)
			(xy 378.237263 -272.038009) (xy 378.207042 -271.996413) (xy 378.183699 -271.950601) (xy 378.167811 -271.901702)
			(xy 378.159768 -271.85092) (xy 377.902244 -271.85092) (xy 377.902226 -271.851861) (xy 377.894283 -271.904565)
			(xy 377.878573 -271.955495) (xy 377.855447 -272.003516) (xy 377.825423 -272.047553) (xy 377.789171 -272.086624)
			(xy 377.7475 -272.119855) (xy 377.701342 -272.146504) (xy 377.651728 -272.165976) (xy 377.599766 -272.177836)
			(xy 377.546616 -272.18182) (xy 377.493466 -272.177836) (xy 377.441504 -272.165976) (xy 377.39189 -272.146504)
			(xy 377.345732 -272.119855) (xy 377.304061 -272.086624) (xy 377.267809 -272.047553) (xy 377.237785 -272.003516)
			(xy 377.214659 -271.955495) (xy 377.198949 -271.904565) (xy 377.191006 -271.851861) (xy 376.933315 -271.851861)
			(xy 376.925421 -271.901702) (xy 376.909533 -271.950601) (xy 376.88619 -271.996413) (xy 376.855969 -272.038009)
			(xy 376.819613 -272.074365) (xy 376.778017 -272.104586) (xy 376.732205 -272.127929) (xy 376.683306 -272.143817)
			(xy 376.632524 -272.15186) (xy 376.581108 -272.15186) (xy 376.530326 -272.143817) (xy 376.481427 -272.127929)
			(xy 376.435615 -272.104586) (xy 376.394019 -272.074365) (xy 376.357663 -272.038009) (xy 376.327442 -271.996413)
			(xy 376.304099 -271.950601) (xy 376.288211 -271.901702) (xy 376.280168 -271.85092) (xy 376.022644 -271.85092)
			(xy 376.022626 -271.851861) (xy 376.014683 -271.904565) (xy 375.998973 -271.955495) (xy 375.975847 -272.003516)
			(xy 375.945823 -272.047553) (xy 375.909571 -272.086624) (xy 375.8679 -272.119855) (xy 375.821742 -272.146504)
			(xy 375.772128 -272.165976) (xy 375.720166 -272.177836) (xy 375.667016 -272.18182) (xy 375.613866 -272.177836)
			(xy 375.561904 -272.165976) (xy 375.51229 -272.146504) (xy 375.466132 -272.119855) (xy 375.424461 -272.086624)
			(xy 375.388209 -272.047553) (xy 375.358185 -272.003516) (xy 375.335059 -271.955495) (xy 375.319349 -271.904565)
			(xy 375.311406 -271.851861) (xy 375.053715 -271.851861) (xy 375.045821 -271.901702) (xy 375.029933 -271.950601)
			(xy 375.00659 -271.996413) (xy 374.976369 -272.038009) (xy 374.940013 -272.074365) (xy 374.898417 -272.104586)
			(xy 374.852605 -272.127929) (xy 374.803706 -272.143817) (xy 374.752924 -272.15186) (xy 374.701508 -272.15186)
			(xy 374.650726 -272.143817) (xy 374.601827 -272.127929) (xy 374.556015 -272.104586) (xy 374.514419 -272.074365)
			(xy 374.478063 -272.038009) (xy 374.447842 -271.996413) (xy 374.424499 -271.950601) (xy 374.408611 -271.901702)
			(xy 374.400568 -271.85092) (xy 374.14279 -271.85092) (xy 374.142772 -271.851861) (xy 374.134829 -271.904565)
			(xy 374.119119 -271.955495) (xy 374.095993 -272.003516) (xy 374.065969 -272.047553) (xy 374.029717 -272.086624)
			(xy 373.988046 -272.119855) (xy 373.941888 -272.146504) (xy 373.892274 -272.165976) (xy 373.840312 -272.177836)
			(xy 373.787162 -272.18182) (xy 373.734012 -272.177836) (xy 373.68205 -272.165976) (xy 373.632436 -272.146504)
			(xy 373.586278 -272.119855) (xy 373.544607 -272.086624) (xy 373.508355 -272.047553) (xy 373.478331 -272.003516)
			(xy 373.455205 -271.955495) (xy 373.439495 -271.904565) (xy 373.431552 -271.851861) (xy 373.174115 -271.851861)
			(xy 373.166221 -271.901702) (xy 373.150333 -271.950601) (xy 373.12699 -271.996413) (xy 373.096769 -272.038009)
			(xy 373.060413 -272.074365) (xy 373.018817 -272.104586) (xy 372.973005 -272.127929) (xy 372.924106 -272.143817)
			(xy 372.873324 -272.15186) (xy 372.821908 -272.15186) (xy 372.771126 -272.143817) (xy 372.722227 -272.127929)
			(xy 372.676415 -272.104586) (xy 372.634819 -272.074365) (xy 372.598463 -272.038009) (xy 372.568242 -271.996413)
			(xy 372.544899 -271.950601) (xy 372.529011 -271.901702) (xy 372.520968 -271.85092) (xy 372.234464 -271.85092)
			(xy 372.226421 -271.901702) (xy 372.210533 -271.950601) (xy 372.18719 -271.996413) (xy 372.156969 -272.038009)
			(xy 372.120613 -272.074365) (xy 372.079017 -272.104586) (xy 372.033205 -272.127929) (xy 371.984306 -272.143817)
			(xy 371.933524 -272.15186) (xy 371.882108 -272.15186) (xy 371.831326 -272.143817) (xy 371.782427 -272.127929)
			(xy 371.736615 -272.104586) (xy 371.695019 -272.074365) (xy 371.658663 -272.038009) (xy 371.628442 -271.996413)
			(xy 371.605099 -271.950601) (xy 371.589211 -271.901702) (xy 371.581168 -271.85092) (xy 371.323644 -271.85092)
			(xy 371.323626 -271.851861) (xy 371.315683 -271.904565) (xy 371.299973 -271.955495) (xy 371.276847 -272.003516)
			(xy 371.246823 -272.047553) (xy 371.210571 -272.086624) (xy 371.1689 -272.119855) (xy 371.122742 -272.146504)
			(xy 371.073128 -272.165976) (xy 371.021166 -272.177836) (xy 370.968016 -272.18182) (xy 370.914866 -272.177836)
			(xy 370.862904 -272.165976) (xy 370.81329 -272.146504) (xy 370.767132 -272.119855) (xy 370.725461 -272.086624)
			(xy 370.689209 -272.047553) (xy 370.659185 -272.003516) (xy 370.636059 -271.955495) (xy 370.620349 -271.904565)
			(xy 370.612406 -271.851861) (xy 370.383826 -271.851861) (xy 370.375883 -271.904565) (xy 370.360173 -271.955495)
			(xy 370.337047 -272.003516) (xy 370.307023 -272.047553) (xy 370.270771 -272.086624) (xy 370.2291 -272.119855)
			(xy 370.182942 -272.146504) (xy 370.133328 -272.165976) (xy 370.081366 -272.177836) (xy 370.028216 -272.18182)
			(xy 369.975066 -272.177836) (xy 369.923104 -272.165976) (xy 369.87349 -272.146504) (xy 369.827332 -272.119855)
			(xy 369.785661 -272.086624) (xy 369.749409 -272.047553) (xy 369.719385 -272.003516) (xy 369.696259 -271.955495)
			(xy 369.680549 -271.904565) (xy 369.672606 -271.851861) (xy 369.444026 -271.851861) (xy 369.436083 -271.904565)
			(xy 369.420373 -271.955495) (xy 369.397247 -272.003516) (xy 369.367223 -272.047553) (xy 369.330971 -272.086624)
			(xy 369.2893 -272.119855) (xy 369.243142 -272.146504) (xy 369.193528 -272.165976) (xy 369.141566 -272.177836)
			(xy 369.088416 -272.18182) (xy 369.035266 -272.177836) (xy 368.983304 -272.165976) (xy 368.93369 -272.146504)
			(xy 368.887532 -272.119855) (xy 368.845861 -272.086624) (xy 368.809609 -272.047553) (xy 368.779585 -272.003516)
			(xy 368.756459 -271.955495) (xy 368.740749 -271.904565) (xy 368.732806 -271.851861) (xy 368.504226 -271.851861)
			(xy 368.496283 -271.904565) (xy 368.480573 -271.955495) (xy 368.457447 -272.003516) (xy 368.427423 -272.047553)
			(xy 368.391171 -272.086624) (xy 368.3495 -272.119855) (xy 368.303342 -272.146504) (xy 368.253728 -272.165976)
			(xy 368.201766 -272.177836) (xy 368.148616 -272.18182) (xy 368.095466 -272.177836) (xy 368.043504 -272.165976)
			(xy 367.99389 -272.146504) (xy 367.947732 -272.119855) (xy 367.906061 -272.086624) (xy 367.869809 -272.047553)
			(xy 367.839785 -272.003516) (xy 367.816659 -271.955495) (xy 367.800949 -271.904565) (xy 367.793006 -271.851861)
			(xy 367.563918 -271.851861) (xy 367.555975 -271.904565) (xy 367.540265 -271.955495) (xy 367.517139 -272.003516)
			(xy 367.487115 -272.047553) (xy 367.450863 -272.086624) (xy 367.409192 -272.119855) (xy 367.363034 -272.146504)
			(xy 367.31342 -272.165976) (xy 367.261458 -272.177836) (xy 367.208308 -272.18182) (xy 367.155158 -272.177836)
			(xy 367.103196 -272.165976) (xy 367.053582 -272.146504) (xy 367.007424 -272.119855) (xy 366.965753 -272.086624)
			(xy 366.929501 -272.047553) (xy 366.899477 -272.003516) (xy 366.876351 -271.955495) (xy 366.860641 -271.904565)
			(xy 366.852698 -271.851861) (xy 366.624118 -271.851861) (xy 366.616175 -271.904565) (xy 366.600465 -271.955495)
			(xy 366.577339 -272.003516) (xy 366.547315 -272.047553) (xy 366.511063 -272.086624) (xy 366.469392 -272.119855)
			(xy 366.423234 -272.146504) (xy 366.37362 -272.165976) (xy 366.321658 -272.177836) (xy 366.268508 -272.18182)
			(xy 366.215358 -272.177836) (xy 366.163396 -272.165976) (xy 366.113782 -272.146504) (xy 366.067624 -272.119855)
			(xy 366.025953 -272.086624) (xy 365.989701 -272.047553) (xy 365.959677 -272.003516) (xy 365.936551 -271.955495)
			(xy 365.920841 -271.904565) (xy 365.912898 -271.851861) (xy 365.684826 -271.851861) (xy 365.676883 -271.904565)
			(xy 365.661173 -271.955495) (xy 365.638047 -272.003516) (xy 365.608023 -272.047553) (xy 365.571771 -272.086624)
			(xy 365.5301 -272.119855) (xy 365.483942 -272.146504) (xy 365.434328 -272.165976) (xy 365.382366 -272.177836)
			(xy 365.329216 -272.18182) (xy 365.276066 -272.177836) (xy 365.224104 -272.165976) (xy 365.17449 -272.146504)
			(xy 365.128332 -272.119855) (xy 365.086661 -272.086624) (xy 365.050409 -272.047553) (xy 365.020385 -272.003516)
			(xy 364.997259 -271.955495) (xy 364.981549 -271.904565) (xy 364.973606 -271.851861) (xy 364.744518 -271.851861)
			(xy 364.736575 -271.904565) (xy 364.720865 -271.955495) (xy 364.697739 -272.003516) (xy 364.667715 -272.047553)
			(xy 364.631463 -272.086624) (xy 364.589792 -272.119855) (xy 364.543634 -272.146504) (xy 364.49402 -272.165976)
			(xy 364.442058 -272.177836) (xy 364.388908 -272.18182) (xy 364.335758 -272.177836) (xy 364.283796 -272.165976)
			(xy 364.234182 -272.146504) (xy 364.188024 -272.119855) (xy 364.146353 -272.086624) (xy 364.110101 -272.047553)
			(xy 364.080077 -272.003516) (xy 364.056951 -271.955495) (xy 364.041241 -271.904565) (xy 364.033298 -271.851861)
			(xy 363.805226 -271.851861) (xy 363.797283 -271.904565) (xy 363.781573 -271.955495) (xy 363.758447 -272.003516)
			(xy 363.728423 -272.047553) (xy 363.692171 -272.086624) (xy 363.6505 -272.119855) (xy 363.604342 -272.146504)
			(xy 363.554728 -272.165976) (xy 363.502766 -272.177836) (xy 363.449616 -272.18182) (xy 363.396466 -272.177836)
			(xy 363.344504 -272.165976) (xy 363.29489 -272.146504) (xy 363.248732 -272.119855) (xy 363.207061 -272.086624)
			(xy 363.170809 -272.047553) (xy 363.140785 -272.003516) (xy 363.117659 -271.955495) (xy 363.101949 -271.904565)
			(xy 363.094006 -271.851861) (xy 362.864398 -271.851861) (xy 362.862413 -271.878346) (xy 362.850554 -271.930305)
			(xy 362.831083 -271.979917) (xy 362.804436 -272.026072) (xy 362.771208 -272.067741) (xy 362.732141 -272.103992)
			(xy 362.688107 -272.134015) (xy 362.64009 -272.157141) (xy 362.589163 -272.172852) (xy 362.536464 -272.180797)
			(xy 362.509816 -272.18132) (xy 362.48467 -272.180558) (xy 362.470782 -272.180062) (xy 362.443577 -272.185672)
			(xy 362.418892 -272.198409) (xy 362.398555 -272.217329) (xy 362.384073 -272.241033) (xy 362.376518 -272.267763)
			(xy 362.375958 -272.28165) (xy 362.375958 -272.521934) (xy 362.385197 -272.550322) (xy 362.395153 -272.609181)
			(xy 362.39577 -272.639028) (xy 362.39577 -272.639536) (xy 362.395236 -272.665931) (xy 362.623852 -272.665931)
			(xy 362.623852 -272.612633) (xy 362.631795 -272.559929) (xy 362.647505 -272.508999) (xy 362.670631 -272.460978)
			(xy 362.700655 -272.416941) (xy 362.736907 -272.37787) (xy 362.778578 -272.344639) (xy 362.824736 -272.31799)
			(xy 362.87435 -272.298518) (xy 362.926312 -272.286658) (xy 362.979462 -272.282675) (xy 363.032612 -272.286658)
			(xy 363.084574 -272.298518) (xy 363.134188 -272.31799) (xy 363.180346 -272.344639) (xy 363.222017 -272.37787)
			(xy 363.258269 -272.416941) (xy 363.288293 -272.460978) (xy 363.311419 -272.508999) (xy 363.327129 -272.559929)
			(xy 363.335072 -272.612633) (xy 363.33557 -272.639282) (xy 363.335072 -272.665931) (xy 363.563652 -272.665931)
			(xy 363.563652 -272.612633) (xy 363.571595 -272.559929) (xy 363.587305 -272.508999) (xy 363.610431 -272.460978)
			(xy 363.640455 -272.416941) (xy 363.676707 -272.37787) (xy 363.718378 -272.344639) (xy 363.764536 -272.31799)
			(xy 363.81415 -272.298518) (xy 363.866112 -272.286658) (xy 363.919262 -272.282675) (xy 363.972412 -272.286658)
			(xy 364.024374 -272.298518) (xy 364.073988 -272.31799) (xy 364.120146 -272.344639) (xy 364.161817 -272.37787)
			(xy 364.198069 -272.416941) (xy 364.228093 -272.460978) (xy 364.251219 -272.508999) (xy 364.266929 -272.559929)
			(xy 364.274872 -272.612633) (xy 364.27537 -272.639282) (xy 364.274872 -272.665931) (xy 364.503452 -272.665931)
			(xy 364.503452 -272.612633) (xy 364.511395 -272.559929) (xy 364.527105 -272.508999) (xy 364.550231 -272.460978)
			(xy 364.580255 -272.416941) (xy 364.616507 -272.37787) (xy 364.658178 -272.344639) (xy 364.704336 -272.31799)
			(xy 364.75395 -272.298518) (xy 364.805912 -272.286658) (xy 364.859062 -272.282675) (xy 364.912212 -272.286658)
			(xy 364.964174 -272.298518) (xy 365.013788 -272.31799) (xy 365.059946 -272.344639) (xy 365.101617 -272.37787)
			(xy 365.137869 -272.416941) (xy 365.167893 -272.460978) (xy 365.191019 -272.508999) (xy 365.206729 -272.559929)
			(xy 365.214672 -272.612633) (xy 365.21517 -272.639282) (xy 365.214672 -272.665931) (xy 365.443252 -272.665931)
			(xy 365.443252 -272.612633) (xy 365.451195 -272.559929) (xy 365.466905 -272.508999) (xy 365.490031 -272.460978)
			(xy 365.520055 -272.416941) (xy 365.556307 -272.37787) (xy 365.597978 -272.344639) (xy 365.644136 -272.31799)
			(xy 365.69375 -272.298518) (xy 365.745712 -272.286658) (xy 365.798862 -272.282675) (xy 365.852012 -272.286658)
			(xy 365.903974 -272.298518) (xy 365.953588 -272.31799) (xy 365.999746 -272.344639) (xy 366.041417 -272.37787)
			(xy 366.077669 -272.416941) (xy 366.107693 -272.460978) (xy 366.130819 -272.508999) (xy 366.146529 -272.559929)
			(xy 366.154472 -272.612633) (xy 366.15497 -272.639282) (xy 366.154472 -272.665931) (xy 366.383052 -272.665931)
			(xy 366.383052 -272.612633) (xy 366.390995 -272.559929) (xy 366.406705 -272.508999) (xy 366.429831 -272.460978)
			(xy 366.459855 -272.416941) (xy 366.496107 -272.37787) (xy 366.537778 -272.344639) (xy 366.583936 -272.31799)
			(xy 366.63355 -272.298518) (xy 366.685512 -272.286658) (xy 366.738662 -272.282675) (xy 366.791812 -272.286658)
			(xy 366.843774 -272.298518) (xy 366.893388 -272.31799) (xy 366.939546 -272.344639) (xy 366.981217 -272.37787)
			(xy 367.017469 -272.416941) (xy 367.047493 -272.460978) (xy 367.070619 -272.508999) (xy 367.086329 -272.559929)
			(xy 367.094272 -272.612633) (xy 367.09477 -272.639282) (xy 367.094272 -272.665931) (xy 367.322852 -272.665931)
			(xy 367.322852 -272.612633) (xy 367.330795 -272.559929) (xy 367.346505 -272.508999) (xy 367.369631 -272.460978)
			(xy 367.399655 -272.416941) (xy 367.435907 -272.37787) (xy 367.477578 -272.344639) (xy 367.523736 -272.31799)
			(xy 367.57335 -272.298518) (xy 367.625312 -272.286658) (xy 367.678462 -272.282675) (xy 367.731612 -272.286658)
			(xy 367.783574 -272.298518) (xy 367.833188 -272.31799) (xy 367.879346 -272.344639) (xy 367.921017 -272.37787)
			(xy 367.957269 -272.416941) (xy 367.987293 -272.460978) (xy 368.010419 -272.508999) (xy 368.026129 -272.559929)
			(xy 368.034072 -272.612633) (xy 368.03457 -272.639282) (xy 368.034072 -272.665931) (xy 368.262652 -272.665931)
			(xy 368.262652 -272.612633) (xy 368.270595 -272.559929) (xy 368.286305 -272.508999) (xy 368.309431 -272.460978)
			(xy 368.339455 -272.416941) (xy 368.375707 -272.37787) (xy 368.417378 -272.344639) (xy 368.463536 -272.31799)
			(xy 368.51315 -272.298518) (xy 368.565112 -272.286658) (xy 368.618262 -272.282675) (xy 368.671412 -272.286658)
			(xy 368.723374 -272.298518) (xy 368.772988 -272.31799) (xy 368.819146 -272.344639) (xy 368.860817 -272.37787)
			(xy 368.897069 -272.416941) (xy 368.927093 -272.460978) (xy 368.950219 -272.508999) (xy 368.965929 -272.559929)
			(xy 368.973872 -272.612633) (xy 368.97437 -272.639282) (xy 368.973872 -272.665931) (xy 369.202452 -272.665931)
			(xy 369.202452 -272.612633) (xy 369.210395 -272.559929) (xy 369.226105 -272.508999) (xy 369.249231 -272.460978)
			(xy 369.279255 -272.416941) (xy 369.315507 -272.37787) (xy 369.357178 -272.344639) (xy 369.403336 -272.31799)
			(xy 369.45295 -272.298518) (xy 369.504912 -272.286658) (xy 369.558062 -272.282675) (xy 369.611212 -272.286658)
			(xy 369.663174 -272.298518) (xy 369.712788 -272.31799) (xy 369.758946 -272.344639) (xy 369.800617 -272.37787)
			(xy 369.836869 -272.416941) (xy 369.866893 -272.460978) (xy 369.890019 -272.508999) (xy 369.905729 -272.559929)
			(xy 369.913672 -272.612633) (xy 369.91417 -272.639282) (xy 369.913672 -272.665931) (xy 370.142252 -272.665931)
			(xy 370.142252 -272.612633) (xy 370.150195 -272.559929) (xy 370.165905 -272.508999) (xy 370.189031 -272.460978)
			(xy 370.219055 -272.416941) (xy 370.255307 -272.37787) (xy 370.296978 -272.344639) (xy 370.343136 -272.31799)
			(xy 370.39275 -272.298518) (xy 370.444712 -272.286658) (xy 370.497862 -272.282675) (xy 370.551012 -272.286658)
			(xy 370.602974 -272.298518) (xy 370.652588 -272.31799) (xy 370.698746 -272.344639) (xy 370.740417 -272.37787)
			(xy 370.776669 -272.416941) (xy 370.806693 -272.460978) (xy 370.829819 -272.508999) (xy 370.845529 -272.559929)
			(xy 370.853472 -272.612633) (xy 370.85397 -272.639282) (xy 370.853472 -272.665931) (xy 371.082052 -272.665931)
			(xy 371.082052 -272.612633) (xy 371.089995 -272.559929) (xy 371.105705 -272.508999) (xy 371.128831 -272.460978)
			(xy 371.158855 -272.416941) (xy 371.195107 -272.37787) (xy 371.236778 -272.344639) (xy 371.282936 -272.31799)
			(xy 371.33255 -272.298518) (xy 371.384512 -272.286658) (xy 371.437662 -272.282675) (xy 371.490812 -272.286658)
			(xy 371.542774 -272.298518) (xy 371.592388 -272.31799) (xy 371.638546 -272.344639) (xy 371.680217 -272.37787)
			(xy 371.716469 -272.416941) (xy 371.746493 -272.460978) (xy 371.769619 -272.508999) (xy 371.785329 -272.559929)
			(xy 371.793272 -272.612633) (xy 371.79377 -272.639282) (xy 371.793272 -272.665931) (xy 372.021852 -272.665931)
			(xy 372.021852 -272.612633) (xy 372.029795 -272.559929) (xy 372.045505 -272.508999) (xy 372.068631 -272.460978)
			(xy 372.098655 -272.416941) (xy 372.134907 -272.37787) (xy 372.176578 -272.344639) (xy 372.222736 -272.31799)
			(xy 372.27235 -272.298518) (xy 372.324312 -272.286658) (xy 372.377462 -272.282675) (xy 372.430612 -272.286658)
			(xy 372.482574 -272.298518) (xy 372.532188 -272.31799) (xy 372.578346 -272.344639) (xy 372.620017 -272.37787)
			(xy 372.656269 -272.416941) (xy 372.686293 -272.460978) (xy 372.709419 -272.508999) (xy 372.725129 -272.559929)
			(xy 372.733072 -272.612633) (xy 372.73357 -272.639282) (xy 372.733072 -272.665931) (xy 372.961906 -272.665931)
			(xy 372.961906 -272.612633) (xy 372.969849 -272.559929) (xy 372.985559 -272.508999) (xy 373.008685 -272.460978)
			(xy 373.038709 -272.416941) (xy 373.074961 -272.37787) (xy 373.116632 -272.344639) (xy 373.16279 -272.31799)
			(xy 373.212404 -272.298518) (xy 373.264366 -272.286658) (xy 373.317516 -272.282675) (xy 373.370666 -272.286658)
			(xy 373.422628 -272.298518) (xy 373.472242 -272.31799) (xy 373.5184 -272.344639) (xy 373.560071 -272.37787)
			(xy 373.596323 -272.416941) (xy 373.626347 -272.460978) (xy 373.649473 -272.508999) (xy 373.665183 -272.559929)
			(xy 373.673126 -272.612633) (xy 373.673624 -272.639282) (xy 373.673144 -272.66499) (xy 373.930414 -272.66499)
			(xy 373.930414 -272.613574) (xy 373.938457 -272.562792) (xy 373.954345 -272.513893) (xy 373.977688 -272.468081)
			(xy 374.007909 -272.426485) (xy 374.044265 -272.390129) (xy 374.085861 -272.359908) (xy 374.131673 -272.336565)
			(xy 374.180572 -272.320677) (xy 374.231354 -272.312634) (xy 374.28277 -272.312634) (xy 374.333552 -272.320677)
			(xy 374.382451 -272.336565) (xy 374.428263 -272.359908) (xy 374.469859 -272.390129) (xy 374.506215 -272.426485)
			(xy 374.536436 -272.468081) (xy 374.559779 -272.513893) (xy 374.575667 -272.562792) (xy 374.58371 -272.613574)
			(xy 374.584214 -272.639282) (xy 374.58371 -272.66499) (xy 374.870214 -272.66499) (xy 374.870214 -272.613574)
			(xy 374.878257 -272.562792) (xy 374.894145 -272.513893) (xy 374.917488 -272.468081) (xy 374.947709 -272.426485)
			(xy 374.984065 -272.390129) (xy 375.025661 -272.359908) (xy 375.071473 -272.336565) (xy 375.120372 -272.320677)
			(xy 375.171154 -272.312634) (xy 375.22257 -272.312634) (xy 375.273352 -272.320677) (xy 375.322251 -272.336565)
			(xy 375.368063 -272.359908) (xy 375.409659 -272.390129) (xy 375.446015 -272.426485) (xy 375.476236 -272.468081)
			(xy 375.499579 -272.513893) (xy 375.515467 -272.562792) (xy 375.52351 -272.613574) (xy 375.524014 -272.639282)
			(xy 375.52351 -272.66499) (xy 375.810014 -272.66499) (xy 375.810014 -272.613574) (xy 375.818057 -272.562792)
			(xy 375.833945 -272.513893) (xy 375.857288 -272.468081) (xy 375.887509 -272.426485) (xy 375.923865 -272.390129)
			(xy 375.965461 -272.359908) (xy 376.011273 -272.336565) (xy 376.060172 -272.320677) (xy 376.110954 -272.312634)
			(xy 376.16237 -272.312634) (xy 376.213152 -272.320677) (xy 376.262051 -272.336565) (xy 376.307863 -272.359908)
			(xy 376.349459 -272.390129) (xy 376.385815 -272.426485) (xy 376.416036 -272.468081) (xy 376.439379 -272.513893)
			(xy 376.455267 -272.562792) (xy 376.46331 -272.613574) (xy 376.463814 -272.639282) (xy 376.46331 -272.66499)
			(xy 376.749814 -272.66499) (xy 376.749814 -272.613574) (xy 376.757857 -272.562792) (xy 376.773745 -272.513893)
			(xy 376.797088 -272.468081) (xy 376.827309 -272.426485) (xy 376.863665 -272.390129) (xy 376.905261 -272.359908)
			(xy 376.951073 -272.336565) (xy 376.999972 -272.320677) (xy 377.050754 -272.312634) (xy 377.10217 -272.312634)
			(xy 377.152952 -272.320677) (xy 377.201851 -272.336565) (xy 377.247663 -272.359908) (xy 377.289259 -272.390129)
			(xy 377.325615 -272.426485) (xy 377.355836 -272.468081) (xy 377.379179 -272.513893) (xy 377.395067 -272.562792)
			(xy 377.40311 -272.613574) (xy 377.403614 -272.639282) (xy 377.40311 -272.66499) (xy 377.402961 -272.665931)
			(xy 377.660652 -272.665931) (xy 377.660652 -272.612633) (xy 377.668595 -272.559929) (xy 377.684305 -272.508999)
			(xy 377.707431 -272.460978) (xy 377.737455 -272.416941) (xy 377.773707 -272.37787) (xy 377.815378 -272.344639)
			(xy 377.861536 -272.31799) (xy 377.91115 -272.298518) (xy 377.963112 -272.286658) (xy 378.016262 -272.282675)
			(xy 378.069412 -272.286658) (xy 378.121374 -272.298518) (xy 378.170988 -272.31799) (xy 378.217146 -272.344639)
			(xy 378.258817 -272.37787) (xy 378.295069 -272.416941) (xy 378.325093 -272.460978) (xy 378.348219 -272.508999)
			(xy 378.363929 -272.559929) (xy 378.371872 -272.612633) (xy 378.37237 -272.639282) (xy 378.371872 -272.665931)
			(xy 378.600452 -272.665931) (xy 378.600452 -272.612633) (xy 378.608395 -272.559929) (xy 378.624105 -272.508999)
			(xy 378.647231 -272.460978) (xy 378.677255 -272.416941) (xy 378.713507 -272.37787) (xy 378.755178 -272.344639)
			(xy 378.801336 -272.31799) (xy 378.85095 -272.298518) (xy 378.902912 -272.286658) (xy 378.956062 -272.282675)
			(xy 379.009212 -272.286658) (xy 379.061174 -272.298518) (xy 379.110788 -272.31799) (xy 379.156946 -272.344639)
			(xy 379.198617 -272.37787) (xy 379.234869 -272.416941) (xy 379.264893 -272.460978) (xy 379.288019 -272.508999)
			(xy 379.303729 -272.559929) (xy 379.311672 -272.612633) (xy 379.31217 -272.639282) (xy 379.311672 -272.665931)
			(xy 379.540506 -272.665931) (xy 379.540506 -272.612633) (xy 379.548449 -272.559929) (xy 379.564159 -272.508999)
			(xy 379.587285 -272.460978) (xy 379.617309 -272.416941) (xy 379.653561 -272.37787) (xy 379.695232 -272.344639)
			(xy 379.74139 -272.31799) (xy 379.791004 -272.298518) (xy 379.842966 -272.286658) (xy 379.896116 -272.282675)
			(xy 379.949266 -272.286658) (xy 380.001228 -272.298518) (xy 380.050842 -272.31799) (xy 380.097 -272.344639)
			(xy 380.138671 -272.37787) (xy 380.174923 -272.416941) (xy 380.204947 -272.460978) (xy 380.228073 -272.508999)
			(xy 380.243783 -272.559929) (xy 380.251726 -272.612633) (xy 380.252224 -272.639282) (xy 380.251744 -272.66499)
			(xy 380.509014 -272.66499) (xy 380.509014 -272.613574) (xy 380.517057 -272.562792) (xy 380.532945 -272.513893)
			(xy 380.556288 -272.468081) (xy 380.586509 -272.426485) (xy 380.622865 -272.390129) (xy 380.664461 -272.359908)
			(xy 380.710273 -272.336565) (xy 380.759172 -272.320677) (xy 380.809954 -272.312634) (xy 380.86137 -272.312634)
			(xy 380.912152 -272.320677) (xy 380.961051 -272.336565) (xy 381.006863 -272.359908) (xy 381.048459 -272.390129)
			(xy 381.084815 -272.426485) (xy 381.115036 -272.468081) (xy 381.138379 -272.513893) (xy 381.154267 -272.562792)
			(xy 381.16231 -272.613574) (xy 381.162814 -272.639282) (xy 381.16231 -272.66499) (xy 381.448814 -272.66499)
			(xy 381.448814 -272.613574) (xy 381.456857 -272.562792) (xy 381.472745 -272.513893) (xy 381.496088 -272.468081)
			(xy 381.526309 -272.426485) (xy 381.562665 -272.390129) (xy 381.604261 -272.359908) (xy 381.650073 -272.336565)
			(xy 381.698972 -272.320677) (xy 381.749754 -272.312634) (xy 381.80117 -272.312634) (xy 381.851952 -272.320677)
			(xy 381.900851 -272.336565) (xy 381.946663 -272.359908) (xy 381.988259 -272.390129) (xy 382.024615 -272.426485)
			(xy 382.054836 -272.468081) (xy 382.078179 -272.513893) (xy 382.094067 -272.562792) (xy 382.10211 -272.613574)
			(xy 382.102614 -272.639282) (xy 382.10211 -272.66499) (xy 382.388614 -272.66499) (xy 382.388614 -272.613574)
			(xy 382.396657 -272.562792) (xy 382.412545 -272.513893) (xy 382.435888 -272.468081) (xy 382.466109 -272.426485)
			(xy 382.502465 -272.390129) (xy 382.544061 -272.359908) (xy 382.589873 -272.336565) (xy 382.638772 -272.320677)
			(xy 382.689554 -272.312634) (xy 382.74097 -272.312634) (xy 382.791752 -272.320677) (xy 382.840651 -272.336565)
			(xy 382.886463 -272.359908) (xy 382.928059 -272.390129) (xy 382.964415 -272.426485) (xy 382.994636 -272.468081)
			(xy 383.017979 -272.513893) (xy 383.033867 -272.562792) (xy 383.04191 -272.613574) (xy 383.042414 -272.639282)
			(xy 383.04191 -272.66499) (xy 383.328414 -272.66499) (xy 383.328414 -272.613574) (xy 383.336457 -272.562792)
			(xy 383.352345 -272.513893) (xy 383.375688 -272.468081) (xy 383.405909 -272.426485) (xy 383.442265 -272.390129)
			(xy 383.483861 -272.359908) (xy 383.529673 -272.336565) (xy 383.578572 -272.320677) (xy 383.629354 -272.312634)
			(xy 383.68077 -272.312634) (xy 383.731552 -272.320677) (xy 383.780451 -272.336565) (xy 383.826263 -272.359908)
			(xy 383.867859 -272.390129) (xy 383.904215 -272.426485) (xy 383.934436 -272.468081) (xy 383.957779 -272.513893)
			(xy 383.973667 -272.562792) (xy 383.98171 -272.613574) (xy 383.982214 -272.639282) (xy 383.98171 -272.66499)
			(xy 383.981561 -272.665931) (xy 384.239252 -272.665931) (xy 384.239252 -272.612633) (xy 384.247195 -272.559929)
			(xy 384.262905 -272.508999) (xy 384.286031 -272.460978) (xy 384.316055 -272.416941) (xy 384.352307 -272.37787)
			(xy 384.393978 -272.344639) (xy 384.440136 -272.31799) (xy 384.48975 -272.298518) (xy 384.541712 -272.286658)
			(xy 384.594862 -272.282675) (xy 384.648012 -272.286658) (xy 384.699974 -272.298518) (xy 384.749588 -272.31799)
			(xy 384.795746 -272.344639) (xy 384.837417 -272.37787) (xy 384.873669 -272.416941) (xy 384.903693 -272.460978)
			(xy 384.926819 -272.508999) (xy 384.942529 -272.559929) (xy 384.950472 -272.612633) (xy 384.95097 -272.639282)
			(xy 385.190749 -272.639282) (xy 385.194779 -272.586784) (xy 385.206776 -272.535516) (xy 385.226459 -272.486681)
			(xy 385.253365 -272.441422) (xy 385.286865 -272.400801) (xy 385.326173 -272.36577) (xy 385.370368 -272.33715)
			(xy 385.418413 -272.315611) (xy 385.469184 -272.301659) (xy 385.521489 -272.295621) (xy 385.574103 -272.297638)
			(xy 385.625793 -272.307662) (xy 385.675346 -272.32546) (xy 385.721602 -272.350613) (xy 385.763476 -272.382532)
			(xy 385.799988 -272.42047) (xy 385.83028 -272.463536) (xy 385.853643 -272.510721) (xy 385.869529 -272.56092)
			(xy 385.877566 -272.612956) (xy 385.87807 -272.639282) (xy 385.877566 -272.665608) (xy 385.869529 -272.717644)
			(xy 385.853643 -272.767843) (xy 385.83028 -272.815028) (xy 385.799988 -272.858094) (xy 385.763476 -272.896032)
			(xy 385.721602 -272.927951) (xy 385.675346 -272.953104) (xy 385.625793 -272.970902) (xy 385.574103 -272.980926)
			(xy 385.521489 -272.982943) (xy 385.469184 -272.976905) (xy 385.418413 -272.962953) (xy 385.370368 -272.941414)
			(xy 385.326173 -272.912794) (xy 385.286865 -272.877763) (xy 385.253365 -272.837142) (xy 385.226459 -272.791883)
			(xy 385.206776 -272.743048) (xy 385.194779 -272.69178) (xy 385.190749 -272.639282) (xy 384.95097 -272.639282)
			(xy 384.950472 -272.665931) (xy 384.942529 -272.718635) (xy 384.926819 -272.769565) (xy 384.903693 -272.817586)
			(xy 384.873669 -272.861623) (xy 384.837417 -272.900694) (xy 384.795746 -272.933925) (xy 384.749588 -272.960574)
			(xy 384.699974 -272.980046) (xy 384.648012 -272.991906) (xy 384.594862 -272.99589) (xy 384.541712 -272.991906)
			(xy 384.48975 -272.980046) (xy 384.440136 -272.960574) (xy 384.393978 -272.933925) (xy 384.352307 -272.900694)
			(xy 384.316055 -272.861623) (xy 384.286031 -272.817586) (xy 384.262905 -272.769565) (xy 384.247195 -272.718635)
			(xy 384.239252 -272.665931) (xy 383.981561 -272.665931) (xy 383.973667 -272.715772) (xy 383.957779 -272.764671)
			(xy 383.934436 -272.810483) (xy 383.904215 -272.852079) (xy 383.867859 -272.888435) (xy 383.826263 -272.918656)
			(xy 383.780451 -272.941999) (xy 383.731552 -272.957887) (xy 383.68077 -272.96593) (xy 383.629354 -272.96593)
			(xy 383.578572 -272.957887) (xy 383.529673 -272.941999) (xy 383.483861 -272.918656) (xy 383.442265 -272.888435)
			(xy 383.405909 -272.852079) (xy 383.375688 -272.810483) (xy 383.352345 -272.764671) (xy 383.336457 -272.715772)
			(xy 383.328414 -272.66499) (xy 383.04191 -272.66499) (xy 383.033867 -272.715772) (xy 383.017979 -272.764671)
			(xy 382.994636 -272.810483) (xy 382.964415 -272.852079) (xy 382.928059 -272.888435) (xy 382.886463 -272.918656)
			(xy 382.840651 -272.941999) (xy 382.791752 -272.957887) (xy 382.74097 -272.96593) (xy 382.689554 -272.96593)
			(xy 382.638772 -272.957887) (xy 382.589873 -272.941999) (xy 382.544061 -272.918656) (xy 382.502465 -272.888435)
			(xy 382.466109 -272.852079) (xy 382.435888 -272.810483) (xy 382.412545 -272.764671) (xy 382.396657 -272.715772)
			(xy 382.388614 -272.66499) (xy 382.10211 -272.66499) (xy 382.094067 -272.715772) (xy 382.078179 -272.764671)
			(xy 382.054836 -272.810483) (xy 382.024615 -272.852079) (xy 381.988259 -272.888435) (xy 381.946663 -272.918656)
			(xy 381.900851 -272.941999) (xy 381.851952 -272.957887) (xy 381.80117 -272.96593) (xy 381.749754 -272.96593)
			(xy 381.698972 -272.957887) (xy 381.650073 -272.941999) (xy 381.604261 -272.918656) (xy 381.562665 -272.888435)
			(xy 381.526309 -272.852079) (xy 381.496088 -272.810483) (xy 381.472745 -272.764671) (xy 381.456857 -272.715772)
			(xy 381.448814 -272.66499) (xy 381.16231 -272.66499) (xy 381.154267 -272.715772) (xy 381.138379 -272.764671)
			(xy 381.115036 -272.810483) (xy 381.084815 -272.852079) (xy 381.048459 -272.888435) (xy 381.006863 -272.918656)
			(xy 380.961051 -272.941999) (xy 380.912152 -272.957887) (xy 380.86137 -272.96593) (xy 380.809954 -272.96593)
			(xy 380.759172 -272.957887) (xy 380.710273 -272.941999) (xy 380.664461 -272.918656) (xy 380.622865 -272.888435)
			(xy 380.586509 -272.852079) (xy 380.556288 -272.810483) (xy 380.532945 -272.764671) (xy 380.517057 -272.715772)
			(xy 380.509014 -272.66499) (xy 380.251744 -272.66499) (xy 380.251726 -272.665931) (xy 380.243783 -272.718635)
			(xy 380.228073 -272.769565) (xy 380.204947 -272.817586) (xy 380.174923 -272.861623) (xy 380.138671 -272.900694)
			(xy 380.097 -272.933925) (xy 380.050842 -272.960574) (xy 380.001228 -272.980046) (xy 379.949266 -272.991906)
			(xy 379.896116 -272.99589) (xy 379.842966 -272.991906) (xy 379.791004 -272.980046) (xy 379.74139 -272.960574)
			(xy 379.695232 -272.933925) (xy 379.653561 -272.900694) (xy 379.617309 -272.861623) (xy 379.587285 -272.817586)
			(xy 379.564159 -272.769565) (xy 379.548449 -272.718635) (xy 379.540506 -272.665931) (xy 379.311672 -272.665931)
			(xy 379.303729 -272.718635) (xy 379.288019 -272.769565) (xy 379.264893 -272.817586) (xy 379.234869 -272.861623)
			(xy 379.198617 -272.900694) (xy 379.156946 -272.933925) (xy 379.110788 -272.960574) (xy 379.061174 -272.980046)
			(xy 379.009212 -272.991906) (xy 378.956062 -272.99589) (xy 378.902912 -272.991906) (xy 378.85095 -272.980046)
			(xy 378.801336 -272.960574) (xy 378.755178 -272.933925) (xy 378.713507 -272.900694) (xy 378.677255 -272.861623)
			(xy 378.647231 -272.817586) (xy 378.624105 -272.769565) (xy 378.608395 -272.718635) (xy 378.600452 -272.665931)
			(xy 378.371872 -272.665931) (xy 378.363929 -272.718635) (xy 378.348219 -272.769565) (xy 378.325093 -272.817586)
			(xy 378.295069 -272.861623) (xy 378.258817 -272.900694) (xy 378.217146 -272.933925) (xy 378.170988 -272.960574)
			(xy 378.121374 -272.980046) (xy 378.069412 -272.991906) (xy 378.016262 -272.99589) (xy 377.963112 -272.991906)
			(xy 377.91115 -272.980046) (xy 377.861536 -272.960574) (xy 377.815378 -272.933925) (xy 377.773707 -272.900694)
			(xy 377.737455 -272.861623) (xy 377.707431 -272.817586) (xy 377.684305 -272.769565) (xy 377.668595 -272.718635)
			(xy 377.660652 -272.665931) (xy 377.402961 -272.665931) (xy 377.395067 -272.715772) (xy 377.379179 -272.764671)
			(xy 377.355836 -272.810483) (xy 377.325615 -272.852079) (xy 377.289259 -272.888435) (xy 377.247663 -272.918656)
			(xy 377.201851 -272.941999) (xy 377.152952 -272.957887) (xy 377.10217 -272.96593) (xy 377.050754 -272.96593)
			(xy 376.999972 -272.957887) (xy 376.951073 -272.941999) (xy 376.905261 -272.918656) (xy 376.863665 -272.888435)
			(xy 376.827309 -272.852079) (xy 376.797088 -272.810483) (xy 376.773745 -272.764671) (xy 376.757857 -272.715772)
			(xy 376.749814 -272.66499) (xy 376.46331 -272.66499) (xy 376.455267 -272.715772) (xy 376.439379 -272.764671)
			(xy 376.416036 -272.810483) (xy 376.385815 -272.852079) (xy 376.349459 -272.888435) (xy 376.307863 -272.918656)
			(xy 376.262051 -272.941999) (xy 376.213152 -272.957887) (xy 376.16237 -272.96593) (xy 376.110954 -272.96593)
			(xy 376.060172 -272.957887) (xy 376.011273 -272.941999) (xy 375.965461 -272.918656) (xy 375.923865 -272.888435)
			(xy 375.887509 -272.852079) (xy 375.857288 -272.810483) (xy 375.833945 -272.764671) (xy 375.818057 -272.715772)
			(xy 375.810014 -272.66499) (xy 375.52351 -272.66499) (xy 375.515467 -272.715772) (xy 375.499579 -272.764671)
			(xy 375.476236 -272.810483) (xy 375.446015 -272.852079) (xy 375.409659 -272.888435) (xy 375.368063 -272.918656)
			(xy 375.322251 -272.941999) (xy 375.273352 -272.957887) (xy 375.22257 -272.96593) (xy 375.171154 -272.96593)
			(xy 375.120372 -272.957887) (xy 375.071473 -272.941999) (xy 375.025661 -272.918656) (xy 374.984065 -272.888435)
			(xy 374.947709 -272.852079) (xy 374.917488 -272.810483) (xy 374.894145 -272.764671) (xy 374.878257 -272.715772)
			(xy 374.870214 -272.66499) (xy 374.58371 -272.66499) (xy 374.575667 -272.715772) (xy 374.559779 -272.764671)
			(xy 374.536436 -272.810483) (xy 374.506215 -272.852079) (xy 374.469859 -272.888435) (xy 374.428263 -272.918656)
			(xy 374.382451 -272.941999) (xy 374.333552 -272.957887) (xy 374.28277 -272.96593) (xy 374.231354 -272.96593)
			(xy 374.180572 -272.957887) (xy 374.131673 -272.941999) (xy 374.085861 -272.918656) (xy 374.044265 -272.888435)
			(xy 374.007909 -272.852079) (xy 373.977688 -272.810483) (xy 373.954345 -272.764671) (xy 373.938457 -272.715772)
			(xy 373.930414 -272.66499) (xy 373.673144 -272.66499) (xy 373.673126 -272.665931) (xy 373.665183 -272.718635)
			(xy 373.649473 -272.769565) (xy 373.626347 -272.817586) (xy 373.596323 -272.861623) (xy 373.560071 -272.900694)
			(xy 373.5184 -272.933925) (xy 373.472242 -272.960574) (xy 373.422628 -272.980046) (xy 373.370666 -272.991906)
			(xy 373.317516 -272.99589) (xy 373.264366 -272.991906) (xy 373.212404 -272.980046) (xy 373.16279 -272.960574)
			(xy 373.116632 -272.933925) (xy 373.074961 -272.900694) (xy 373.038709 -272.861623) (xy 373.008685 -272.817586)
			(xy 372.985559 -272.769565) (xy 372.969849 -272.718635) (xy 372.961906 -272.665931) (xy 372.733072 -272.665931)
			(xy 372.725129 -272.718635) (xy 372.709419 -272.769565) (xy 372.686293 -272.817586) (xy 372.656269 -272.861623)
			(xy 372.620017 -272.900694) (xy 372.578346 -272.933925) (xy 372.532188 -272.960574) (xy 372.482574 -272.980046)
			(xy 372.430612 -272.991906) (xy 372.377462 -272.99589) (xy 372.324312 -272.991906) (xy 372.27235 -272.980046)
			(xy 372.222736 -272.960574) (xy 372.176578 -272.933925) (xy 372.134907 -272.900694) (xy 372.098655 -272.861623)
			(xy 372.068631 -272.817586) (xy 372.045505 -272.769565) (xy 372.029795 -272.718635) (xy 372.021852 -272.665931)
			(xy 371.793272 -272.665931) (xy 371.785329 -272.718635) (xy 371.769619 -272.769565) (xy 371.746493 -272.817586)
			(xy 371.716469 -272.861623) (xy 371.680217 -272.900694) (xy 371.638546 -272.933925) (xy 371.592388 -272.960574)
			(xy 371.542774 -272.980046) (xy 371.490812 -272.991906) (xy 371.437662 -272.99589) (xy 371.384512 -272.991906)
			(xy 371.33255 -272.980046) (xy 371.282936 -272.960574) (xy 371.236778 -272.933925) (xy 371.195107 -272.900694)
			(xy 371.158855 -272.861623) (xy 371.128831 -272.817586) (xy 371.105705 -272.769565) (xy 371.089995 -272.718635)
			(xy 371.082052 -272.665931) (xy 370.853472 -272.665931) (xy 370.845529 -272.718635) (xy 370.829819 -272.769565)
			(xy 370.806693 -272.817586) (xy 370.776669 -272.861623) (xy 370.740417 -272.900694) (xy 370.698746 -272.933925)
			(xy 370.652588 -272.960574) (xy 370.602974 -272.980046) (xy 370.551012 -272.991906) (xy 370.497862 -272.99589)
			(xy 370.444712 -272.991906) (xy 370.39275 -272.980046) (xy 370.343136 -272.960574) (xy 370.296978 -272.933925)
			(xy 370.255307 -272.900694) (xy 370.219055 -272.861623) (xy 370.189031 -272.817586) (xy 370.165905 -272.769565)
			(xy 370.150195 -272.718635) (xy 370.142252 -272.665931) (xy 369.913672 -272.665931) (xy 369.905729 -272.718635)
			(xy 369.890019 -272.769565) (xy 369.866893 -272.817586) (xy 369.836869 -272.861623) (xy 369.800617 -272.900694)
			(xy 369.758946 -272.933925) (xy 369.712788 -272.960574) (xy 369.663174 -272.980046) (xy 369.611212 -272.991906)
			(xy 369.558062 -272.99589) (xy 369.504912 -272.991906) (xy 369.45295 -272.980046) (xy 369.403336 -272.960574)
			(xy 369.357178 -272.933925) (xy 369.315507 -272.900694) (xy 369.279255 -272.861623) (xy 369.249231 -272.817586)
			(xy 369.226105 -272.769565) (xy 369.210395 -272.718635) (xy 369.202452 -272.665931) (xy 368.973872 -272.665931)
			(xy 368.965929 -272.718635) (xy 368.950219 -272.769565) (xy 368.927093 -272.817586) (xy 368.897069 -272.861623)
			(xy 368.860817 -272.900694) (xy 368.819146 -272.933925) (xy 368.772988 -272.960574) (xy 368.723374 -272.980046)
			(xy 368.671412 -272.991906) (xy 368.618262 -272.99589) (xy 368.565112 -272.991906) (xy 368.51315 -272.980046)
			(xy 368.463536 -272.960574) (xy 368.417378 -272.933925) (xy 368.375707 -272.900694) (xy 368.339455 -272.861623)
			(xy 368.309431 -272.817586) (xy 368.286305 -272.769565) (xy 368.270595 -272.718635) (xy 368.262652 -272.665931)
			(xy 368.034072 -272.665931) (xy 368.026129 -272.718635) (xy 368.010419 -272.769565) (xy 367.987293 -272.817586)
			(xy 367.957269 -272.861623) (xy 367.921017 -272.900694) (xy 367.879346 -272.933925) (xy 367.833188 -272.960574)
			(xy 367.783574 -272.980046) (xy 367.731612 -272.991906) (xy 367.678462 -272.99589) (xy 367.625312 -272.991906)
			(xy 367.57335 -272.980046) (xy 367.523736 -272.960574) (xy 367.477578 -272.933925) (xy 367.435907 -272.900694)
			(xy 367.399655 -272.861623) (xy 367.369631 -272.817586) (xy 367.346505 -272.769565) (xy 367.330795 -272.718635)
			(xy 367.322852 -272.665931) (xy 367.094272 -272.665931) (xy 367.086329 -272.718635) (xy 367.070619 -272.769565)
			(xy 367.047493 -272.817586) (xy 367.017469 -272.861623) (xy 366.981217 -272.900694) (xy 366.939546 -272.933925)
			(xy 366.893388 -272.960574) (xy 366.843774 -272.980046) (xy 366.791812 -272.991906) (xy 366.738662 -272.99589)
			(xy 366.685512 -272.991906) (xy 366.63355 -272.980046) (xy 366.583936 -272.960574) (xy 366.537778 -272.933925)
			(xy 366.496107 -272.900694) (xy 366.459855 -272.861623) (xy 366.429831 -272.817586) (xy 366.406705 -272.769565)
			(xy 366.390995 -272.718635) (xy 366.383052 -272.665931) (xy 366.154472 -272.665931) (xy 366.146529 -272.718635)
			(xy 366.130819 -272.769565) (xy 366.107693 -272.817586) (xy 366.077669 -272.861623) (xy 366.041417 -272.900694)
			(xy 365.999746 -272.933925) (xy 365.953588 -272.960574) (xy 365.903974 -272.980046) (xy 365.852012 -272.991906)
			(xy 365.798862 -272.99589) (xy 365.745712 -272.991906) (xy 365.69375 -272.980046) (xy 365.644136 -272.960574)
			(xy 365.597978 -272.933925) (xy 365.556307 -272.900694) (xy 365.520055 -272.861623) (xy 365.490031 -272.817586)
			(xy 365.466905 -272.769565) (xy 365.451195 -272.718635) (xy 365.443252 -272.665931) (xy 365.214672 -272.665931)
			(xy 365.206729 -272.718635) (xy 365.191019 -272.769565) (xy 365.167893 -272.817586) (xy 365.137869 -272.861623)
			(xy 365.101617 -272.900694) (xy 365.059946 -272.933925) (xy 365.013788 -272.960574) (xy 364.964174 -272.980046)
			(xy 364.912212 -272.991906) (xy 364.859062 -272.99589) (xy 364.805912 -272.991906) (xy 364.75395 -272.980046)
			(xy 364.704336 -272.960574) (xy 364.658178 -272.933925) (xy 364.616507 -272.900694) (xy 364.580255 -272.861623)
			(xy 364.550231 -272.817586) (xy 364.527105 -272.769565) (xy 364.511395 -272.718635) (xy 364.503452 -272.665931)
			(xy 364.274872 -272.665931) (xy 364.266929 -272.718635) (xy 364.251219 -272.769565) (xy 364.228093 -272.817586)
			(xy 364.198069 -272.861623) (xy 364.161817 -272.900694) (xy 364.120146 -272.933925) (xy 364.073988 -272.960574)
			(xy 364.024374 -272.980046) (xy 363.972412 -272.991906) (xy 363.919262 -272.99589) (xy 363.866112 -272.991906)
			(xy 363.81415 -272.980046) (xy 363.764536 -272.960574) (xy 363.718378 -272.933925) (xy 363.676707 -272.900694)
			(xy 363.640455 -272.861623) (xy 363.610431 -272.817586) (xy 363.587305 -272.769565) (xy 363.571595 -272.718635)
			(xy 363.563652 -272.665931) (xy 363.335072 -272.665931) (xy 363.327129 -272.718635) (xy 363.311419 -272.769565)
			(xy 363.288293 -272.817586) (xy 363.258269 -272.861623) (xy 363.222017 -272.900694) (xy 363.180346 -272.933925)
			(xy 363.134188 -272.960574) (xy 363.084574 -272.980046) (xy 363.032612 -272.991906) (xy 362.979462 -272.99589)
			(xy 362.926312 -272.991906) (xy 362.87435 -272.980046) (xy 362.824736 -272.960574) (xy 362.778578 -272.933925)
			(xy 362.736907 -272.900694) (xy 362.700655 -272.861623) (xy 362.670631 -272.817586) (xy 362.647505 -272.769565)
			(xy 362.631795 -272.718635) (xy 362.623852 -272.665931) (xy 362.395236 -272.665931) (xy 362.395166 -272.669385)
			(xy 362.385213 -272.728246) (xy 362.375958 -272.75663) (xy 362.375958 -272.996406) (xy 362.376389 -273.010328)
			(xy 362.383909 -273.037138) (xy 362.398388 -273.060922) (xy 362.418751 -273.079913) (xy 362.443486 -273.092701)
			(xy 362.470755 -273.098335) (xy 362.48467 -273.097752) (xy 362.509562 -273.09699) (xy 362.537549 -273.097507)
			(xy 362.592836 -273.106258) (xy 362.646072 -273.123551) (xy 362.695948 -273.148959) (xy 362.741235 -273.181857)
			(xy 362.780817 -273.221435) (xy 362.81372 -273.266718) (xy 362.839134 -273.316591) (xy 362.856432 -273.369825)
			(xy 362.86519 -273.425111) (xy 362.86567 -273.453098) (xy 362.865207 -273.479288) (xy 362.865139 -273.479747)
			(xy 363.093752 -273.479747) (xy 363.093752 -273.426449) (xy 363.101695 -273.373745) (xy 363.117405 -273.322815)
			(xy 363.140531 -273.274794) (xy 363.170555 -273.230757) (xy 363.206807 -273.191686) (xy 363.248478 -273.158455)
			(xy 363.294636 -273.131806) (xy 363.34425 -273.112334) (xy 363.396212 -273.100474) (xy 363.449362 -273.096491)
			(xy 363.502512 -273.100474) (xy 363.554474 -273.112334) (xy 363.604088 -273.131806) (xy 363.650246 -273.158455)
			(xy 363.691917 -273.191686) (xy 363.728169 -273.230757) (xy 363.758193 -273.274794) (xy 363.781319 -273.322815)
			(xy 363.797029 -273.373745) (xy 363.804972 -273.426449) (xy 363.80547 -273.453098) (xy 363.804972 -273.479747)
			(xy 363.797029 -273.532451) (xy 363.781319 -273.583381) (xy 363.758193 -273.631402) (xy 363.728169 -273.675439)
			(xy 363.691917 -273.71451) (xy 363.650246 -273.747741) (xy 363.604088 -273.77439) (xy 363.554474 -273.793862)
			(xy 363.502512 -273.805722) (xy 363.449362 -273.809706) (xy 363.396212 -273.805722) (xy 363.34425 -273.793862)
			(xy 363.294636 -273.77439) (xy 363.248478 -273.747741) (xy 363.206807 -273.71451) (xy 363.170555 -273.675439)
			(xy 363.140531 -273.631402) (xy 363.117405 -273.583381) (xy 363.101695 -273.532451) (xy 363.093752 -273.479747)
			(xy 362.865139 -273.479747) (xy 362.857536 -273.531102) (xy 362.842358 -273.581235) (xy 362.820002 -273.628604)
			(xy 362.790949 -273.672188) (xy 362.755827 -273.711046) (xy 362.715391 -273.744342) (xy 362.670516 -273.771356)
			(xy 362.622167 -273.791507) (xy 362.571389 -273.804359) (xy 362.545376 -273.807428) (xy 362.531165 -273.809345)
			(xy 362.504566 -273.820027) (xy 362.481989 -273.837688) (xy 362.465218 -273.860933) (xy 362.455576 -273.887926)
			(xy 362.453825 -273.916536) (xy 362.460103 -273.944503) (xy 362.473915 -273.96962) (xy 362.483654 -273.980148)
			(xy 362.552996 -274.04949) (xy 362.563359 -274.059195) (xy 362.588172 -274.072973) (xy 362.615816 -274.079396)
			(xy 362.644162 -274.077969) (xy 362.671021 -274.068802) (xy 362.694324 -274.052602) (xy 362.703618 -274.04187)
			(xy 362.72061 -274.021769) (xy 362.759507 -273.986311) (xy 362.803201 -273.956969) (xy 362.85074 -273.934381)
			(xy 362.901088 -273.919042) (xy 362.953146 -273.911284) (xy 362.979462 -273.910806) (xy 363.004883 -273.911263)
			(xy 363.055209 -273.918501) (xy 363.103993 -273.932822) (xy 363.150245 -273.953934) (xy 363.193026 -273.981408)
			(xy 363.231465 -274.014687) (xy 363.264781 -274.053093) (xy 363.292298 -274.095846) (xy 363.313455 -274.142078)
			(xy 363.321092 -274.16633) (xy 363.33176 -274.202652) (xy 363.567218 -274.202652) (xy 363.577886 -274.16633)
			(xy 363.5855 -274.142069) (xy 363.606653 -274.095829) (xy 363.634167 -274.053069) (xy 363.667484 -274.014657)
			(xy 363.705926 -273.981374) (xy 363.748711 -273.953898) (xy 363.79497 -273.932788) (xy 363.843761 -273.918472)
			(xy 363.894092 -273.911241) (xy 363.919516 -273.910806) (xy 363.942906 -273.911177) (xy 363.989282 -273.917304)
			(xy 364.034457 -273.929451) (xy 364.077653 -273.947409) (xy 364.098078 -273.958812) (xy 364.109928 -273.965223)
			(xy 364.135943 -273.972197) (xy 364.162876 -273.972114) (xy 364.188848 -273.964982) (xy 364.212046 -273.951297)
			(xy 364.23085 -273.932014) (xy 364.237778 -273.920458) (xy 364.248446 -273.901916) (xy 364.254986 -273.890138)
			(xy 364.262257 -273.864205) (xy 364.262507 -273.837274) (xy 364.255718 -273.811211) (xy 364.242361 -273.787825)
			(xy 364.223362 -273.768735) (xy 364.21187 -273.761708) (xy 364.188964 -273.748001) (xy 364.14717 -273.714798)
			(xy 364.110807 -273.675722) (xy 364.080691 -273.631651) (xy 364.0575 -273.583574) (xy 364.041755 -273.532571)
			(xy 364.033808 -273.479787) (xy 364.033308 -273.453098) (xy 364.033829 -273.425113) (xy 364.042585 -273.369833)
			(xy 364.059881 -273.316603) (xy 364.085292 -273.266734) (xy 364.118191 -273.221454) (xy 364.157768 -273.181879)
			(xy 364.203049 -273.148982) (xy 364.252919 -273.123574) (xy 364.30615 -273.106281) (xy 364.361431 -273.097527)
			(xy 364.389416 -273.09699) (xy 364.415323 -273.097451) (xy 364.466591 -273.104952) (xy 364.516229 -273.119807)
			(xy 364.563189 -273.141704) (xy 364.606478 -273.170178) (xy 364.64518 -273.204628) (xy 364.678477 -273.244326)
			(xy 364.692438 -273.266154) (xy 364.697612 -273.273776) (xy 364.712196 -273.285006) (xy 364.729805 -273.290367)
			(xy 364.748172 -273.289168) (xy 364.764935 -273.281563) (xy 364.771686 -273.275298) (xy 364.805214 -273.24177)
			(xy 364.822127 -273.225463) (xy 364.860125 -273.197837) (xy 364.901977 -273.176496) (xy 364.946653 -273.161967)
			(xy 364.993052 -273.154607) (xy 365.016542 -273.15414) (xy 365.134906 -273.15414) (xy 365.147098 -273.147028)
			(xy 365.167841 -273.13514) (xy 365.211831 -273.116416) (xy 365.257931 -273.103744) (xy 365.305311 -273.097351)
			(xy 365.329216 -273.09699) (xy 365.355865 -273.097489) (xy 365.408566 -273.105435) (xy 365.459495 -273.121146)
			(xy 365.507514 -273.144272) (xy 365.55155 -273.174297) (xy 365.590618 -273.21055) (xy 365.623848 -273.25222)
			(xy 365.650496 -273.298377) (xy 365.669967 -273.34799) (xy 365.681827 -273.399952) (xy 365.68581 -273.4531)
			(xy 365.683813 -273.479747) (xy 365.913406 -273.479747) (xy 365.913406 -273.426449) (xy 365.921349 -273.373745)
			(xy 365.937059 -273.322815) (xy 365.960185 -273.274794) (xy 365.990209 -273.230757) (xy 366.026461 -273.191686)
			(xy 366.068132 -273.158455) (xy 366.11429 -273.131806) (xy 366.163904 -273.112334) (xy 366.215866 -273.100474)
			(xy 366.269016 -273.096491) (xy 366.322166 -273.100474) (xy 366.374128 -273.112334) (xy 366.423742 -273.131806)
			(xy 366.4699 -273.158455) (xy 366.511571 -273.191686) (xy 366.547823 -273.230757) (xy 366.577847 -273.274794)
			(xy 366.600973 -273.322815) (xy 366.616683 -273.373745) (xy 366.624626 -273.426449) (xy 366.625124 -273.453098)
			(xy 366.624626 -273.479747) (xy 366.853206 -273.479747) (xy 366.853206 -273.426449) (xy 366.861149 -273.373745)
			(xy 366.876859 -273.322815) (xy 366.899985 -273.274794) (xy 366.930009 -273.230757) (xy 366.966261 -273.191686)
			(xy 367.007932 -273.158455) (xy 367.05409 -273.131806) (xy 367.103704 -273.112334) (xy 367.155666 -273.100474)
			(xy 367.208816 -273.096491) (xy 367.261966 -273.100474) (xy 367.313928 -273.112334) (xy 367.363542 -273.131806)
			(xy 367.4097 -273.158455) (xy 367.451371 -273.191686) (xy 367.487623 -273.230757) (xy 367.517647 -273.274794)
			(xy 367.540773 -273.322815) (xy 367.556483 -273.373745) (xy 367.564426 -273.426449) (xy 367.564924 -273.453098)
			(xy 367.564426 -273.479747) (xy 367.793006 -273.479747) (xy 367.793006 -273.426449) (xy 367.800949 -273.373745)
			(xy 367.816659 -273.322815) (xy 367.839785 -273.274794) (xy 367.869809 -273.230757) (xy 367.906061 -273.191686)
			(xy 367.947732 -273.158455) (xy 367.99389 -273.131806) (xy 368.043504 -273.112334) (xy 368.095466 -273.100474)
			(xy 368.148616 -273.096491) (xy 368.201766 -273.100474) (xy 368.253728 -273.112334) (xy 368.303342 -273.131806)
			(xy 368.3495 -273.158455) (xy 368.391171 -273.191686) (xy 368.427423 -273.230757) (xy 368.457447 -273.274794)
			(xy 368.480573 -273.322815) (xy 368.496283 -273.373745) (xy 368.504226 -273.426449) (xy 368.504724 -273.453098)
			(xy 368.504226 -273.479747) (xy 368.732806 -273.479747) (xy 368.732806 -273.426449) (xy 368.740749 -273.373745)
			(xy 368.756459 -273.322815) (xy 368.779585 -273.274794) (xy 368.809609 -273.230757) (xy 368.845861 -273.191686)
			(xy 368.887532 -273.158455) (xy 368.93369 -273.131806) (xy 368.983304 -273.112334) (xy 369.035266 -273.100474)
			(xy 369.088416 -273.096491) (xy 369.141566 -273.100474) (xy 369.193528 -273.112334) (xy 369.243142 -273.131806)
			(xy 369.2893 -273.158455) (xy 369.330971 -273.191686) (xy 369.367223 -273.230757) (xy 369.397247 -273.274794)
			(xy 369.420373 -273.322815) (xy 369.436083 -273.373745) (xy 369.444026 -273.426449) (xy 369.444524 -273.453098)
			(xy 369.444026 -273.479747) (xy 369.672606 -273.479747) (xy 369.672606 -273.426449) (xy 369.680549 -273.373745)
			(xy 369.696259 -273.322815) (xy 369.719385 -273.274794) (xy 369.749409 -273.230757) (xy 369.785661 -273.191686)
			(xy 369.827332 -273.158455) (xy 369.87349 -273.131806) (xy 369.923104 -273.112334) (xy 369.975066 -273.100474)
			(xy 370.028216 -273.096491) (xy 370.081366 -273.100474) (xy 370.133328 -273.112334) (xy 370.182942 -273.131806)
			(xy 370.2291 -273.158455) (xy 370.270771 -273.191686) (xy 370.307023 -273.230757) (xy 370.337047 -273.274794)
			(xy 370.360173 -273.322815) (xy 370.375883 -273.373745) (xy 370.383826 -273.426449) (xy 370.384324 -273.453098)
			(xy 370.383826 -273.479747) (xy 370.612152 -273.479747) (xy 370.612152 -273.426449) (xy 370.620095 -273.373745)
			(xy 370.635805 -273.322815) (xy 370.658931 -273.274794) (xy 370.688955 -273.230757) (xy 370.725207 -273.191686)
			(xy 370.766878 -273.158455) (xy 370.813036 -273.131806) (xy 370.86265 -273.112334) (xy 370.914612 -273.100474)
			(xy 370.967762 -273.096491) (xy 371.020912 -273.100474) (xy 371.072874 -273.112334) (xy 371.122488 -273.131806)
			(xy 371.168646 -273.158455) (xy 371.210317 -273.191686) (xy 371.246569 -273.230757) (xy 371.276593 -273.274794)
			(xy 371.299719 -273.322815) (xy 371.315429 -273.373745) (xy 371.323372 -273.426449) (xy 371.32387 -273.453098)
			(xy 371.32339 -273.478806) (xy 371.581168 -273.478806) (xy 371.581168 -273.42739) (xy 371.589211 -273.376608)
			(xy 371.605099 -273.327709) (xy 371.628442 -273.281897) (xy 371.658663 -273.240301) (xy 371.695019 -273.203945)
			(xy 371.736615 -273.173724) (xy 371.782427 -273.150381) (xy 371.831326 -273.134493) (xy 371.882108 -273.12645)
			(xy 371.933524 -273.12645) (xy 371.984306 -273.134493) (xy 372.033205 -273.150381) (xy 372.079017 -273.173724)
			(xy 372.120613 -273.203945) (xy 372.156969 -273.240301) (xy 372.18719 -273.281897) (xy 372.210533 -273.327709)
			(xy 372.226421 -273.376608) (xy 372.234464 -273.42739) (xy 372.234968 -273.453098) (xy 372.234464 -273.478806)
			(xy 372.520968 -273.478806) (xy 372.520968 -273.42739) (xy 372.529011 -273.376608) (xy 372.544899 -273.327709)
			(xy 372.568242 -273.281897) (xy 372.598463 -273.240301) (xy 372.634819 -273.203945) (xy 372.676415 -273.173724)
			(xy 372.722227 -273.150381) (xy 372.771126 -273.134493) (xy 372.821908 -273.12645) (xy 372.873324 -273.12645)
			(xy 372.924106 -273.134493) (xy 372.973005 -273.150381) (xy 373.018817 -273.173724) (xy 373.060413 -273.203945)
			(xy 373.096769 -273.240301) (xy 373.12699 -273.281897) (xy 373.150333 -273.327709) (xy 373.166221 -273.376608)
			(xy 373.174264 -273.42739) (xy 373.174768 -273.453098) (xy 373.174264 -273.478806) (xy 373.174115 -273.479747)
			(xy 373.431806 -273.479747) (xy 373.431806 -273.426449) (xy 373.439749 -273.373745) (xy 373.455459 -273.322815)
			(xy 373.478585 -273.274794) (xy 373.508609 -273.230757) (xy 373.544861 -273.191686) (xy 373.586532 -273.158455)
			(xy 373.63269 -273.131806) (xy 373.682304 -273.112334) (xy 373.734266 -273.100474) (xy 373.787416 -273.096491)
			(xy 373.840566 -273.100474) (xy 373.892528 -273.112334) (xy 373.942142 -273.131806) (xy 373.9883 -273.158455)
			(xy 374.029971 -273.191686) (xy 374.066223 -273.230757) (xy 374.096247 -273.274794) (xy 374.119373 -273.322815)
			(xy 374.135083 -273.373745) (xy 374.143026 -273.426449) (xy 374.143524 -273.453098) (xy 374.143044 -273.478806)
			(xy 374.400568 -273.478806) (xy 374.400568 -273.42739) (xy 374.408611 -273.376608) (xy 374.424499 -273.327709)
			(xy 374.447842 -273.281897) (xy 374.478063 -273.240301) (xy 374.514419 -273.203945) (xy 374.556015 -273.173724)
			(xy 374.601827 -273.150381) (xy 374.650726 -273.134493) (xy 374.701508 -273.12645) (xy 374.752924 -273.12645)
			(xy 374.803706 -273.134493) (xy 374.852605 -273.150381) (xy 374.898417 -273.173724) (xy 374.940013 -273.203945)
			(xy 374.976369 -273.240301) (xy 375.00659 -273.281897) (xy 375.029933 -273.327709) (xy 375.045821 -273.376608)
			(xy 375.053864 -273.42739) (xy 375.054368 -273.453098) (xy 375.053864 -273.478806) (xy 375.053715 -273.479747)
			(xy 375.311406 -273.479747) (xy 375.311406 -273.426449) (xy 375.319349 -273.373745) (xy 375.335059 -273.322815)
			(xy 375.358185 -273.274794) (xy 375.388209 -273.230757) (xy 375.424461 -273.191686) (xy 375.466132 -273.158455)
			(xy 375.51229 -273.131806) (xy 375.561904 -273.112334) (xy 375.613866 -273.100474) (xy 375.667016 -273.096491)
			(xy 375.720166 -273.100474) (xy 375.772128 -273.112334) (xy 375.821742 -273.131806) (xy 375.8679 -273.158455)
			(xy 375.909571 -273.191686) (xy 375.945823 -273.230757) (xy 375.975847 -273.274794) (xy 375.998973 -273.322815)
			(xy 376.014683 -273.373745) (xy 376.022626 -273.426449) (xy 376.023124 -273.453098) (xy 376.022644 -273.478806)
			(xy 376.280168 -273.478806) (xy 376.280168 -273.42739) (xy 376.288211 -273.376608) (xy 376.304099 -273.327709)
			(xy 376.327442 -273.281897) (xy 376.357663 -273.240301) (xy 376.394019 -273.203945) (xy 376.435615 -273.173724)
			(xy 376.481427 -273.150381) (xy 376.530326 -273.134493) (xy 376.581108 -273.12645) (xy 376.632524 -273.12645)
			(xy 376.683306 -273.134493) (xy 376.732205 -273.150381) (xy 376.778017 -273.173724) (xy 376.819613 -273.203945)
			(xy 376.855969 -273.240301) (xy 376.88619 -273.281897) (xy 376.909533 -273.327709) (xy 376.925421 -273.376608)
			(xy 376.933464 -273.42739) (xy 376.933968 -273.453098) (xy 376.933464 -273.478806) (xy 376.933315 -273.479747)
			(xy 377.191006 -273.479747) (xy 377.191006 -273.426449) (xy 377.198949 -273.373745) (xy 377.214659 -273.322815)
			(xy 377.237785 -273.274794) (xy 377.267809 -273.230757) (xy 377.304061 -273.191686) (xy 377.345732 -273.158455)
			(xy 377.39189 -273.131806) (xy 377.441504 -273.112334) (xy 377.493466 -273.100474) (xy 377.546616 -273.096491)
			(xy 377.599766 -273.100474) (xy 377.651728 -273.112334) (xy 377.701342 -273.131806) (xy 377.7475 -273.158455)
			(xy 377.789171 -273.191686) (xy 377.825423 -273.230757) (xy 377.855447 -273.274794) (xy 377.878573 -273.322815)
			(xy 377.894283 -273.373745) (xy 377.902226 -273.426449) (xy 377.902724 -273.453098) (xy 377.902244 -273.478806)
			(xy 378.159768 -273.478806) (xy 378.159768 -273.42739) (xy 378.167811 -273.376608) (xy 378.183699 -273.327709)
			(xy 378.207042 -273.281897) (xy 378.237263 -273.240301) (xy 378.273619 -273.203945) (xy 378.315215 -273.173724)
			(xy 378.361027 -273.150381) (xy 378.409926 -273.134493) (xy 378.460708 -273.12645) (xy 378.512124 -273.12645)
			(xy 378.562906 -273.134493) (xy 378.611805 -273.150381) (xy 378.657617 -273.173724) (xy 378.699213 -273.203945)
			(xy 378.735569 -273.240301) (xy 378.76579 -273.281897) (xy 378.789133 -273.327709) (xy 378.805021 -273.376608)
			(xy 378.813064 -273.42739) (xy 378.813568 -273.453098) (xy 378.813064 -273.478806) (xy 379.099568 -273.478806)
			(xy 379.099568 -273.42739) (xy 379.107611 -273.376608) (xy 379.123499 -273.327709) (xy 379.146842 -273.281897)
			(xy 379.177063 -273.240301) (xy 379.213419 -273.203945) (xy 379.255015 -273.173724) (xy 379.300827 -273.150381)
			(xy 379.349726 -273.134493) (xy 379.400508 -273.12645) (xy 379.451924 -273.12645) (xy 379.502706 -273.134493)
			(xy 379.551605 -273.150381) (xy 379.597417 -273.173724) (xy 379.639013 -273.203945) (xy 379.675369 -273.240301)
			(xy 379.70559 -273.281897) (xy 379.728933 -273.327709) (xy 379.744821 -273.376608) (xy 379.752864 -273.42739)
			(xy 379.753368 -273.453098) (xy 379.752864 -273.478806) (xy 379.752715 -273.479747) (xy 380.010406 -273.479747)
			(xy 380.010406 -273.426449) (xy 380.018349 -273.373745) (xy 380.034059 -273.322815) (xy 380.057185 -273.274794)
			(xy 380.087209 -273.230757) (xy 380.123461 -273.191686) (xy 380.165132 -273.158455) (xy 380.21129 -273.131806)
			(xy 380.260904 -273.112334) (xy 380.312866 -273.100474) (xy 380.366016 -273.096491) (xy 380.419166 -273.100474)
			(xy 380.471128 -273.112334) (xy 380.520742 -273.131806) (xy 380.5669 -273.158455) (xy 380.608571 -273.191686)
			(xy 380.644823 -273.230757) (xy 380.674847 -273.274794) (xy 380.697973 -273.322815) (xy 380.713683 -273.373745)
			(xy 380.721626 -273.426449) (xy 380.722124 -273.453098) (xy 380.721644 -273.478806) (xy 380.979168 -273.478806)
			(xy 380.979168 -273.42739) (xy 380.987211 -273.376608) (xy 381.003099 -273.327709) (xy 381.026442 -273.281897)
			(xy 381.056663 -273.240301) (xy 381.093019 -273.203945) (xy 381.134615 -273.173724) (xy 381.180427 -273.150381)
			(xy 381.229326 -273.134493) (xy 381.280108 -273.12645) (xy 381.331524 -273.12645) (xy 381.382306 -273.134493)
			(xy 381.431205 -273.150381) (xy 381.477017 -273.173724) (xy 381.518613 -273.203945) (xy 381.554969 -273.240301)
			(xy 381.58519 -273.281897) (xy 381.608533 -273.327709) (xy 381.624421 -273.376608) (xy 381.632464 -273.42739)
			(xy 381.632968 -273.453098) (xy 381.632464 -273.478806) (xy 381.632315 -273.479747) (xy 381.890006 -273.479747)
			(xy 381.890006 -273.426449) (xy 381.897949 -273.373745) (xy 381.913659 -273.322815) (xy 381.936785 -273.274794)
			(xy 381.966809 -273.230757) (xy 382.003061 -273.191686) (xy 382.044732 -273.158455) (xy 382.09089 -273.131806)
			(xy 382.140504 -273.112334) (xy 382.192466 -273.100474) (xy 382.245616 -273.096491) (xy 382.298766 -273.100474)
			(xy 382.350728 -273.112334) (xy 382.400342 -273.131806) (xy 382.4465 -273.158455) (xy 382.488171 -273.191686)
			(xy 382.524423 -273.230757) (xy 382.554447 -273.274794) (xy 382.577573 -273.322815) (xy 382.593283 -273.373745)
			(xy 382.601226 -273.426449) (xy 382.601724 -273.453098) (xy 382.601244 -273.478806) (xy 382.858768 -273.478806)
			(xy 382.858768 -273.42739) (xy 382.866811 -273.376608) (xy 382.882699 -273.327709) (xy 382.906042 -273.281897)
			(xy 382.936263 -273.240301) (xy 382.972619 -273.203945) (xy 383.014215 -273.173724) (xy 383.060027 -273.150381)
			(xy 383.108926 -273.134493) (xy 383.159708 -273.12645) (xy 383.211124 -273.12645) (xy 383.261906 -273.134493)
			(xy 383.310805 -273.150381) (xy 383.356617 -273.173724) (xy 383.398213 -273.203945) (xy 383.434569 -273.240301)
			(xy 383.46479 -273.281897) (xy 383.488133 -273.327709) (xy 383.504021 -273.376608) (xy 383.512064 -273.42739)
			(xy 383.512568 -273.453098) (xy 383.512064 -273.478806) (xy 383.511915 -273.479747) (xy 383.769352 -273.479747)
			(xy 383.769352 -273.426449) (xy 383.777295 -273.373745) (xy 383.793005 -273.322815) (xy 383.816131 -273.274794)
			(xy 383.846155 -273.230757) (xy 383.882407 -273.191686) (xy 383.924078 -273.158455) (xy 383.970236 -273.131806)
			(xy 384.01985 -273.112334) (xy 384.071812 -273.100474) (xy 384.124962 -273.096491) (xy 384.178112 -273.100474)
			(xy 384.230074 -273.112334) (xy 384.279688 -273.131806) (xy 384.325846 -273.158455) (xy 384.367517 -273.191686)
			(xy 384.403769 -273.230757) (xy 384.433793 -273.274794) (xy 384.456919 -273.322815) (xy 384.472629 -273.373745)
			(xy 384.480572 -273.426449) (xy 384.48107 -273.453098) (xy 384.720849 -273.453098) (xy 384.724879 -273.4006)
			(xy 384.736876 -273.349332) (xy 384.756559 -273.300497) (xy 384.783465 -273.255238) (xy 384.816965 -273.214617)
			(xy 384.856273 -273.179586) (xy 384.900468 -273.150966) (xy 384.948513 -273.129427) (xy 384.999284 -273.115475)
			(xy 385.051589 -273.109437) (xy 385.104203 -273.111454) (xy 385.155893 -273.121478) (xy 385.205446 -273.139276)
			(xy 385.251702 -273.164429) (xy 385.293576 -273.196348) (xy 385.330088 -273.234286) (xy 385.36038 -273.277352)
			(xy 385.383743 -273.324537) (xy 385.399629 -273.374736) (xy 385.407666 -273.426772) (xy 385.40817 -273.453098)
			(xy 385.407666 -273.479424) (xy 385.399629 -273.53146) (xy 385.383743 -273.581659) (xy 385.36038 -273.628844)
			(xy 385.330088 -273.67191) (xy 385.293576 -273.709848) (xy 385.251702 -273.741767) (xy 385.205446 -273.76692)
			(xy 385.155893 -273.784718) (xy 385.104203 -273.794742) (xy 385.051589 -273.796759) (xy 384.999284 -273.790721)
			(xy 384.948513 -273.776769) (xy 384.900468 -273.75523) (xy 384.856273 -273.72661) (xy 384.816965 -273.691579)
			(xy 384.783465 -273.650958) (xy 384.756559 -273.605699) (xy 384.736876 -273.556864) (xy 384.724879 -273.505596)
			(xy 384.720849 -273.453098) (xy 384.48107 -273.453098) (xy 384.480572 -273.479747) (xy 384.472629 -273.532451)
			(xy 384.456919 -273.583381) (xy 384.433793 -273.631402) (xy 384.403769 -273.675439) (xy 384.367517 -273.71451)
			(xy 384.325846 -273.747741) (xy 384.279688 -273.77439) (xy 384.230074 -273.793862) (xy 384.178112 -273.805722)
			(xy 384.124962 -273.809706) (xy 384.071812 -273.805722) (xy 384.01985 -273.793862) (xy 383.970236 -273.77439)
			(xy 383.924078 -273.747741) (xy 383.882407 -273.71451) (xy 383.846155 -273.675439) (xy 383.816131 -273.631402)
			(xy 383.793005 -273.583381) (xy 383.777295 -273.532451) (xy 383.769352 -273.479747) (xy 383.511915 -273.479747)
			(xy 383.504021 -273.529588) (xy 383.488133 -273.578487) (xy 383.46479 -273.624299) (xy 383.434569 -273.665895)
			(xy 383.398213 -273.702251) (xy 383.356617 -273.732472) (xy 383.310805 -273.755815) (xy 383.261906 -273.771703)
			(xy 383.211124 -273.779746) (xy 383.159708 -273.779746) (xy 383.108926 -273.771703) (xy 383.060027 -273.755815)
			(xy 383.014215 -273.732472) (xy 382.972619 -273.702251) (xy 382.936263 -273.665895) (xy 382.906042 -273.624299)
			(xy 382.882699 -273.578487) (xy 382.866811 -273.529588) (xy 382.858768 -273.478806) (xy 382.601244 -273.478806)
			(xy 382.601226 -273.479747) (xy 382.593283 -273.532451) (xy 382.577573 -273.583381) (xy 382.554447 -273.631402)
			(xy 382.524423 -273.675439) (xy 382.488171 -273.71451) (xy 382.4465 -273.747741) (xy 382.400342 -273.77439)
			(xy 382.350728 -273.793862) (xy 382.298766 -273.805722) (xy 382.245616 -273.809706) (xy 382.192466 -273.805722)
			(xy 382.140504 -273.793862) (xy 382.09089 -273.77439) (xy 382.044732 -273.747741) (xy 382.003061 -273.71451)
			(xy 381.966809 -273.675439) (xy 381.936785 -273.631402) (xy 381.913659 -273.583381) (xy 381.897949 -273.532451)
			(xy 381.890006 -273.479747) (xy 381.632315 -273.479747) (xy 381.624421 -273.529588) (xy 381.608533 -273.578487)
			(xy 381.58519 -273.624299) (xy 381.554969 -273.665895) (xy 381.518613 -273.702251) (xy 381.477017 -273.732472)
			(xy 381.431205 -273.755815) (xy 381.382306 -273.771703) (xy 381.331524 -273.779746) (xy 381.280108 -273.779746)
			(xy 381.229326 -273.771703) (xy 381.180427 -273.755815) (xy 381.134615 -273.732472) (xy 381.093019 -273.702251)
			(xy 381.056663 -273.665895) (xy 381.026442 -273.624299) (xy 381.003099 -273.578487) (xy 380.987211 -273.529588)
			(xy 380.979168 -273.478806) (xy 380.721644 -273.478806) (xy 380.721626 -273.479747) (xy 380.713683 -273.532451)
			(xy 380.697973 -273.583381) (xy 380.674847 -273.631402) (xy 380.644823 -273.675439) (xy 380.608571 -273.71451)
			(xy 380.5669 -273.747741) (xy 380.520742 -273.77439) (xy 380.471128 -273.793862) (xy 380.419166 -273.805722)
			(xy 380.366016 -273.809706) (xy 380.312866 -273.805722) (xy 380.260904 -273.793862) (xy 380.21129 -273.77439)
			(xy 380.165132 -273.747741) (xy 380.123461 -273.71451) (xy 380.087209 -273.675439) (xy 380.057185 -273.631402)
			(xy 380.034059 -273.583381) (xy 380.018349 -273.532451) (xy 380.010406 -273.479747) (xy 379.752715 -273.479747)
			(xy 379.744821 -273.529588) (xy 379.728933 -273.578487) (xy 379.70559 -273.624299) (xy 379.675369 -273.665895)
			(xy 379.639013 -273.702251) (xy 379.597417 -273.732472) (xy 379.551605 -273.755815) (xy 379.502706 -273.771703)
			(xy 379.451924 -273.779746) (xy 379.400508 -273.779746) (xy 379.349726 -273.771703) (xy 379.300827 -273.755815)
			(xy 379.255015 -273.732472) (xy 379.213419 -273.702251) (xy 379.177063 -273.665895) (xy 379.146842 -273.624299)
			(xy 379.123499 -273.578487) (xy 379.107611 -273.529588) (xy 379.099568 -273.478806) (xy 378.813064 -273.478806)
			(xy 378.805021 -273.529588) (xy 378.789133 -273.578487) (xy 378.76579 -273.624299) (xy 378.735569 -273.665895)
			(xy 378.699213 -273.702251) (xy 378.657617 -273.732472) (xy 378.611805 -273.755815) (xy 378.562906 -273.771703)
			(xy 378.512124 -273.779746) (xy 378.460708 -273.779746) (xy 378.409926 -273.771703) (xy 378.361027 -273.755815)
			(xy 378.315215 -273.732472) (xy 378.273619 -273.702251) (xy 378.237263 -273.665895) (xy 378.207042 -273.624299)
			(xy 378.183699 -273.578487) (xy 378.167811 -273.529588) (xy 378.159768 -273.478806) (xy 377.902244 -273.478806)
			(xy 377.902226 -273.479747) (xy 377.894283 -273.532451) (xy 377.878573 -273.583381) (xy 377.855447 -273.631402)
			(xy 377.825423 -273.675439) (xy 377.789171 -273.71451) (xy 377.7475 -273.747741) (xy 377.701342 -273.77439)
			(xy 377.651728 -273.793862) (xy 377.599766 -273.805722) (xy 377.546616 -273.809706) (xy 377.493466 -273.805722)
			(xy 377.441504 -273.793862) (xy 377.39189 -273.77439) (xy 377.345732 -273.747741) (xy 377.304061 -273.71451)
			(xy 377.267809 -273.675439) (xy 377.237785 -273.631402) (xy 377.214659 -273.583381) (xy 377.198949 -273.532451)
			(xy 377.191006 -273.479747) (xy 376.933315 -273.479747) (xy 376.925421 -273.529588) (xy 376.909533 -273.578487)
			(xy 376.88619 -273.624299) (xy 376.855969 -273.665895) (xy 376.819613 -273.702251) (xy 376.778017 -273.732472)
			(xy 376.732205 -273.755815) (xy 376.683306 -273.771703) (xy 376.632524 -273.779746) (xy 376.581108 -273.779746)
			(xy 376.530326 -273.771703) (xy 376.481427 -273.755815) (xy 376.435615 -273.732472) (xy 376.394019 -273.702251)
			(xy 376.357663 -273.665895) (xy 376.327442 -273.624299) (xy 376.304099 -273.578487) (xy 376.288211 -273.529588)
			(xy 376.280168 -273.478806) (xy 376.022644 -273.478806) (xy 376.022626 -273.479747) (xy 376.014683 -273.532451)
			(xy 375.998973 -273.583381) (xy 375.975847 -273.631402) (xy 375.945823 -273.675439) (xy 375.909571 -273.71451)
			(xy 375.8679 -273.747741) (xy 375.821742 -273.77439) (xy 375.772128 -273.793862) (xy 375.720166 -273.805722)
			(xy 375.667016 -273.809706) (xy 375.613866 -273.805722) (xy 375.561904 -273.793862) (xy 375.51229 -273.77439)
			(xy 375.466132 -273.747741) (xy 375.424461 -273.71451) (xy 375.388209 -273.675439) (xy 375.358185 -273.631402)
			(xy 375.335059 -273.583381) (xy 375.319349 -273.532451) (xy 375.311406 -273.479747) (xy 375.053715 -273.479747)
			(xy 375.045821 -273.529588) (xy 375.029933 -273.578487) (xy 375.00659 -273.624299) (xy 374.976369 -273.665895)
			(xy 374.940013 -273.702251) (xy 374.898417 -273.732472) (xy 374.852605 -273.755815) (xy 374.803706 -273.771703)
			(xy 374.752924 -273.779746) (xy 374.701508 -273.779746) (xy 374.650726 -273.771703) (xy 374.601827 -273.755815)
			(xy 374.556015 -273.732472) (xy 374.514419 -273.702251) (xy 374.478063 -273.665895) (xy 374.447842 -273.624299)
			(xy 374.424499 -273.578487) (xy 374.408611 -273.529588) (xy 374.400568 -273.478806) (xy 374.143044 -273.478806)
			(xy 374.143026 -273.479747) (xy 374.135083 -273.532451) (xy 374.119373 -273.583381) (xy 374.096247 -273.631402)
			(xy 374.066223 -273.675439) (xy 374.029971 -273.71451) (xy 373.9883 -273.747741) (xy 373.942142 -273.77439)
			(xy 373.892528 -273.793862) (xy 373.840566 -273.805722) (xy 373.787416 -273.809706) (xy 373.734266 -273.805722)
			(xy 373.682304 -273.793862) (xy 373.63269 -273.77439) (xy 373.586532 -273.747741) (xy 373.544861 -273.71451)
			(xy 373.508609 -273.675439) (xy 373.478585 -273.631402) (xy 373.455459 -273.583381) (xy 373.439749 -273.532451)
			(xy 373.431806 -273.479747) (xy 373.174115 -273.479747) (xy 373.166221 -273.529588) (xy 373.150333 -273.578487)
			(xy 373.12699 -273.624299) (xy 373.096769 -273.665895) (xy 373.060413 -273.702251) (xy 373.018817 -273.732472)
			(xy 372.973005 -273.755815) (xy 372.924106 -273.771703) (xy 372.873324 -273.779746) (xy 372.821908 -273.779746)
			(xy 372.771126 -273.771703) (xy 372.722227 -273.755815) (xy 372.676415 -273.732472) (xy 372.634819 -273.702251)
			(xy 372.598463 -273.665895) (xy 372.568242 -273.624299) (xy 372.544899 -273.578487) (xy 372.529011 -273.529588)
			(xy 372.520968 -273.478806) (xy 372.234464 -273.478806) (xy 372.226421 -273.529588) (xy 372.210533 -273.578487)
			(xy 372.18719 -273.624299) (xy 372.156969 -273.665895) (xy 372.120613 -273.702251) (xy 372.079017 -273.732472)
			(xy 372.033205 -273.755815) (xy 371.984306 -273.771703) (xy 371.933524 -273.779746) (xy 371.882108 -273.779746)
			(xy 371.831326 -273.771703) (xy 371.782427 -273.755815) (xy 371.736615 -273.732472) (xy 371.695019 -273.702251)
			(xy 371.658663 -273.665895) (xy 371.628442 -273.624299) (xy 371.605099 -273.578487) (xy 371.589211 -273.529588)
			(xy 371.581168 -273.478806) (xy 371.32339 -273.478806) (xy 371.323372 -273.479747) (xy 371.315429 -273.532451)
			(xy 371.299719 -273.583381) (xy 371.276593 -273.631402) (xy 371.246569 -273.675439) (xy 371.210317 -273.71451)
			(xy 371.168646 -273.747741) (xy 371.122488 -273.77439) (xy 371.072874 -273.793862) (xy 371.020912 -273.805722)
			(xy 370.967762 -273.809706) (xy 370.914612 -273.805722) (xy 370.86265 -273.793862) (xy 370.813036 -273.77439)
			(xy 370.766878 -273.747741) (xy 370.725207 -273.71451) (xy 370.688955 -273.675439) (xy 370.658931 -273.631402)
			(xy 370.635805 -273.583381) (xy 370.620095 -273.532451) (xy 370.612152 -273.479747) (xy 370.383826 -273.479747)
			(xy 370.375883 -273.532451) (xy 370.360173 -273.583381) (xy 370.337047 -273.631402) (xy 370.307023 -273.675439)
			(xy 370.270771 -273.71451) (xy 370.2291 -273.747741) (xy 370.182942 -273.77439) (xy 370.133328 -273.793862)
			(xy 370.081366 -273.805722) (xy 370.028216 -273.809706) (xy 369.975066 -273.805722) (xy 369.923104 -273.793862)
			(xy 369.87349 -273.77439) (xy 369.827332 -273.747741) (xy 369.785661 -273.71451) (xy 369.749409 -273.675439)
			(xy 369.719385 -273.631402) (xy 369.696259 -273.583381) (xy 369.680549 -273.532451) (xy 369.672606 -273.479747)
			(xy 369.444026 -273.479747) (xy 369.436083 -273.532451) (xy 369.420373 -273.583381) (xy 369.397247 -273.631402)
			(xy 369.367223 -273.675439) (xy 369.330971 -273.71451) (xy 369.2893 -273.747741) (xy 369.243142 -273.77439)
			(xy 369.193528 -273.793862) (xy 369.141566 -273.805722) (xy 369.088416 -273.809706) (xy 369.035266 -273.805722)
			(xy 368.983304 -273.793862) (xy 368.93369 -273.77439) (xy 368.887532 -273.747741) (xy 368.845861 -273.71451)
			(xy 368.809609 -273.675439) (xy 368.779585 -273.631402) (xy 368.756459 -273.583381) (xy 368.740749 -273.532451)
			(xy 368.732806 -273.479747) (xy 368.504226 -273.479747) (xy 368.496283 -273.532451) (xy 368.480573 -273.583381)
			(xy 368.457447 -273.631402) (xy 368.427423 -273.675439) (xy 368.391171 -273.71451) (xy 368.3495 -273.747741)
			(xy 368.303342 -273.77439) (xy 368.253728 -273.793862) (xy 368.201766 -273.805722) (xy 368.148616 -273.809706)
			(xy 368.095466 -273.805722) (xy 368.043504 -273.793862) (xy 367.99389 -273.77439) (xy 367.947732 -273.747741)
			(xy 367.906061 -273.71451) (xy 367.869809 -273.675439) (xy 367.839785 -273.631402) (xy 367.816659 -273.583381)
			(xy 367.800949 -273.532451) (xy 367.793006 -273.479747) (xy 367.564426 -273.479747) (xy 367.556483 -273.532451)
			(xy 367.540773 -273.583381) (xy 367.517647 -273.631402) (xy 367.487623 -273.675439) (xy 367.451371 -273.71451)
			(xy 367.4097 -273.747741) (xy 367.363542 -273.77439) (xy 367.313928 -273.793862) (xy 367.261966 -273.805722)
			(xy 367.208816 -273.809706) (xy 367.155666 -273.805722) (xy 367.103704 -273.793862) (xy 367.05409 -273.77439)
			(xy 367.007932 -273.747741) (xy 366.966261 -273.71451) (xy 366.930009 -273.675439) (xy 366.899985 -273.631402)
			(xy 366.876859 -273.583381) (xy 366.861149 -273.532451) (xy 366.853206 -273.479747) (xy 366.624626 -273.479747)
			(xy 366.616683 -273.532451) (xy 366.600973 -273.583381) (xy 366.577847 -273.631402) (xy 366.547823 -273.675439)
			(xy 366.511571 -273.71451) (xy 366.4699 -273.747741) (xy 366.423742 -273.77439) (xy 366.374128 -273.793862)
			(xy 366.322166 -273.805722) (xy 366.269016 -273.809706) (xy 366.215866 -273.805722) (xy 366.163904 -273.793862)
			(xy 366.11429 -273.77439) (xy 366.068132 -273.747741) (xy 366.026461 -273.71451) (xy 365.990209 -273.675439)
			(xy 365.960185 -273.631402) (xy 365.937059 -273.583381) (xy 365.921349 -273.532451) (xy 365.913406 -273.479747)
			(xy 365.683813 -273.479747) (xy 365.681827 -273.506248) (xy 365.669967 -273.55821) (xy 365.650496 -273.607823)
			(xy 365.623848 -273.65398) (xy 365.590618 -273.69565) (xy 365.55155 -273.731903) (xy 365.507514 -273.761928)
			(xy 365.459495 -273.785054) (xy 365.408566 -273.800765) (xy 365.355865 -273.808711) (xy 365.329216 -273.809206)
			(xy 365.305231 -273.808819) (xy 365.257697 -273.802375) (xy 365.211463 -273.789589) (xy 365.189262 -273.780504)
			(xy 365.174131 -273.816335) (xy 365.138302 -273.885377) (xy 365.096405 -273.950914) (xy 365.07293 -273.981926)
			(xy 365.095446 -273.99951) (xy 365.135098 -274.040632) (xy 365.167673 -274.087561) (xy 365.192332 -274.139091)
			(xy 365.200946 -274.16633) (xy 365.211614 -274.202652) (xy 365.446818 -274.202652) (xy 365.457486 -274.16633)
			(xy 365.4651 -274.142069) (xy 365.486253 -274.095829) (xy 365.513767 -274.053069) (xy 365.547084 -274.014657)
			(xy 365.585526 -273.981374) (xy 365.628311 -273.953898) (xy 365.67457 -273.932788) (xy 365.723361 -273.918472)
			(xy 365.773692 -273.911241) (xy 365.799116 -273.910806) (xy 365.827098 -273.911356) (xy 365.882372 -273.920113)
			(xy 365.935596 -273.937409) (xy 365.985459 -273.962819) (xy 366.030734 -273.995715) (xy 366.070304 -274.035289)
			(xy 366.103197 -274.080566) (xy 366.128602 -274.130431) (xy 366.145894 -274.183657) (xy 366.154646 -274.238932)
			(xy 366.155224 -274.266914) (xy 366.154784 -274.292451) (xy 366.154624 -274.293563) (xy 366.383052 -274.293563)
			(xy 366.383052 -274.240265) (xy 366.390995 -274.187561) (xy 366.406705 -274.136631) (xy 366.429831 -274.08861)
			(xy 366.459855 -274.044573) (xy 366.496107 -274.005502) (xy 366.537778 -273.972271) (xy 366.583936 -273.945622)
			(xy 366.63355 -273.92615) (xy 366.685512 -273.91429) (xy 366.738662 -273.910307) (xy 366.791812 -273.91429)
			(xy 366.843774 -273.92615) (xy 366.893388 -273.945622) (xy 366.939546 -273.972271) (xy 366.981217 -274.005502)
			(xy 367.017469 -274.044573) (xy 367.047493 -274.08861) (xy 367.070619 -274.136631) (xy 367.086329 -274.187561)
			(xy 367.094272 -274.240265) (xy 367.09477 -274.266914) (xy 367.094272 -274.293563) (xy 367.322852 -274.293563)
			(xy 367.322852 -274.240265) (xy 367.330795 -274.187561) (xy 367.346505 -274.136631) (xy 367.369631 -274.08861)
			(xy 367.399655 -274.044573) (xy 367.435907 -274.005502) (xy 367.477578 -273.972271) (xy 367.523736 -273.945622)
			(xy 367.57335 -273.92615) (xy 367.625312 -273.91429) (xy 367.678462 -273.910307) (xy 367.731612 -273.91429)
			(xy 367.783574 -273.92615) (xy 367.833188 -273.945622) (xy 367.879346 -273.972271) (xy 367.921017 -274.005502)
			(xy 367.957269 -274.044573) (xy 367.987293 -274.08861) (xy 368.010419 -274.136631) (xy 368.026129 -274.187561)
			(xy 368.034072 -274.240265) (xy 368.03457 -274.266914) (xy 368.034072 -274.293563) (xy 368.262652 -274.293563)
			(xy 368.262652 -274.240265) (xy 368.270595 -274.187561) (xy 368.286305 -274.136631) (xy 368.309431 -274.08861)
			(xy 368.339455 -274.044573) (xy 368.375707 -274.005502) (xy 368.417378 -273.972271) (xy 368.463536 -273.945622)
			(xy 368.51315 -273.92615) (xy 368.565112 -273.91429) (xy 368.618262 -273.910307) (xy 368.671412 -273.91429)
			(xy 368.723374 -273.92615) (xy 368.772988 -273.945622) (xy 368.819146 -273.972271) (xy 368.860817 -274.005502)
			(xy 368.897069 -274.044573) (xy 368.927093 -274.08861) (xy 368.950219 -274.136631) (xy 368.965929 -274.187561)
			(xy 368.973872 -274.240265) (xy 368.97437 -274.266914) (xy 368.973872 -274.293563) (xy 369.202706 -274.293563)
			(xy 369.202706 -274.240265) (xy 369.210649 -274.187561) (xy 369.226359 -274.136631) (xy 369.249485 -274.08861)
			(xy 369.279509 -274.044573) (xy 369.315761 -274.005502) (xy 369.357432 -273.972271) (xy 369.40359 -273.945622)
			(xy 369.453204 -273.92615) (xy 369.505166 -273.91429) (xy 369.558316 -273.910307) (xy 369.611466 -273.91429)
			(xy 369.663428 -273.92615) (xy 369.713042 -273.945622) (xy 369.7592 -273.972271) (xy 369.800871 -274.005502)
			(xy 369.837123 -274.044573) (xy 369.867147 -274.08861) (xy 369.890273 -274.136631) (xy 369.905983 -274.187561)
			(xy 369.913926 -274.240265) (xy 369.914424 -274.266914) (xy 369.913926 -274.293563) (xy 370.142252 -274.293563)
			(xy 370.142252 -274.240265) (xy 370.150195 -274.187561) (xy 370.165905 -274.136631) (xy 370.189031 -274.08861)
			(xy 370.219055 -274.044573) (xy 370.255307 -274.005502) (xy 370.296978 -273.972271) (xy 370.343136 -273.945622)
			(xy 370.39275 -273.92615) (xy 370.444712 -273.91429) (xy 370.497862 -273.910307) (xy 370.551012 -273.91429)
			(xy 370.602974 -273.92615) (xy 370.652588 -273.945622) (xy 370.698746 -273.972271) (xy 370.740417 -274.005502)
			(xy 370.776669 -274.044573) (xy 370.806693 -274.08861) (xy 370.829819 -274.136631) (xy 370.845529 -274.187561)
			(xy 370.853472 -274.240265) (xy 370.85397 -274.266914) (xy 370.85349 -274.292622) (xy 371.111014 -274.292622)
			(xy 371.111014 -274.241206) (xy 371.119057 -274.190424) (xy 371.134945 -274.141525) (xy 371.158288 -274.095713)
			(xy 371.188509 -274.054117) (xy 371.224865 -274.017761) (xy 371.266461 -273.98754) (xy 371.312273 -273.964197)
			(xy 371.361172 -273.948309) (xy 371.411954 -273.940266) (xy 371.46337 -273.940266) (xy 371.514152 -273.948309)
			(xy 371.563051 -273.964197) (xy 371.608863 -273.98754) (xy 371.650459 -274.017761) (xy 371.686815 -274.054117)
			(xy 371.717036 -274.095713) (xy 371.740379 -274.141525) (xy 371.756267 -274.190424) (xy 371.76431 -274.241206)
			(xy 371.764814 -274.266914) (xy 371.76431 -274.292622) (xy 371.764161 -274.293563) (xy 372.021852 -274.293563)
			(xy 372.021852 -274.240265) (xy 372.029795 -274.187561) (xy 372.045505 -274.136631) (xy 372.068631 -274.08861)
			(xy 372.098655 -274.044573) (xy 372.134907 -274.005502) (xy 372.176578 -273.972271) (xy 372.222736 -273.945622)
			(xy 372.27235 -273.92615) (xy 372.324312 -273.91429) (xy 372.377462 -273.910307) (xy 372.430612 -273.91429)
			(xy 372.482574 -273.92615) (xy 372.532188 -273.945622) (xy 372.578346 -273.972271) (xy 372.620017 -274.005502)
			(xy 372.656269 -274.044573) (xy 372.686293 -274.08861) (xy 372.709419 -274.136631) (xy 372.725129 -274.187561)
			(xy 372.733072 -274.240265) (xy 372.73357 -274.266914) (xy 372.73309 -274.292622) (xy 372.990614 -274.292622)
			(xy 372.990614 -274.241206) (xy 372.998657 -274.190424) (xy 373.014545 -274.141525) (xy 373.037888 -274.095713)
			(xy 373.068109 -274.054117) (xy 373.104465 -274.017761) (xy 373.146061 -273.98754) (xy 373.191873 -273.964197)
			(xy 373.240772 -273.948309) (xy 373.291554 -273.940266) (xy 373.34297 -273.940266) (xy 373.393752 -273.948309)
			(xy 373.442651 -273.964197) (xy 373.488463 -273.98754) (xy 373.530059 -274.017761) (xy 373.566415 -274.054117)
			(xy 373.596636 -274.095713) (xy 373.619979 -274.141525) (xy 373.635867 -274.190424) (xy 373.64391 -274.241206)
			(xy 373.644414 -274.266914) (xy 373.64391 -274.292622) (xy 373.643761 -274.293563) (xy 373.901706 -274.293563)
			(xy 373.901706 -274.240265) (xy 373.909649 -274.187561) (xy 373.925359 -274.136631) (xy 373.948485 -274.08861)
			(xy 373.978509 -274.044573) (xy 374.014761 -274.005502) (xy 374.056432 -273.972271) (xy 374.10259 -273.945622)
			(xy 374.152204 -273.92615) (xy 374.204166 -273.91429) (xy 374.257316 -273.910307) (xy 374.310466 -273.91429)
			(xy 374.362428 -273.92615) (xy 374.412042 -273.945622) (xy 374.4582 -273.972271) (xy 374.499871 -274.005502)
			(xy 374.536123 -274.044573) (xy 374.566147 -274.08861) (xy 374.589273 -274.136631) (xy 374.604983 -274.187561)
			(xy 374.612926 -274.240265) (xy 374.613424 -274.266914) (xy 374.612944 -274.292622) (xy 374.870214 -274.292622)
			(xy 374.870214 -274.241206) (xy 374.878257 -274.190424) (xy 374.894145 -274.141525) (xy 374.917488 -274.095713)
			(xy 374.947709 -274.054117) (xy 374.984065 -274.017761) (xy 375.025661 -273.98754) (xy 375.071473 -273.964197)
			(xy 375.120372 -273.948309) (xy 375.171154 -273.940266) (xy 375.22257 -273.940266) (xy 375.273352 -273.948309)
			(xy 375.322251 -273.964197) (xy 375.368063 -273.98754) (xy 375.409659 -274.017761) (xy 375.446015 -274.054117)
			(xy 375.476236 -274.095713) (xy 375.499579 -274.141525) (xy 375.515467 -274.190424) (xy 375.52351 -274.241206)
			(xy 375.524014 -274.266914) (xy 375.52351 -274.292622) (xy 375.810014 -274.292622) (xy 375.810014 -274.241206)
			(xy 375.818057 -274.190424) (xy 375.833945 -274.141525) (xy 375.857288 -274.095713) (xy 375.887509 -274.054117)
			(xy 375.923865 -274.017761) (xy 375.965461 -273.98754) (xy 376.011273 -273.964197) (xy 376.060172 -273.948309)
			(xy 376.110954 -273.940266) (xy 376.16237 -273.940266) (xy 376.213152 -273.948309) (xy 376.262051 -273.964197)
			(xy 376.307863 -273.98754) (xy 376.349459 -274.017761) (xy 376.385815 -274.054117) (xy 376.416036 -274.095713)
			(xy 376.439379 -274.141525) (xy 376.455267 -274.190424) (xy 376.46331 -274.241206) (xy 376.463814 -274.266914)
			(xy 376.46331 -274.292622) (xy 376.463161 -274.293563) (xy 376.720852 -274.293563) (xy 376.720852 -274.240265)
			(xy 376.728795 -274.187561) (xy 376.744505 -274.136631) (xy 376.767631 -274.08861) (xy 376.797655 -274.044573)
			(xy 376.833907 -274.005502) (xy 376.875578 -273.972271) (xy 376.921736 -273.945622) (xy 376.97135 -273.92615)
			(xy 377.023312 -273.91429) (xy 377.076462 -273.910307) (xy 377.129612 -273.91429) (xy 377.181574 -273.92615)
			(xy 377.231188 -273.945622) (xy 377.277346 -273.972271) (xy 377.319017 -274.005502) (xy 377.355269 -274.044573)
			(xy 377.385293 -274.08861) (xy 377.408419 -274.136631) (xy 377.424129 -274.187561) (xy 377.432072 -274.240265)
			(xy 377.43257 -274.266914) (xy 377.43209 -274.292622) (xy 377.689614 -274.292622) (xy 377.689614 -274.241206)
			(xy 377.697657 -274.190424) (xy 377.713545 -274.141525) (xy 377.736888 -274.095713) (xy 377.767109 -274.054117)
			(xy 377.803465 -274.017761) (xy 377.845061 -273.98754) (xy 377.890873 -273.964197) (xy 377.939772 -273.948309)
			(xy 377.990554 -273.940266) (xy 378.04197 -273.940266) (xy 378.092752 -273.948309) (xy 378.141651 -273.964197)
			(xy 378.187463 -273.98754) (xy 378.229059 -274.017761) (xy 378.265415 -274.054117) (xy 378.295636 -274.095713)
			(xy 378.318979 -274.141525) (xy 378.334867 -274.190424) (xy 378.34291 -274.241206) (xy 378.343414 -274.266914)
			(xy 378.34291 -274.292622) (xy 378.342761 -274.293563) (xy 378.600452 -274.293563) (xy 378.600452 -274.240265)
			(xy 378.608395 -274.187561) (xy 378.624105 -274.136631) (xy 378.647231 -274.08861) (xy 378.677255 -274.044573)
			(xy 378.713507 -274.005502) (xy 378.755178 -273.972271) (xy 378.801336 -273.945622) (xy 378.85095 -273.92615)
			(xy 378.902912 -273.91429) (xy 378.956062 -273.910307) (xy 379.009212 -273.91429) (xy 379.061174 -273.92615)
			(xy 379.110788 -273.945622) (xy 379.156946 -273.972271) (xy 379.198617 -274.005502) (xy 379.234869 -274.044573)
			(xy 379.264893 -274.08861) (xy 379.288019 -274.136631) (xy 379.303729 -274.187561) (xy 379.311672 -274.240265)
			(xy 379.31217 -274.266914) (xy 379.31169 -274.292622) (xy 379.569214 -274.292622) (xy 379.569214 -274.241206)
			(xy 379.577257 -274.190424) (xy 379.593145 -274.141525) (xy 379.616488 -274.095713) (xy 379.646709 -274.054117)
			(xy 379.683065 -274.017761) (xy 379.724661 -273.98754) (xy 379.770473 -273.964197) (xy 379.819372 -273.948309)
			(xy 379.870154 -273.940266) (xy 379.92157 -273.940266) (xy 379.972352 -273.948309) (xy 380.021251 -273.964197)
			(xy 380.067063 -273.98754) (xy 380.108659 -274.017761) (xy 380.145015 -274.054117) (xy 380.175236 -274.095713)
			(xy 380.198579 -274.141525) (xy 380.214467 -274.190424) (xy 380.22251 -274.241206) (xy 380.223014 -274.266914)
			(xy 380.22251 -274.292622) (xy 380.222361 -274.293563) (xy 380.480306 -274.293563) (xy 380.480306 -274.240265)
			(xy 380.488249 -274.187561) (xy 380.503959 -274.136631) (xy 380.527085 -274.08861) (xy 380.557109 -274.044573)
			(xy 380.593361 -274.005502) (xy 380.635032 -273.972271) (xy 380.68119 -273.945622) (xy 380.730804 -273.92615)
			(xy 380.782766 -273.91429) (xy 380.835916 -273.910307) (xy 380.889066 -273.91429) (xy 380.941028 -273.92615)
			(xy 380.990642 -273.945622) (xy 381.0368 -273.972271) (xy 381.078471 -274.005502) (xy 381.114723 -274.044573)
			(xy 381.144747 -274.08861) (xy 381.167873 -274.136631) (xy 381.183583 -274.187561) (xy 381.191526 -274.240265)
			(xy 381.192024 -274.266914) (xy 381.191544 -274.292622) (xy 381.448814 -274.292622) (xy 381.448814 -274.241206)
			(xy 381.456857 -274.190424) (xy 381.472745 -274.141525) (xy 381.496088 -274.095713) (xy 381.526309 -274.054117)
			(xy 381.562665 -274.017761) (xy 381.604261 -273.98754) (xy 381.650073 -273.964197) (xy 381.698972 -273.948309)
			(xy 381.749754 -273.940266) (xy 381.80117 -273.940266) (xy 381.851952 -273.948309) (xy 381.900851 -273.964197)
			(xy 381.946663 -273.98754) (xy 381.988259 -274.017761) (xy 382.024615 -274.054117) (xy 382.054836 -274.095713)
			(xy 382.078179 -274.141525) (xy 382.094067 -274.190424) (xy 382.10211 -274.241206) (xy 382.102614 -274.266914)
			(xy 382.10211 -274.292622) (xy 382.388614 -274.292622) (xy 382.388614 -274.241206) (xy 382.396657 -274.190424)
			(xy 382.412545 -274.141525) (xy 382.435888 -274.095713) (xy 382.466109 -274.054117) (xy 382.502465 -274.017761)
			(xy 382.544061 -273.98754) (xy 382.589873 -273.964197) (xy 382.638772 -273.948309) (xy 382.689554 -273.940266)
			(xy 382.74097 -273.940266) (xy 382.791752 -273.948309) (xy 382.840651 -273.964197) (xy 382.886463 -273.98754)
			(xy 382.928059 -274.017761) (xy 382.964415 -274.054117) (xy 382.994636 -274.095713) (xy 383.017979 -274.141525)
			(xy 383.033867 -274.190424) (xy 383.04191 -274.241206) (xy 383.042414 -274.266914) (xy 383.04191 -274.292622)
			(xy 383.041761 -274.293563) (xy 383.299452 -274.293563) (xy 383.299452 -274.240265) (xy 383.307395 -274.187561)
			(xy 383.323105 -274.136631) (xy 383.346231 -274.08861) (xy 383.376255 -274.044573) (xy 383.412507 -274.005502)
			(xy 383.454178 -273.972271) (xy 383.500336 -273.945622) (xy 383.54995 -273.92615) (xy 383.601912 -273.91429)
			(xy 383.655062 -273.910307) (xy 383.708212 -273.91429) (xy 383.760174 -273.92615) (xy 383.809788 -273.945622)
			(xy 383.855946 -273.972271) (xy 383.897617 -274.005502) (xy 383.933869 -274.044573) (xy 383.963893 -274.08861)
			(xy 383.987019 -274.136631) (xy 384.002729 -274.187561) (xy 384.010672 -274.240265) (xy 384.01117 -274.266914)
			(xy 384.010672 -274.293563) (xy 384.002729 -274.346267) (xy 383.987019 -274.397197) (xy 383.963893 -274.445218)
			(xy 383.933869 -274.489255) (xy 383.897617 -274.528326) (xy 383.855946 -274.561557) (xy 383.809788 -274.588206)
			(xy 383.760174 -274.607678) (xy 383.708212 -274.619538) (xy 383.655062 -274.623522) (xy 383.601912 -274.619538)
			(xy 383.54995 -274.607678) (xy 383.500336 -274.588206) (xy 383.454178 -274.561557) (xy 383.412507 -274.528326)
			(xy 383.376255 -274.489255) (xy 383.346231 -274.445218) (xy 383.323105 -274.397197) (xy 383.307395 -274.346267)
			(xy 383.299452 -274.293563) (xy 383.041761 -274.293563) (xy 383.033867 -274.343404) (xy 383.017979 -274.392303)
			(xy 382.994636 -274.438115) (xy 382.964415 -274.479711) (xy 382.928059 -274.516067) (xy 382.886463 -274.546288)
			(xy 382.840651 -274.569631) (xy 382.791752 -274.585519) (xy 382.74097 -274.593562) (xy 382.689554 -274.593562)
			(xy 382.638772 -274.585519) (xy 382.589873 -274.569631) (xy 382.544061 -274.546288) (xy 382.502465 -274.516067)
			(xy 382.466109 -274.479711) (xy 382.435888 -274.438115) (xy 382.412545 -274.392303) (xy 382.396657 -274.343404)
			(xy 382.388614 -274.292622) (xy 382.10211 -274.292622) (xy 382.094067 -274.343404) (xy 382.078179 -274.392303)
			(xy 382.054836 -274.438115) (xy 382.024615 -274.479711) (xy 381.988259 -274.516067) (xy 381.946663 -274.546288)
			(xy 381.900851 -274.569631) (xy 381.851952 -274.585519) (xy 381.80117 -274.593562) (xy 381.749754 -274.593562)
			(xy 381.698972 -274.585519) (xy 381.650073 -274.569631) (xy 381.604261 -274.546288) (xy 381.562665 -274.516067)
			(xy 381.526309 -274.479711) (xy 381.496088 -274.438115) (xy 381.472745 -274.392303) (xy 381.456857 -274.343404)
			(xy 381.448814 -274.292622) (xy 381.191544 -274.292622) (xy 381.191526 -274.293563) (xy 381.183583 -274.346267)
			(xy 381.167873 -274.397197) (xy 381.144747 -274.445218) (xy 381.114723 -274.489255) (xy 381.078471 -274.528326)
			(xy 381.0368 -274.561557) (xy 380.990642 -274.588206) (xy 380.941028 -274.607678) (xy 380.889066 -274.619538)
			(xy 380.835916 -274.623522) (xy 380.782766 -274.619538) (xy 380.730804 -274.607678) (xy 380.68119 -274.588206)
			(xy 380.635032 -274.561557) (xy 380.593361 -274.528326) (xy 380.557109 -274.489255) (xy 380.527085 -274.445218)
			(xy 380.503959 -274.397197) (xy 380.488249 -274.346267) (xy 380.480306 -274.293563) (xy 380.222361 -274.293563)
			(xy 380.214467 -274.343404) (xy 380.198579 -274.392303) (xy 380.175236 -274.438115) (xy 380.145015 -274.479711)
			(xy 380.108659 -274.516067) (xy 380.067063 -274.546288) (xy 380.021251 -274.569631) (xy 379.972352 -274.585519)
			(xy 379.92157 -274.593562) (xy 379.870154 -274.593562) (xy 379.819372 -274.585519) (xy 379.770473 -274.569631)
			(xy 379.724661 -274.546288) (xy 379.683065 -274.516067) (xy 379.646709 -274.479711) (xy 379.616488 -274.438115)
			(xy 379.593145 -274.392303) (xy 379.577257 -274.343404) (xy 379.569214 -274.292622) (xy 379.31169 -274.292622)
			(xy 379.311672 -274.293563) (xy 379.303729 -274.346267) (xy 379.288019 -274.397197) (xy 379.264893 -274.445218)
			(xy 379.234869 -274.489255) (xy 379.198617 -274.528326) (xy 379.156946 -274.561557) (xy 379.110788 -274.588206)
			(xy 379.061174 -274.607678) (xy 379.009212 -274.619538) (xy 378.956062 -274.623522) (xy 378.902912 -274.619538)
			(xy 378.85095 -274.607678) (xy 378.801336 -274.588206) (xy 378.755178 -274.561557) (xy 378.713507 -274.528326)
			(xy 378.677255 -274.489255) (xy 378.647231 -274.445218) (xy 378.624105 -274.397197) (xy 378.608395 -274.346267)
			(xy 378.600452 -274.293563) (xy 378.342761 -274.293563) (xy 378.334867 -274.343404) (xy 378.318979 -274.392303)
			(xy 378.295636 -274.438115) (xy 378.265415 -274.479711) (xy 378.229059 -274.516067) (xy 378.187463 -274.546288)
			(xy 378.141651 -274.569631) (xy 378.092752 -274.585519) (xy 378.04197 -274.593562) (xy 377.990554 -274.593562)
			(xy 377.939772 -274.585519) (xy 377.890873 -274.569631) (xy 377.845061 -274.546288) (xy 377.803465 -274.516067)
			(xy 377.767109 -274.479711) (xy 377.736888 -274.438115) (xy 377.713545 -274.392303) (xy 377.697657 -274.343404)
			(xy 377.689614 -274.292622) (xy 377.43209 -274.292622) (xy 377.432072 -274.293563) (xy 377.424129 -274.346267)
			(xy 377.408419 -274.397197) (xy 377.385293 -274.445218) (xy 377.355269 -274.489255) (xy 377.319017 -274.528326)
			(xy 377.277346 -274.561557) (xy 377.231188 -274.588206) (xy 377.181574 -274.607678) (xy 377.129612 -274.619538)
			(xy 377.076462 -274.623522) (xy 377.023312 -274.619538) (xy 376.97135 -274.607678) (xy 376.921736 -274.588206)
			(xy 376.875578 -274.561557) (xy 376.833907 -274.528326) (xy 376.797655 -274.489255) (xy 376.767631 -274.445218)
			(xy 376.744505 -274.397197) (xy 376.728795 -274.346267) (xy 376.720852 -274.293563) (xy 376.463161 -274.293563)
			(xy 376.455267 -274.343404) (xy 376.439379 -274.392303) (xy 376.416036 -274.438115) (xy 376.385815 -274.479711)
			(xy 376.349459 -274.516067) (xy 376.307863 -274.546288) (xy 376.262051 -274.569631) (xy 376.213152 -274.585519)
			(xy 376.16237 -274.593562) (xy 376.110954 -274.593562) (xy 376.060172 -274.585519) (xy 376.011273 -274.569631)
			(xy 375.965461 -274.546288) (xy 375.923865 -274.516067) (xy 375.887509 -274.479711) (xy 375.857288 -274.438115)
			(xy 375.833945 -274.392303) (xy 375.818057 -274.343404) (xy 375.810014 -274.292622) (xy 375.52351 -274.292622)
			(xy 375.515467 -274.343404) (xy 375.499579 -274.392303) (xy 375.476236 -274.438115) (xy 375.446015 -274.479711)
			(xy 375.409659 -274.516067) (xy 375.368063 -274.546288) (xy 375.322251 -274.569631) (xy 375.273352 -274.585519)
			(xy 375.22257 -274.593562) (xy 375.171154 -274.593562) (xy 375.120372 -274.585519) (xy 375.071473 -274.569631)
			(xy 375.025661 -274.546288) (xy 374.984065 -274.516067) (xy 374.947709 -274.479711) (xy 374.917488 -274.438115)
			(xy 374.894145 -274.392303) (xy 374.878257 -274.343404) (xy 374.870214 -274.292622) (xy 374.612944 -274.292622)
			(xy 374.612926 -274.293563) (xy 374.604983 -274.346267) (xy 374.589273 -274.397197) (xy 374.566147 -274.445218)
			(xy 374.536123 -274.489255) (xy 374.499871 -274.528326) (xy 374.4582 -274.561557) (xy 374.412042 -274.588206)
			(xy 374.362428 -274.607678) (xy 374.310466 -274.619538) (xy 374.257316 -274.623522) (xy 374.204166 -274.619538)
			(xy 374.152204 -274.607678) (xy 374.10259 -274.588206) (xy 374.056432 -274.561557) (xy 374.014761 -274.528326)
			(xy 373.978509 -274.489255) (xy 373.948485 -274.445218) (xy 373.925359 -274.397197) (xy 373.909649 -274.346267)
			(xy 373.901706 -274.293563) (xy 373.643761 -274.293563) (xy 373.635867 -274.343404) (xy 373.619979 -274.392303)
			(xy 373.596636 -274.438115) (xy 373.566415 -274.479711) (xy 373.530059 -274.516067) (xy 373.488463 -274.546288)
			(xy 373.442651 -274.569631) (xy 373.393752 -274.585519) (xy 373.34297 -274.593562) (xy 373.291554 -274.593562)
			(xy 373.240772 -274.585519) (xy 373.191873 -274.569631) (xy 373.146061 -274.546288) (xy 373.104465 -274.516067)
			(xy 373.068109 -274.479711) (xy 373.037888 -274.438115) (xy 373.014545 -274.392303) (xy 372.998657 -274.343404)
			(xy 372.990614 -274.292622) (xy 372.73309 -274.292622) (xy 372.733072 -274.293563) (xy 372.725129 -274.346267)
			(xy 372.709419 -274.397197) (xy 372.686293 -274.445218) (xy 372.656269 -274.489255) (xy 372.620017 -274.528326)
			(xy 372.578346 -274.561557) (xy 372.532188 -274.588206) (xy 372.482574 -274.607678) (xy 372.430612 -274.619538)
			(xy 372.377462 -274.623522) (xy 372.324312 -274.619538) (xy 372.27235 -274.607678) (xy 372.222736 -274.588206)
			(xy 372.176578 -274.561557) (xy 372.134907 -274.528326) (xy 372.098655 -274.489255) (xy 372.068631 -274.445218)
			(xy 372.045505 -274.397197) (xy 372.029795 -274.346267) (xy 372.021852 -274.293563) (xy 371.764161 -274.293563)
			(xy 371.756267 -274.343404) (xy 371.740379 -274.392303) (xy 371.717036 -274.438115) (xy 371.686815 -274.479711)
			(xy 371.650459 -274.516067) (xy 371.608863 -274.546288) (xy 371.563051 -274.569631) (xy 371.514152 -274.585519)
			(xy 371.46337 -274.593562) (xy 371.411954 -274.593562) (xy 371.361172 -274.585519) (xy 371.312273 -274.569631)
			(xy 371.266461 -274.546288) (xy 371.224865 -274.516067) (xy 371.188509 -274.479711) (xy 371.158288 -274.438115)
			(xy 371.134945 -274.392303) (xy 371.119057 -274.343404) (xy 371.111014 -274.292622) (xy 370.85349 -274.292622)
			(xy 370.853472 -274.293563) (xy 370.845529 -274.346267) (xy 370.829819 -274.397197) (xy 370.806693 -274.445218)
			(xy 370.776669 -274.489255) (xy 370.740417 -274.528326) (xy 370.698746 -274.561557) (xy 370.652588 -274.588206)
			(xy 370.602974 -274.607678) (xy 370.551012 -274.619538) (xy 370.497862 -274.623522) (xy 370.444712 -274.619538)
			(xy 370.39275 -274.607678) (xy 370.343136 -274.588206) (xy 370.296978 -274.561557) (xy 370.255307 -274.528326)
			(xy 370.219055 -274.489255) (xy 370.189031 -274.445218) (xy 370.165905 -274.397197) (xy 370.150195 -274.346267)
			(xy 370.142252 -274.293563) (xy 369.913926 -274.293563) (xy 369.905983 -274.346267) (xy 369.890273 -274.397197)
			(xy 369.867147 -274.445218) (xy 369.837123 -274.489255) (xy 369.800871 -274.528326) (xy 369.7592 -274.561557)
			(xy 369.713042 -274.588206) (xy 369.663428 -274.607678) (xy 369.611466 -274.619538) (xy 369.558316 -274.623522)
			(xy 369.505166 -274.619538) (xy 369.453204 -274.607678) (xy 369.40359 -274.588206) (xy 369.357432 -274.561557)
			(xy 369.315761 -274.528326) (xy 369.279509 -274.489255) (xy 369.249485 -274.445218) (xy 369.226359 -274.397197)
			(xy 369.210649 -274.346267) (xy 369.202706 -274.293563) (xy 368.973872 -274.293563) (xy 368.965929 -274.346267)
			(xy 368.950219 -274.397197) (xy 368.927093 -274.445218) (xy 368.897069 -274.489255) (xy 368.860817 -274.528326)
			(xy 368.819146 -274.561557) (xy 368.772988 -274.588206) (xy 368.723374 -274.607678) (xy 368.671412 -274.619538)
			(xy 368.618262 -274.623522) (xy 368.565112 -274.619538) (xy 368.51315 -274.607678) (xy 368.463536 -274.588206)
			(xy 368.417378 -274.561557) (xy 368.375707 -274.528326) (xy 368.339455 -274.489255) (xy 368.309431 -274.445218)
			(xy 368.286305 -274.397197) (xy 368.270595 -274.346267) (xy 368.262652 -274.293563) (xy 368.034072 -274.293563)
			(xy 368.026129 -274.346267) (xy 368.010419 -274.397197) (xy 367.987293 -274.445218) (xy 367.957269 -274.489255)
			(xy 367.921017 -274.528326) (xy 367.879346 -274.561557) (xy 367.833188 -274.588206) (xy 367.783574 -274.607678)
			(xy 367.731612 -274.619538) (xy 367.678462 -274.623522) (xy 367.625312 -274.619538) (xy 367.57335 -274.607678)
			(xy 367.523736 -274.588206) (xy 367.477578 -274.561557) (xy 367.435907 -274.528326) (xy 367.399655 -274.489255)
			(xy 367.369631 -274.445218) (xy 367.346505 -274.397197) (xy 367.330795 -274.346267) (xy 367.322852 -274.293563)
			(xy 367.094272 -274.293563) (xy 367.086329 -274.346267) (xy 367.070619 -274.397197) (xy 367.047493 -274.445218)
			(xy 367.017469 -274.489255) (xy 366.981217 -274.528326) (xy 366.939546 -274.561557) (xy 366.893388 -274.588206)
			(xy 366.843774 -274.607678) (xy 366.791812 -274.619538) (xy 366.738662 -274.623522) (xy 366.685512 -274.619538)
			(xy 366.63355 -274.607678) (xy 366.583936 -274.588206) (xy 366.537778 -274.561557) (xy 366.496107 -274.528326)
			(xy 366.459855 -274.489255) (xy 366.429831 -274.445218) (xy 366.406705 -274.397197) (xy 366.390995 -274.346267)
			(xy 366.383052 -274.293563) (xy 366.154624 -274.293563) (xy 366.14749 -274.343001) (xy 366.133054 -274.391992)
			(xy 366.11177 -274.43842) (xy 366.084075 -274.481333) (xy 366.050538 -274.519853) (xy 366.011844 -274.553189)
			(xy 365.968787 -274.58066) (xy 365.945674 -274.591526) (xy 365.945674 -274.680426) (xy 365.946226 -274.695527)
			(xy 365.955061 -274.72441) (xy 365.971953 -274.749448) (xy 365.995425 -274.768456) (xy 366.023428 -274.779773)
			(xy 366.053515 -274.782411) (xy 366.08306 -274.776139) (xy 366.09655 -274.769326) (xy 366.123115 -274.755308)
			(xy 366.179783 -274.735405) (xy 366.238986 -274.725286) (xy 366.269016 -274.724622) (xy 366.295662 -274.725121)
			(xy 366.348359 -274.733066) (xy 366.399284 -274.748776) (xy 366.447298 -274.771901) (xy 366.491329 -274.801923)
			(xy 366.530395 -274.838172) (xy 366.563621 -274.879838) (xy 366.590267 -274.925991) (xy 366.609736 -274.9756)
			(xy 366.621595 -275.027556) (xy 366.625577 -275.0807) (xy 366.623578 -275.107379) (xy 366.853206 -275.107379)
			(xy 366.853206 -275.054081) (xy 366.861149 -275.001377) (xy 366.876859 -274.950447) (xy 366.899985 -274.902426)
			(xy 366.930009 -274.858389) (xy 366.966261 -274.819318) (xy 367.007932 -274.786087) (xy 367.05409 -274.759438)
			(xy 367.103704 -274.739966) (xy 367.155666 -274.728106) (xy 367.208816 -274.724123) (xy 367.261966 -274.728106)
			(xy 367.313928 -274.739966) (xy 367.363542 -274.759438) (xy 367.4097 -274.786087) (xy 367.451371 -274.819318)
			(xy 367.487623 -274.858389) (xy 367.517647 -274.902426) (xy 367.540773 -274.950447) (xy 367.556483 -275.001377)
			(xy 367.564426 -275.054081) (xy 367.564924 -275.08073) (xy 367.564426 -275.107379) (xy 367.793006 -275.107379)
			(xy 367.793006 -275.054081) (xy 367.800949 -275.001377) (xy 367.816659 -274.950447) (xy 367.839785 -274.902426)
			(xy 367.869809 -274.858389) (xy 367.906061 -274.819318) (xy 367.947732 -274.786087) (xy 367.99389 -274.759438)
			(xy 368.043504 -274.739966) (xy 368.095466 -274.728106) (xy 368.148616 -274.724123) (xy 368.201766 -274.728106)
			(xy 368.253728 -274.739966) (xy 368.303342 -274.759438) (xy 368.3495 -274.786087) (xy 368.391171 -274.819318)
			(xy 368.427423 -274.858389) (xy 368.457447 -274.902426) (xy 368.480573 -274.950447) (xy 368.496283 -275.001377)
			(xy 368.504226 -275.054081) (xy 368.504724 -275.08073) (xy 368.504231 -275.107125) (xy 368.732552 -275.107125)
			(xy 368.732552 -275.053827) (xy 368.740495 -275.001123) (xy 368.756205 -274.950193) (xy 368.779331 -274.902172)
			(xy 368.809355 -274.858135) (xy 368.845607 -274.819064) (xy 368.887278 -274.785833) (xy 368.933436 -274.759184)
			(xy 368.98305 -274.739712) (xy 369.035012 -274.727852) (xy 369.088162 -274.723869) (xy 369.141312 -274.727852)
			(xy 369.193274 -274.739712) (xy 369.242888 -274.759184) (xy 369.289046 -274.785833) (xy 369.330717 -274.819064)
			(xy 369.366969 -274.858135) (xy 369.396993 -274.902172) (xy 369.420119 -274.950193) (xy 369.435829 -275.001123)
			(xy 369.443772 -275.053827) (xy 369.44427 -275.080476) (xy 369.443772 -275.107125) (xy 369.443734 -275.107379)
			(xy 369.672606 -275.107379) (xy 369.672606 -275.054081) (xy 369.680549 -275.001377) (xy 369.696259 -274.950447)
			(xy 369.719385 -274.902426) (xy 369.749409 -274.858389) (xy 369.785661 -274.819318) (xy 369.827332 -274.786087)
			(xy 369.87349 -274.759438) (xy 369.923104 -274.739966) (xy 369.975066 -274.728106) (xy 370.028216 -274.724123)
			(xy 370.081366 -274.728106) (xy 370.133328 -274.739966) (xy 370.182942 -274.759438) (xy 370.2291 -274.786087)
			(xy 370.270771 -274.819318) (xy 370.307023 -274.858389) (xy 370.337047 -274.902426) (xy 370.360173 -274.950447)
			(xy 370.375883 -275.001377) (xy 370.383826 -275.054081) (xy 370.384324 -275.08073) (xy 370.383844 -275.106438)
			(xy 370.641368 -275.106438) (xy 370.641368 -275.055022) (xy 370.649411 -275.00424) (xy 370.665299 -274.955341)
			(xy 370.688642 -274.909529) (xy 370.718863 -274.867933) (xy 370.755219 -274.831577) (xy 370.796815 -274.801356)
			(xy 370.842627 -274.778013) (xy 370.891526 -274.762125) (xy 370.942308 -274.754082) (xy 370.993724 -274.754082)
			(xy 371.044506 -274.762125) (xy 371.093405 -274.778013) (xy 371.139217 -274.801356) (xy 371.180813 -274.831577)
			(xy 371.217169 -274.867933) (xy 371.24739 -274.909529) (xy 371.270733 -274.955341) (xy 371.286621 -275.00424)
			(xy 371.294664 -275.055022) (xy 371.295168 -275.08073) (xy 371.294664 -275.106438) (xy 371.581168 -275.106438)
			(xy 371.581168 -275.055022) (xy 371.589211 -275.00424) (xy 371.605099 -274.955341) (xy 371.628442 -274.909529)
			(xy 371.658663 -274.867933) (xy 371.695019 -274.831577) (xy 371.736615 -274.801356) (xy 371.782427 -274.778013)
			(xy 371.831326 -274.762125) (xy 371.882108 -274.754082) (xy 371.933524 -274.754082) (xy 371.984306 -274.762125)
			(xy 372.033205 -274.778013) (xy 372.079017 -274.801356) (xy 372.120613 -274.831577) (xy 372.156969 -274.867933)
			(xy 372.18719 -274.909529) (xy 372.210533 -274.955341) (xy 372.226421 -275.00424) (xy 372.234464 -275.055022)
			(xy 372.234968 -275.08073) (xy 372.234464 -275.106438) (xy 372.520968 -275.106438) (xy 372.520968 -275.055022)
			(xy 372.529011 -275.00424) (xy 372.544899 -274.955341) (xy 372.568242 -274.909529) (xy 372.598463 -274.867933)
			(xy 372.634819 -274.831577) (xy 372.676415 -274.801356) (xy 372.722227 -274.778013) (xy 372.771126 -274.762125)
			(xy 372.821908 -274.754082) (xy 372.873324 -274.754082) (xy 372.924106 -274.762125) (xy 372.973005 -274.778013)
			(xy 373.018817 -274.801356) (xy 373.060413 -274.831577) (xy 373.096769 -274.867933) (xy 373.12699 -274.909529)
			(xy 373.150333 -274.955341) (xy 373.166221 -275.00424) (xy 373.174264 -275.055022) (xy 373.174768 -275.08073)
			(xy 373.174264 -275.106438) (xy 373.460768 -275.106438) (xy 373.460768 -275.055022) (xy 373.468811 -275.00424)
			(xy 373.484699 -274.955341) (xy 373.508042 -274.909529) (xy 373.538263 -274.867933) (xy 373.574619 -274.831577)
			(xy 373.616215 -274.801356) (xy 373.662027 -274.778013) (xy 373.710926 -274.762125) (xy 373.761708 -274.754082)
			(xy 373.813124 -274.754082) (xy 373.863906 -274.762125) (xy 373.912805 -274.778013) (xy 373.958617 -274.801356)
			(xy 374.000213 -274.831577) (xy 374.036569 -274.867933) (xy 374.06679 -274.909529) (xy 374.090133 -274.955341)
			(xy 374.106021 -275.00424) (xy 374.114064 -275.055022) (xy 374.114568 -275.08073) (xy 374.114064 -275.106438)
			(xy 374.113915 -275.107379) (xy 374.371352 -275.107379) (xy 374.371352 -275.054081) (xy 374.379295 -275.001377)
			(xy 374.395005 -274.950447) (xy 374.418131 -274.902426) (xy 374.448155 -274.858389) (xy 374.484407 -274.819318)
			(xy 374.526078 -274.786087) (xy 374.572236 -274.759438) (xy 374.62185 -274.739966) (xy 374.673812 -274.728106)
			(xy 374.726962 -274.724123) (xy 374.780112 -274.728106) (xy 374.832074 -274.739966) (xy 374.881688 -274.759438)
			(xy 374.927846 -274.786087) (xy 374.969517 -274.819318) (xy 375.005769 -274.858389) (xy 375.035793 -274.902426)
			(xy 375.058919 -274.950447) (xy 375.074629 -275.001377) (xy 375.082572 -275.054081) (xy 375.08307 -275.08073)
			(xy 375.082572 -275.107379) (xy 375.311406 -275.107379) (xy 375.311406 -275.054081) (xy 375.319349 -275.001377)
			(xy 375.335059 -274.950447) (xy 375.358185 -274.902426) (xy 375.388209 -274.858389) (xy 375.424461 -274.819318)
			(xy 375.466132 -274.786087) (xy 375.51229 -274.759438) (xy 375.561904 -274.739966) (xy 375.613866 -274.728106)
			(xy 375.667016 -274.724123) (xy 375.720166 -274.728106) (xy 375.772128 -274.739966) (xy 375.821742 -274.759438)
			(xy 375.8679 -274.786087) (xy 375.909571 -274.819318) (xy 375.945823 -274.858389) (xy 375.975847 -274.902426)
			(xy 375.998973 -274.950447) (xy 376.014683 -275.001377) (xy 376.022626 -275.054081) (xy 376.023124 -275.08073)
			(xy 376.022626 -275.107379) (xy 376.251206 -275.107379) (xy 376.251206 -275.054081) (xy 376.259149 -275.001377)
			(xy 376.274859 -274.950447) (xy 376.297985 -274.902426) (xy 376.328009 -274.858389) (xy 376.364261 -274.819318)
			(xy 376.405932 -274.786087) (xy 376.45209 -274.759438) (xy 376.501704 -274.739966) (xy 376.553666 -274.728106)
			(xy 376.606816 -274.724123) (xy 376.659966 -274.728106) (xy 376.711928 -274.739966) (xy 376.761542 -274.759438)
			(xy 376.8077 -274.786087) (xy 376.849371 -274.819318) (xy 376.885623 -274.858389) (xy 376.915647 -274.902426)
			(xy 376.938773 -274.950447) (xy 376.954483 -275.001377) (xy 376.962426 -275.054081) (xy 376.962924 -275.08073)
			(xy 376.962444 -275.106438) (xy 377.219968 -275.106438) (xy 377.219968 -275.055022) (xy 377.228011 -275.00424)
			(xy 377.243899 -274.955341) (xy 377.267242 -274.909529) (xy 377.297463 -274.867933) (xy 377.333819 -274.831577)
			(xy 377.375415 -274.801356) (xy 377.421227 -274.778013) (xy 377.470126 -274.762125) (xy 377.520908 -274.754082)
			(xy 377.572324 -274.754082) (xy 377.623106 -274.762125) (xy 377.672005 -274.778013) (xy 377.717817 -274.801356)
			(xy 377.759413 -274.831577) (xy 377.795769 -274.867933) (xy 377.82599 -274.909529) (xy 377.849333 -274.955341)
			(xy 377.865221 -275.00424) (xy 377.873264 -275.055022) (xy 377.873768 -275.08073) (xy 377.873264 -275.106438)
			(xy 378.159768 -275.106438) (xy 378.159768 -275.055022) (xy 378.167811 -275.00424) (xy 378.183699 -274.955341)
			(xy 378.207042 -274.909529) (xy 378.237263 -274.867933) (xy 378.273619 -274.831577) (xy 378.315215 -274.801356)
			(xy 378.361027 -274.778013) (xy 378.409926 -274.762125) (xy 378.460708 -274.754082) (xy 378.512124 -274.754082)
			(xy 378.562906 -274.762125) (xy 378.611805 -274.778013) (xy 378.657617 -274.801356) (xy 378.699213 -274.831577)
			(xy 378.735569 -274.867933) (xy 378.76579 -274.909529) (xy 378.789133 -274.955341) (xy 378.805021 -275.00424)
			(xy 378.813064 -275.055022) (xy 378.813568 -275.08073) (xy 378.813064 -275.106438) (xy 379.099568 -275.106438)
			(xy 379.099568 -275.055022) (xy 379.107611 -275.00424) (xy 379.123499 -274.955341) (xy 379.146842 -274.909529)
			(xy 379.177063 -274.867933) (xy 379.213419 -274.831577) (xy 379.255015 -274.801356) (xy 379.300827 -274.778013)
			(xy 379.349726 -274.762125) (xy 379.400508 -274.754082) (xy 379.451924 -274.754082) (xy 379.502706 -274.762125)
			(xy 379.551605 -274.778013) (xy 379.597417 -274.801356) (xy 379.639013 -274.831577) (xy 379.675369 -274.867933)
			(xy 379.70559 -274.909529) (xy 379.728933 -274.955341) (xy 379.744821 -275.00424) (xy 379.752864 -275.055022)
			(xy 379.753368 -275.08073) (xy 379.752864 -275.106438) (xy 380.039368 -275.106438) (xy 380.039368 -275.055022)
			(xy 380.047411 -275.00424) (xy 380.063299 -274.955341) (xy 380.086642 -274.909529) (xy 380.116863 -274.867933)
			(xy 380.153219 -274.831577) (xy 380.194815 -274.801356) (xy 380.240627 -274.778013) (xy 380.289526 -274.762125)
			(xy 380.340308 -274.754082) (xy 380.391724 -274.754082) (xy 380.442506 -274.762125) (xy 380.491405 -274.778013)
			(xy 380.537217 -274.801356) (xy 380.578813 -274.831577) (xy 380.615169 -274.867933) (xy 380.64539 -274.909529)
			(xy 380.668733 -274.955341) (xy 380.684621 -275.00424) (xy 380.692664 -275.055022) (xy 380.693168 -275.08073)
			(xy 380.692664 -275.106438) (xy 380.692515 -275.107379) (xy 380.949952 -275.107379) (xy 380.949952 -275.054081)
			(xy 380.957895 -275.001377) (xy 380.973605 -274.950447) (xy 380.996731 -274.902426) (xy 381.026755 -274.858389)
			(xy 381.063007 -274.819318) (xy 381.104678 -274.786087) (xy 381.150836 -274.759438) (xy 381.20045 -274.739966)
			(xy 381.252412 -274.728106) (xy 381.305562 -274.724123) (xy 381.358712 -274.728106) (xy 381.410674 -274.739966)
			(xy 381.460288 -274.759438) (xy 381.506446 -274.786087) (xy 381.548117 -274.819318) (xy 381.584369 -274.858389)
			(xy 381.614393 -274.902426) (xy 381.637519 -274.950447) (xy 381.653229 -275.001377) (xy 381.661172 -275.054081)
			(xy 381.66167 -275.08073) (xy 381.661172 -275.107379) (xy 381.890006 -275.107379) (xy 381.890006 -275.054081)
			(xy 381.897949 -275.001377) (xy 381.913659 -274.950447) (xy 381.936785 -274.902426) (xy 381.966809 -274.858389)
			(xy 382.003061 -274.819318) (xy 382.044732 -274.786087) (xy 382.09089 -274.759438) (xy 382.140504 -274.739966)
			(xy 382.192466 -274.728106) (xy 382.245616 -274.724123) (xy 382.298766 -274.728106) (xy 382.350728 -274.739966)
			(xy 382.400342 -274.759438) (xy 382.4465 -274.786087) (xy 382.488171 -274.819318) (xy 382.524423 -274.858389)
			(xy 382.554447 -274.902426) (xy 382.577573 -274.950447) (xy 382.593283 -275.001377) (xy 382.601226 -275.054081)
			(xy 382.601724 -275.08073) (xy 382.601226 -275.107379) (xy 382.601188 -275.107633) (xy 382.829806 -275.107633)
			(xy 382.829806 -275.054335) (xy 382.837749 -275.001631) (xy 382.853459 -274.950701) (xy 382.876585 -274.90268)
			(xy 382.906609 -274.858643) (xy 382.942861 -274.819572) (xy 382.984532 -274.786341) (xy 383.03069 -274.759692)
			(xy 383.080304 -274.74022) (xy 383.132266 -274.72836) (xy 383.185416 -274.724377) (xy 383.238566 -274.72836)
			(xy 383.290528 -274.74022) (xy 383.340142 -274.759692) (xy 383.3863 -274.786341) (xy 383.427971 -274.819572)
			(xy 383.464223 -274.858643) (xy 383.494247 -274.90268) (xy 383.517373 -274.950701) (xy 383.533083 -275.001631)
			(xy 383.541026 -275.054335) (xy 383.541524 -275.080984) (xy 383.781303 -275.080984) (xy 383.785333 -275.028486)
			(xy 383.79733 -274.977218) (xy 383.817013 -274.928383) (xy 383.843919 -274.883124) (xy 383.877419 -274.842503)
			(xy 383.916727 -274.807472) (xy 383.960922 -274.778852) (xy 384.008967 -274.757313) (xy 384.059738 -274.743361)
			(xy 384.112043 -274.737323) (xy 384.164657 -274.73934) (xy 384.216347 -274.749364) (xy 384.2659 -274.767162)
			(xy 384.312156 -274.792315) (xy 384.35403 -274.824234) (xy 384.390542 -274.862172) (xy 384.420834 -274.905238)
			(xy 384.444197 -274.952423) (xy 384.460083 -275.002622) (xy 384.46812 -275.054658) (xy 384.468624 -275.080984)
			(xy 384.46812 -275.10731) (xy 384.46807 -275.107633) (xy 386.589006 -275.107633) (xy 386.589006 -275.054335)
			(xy 386.596949 -275.001631) (xy 386.612659 -274.950701) (xy 386.635785 -274.90268) (xy 386.665809 -274.858643)
			(xy 386.702061 -274.819572) (xy 386.743732 -274.786341) (xy 386.78989 -274.759692) (xy 386.839504 -274.74022)
			(xy 386.891466 -274.72836) (xy 386.944616 -274.724377) (xy 386.997766 -274.72836) (xy 387.049728 -274.74022)
			(xy 387.099342 -274.759692) (xy 387.1455 -274.786341) (xy 387.187171 -274.819572) (xy 387.223423 -274.858643)
			(xy 387.253447 -274.90268) (xy 387.276573 -274.950701) (xy 387.292283 -275.001631) (xy 387.300226 -275.054335)
			(xy 387.300724 -275.080984) (xy 387.300226 -275.107633) (xy 387.292283 -275.160337) (xy 387.276573 -275.211267)
			(xy 387.253447 -275.259288) (xy 387.223423 -275.303325) (xy 387.187171 -275.342396) (xy 387.1455 -275.375627)
			(xy 387.099342 -275.402276) (xy 387.049728 -275.421748) (xy 386.997766 -275.433608) (xy 386.944616 -275.437592)
			(xy 386.891466 -275.433608) (xy 386.839504 -275.421748) (xy 386.78989 -275.402276) (xy 386.743732 -275.375627)
			(xy 386.702061 -275.342396) (xy 386.665809 -275.303325) (xy 386.635785 -275.259288) (xy 386.612659 -275.211267)
			(xy 386.596949 -275.160337) (xy 386.589006 -275.107633) (xy 384.46807 -275.107633) (xy 384.460083 -275.159346)
			(xy 384.444197 -275.209545) (xy 384.420834 -275.25673) (xy 384.390542 -275.299796) (xy 384.35403 -275.337734)
			(xy 384.312156 -275.369653) (xy 384.2659 -275.394806) (xy 384.216347 -275.412604) (xy 384.164657 -275.422628)
			(xy 384.112043 -275.424645) (xy 384.059738 -275.418607) (xy 384.008967 -275.404655) (xy 383.960922 -275.383116)
			(xy 383.916727 -275.354496) (xy 383.877419 -275.319465) (xy 383.843919 -275.278844) (xy 383.817013 -275.233585)
			(xy 383.79733 -275.18475) (xy 383.785333 -275.133482) (xy 383.781303 -275.080984) (xy 383.541524 -275.080984)
			(xy 383.541026 -275.107633) (xy 383.533083 -275.160337) (xy 383.517373 -275.211267) (xy 383.494247 -275.259288)
			(xy 383.464223 -275.303325) (xy 383.427971 -275.342396) (xy 383.3863 -275.375627) (xy 383.340142 -275.402276)
			(xy 383.290528 -275.421748) (xy 383.238566 -275.433608) (xy 383.185416 -275.437592) (xy 383.132266 -275.433608)
			(xy 383.080304 -275.421748) (xy 383.03069 -275.402276) (xy 382.984532 -275.375627) (xy 382.942861 -275.342396)
			(xy 382.906609 -275.303325) (xy 382.876585 -275.259288) (xy 382.853459 -275.211267) (xy 382.837749 -275.160337)
			(xy 382.829806 -275.107633) (xy 382.601188 -275.107633) (xy 382.593283 -275.160083) (xy 382.577573 -275.211013)
			(xy 382.554447 -275.259034) (xy 382.524423 -275.303071) (xy 382.488171 -275.342142) (xy 382.4465 -275.375373)
			(xy 382.400342 -275.402022) (xy 382.350728 -275.421494) (xy 382.298766 -275.433354) (xy 382.245616 -275.437338)
			(xy 382.192466 -275.433354) (xy 382.140504 -275.421494) (xy 382.09089 -275.402022) (xy 382.044732 -275.375373)
			(xy 382.003061 -275.342142) (xy 381.966809 -275.303071) (xy 381.936785 -275.259034) (xy 381.913659 -275.211013)
			(xy 381.897949 -275.160083) (xy 381.890006 -275.107379) (xy 381.661172 -275.107379) (xy 381.653229 -275.160083)
			(xy 381.637519 -275.211013) (xy 381.614393 -275.259034) (xy 381.584369 -275.303071) (xy 381.548117 -275.342142)
			(xy 381.506446 -275.375373) (xy 381.460288 -275.402022) (xy 381.410674 -275.421494) (xy 381.358712 -275.433354)
			(xy 381.305562 -275.437338) (xy 381.252412 -275.433354) (xy 381.20045 -275.421494) (xy 381.150836 -275.402022)
			(xy 381.104678 -275.375373) (xy 381.063007 -275.342142) (xy 381.026755 -275.303071) (xy 380.996731 -275.259034)
			(xy 380.973605 -275.211013) (xy 380.957895 -275.160083) (xy 380.949952 -275.107379) (xy 380.692515 -275.107379)
			(xy 380.684621 -275.15722) (xy 380.668733 -275.206119) (xy 380.64539 -275.251931) (xy 380.615169 -275.293527)
			(xy 380.578813 -275.329883) (xy 380.537217 -275.360104) (xy 380.491405 -275.383447) (xy 380.442506 -275.399335)
			(xy 380.391724 -275.407378) (xy 380.340308 -275.407378) (xy 380.289526 -275.399335) (xy 380.240627 -275.383447)
			(xy 380.194815 -275.360104) (xy 380.153219 -275.329883) (xy 380.116863 -275.293527) (xy 380.086642 -275.251931)
			(xy 380.063299 -275.206119) (xy 380.047411 -275.15722) (xy 380.039368 -275.106438) (xy 379.752864 -275.106438)
			(xy 379.744821 -275.15722) (xy 379.728933 -275.206119) (xy 379.70559 -275.251931) (xy 379.675369 -275.293527)
			(xy 379.639013 -275.329883) (xy 379.597417 -275.360104) (xy 379.551605 -275.383447) (xy 379.502706 -275.399335)
			(xy 379.451924 -275.407378) (xy 379.400508 -275.407378) (xy 379.349726 -275.399335) (xy 379.300827 -275.383447)
			(xy 379.255015 -275.360104) (xy 379.213419 -275.329883) (xy 379.177063 -275.293527) (xy 379.146842 -275.251931)
			(xy 379.123499 -275.206119) (xy 379.107611 -275.15722) (xy 379.099568 -275.106438) (xy 378.813064 -275.106438)
			(xy 378.805021 -275.15722) (xy 378.789133 -275.206119) (xy 378.76579 -275.251931) (xy 378.735569 -275.293527)
			(xy 378.699213 -275.329883) (xy 378.657617 -275.360104) (xy 378.611805 -275.383447) (xy 378.562906 -275.399335)
			(xy 378.512124 -275.407378) (xy 378.460708 -275.407378) (xy 378.409926 -275.399335) (xy 378.361027 -275.383447)
			(xy 378.315215 -275.360104) (xy 378.273619 -275.329883) (xy 378.237263 -275.293527) (xy 378.207042 -275.251931)
			(xy 378.183699 -275.206119) (xy 378.167811 -275.15722) (xy 378.159768 -275.106438) (xy 377.873264 -275.106438)
			(xy 377.865221 -275.15722) (xy 377.849333 -275.206119) (xy 377.82599 -275.251931) (xy 377.795769 -275.293527)
			(xy 377.759413 -275.329883) (xy 377.717817 -275.360104) (xy 377.672005 -275.383447) (xy 377.623106 -275.399335)
			(xy 377.572324 -275.407378) (xy 377.520908 -275.407378) (xy 377.470126 -275.399335) (xy 377.421227 -275.383447)
			(xy 377.375415 -275.360104) (xy 377.333819 -275.329883) (xy 377.297463 -275.293527) (xy 377.267242 -275.251931)
			(xy 377.243899 -275.206119) (xy 377.228011 -275.15722) (xy 377.219968 -275.106438) (xy 376.962444 -275.106438)
			(xy 376.962426 -275.107379) (xy 376.954483 -275.160083) (xy 376.938773 -275.211013) (xy 376.915647 -275.259034)
			(xy 376.885623 -275.303071) (xy 376.849371 -275.342142) (xy 376.8077 -275.375373) (xy 376.761542 -275.402022)
			(xy 376.711928 -275.421494) (xy 376.659966 -275.433354) (xy 376.606816 -275.437338) (xy 376.553666 -275.433354)
			(xy 376.501704 -275.421494) (xy 376.45209 -275.402022) (xy 376.405932 -275.375373) (xy 376.364261 -275.342142)
			(xy 376.328009 -275.303071) (xy 376.297985 -275.259034) (xy 376.274859 -275.211013) (xy 376.259149 -275.160083)
			(xy 376.251206 -275.107379) (xy 376.022626 -275.107379) (xy 376.014683 -275.160083) (xy 375.998973 -275.211013)
			(xy 375.975847 -275.259034) (xy 375.945823 -275.303071) (xy 375.909571 -275.342142) (xy 375.8679 -275.375373)
			(xy 375.821742 -275.402022) (xy 375.772128 -275.421494) (xy 375.720166 -275.433354) (xy 375.667016 -275.437338)
			(xy 375.613866 -275.433354) (xy 375.561904 -275.421494) (xy 375.51229 -275.402022) (xy 375.466132 -275.375373)
			(xy 375.424461 -275.342142) (xy 375.388209 -275.303071) (xy 375.358185 -275.259034) (xy 375.335059 -275.211013)
			(xy 375.319349 -275.160083) (xy 375.311406 -275.107379) (xy 375.082572 -275.107379) (xy 375.074629 -275.160083)
			(xy 375.058919 -275.211013) (xy 375.035793 -275.259034) (xy 375.005769 -275.303071) (xy 374.969517 -275.342142)
			(xy 374.927846 -275.375373) (xy 374.881688 -275.402022) (xy 374.832074 -275.421494) (xy 374.780112 -275.433354)
			(xy 374.726962 -275.437338) (xy 374.673812 -275.433354) (xy 374.62185 -275.421494) (xy 374.572236 -275.402022)
			(xy 374.526078 -275.375373) (xy 374.484407 -275.342142) (xy 374.448155 -275.303071) (xy 374.418131 -275.259034)
			(xy 374.395005 -275.211013) (xy 374.379295 -275.160083) (xy 374.371352 -275.107379) (xy 374.113915 -275.107379)
			(xy 374.106021 -275.15722) (xy 374.090133 -275.206119) (xy 374.06679 -275.251931) (xy 374.036569 -275.293527)
			(xy 374.000213 -275.329883) (xy 373.958617 -275.360104) (xy 373.912805 -275.383447) (xy 373.863906 -275.399335)
			(xy 373.813124 -275.407378) (xy 373.761708 -275.407378) (xy 373.710926 -275.399335) (xy 373.662027 -275.383447)
			(xy 373.616215 -275.360104) (xy 373.574619 -275.329883) (xy 373.538263 -275.293527) (xy 373.508042 -275.251931)
			(xy 373.484699 -275.206119) (xy 373.468811 -275.15722) (xy 373.460768 -275.106438) (xy 373.174264 -275.106438)
			(xy 373.166221 -275.15722) (xy 373.150333 -275.206119) (xy 373.12699 -275.251931) (xy 373.096769 -275.293527)
			(xy 373.060413 -275.329883) (xy 373.018817 -275.360104) (xy 372.973005 -275.383447) (xy 372.924106 -275.399335)
			(xy 372.873324 -275.407378) (xy 372.821908 -275.407378) (xy 372.771126 -275.399335) (xy 372.722227 -275.383447)
			(xy 372.676415 -275.360104) (xy 372.634819 -275.329883) (xy 372.598463 -275.293527) (xy 372.568242 -275.251931)
			(xy 372.544899 -275.206119) (xy 372.529011 -275.15722) (xy 372.520968 -275.106438) (xy 372.234464 -275.106438)
			(xy 372.226421 -275.15722) (xy 372.210533 -275.206119) (xy 372.18719 -275.251931) (xy 372.156969 -275.293527)
			(xy 372.120613 -275.329883) (xy 372.079017 -275.360104) (xy 372.033205 -275.383447) (xy 371.984306 -275.399335)
			(xy 371.933524 -275.407378) (xy 371.882108 -275.407378) (xy 371.831326 -275.399335) (xy 371.782427 -275.383447)
			(xy 371.736615 -275.360104) (xy 371.695019 -275.329883) (xy 371.658663 -275.293527) (xy 371.628442 -275.251931)
			(xy 371.605099 -275.206119) (xy 371.589211 -275.15722) (xy 371.581168 -275.106438) (xy 371.294664 -275.106438)
			(xy 371.286621 -275.15722) (xy 371.270733 -275.206119) (xy 371.24739 -275.251931) (xy 371.217169 -275.293527)
			(xy 371.180813 -275.329883) (xy 371.139217 -275.360104) (xy 371.093405 -275.383447) (xy 371.044506 -275.399335)
			(xy 370.993724 -275.407378) (xy 370.942308 -275.407378) (xy 370.891526 -275.399335) (xy 370.842627 -275.383447)
			(xy 370.796815 -275.360104) (xy 370.755219 -275.329883) (xy 370.718863 -275.293527) (xy 370.688642 -275.251931)
			(xy 370.665299 -275.206119) (xy 370.649411 -275.15722) (xy 370.641368 -275.106438) (xy 370.383844 -275.106438)
			(xy 370.383826 -275.107379) (xy 370.375883 -275.160083) (xy 370.360173 -275.211013) (xy 370.337047 -275.259034)
			(xy 370.307023 -275.303071) (xy 370.270771 -275.342142) (xy 370.2291 -275.375373) (xy 370.182942 -275.402022)
			(xy 370.133328 -275.421494) (xy 370.081366 -275.433354) (xy 370.028216 -275.437338) (xy 369.975066 -275.433354)
			(xy 369.923104 -275.421494) (xy 369.87349 -275.402022) (xy 369.827332 -275.375373) (xy 369.785661 -275.342142)
			(xy 369.749409 -275.303071) (xy 369.719385 -275.259034) (xy 369.696259 -275.211013) (xy 369.680549 -275.160083)
			(xy 369.672606 -275.107379) (xy 369.443734 -275.107379) (xy 369.435829 -275.159829) (xy 369.420119 -275.210759)
			(xy 369.396993 -275.25878) (xy 369.366969 -275.302817) (xy 369.330717 -275.341888) (xy 369.289046 -275.375119)
			(xy 369.242888 -275.401768) (xy 369.193274 -275.42124) (xy 369.141312 -275.4331) (xy 369.088162 -275.437084)
			(xy 369.035012 -275.4331) (xy 368.98305 -275.42124) (xy 368.933436 -275.401768) (xy 368.887278 -275.375119)
			(xy 368.845607 -275.341888) (xy 368.809355 -275.302817) (xy 368.779331 -275.25878) (xy 368.756205 -275.210759)
			(xy 368.740495 -275.159829) (xy 368.732552 -275.107125) (xy 368.504231 -275.107125) (xy 368.504226 -275.107379)
			(xy 368.496283 -275.160083) (xy 368.480573 -275.211013) (xy 368.457447 -275.259034) (xy 368.427423 -275.303071)
			(xy 368.391171 -275.342142) (xy 368.3495 -275.375373) (xy 368.303342 -275.402022) (xy 368.253728 -275.421494)
			(xy 368.201766 -275.433354) (xy 368.148616 -275.437338) (xy 368.095466 -275.433354) (xy 368.043504 -275.421494)
			(xy 367.99389 -275.402022) (xy 367.947732 -275.375373) (xy 367.906061 -275.342142) (xy 367.869809 -275.303071)
			(xy 367.839785 -275.259034) (xy 367.816659 -275.211013) (xy 367.800949 -275.160083) (xy 367.793006 -275.107379)
			(xy 367.564426 -275.107379) (xy 367.556483 -275.160083) (xy 367.540773 -275.211013) (xy 367.517647 -275.259034)
			(xy 367.487623 -275.303071) (xy 367.451371 -275.342142) (xy 367.4097 -275.375373) (xy 367.363542 -275.402022)
			(xy 367.313928 -275.421494) (xy 367.261966 -275.433354) (xy 367.208816 -275.437338) (xy 367.155666 -275.433354)
			(xy 367.103704 -275.421494) (xy 367.05409 -275.402022) (xy 367.007932 -275.375373) (xy 366.966261 -275.342142)
			(xy 366.930009 -275.303071) (xy 366.899985 -275.259034) (xy 366.876859 -275.211013) (xy 366.861149 -275.160083)
			(xy 366.853206 -275.107379) (xy 366.623578 -275.107379) (xy 366.621595 -275.133844) (xy 366.609736 -275.1858)
			(xy 366.590267 -275.235409) (xy 366.563621 -275.281562) (xy 366.530395 -275.323228) (xy 366.491329 -275.359477)
			(xy 366.447298 -275.389499) (xy 366.399284 -275.412624) (xy 366.348359 -275.428334) (xy 366.295662 -275.436279)
			(xy 366.269016 -275.436838) (xy 366.238983 -275.436199) (xy 366.179775 -275.426086) (xy 366.123104 -275.406179)
			(xy 366.09655 -275.392134) (xy 366.083073 -275.385292) (xy 366.053524 -275.379015) (xy 366.023431 -275.381652)
			(xy 365.995424 -275.392974) (xy 365.971952 -275.41199) (xy 365.955066 -275.437038) (xy 365.946243 -275.46593)
			(xy 365.945674 -275.481034) (xy 365.945674 -275.570442) (xy 365.970252 -275.58213) (xy 366.01584 -275.611849)
			(xy 366.056375 -275.648161) (xy 366.090911 -275.690218) (xy 366.118644 -275.737042) (xy 366.138929 -275.787541)
			(xy 366.151292 -275.840538) (xy 366.155445 -275.8948) (xy 366.153405 -275.921449) (xy 366.383306 -275.921449)
			(xy 366.383306 -275.868151) (xy 366.391249 -275.815447) (xy 366.406959 -275.764517) (xy 366.430085 -275.716496)
			(xy 366.460109 -275.672459) (xy 366.496361 -275.633388) (xy 366.538032 -275.600157) (xy 366.58419 -275.573508)
			(xy 366.633804 -275.554036) (xy 366.685766 -275.542176) (xy 366.738916 -275.538193) (xy 366.792066 -275.542176)
			(xy 366.844028 -275.554036) (xy 366.893642 -275.573508) (xy 366.9398 -275.600157) (xy 366.981471 -275.633388)
			(xy 367.017723 -275.672459) (xy 367.047747 -275.716496) (xy 367.070873 -275.764517) (xy 367.086583 -275.815447)
			(xy 367.094526 -275.868151) (xy 367.095024 -275.8948) (xy 367.094531 -275.921195) (xy 367.323106 -275.921195)
			(xy 367.323106 -275.867897) (xy 367.331049 -275.815193) (xy 367.346759 -275.764263) (xy 367.369885 -275.716242)
			(xy 367.399909 -275.672205) (xy 367.436161 -275.633134) (xy 367.477832 -275.599903) (xy 367.52399 -275.573254)
			(xy 367.573604 -275.553782) (xy 367.625566 -275.541922) (xy 367.678716 -275.537939) (xy 367.731866 -275.541922)
			(xy 367.783828 -275.553782) (xy 367.833442 -275.573254) (xy 367.8796 -275.599903) (xy 367.921271 -275.633134)
			(xy 367.957523 -275.672205) (xy 367.987547 -275.716242) (xy 368.010673 -275.764263) (xy 368.026383 -275.815193)
			(xy 368.034326 -275.867897) (xy 368.034824 -275.894546) (xy 368.034326 -275.921195) (xy 368.262906 -275.921195)
			(xy 368.262906 -275.867897) (xy 368.270849 -275.815193) (xy 368.286559 -275.764263) (xy 368.309685 -275.716242)
			(xy 368.339709 -275.672205) (xy 368.375961 -275.633134) (xy 368.417632 -275.599903) (xy 368.46379 -275.573254)
			(xy 368.513404 -275.553782) (xy 368.565366 -275.541922) (xy 368.618516 -275.537939) (xy 368.671666 -275.541922)
			(xy 368.723628 -275.553782) (xy 368.773242 -275.573254) (xy 368.8194 -275.599903) (xy 368.861071 -275.633134)
			(xy 368.897323 -275.672205) (xy 368.927347 -275.716242) (xy 368.950473 -275.764263) (xy 368.966183 -275.815193)
			(xy 368.974126 -275.867897) (xy 368.974624 -275.894546) (xy 368.974126 -275.921195) (xy 369.202706 -275.921195)
			(xy 369.202706 -275.867897) (xy 369.210649 -275.815193) (xy 369.226359 -275.764263) (xy 369.249485 -275.716242)
			(xy 369.279509 -275.672205) (xy 369.315761 -275.633134) (xy 369.357432 -275.599903) (xy 369.40359 -275.573254)
			(xy 369.453204 -275.553782) (xy 369.505166 -275.541922) (xy 369.558316 -275.537939) (xy 369.611466 -275.541922)
			(xy 369.663428 -275.553782) (xy 369.713042 -275.573254) (xy 369.7592 -275.599903) (xy 369.800871 -275.633134)
			(xy 369.837123 -275.672205) (xy 369.867147 -275.716242) (xy 369.890273 -275.764263) (xy 369.905983 -275.815193)
			(xy 369.913926 -275.867897) (xy 369.914424 -275.894546) (xy 369.913926 -275.921195) (xy 369.913888 -275.921449)
			(xy 370.142506 -275.921449) (xy 370.142506 -275.868151) (xy 370.150449 -275.815447) (xy 370.166159 -275.764517)
			(xy 370.189285 -275.716496) (xy 370.219309 -275.672459) (xy 370.255561 -275.633388) (xy 370.297232 -275.600157)
			(xy 370.34339 -275.573508) (xy 370.393004 -275.554036) (xy 370.444966 -275.542176) (xy 370.498116 -275.538193)
			(xy 370.551266 -275.542176) (xy 370.603228 -275.554036) (xy 370.652842 -275.573508) (xy 370.699 -275.600157)
			(xy 370.740671 -275.633388) (xy 370.776923 -275.672459) (xy 370.806947 -275.716496) (xy 370.830073 -275.764517)
			(xy 370.845783 -275.815447) (xy 370.853726 -275.868151) (xy 370.854224 -275.8948) (xy 370.853744 -275.920508)
			(xy 371.111014 -275.920508) (xy 371.111014 -275.869092) (xy 371.119057 -275.81831) (xy 371.134945 -275.769411)
			(xy 371.158288 -275.723599) (xy 371.188509 -275.682003) (xy 371.224865 -275.645647) (xy 371.266461 -275.615426)
			(xy 371.312273 -275.592083) (xy 371.361172 -275.576195) (xy 371.411954 -275.568152) (xy 371.46337 -275.568152)
			(xy 371.514152 -275.576195) (xy 371.563051 -275.592083) (xy 371.608863 -275.615426) (xy 371.650459 -275.645647)
			(xy 371.686815 -275.682003) (xy 371.717036 -275.723599) (xy 371.740379 -275.769411) (xy 371.756267 -275.81831)
			(xy 371.76431 -275.869092) (xy 371.764814 -275.8948) (xy 371.76431 -275.920508) (xy 371.764161 -275.921449)
			(xy 372.021852 -275.921449) (xy 372.021852 -275.868151) (xy 372.029795 -275.815447) (xy 372.045505 -275.764517)
			(xy 372.068631 -275.716496) (xy 372.098655 -275.672459) (xy 372.134907 -275.633388) (xy 372.176578 -275.600157)
			(xy 372.222736 -275.573508) (xy 372.27235 -275.554036) (xy 372.324312 -275.542176) (xy 372.377462 -275.538193)
			(xy 372.430612 -275.542176) (xy 372.482574 -275.554036) (xy 372.532188 -275.573508) (xy 372.578346 -275.600157)
			(xy 372.620017 -275.633388) (xy 372.656269 -275.672459) (xy 372.686293 -275.716496) (xy 372.709419 -275.764517)
			(xy 372.725129 -275.815447) (xy 372.733072 -275.868151) (xy 372.73357 -275.8948) (xy 372.73309 -275.920508)
			(xy 372.990614 -275.920508) (xy 372.990614 -275.869092) (xy 372.998657 -275.81831) (xy 373.014545 -275.769411)
			(xy 373.037888 -275.723599) (xy 373.068109 -275.682003) (xy 373.104465 -275.645647) (xy 373.146061 -275.615426)
			(xy 373.191873 -275.592083) (xy 373.240772 -275.576195) (xy 373.291554 -275.568152) (xy 373.34297 -275.568152)
			(xy 373.393752 -275.576195) (xy 373.442651 -275.592083) (xy 373.488463 -275.615426) (xy 373.530059 -275.645647)
			(xy 373.566415 -275.682003) (xy 373.596636 -275.723599) (xy 373.619979 -275.769411) (xy 373.635867 -275.81831)
			(xy 373.64391 -275.869092) (xy 373.644414 -275.8948) (xy 373.64391 -275.920508) (xy 373.643761 -275.921449)
			(xy 373.901452 -275.921449) (xy 373.901452 -275.868151) (xy 373.909395 -275.815447) (xy 373.925105 -275.764517)
			(xy 373.948231 -275.716496) (xy 373.978255 -275.672459) (xy 374.014507 -275.633388) (xy 374.056178 -275.600157)
			(xy 374.102336 -275.573508) (xy 374.15195 -275.554036) (xy 374.203912 -275.542176) (xy 374.257062 -275.538193)
			(xy 374.310212 -275.542176) (xy 374.362174 -275.554036) (xy 374.411788 -275.573508) (xy 374.457946 -275.600157)
			(xy 374.499617 -275.633388) (xy 374.535869 -275.672459) (xy 374.565893 -275.716496) (xy 374.589019 -275.764517)
			(xy 374.604729 -275.815447) (xy 374.612672 -275.868151) (xy 374.61317 -275.8948) (xy 374.61269 -275.920508)
			(xy 374.870214 -275.920508) (xy 374.870214 -275.869092) (xy 374.878257 -275.81831) (xy 374.894145 -275.769411)
			(xy 374.917488 -275.723599) (xy 374.947709 -275.682003) (xy 374.984065 -275.645647) (xy 375.025661 -275.615426)
			(xy 375.071473 -275.592083) (xy 375.120372 -275.576195) (xy 375.171154 -275.568152) (xy 375.22257 -275.568152)
			(xy 375.273352 -275.576195) (xy 375.322251 -275.592083) (xy 375.368063 -275.615426) (xy 375.409659 -275.645647)
			(xy 375.446015 -275.682003) (xy 375.476236 -275.723599) (xy 375.499579 -275.769411) (xy 375.515467 -275.81831)
			(xy 375.52351 -275.869092) (xy 375.524014 -275.8948) (xy 375.52351 -275.920508) (xy 375.810014 -275.920508)
			(xy 375.810014 -275.869092) (xy 375.818057 -275.81831) (xy 375.833945 -275.769411) (xy 375.857288 -275.723599)
			(xy 375.887509 -275.682003) (xy 375.923865 -275.645647) (xy 375.965461 -275.615426) (xy 376.011273 -275.592083)
			(xy 376.060172 -275.576195) (xy 376.110954 -275.568152) (xy 376.16237 -275.568152) (xy 376.213152 -275.576195)
			(xy 376.262051 -275.592083) (xy 376.307863 -275.615426) (xy 376.349459 -275.645647) (xy 376.385815 -275.682003)
			(xy 376.416036 -275.723599) (xy 376.439379 -275.769411) (xy 376.455267 -275.81831) (xy 376.46331 -275.869092)
			(xy 376.463814 -275.8948) (xy 376.46331 -275.920508) (xy 376.463161 -275.921449) (xy 376.721106 -275.921449)
			(xy 376.721106 -275.868151) (xy 376.729049 -275.815447) (xy 376.744759 -275.764517) (xy 376.767885 -275.716496)
			(xy 376.797909 -275.672459) (xy 376.834161 -275.633388) (xy 376.875832 -275.600157) (xy 376.92199 -275.573508)
			(xy 376.971604 -275.554036) (xy 377.023566 -275.542176) (xy 377.076716 -275.538193) (xy 377.129866 -275.542176)
			(xy 377.181828 -275.554036) (xy 377.231442 -275.573508) (xy 377.2776 -275.600157) (xy 377.319271 -275.633388)
			(xy 377.355523 -275.672459) (xy 377.385547 -275.716496) (xy 377.408673 -275.764517) (xy 377.424383 -275.815447)
			(xy 377.432326 -275.868151) (xy 377.432824 -275.8948) (xy 377.432344 -275.920508) (xy 377.689614 -275.920508)
			(xy 377.689614 -275.869092) (xy 377.697657 -275.81831) (xy 377.713545 -275.769411) (xy 377.736888 -275.723599)
			(xy 377.767109 -275.682003) (xy 377.803465 -275.645647) (xy 377.845061 -275.615426) (xy 377.890873 -275.592083)
			(xy 377.939772 -275.576195) (xy 377.990554 -275.568152) (xy 378.04197 -275.568152) (xy 378.092752 -275.576195)
			(xy 378.141651 -275.592083) (xy 378.187463 -275.615426) (xy 378.229059 -275.645647) (xy 378.265415 -275.682003)
			(xy 378.295636 -275.723599) (xy 378.318979 -275.769411) (xy 378.334867 -275.81831) (xy 378.34291 -275.869092)
			(xy 378.343414 -275.8948) (xy 378.34291 -275.920508) (xy 378.342761 -275.921449) (xy 378.600452 -275.921449)
			(xy 378.600452 -275.868151) (xy 378.608395 -275.815447) (xy 378.624105 -275.764517) (xy 378.647231 -275.716496)
			(xy 378.677255 -275.672459) (xy 378.713507 -275.633388) (xy 378.755178 -275.600157) (xy 378.801336 -275.573508)
			(xy 378.85095 -275.554036) (xy 378.902912 -275.542176) (xy 378.956062 -275.538193) (xy 379.009212 -275.542176)
			(xy 379.061174 -275.554036) (xy 379.110788 -275.573508) (xy 379.156946 -275.600157) (xy 379.198617 -275.633388)
			(xy 379.234869 -275.672459) (xy 379.264893 -275.716496) (xy 379.288019 -275.764517) (xy 379.303729 -275.815447)
			(xy 379.311672 -275.868151) (xy 379.31217 -275.8948) (xy 379.31169 -275.920508) (xy 379.569214 -275.920508)
			(xy 379.569214 -275.869092) (xy 379.577257 -275.81831) (xy 379.593145 -275.769411) (xy 379.616488 -275.723599)
			(xy 379.646709 -275.682003) (xy 379.683065 -275.645647) (xy 379.724661 -275.615426) (xy 379.770473 -275.592083)
			(xy 379.819372 -275.576195) (xy 379.870154 -275.568152) (xy 379.92157 -275.568152) (xy 379.972352 -275.576195)
			(xy 380.021251 -275.592083) (xy 380.067063 -275.615426) (xy 380.108659 -275.645647) (xy 380.145015 -275.682003)
			(xy 380.175236 -275.723599) (xy 380.198579 -275.769411) (xy 380.214467 -275.81831) (xy 380.22251 -275.869092)
			(xy 380.223014 -275.8948) (xy 380.22251 -275.920508) (xy 380.222361 -275.921449) (xy 380.480052 -275.921449)
			(xy 380.480052 -275.868151) (xy 380.487995 -275.815447) (xy 380.503705 -275.764517) (xy 380.526831 -275.716496)
			(xy 380.556855 -275.672459) (xy 380.593107 -275.633388) (xy 380.634778 -275.600157) (xy 380.680936 -275.573508)
			(xy 380.73055 -275.554036) (xy 380.782512 -275.542176) (xy 380.835662 -275.538193) (xy 380.888812 -275.542176)
			(xy 380.940774 -275.554036) (xy 380.990388 -275.573508) (xy 381.036546 -275.600157) (xy 381.078217 -275.633388)
			(xy 381.114469 -275.672459) (xy 381.144493 -275.716496) (xy 381.167619 -275.764517) (xy 381.183329 -275.815447)
			(xy 381.191272 -275.868151) (xy 381.19177 -275.8948) (xy 381.19129 -275.920508) (xy 381.448814 -275.920508)
			(xy 381.448814 -275.869092) (xy 381.456857 -275.81831) (xy 381.472745 -275.769411) (xy 381.496088 -275.723599)
			(xy 381.526309 -275.682003) (xy 381.562665 -275.645647) (xy 381.604261 -275.615426) (xy 381.650073 -275.592083)
			(xy 381.698972 -275.576195) (xy 381.749754 -275.568152) (xy 381.80117 -275.568152) (xy 381.851952 -275.576195)
			(xy 381.900851 -275.592083) (xy 381.946663 -275.615426) (xy 381.988259 -275.645647) (xy 382.024615 -275.682003)
			(xy 382.054836 -275.723599) (xy 382.078179 -275.769411) (xy 382.094067 -275.81831) (xy 382.10211 -275.869092)
			(xy 382.102614 -275.8948) (xy 382.10211 -275.920508) (xy 382.388614 -275.920508) (xy 382.388614 -275.869092)
			(xy 382.396657 -275.81831) (xy 382.412545 -275.769411) (xy 382.435888 -275.723599) (xy 382.466109 -275.682003)
			(xy 382.502465 -275.645647) (xy 382.544061 -275.615426) (xy 382.589873 -275.592083) (xy 382.638772 -275.576195)
			(xy 382.689554 -275.568152) (xy 382.74097 -275.568152) (xy 382.791752 -275.576195) (xy 382.840651 -275.592083)
			(xy 382.886463 -275.615426) (xy 382.928059 -275.645647) (xy 382.964415 -275.682003) (xy 382.994636 -275.723599)
			(xy 383.017979 -275.769411) (xy 383.033867 -275.81831) (xy 383.04191 -275.869092) (xy 383.042414 -275.8948)
			(xy 383.04191 -275.920508) (xy 383.041761 -275.921449) (xy 383.299452 -275.921449) (xy 383.299452 -275.868151)
			(xy 383.307395 -275.815447) (xy 383.323105 -275.764517) (xy 383.346231 -275.716496) (xy 383.376255 -275.672459)
			(xy 383.412507 -275.633388) (xy 383.454178 -275.600157) (xy 383.500336 -275.573508) (xy 383.54995 -275.554036)
			(xy 383.601912 -275.542176) (xy 383.655062 -275.538193) (xy 383.708212 -275.542176) (xy 383.760174 -275.554036)
			(xy 383.809788 -275.573508) (xy 383.855946 -275.600157) (xy 383.897617 -275.633388) (xy 383.933869 -275.672459)
			(xy 383.963893 -275.716496) (xy 383.987019 -275.764517) (xy 384.002729 -275.815447) (xy 384.010672 -275.868151)
			(xy 384.01117 -275.8948) (xy 384.010672 -275.921449) (xy 384.002729 -275.974153) (xy 383.987019 -276.025083)
			(xy 383.963893 -276.073104) (xy 383.933869 -276.117141) (xy 383.897617 -276.156212) (xy 383.855946 -276.189443)
			(xy 383.809788 -276.216092) (xy 383.760174 -276.235564) (xy 383.708212 -276.247424) (xy 383.655062 -276.251408)
			(xy 383.601912 -276.247424) (xy 383.54995 -276.235564) (xy 383.500336 -276.216092) (xy 383.454178 -276.189443)
			(xy 383.412507 -276.156212) (xy 383.376255 -276.117141) (xy 383.346231 -276.073104) (xy 383.323105 -276.025083)
			(xy 383.307395 -275.974153) (xy 383.299452 -275.921449) (xy 383.041761 -275.921449) (xy 383.033867 -275.97129)
			(xy 383.017979 -276.020189) (xy 382.994636 -276.066001) (xy 382.964415 -276.107597) (xy 382.928059 -276.143953)
			(xy 382.886463 -276.174174) (xy 382.840651 -276.197517) (xy 382.791752 -276.213405) (xy 382.74097 -276.221448)
			(xy 382.689554 -276.221448) (xy 382.638772 -276.213405) (xy 382.589873 -276.197517) (xy 382.544061 -276.174174)
			(xy 382.502465 -276.143953) (xy 382.466109 -276.107597) (xy 382.435888 -276.066001) (xy 382.412545 -276.020189)
			(xy 382.396657 -275.97129) (xy 382.388614 -275.920508) (xy 382.10211 -275.920508) (xy 382.094067 -275.97129)
			(xy 382.078179 -276.020189) (xy 382.054836 -276.066001) (xy 382.024615 -276.107597) (xy 381.988259 -276.143953)
			(xy 381.946663 -276.174174) (xy 381.900851 -276.197517) (xy 381.851952 -276.213405) (xy 381.80117 -276.221448)
			(xy 381.749754 -276.221448) (xy 381.698972 -276.213405) (xy 381.650073 -276.197517) (xy 381.604261 -276.174174)
			(xy 381.562665 -276.143953) (xy 381.526309 -276.107597) (xy 381.496088 -276.066001) (xy 381.472745 -276.020189)
			(xy 381.456857 -275.97129) (xy 381.448814 -275.920508) (xy 381.19129 -275.920508) (xy 381.191272 -275.921449)
			(xy 381.183329 -275.974153) (xy 381.167619 -276.025083) (xy 381.144493 -276.073104) (xy 381.114469 -276.117141)
			(xy 381.078217 -276.156212) (xy 381.036546 -276.189443) (xy 380.990388 -276.216092) (xy 380.940774 -276.235564)
			(xy 380.888812 -276.247424) (xy 380.835662 -276.251408) (xy 380.782512 -276.247424) (xy 380.73055 -276.235564)
			(xy 380.680936 -276.216092) (xy 380.634778 -276.189443) (xy 380.593107 -276.156212) (xy 380.556855 -276.117141)
			(xy 380.526831 -276.073104) (xy 380.503705 -276.025083) (xy 380.487995 -275.974153) (xy 380.480052 -275.921449)
			(xy 380.222361 -275.921449) (xy 380.214467 -275.97129) (xy 380.198579 -276.020189) (xy 380.175236 -276.066001)
			(xy 380.145015 -276.107597) (xy 380.108659 -276.143953) (xy 380.067063 -276.174174) (xy 380.021251 -276.197517)
			(xy 379.972352 -276.213405) (xy 379.92157 -276.221448) (xy 379.870154 -276.221448) (xy 379.819372 -276.213405)
			(xy 379.770473 -276.197517) (xy 379.724661 -276.174174) (xy 379.683065 -276.143953) (xy 379.646709 -276.107597)
			(xy 379.616488 -276.066001) (xy 379.593145 -276.020189) (xy 379.577257 -275.97129) (xy 379.569214 -275.920508)
			(xy 379.31169 -275.920508) (xy 379.311672 -275.921449) (xy 379.303729 -275.974153) (xy 379.288019 -276.025083)
			(xy 379.264893 -276.073104) (xy 379.234869 -276.117141) (xy 379.198617 -276.156212) (xy 379.156946 -276.189443)
			(xy 379.110788 -276.216092) (xy 379.061174 -276.235564) (xy 379.009212 -276.247424) (xy 378.956062 -276.251408)
			(xy 378.902912 -276.247424) (xy 378.85095 -276.235564) (xy 378.801336 -276.216092) (xy 378.755178 -276.189443)
			(xy 378.713507 -276.156212) (xy 378.677255 -276.117141) (xy 378.647231 -276.073104) (xy 378.624105 -276.025083)
			(xy 378.608395 -275.974153) (xy 378.600452 -275.921449) (xy 378.342761 -275.921449) (xy 378.334867 -275.97129)
			(xy 378.318979 -276.020189) (xy 378.295636 -276.066001) (xy 378.265415 -276.107597) (xy 378.229059 -276.143953)
			(xy 378.187463 -276.174174) (xy 378.141651 -276.197517) (xy 378.092752 -276.213405) (xy 378.04197 -276.221448)
			(xy 377.990554 -276.221448) (xy 377.939772 -276.213405) (xy 377.890873 -276.197517) (xy 377.845061 -276.174174)
			(xy 377.803465 -276.143953) (xy 377.767109 -276.107597) (xy 377.736888 -276.066001) (xy 377.713545 -276.020189)
			(xy 377.697657 -275.97129) (xy 377.689614 -275.920508) (xy 377.432344 -275.920508) (xy 377.432326 -275.921449)
			(xy 377.424383 -275.974153) (xy 377.408673 -276.025083) (xy 377.385547 -276.073104) (xy 377.355523 -276.117141)
			(xy 377.319271 -276.156212) (xy 377.2776 -276.189443) (xy 377.231442 -276.216092) (xy 377.181828 -276.235564)
			(xy 377.129866 -276.247424) (xy 377.076716 -276.251408) (xy 377.023566 -276.247424) (xy 376.971604 -276.235564)
			(xy 376.92199 -276.216092) (xy 376.875832 -276.189443) (xy 376.834161 -276.156212) (xy 376.797909 -276.117141)
			(xy 376.767885 -276.073104) (xy 376.744759 -276.025083) (xy 376.729049 -275.974153) (xy 376.721106 -275.921449)
			(xy 376.463161 -275.921449) (xy 376.455267 -275.97129) (xy 376.439379 -276.020189) (xy 376.416036 -276.066001)
			(xy 376.385815 -276.107597) (xy 376.349459 -276.143953) (xy 376.307863 -276.174174) (xy 376.262051 -276.197517)
			(xy 376.213152 -276.213405) (xy 376.16237 -276.221448) (xy 376.110954 -276.221448) (xy 376.060172 -276.213405)
			(xy 376.011273 -276.197517) (xy 375.965461 -276.174174) (xy 375.923865 -276.143953) (xy 375.887509 -276.107597)
			(xy 375.857288 -276.066001) (xy 375.833945 -276.020189) (xy 375.818057 -275.97129) (xy 375.810014 -275.920508)
			(xy 375.52351 -275.920508) (xy 375.515467 -275.97129) (xy 375.499579 -276.020189) (xy 375.476236 -276.066001)
			(xy 375.446015 -276.107597) (xy 375.409659 -276.143953) (xy 375.368063 -276.174174) (xy 375.322251 -276.197517)
			(xy 375.273352 -276.213405) (xy 375.22257 -276.221448) (xy 375.171154 -276.221448) (xy 375.120372 -276.213405)
			(xy 375.071473 -276.197517) (xy 375.025661 -276.174174) (xy 374.984065 -276.143953) (xy 374.947709 -276.107597)
			(xy 374.917488 -276.066001) (xy 374.894145 -276.020189) (xy 374.878257 -275.97129) (xy 374.870214 -275.920508)
			(xy 374.61269 -275.920508) (xy 374.612672 -275.921449) (xy 374.604729 -275.974153) (xy 374.589019 -276.025083)
			(xy 374.565893 -276.073104) (xy 374.535869 -276.117141) (xy 374.499617 -276.156212) (xy 374.457946 -276.189443)
			(xy 374.411788 -276.216092) (xy 374.362174 -276.235564) (xy 374.310212 -276.247424) (xy 374.257062 -276.251408)
			(xy 374.203912 -276.247424) (xy 374.15195 -276.235564) (xy 374.102336 -276.216092) (xy 374.056178 -276.189443)
			(xy 374.014507 -276.156212) (xy 373.978255 -276.117141) (xy 373.948231 -276.073104) (xy 373.925105 -276.025083)
			(xy 373.909395 -275.974153) (xy 373.901452 -275.921449) (xy 373.643761 -275.921449) (xy 373.635867 -275.97129)
			(xy 373.619979 -276.020189) (xy 373.596636 -276.066001) (xy 373.566415 -276.107597) (xy 373.530059 -276.143953)
			(xy 373.488463 -276.174174) (xy 373.442651 -276.197517) (xy 373.393752 -276.213405) (xy 373.34297 -276.221448)
			(xy 373.291554 -276.221448) (xy 373.240772 -276.213405) (xy 373.191873 -276.197517) (xy 373.146061 -276.174174)
			(xy 373.104465 -276.143953) (xy 373.068109 -276.107597) (xy 373.037888 -276.066001) (xy 373.014545 -276.020189)
			(xy 372.998657 -275.97129) (xy 372.990614 -275.920508) (xy 372.73309 -275.920508) (xy 372.733072 -275.921449)
			(xy 372.725129 -275.974153) (xy 372.709419 -276.025083) (xy 372.686293 -276.073104) (xy 372.656269 -276.117141)
			(xy 372.620017 -276.156212) (xy 372.578346 -276.189443) (xy 372.532188 -276.216092) (xy 372.482574 -276.235564)
			(xy 372.430612 -276.247424) (xy 372.377462 -276.251408) (xy 372.324312 -276.247424) (xy 372.27235 -276.235564)
			(xy 372.222736 -276.216092) (xy 372.176578 -276.189443) (xy 372.134907 -276.156212) (xy 372.098655 -276.117141)
			(xy 372.068631 -276.073104) (xy 372.045505 -276.025083) (xy 372.029795 -275.974153) (xy 372.021852 -275.921449)
			(xy 371.764161 -275.921449) (xy 371.756267 -275.97129) (xy 371.740379 -276.020189) (xy 371.717036 -276.066001)
			(xy 371.686815 -276.107597) (xy 371.650459 -276.143953) (xy 371.608863 -276.174174) (xy 371.563051 -276.197517)
			(xy 371.514152 -276.213405) (xy 371.46337 -276.221448) (xy 371.411954 -276.221448) (xy 371.361172 -276.213405)
			(xy 371.312273 -276.197517) (xy 371.266461 -276.174174) (xy 371.224865 -276.143953) (xy 371.188509 -276.107597)
			(xy 371.158288 -276.066001) (xy 371.134945 -276.020189) (xy 371.119057 -275.97129) (xy 371.111014 -275.920508)
			(xy 370.853744 -275.920508) (xy 370.853726 -275.921449) (xy 370.845783 -275.974153) (xy 370.830073 -276.025083)
			(xy 370.806947 -276.073104) (xy 370.776923 -276.117141) (xy 370.740671 -276.156212) (xy 370.699 -276.189443)
			(xy 370.652842 -276.216092) (xy 370.603228 -276.235564) (xy 370.551266 -276.247424) (xy 370.498116 -276.251408)
			(xy 370.444966 -276.247424) (xy 370.393004 -276.235564) (xy 370.34339 -276.216092) (xy 370.297232 -276.189443)
			(xy 370.255561 -276.156212) (xy 370.219309 -276.117141) (xy 370.189285 -276.073104) (xy 370.166159 -276.025083)
			(xy 370.150449 -275.974153) (xy 370.142506 -275.921449) (xy 369.913888 -275.921449) (xy 369.905983 -275.973899)
			(xy 369.890273 -276.024829) (xy 369.867147 -276.07285) (xy 369.837123 -276.116887) (xy 369.800871 -276.155958)
			(xy 369.7592 -276.189189) (xy 369.713042 -276.215838) (xy 369.663428 -276.23531) (xy 369.611466 -276.24717)
			(xy 369.558316 -276.251154) (xy 369.505166 -276.24717) (xy 369.453204 -276.23531) (xy 369.40359 -276.215838)
			(xy 369.357432 -276.189189) (xy 369.315761 -276.155958) (xy 369.279509 -276.116887) (xy 369.249485 -276.07285)
			(xy 369.226359 -276.024829) (xy 369.210649 -275.973899) (xy 369.202706 -275.921195) (xy 368.974126 -275.921195)
			(xy 368.966183 -275.973899) (xy 368.950473 -276.024829) (xy 368.927347 -276.07285) (xy 368.897323 -276.116887)
			(xy 368.861071 -276.155958) (xy 368.8194 -276.189189) (xy 368.773242 -276.215838) (xy 368.723628 -276.23531)
			(xy 368.671666 -276.24717) (xy 368.618516 -276.251154) (xy 368.565366 -276.24717) (xy 368.513404 -276.23531)
			(xy 368.46379 -276.215838) (xy 368.417632 -276.189189) (xy 368.375961 -276.155958) (xy 368.339709 -276.116887)
			(xy 368.309685 -276.07285) (xy 368.286559 -276.024829) (xy 368.270849 -275.973899) (xy 368.262906 -275.921195)
			(xy 368.034326 -275.921195) (xy 368.026383 -275.973899) (xy 368.010673 -276.024829) (xy 367.987547 -276.07285)
			(xy 367.957523 -276.116887) (xy 367.921271 -276.155958) (xy 367.8796 -276.189189) (xy 367.833442 -276.215838)
			(xy 367.783828 -276.23531) (xy 367.731866 -276.24717) (xy 367.678716 -276.251154) (xy 367.625566 -276.24717)
			(xy 367.573604 -276.23531) (xy 367.52399 -276.215838) (xy 367.477832 -276.189189) (xy 367.436161 -276.155958)
			(xy 367.399909 -276.116887) (xy 367.369885 -276.07285) (xy 367.346759 -276.024829) (xy 367.331049 -275.973899)
			(xy 367.323106 -275.921195) (xy 367.094531 -275.921195) (xy 367.094526 -275.921449) (xy 367.086583 -275.974153)
			(xy 367.070873 -276.025083) (xy 367.047747 -276.073104) (xy 367.017723 -276.117141) (xy 366.981471 -276.156212)
			(xy 366.9398 -276.189443) (xy 366.893642 -276.216092) (xy 366.844028 -276.235564) (xy 366.792066 -276.247424)
			(xy 366.738916 -276.251408) (xy 366.685766 -276.247424) (xy 366.633804 -276.235564) (xy 366.58419 -276.216092)
			(xy 366.538032 -276.189443) (xy 366.496361 -276.156212) (xy 366.460109 -276.117141) (xy 366.430085 -276.073104)
			(xy 366.406959 -276.025083) (xy 366.391249 -275.974153) (xy 366.383306 -275.921449) (xy 366.153405 -275.921449)
			(xy 366.151292 -275.949062) (xy 366.138929 -276.002059) (xy 366.118644 -276.052558) (xy 366.090911 -276.099382)
			(xy 366.056375 -276.141439) (xy 366.01584 -276.177751) (xy 365.970252 -276.20747) (xy 365.945674 -276.219158)
			(xy 365.945674 -276.307804) (xy 365.946223 -276.322908) (xy 365.955055 -276.351796) (xy 365.971946 -276.37684)
			(xy 365.99542 -276.395853) (xy 366.023427 -276.407173) (xy 366.053519 -276.409811) (xy 366.083068 -276.403536)
			(xy 366.09655 -276.396704) (xy 366.123083 -276.382735) (xy 366.179672 -276.362916) (xy 366.238782 -276.352861)
			(xy 366.268762 -276.352254) (xy 366.296489 -276.352788) (xy 366.351273 -276.361393) (xy 366.40406 -276.378385)
			(xy 366.453576 -276.403354) (xy 366.498623 -276.435696) (xy 366.538113 -276.474629) (xy 366.571091 -276.519213)
			(xy 366.596761 -276.568369) (xy 366.6145 -276.62091) (xy 366.623882 -276.675566) (xy 366.62487 -276.703282)
			(xy 366.625457 -276.71649) (xy 366.632564 -276.741946) (xy 366.645969 -276.764725) (xy 366.664772 -276.783298)
			(xy 366.687714 -276.796421) (xy 366.713255 -276.803214) (xy 366.72647 -276.803612) (xy 366.750854 -276.803612)
			(xy 366.764063 -276.803185) (xy 366.789593 -276.79639) (xy 366.812523 -276.783268) (xy 366.831317 -276.7647)
			(xy 366.844714 -276.741931) (xy 366.851817 -276.716484) (xy 366.852454 -276.703282) (xy 366.853328 -276.676893)
			(xy 366.861904 -276.624797) (xy 366.878077 -276.574538) (xy 366.901492 -276.527217) (xy 366.931637 -276.483872)
			(xy 366.967851 -276.445451) (xy 367.00934 -276.412799) (xy 367.055195 -276.386629) (xy 367.104411 -276.367515)
			(xy 367.15591 -276.355877) (xy 367.208562 -276.351969) (xy 367.261214 -276.355877) (xy 367.312713 -276.367515)
			(xy 367.361929 -276.386629) (xy 367.407784 -276.412799) (xy 367.449273 -276.445451) (xy 367.485487 -276.483872)
			(xy 367.515632 -276.527217) (xy 367.539047 -276.574538) (xy 367.55522 -276.624797) (xy 367.563796 -276.676893)
			(xy 367.56467 -276.703282) (xy 367.565257 -276.71649) (xy 367.572364 -276.741946) (xy 367.585769 -276.764725)
			(xy 367.604572 -276.783298) (xy 367.627514 -276.796421) (xy 367.653055 -276.803214) (xy 367.66627 -276.803612)
			(xy 367.690654 -276.803612) (xy 367.703863 -276.803185) (xy 367.729393 -276.79639) (xy 367.752323 -276.783268)
			(xy 367.771117 -276.7647) (xy 367.784514 -276.741931) (xy 367.791617 -276.716484) (xy 367.792254 -276.703282)
			(xy 367.79311 -276.676881) (xy 367.801656 -276.624756) (xy 367.817807 -276.574465) (xy 367.841209 -276.527111)
			(xy 367.871348 -276.483733) (xy 367.907564 -276.445282) (xy 367.949062 -276.412602) (xy 367.994931 -276.386409)
			(xy 368.044166 -276.367279) (xy 368.095686 -276.35563) (xy 368.148362 -276.351718) (xy 368.201038 -276.35563)
			(xy 368.252558 -276.367279) (xy 368.301793 -276.386409) (xy 368.347662 -276.412602) (xy 368.38916 -276.445282)
			(xy 368.425376 -276.483733) (xy 368.455515 -276.527111) (xy 368.478917 -276.574465) (xy 368.495068 -276.624756)
			(xy 368.503614 -276.676881) (xy 368.50447 -276.703282) (xy 368.505057 -276.71649) (xy 368.512164 -276.741946)
			(xy 368.525569 -276.764725) (xy 368.544372 -276.783298) (xy 368.567314 -276.796421) (xy 368.592855 -276.803214)
			(xy 368.60607 -276.803612) (xy 368.630708 -276.803612) (xy 368.643921 -276.80319) (xy 368.669461 -276.796403)
			(xy 368.692402 -276.783285) (xy 368.711205 -276.764716) (xy 368.724609 -276.741942) (xy 368.731717 -276.716489)
			(xy 368.732308 -276.703282) (xy 368.733182 -276.676893) (xy 368.741758 -276.624797) (xy 368.757931 -276.574538)
			(xy 368.781346 -276.527217) (xy 368.811491 -276.483872) (xy 368.847705 -276.445451) (xy 368.889194 -276.412799)
			(xy 368.935049 -276.386629) (xy 368.984265 -276.367515) (xy 369.035764 -276.355877) (xy 369.088416 -276.351969)
			(xy 369.141068 -276.355877) (xy 369.192567 -276.367515) (xy 369.241783 -276.386629) (xy 369.287638 -276.412799)
			(xy 369.329127 -276.445451) (xy 369.365341 -276.483872) (xy 369.395486 -276.527217) (xy 369.418901 -276.574538)
			(xy 369.435074 -276.624797) (xy 369.44365 -276.676893) (xy 369.444524 -276.703282) (xy 369.445111 -276.716488)
			(xy 369.45222 -276.741938) (xy 369.465626 -276.76471) (xy 369.48443 -276.783274) (xy 369.507372 -276.796386)
			(xy 369.532912 -276.803167) (xy 369.546124 -276.803612) (xy 369.570508 -276.803612) (xy 369.583721 -276.80319)
			(xy 369.609261 -276.796403) (xy 369.632202 -276.783285) (xy 369.651005 -276.764716) (xy 369.664409 -276.741942)
			(xy 369.671517 -276.716489) (xy 369.672108 -276.703282) (xy 369.672982 -276.676893) (xy 369.681558 -276.624797)
			(xy 369.697731 -276.574538) (xy 369.721146 -276.527217) (xy 369.751291 -276.483872) (xy 369.787505 -276.445451)
			(xy 369.828994 -276.412799) (xy 369.874849 -276.386629) (xy 369.924065 -276.367515) (xy 369.975564 -276.355877)
			(xy 370.028216 -276.351969) (xy 370.080868 -276.355877) (xy 370.132367 -276.367515) (xy 370.181583 -276.386629)
			(xy 370.227438 -276.412799) (xy 370.268927 -276.445451) (xy 370.305141 -276.483872) (xy 370.335286 -276.527217)
			(xy 370.358701 -276.574538) (xy 370.374874 -276.624797) (xy 370.38345 -276.676893) (xy 370.384324 -276.703282)
			(xy 370.384911 -276.716488) (xy 370.39202 -276.741938) (xy 370.405426 -276.76471) (xy 370.42423 -276.783274)
			(xy 370.447172 -276.796386) (xy 370.472712 -276.803167) (xy 370.485924 -276.803612) (xy 370.510308 -276.803612)
			(xy 370.523521 -276.80319) (xy 370.549061 -276.796403) (xy 370.572002 -276.783285) (xy 370.590805 -276.764716)
			(xy 370.604209 -276.741942) (xy 370.611317 -276.716489) (xy 370.611908 -276.703282) (xy 370.612782 -276.676893)
			(xy 370.621358 -276.624797) (xy 370.637531 -276.574538) (xy 370.660946 -276.527217) (xy 370.691091 -276.483872)
			(xy 370.727305 -276.445451) (xy 370.768794 -276.412799) (xy 370.814649 -276.386629) (xy 370.863865 -276.367515)
			(xy 370.915364 -276.355877) (xy 370.968016 -276.351969) (xy 371.020668 -276.355877) (xy 371.072167 -276.367515)
			(xy 371.121383 -276.386629) (xy 371.167238 -276.412799) (xy 371.208727 -276.445451) (xy 371.244941 -276.483872)
			(xy 371.275086 -276.527217) (xy 371.298501 -276.574538) (xy 371.314674 -276.624797) (xy 371.32325 -276.676893)
			(xy 371.324124 -276.703282) (xy 371.324711 -276.716488) (xy 371.33182 -276.741938) (xy 371.345226 -276.76471)
			(xy 371.36403 -276.783274) (xy 371.386972 -276.796386) (xy 371.412512 -276.803167) (xy 371.425724 -276.803612)
			(xy 371.479318 -276.803612) (xy 371.492509 -276.803192) (xy 371.518009 -276.796424) (xy 371.540922 -276.783345)
			(xy 371.559716 -276.76483) (xy 371.573135 -276.742115) (xy 371.580283 -276.716719) (xy 371.580918 -276.703536)
			(xy 371.581779 -276.678096) (xy 371.590408 -276.627934) (xy 371.606708 -276.579715) (xy 371.630283 -276.534605)
			(xy 371.660564 -276.493693) (xy 371.69682 -276.457968) (xy 371.738174 -276.428294) (xy 371.783628 -276.405387)
			(xy 371.832082 -276.389802) (xy 371.882366 -276.381913) (xy 371.933266 -276.381913) (xy 371.98355 -276.389802)
			(xy 372.032004 -276.405387) (xy 372.077458 -276.428294) (xy 372.118812 -276.457968) (xy 372.155068 -276.493693)
			(xy 372.185349 -276.534605) (xy 372.208924 -276.579715) (xy 372.225224 -276.627934) (xy 372.233853 -276.678096)
			(xy 372.234714 -276.703536) (xy 372.235331 -276.71672) (xy 372.242481 -276.742117) (xy 372.255904 -276.764832)
			(xy 372.274702 -276.783345) (xy 372.297619 -276.79642) (xy 372.323122 -276.803182) (xy 372.336314 -276.803612)
			(xy 372.419118 -276.803612) (xy 372.432309 -276.803192) (xy 372.457809 -276.796424) (xy 372.480722 -276.783345)
			(xy 372.499516 -276.76483) (xy 372.512935 -276.742115) (xy 372.520083 -276.716719) (xy 372.520718 -276.703536)
			(xy 372.521579 -276.678096) (xy 372.530208 -276.627934) (xy 372.546508 -276.579715) (xy 372.570083 -276.534605)
			(xy 372.600364 -276.493693) (xy 372.63662 -276.457968) (xy 372.677974 -276.428294) (xy 372.723428 -276.405387)
			(xy 372.771882 -276.389802) (xy 372.822166 -276.381913) (xy 372.873066 -276.381913) (xy 372.92335 -276.389802)
			(xy 372.971804 -276.405387) (xy 373.017258 -276.428294) (xy 373.058612 -276.457968) (xy 373.094868 -276.493693)
			(xy 373.125149 -276.534605) (xy 373.148724 -276.579715) (xy 373.165024 -276.627934) (xy 373.173653 -276.678096)
			(xy 373.174514 -276.703536) (xy 373.175131 -276.71672) (xy 373.182281 -276.742117) (xy 373.195704 -276.764832)
			(xy 373.214502 -276.783345) (xy 373.237419 -276.79642) (xy 373.262922 -276.803182) (xy 373.276114 -276.803612)
			(xy 373.329454 -276.803612) (xy 373.342663 -276.803185) (xy 373.368193 -276.79639) (xy 373.391123 -276.783268)
			(xy 373.409917 -276.7647) (xy 373.423314 -276.741931) (xy 373.430417 -276.716484) (xy 373.431054 -276.703282)
			(xy 373.431928 -276.676893) (xy 373.440504 -276.624797) (xy 373.456677 -276.574538) (xy 373.480092 -276.527217)
			(xy 373.510237 -276.483872) (xy 373.546451 -276.445451) (xy 373.58794 -276.412799) (xy 373.633795 -276.386629)
			(xy 373.683011 -276.367515) (xy 373.73451 -276.355877) (xy 373.787162 -276.351969) (xy 373.839814 -276.355877)
			(xy 373.891313 -276.367515) (xy 373.940529 -276.386629) (xy 373.986384 -276.412799) (xy 374.027873 -276.445451)
			(xy 374.064087 -276.483872) (xy 374.094232 -276.527217) (xy 374.117647 -276.574538) (xy 374.13382 -276.624797)
			(xy 374.142396 -276.676893) (xy 374.14327 -276.703282) (xy 374.143857 -276.71649) (xy 374.150964 -276.741946)
			(xy 374.164369 -276.764725) (xy 374.183172 -276.783298) (xy 374.206114 -276.796421) (xy 374.231655 -276.803214)
			(xy 374.24487 -276.803612) (xy 374.298718 -276.803612) (xy 374.311909 -276.803192) (xy 374.337409 -276.796424)
			(xy 374.360322 -276.783345) (xy 374.379116 -276.76483) (xy 374.392535 -276.742115) (xy 374.399683 -276.716719)
			(xy 374.400318 -276.703536) (xy 374.401179 -276.678096) (xy 374.409808 -276.627934) (xy 374.426108 -276.579715)
			(xy 374.449683 -276.534605) (xy 374.479964 -276.493693) (xy 374.51622 -276.457968) (xy 374.557574 -276.428294)
			(xy 374.603028 -276.405387) (xy 374.651482 -276.389802) (xy 374.701766 -276.381913) (xy 374.752666 -276.381913)
			(xy 374.80295 -276.389802) (xy 374.851404 -276.405387) (xy 374.896858 -276.428294) (xy 374.938212 -276.457968)
			(xy 374.974468 -276.493693) (xy 375.004749 -276.534605) (xy 375.028324 -276.579715) (xy 375.044624 -276.627934)
			(xy 375.053253 -276.678096) (xy 375.054114 -276.703536) (xy 375.054731 -276.71672) (xy 375.061881 -276.742117)
			(xy 375.075304 -276.764832) (xy 375.094102 -276.783345) (xy 375.117019 -276.79642) (xy 375.142522 -276.803182)
			(xy 375.155714 -276.803612) (xy 375.209308 -276.803612) (xy 375.222521 -276.80319) (xy 375.248061 -276.796403)
			(xy 375.271002 -276.783285) (xy 375.289805 -276.764716) (xy 375.303209 -276.741942) (xy 375.310317 -276.716489)
			(xy 375.310908 -276.703282) (xy 375.311782 -276.676893) (xy 375.320358 -276.624797) (xy 375.336531 -276.574538)
			(xy 375.359946 -276.527217) (xy 375.390091 -276.483872) (xy 375.426305 -276.445451) (xy 375.467794 -276.412799)
			(xy 375.513649 -276.386629) (xy 375.562865 -276.367515) (xy 375.614364 -276.355877) (xy 375.667016 -276.351969)
			(xy 375.719668 -276.355877) (xy 375.771167 -276.367515) (xy 375.820383 -276.386629) (xy 375.866238 -276.412799)
			(xy 375.907727 -276.445451) (xy 375.943941 -276.483872) (xy 375.974086 -276.527217) (xy 375.997501 -276.574538)
			(xy 376.013674 -276.624797) (xy 376.02225 -276.676893) (xy 376.023124 -276.703282) (xy 376.023711 -276.716488)
			(xy 376.03082 -276.741938) (xy 376.044226 -276.76471) (xy 376.06303 -276.783274) (xy 376.085972 -276.796386)
			(xy 376.111512 -276.803167) (xy 376.124724 -276.803612) (xy 376.178318 -276.803612) (xy 376.191509 -276.803192)
			(xy 376.217009 -276.796424) (xy 376.239922 -276.783345) (xy 376.258716 -276.76483) (xy 376.272135 -276.742115)
			(xy 376.279283 -276.716719) (xy 376.279918 -276.703536) (xy 376.280779 -276.678096) (xy 376.289408 -276.627934)
			(xy 376.305708 -276.579715) (xy 376.329283 -276.534605) (xy 376.359564 -276.493693) (xy 376.39582 -276.457968)
			(xy 376.437174 -276.428294) (xy 376.482628 -276.405387) (xy 376.531082 -276.389802) (xy 376.581366 -276.381913)
			(xy 376.632266 -276.381913) (xy 376.68255 -276.389802) (xy 376.731004 -276.405387) (xy 376.776458 -276.428294)
			(xy 376.817812 -276.457968) (xy 376.854068 -276.493693) (xy 376.884349 -276.534605) (xy 376.907924 -276.579715)
			(xy 376.924224 -276.627934) (xy 376.932853 -276.678096) (xy 376.933714 -276.703536) (xy 376.934331 -276.71672)
			(xy 376.941481 -276.742117) (xy 376.954904 -276.764832) (xy 376.973702 -276.783345) (xy 376.996619 -276.79642)
			(xy 377.022122 -276.803182) (xy 377.035314 -276.803612) (xy 377.088908 -276.803612) (xy 377.102121 -276.80319)
			(xy 377.127661 -276.796403) (xy 377.150602 -276.783285) (xy 377.169405 -276.764716) (xy 377.182809 -276.741942)
			(xy 377.189917 -276.716489) (xy 377.190508 -276.703282) (xy 377.191382 -276.676893) (xy 377.199958 -276.624797)
			(xy 377.216131 -276.574538) (xy 377.239546 -276.527217) (xy 377.269691 -276.483872) (xy 377.305905 -276.445451)
			(xy 377.347394 -276.412799) (xy 377.393249 -276.386629) (xy 377.442465 -276.367515) (xy 377.493964 -276.355877)
			(xy 377.546616 -276.351969) (xy 377.599268 -276.355877) (xy 377.650767 -276.367515) (xy 377.699983 -276.386629)
			(xy 377.745838 -276.412799) (xy 377.787327 -276.445451) (xy 377.823541 -276.483872) (xy 377.853686 -276.527217)
			(xy 377.877101 -276.574538) (xy 377.893274 -276.624797) (xy 377.90185 -276.676893) (xy 377.902724 -276.703282)
			(xy 377.903311 -276.716488) (xy 377.91042 -276.741938) (xy 377.923826 -276.76471) (xy 377.94263 -276.783274)
			(xy 377.965572 -276.796386) (xy 377.991112 -276.803167) (xy 378.004324 -276.803612) (xy 378.057918 -276.803612)
			(xy 378.071109 -276.803192) (xy 378.096609 -276.796424) (xy 378.119522 -276.783345) (xy 378.138316 -276.76483)
			(xy 378.151735 -276.742115) (xy 378.158883 -276.716719) (xy 378.159518 -276.703536) (xy 378.160379 -276.678096)
			(xy 378.169008 -276.627934) (xy 378.185308 -276.579715) (xy 378.208883 -276.534605) (xy 378.239164 -276.493693)
			(xy 378.27542 -276.457968) (xy 378.316774 -276.428294) (xy 378.362228 -276.405387) (xy 378.410682 -276.389802)
			(xy 378.460966 -276.381913) (xy 378.511866 -276.381913) (xy 378.56215 -276.389802) (xy 378.610604 -276.405387)
			(xy 378.656058 -276.428294) (xy 378.697412 -276.457968) (xy 378.733668 -276.493693) (xy 378.763949 -276.534605)
			(xy 378.787524 -276.579715) (xy 378.803824 -276.627934) (xy 378.812453 -276.678096) (xy 378.813314 -276.703536)
			(xy 378.813931 -276.71672) (xy 378.821081 -276.742117) (xy 378.834504 -276.764832) (xy 378.853302 -276.783345)
			(xy 378.876219 -276.79642) (xy 378.901722 -276.803182) (xy 378.914914 -276.803612) (xy 378.997718 -276.803612)
			(xy 379.010909 -276.803192) (xy 379.036409 -276.796424) (xy 379.059322 -276.783345) (xy 379.078116 -276.76483)
			(xy 379.091535 -276.742115) (xy 379.098683 -276.716719) (xy 379.099318 -276.703536) (xy 379.100179 -276.678096)
			(xy 379.108808 -276.627934) (xy 379.125108 -276.579715) (xy 379.148683 -276.534605) (xy 379.178964 -276.493693)
			(xy 379.21522 -276.457968) (xy 379.256574 -276.428294) (xy 379.302028 -276.405387) (xy 379.350482 -276.389802)
			(xy 379.400766 -276.381913) (xy 379.451666 -276.381913) (xy 379.50195 -276.389802) (xy 379.550404 -276.405387)
			(xy 379.595858 -276.428294) (xy 379.637212 -276.457968) (xy 379.673468 -276.493693) (xy 379.703749 -276.534605)
			(xy 379.727324 -276.579715) (xy 379.743624 -276.627934) (xy 379.752253 -276.678096) (xy 379.753114 -276.703536)
			(xy 379.753731 -276.71672) (xy 379.760881 -276.742117) (xy 379.774304 -276.764832) (xy 379.793102 -276.783345)
			(xy 379.816019 -276.79642) (xy 379.841522 -276.803182) (xy 379.854714 -276.803612) (xy 379.908054 -276.803612)
			(xy 379.921263 -276.803185) (xy 379.946793 -276.79639) (xy 379.969723 -276.783268) (xy 379.988517 -276.7647)
			(xy 380.001914 -276.741931) (xy 380.009017 -276.716484) (xy 380.009654 -276.703282) (xy 380.010528 -276.676893)
			(xy 380.019104 -276.624797) (xy 380.035277 -276.574538) (xy 380.058692 -276.527217) (xy 380.088837 -276.483872)
			(xy 380.125051 -276.445451) (xy 380.16654 -276.412799) (xy 380.212395 -276.386629) (xy 380.261611 -276.367515)
			(xy 380.31311 -276.355877) (xy 380.365762 -276.351969) (xy 380.418414 -276.355877) (xy 380.469913 -276.367515)
			(xy 380.519129 -276.386629) (xy 380.564984 -276.412799) (xy 380.606473 -276.445451) (xy 380.642687 -276.483872)
			(xy 380.672832 -276.527217) (xy 380.696247 -276.574538) (xy 380.71242 -276.624797) (xy 380.720996 -276.676893)
			(xy 380.72187 -276.703282) (xy 380.722457 -276.71649) (xy 380.729564 -276.741946) (xy 380.742969 -276.764725)
			(xy 380.761772 -276.783298) (xy 380.784714 -276.796421) (xy 380.810255 -276.803214) (xy 380.82347 -276.803612)
			(xy 380.877318 -276.803612) (xy 380.890509 -276.803192) (xy 380.916009 -276.796424) (xy 380.938922 -276.783345)
			(xy 380.957716 -276.76483) (xy 380.971135 -276.742115) (xy 380.978283 -276.716719) (xy 380.978918 -276.703536)
			(xy 380.979779 -276.678096) (xy 380.988408 -276.627934) (xy 381.004708 -276.579715) (xy 381.028283 -276.534605)
			(xy 381.058564 -276.493693) (xy 381.09482 -276.457968) (xy 381.136174 -276.428294) (xy 381.181628 -276.405387)
			(xy 381.230082 -276.389802) (xy 381.280366 -276.381913) (xy 381.331266 -276.381913) (xy 381.38155 -276.389802)
			(xy 381.430004 -276.405387) (xy 381.475458 -276.428294) (xy 381.516812 -276.457968) (xy 381.553068 -276.493693)
			(xy 381.583349 -276.534605) (xy 381.606924 -276.579715) (xy 381.623224 -276.627934) (xy 381.631853 -276.678096)
			(xy 381.632714 -276.703536) (xy 381.633331 -276.71672) (xy 381.640481 -276.742117) (xy 381.653904 -276.764832)
			(xy 381.672702 -276.783345) (xy 381.695619 -276.79642) (xy 381.721122 -276.803182) (xy 381.734314 -276.803612)
			(xy 381.787908 -276.803612) (xy 381.801121 -276.80319) (xy 381.826661 -276.796403) (xy 381.849602 -276.783285)
			(xy 381.868405 -276.764716) (xy 381.881809 -276.741942) (xy 381.888917 -276.716489) (xy 381.889508 -276.703282)
			(xy 381.890382 -276.676893) (xy 381.898958 -276.624797) (xy 381.915131 -276.574538) (xy 381.938546 -276.527217)
			(xy 381.968691 -276.483872) (xy 382.004905 -276.445451) (xy 382.046394 -276.412799) (xy 382.092249 -276.386629)
			(xy 382.141465 -276.367515) (xy 382.192964 -276.355877) (xy 382.245616 -276.351969) (xy 382.298268 -276.355877)
			(xy 382.349767 -276.367515) (xy 382.398983 -276.386629) (xy 382.444838 -276.412799) (xy 382.486327 -276.445451)
			(xy 382.522541 -276.483872) (xy 382.552686 -276.527217) (xy 382.576101 -276.574538) (xy 382.592274 -276.624797)
			(xy 382.60085 -276.676893) (xy 382.601724 -276.703282) (xy 382.602311 -276.716488) (xy 382.60942 -276.741938)
			(xy 382.622826 -276.76471) (xy 382.64163 -276.783274) (xy 382.664572 -276.796386) (xy 382.690112 -276.803167)
			(xy 382.703324 -276.803612) (xy 382.756918 -276.803612) (xy 382.770109 -276.803192) (xy 382.795609 -276.796424)
			(xy 382.818522 -276.783345) (xy 382.837316 -276.76483) (xy 382.850735 -276.742115) (xy 382.857883 -276.716719)
			(xy 382.858518 -276.703536) (xy 382.859379 -276.678096) (xy 382.868008 -276.627934) (xy 382.884308 -276.579715)
			(xy 382.907883 -276.534605) (xy 382.938164 -276.493693) (xy 382.97442 -276.457968) (xy 383.015774 -276.428294)
			(xy 383.061228 -276.405387) (xy 383.109682 -276.389802) (xy 383.159966 -276.381913) (xy 383.210866 -276.381913)
			(xy 383.26115 -276.389802) (xy 383.309604 -276.405387) (xy 383.355058 -276.428294) (xy 383.396412 -276.457968)
			(xy 383.432668 -276.493693) (xy 383.462949 -276.534605) (xy 383.486524 -276.579715) (xy 383.502824 -276.627934)
			(xy 383.511453 -276.678096) (xy 383.512314 -276.703536) (xy 383.512931 -276.71672) (xy 383.520081 -276.742117)
			(xy 383.533504 -276.764832) (xy 383.552302 -276.783345) (xy 383.575219 -276.79642) (xy 383.600722 -276.803182)
			(xy 383.613914 -276.803612) (xy 383.667254 -276.803612) (xy 383.680463 -276.803185) (xy 383.705993 -276.79639)
			(xy 383.728923 -276.783268) (xy 383.747717 -276.7647) (xy 383.761114 -276.741931) (xy 383.768217 -276.716484)
			(xy 383.768854 -276.703282) (xy 383.769728 -276.676893) (xy 383.778304 -276.624797) (xy 383.794477 -276.574538)
			(xy 383.817892 -276.527217) (xy 383.848037 -276.483872) (xy 383.884251 -276.445451) (xy 383.92574 -276.412799)
			(xy 383.971595 -276.386629) (xy 384.020811 -276.367515) (xy 384.07231 -276.355877) (xy 384.124962 -276.351969)
			(xy 384.177614 -276.355877) (xy 384.229113 -276.367515) (xy 384.278329 -276.386629) (xy 384.324184 -276.412799)
			(xy 384.365673 -276.445451) (xy 384.401887 -276.483872) (xy 384.432032 -276.527217) (xy 384.455447 -276.574538)
			(xy 384.47162 -276.624797) (xy 384.480196 -276.676893) (xy 384.48107 -276.703282) (xy 384.481657 -276.71649)
			(xy 384.488764 -276.741946) (xy 384.502169 -276.764725) (xy 384.520972 -276.783298) (xy 384.543914 -276.796421)
			(xy 384.569455 -276.803214) (xy 384.58267 -276.803612) (xy 385.473194 -276.803612) (xy 386.017262 -277.347426)
			(xy 386.028353 -277.357745) (xy 386.055094 -277.371943) (xy 386.084826 -277.377661) (xy 386.114925 -277.374395)
			(xy 386.142739 -277.362432) (xy 386.165812 -277.342829) (xy 386.174488 -277.330408) (xy 386.18861 -277.309193)
			(xy 386.221953 -277.270649) (xy 386.260445 -277.237246) (xy 386.3033 -277.209664) (xy 386.349646 -277.188464)
			(xy 386.398538 -277.17408) (xy 386.44898 -277.166804) (xy 386.474462 -277.166324) (xy 386.502448 -277.166842)
			(xy 386.557733 -277.175593) (xy 386.610967 -277.192886) (xy 386.66084 -277.218295) (xy 386.706124 -277.251193)
			(xy 386.745703 -277.290771) (xy 386.778602 -277.336055) (xy 386.804012 -277.385927) (xy 386.821306 -277.439161)
			(xy 386.830058 -277.494446) (xy 386.83057 -277.522432) (xy 386.83014 -277.547919) (xy 386.822882 -277.598373)
			(xy 386.808507 -277.647278) (xy 386.787306 -277.693634) (xy 386.759713 -277.736493) (xy 386.726292 -277.774982)
			(xy 386.687726 -277.808313) (xy 386.666486 -277.822406) (xy 386.654072 -277.831063) (xy 386.634552 -277.854172)
			(xy 386.622645 -277.88198) (xy 386.619391 -277.912054) (xy 386.625074 -277.941764) (xy 386.639199 -277.968514)
			(xy 386.649468 -277.979632) (xy 386.725414 -278.055578) (xy 386.749037 -278.037915) (xy 386.800907 -278.009838)
			(xy 386.856693 -277.990687) (xy 386.914871 -277.980984) (xy 386.944362 -277.980394) (xy 386.972349 -277.980912)
			(xy 387.027635 -277.989663) (xy 387.080872 -278.006955) (xy 387.130747 -278.032363) (xy 387.176033 -278.065262)
			(xy 387.215615 -278.104839) (xy 387.248518 -278.150122) (xy 387.273931 -278.199995) (xy 387.291229 -278.25323)
			(xy 387.299985 -278.308515) (xy 387.30047 -278.336502) (xy 387.300039 -278.361043) (xy 387.293262 -278.409655)
			(xy 387.279878 -278.456877) (xy 387.26014 -278.501816) (xy 387.247638 -278.522938) (xy 387.22681 -278.557228)
			(xy 391.057892 -282.388056) (xy 391.057892 -282.63596) (xy 391.567924 -283.145992) (xy 391.567924 -359.051352)
			(xy 383.752344 -366.866932) (xy 368.631724 -366.866932) (xy 368.370104 -367.128552) (xy 368.370104 -380.351792)
			(xy 369.66398 -381.645668) (xy 404.3172 -381.645668)
		)
		(stroke
			(width 0)
			(type solid)
		)
		(fill yes)
		(layer "B.Cu")
		(net "PVPP_HBM_CPU0")
	)
	(gr_poly
		(pts
			(xy 162.18916 -379.346968) (xy 162.18916 -355.067108) (xy 161.163 -354.040948) (xy 161.163 -353.462844)
			(xy 161.161476 -353.456494) (xy 161.154881 -353.429734) (xy 161.147748 -353.375084) (xy 161.147252 -353.347528)
			(xy 161.147252 -336.496914) (xy 160.497774 -335.847436) (xy 157.17012 -335.847436) (xy 157.141822 -335.846956)
			(xy 157.085715 -335.839534) (xy 157.031056 -335.824855) (xy 156.978779 -335.803169) (xy 156.92978 -335.774847)
			(xy 156.884895 -335.740373) (xy 156.864558 -335.72069) (xy 154.842718 -333.69885) (xy 154.823025 -333.678521)
			(xy 154.788549 -333.633636) (xy 154.760225 -333.584635) (xy 154.738537 -333.532357) (xy 154.723856 -333.477696)
			(xy 154.716433 -333.421587) (xy 154.715972 -333.393288) (xy 154.715972 -273.662394) (xy 154.279854 -273.226276)
			(xy 152.72004 -273.226276) (xy 152.691059 -273.225788) (xy 152.63362 -273.218009) (xy 152.577732 -273.202638)
			(xy 152.550876 -273.191732) (xy 152.541478 -273.187668) (xy 152.43556 -273.187668) (xy 151.302974 -272.055336)
			(xy 139.58316 -272.055336) (xy 139.555585 -272.054882) (xy 139.500885 -272.047837) (xy 139.447523 -272.033903)
			(xy 139.396362 -272.013306) (xy 139.372086 -272.000218) (xy 139.363476 -271.995836) (xy 139.344348 -271.99325)
			(xy 139.325627 -271.997955) (xy 139.309993 -272.009276) (xy 139.304522 -272.017236) (xy 139.290402 -272.038454)
			(xy 139.257062 -272.077005) (xy 139.218572 -272.110414) (xy 139.175717 -272.138002) (xy 139.12937 -272.159206)
			(xy 139.080476 -272.173594) (xy 139.030031 -272.180873) (xy 139.004548 -272.18132) (xy 138.976155 -272.180763)
			(xy 138.920089 -272.17174) (xy 138.866166 -272.153932) (xy 138.815755 -272.12779) (xy 138.770132 -272.093977)
			(xy 138.730455 -272.053351) (xy 138.69773 -272.006941) (xy 138.684762 -271.981676) (xy 138.670792 -271.953228)
			(xy 137.728452 -271.953228) (xy 137.649458 -271.874234) (xy 137.62736 -271.874996) (xy 137.589112 -271.876023)
			(xy 137.512692 -271.872154) (xy 137.436912 -271.861546) (xy 137.362366 -271.844284) (xy 137.289637 -271.820501)
			(xy 137.219295 -271.790385) (xy 137.1854 -271.772634) (xy 137.175748 -271.7673) (xy 137.17143 -271.76476)
			(xy 137.170414 -271.764252) (xy 137.162032 -271.75968) (xy 137.123706 -271.736874) (xy 137.051504 -271.684512)
			(xy 136.98508 -271.624991) (xy 136.92514 -271.558945) (xy 136.872322 -271.487076) (xy 136.827187 -271.410149)
			(xy 136.80821 -271.36979) (xy 136.804133 -271.361725) (xy 136.791414 -271.348904) (xy 136.775049 -271.341266)
			(xy 136.757054 -271.33975) (xy 136.748266 -271.34185) (xy 136.725375 -271.347909) (xy 136.67847 -271.354411)
			(xy 136.654794 -271.354804) (xy 136.629562 -271.354364) (xy 136.579641 -271.346989) (xy 136.531338 -271.332382)
			(xy 136.485695 -271.31086) (xy 136.443695 -271.282887) (xy 136.406245 -271.249064) (xy 136.37415 -271.210122)
			(xy 136.348104 -271.166901) (xy 136.328668 -271.120331) (xy 136.322054 -271.095978) (xy 136.319486 -271.087308)
			(xy 136.309242 -271.072422) (xy 136.29446 -271.062029) (xy 136.276986 -271.057425) (xy 136.267952 -271.057878)
			(xy 136.218127 -271.061931) (xy 136.11818 -271.059895) (xy 136.068562 -271.053814) (xy 136.065024 -271.079429)
			(xy 136.051504 -271.129339) (xy 136.030908 -271.176768) (xy 136.003669 -271.22072) (xy 135.970359 -271.260271)
			(xy 135.931679 -271.294587) (xy 135.888442 -271.322948) (xy 135.841558 -271.344758) (xy 135.792013 -271.359557)
			(xy 135.740848 -271.367035) (xy 135.714994 -271.367504) (xy 135.68915 -271.367043) (xy 135.638005 -271.359571)
			(xy 135.588477 -271.344786) (xy 135.541606 -271.322998) (xy 135.498376 -271.294664) (xy 135.459695 -271.260379)
			(xy 135.426376 -271.220864) (xy 135.399118 -271.176948) (xy 135.378493 -271.129554) (xy 135.364935 -271.079676)
			(xy 135.361426 -271.054068) (xy 135.325786 -271.058506) (xy 135.254051 -271.062168) (xy 135.18226 -271.05986)
			(xy 135.146542 -271.0561) (xy 135.137447 -271.05548) (xy 135.119784 -271.059945) (xy 135.104793 -271.070296)
			(xy 135.09436 -271.085231) (xy 135.091678 -271.093946) (xy 135.084826 -271.118332) (xy 135.064639 -271.164788)
			(xy 135.037531 -271.207577) (xy 135.004151 -271.245675) (xy 134.965296 -271.278171) (xy 134.921896 -271.304289)
			(xy 134.874989 -271.323403) (xy 134.825695 -271.335058) (xy 134.775194 -271.338974) (xy 134.724693 -271.335058)
			(xy 134.675399 -271.323403) (xy 134.628492 -271.304289) (xy 134.585092 -271.278171) (xy 134.546237 -271.245675)
			(xy 134.512857 -271.207577) (xy 134.485749 -271.164788) (xy 134.465562 -271.118332) (xy 134.45871 -271.093946)
			(xy 134.456067 -271.085226) (xy 134.445619 -271.070316) (xy 134.430603 -271.060019) (xy 134.412929 -271.055646)
			(xy 134.403846 -271.056354) (xy 134.354686 -271.061255) (xy 134.255889 -271.061128) (xy 134.206742 -271.0561)
			(xy 134.197647 -271.05548) (xy 134.179984 -271.059945) (xy 134.164993 -271.070296) (xy 134.15456 -271.085231)
			(xy 134.151878 -271.093946) (xy 134.144554 -271.119849) (xy 134.122623 -271.169004) (xy 134.092945 -271.213909)
			(xy 134.056319 -271.253352) (xy 134.013733 -271.28627) (xy 133.966335 -271.311777) (xy 133.915402 -271.329184)
			(xy 133.862307 -271.338023) (xy 133.835394 -271.338548) (xy 133.808464 -271.337999) (xy 133.755333 -271.329174)
			(xy 133.704366 -271.311762) (xy 133.656941 -271.286236) (xy 133.614338 -271.253283) (xy 133.577711 -271.213796)
			(xy 133.548048 -271.168841) (xy 133.526152 -271.119634) (xy 133.51891 -271.093692) (xy 133.516209 -271.085017)
			(xy 133.505715 -271.070199) (xy 133.490729 -271.059945) (xy 133.473117 -271.05553) (xy 133.464046 -271.0561)
			(xy 133.439493 -271.058725) (xy 133.390187 -271.06152) (xy 133.365494 -271.061688) (xy 133.336319 -271.061449)
			(xy 133.278103 -271.057511) (xy 133.249162 -271.053814) (xy 133.245624 -271.079429) (xy 133.232104 -271.129339)
			(xy 133.211508 -271.176768) (xy 133.184269 -271.22072) (xy 133.150959 -271.260271) (xy 133.112279 -271.294587)
			(xy 133.069042 -271.322948) (xy 133.022158 -271.344758) (xy 132.972613 -271.359557) (xy 132.921448 -271.367035)
			(xy 132.895594 -271.367504) (xy 132.86975 -271.367043) (xy 132.818605 -271.359571) (xy 132.769077 -271.344786)
			(xy 132.722206 -271.322998) (xy 132.678976 -271.294664) (xy 132.640295 -271.260379) (xy 132.606976 -271.220864)
			(xy 132.579718 -271.176948) (xy 132.559093 -271.129554) (xy 132.545535 -271.079676) (xy 132.542026 -271.054068)
			(xy 132.506386 -271.058506) (xy 132.434651 -271.062168) (xy 132.36286 -271.05986) (xy 132.327142 -271.0561)
			(xy 132.318047 -271.05548) (xy 132.300384 -271.059945) (xy 132.285393 -271.070296) (xy 132.27496 -271.085231)
			(xy 132.272278 -271.093946) (xy 132.265426 -271.118332) (xy 132.245239 -271.164788) (xy 132.218131 -271.207577)
			(xy 132.184751 -271.245675) (xy 132.145896 -271.278171) (xy 132.102496 -271.304289) (xy 132.055589 -271.323403)
			(xy 132.006295 -271.335058) (xy 131.955794 -271.338974) (xy 131.905293 -271.335058) (xy 131.855999 -271.323403)
			(xy 131.809092 -271.304289) (xy 131.765692 -271.278171) (xy 131.726837 -271.245675) (xy 131.693457 -271.207577)
			(xy 131.666349 -271.164788) (xy 131.646162 -271.118332) (xy 131.63931 -271.093946) (xy 131.636667 -271.085226)
			(xy 131.626219 -271.070316) (xy 131.611203 -271.060019) (xy 131.593529 -271.055646) (xy 131.584446 -271.056354)
			(xy 131.548718 -271.060033) (xy 131.47692 -271.062171) (xy 131.405192 -271.058344) (xy 131.369562 -271.053814)
			(xy 131.366024 -271.079429) (xy 131.352504 -271.129339) (xy 131.331908 -271.176768) (xy 131.304669 -271.22072)
			(xy 131.271359 -271.260271) (xy 131.232679 -271.294587) (xy 131.189442 -271.322948) (xy 131.142558 -271.344758)
			(xy 131.093013 -271.359557) (xy 131.041848 -271.367035) (xy 131.015994 -271.367504) (xy 130.99015 -271.367043)
			(xy 130.939005 -271.359571) (xy 130.889477 -271.344786) (xy 130.842606 -271.322998) (xy 130.799376 -271.294664)
			(xy 130.760695 -271.260379) (xy 130.727376 -271.220864) (xy 130.700118 -271.176948) (xy 130.679493 -271.129554)
			(xy 130.665935 -271.079676) (xy 130.662426 -271.054068) (xy 130.626786 -271.058506) (xy 130.555051 -271.062168)
			(xy 130.48326 -271.05986) (xy 130.447542 -271.0561) (xy 130.438447 -271.05548) (xy 130.420784 -271.059945)
			(xy 130.405793 -271.070296) (xy 130.39536 -271.085231) (xy 130.392678 -271.093946) (xy 130.385826 -271.118332)
			(xy 130.365639 -271.164788) (xy 130.338531 -271.207577) (xy 130.305151 -271.245675) (xy 130.266296 -271.278171)
			(xy 130.222896 -271.304289) (xy 130.175989 -271.323403) (xy 130.126695 -271.335058) (xy 130.076194 -271.338974)
			(xy 130.025693 -271.335058) (xy 129.976399 -271.323403) (xy 129.929492 -271.304289) (xy 129.886092 -271.278171)
			(xy 129.847237 -271.245675) (xy 129.813857 -271.207577) (xy 129.786749 -271.164788) (xy 129.766562 -271.118332)
			(xy 129.75971 -271.093946) (xy 129.757067 -271.085226) (xy 129.746619 -271.070316) (xy 129.731603 -271.060019)
			(xy 129.713929 -271.055646) (xy 129.704846 -271.056354) (xy 129.669118 -271.060033) (xy 129.59732 -271.062171)
			(xy 129.525592 -271.058344) (xy 129.489962 -271.053814) (xy 129.486424 -271.079429) (xy 129.472904 -271.129339)
			(xy 129.452308 -271.176768) (xy 129.425069 -271.22072) (xy 129.391759 -271.260271) (xy 129.353079 -271.294587)
			(xy 129.309842 -271.322948) (xy 129.262958 -271.344758) (xy 129.213413 -271.359557) (xy 129.162248 -271.367035)
			(xy 129.136394 -271.367504) (xy 129.11055 -271.367043) (xy 129.059405 -271.359571) (xy 129.009877 -271.344786)
			(xy 128.963006 -271.322998) (xy 128.919776 -271.294664) (xy 128.881095 -271.260379) (xy 128.847776 -271.220864)
			(xy 128.820518 -271.176948) (xy 128.799893 -271.129554) (xy 128.786335 -271.079676) (xy 128.782826 -271.054068)
			(xy 128.747186 -271.058506) (xy 128.675451 -271.062168) (xy 128.60366 -271.05986) (xy 128.567942 -271.0561)
			(xy 128.558847 -271.05548) (xy 128.541184 -271.059945) (xy 128.526193 -271.070296) (xy 128.51576 -271.085231)
			(xy 128.513078 -271.093946) (xy 128.506226 -271.118332) (xy 128.486039 -271.164788) (xy 128.458931 -271.207577)
			(xy 128.425551 -271.245675) (xy 128.386696 -271.278171) (xy 128.343296 -271.304289) (xy 128.296389 -271.323403)
			(xy 128.247095 -271.335058) (xy 128.196594 -271.338974) (xy 128.146093 -271.335058) (xy 128.096799 -271.323403)
			(xy 128.049892 -271.304289) (xy 128.006492 -271.278171) (xy 127.967637 -271.245675) (xy 127.934257 -271.207577)
			(xy 127.907149 -271.164788) (xy 127.886962 -271.118332) (xy 127.88011 -271.093946) (xy 127.877467 -271.085226)
			(xy 127.867019 -271.070316) (xy 127.852003 -271.060019) (xy 127.834329 -271.055646) (xy 127.825246 -271.056354)
			(xy 127.776086 -271.061255) (xy 127.677289 -271.061128) (xy 127.628142 -271.0561) (xy 127.619047 -271.05548)
			(xy 127.601384 -271.059945) (xy 127.586393 -271.070296) (xy 127.57596 -271.085231) (xy 127.573278 -271.093946)
			(xy 127.566426 -271.118332) (xy 127.546239 -271.164788) (xy 127.519131 -271.207577) (xy 127.485751 -271.245675)
			(xy 127.446896 -271.278171) (xy 127.403496 -271.304289) (xy 127.356589 -271.323403) (xy 127.307295 -271.335058)
			(xy 127.256794 -271.338974) (xy 127.206293 -271.335058) (xy 127.156999 -271.323403) (xy 127.110092 -271.304289)
			(xy 127.066692 -271.278171) (xy 127.027837 -271.245675) (xy 126.994457 -271.207577) (xy 126.967349 -271.164788)
			(xy 126.947162 -271.118332) (xy 126.94031 -271.093946) (xy 126.937667 -271.085226) (xy 126.927219 -271.070316)
			(xy 126.912203 -271.060019) (xy 126.894529 -271.055646) (xy 126.885446 -271.056354) (xy 126.849718 -271.060033)
			(xy 126.77792 -271.062171) (xy 126.706192 -271.058344) (xy 126.670562 -271.053814) (xy 126.667024 -271.079429)
			(xy 126.653504 -271.129339) (xy 126.632908 -271.176768) (xy 126.605669 -271.22072) (xy 126.572359 -271.260271)
			(xy 126.533679 -271.294587) (xy 126.490442 -271.322948) (xy 126.443558 -271.344758) (xy 126.394013 -271.359557)
			(xy 126.342848 -271.367035) (xy 126.316994 -271.367504) (xy 126.29115 -271.367043) (xy 126.240005 -271.359571)
			(xy 126.190477 -271.344786) (xy 126.143606 -271.322998) (xy 126.100376 -271.294664) (xy 126.061695 -271.260379)
			(xy 126.028376 -271.220864) (xy 126.001118 -271.176948) (xy 125.980493 -271.129554) (xy 125.966935 -271.079676)
			(xy 125.963426 -271.054068) (xy 125.927786 -271.058506) (xy 125.856051 -271.062168) (xy 125.78426 -271.05986)
			(xy 125.748542 -271.0561) (xy 125.739447 -271.05548) (xy 125.721784 -271.059945) (xy 125.706793 -271.070296)
			(xy 125.69636 -271.085231) (xy 125.693678 -271.093946) (xy 125.686826 -271.118332) (xy 125.666639 -271.164788)
			(xy 125.639531 -271.207577) (xy 125.606151 -271.245675) (xy 125.567296 -271.278171) (xy 125.523896 -271.304289)
			(xy 125.476989 -271.323403) (xy 125.427695 -271.335058) (xy 125.377194 -271.338974) (xy 125.326693 -271.335058)
			(xy 125.277399 -271.323403) (xy 125.230492 -271.304289) (xy 125.187092 -271.278171) (xy 125.148237 -271.245675)
			(xy 125.114857 -271.207577) (xy 125.087749 -271.164788) (xy 125.067562 -271.118332) (xy 125.06071 -271.093946)
			(xy 125.058067 -271.085226) (xy 125.047619 -271.070316) (xy 125.032603 -271.060019) (xy 125.014929 -271.055646)
			(xy 125.005846 -271.056354) (xy 124.970118 -271.060033) (xy 124.89832 -271.062171) (xy 124.826592 -271.058344)
			(xy 124.790962 -271.053814) (xy 124.787424 -271.079429) (xy 124.773904 -271.129339) (xy 124.753308 -271.176768)
			(xy 124.726069 -271.22072) (xy 124.692759 -271.260271) (xy 124.654079 -271.294587) (xy 124.610842 -271.322948)
			(xy 124.563958 -271.344758) (xy 124.514413 -271.359557) (xy 124.463248 -271.367035) (xy 124.437394 -271.367504)
			(xy 124.41155 -271.367043) (xy 124.360405 -271.359571) (xy 124.310877 -271.344786) (xy 124.264006 -271.322998)
			(xy 124.220776 -271.294664) (xy 124.182095 -271.260379) (xy 124.148776 -271.220864) (xy 124.121518 -271.176948)
			(xy 124.100893 -271.129554) (xy 124.087335 -271.079676) (xy 124.083826 -271.054068) (xy 124.048186 -271.058506)
			(xy 123.976451 -271.062168) (xy 123.90466 -271.05986) (xy 123.868942 -271.0561) (xy 123.859847 -271.05548)
			(xy 123.842184 -271.059945) (xy 123.827193 -271.070296) (xy 123.81676 -271.085231) (xy 123.814078 -271.093946)
			(xy 123.806754 -271.119849) (xy 123.784823 -271.169004) (xy 123.755145 -271.213909) (xy 123.718519 -271.253352)
			(xy 123.675933 -271.28627) (xy 123.628535 -271.311777) (xy 123.577602 -271.329184) (xy 123.524507 -271.338023)
			(xy 123.497594 -271.338548) (xy 123.470664 -271.337999) (xy 123.417533 -271.329174) (xy 123.366566 -271.311762)
			(xy 123.319141 -271.286236) (xy 123.276538 -271.253283) (xy 123.239911 -271.213796) (xy 123.210248 -271.168841)
			(xy 123.188352 -271.119634) (xy 123.18111 -271.093692) (xy 123.178409 -271.085017) (xy 123.167915 -271.070199)
			(xy 123.152929 -271.059945) (xy 123.135317 -271.05553) (xy 123.126246 -271.0561) (xy 123.090565 -271.059822)
			(xy 123.018855 -271.062045) (xy 122.947208 -271.058302) (xy 122.911616 -271.053814) (xy 122.908078 -271.079431)
			(xy 122.894559 -271.129344) (xy 122.873964 -271.176777) (xy 122.846726 -271.220733) (xy 122.813417 -271.260288)
			(xy 122.774737 -271.29461) (xy 122.731501 -271.322977) (xy 122.684617 -271.344793) (xy 122.63507 -271.3596)
			(xy 122.583904 -271.367085) (xy 122.558048 -271.367504) (xy 122.532206 -271.367039) (xy 122.481066 -271.359562)
			(xy 122.431544 -271.344773) (xy 122.384678 -271.322982) (xy 122.341454 -271.294647) (xy 122.302779 -271.260362)
			(xy 122.269464 -271.220848) (xy 122.24221 -271.176934) (xy 122.221589 -271.129543) (xy 122.208033 -271.079668)
			(xy 122.20448 -271.054068) (xy 122.165827 -271.05885) (xy 122.088012 -271.062272) (xy 122.010205 -271.058672)
			(xy 121.971562 -271.053814) (xy 121.968024 -271.079429) (xy 121.954504 -271.129339) (xy 121.933908 -271.176768)
			(xy 121.906669 -271.22072) (xy 121.873359 -271.260271) (xy 121.834679 -271.294587) (xy 121.791442 -271.322948)
			(xy 121.744558 -271.344758) (xy 121.695013 -271.359557) (xy 121.643848 -271.367035) (xy 121.617994 -271.367504)
			(xy 121.59215 -271.367043) (xy 121.541005 -271.359571) (xy 121.491477 -271.344786) (xy 121.444606 -271.322998)
			(xy 121.401376 -271.294664) (xy 121.362695 -271.260379) (xy 121.329376 -271.220864) (xy 121.302118 -271.176948)
			(xy 121.281493 -271.129554) (xy 121.267935 -271.079676) (xy 121.264426 -271.054068) (xy 121.225814 -271.058835)
			(xy 121.148085 -271.062248) (xy 121.070362 -271.05867) (xy 121.031762 -271.053814) (xy 121.028224 -271.079429)
			(xy 121.014704 -271.129339) (xy 120.994108 -271.176768) (xy 120.966869 -271.22072) (xy 120.933559 -271.260271)
			(xy 120.894879 -271.294587) (xy 120.851642 -271.322948) (xy 120.804758 -271.344758) (xy 120.755213 -271.359557)
			(xy 120.704048 -271.367035) (xy 120.678194 -271.367504) (xy 120.65235 -271.367043) (xy 120.601205 -271.359571)
			(xy 120.551677 -271.344786) (xy 120.504806 -271.322998) (xy 120.461576 -271.294664) (xy 120.422895 -271.260379)
			(xy 120.389576 -271.220864) (xy 120.362318 -271.176948) (xy 120.341693 -271.129554) (xy 120.328135 -271.079676)
			(xy 120.324626 -271.054068) (xy 120.286014 -271.058835) (xy 120.208285 -271.062248) (xy 120.130562 -271.05867)
			(xy 120.091962 -271.053814) (xy 120.088424 -271.079429) (xy 120.074904 -271.129339) (xy 120.054308 -271.176768)
			(xy 120.027069 -271.22072) (xy 119.993759 -271.260271) (xy 119.955079 -271.294587) (xy 119.911842 -271.322948)
			(xy 119.864958 -271.344758) (xy 119.815413 -271.359557) (xy 119.764248 -271.367035) (xy 119.738394 -271.367504)
			(xy 119.710473 -271.366961) (xy 119.655315 -271.358251) (xy 119.60219 -271.341045) (xy 119.552398 -271.315764)
			(xy 119.507159 -271.283027) (xy 119.467578 -271.243635) (xy 119.434626 -271.198552) (xy 119.421402 -271.173956)
			(xy 119.414003 -271.160594) (xy 119.392706 -271.138718) (xy 119.365894 -271.124116) (xy 119.335964 -271.11809)
			(xy 119.30559 -271.121181) (xy 119.291354 -271.126712) (xy 119.09425 -271.210532) (xy 119.085868 -271.221708)
			(xy 119.068977 -271.243887) (xy 119.029455 -271.283201) (xy 118.984285 -271.315869) (xy 118.934572 -271.341092)
			(xy 118.881533 -271.358253) (xy 118.826467 -271.366932) (xy 118.798594 -271.367504) (xy 118.770611 -271.366955)
			(xy 118.715335 -271.358199) (xy 118.662109 -271.340904) (xy 118.612244 -271.315495) (xy 118.566968 -271.282599)
			(xy 118.527395 -271.243025) (xy 118.4945 -271.197747) (xy 118.469092 -271.147882) (xy 118.451799 -271.094655)
			(xy 118.443045 -271.039379) (xy 118.442486 -271.011396) (xy 118.442486 -271.00276) (xy 118.442405 -270.989235)
			(xy 118.435968 -270.962975) (xy 118.422863 -270.939326) (xy 118.404009 -270.919946) (xy 118.38073 -270.906194)
			(xy 118.354658 -270.899035) (xy 118.34114 -270.89862) (xy 118.316248 -270.89862) (xy 118.302731 -270.899074)
			(xy 118.27666 -270.90623) (xy 118.253379 -270.919975) (xy 118.234519 -270.939345) (xy 118.221401 -270.962985)
			(xy 118.214942 -270.989237) (xy 118.214902 -271.00276) (xy 118.214902 -271.011396) (xy 118.214404 -271.038045)
			(xy 118.206461 -271.090749) (xy 118.190751 -271.141679) (xy 118.167625 -271.1897) (xy 118.137601 -271.233737)
			(xy 118.101349 -271.272808) (xy 118.059678 -271.306039) (xy 118.01352 -271.332688) (xy 117.963906 -271.35216)
			(xy 117.911944 -271.36402) (xy 117.858794 -271.368004) (xy 117.805644 -271.36402) (xy 117.753682 -271.35216)
			(xy 117.704068 -271.332688) (xy 117.65791 -271.306039) (xy 117.616239 -271.272808) (xy 117.579987 -271.233737)
			(xy 117.549963 -271.1897) (xy 117.526837 -271.141679) (xy 117.511127 -271.090749) (xy 117.503184 -271.038045)
			(xy 117.502686 -271.011396) (xy 117.502686 -271.00276) (xy 117.502605 -270.989235) (xy 117.496168 -270.962975)
			(xy 117.483063 -270.939326) (xy 117.464209 -270.919946) (xy 117.44093 -270.906194) (xy 117.414858 -270.899035)
			(xy 117.40134 -270.89862) (xy 117.376448 -270.89862) (xy 117.362931 -270.899074) (xy 117.33686 -270.90623)
			(xy 117.313579 -270.919975) (xy 117.294719 -270.939345) (xy 117.281601 -270.962985) (xy 117.275142 -270.989237)
			(xy 117.275102 -271.00276) (xy 117.275102 -271.011396) (xy 117.274604 -271.038045) (xy 117.266661 -271.090749)
			(xy 117.250951 -271.141679) (xy 117.227825 -271.1897) (xy 117.197801 -271.233737) (xy 117.161549 -271.272808)
			(xy 117.119878 -271.306039) (xy 117.07372 -271.332688) (xy 117.024106 -271.35216) (xy 116.972144 -271.36402)
			(xy 116.918994 -271.368004) (xy 116.865844 -271.36402) (xy 116.813882 -271.35216) (xy 116.764268 -271.332688)
			(xy 116.71811 -271.306039) (xy 116.676439 -271.272808) (xy 116.640187 -271.233737) (xy 116.610163 -271.1897)
			(xy 116.587037 -271.141679) (xy 116.571327 -271.090749) (xy 116.563384 -271.038045) (xy 116.562886 -271.011396)
			(xy 116.563328 -270.986131) (xy 116.570471 -270.936108) (xy 116.584613 -270.887598) (xy 116.605471 -270.841573)
			(xy 116.632625 -270.798959) (xy 116.648738 -270.779494) (xy 116.679472 -270.74368) (xy 116.487956 -270.552164)
			(xy 116.465604 -270.553434) (xy 116.449348 -270.553688) (xy 116.421361 -270.553171) (xy 116.366075 -270.544421)
			(xy 116.312838 -270.527129) (xy 116.262963 -270.501721) (xy 116.217677 -270.468823) (xy 116.178095 -270.429245)
			(xy 116.145193 -270.383961) (xy 116.119782 -270.334088) (xy 116.102485 -270.280853) (xy 116.093731 -270.225567)
			(xy 116.09324 -270.19758) (xy 116.093494 -270.181324) (xy 116.094764 -270.158972) (xy 115.824508 -269.888716)
			(xy 114.426492 -269.888716) (xy 113.944908 -270.3703) (xy 113.944908 -270.650462) (xy 113.949226 -270.660368)
			(xy 113.966328 -270.70014) (xy 113.993414 -270.782375) (xy 114.012146 -270.866904) (xy 114.022336 -270.952882)
			(xy 114.023648 -270.996156) (xy 114.023648 -271.011396) (xy 114.024153 -271.023899) (xy 114.032228 -271.047565)
			(xy 114.047514 -271.067354) (xy 114.057684 -271.074642) (xy 114.066828 -271.079722) (xy 114.082576 -271.08912)
			(xy 114.083592 -271.089882) (xy 114.0841 -271.090136) (xy 114.114987 -271.109688) (xy 114.173694 -271.153254)
			(xy 114.22851 -271.201624) (xy 114.279044 -271.254453) (xy 114.302286 -271.282668) (xy 114.317526 -271.301464)
			(xy 114.38001 -271.301464) (xy 114.408739 -271.343862) (xy 114.457627 -271.43386) (xy 114.477546 -271.481042)
			(xy 114.500177 -271.475406) (xy 114.546428 -271.469415) (xy 114.569748 -271.469104) (xy 114.596394 -271.469605)
			(xy 114.64909 -271.477554) (xy 114.700013 -271.493268) (xy 114.748026 -271.516395) (xy 114.792055 -271.54642)
			(xy 114.831119 -271.58267) (xy 114.864343 -271.624338) (xy 114.890987 -271.670491) (xy 114.910456 -271.7201)
			(xy 114.922313 -271.772057) (xy 114.926296 -271.8252) (xy 114.924298 -271.851861) (xy 115.153938 -271.851861)
			(xy 115.153938 -271.798563) (xy 115.161881 -271.745859) (xy 115.177591 -271.694929) (xy 115.200717 -271.646908)
			(xy 115.230741 -271.602871) (xy 115.266993 -271.5638) (xy 115.308664 -271.530569) (xy 115.354822 -271.50392)
			(xy 115.404436 -271.484448) (xy 115.456398 -271.472588) (xy 115.509548 -271.468605) (xy 115.562698 -271.472588)
			(xy 115.61466 -271.484448) (xy 115.664274 -271.50392) (xy 115.710432 -271.530569) (xy 115.752103 -271.5638)
			(xy 115.788355 -271.602871) (xy 115.818379 -271.646908) (xy 115.841505 -271.694929) (xy 115.857215 -271.745859)
			(xy 115.865158 -271.798563) (xy 115.865656 -271.825212) (xy 115.865158 -271.851861) (xy 116.09323 -271.851861)
			(xy 116.09323 -271.798563) (xy 116.101173 -271.745859) (xy 116.116883 -271.694929) (xy 116.140009 -271.646908)
			(xy 116.170033 -271.602871) (xy 116.206285 -271.5638) (xy 116.247956 -271.530569) (xy 116.294114 -271.50392)
			(xy 116.343728 -271.484448) (xy 116.39569 -271.472588) (xy 116.44884 -271.468605) (xy 116.50199 -271.472588)
			(xy 116.553952 -271.484448) (xy 116.603566 -271.50392) (xy 116.649724 -271.530569) (xy 116.691395 -271.5638)
			(xy 116.727647 -271.602871) (xy 116.757671 -271.646908) (xy 116.780797 -271.694929) (xy 116.796507 -271.745859)
			(xy 116.80445 -271.798563) (xy 116.804948 -271.825212) (xy 116.80445 -271.851861) (xy 117.033538 -271.851861)
			(xy 117.033538 -271.798563) (xy 117.041481 -271.745859) (xy 117.057191 -271.694929) (xy 117.080317 -271.646908)
			(xy 117.110341 -271.602871) (xy 117.146593 -271.5638) (xy 117.188264 -271.530569) (xy 117.234422 -271.50392)
			(xy 117.284036 -271.484448) (xy 117.335998 -271.472588) (xy 117.389148 -271.468605) (xy 117.442298 -271.472588)
			(xy 117.49426 -271.484448) (xy 117.543874 -271.50392) (xy 117.590032 -271.530569) (xy 117.631703 -271.5638)
			(xy 117.667955 -271.602871) (xy 117.697979 -271.646908) (xy 117.721105 -271.694929) (xy 117.736815 -271.745859)
			(xy 117.744758 -271.798563) (xy 117.745256 -271.825212) (xy 117.744758 -271.851861) (xy 117.97283 -271.851861)
			(xy 117.97283 -271.798563) (xy 117.980773 -271.745859) (xy 117.996483 -271.694929) (xy 118.019609 -271.646908)
			(xy 118.049633 -271.602871) (xy 118.085885 -271.5638) (xy 118.127556 -271.530569) (xy 118.173714 -271.50392)
			(xy 118.223328 -271.484448) (xy 118.27529 -271.472588) (xy 118.32844 -271.468605) (xy 118.38159 -271.472588)
			(xy 118.433552 -271.484448) (xy 118.483166 -271.50392) (xy 118.529324 -271.530569) (xy 118.570995 -271.5638)
			(xy 118.607247 -271.602871) (xy 118.637271 -271.646908) (xy 118.660397 -271.694929) (xy 118.676107 -271.745859)
			(xy 118.68405 -271.798563) (xy 118.684548 -271.825212) (xy 118.68405 -271.851861) (xy 118.91263 -271.851861)
			(xy 118.91263 -271.798563) (xy 118.920573 -271.745859) (xy 118.936283 -271.694929) (xy 118.959409 -271.646908)
			(xy 118.989433 -271.602871) (xy 119.025685 -271.5638) (xy 119.067356 -271.530569) (xy 119.113514 -271.50392)
			(xy 119.163128 -271.484448) (xy 119.21509 -271.472588) (xy 119.26824 -271.468605) (xy 119.32139 -271.472588)
			(xy 119.373352 -271.484448) (xy 119.422966 -271.50392) (xy 119.469124 -271.530569) (xy 119.510795 -271.5638)
			(xy 119.547047 -271.602871) (xy 119.577071 -271.646908) (xy 119.600197 -271.694929) (xy 119.615907 -271.745859)
			(xy 119.62385 -271.798563) (xy 119.624348 -271.825212) (xy 119.62385 -271.851861) (xy 119.852938 -271.851861)
			(xy 119.852938 -271.798563) (xy 119.860881 -271.745859) (xy 119.876591 -271.694929) (xy 119.899717 -271.646908)
			(xy 119.929741 -271.602871) (xy 119.965993 -271.5638) (xy 120.007664 -271.530569) (xy 120.053822 -271.50392)
			(xy 120.103436 -271.484448) (xy 120.155398 -271.472588) (xy 120.208548 -271.468605) (xy 120.261698 -271.472588)
			(xy 120.31366 -271.484448) (xy 120.363274 -271.50392) (xy 120.409432 -271.530569) (xy 120.451103 -271.5638)
			(xy 120.487355 -271.602871) (xy 120.517379 -271.646908) (xy 120.540505 -271.694929) (xy 120.556215 -271.745859)
			(xy 120.564158 -271.798563) (xy 120.564656 -271.825212) (xy 120.564158 -271.851861) (xy 120.792738 -271.851861)
			(xy 120.792738 -271.798563) (xy 120.800681 -271.745859) (xy 120.816391 -271.694929) (xy 120.839517 -271.646908)
			(xy 120.869541 -271.602871) (xy 120.905793 -271.5638) (xy 120.947464 -271.530569) (xy 120.993622 -271.50392)
			(xy 121.043236 -271.484448) (xy 121.095198 -271.472588) (xy 121.148348 -271.468605) (xy 121.201498 -271.472588)
			(xy 121.25346 -271.484448) (xy 121.303074 -271.50392) (xy 121.349232 -271.530569) (xy 121.390903 -271.5638)
			(xy 121.427155 -271.602871) (xy 121.457179 -271.646908) (xy 121.480305 -271.694929) (xy 121.496015 -271.745859)
			(xy 121.503958 -271.798563) (xy 121.504456 -271.825212) (xy 121.503958 -271.851861) (xy 121.732538 -271.851861)
			(xy 121.732538 -271.798563) (xy 121.740481 -271.745859) (xy 121.756191 -271.694929) (xy 121.779317 -271.646908)
			(xy 121.809341 -271.602871) (xy 121.845593 -271.5638) (xy 121.887264 -271.530569) (xy 121.933422 -271.50392)
			(xy 121.983036 -271.484448) (xy 122.034998 -271.472588) (xy 122.088148 -271.468605) (xy 122.141298 -271.472588)
			(xy 122.19326 -271.484448) (xy 122.242874 -271.50392) (xy 122.289032 -271.530569) (xy 122.330703 -271.5638)
			(xy 122.366955 -271.602871) (xy 122.396979 -271.646908) (xy 122.420105 -271.694929) (xy 122.435815 -271.745859)
			(xy 122.443758 -271.798563) (xy 122.444256 -271.825212) (xy 122.443758 -271.851861) (xy 122.672338 -271.851861)
			(xy 122.672338 -271.798563) (xy 122.680281 -271.745859) (xy 122.695991 -271.694929) (xy 122.719117 -271.646908)
			(xy 122.749141 -271.602871) (xy 122.785393 -271.5638) (xy 122.827064 -271.530569) (xy 122.873222 -271.50392)
			(xy 122.922836 -271.484448) (xy 122.974798 -271.472588) (xy 123.027948 -271.468605) (xy 123.081098 -271.472588)
			(xy 123.13306 -271.484448) (xy 123.182674 -271.50392) (xy 123.228832 -271.530569) (xy 123.270503 -271.5638)
			(xy 123.306755 -271.602871) (xy 123.336779 -271.646908) (xy 123.359905 -271.694929) (xy 123.375615 -271.745859)
			(xy 123.383558 -271.798563) (xy 123.384056 -271.825212) (xy 123.383576 -271.85092) (xy 123.6411 -271.85092)
			(xy 123.6411 -271.799504) (xy 123.649143 -271.748722) (xy 123.665031 -271.699823) (xy 123.688374 -271.654011)
			(xy 123.718595 -271.612415) (xy 123.754951 -271.576059) (xy 123.796547 -271.545838) (xy 123.842359 -271.522495)
			(xy 123.891258 -271.506607) (xy 123.94204 -271.498564) (xy 123.993456 -271.498564) (xy 124.044238 -271.506607)
			(xy 124.093137 -271.522495) (xy 124.138949 -271.545838) (xy 124.180545 -271.576059) (xy 124.216901 -271.612415)
			(xy 124.247122 -271.654011) (xy 124.270465 -271.699823) (xy 124.286353 -271.748722) (xy 124.294396 -271.799504)
			(xy 124.2949 -271.825212) (xy 124.294396 -271.85092) (xy 124.5809 -271.85092) (xy 124.5809 -271.799504)
			(xy 124.588943 -271.748722) (xy 124.604831 -271.699823) (xy 124.628174 -271.654011) (xy 124.658395 -271.612415)
			(xy 124.694751 -271.576059) (xy 124.736347 -271.545838) (xy 124.782159 -271.522495) (xy 124.831058 -271.506607)
			(xy 124.88184 -271.498564) (xy 124.933256 -271.498564) (xy 124.984038 -271.506607) (xy 125.032937 -271.522495)
			(xy 125.078749 -271.545838) (xy 125.120345 -271.576059) (xy 125.156701 -271.612415) (xy 125.186922 -271.654011)
			(xy 125.210265 -271.699823) (xy 125.226153 -271.748722) (xy 125.234196 -271.799504) (xy 125.2347 -271.825212)
			(xy 125.234196 -271.85092) (xy 125.234047 -271.851861) (xy 125.491484 -271.851861) (xy 125.491484 -271.798563)
			(xy 125.499427 -271.745859) (xy 125.515137 -271.694929) (xy 125.538263 -271.646908) (xy 125.568287 -271.602871)
			(xy 125.604539 -271.5638) (xy 125.64621 -271.530569) (xy 125.692368 -271.50392) (xy 125.741982 -271.484448)
			(xy 125.793944 -271.472588) (xy 125.847094 -271.468605) (xy 125.900244 -271.472588) (xy 125.952206 -271.484448)
			(xy 126.00182 -271.50392) (xy 126.047978 -271.530569) (xy 126.089649 -271.5638) (xy 126.125901 -271.602871)
			(xy 126.155925 -271.646908) (xy 126.179051 -271.694929) (xy 126.194761 -271.745859) (xy 126.202704 -271.798563)
			(xy 126.203202 -271.825212) (xy 126.202722 -271.85092) (xy 126.4605 -271.85092) (xy 126.4605 -271.799504)
			(xy 126.468543 -271.748722) (xy 126.484431 -271.699823) (xy 126.507774 -271.654011) (xy 126.537995 -271.612415)
			(xy 126.574351 -271.576059) (xy 126.615947 -271.545838) (xy 126.661759 -271.522495) (xy 126.710658 -271.506607)
			(xy 126.76144 -271.498564) (xy 126.812856 -271.498564) (xy 126.863638 -271.506607) (xy 126.912537 -271.522495)
			(xy 126.958349 -271.545838) (xy 126.999945 -271.576059) (xy 127.036301 -271.612415) (xy 127.066522 -271.654011)
			(xy 127.089865 -271.699823) (xy 127.105753 -271.748722) (xy 127.113796 -271.799504) (xy 127.1143 -271.825212)
			(xy 127.113796 -271.85092) (xy 127.113647 -271.851861) (xy 127.371338 -271.851861) (xy 127.371338 -271.798563)
			(xy 127.379281 -271.745859) (xy 127.394991 -271.694929) (xy 127.418117 -271.646908) (xy 127.448141 -271.602871)
			(xy 127.484393 -271.5638) (xy 127.526064 -271.530569) (xy 127.572222 -271.50392) (xy 127.621836 -271.484448)
			(xy 127.673798 -271.472588) (xy 127.726948 -271.468605) (xy 127.780098 -271.472588) (xy 127.83206 -271.484448)
			(xy 127.881674 -271.50392) (xy 127.927832 -271.530569) (xy 127.969503 -271.5638) (xy 128.005755 -271.602871)
			(xy 128.035779 -271.646908) (xy 128.058905 -271.694929) (xy 128.074615 -271.745859) (xy 128.082558 -271.798563)
			(xy 128.083056 -271.825212) (xy 128.082576 -271.85092) (xy 128.3401 -271.85092) (xy 128.3401 -271.799504)
			(xy 128.348143 -271.748722) (xy 128.364031 -271.699823) (xy 128.387374 -271.654011) (xy 128.417595 -271.612415)
			(xy 128.453951 -271.576059) (xy 128.495547 -271.545838) (xy 128.541359 -271.522495) (xy 128.590258 -271.506607)
			(xy 128.64104 -271.498564) (xy 128.692456 -271.498564) (xy 128.743238 -271.506607) (xy 128.792137 -271.522495)
			(xy 128.837949 -271.545838) (xy 128.879545 -271.576059) (xy 128.915901 -271.612415) (xy 128.946122 -271.654011)
			(xy 128.969465 -271.699823) (xy 128.985353 -271.748722) (xy 128.993396 -271.799504) (xy 128.9939 -271.825212)
			(xy 128.993396 -271.85092) (xy 128.993247 -271.851861) (xy 129.250938 -271.851861) (xy 129.250938 -271.798563)
			(xy 129.258881 -271.745859) (xy 129.274591 -271.694929) (xy 129.297717 -271.646908) (xy 129.327741 -271.602871)
			(xy 129.363993 -271.5638) (xy 129.405664 -271.530569) (xy 129.451822 -271.50392) (xy 129.501436 -271.484448)
			(xy 129.553398 -271.472588) (xy 129.606548 -271.468605) (xy 129.659698 -271.472588) (xy 129.71166 -271.484448)
			(xy 129.761274 -271.50392) (xy 129.807432 -271.530569) (xy 129.849103 -271.5638) (xy 129.885355 -271.602871)
			(xy 129.915379 -271.646908) (xy 129.938505 -271.694929) (xy 129.954215 -271.745859) (xy 129.962158 -271.798563)
			(xy 129.962656 -271.825212) (xy 129.962176 -271.85092) (xy 130.2197 -271.85092) (xy 130.2197 -271.799504)
			(xy 130.227743 -271.748722) (xy 130.243631 -271.699823) (xy 130.266974 -271.654011) (xy 130.297195 -271.612415)
			(xy 130.333551 -271.576059) (xy 130.375147 -271.545838) (xy 130.420959 -271.522495) (xy 130.469858 -271.506607)
			(xy 130.52064 -271.498564) (xy 130.572056 -271.498564) (xy 130.622838 -271.506607) (xy 130.671737 -271.522495)
			(xy 130.717549 -271.545838) (xy 130.759145 -271.576059) (xy 130.795501 -271.612415) (xy 130.825722 -271.654011)
			(xy 130.849065 -271.699823) (xy 130.864953 -271.748722) (xy 130.872996 -271.799504) (xy 130.8735 -271.825212)
			(xy 130.872996 -271.85092) (xy 131.1595 -271.85092) (xy 131.1595 -271.799504) (xy 131.167543 -271.748722)
			(xy 131.183431 -271.699823) (xy 131.206774 -271.654011) (xy 131.236995 -271.612415) (xy 131.273351 -271.576059)
			(xy 131.314947 -271.545838) (xy 131.360759 -271.522495) (xy 131.409658 -271.506607) (xy 131.46044 -271.498564)
			(xy 131.511856 -271.498564) (xy 131.562638 -271.506607) (xy 131.611537 -271.522495) (xy 131.657349 -271.545838)
			(xy 131.698945 -271.576059) (xy 131.735301 -271.612415) (xy 131.765522 -271.654011) (xy 131.788865 -271.699823)
			(xy 131.804753 -271.748722) (xy 131.812796 -271.799504) (xy 131.8133 -271.825212) (xy 131.812796 -271.85092)
			(xy 131.812647 -271.851861) (xy 132.070084 -271.851861) (xy 132.070084 -271.798563) (xy 132.078027 -271.745859)
			(xy 132.093737 -271.694929) (xy 132.116863 -271.646908) (xy 132.146887 -271.602871) (xy 132.183139 -271.5638)
			(xy 132.22481 -271.530569) (xy 132.270968 -271.50392) (xy 132.320582 -271.484448) (xy 132.372544 -271.472588)
			(xy 132.425694 -271.468605) (xy 132.478844 -271.472588) (xy 132.530806 -271.484448) (xy 132.58042 -271.50392)
			(xy 132.626578 -271.530569) (xy 132.668249 -271.5638) (xy 132.704501 -271.602871) (xy 132.734525 -271.646908)
			(xy 132.757651 -271.694929) (xy 132.773361 -271.745859) (xy 132.781304 -271.798563) (xy 132.781802 -271.825212)
			(xy 132.781322 -271.85092) (xy 133.0391 -271.85092) (xy 133.0391 -271.799504) (xy 133.047143 -271.748722)
			(xy 133.063031 -271.699823) (xy 133.086374 -271.654011) (xy 133.116595 -271.612415) (xy 133.152951 -271.576059)
			(xy 133.194547 -271.545838) (xy 133.240359 -271.522495) (xy 133.289258 -271.506607) (xy 133.34004 -271.498564)
			(xy 133.391456 -271.498564) (xy 133.442238 -271.506607) (xy 133.491137 -271.522495) (xy 133.536949 -271.545838)
			(xy 133.578545 -271.576059) (xy 133.614901 -271.612415) (xy 133.645122 -271.654011) (xy 133.668465 -271.699823)
			(xy 133.684353 -271.748722) (xy 133.692396 -271.799504) (xy 133.6929 -271.825212) (xy 133.692396 -271.85092)
			(xy 133.692247 -271.851861) (xy 133.949938 -271.851861) (xy 133.949938 -271.798563) (xy 133.957881 -271.745859)
			(xy 133.973591 -271.694929) (xy 133.996717 -271.646908) (xy 134.026741 -271.602871) (xy 134.062993 -271.5638)
			(xy 134.104664 -271.530569) (xy 134.150822 -271.50392) (xy 134.200436 -271.484448) (xy 134.252398 -271.472588)
			(xy 134.305548 -271.468605) (xy 134.358698 -271.472588) (xy 134.41066 -271.484448) (xy 134.460274 -271.50392)
			(xy 134.506432 -271.530569) (xy 134.548103 -271.5638) (xy 134.584355 -271.602871) (xy 134.614379 -271.646908)
			(xy 134.637505 -271.694929) (xy 134.653215 -271.745859) (xy 134.661158 -271.798563) (xy 134.661656 -271.825212)
			(xy 134.661176 -271.85092) (xy 134.9187 -271.85092) (xy 134.9187 -271.799504) (xy 134.926743 -271.748722)
			(xy 134.942631 -271.699823) (xy 134.965974 -271.654011) (xy 134.996195 -271.612415) (xy 135.032551 -271.576059)
			(xy 135.074147 -271.545838) (xy 135.119959 -271.522495) (xy 135.168858 -271.506607) (xy 135.21964 -271.498564)
			(xy 135.271056 -271.498564) (xy 135.321838 -271.506607) (xy 135.370737 -271.522495) (xy 135.416549 -271.545838)
			(xy 135.458145 -271.576059) (xy 135.494501 -271.612415) (xy 135.524722 -271.654011) (xy 135.548065 -271.699823)
			(xy 135.563953 -271.748722) (xy 135.571996 -271.799504) (xy 135.5725 -271.825212) (xy 135.571996 -271.85092)
			(xy 135.571847 -271.851861) (xy 135.829538 -271.851861) (xy 135.829538 -271.798563) (xy 135.837481 -271.745859)
			(xy 135.853191 -271.694929) (xy 135.876317 -271.646908) (xy 135.906341 -271.602871) (xy 135.942593 -271.5638)
			(xy 135.984264 -271.530569) (xy 136.030422 -271.50392) (xy 136.080036 -271.484448) (xy 136.131998 -271.472588)
			(xy 136.185148 -271.468605) (xy 136.238298 -271.472588) (xy 136.29026 -271.484448) (xy 136.339874 -271.50392)
			(xy 136.386032 -271.530569) (xy 136.427703 -271.5638) (xy 136.463955 -271.602871) (xy 136.493979 -271.646908)
			(xy 136.517105 -271.694929) (xy 136.532815 -271.745859) (xy 136.540758 -271.798563) (xy 136.541256 -271.825212)
			(xy 136.540758 -271.851861) (xy 136.532815 -271.904565) (xy 136.517105 -271.955495) (xy 136.493979 -272.003516)
			(xy 136.463955 -272.047553) (xy 136.427703 -272.086624) (xy 136.386032 -272.119855) (xy 136.339874 -272.146504)
			(xy 136.29026 -272.165976) (xy 136.238298 -272.177836) (xy 136.185148 -272.18182) (xy 136.131998 -272.177836)
			(xy 136.080036 -272.165976) (xy 136.030422 -272.146504) (xy 135.984264 -272.119855) (xy 135.942593 -272.086624)
			(xy 135.906341 -272.047553) (xy 135.876317 -272.003516) (xy 135.853191 -271.955495) (xy 135.837481 -271.904565)
			(xy 135.829538 -271.851861) (xy 135.571847 -271.851861) (xy 135.563953 -271.901702) (xy 135.548065 -271.950601)
			(xy 135.524722 -271.996413) (xy 135.494501 -272.038009) (xy 135.458145 -272.074365) (xy 135.416549 -272.104586)
			(xy 135.370737 -272.127929) (xy 135.321838 -272.143817) (xy 135.271056 -272.15186) (xy 135.21964 -272.15186)
			(xy 135.168858 -272.143817) (xy 135.119959 -272.127929) (xy 135.074147 -272.104586) (xy 135.032551 -272.074365)
			(xy 134.996195 -272.038009) (xy 134.965974 -271.996413) (xy 134.942631 -271.950601) (xy 134.926743 -271.901702)
			(xy 134.9187 -271.85092) (xy 134.661176 -271.85092) (xy 134.661158 -271.851861) (xy 134.653215 -271.904565)
			(xy 134.637505 -271.955495) (xy 134.614379 -272.003516) (xy 134.584355 -272.047553) (xy 134.548103 -272.086624)
			(xy 134.506432 -272.119855) (xy 134.460274 -272.146504) (xy 134.41066 -272.165976) (xy 134.358698 -272.177836)
			(xy 134.305548 -272.18182) (xy 134.252398 -272.177836) (xy 134.200436 -272.165976) (xy 134.150822 -272.146504)
			(xy 134.104664 -272.119855) (xy 134.062993 -272.086624) (xy 134.026741 -272.047553) (xy 133.996717 -272.003516)
			(xy 133.973591 -271.955495) (xy 133.957881 -271.904565) (xy 133.949938 -271.851861) (xy 133.692247 -271.851861)
			(xy 133.684353 -271.901702) (xy 133.668465 -271.950601) (xy 133.645122 -271.996413) (xy 133.614901 -272.038009)
			(xy 133.578545 -272.074365) (xy 133.536949 -272.104586) (xy 133.491137 -272.127929) (xy 133.442238 -272.143817)
			(xy 133.391456 -272.15186) (xy 133.34004 -272.15186) (xy 133.289258 -272.143817) (xy 133.240359 -272.127929)
			(xy 133.194547 -272.104586) (xy 133.152951 -272.074365) (xy 133.116595 -272.038009) (xy 133.086374 -271.996413)
			(xy 133.063031 -271.950601) (xy 133.047143 -271.901702) (xy 133.0391 -271.85092) (xy 132.781322 -271.85092)
			(xy 132.781304 -271.851861) (xy 132.773361 -271.904565) (xy 132.757651 -271.955495) (xy 132.734525 -272.003516)
			(xy 132.704501 -272.047553) (xy 132.668249 -272.086624) (xy 132.626578 -272.119855) (xy 132.58042 -272.146504)
			(xy 132.530806 -272.165976) (xy 132.478844 -272.177836) (xy 132.425694 -272.18182) (xy 132.372544 -272.177836)
			(xy 132.320582 -272.165976) (xy 132.270968 -272.146504) (xy 132.22481 -272.119855) (xy 132.183139 -272.086624)
			(xy 132.146887 -272.047553) (xy 132.116863 -272.003516) (xy 132.093737 -271.955495) (xy 132.078027 -271.904565)
			(xy 132.070084 -271.851861) (xy 131.812647 -271.851861) (xy 131.804753 -271.901702) (xy 131.788865 -271.950601)
			(xy 131.765522 -271.996413) (xy 131.735301 -272.038009) (xy 131.698945 -272.074365) (xy 131.657349 -272.104586)
			(xy 131.611537 -272.127929) (xy 131.562638 -272.143817) (xy 131.511856 -272.15186) (xy 131.46044 -272.15186)
			(xy 131.409658 -272.143817) (xy 131.360759 -272.127929) (xy 131.314947 -272.104586) (xy 131.273351 -272.074365)
			(xy 131.236995 -272.038009) (xy 131.206774 -271.996413) (xy 131.183431 -271.950601) (xy 131.167543 -271.901702)
			(xy 131.1595 -271.85092) (xy 130.872996 -271.85092) (xy 130.864953 -271.901702) (xy 130.849065 -271.950601)
			(xy 130.825722 -271.996413) (xy 130.795501 -272.038009) (xy 130.759145 -272.074365) (xy 130.717549 -272.104586)
			(xy 130.671737 -272.127929) (xy 130.622838 -272.143817) (xy 130.572056 -272.15186) (xy 130.52064 -272.15186)
			(xy 130.469858 -272.143817) (xy 130.420959 -272.127929) (xy 130.375147 -272.104586) (xy 130.333551 -272.074365)
			(xy 130.297195 -272.038009) (xy 130.266974 -271.996413) (xy 130.243631 -271.950601) (xy 130.227743 -271.901702)
			(xy 130.2197 -271.85092) (xy 129.962176 -271.85092) (xy 129.962158 -271.851861) (xy 129.954215 -271.904565)
			(xy 129.938505 -271.955495) (xy 129.915379 -272.003516) (xy 129.885355 -272.047553) (xy 129.849103 -272.086624)
			(xy 129.807432 -272.119855) (xy 129.761274 -272.146504) (xy 129.71166 -272.165976) (xy 129.659698 -272.177836)
			(xy 129.606548 -272.18182) (xy 129.553398 -272.177836) (xy 129.501436 -272.165976) (xy 129.451822 -272.146504)
			(xy 129.405664 -272.119855) (xy 129.363993 -272.086624) (xy 129.327741 -272.047553) (xy 129.297717 -272.003516)
			(xy 129.274591 -271.955495) (xy 129.258881 -271.904565) (xy 129.250938 -271.851861) (xy 128.993247 -271.851861)
			(xy 128.985353 -271.901702) (xy 128.969465 -271.950601) (xy 128.946122 -271.996413) (xy 128.915901 -272.038009)
			(xy 128.879545 -272.074365) (xy 128.837949 -272.104586) (xy 128.792137 -272.127929) (xy 128.743238 -272.143817)
			(xy 128.692456 -272.15186) (xy 128.64104 -272.15186) (xy 128.590258 -272.143817) (xy 128.541359 -272.127929)
			(xy 128.495547 -272.104586) (xy 128.453951 -272.074365) (xy 128.417595 -272.038009) (xy 128.387374 -271.996413)
			(xy 128.364031 -271.950601) (xy 128.348143 -271.901702) (xy 128.3401 -271.85092) (xy 128.082576 -271.85092)
			(xy 128.082558 -271.851861) (xy 128.074615 -271.904565) (xy 128.058905 -271.955495) (xy 128.035779 -272.003516)
			(xy 128.005755 -272.047553) (xy 127.969503 -272.086624) (xy 127.927832 -272.119855) (xy 127.881674 -272.146504)
			(xy 127.83206 -272.165976) (xy 127.780098 -272.177836) (xy 127.726948 -272.18182) (xy 127.673798 -272.177836)
			(xy 127.621836 -272.165976) (xy 127.572222 -272.146504) (xy 127.526064 -272.119855) (xy 127.484393 -272.086624)
			(xy 127.448141 -272.047553) (xy 127.418117 -272.003516) (xy 127.394991 -271.955495) (xy 127.379281 -271.904565)
			(xy 127.371338 -271.851861) (xy 127.113647 -271.851861) (xy 127.105753 -271.901702) (xy 127.089865 -271.950601)
			(xy 127.066522 -271.996413) (xy 127.036301 -272.038009) (xy 126.999945 -272.074365) (xy 126.958349 -272.104586)
			(xy 126.912537 -272.127929) (xy 126.863638 -272.143817) (xy 126.812856 -272.15186) (xy 126.76144 -272.15186)
			(xy 126.710658 -272.143817) (xy 126.661759 -272.127929) (xy 126.615947 -272.104586) (xy 126.574351 -272.074365)
			(xy 126.537995 -272.038009) (xy 126.507774 -271.996413) (xy 126.484431 -271.950601) (xy 126.468543 -271.901702)
			(xy 126.4605 -271.85092) (xy 126.202722 -271.85092) (xy 126.202704 -271.851861) (xy 126.194761 -271.904565)
			(xy 126.179051 -271.955495) (xy 126.155925 -272.003516) (xy 126.125901 -272.047553) (xy 126.089649 -272.086624)
			(xy 126.047978 -272.119855) (xy 126.00182 -272.146504) (xy 125.952206 -272.165976) (xy 125.900244 -272.177836)
			(xy 125.847094 -272.18182) (xy 125.793944 -272.177836) (xy 125.741982 -272.165976) (xy 125.692368 -272.146504)
			(xy 125.64621 -272.119855) (xy 125.604539 -272.086624) (xy 125.568287 -272.047553) (xy 125.538263 -272.003516)
			(xy 125.515137 -271.955495) (xy 125.499427 -271.904565) (xy 125.491484 -271.851861) (xy 125.234047 -271.851861)
			(xy 125.226153 -271.901702) (xy 125.210265 -271.950601) (xy 125.186922 -271.996413) (xy 125.156701 -272.038009)
			(xy 125.120345 -272.074365) (xy 125.078749 -272.104586) (xy 125.032937 -272.127929) (xy 124.984038 -272.143817)
			(xy 124.933256 -272.15186) (xy 124.88184 -272.15186) (xy 124.831058 -272.143817) (xy 124.782159 -272.127929)
			(xy 124.736347 -272.104586) (xy 124.694751 -272.074365) (xy 124.658395 -272.038009) (xy 124.628174 -271.996413)
			(xy 124.604831 -271.950601) (xy 124.588943 -271.901702) (xy 124.5809 -271.85092) (xy 124.294396 -271.85092)
			(xy 124.286353 -271.901702) (xy 124.270465 -271.950601) (xy 124.247122 -271.996413) (xy 124.216901 -272.038009)
			(xy 124.180545 -272.074365) (xy 124.138949 -272.104586) (xy 124.093137 -272.127929) (xy 124.044238 -272.143817)
			(xy 123.993456 -272.15186) (xy 123.94204 -272.15186) (xy 123.891258 -272.143817) (xy 123.842359 -272.127929)
			(xy 123.796547 -272.104586) (xy 123.754951 -272.074365) (xy 123.718595 -272.038009) (xy 123.688374 -271.996413)
			(xy 123.665031 -271.950601) (xy 123.649143 -271.901702) (xy 123.6411 -271.85092) (xy 123.383576 -271.85092)
			(xy 123.383558 -271.851861) (xy 123.375615 -271.904565) (xy 123.359905 -271.955495) (xy 123.336779 -272.003516)
			(xy 123.306755 -272.047553) (xy 123.270503 -272.086624) (xy 123.228832 -272.119855) (xy 123.182674 -272.146504)
			(xy 123.13306 -272.165976) (xy 123.081098 -272.177836) (xy 123.027948 -272.18182) (xy 122.974798 -272.177836)
			(xy 122.922836 -272.165976) (xy 122.873222 -272.146504) (xy 122.827064 -272.119855) (xy 122.785393 -272.086624)
			(xy 122.749141 -272.047553) (xy 122.719117 -272.003516) (xy 122.695991 -271.955495) (xy 122.680281 -271.904565)
			(xy 122.672338 -271.851861) (xy 122.443758 -271.851861) (xy 122.435815 -271.904565) (xy 122.420105 -271.955495)
			(xy 122.396979 -272.003516) (xy 122.366955 -272.047553) (xy 122.330703 -272.086624) (xy 122.289032 -272.119855)
			(xy 122.242874 -272.146504) (xy 122.19326 -272.165976) (xy 122.141298 -272.177836) (xy 122.088148 -272.18182)
			(xy 122.034998 -272.177836) (xy 121.983036 -272.165976) (xy 121.933422 -272.146504) (xy 121.887264 -272.119855)
			(xy 121.845593 -272.086624) (xy 121.809341 -272.047553) (xy 121.779317 -272.003516) (xy 121.756191 -271.955495)
			(xy 121.740481 -271.904565) (xy 121.732538 -271.851861) (xy 121.503958 -271.851861) (xy 121.496015 -271.904565)
			(xy 121.480305 -271.955495) (xy 121.457179 -272.003516) (xy 121.427155 -272.047553) (xy 121.390903 -272.086624)
			(xy 121.349232 -272.119855) (xy 121.303074 -272.146504) (xy 121.25346 -272.165976) (xy 121.201498 -272.177836)
			(xy 121.148348 -272.18182) (xy 121.095198 -272.177836) (xy 121.043236 -272.165976) (xy 120.993622 -272.146504)
			(xy 120.947464 -272.119855) (xy 120.905793 -272.086624) (xy 120.869541 -272.047553) (xy 120.839517 -272.003516)
			(xy 120.816391 -271.955495) (xy 120.800681 -271.904565) (xy 120.792738 -271.851861) (xy 120.564158 -271.851861)
			(xy 120.556215 -271.904565) (xy 120.540505 -271.955495) (xy 120.517379 -272.003516) (xy 120.487355 -272.047553)
			(xy 120.451103 -272.086624) (xy 120.409432 -272.119855) (xy 120.363274 -272.146504) (xy 120.31366 -272.165976)
			(xy 120.261698 -272.177836) (xy 120.208548 -272.18182) (xy 120.155398 -272.177836) (xy 120.103436 -272.165976)
			(xy 120.053822 -272.146504) (xy 120.007664 -272.119855) (xy 119.965993 -272.086624) (xy 119.929741 -272.047553)
			(xy 119.899717 -272.003516) (xy 119.876591 -271.955495) (xy 119.860881 -271.904565) (xy 119.852938 -271.851861)
			(xy 119.62385 -271.851861) (xy 119.615907 -271.904565) (xy 119.600197 -271.955495) (xy 119.577071 -272.003516)
			(xy 119.547047 -272.047553) (xy 119.510795 -272.086624) (xy 119.469124 -272.119855) (xy 119.422966 -272.146504)
			(xy 119.373352 -272.165976) (xy 119.32139 -272.177836) (xy 119.26824 -272.18182) (xy 119.21509 -272.177836)
			(xy 119.163128 -272.165976) (xy 119.113514 -272.146504) (xy 119.067356 -272.119855) (xy 119.025685 -272.086624)
			(xy 118.989433 -272.047553) (xy 118.959409 -272.003516) (xy 118.936283 -271.955495) (xy 118.920573 -271.904565)
			(xy 118.91263 -271.851861) (xy 118.68405 -271.851861) (xy 118.676107 -271.904565) (xy 118.660397 -271.955495)
			(xy 118.637271 -272.003516) (xy 118.607247 -272.047553) (xy 118.570995 -272.086624) (xy 118.529324 -272.119855)
			(xy 118.483166 -272.146504) (xy 118.433552 -272.165976) (xy 118.38159 -272.177836) (xy 118.32844 -272.18182)
			(xy 118.27529 -272.177836) (xy 118.223328 -272.165976) (xy 118.173714 -272.146504) (xy 118.127556 -272.119855)
			(xy 118.085885 -272.086624) (xy 118.049633 -272.047553) (xy 118.019609 -272.003516) (xy 117.996483 -271.955495)
			(xy 117.980773 -271.904565) (xy 117.97283 -271.851861) (xy 117.744758 -271.851861) (xy 117.736815 -271.904565)
			(xy 117.721105 -271.955495) (xy 117.697979 -272.003516) (xy 117.667955 -272.047553) (xy 117.631703 -272.086624)
			(xy 117.590032 -272.119855) (xy 117.543874 -272.146504) (xy 117.49426 -272.165976) (xy 117.442298 -272.177836)
			(xy 117.389148 -272.18182) (xy 117.335998 -272.177836) (xy 117.284036 -272.165976) (xy 117.234422 -272.146504)
			(xy 117.188264 -272.119855) (xy 117.146593 -272.086624) (xy 117.110341 -272.047553) (xy 117.080317 -272.003516)
			(xy 117.057191 -271.955495) (xy 117.041481 -271.904565) (xy 117.033538 -271.851861) (xy 116.80445 -271.851861)
			(xy 116.796507 -271.904565) (xy 116.780797 -271.955495) (xy 116.757671 -272.003516) (xy 116.727647 -272.047553)
			(xy 116.691395 -272.086624) (xy 116.649724 -272.119855) (xy 116.603566 -272.146504) (xy 116.553952 -272.165976)
			(xy 116.50199 -272.177836) (xy 116.44884 -272.18182) (xy 116.39569 -272.177836) (xy 116.343728 -272.165976)
			(xy 116.294114 -272.146504) (xy 116.247956 -272.119855) (xy 116.206285 -272.086624) (xy 116.170033 -272.047553)
			(xy 116.140009 -272.003516) (xy 116.116883 -271.955495) (xy 116.101173 -271.904565) (xy 116.09323 -271.851861)
			(xy 115.865158 -271.851861) (xy 115.857215 -271.904565) (xy 115.841505 -271.955495) (xy 115.818379 -272.003516)
			(xy 115.788355 -272.047553) (xy 115.752103 -272.086624) (xy 115.710432 -272.119855) (xy 115.664274 -272.146504)
			(xy 115.61466 -272.165976) (xy 115.562698 -272.177836) (xy 115.509548 -272.18182) (xy 115.456398 -272.177836)
			(xy 115.404436 -272.165976) (xy 115.354822 -272.146504) (xy 115.308664 -272.119855) (xy 115.266993 -272.086624)
			(xy 115.230741 -272.047553) (xy 115.200717 -272.003516) (xy 115.177591 -271.955495) (xy 115.161881 -271.904565)
			(xy 115.153938 -271.851861) (xy 114.924298 -271.851861) (xy 114.922313 -271.878343) (xy 114.910456 -271.9303)
			(xy 114.890987 -271.979909) (xy 114.864343 -272.026062) (xy 114.831119 -272.06773) (xy 114.792055 -272.10398)
			(xy 114.748026 -272.134005) (xy 114.700013 -272.157132) (xy 114.64909 -272.172846) (xy 114.596394 -272.180795)
			(xy 114.569748 -272.18132) (xy 114.558863 -272.181269) (xy 114.537131 -272.179998) (xy 114.526314 -272.17878)
			(xy 114.50828 -272.176494) (xy 114.462052 -272.206212) (xy 114.455702 -272.219166) (xy 114.439149 -272.253002)
			(xy 114.401253 -272.318108) (xy 114.38001 -272.349214) (xy 114.375692 -272.35531) (xy 114.366294 -272.384774)
			(xy 114.37747 -272.41627) (xy 114.382296 -272.42262) (xy 114.397463 -272.443141) (xy 114.422396 -272.487663)
			(xy 114.440723 -272.535286) (xy 114.452069 -272.585037) (xy 114.456203 -272.635897) (xy 114.454338 -272.665931)
			(xy 114.683784 -272.665931) (xy 114.683784 -272.612633) (xy 114.691727 -272.559929) (xy 114.707437 -272.508999)
			(xy 114.730563 -272.460978) (xy 114.760587 -272.416941) (xy 114.796839 -272.37787) (xy 114.83851 -272.344639)
			(xy 114.884668 -272.31799) (xy 114.934282 -272.298518) (xy 114.986244 -272.286658) (xy 115.039394 -272.282675)
			(xy 115.092544 -272.286658) (xy 115.144506 -272.298518) (xy 115.19412 -272.31799) (xy 115.240278 -272.344639)
			(xy 115.281949 -272.37787) (xy 115.318201 -272.416941) (xy 115.348225 -272.460978) (xy 115.371351 -272.508999)
			(xy 115.387061 -272.559929) (xy 115.395004 -272.612633) (xy 115.395502 -272.639282) (xy 115.395004 -272.665931)
			(xy 115.623584 -272.665931) (xy 115.623584 -272.612633) (xy 115.631527 -272.559929) (xy 115.647237 -272.508999)
			(xy 115.670363 -272.460978) (xy 115.700387 -272.416941) (xy 115.736639 -272.37787) (xy 115.77831 -272.344639)
			(xy 115.824468 -272.31799) (xy 115.874082 -272.298518) (xy 115.926044 -272.286658) (xy 115.979194 -272.282675)
			(xy 116.032344 -272.286658) (xy 116.084306 -272.298518) (xy 116.13392 -272.31799) (xy 116.180078 -272.344639)
			(xy 116.221749 -272.37787) (xy 116.258001 -272.416941) (xy 116.288025 -272.460978) (xy 116.311151 -272.508999)
			(xy 116.326861 -272.559929) (xy 116.334804 -272.612633) (xy 116.335302 -272.639282) (xy 116.334804 -272.665931)
			(xy 116.563384 -272.665931) (xy 116.563384 -272.612633) (xy 116.571327 -272.559929) (xy 116.587037 -272.508999)
			(xy 116.610163 -272.460978) (xy 116.640187 -272.416941) (xy 116.676439 -272.37787) (xy 116.71811 -272.344639)
			(xy 116.764268 -272.31799) (xy 116.813882 -272.298518) (xy 116.865844 -272.286658) (xy 116.918994 -272.282675)
			(xy 116.972144 -272.286658) (xy 117.024106 -272.298518) (xy 117.07372 -272.31799) (xy 117.119878 -272.344639)
			(xy 117.161549 -272.37787) (xy 117.197801 -272.416941) (xy 117.227825 -272.460978) (xy 117.250951 -272.508999)
			(xy 117.266661 -272.559929) (xy 117.274604 -272.612633) (xy 117.275102 -272.639282) (xy 117.274604 -272.665931)
			(xy 117.503184 -272.665931) (xy 117.503184 -272.612633) (xy 117.511127 -272.559929) (xy 117.526837 -272.508999)
			(xy 117.549963 -272.460978) (xy 117.579987 -272.416941) (xy 117.616239 -272.37787) (xy 117.65791 -272.344639)
			(xy 117.704068 -272.31799) (xy 117.753682 -272.298518) (xy 117.805644 -272.286658) (xy 117.858794 -272.282675)
			(xy 117.911944 -272.286658) (xy 117.963906 -272.298518) (xy 118.01352 -272.31799) (xy 118.059678 -272.344639)
			(xy 118.101349 -272.37787) (xy 118.137601 -272.416941) (xy 118.167625 -272.460978) (xy 118.190751 -272.508999)
			(xy 118.206461 -272.559929) (xy 118.214404 -272.612633) (xy 118.214902 -272.639282) (xy 118.214404 -272.665931)
			(xy 118.442984 -272.665931) (xy 118.442984 -272.612633) (xy 118.450927 -272.559929) (xy 118.466637 -272.508999)
			(xy 118.489763 -272.460978) (xy 118.519787 -272.416941) (xy 118.556039 -272.37787) (xy 118.59771 -272.344639)
			(xy 118.643868 -272.31799) (xy 118.693482 -272.298518) (xy 118.745444 -272.286658) (xy 118.798594 -272.282675)
			(xy 118.851744 -272.286658) (xy 118.903706 -272.298518) (xy 118.95332 -272.31799) (xy 118.999478 -272.344639)
			(xy 119.041149 -272.37787) (xy 119.077401 -272.416941) (xy 119.107425 -272.460978) (xy 119.130551 -272.508999)
			(xy 119.146261 -272.559929) (xy 119.154204 -272.612633) (xy 119.154702 -272.639282) (xy 119.154204 -272.665931)
			(xy 119.382784 -272.665931) (xy 119.382784 -272.612633) (xy 119.390727 -272.559929) (xy 119.406437 -272.508999)
			(xy 119.429563 -272.460978) (xy 119.459587 -272.416941) (xy 119.495839 -272.37787) (xy 119.53751 -272.344639)
			(xy 119.583668 -272.31799) (xy 119.633282 -272.298518) (xy 119.685244 -272.286658) (xy 119.738394 -272.282675)
			(xy 119.791544 -272.286658) (xy 119.843506 -272.298518) (xy 119.89312 -272.31799) (xy 119.939278 -272.344639)
			(xy 119.980949 -272.37787) (xy 120.017201 -272.416941) (xy 120.047225 -272.460978) (xy 120.070351 -272.508999)
			(xy 120.086061 -272.559929) (xy 120.094004 -272.612633) (xy 120.094502 -272.639282) (xy 120.094004 -272.665931)
			(xy 120.322584 -272.665931) (xy 120.322584 -272.612633) (xy 120.330527 -272.559929) (xy 120.346237 -272.508999)
			(xy 120.369363 -272.460978) (xy 120.399387 -272.416941) (xy 120.435639 -272.37787) (xy 120.47731 -272.344639)
			(xy 120.523468 -272.31799) (xy 120.573082 -272.298518) (xy 120.625044 -272.286658) (xy 120.678194 -272.282675)
			(xy 120.731344 -272.286658) (xy 120.783306 -272.298518) (xy 120.83292 -272.31799) (xy 120.879078 -272.344639)
			(xy 120.920749 -272.37787) (xy 120.957001 -272.416941) (xy 120.987025 -272.460978) (xy 121.010151 -272.508999)
			(xy 121.025861 -272.559929) (xy 121.033804 -272.612633) (xy 121.034302 -272.639282) (xy 121.033804 -272.665931)
			(xy 121.262384 -272.665931) (xy 121.262384 -272.612633) (xy 121.270327 -272.559929) (xy 121.286037 -272.508999)
			(xy 121.309163 -272.460978) (xy 121.339187 -272.416941) (xy 121.375439 -272.37787) (xy 121.41711 -272.344639)
			(xy 121.463268 -272.31799) (xy 121.512882 -272.298518) (xy 121.564844 -272.286658) (xy 121.617994 -272.282675)
			(xy 121.671144 -272.286658) (xy 121.723106 -272.298518) (xy 121.77272 -272.31799) (xy 121.818878 -272.344639)
			(xy 121.860549 -272.37787) (xy 121.896801 -272.416941) (xy 121.926825 -272.460978) (xy 121.949951 -272.508999)
			(xy 121.965661 -272.559929) (xy 121.973604 -272.612633) (xy 121.974102 -272.639282) (xy 121.973604 -272.665931)
			(xy 122.202184 -272.665931) (xy 122.202184 -272.612633) (xy 122.210127 -272.559929) (xy 122.225837 -272.508999)
			(xy 122.248963 -272.460978) (xy 122.278987 -272.416941) (xy 122.315239 -272.37787) (xy 122.35691 -272.344639)
			(xy 122.403068 -272.31799) (xy 122.452682 -272.298518) (xy 122.504644 -272.286658) (xy 122.557794 -272.282675)
			(xy 122.610944 -272.286658) (xy 122.662906 -272.298518) (xy 122.71252 -272.31799) (xy 122.758678 -272.344639)
			(xy 122.800349 -272.37787) (xy 122.836601 -272.416941) (xy 122.866625 -272.460978) (xy 122.889751 -272.508999)
			(xy 122.905461 -272.559929) (xy 122.913404 -272.612633) (xy 122.913902 -272.639282) (xy 122.913404 -272.665931)
			(xy 123.141984 -272.665931) (xy 123.141984 -272.612633) (xy 123.149927 -272.559929) (xy 123.165637 -272.508999)
			(xy 123.188763 -272.460978) (xy 123.218787 -272.416941) (xy 123.255039 -272.37787) (xy 123.29671 -272.344639)
			(xy 123.342868 -272.31799) (xy 123.392482 -272.298518) (xy 123.444444 -272.286658) (xy 123.497594 -272.282675)
			(xy 123.550744 -272.286658) (xy 123.602706 -272.298518) (xy 123.65232 -272.31799) (xy 123.698478 -272.344639)
			(xy 123.740149 -272.37787) (xy 123.776401 -272.416941) (xy 123.806425 -272.460978) (xy 123.829551 -272.508999)
			(xy 123.845261 -272.559929) (xy 123.853204 -272.612633) (xy 123.853702 -272.639282) (xy 123.853204 -272.665931)
			(xy 124.081784 -272.665931) (xy 124.081784 -272.612633) (xy 124.089727 -272.559929) (xy 124.105437 -272.508999)
			(xy 124.128563 -272.460978) (xy 124.158587 -272.416941) (xy 124.194839 -272.37787) (xy 124.23651 -272.344639)
			(xy 124.282668 -272.31799) (xy 124.332282 -272.298518) (xy 124.384244 -272.286658) (xy 124.437394 -272.282675)
			(xy 124.490544 -272.286658) (xy 124.542506 -272.298518) (xy 124.59212 -272.31799) (xy 124.638278 -272.344639)
			(xy 124.679949 -272.37787) (xy 124.716201 -272.416941) (xy 124.746225 -272.460978) (xy 124.769351 -272.508999)
			(xy 124.785061 -272.559929) (xy 124.793004 -272.612633) (xy 124.793502 -272.639282) (xy 124.793004 -272.665931)
			(xy 125.021838 -272.665931) (xy 125.021838 -272.612633) (xy 125.029781 -272.559929) (xy 125.045491 -272.508999)
			(xy 125.068617 -272.460978) (xy 125.098641 -272.416941) (xy 125.134893 -272.37787) (xy 125.176564 -272.344639)
			(xy 125.222722 -272.31799) (xy 125.272336 -272.298518) (xy 125.324298 -272.286658) (xy 125.377448 -272.282675)
			(xy 125.430598 -272.286658) (xy 125.48256 -272.298518) (xy 125.532174 -272.31799) (xy 125.578332 -272.344639)
			(xy 125.620003 -272.37787) (xy 125.656255 -272.416941) (xy 125.686279 -272.460978) (xy 125.709405 -272.508999)
			(xy 125.725115 -272.559929) (xy 125.733058 -272.612633) (xy 125.733556 -272.639282) (xy 125.733076 -272.66499)
			(xy 125.990346 -272.66499) (xy 125.990346 -272.613574) (xy 125.998389 -272.562792) (xy 126.014277 -272.513893)
			(xy 126.03762 -272.468081) (xy 126.067841 -272.426485) (xy 126.104197 -272.390129) (xy 126.145793 -272.359908)
			(xy 126.191605 -272.336565) (xy 126.240504 -272.320677) (xy 126.291286 -272.312634) (xy 126.342702 -272.312634)
			(xy 126.393484 -272.320677) (xy 126.442383 -272.336565) (xy 126.488195 -272.359908) (xy 126.529791 -272.390129)
			(xy 126.566147 -272.426485) (xy 126.596368 -272.468081) (xy 126.619711 -272.513893) (xy 126.635599 -272.562792)
			(xy 126.643642 -272.613574) (xy 126.644146 -272.639282) (xy 126.643642 -272.66499) (xy 126.930146 -272.66499)
			(xy 126.930146 -272.613574) (xy 126.938189 -272.562792) (xy 126.954077 -272.513893) (xy 126.97742 -272.468081)
			(xy 127.007641 -272.426485) (xy 127.043997 -272.390129) (xy 127.085593 -272.359908) (xy 127.131405 -272.336565)
			(xy 127.180304 -272.320677) (xy 127.231086 -272.312634) (xy 127.282502 -272.312634) (xy 127.333284 -272.320677)
			(xy 127.382183 -272.336565) (xy 127.427995 -272.359908) (xy 127.469591 -272.390129) (xy 127.505947 -272.426485)
			(xy 127.536168 -272.468081) (xy 127.559511 -272.513893) (xy 127.575399 -272.562792) (xy 127.583442 -272.613574)
			(xy 127.583946 -272.639282) (xy 127.583442 -272.66499) (xy 127.869946 -272.66499) (xy 127.869946 -272.613574)
			(xy 127.877989 -272.562792) (xy 127.893877 -272.513893) (xy 127.91722 -272.468081) (xy 127.947441 -272.426485)
			(xy 127.983797 -272.390129) (xy 128.025393 -272.359908) (xy 128.071205 -272.336565) (xy 128.120104 -272.320677)
			(xy 128.170886 -272.312634) (xy 128.222302 -272.312634) (xy 128.273084 -272.320677) (xy 128.321983 -272.336565)
			(xy 128.367795 -272.359908) (xy 128.409391 -272.390129) (xy 128.445747 -272.426485) (xy 128.475968 -272.468081)
			(xy 128.499311 -272.513893) (xy 128.515199 -272.562792) (xy 128.523242 -272.613574) (xy 128.523746 -272.639282)
			(xy 128.523242 -272.66499) (xy 128.809746 -272.66499) (xy 128.809746 -272.613574) (xy 128.817789 -272.562792)
			(xy 128.833677 -272.513893) (xy 128.85702 -272.468081) (xy 128.887241 -272.426485) (xy 128.923597 -272.390129)
			(xy 128.965193 -272.359908) (xy 129.011005 -272.336565) (xy 129.059904 -272.320677) (xy 129.110686 -272.312634)
			(xy 129.162102 -272.312634) (xy 129.212884 -272.320677) (xy 129.261783 -272.336565) (xy 129.307595 -272.359908)
			(xy 129.349191 -272.390129) (xy 129.385547 -272.426485) (xy 129.415768 -272.468081) (xy 129.439111 -272.513893)
			(xy 129.454999 -272.562792) (xy 129.463042 -272.613574) (xy 129.463546 -272.639282) (xy 129.463042 -272.66499)
			(xy 129.462893 -272.665931) (xy 129.720584 -272.665931) (xy 129.720584 -272.612633) (xy 129.728527 -272.559929)
			(xy 129.744237 -272.508999) (xy 129.767363 -272.460978) (xy 129.797387 -272.416941) (xy 129.833639 -272.37787)
			(xy 129.87531 -272.344639) (xy 129.921468 -272.31799) (xy 129.971082 -272.298518) (xy 130.023044 -272.286658)
			(xy 130.076194 -272.282675) (xy 130.129344 -272.286658) (xy 130.181306 -272.298518) (xy 130.23092 -272.31799)
			(xy 130.277078 -272.344639) (xy 130.318749 -272.37787) (xy 130.355001 -272.416941) (xy 130.385025 -272.460978)
			(xy 130.408151 -272.508999) (xy 130.423861 -272.559929) (xy 130.431804 -272.612633) (xy 130.432302 -272.639282)
			(xy 130.431804 -272.665931) (xy 130.660384 -272.665931) (xy 130.660384 -272.612633) (xy 130.668327 -272.559929)
			(xy 130.684037 -272.508999) (xy 130.707163 -272.460978) (xy 130.737187 -272.416941) (xy 130.773439 -272.37787)
			(xy 130.81511 -272.344639) (xy 130.861268 -272.31799) (xy 130.910882 -272.298518) (xy 130.962844 -272.286658)
			(xy 131.015994 -272.282675) (xy 131.069144 -272.286658) (xy 131.121106 -272.298518) (xy 131.17072 -272.31799)
			(xy 131.216878 -272.344639) (xy 131.258549 -272.37787) (xy 131.294801 -272.416941) (xy 131.324825 -272.460978)
			(xy 131.347951 -272.508999) (xy 131.363661 -272.559929) (xy 131.371604 -272.612633) (xy 131.372102 -272.639282)
			(xy 131.371604 -272.665931) (xy 131.600438 -272.665931) (xy 131.600438 -272.612633) (xy 131.608381 -272.559929)
			(xy 131.624091 -272.508999) (xy 131.647217 -272.460978) (xy 131.677241 -272.416941) (xy 131.713493 -272.37787)
			(xy 131.755164 -272.344639) (xy 131.801322 -272.31799) (xy 131.850936 -272.298518) (xy 131.902898 -272.286658)
			(xy 131.956048 -272.282675) (xy 132.009198 -272.286658) (xy 132.06116 -272.298518) (xy 132.110774 -272.31799)
			(xy 132.156932 -272.344639) (xy 132.198603 -272.37787) (xy 132.234855 -272.416941) (xy 132.264879 -272.460978)
			(xy 132.288005 -272.508999) (xy 132.303715 -272.559929) (xy 132.311658 -272.612633) (xy 132.312156 -272.639282)
			(xy 132.311676 -272.66499) (xy 132.568946 -272.66499) (xy 132.568946 -272.613574) (xy 132.576989 -272.562792)
			(xy 132.592877 -272.513893) (xy 132.61622 -272.468081) (xy 132.646441 -272.426485) (xy 132.682797 -272.390129)
			(xy 132.724393 -272.359908) (xy 132.770205 -272.336565) (xy 132.819104 -272.320677) (xy 132.869886 -272.312634)
			(xy 132.921302 -272.312634) (xy 132.972084 -272.320677) (xy 133.020983 -272.336565) (xy 133.066795 -272.359908)
			(xy 133.108391 -272.390129) (xy 133.144747 -272.426485) (xy 133.174968 -272.468081) (xy 133.198311 -272.513893)
			(xy 133.214199 -272.562792) (xy 133.222242 -272.613574) (xy 133.222746 -272.639282) (xy 133.222242 -272.66499)
			(xy 133.508746 -272.66499) (xy 133.508746 -272.613574) (xy 133.516789 -272.562792) (xy 133.532677 -272.513893)
			(xy 133.55602 -272.468081) (xy 133.586241 -272.426485) (xy 133.622597 -272.390129) (xy 133.664193 -272.359908)
			(xy 133.710005 -272.336565) (xy 133.758904 -272.320677) (xy 133.809686 -272.312634) (xy 133.861102 -272.312634)
			(xy 133.911884 -272.320677) (xy 133.960783 -272.336565) (xy 134.006595 -272.359908) (xy 134.048191 -272.390129)
			(xy 134.084547 -272.426485) (xy 134.114768 -272.468081) (xy 134.138111 -272.513893) (xy 134.153999 -272.562792)
			(xy 134.162042 -272.613574) (xy 134.162546 -272.639282) (xy 134.162042 -272.66499) (xy 134.448546 -272.66499)
			(xy 134.448546 -272.613574) (xy 134.456589 -272.562792) (xy 134.472477 -272.513893) (xy 134.49582 -272.468081)
			(xy 134.526041 -272.426485) (xy 134.562397 -272.390129) (xy 134.603993 -272.359908) (xy 134.649805 -272.336565)
			(xy 134.698704 -272.320677) (xy 134.749486 -272.312634) (xy 134.800902 -272.312634) (xy 134.851684 -272.320677)
			(xy 134.900583 -272.336565) (xy 134.946395 -272.359908) (xy 134.987991 -272.390129) (xy 135.024347 -272.426485)
			(xy 135.054568 -272.468081) (xy 135.077911 -272.513893) (xy 135.093799 -272.562792) (xy 135.101842 -272.613574)
			(xy 135.102346 -272.639282) (xy 135.101842 -272.66499) (xy 135.388346 -272.66499) (xy 135.388346 -272.613574)
			(xy 135.396389 -272.562792) (xy 135.412277 -272.513893) (xy 135.43562 -272.468081) (xy 135.465841 -272.426485)
			(xy 135.502197 -272.390129) (xy 135.543793 -272.359908) (xy 135.589605 -272.336565) (xy 135.638504 -272.320677)
			(xy 135.689286 -272.312634) (xy 135.740702 -272.312634) (xy 135.791484 -272.320677) (xy 135.840383 -272.336565)
			(xy 135.886195 -272.359908) (xy 135.927791 -272.390129) (xy 135.964147 -272.426485) (xy 135.994368 -272.468081)
			(xy 136.017711 -272.513893) (xy 136.033599 -272.562792) (xy 136.041642 -272.613574) (xy 136.042146 -272.639282)
			(xy 136.041642 -272.66499) (xy 136.041493 -272.665931) (xy 136.299184 -272.665931) (xy 136.299184 -272.612633)
			(xy 136.307127 -272.559929) (xy 136.322837 -272.508999) (xy 136.345963 -272.460978) (xy 136.375987 -272.416941)
			(xy 136.412239 -272.37787) (xy 136.45391 -272.344639) (xy 136.500068 -272.31799) (xy 136.549682 -272.298518)
			(xy 136.601644 -272.286658) (xy 136.654794 -272.282675) (xy 136.707944 -272.286658) (xy 136.759906 -272.298518)
			(xy 136.80952 -272.31799) (xy 136.855678 -272.344639) (xy 136.897349 -272.37787) (xy 136.933601 -272.416941)
			(xy 136.963625 -272.460978) (xy 136.986751 -272.508999) (xy 137.002461 -272.559929) (xy 137.010404 -272.612633)
			(xy 137.010902 -272.639282) (xy 137.250681 -272.639282) (xy 137.254711 -272.586784) (xy 137.266708 -272.535516)
			(xy 137.286391 -272.486681) (xy 137.313297 -272.441422) (xy 137.346797 -272.400801) (xy 137.386105 -272.36577)
			(xy 137.4303 -272.33715) (xy 137.478345 -272.315611) (xy 137.529116 -272.301659) (xy 137.581421 -272.295621)
			(xy 137.634035 -272.297638) (xy 137.685725 -272.307662) (xy 137.735278 -272.32546) (xy 137.781534 -272.350613)
			(xy 137.823408 -272.382532) (xy 137.85992 -272.42047) (xy 137.890212 -272.463536) (xy 137.913575 -272.510721)
			(xy 137.929461 -272.56092) (xy 137.937498 -272.612956) (xy 137.938002 -272.639282) (xy 137.937498 -272.665608)
			(xy 137.929461 -272.717644) (xy 137.913575 -272.767843) (xy 137.890212 -272.815028) (xy 137.85992 -272.858094)
			(xy 137.823408 -272.896032) (xy 137.781534 -272.927951) (xy 137.735278 -272.953104) (xy 137.685725 -272.970902)
			(xy 137.634035 -272.980926) (xy 137.581421 -272.982943) (xy 137.529116 -272.976905) (xy 137.478345 -272.962953)
			(xy 137.4303 -272.941414) (xy 137.386105 -272.912794) (xy 137.346797 -272.877763) (xy 137.313297 -272.837142)
			(xy 137.286391 -272.791883) (xy 137.266708 -272.743048) (xy 137.254711 -272.69178) (xy 137.250681 -272.639282)
			(xy 137.010902 -272.639282) (xy 137.010404 -272.665931) (xy 137.002461 -272.718635) (xy 136.986751 -272.769565)
			(xy 136.963625 -272.817586) (xy 136.933601 -272.861623) (xy 136.897349 -272.900694) (xy 136.855678 -272.933925)
			(xy 136.80952 -272.960574) (xy 136.759906 -272.980046) (xy 136.707944 -272.991906) (xy 136.654794 -272.99589)
			(xy 136.601644 -272.991906) (xy 136.549682 -272.980046) (xy 136.500068 -272.960574) (xy 136.45391 -272.933925)
			(xy 136.412239 -272.900694) (xy 136.375987 -272.861623) (xy 136.345963 -272.817586) (xy 136.322837 -272.769565)
			(xy 136.307127 -272.718635) (xy 136.299184 -272.665931) (xy 136.041493 -272.665931) (xy 136.033599 -272.715772)
			(xy 136.017711 -272.764671) (xy 135.994368 -272.810483) (xy 135.964147 -272.852079) (xy 135.927791 -272.888435)
			(xy 135.886195 -272.918656) (xy 135.840383 -272.941999) (xy 135.791484 -272.957887) (xy 135.740702 -272.96593)
			(xy 135.689286 -272.96593) (xy 135.638504 -272.957887) (xy 135.589605 -272.941999) (xy 135.543793 -272.918656)
			(xy 135.502197 -272.888435) (xy 135.465841 -272.852079) (xy 135.43562 -272.810483) (xy 135.412277 -272.764671)
			(xy 135.396389 -272.715772) (xy 135.388346 -272.66499) (xy 135.101842 -272.66499) (xy 135.093799 -272.715772)
			(xy 135.077911 -272.764671) (xy 135.054568 -272.810483) (xy 135.024347 -272.852079) (xy 134.987991 -272.888435)
			(xy 134.946395 -272.918656) (xy 134.900583 -272.941999) (xy 134.851684 -272.957887) (xy 134.800902 -272.96593)
			(xy 134.749486 -272.96593) (xy 134.698704 -272.957887) (xy 134.649805 -272.941999) (xy 134.603993 -272.918656)
			(xy 134.562397 -272.888435) (xy 134.526041 -272.852079) (xy 134.49582 -272.810483) (xy 134.472477 -272.764671)
			(xy 134.456589 -272.715772) (xy 134.448546 -272.66499) (xy 134.162042 -272.66499) (xy 134.153999 -272.715772)
			(xy 134.138111 -272.764671) (xy 134.114768 -272.810483) (xy 134.084547 -272.852079) (xy 134.048191 -272.888435)
			(xy 134.006595 -272.918656) (xy 133.960783 -272.941999) (xy 133.911884 -272.957887) (xy 133.861102 -272.96593)
			(xy 133.809686 -272.96593) (xy 133.758904 -272.957887) (xy 133.710005 -272.941999) (xy 133.664193 -272.918656)
			(xy 133.622597 -272.888435) (xy 133.586241 -272.852079) (xy 133.55602 -272.810483) (xy 133.532677 -272.764671)
			(xy 133.516789 -272.715772) (xy 133.508746 -272.66499) (xy 133.222242 -272.66499) (xy 133.214199 -272.715772)
			(xy 133.198311 -272.764671) (xy 133.174968 -272.810483) (xy 133.144747 -272.852079) (xy 133.108391 -272.888435)
			(xy 133.066795 -272.918656) (xy 133.020983 -272.941999) (xy 132.972084 -272.957887) (xy 132.921302 -272.96593)
			(xy 132.869886 -272.96593) (xy 132.819104 -272.957887) (xy 132.770205 -272.941999) (xy 132.724393 -272.918656)
			(xy 132.682797 -272.888435) (xy 132.646441 -272.852079) (xy 132.61622 -272.810483) (xy 132.592877 -272.764671)
			(xy 132.576989 -272.715772) (xy 132.568946 -272.66499) (xy 132.311676 -272.66499) (xy 132.311658 -272.665931)
			(xy 132.303715 -272.718635) (xy 132.288005 -272.769565) (xy 132.264879 -272.817586) (xy 132.234855 -272.861623)
			(xy 132.198603 -272.900694) (xy 132.156932 -272.933925) (xy 132.110774 -272.960574) (xy 132.06116 -272.980046)
			(xy 132.009198 -272.991906) (xy 131.956048 -272.99589) (xy 131.902898 -272.991906) (xy 131.850936 -272.980046)
			(xy 131.801322 -272.960574) (xy 131.755164 -272.933925) (xy 131.713493 -272.900694) (xy 131.677241 -272.861623)
			(xy 131.647217 -272.817586) (xy 131.624091 -272.769565) (xy 131.608381 -272.718635) (xy 131.600438 -272.665931)
			(xy 131.371604 -272.665931) (xy 131.363661 -272.718635) (xy 131.347951 -272.769565) (xy 131.324825 -272.817586)
			(xy 131.294801 -272.861623) (xy 131.258549 -272.900694) (xy 131.216878 -272.933925) (xy 131.17072 -272.960574)
			(xy 131.121106 -272.980046) (xy 131.069144 -272.991906) (xy 131.015994 -272.99589) (xy 130.962844 -272.991906)
			(xy 130.910882 -272.980046) (xy 130.861268 -272.960574) (xy 130.81511 -272.933925) (xy 130.773439 -272.900694)
			(xy 130.737187 -272.861623) (xy 130.707163 -272.817586) (xy 130.684037 -272.769565) (xy 130.668327 -272.718635)
			(xy 130.660384 -272.665931) (xy 130.431804 -272.665931) (xy 130.423861 -272.718635) (xy 130.408151 -272.769565)
			(xy 130.385025 -272.817586) (xy 130.355001 -272.861623) (xy 130.318749 -272.900694) (xy 130.277078 -272.933925)
			(xy 130.23092 -272.960574) (xy 130.181306 -272.980046) (xy 130.129344 -272.991906) (xy 130.076194 -272.99589)
			(xy 130.023044 -272.991906) (xy 129.971082 -272.980046) (xy 129.921468 -272.960574) (xy 129.87531 -272.933925)
			(xy 129.833639 -272.900694) (xy 129.797387 -272.861623) (xy 129.767363 -272.817586) (xy 129.744237 -272.769565)
			(xy 129.728527 -272.718635) (xy 129.720584 -272.665931) (xy 129.462893 -272.665931) (xy 129.454999 -272.715772)
			(xy 129.439111 -272.764671) (xy 129.415768 -272.810483) (xy 129.385547 -272.852079) (xy 129.349191 -272.888435)
			(xy 129.307595 -272.918656) (xy 129.261783 -272.941999) (xy 129.212884 -272.957887) (xy 129.162102 -272.96593)
			(xy 129.110686 -272.96593) (xy 129.059904 -272.957887) (xy 129.011005 -272.941999) (xy 128.965193 -272.918656)
			(xy 128.923597 -272.888435) (xy 128.887241 -272.852079) (xy 128.85702 -272.810483) (xy 128.833677 -272.764671)
			(xy 128.817789 -272.715772) (xy 128.809746 -272.66499) (xy 128.523242 -272.66499) (xy 128.515199 -272.715772)
			(xy 128.499311 -272.764671) (xy 128.475968 -272.810483) (xy 128.445747 -272.852079) (xy 128.409391 -272.888435)
			(xy 128.367795 -272.918656) (xy 128.321983 -272.941999) (xy 128.273084 -272.957887) (xy 128.222302 -272.96593)
			(xy 128.170886 -272.96593) (xy 128.120104 -272.957887) (xy 128.071205 -272.941999) (xy 128.025393 -272.918656)
			(xy 127.983797 -272.888435) (xy 127.947441 -272.852079) (xy 127.91722 -272.810483) (xy 127.893877 -272.764671)
			(xy 127.877989 -272.715772) (xy 127.869946 -272.66499) (xy 127.583442 -272.66499) (xy 127.575399 -272.715772)
			(xy 127.559511 -272.764671) (xy 127.536168 -272.810483) (xy 127.505947 -272.852079) (xy 127.469591 -272.888435)
			(xy 127.427995 -272.918656) (xy 127.382183 -272.941999) (xy 127.333284 -272.957887) (xy 127.282502 -272.96593)
			(xy 127.231086 -272.96593) (xy 127.180304 -272.957887) (xy 127.131405 -272.941999) (xy 127.085593 -272.918656)
			(xy 127.043997 -272.888435) (xy 127.007641 -272.852079) (xy 126.97742 -272.810483) (xy 126.954077 -272.764671)
			(xy 126.938189 -272.715772) (xy 126.930146 -272.66499) (xy 126.643642 -272.66499) (xy 126.635599 -272.715772)
			(xy 126.619711 -272.764671) (xy 126.596368 -272.810483) (xy 126.566147 -272.852079) (xy 126.529791 -272.888435)
			(xy 126.488195 -272.918656) (xy 126.442383 -272.941999) (xy 126.393484 -272.957887) (xy 126.342702 -272.96593)
			(xy 126.291286 -272.96593) (xy 126.240504 -272.957887) (xy 126.191605 -272.941999) (xy 126.145793 -272.918656)
			(xy 126.104197 -272.888435) (xy 126.067841 -272.852079) (xy 126.03762 -272.810483) (xy 126.014277 -272.764671)
			(xy 125.998389 -272.715772) (xy 125.990346 -272.66499) (xy 125.733076 -272.66499) (xy 125.733058 -272.665931)
			(xy 125.725115 -272.718635) (xy 125.709405 -272.769565) (xy 125.686279 -272.817586) (xy 125.656255 -272.861623)
			(xy 125.620003 -272.900694) (xy 125.578332 -272.933925) (xy 125.532174 -272.960574) (xy 125.48256 -272.980046)
			(xy 125.430598 -272.991906) (xy 125.377448 -272.99589) (xy 125.324298 -272.991906) (xy 125.272336 -272.980046)
			(xy 125.222722 -272.960574) (xy 125.176564 -272.933925) (xy 125.134893 -272.900694) (xy 125.098641 -272.861623)
			(xy 125.068617 -272.817586) (xy 125.045491 -272.769565) (xy 125.029781 -272.718635) (xy 125.021838 -272.665931)
			(xy 124.793004 -272.665931) (xy 124.785061 -272.718635) (xy 124.769351 -272.769565) (xy 124.746225 -272.817586)
			(xy 124.716201 -272.861623) (xy 124.679949 -272.900694) (xy 124.638278 -272.933925) (xy 124.59212 -272.960574)
			(xy 124.542506 -272.980046) (xy 124.490544 -272.991906) (xy 124.437394 -272.99589) (xy 124.384244 -272.991906)
			(xy 124.332282 -272.980046) (xy 124.282668 -272.960574) (xy 124.23651 -272.933925) (xy 124.194839 -272.900694)
			(xy 124.158587 -272.861623) (xy 124.128563 -272.817586) (xy 124.105437 -272.769565) (xy 124.089727 -272.718635)
			(xy 124.081784 -272.665931) (xy 123.853204 -272.665931) (xy 123.845261 -272.718635) (xy 123.829551 -272.769565)
			(xy 123.806425 -272.817586) (xy 123.776401 -272.861623) (xy 123.740149 -272.900694) (xy 123.698478 -272.933925)
			(xy 123.65232 -272.960574) (xy 123.602706 -272.980046) (xy 123.550744 -272.991906) (xy 123.497594 -272.99589)
			(xy 123.444444 -272.991906) (xy 123.392482 -272.980046) (xy 123.342868 -272.960574) (xy 123.29671 -272.933925)
			(xy 123.255039 -272.900694) (xy 123.218787 -272.861623) (xy 123.188763 -272.817586) (xy 123.165637 -272.769565)
			(xy 123.149927 -272.718635) (xy 123.141984 -272.665931) (xy 122.913404 -272.665931) (xy 122.905461 -272.718635)
			(xy 122.889751 -272.769565) (xy 122.866625 -272.817586) (xy 122.836601 -272.861623) (xy 122.800349 -272.900694)
			(xy 122.758678 -272.933925) (xy 122.71252 -272.960574) (xy 122.662906 -272.980046) (xy 122.610944 -272.991906)
			(xy 122.557794 -272.99589) (xy 122.504644 -272.991906) (xy 122.452682 -272.980046) (xy 122.403068 -272.960574)
			(xy 122.35691 -272.933925) (xy 122.315239 -272.900694) (xy 122.278987 -272.861623) (xy 122.248963 -272.817586)
			(xy 122.225837 -272.769565) (xy 122.210127 -272.718635) (xy 122.202184 -272.665931) (xy 121.973604 -272.665931)
			(xy 121.965661 -272.718635) (xy 121.949951 -272.769565) (xy 121.926825 -272.817586) (xy 121.896801 -272.861623)
			(xy 121.860549 -272.900694) (xy 121.818878 -272.933925) (xy 121.77272 -272.960574) (xy 121.723106 -272.980046)
			(xy 121.671144 -272.991906) (xy 121.617994 -272.99589) (xy 121.564844 -272.991906) (xy 121.512882 -272.980046)
			(xy 121.463268 -272.960574) (xy 121.41711 -272.933925) (xy 121.375439 -272.900694) (xy 121.339187 -272.861623)
			(xy 121.309163 -272.817586) (xy 121.286037 -272.769565) (xy 121.270327 -272.718635) (xy 121.262384 -272.665931)
			(xy 121.033804 -272.665931) (xy 121.025861 -272.718635) (xy 121.010151 -272.769565) (xy 120.987025 -272.817586)
			(xy 120.957001 -272.861623) (xy 120.920749 -272.900694) (xy 120.879078 -272.933925) (xy 120.83292 -272.960574)
			(xy 120.783306 -272.980046) (xy 120.731344 -272.991906) (xy 120.678194 -272.99589) (xy 120.625044 -272.991906)
			(xy 120.573082 -272.980046) (xy 120.523468 -272.960574) (xy 120.47731 -272.933925) (xy 120.435639 -272.900694)
			(xy 120.399387 -272.861623) (xy 120.369363 -272.817586) (xy 120.346237 -272.769565) (xy 120.330527 -272.718635)
			(xy 120.322584 -272.665931) (xy 120.094004 -272.665931) (xy 120.086061 -272.718635) (xy 120.070351 -272.769565)
			(xy 120.047225 -272.817586) (xy 120.017201 -272.861623) (xy 119.980949 -272.900694) (xy 119.939278 -272.933925)
			(xy 119.89312 -272.960574) (xy 119.843506 -272.980046) (xy 119.791544 -272.991906) (xy 119.738394 -272.99589)
			(xy 119.685244 -272.991906) (xy 119.633282 -272.980046) (xy 119.583668 -272.960574) (xy 119.53751 -272.933925)
			(xy 119.495839 -272.900694) (xy 119.459587 -272.861623) (xy 119.429563 -272.817586) (xy 119.406437 -272.769565)
			(xy 119.390727 -272.718635) (xy 119.382784 -272.665931) (xy 119.154204 -272.665931) (xy 119.146261 -272.718635)
			(xy 119.130551 -272.769565) (xy 119.107425 -272.817586) (xy 119.077401 -272.861623) (xy 119.041149 -272.900694)
			(xy 118.999478 -272.933925) (xy 118.95332 -272.960574) (xy 118.903706 -272.980046) (xy 118.851744 -272.991906)
			(xy 118.798594 -272.99589) (xy 118.745444 -272.991906) (xy 118.693482 -272.980046) (xy 118.643868 -272.960574)
			(xy 118.59771 -272.933925) (xy 118.556039 -272.900694) (xy 118.519787 -272.861623) (xy 118.489763 -272.817586)
			(xy 118.466637 -272.769565) (xy 118.450927 -272.718635) (xy 118.442984 -272.665931) (xy 118.214404 -272.665931)
			(xy 118.206461 -272.718635) (xy 118.190751 -272.769565) (xy 118.167625 -272.817586) (xy 118.137601 -272.861623)
			(xy 118.101349 -272.900694) (xy 118.059678 -272.933925) (xy 118.01352 -272.960574) (xy 117.963906 -272.980046)
			(xy 117.911944 -272.991906) (xy 117.858794 -272.99589) (xy 117.805644 -272.991906) (xy 117.753682 -272.980046)
			(xy 117.704068 -272.960574) (xy 117.65791 -272.933925) (xy 117.616239 -272.900694) (xy 117.579987 -272.861623)
			(xy 117.549963 -272.817586) (xy 117.526837 -272.769565) (xy 117.511127 -272.718635) (xy 117.503184 -272.665931)
			(xy 117.274604 -272.665931) (xy 117.266661 -272.718635) (xy 117.250951 -272.769565) (xy 117.227825 -272.817586)
			(xy 117.197801 -272.861623) (xy 117.161549 -272.900694) (xy 117.119878 -272.933925) (xy 117.07372 -272.960574)
			(xy 117.024106 -272.980046) (xy 116.972144 -272.991906) (xy 116.918994 -272.99589) (xy 116.865844 -272.991906)
			(xy 116.813882 -272.980046) (xy 116.764268 -272.960574) (xy 116.71811 -272.933925) (xy 116.676439 -272.900694)
			(xy 116.640187 -272.861623) (xy 116.610163 -272.817586) (xy 116.587037 -272.769565) (xy 116.571327 -272.718635)
			(xy 116.563384 -272.665931) (xy 116.334804 -272.665931) (xy 116.326861 -272.718635) (xy 116.311151 -272.769565)
			(xy 116.288025 -272.817586) (xy 116.258001 -272.861623) (xy 116.221749 -272.900694) (xy 116.180078 -272.933925)
			(xy 116.13392 -272.960574) (xy 116.084306 -272.980046) (xy 116.032344 -272.991906) (xy 115.979194 -272.99589)
			(xy 115.926044 -272.991906) (xy 115.874082 -272.980046) (xy 115.824468 -272.960574) (xy 115.77831 -272.933925)
			(xy 115.736639 -272.900694) (xy 115.700387 -272.861623) (xy 115.670363 -272.817586) (xy 115.647237 -272.769565)
			(xy 115.631527 -272.718635) (xy 115.623584 -272.665931) (xy 115.395004 -272.665931) (xy 115.387061 -272.718635)
			(xy 115.371351 -272.769565) (xy 115.348225 -272.817586) (xy 115.318201 -272.861623) (xy 115.281949 -272.900694)
			(xy 115.240278 -272.933925) (xy 115.19412 -272.960574) (xy 115.144506 -272.980046) (xy 115.092544 -272.991906)
			(xy 115.039394 -272.99589) (xy 114.986244 -272.991906) (xy 114.934282 -272.980046) (xy 114.884668 -272.960574)
			(xy 114.83851 -272.933925) (xy 114.796839 -272.900694) (xy 114.760587 -272.861623) (xy 114.730563 -272.817586)
			(xy 114.707437 -272.769565) (xy 114.691727 -272.718635) (xy 114.683784 -272.665931) (xy 114.454338 -272.665931)
			(xy 114.45304 -272.686827) (xy 114.442645 -272.736785) (xy 114.425229 -272.784749) (xy 114.413538 -272.80743)
			(xy 114.407442 -272.81886) (xy 114.407442 -272.97126) (xy 114.414808 -272.983452) (xy 114.425742 -273.001949)
			(xy 114.446069 -273.039812) (xy 114.455448 -273.059144) (xy 114.461798 -273.072098) (xy 114.508026 -273.101816)
			(xy 114.52606 -273.09953) (xy 114.536877 -273.098318) (xy 114.558609 -273.097048) (xy 114.569494 -273.09699)
			(xy 114.596146 -273.097463) (xy 114.648854 -273.105406) (xy 114.699789 -273.121117) (xy 114.747814 -273.144244)
			(xy 114.791855 -273.17427) (xy 114.830929 -273.210525) (xy 114.864164 -273.252199) (xy 114.890815 -273.298361)
			(xy 114.910289 -273.347979) (xy 114.922151 -273.399946) (xy 114.926134 -273.4531) (xy 114.924137 -273.479747)
			(xy 115.153684 -273.479747) (xy 115.153684 -273.426449) (xy 115.161627 -273.373745) (xy 115.177337 -273.322815)
			(xy 115.200463 -273.274794) (xy 115.230487 -273.230757) (xy 115.266739 -273.191686) (xy 115.30841 -273.158455)
			(xy 115.354568 -273.131806) (xy 115.404182 -273.112334) (xy 115.456144 -273.100474) (xy 115.509294 -273.096491)
			(xy 115.562444 -273.100474) (xy 115.614406 -273.112334) (xy 115.66402 -273.131806) (xy 115.710178 -273.158455)
			(xy 115.751849 -273.191686) (xy 115.788101 -273.230757) (xy 115.818125 -273.274794) (xy 115.841251 -273.322815)
			(xy 115.856961 -273.373745) (xy 115.864904 -273.426449) (xy 115.865402 -273.453098) (xy 115.864904 -273.479747)
			(xy 115.856961 -273.532451) (xy 115.841251 -273.583381) (xy 115.818125 -273.631402) (xy 115.788101 -273.675439)
			(xy 115.751849 -273.71451) (xy 115.710178 -273.747741) (xy 115.66402 -273.77439) (xy 115.614406 -273.793862)
			(xy 115.562444 -273.805722) (xy 115.509294 -273.809706) (xy 115.456144 -273.805722) (xy 115.404182 -273.793862)
			(xy 115.354568 -273.77439) (xy 115.30841 -273.747741) (xy 115.266739 -273.71451) (xy 115.230487 -273.675439)
			(xy 115.200463 -273.631402) (xy 115.177337 -273.583381) (xy 115.161627 -273.532451) (xy 115.153684 -273.479747)
			(xy 114.924137 -273.479747) (xy 114.922151 -273.506254) (xy 114.910289 -273.558221) (xy 114.890815 -273.607839)
			(xy 114.864164 -273.654001) (xy 114.830929 -273.695675) (xy 114.791855 -273.73193) (xy 114.747814 -273.761956)
			(xy 114.699789 -273.785083) (xy 114.648854 -273.800794) (xy 114.596146 -273.808737) (xy 114.569494 -273.809206)
			(xy 114.555852 -273.809108) (xy 114.528644 -273.807072) (xy 114.515138 -273.805142) (xy 114.477546 -273.7993)
			(xy 114.44732 -273.864324) (xy 114.469926 -273.890486) (xy 114.634264 -274.054824) (xy 114.656108 -274.055586)
			(xy 114.754406 -274.051776) (xy 114.769138 -274.035012) (xy 114.769392 -274.034758) (xy 114.786384 -274.01567)
			(xy 114.824896 -273.98208) (xy 114.867813 -273.954337) (xy 114.914254 -273.933012) (xy 114.963266 -273.918542)
			(xy 115.013843 -273.911225) (xy 115.039394 -273.910806) (xy 115.065298 -273.911272) (xy 115.116559 -273.918781)
			(xy 115.16619 -273.933641) (xy 115.213144 -273.955538) (xy 115.256427 -273.98401) (xy 115.295126 -274.018455)
			(xy 115.328423 -274.058146) (xy 115.355616 -274.102244) (xy 115.376129 -274.149818) (xy 115.38331 -274.174712)
			(xy 115.432899 -274.168408) (xy 115.532819 -274.165352) (xy 115.5827 -274.168616) (xy 115.60048 -274.169886)
			(xy 115.647216 -274.137882) (xy 115.653058 -274.124674) (xy 115.663801 -274.101191) (xy 115.691064 -274.057335)
			(xy 115.724373 -274.017874) (xy 115.76303 -273.983636) (xy 115.806225 -273.955338) (xy 115.853053 -273.933573)
			(xy 115.902533 -273.918797) (xy 115.953629 -273.911319) (xy 115.979448 -273.910806) (xy 115.990333 -273.910857)
			(xy 116.012065 -273.912128) (xy 116.022882 -273.913346) (xy 116.040916 -273.915632) (xy 116.087144 -273.885914)
			(xy 116.093494 -273.87296) (xy 116.10999 -273.839193) (xy 116.147759 -273.774215) (xy 116.168932 -273.743166)
			(xy 116.17325 -273.73707) (xy 116.182648 -273.707606) (xy 116.171472 -273.67611) (xy 116.166646 -273.66976)
			(xy 116.1494 -273.64628) (xy 116.121984 -273.594881) (xy 116.103297 -273.539706) (xy 116.093835 -273.482225)
			(xy 116.09324 -273.453098) (xy 116.093761 -273.425114) (xy 116.102517 -273.369836) (xy 116.119814 -273.316608)
			(xy 116.145225 -273.266741) (xy 116.178124 -273.221464) (xy 116.217702 -273.181892) (xy 116.262984 -273.148999)
			(xy 116.312854 -273.123595) (xy 116.366084 -273.106305) (xy 116.421364 -273.097557) (xy 116.449348 -273.09699)
			(xy 116.45011 -273.09699) (xy 116.465816 -273.097169) (xy 116.497104 -273.099971) (xy 116.512594 -273.102578)
			(xy 116.517166 -273.10334) (xy 116.762022 -273.10334) (xy 116.786352 -273.10378) (xy 116.834537 -273.11056)
			(xy 116.88132 -273.123944) (xy 116.9258 -273.143676) (xy 116.94668 -273.156172) (xy 116.952522 -273.159728)
			(xy 116.983002 -273.168872) (xy 116.996972 -273.165062) (xy 117.016456 -273.159988) (xy 117.056343 -273.154502)
			(xy 117.076474 -273.15414) (xy 117.195092 -273.15414) (xy 117.20703 -273.147028) (xy 117.227773 -273.135142)
			(xy 117.271764 -273.116422) (xy 117.317864 -273.103754) (xy 117.365244 -273.097365) (xy 117.389148 -273.09699)
			(xy 117.415795 -273.097491) (xy 117.468493 -273.105441) (xy 117.519418 -273.121155) (xy 117.567433 -273.144283)
			(xy 117.611464 -273.174309) (xy 117.650529 -273.210561) (xy 117.683755 -273.25223) (xy 117.7104 -273.298385)
			(xy 117.729869 -273.347996) (xy 117.741727 -273.399955) (xy 117.74571 -273.4531) (xy 117.743713 -273.479747)
			(xy 117.973338 -273.479747) (xy 117.973338 -273.426449) (xy 117.981281 -273.373745) (xy 117.996991 -273.322815)
			(xy 118.020117 -273.274794) (xy 118.050141 -273.230757) (xy 118.086393 -273.191686) (xy 118.128064 -273.158455)
			(xy 118.174222 -273.131806) (xy 118.223836 -273.112334) (xy 118.275798 -273.100474) (xy 118.328948 -273.096491)
			(xy 118.382098 -273.100474) (xy 118.43406 -273.112334) (xy 118.483674 -273.131806) (xy 118.529832 -273.158455)
			(xy 118.571503 -273.191686) (xy 118.607755 -273.230757) (xy 118.637779 -273.274794) (xy 118.660905 -273.322815)
			(xy 118.676615 -273.373745) (xy 118.684558 -273.426449) (xy 118.685056 -273.453098) (xy 118.684558 -273.479747)
			(xy 118.913138 -273.479747) (xy 118.913138 -273.426449) (xy 118.921081 -273.373745) (xy 118.936791 -273.322815)
			(xy 118.959917 -273.274794) (xy 118.989941 -273.230757) (xy 119.026193 -273.191686) (xy 119.067864 -273.158455)
			(xy 119.114022 -273.131806) (xy 119.163636 -273.112334) (xy 119.215598 -273.100474) (xy 119.268748 -273.096491)
			(xy 119.321898 -273.100474) (xy 119.37386 -273.112334) (xy 119.423474 -273.131806) (xy 119.469632 -273.158455)
			(xy 119.511303 -273.191686) (xy 119.547555 -273.230757) (xy 119.577579 -273.274794) (xy 119.600705 -273.322815)
			(xy 119.616415 -273.373745) (xy 119.624358 -273.426449) (xy 119.624856 -273.453098) (xy 119.624358 -273.479747)
			(xy 119.852938 -273.479747) (xy 119.852938 -273.426449) (xy 119.860881 -273.373745) (xy 119.876591 -273.322815)
			(xy 119.899717 -273.274794) (xy 119.929741 -273.230757) (xy 119.965993 -273.191686) (xy 120.007664 -273.158455)
			(xy 120.053822 -273.131806) (xy 120.103436 -273.112334) (xy 120.155398 -273.100474) (xy 120.208548 -273.096491)
			(xy 120.261698 -273.100474) (xy 120.31366 -273.112334) (xy 120.363274 -273.131806) (xy 120.409432 -273.158455)
			(xy 120.451103 -273.191686) (xy 120.487355 -273.230757) (xy 120.517379 -273.274794) (xy 120.540505 -273.322815)
			(xy 120.556215 -273.373745) (xy 120.564158 -273.426449) (xy 120.564656 -273.453098) (xy 120.564158 -273.479747)
			(xy 120.792738 -273.479747) (xy 120.792738 -273.426449) (xy 120.800681 -273.373745) (xy 120.816391 -273.322815)
			(xy 120.839517 -273.274794) (xy 120.869541 -273.230757) (xy 120.905793 -273.191686) (xy 120.947464 -273.158455)
			(xy 120.993622 -273.131806) (xy 121.043236 -273.112334) (xy 121.095198 -273.100474) (xy 121.148348 -273.096491)
			(xy 121.201498 -273.100474) (xy 121.25346 -273.112334) (xy 121.303074 -273.131806) (xy 121.349232 -273.158455)
			(xy 121.390903 -273.191686) (xy 121.427155 -273.230757) (xy 121.457179 -273.274794) (xy 121.480305 -273.322815)
			(xy 121.496015 -273.373745) (xy 121.503958 -273.426449) (xy 121.504456 -273.453098) (xy 121.503958 -273.479747)
			(xy 121.732538 -273.479747) (xy 121.732538 -273.426449) (xy 121.740481 -273.373745) (xy 121.756191 -273.322815)
			(xy 121.779317 -273.274794) (xy 121.809341 -273.230757) (xy 121.845593 -273.191686) (xy 121.887264 -273.158455)
			(xy 121.933422 -273.131806) (xy 121.983036 -273.112334) (xy 122.034998 -273.100474) (xy 122.088148 -273.096491)
			(xy 122.141298 -273.100474) (xy 122.19326 -273.112334) (xy 122.242874 -273.131806) (xy 122.289032 -273.158455)
			(xy 122.330703 -273.191686) (xy 122.366955 -273.230757) (xy 122.396979 -273.274794) (xy 122.420105 -273.322815)
			(xy 122.435815 -273.373745) (xy 122.443758 -273.426449) (xy 122.444256 -273.453098) (xy 122.443758 -273.479747)
			(xy 122.672084 -273.479747) (xy 122.672084 -273.426449) (xy 122.680027 -273.373745) (xy 122.695737 -273.322815)
			(xy 122.718863 -273.274794) (xy 122.748887 -273.230757) (xy 122.785139 -273.191686) (xy 122.82681 -273.158455)
			(xy 122.872968 -273.131806) (xy 122.922582 -273.112334) (xy 122.974544 -273.100474) (xy 123.027694 -273.096491)
			(xy 123.080844 -273.100474) (xy 123.132806 -273.112334) (xy 123.18242 -273.131806) (xy 123.228578 -273.158455)
			(xy 123.270249 -273.191686) (xy 123.306501 -273.230757) (xy 123.336525 -273.274794) (xy 123.359651 -273.322815)
			(xy 123.375361 -273.373745) (xy 123.383304 -273.426449) (xy 123.383802 -273.453098) (xy 123.383322 -273.478806)
			(xy 123.6411 -273.478806) (xy 123.6411 -273.42739) (xy 123.649143 -273.376608) (xy 123.665031 -273.327709)
			(xy 123.688374 -273.281897) (xy 123.718595 -273.240301) (xy 123.754951 -273.203945) (xy 123.796547 -273.173724)
			(xy 123.842359 -273.150381) (xy 123.891258 -273.134493) (xy 123.94204 -273.12645) (xy 123.993456 -273.12645)
			(xy 124.044238 -273.134493) (xy 124.093137 -273.150381) (xy 124.138949 -273.173724) (xy 124.180545 -273.203945)
			(xy 124.216901 -273.240301) (xy 124.247122 -273.281897) (xy 124.270465 -273.327709) (xy 124.286353 -273.376608)
			(xy 124.294396 -273.42739) (xy 124.2949 -273.453098) (xy 124.294396 -273.478806) (xy 124.5809 -273.478806)
			(xy 124.5809 -273.42739) (xy 124.588943 -273.376608) (xy 124.604831 -273.327709) (xy 124.628174 -273.281897)
			(xy 124.658395 -273.240301) (xy 124.694751 -273.203945) (xy 124.736347 -273.173724) (xy 124.782159 -273.150381)
			(xy 124.831058 -273.134493) (xy 124.88184 -273.12645) (xy 124.933256 -273.12645) (xy 124.984038 -273.134493)
			(xy 125.032937 -273.150381) (xy 125.078749 -273.173724) (xy 125.120345 -273.203945) (xy 125.156701 -273.240301)
			(xy 125.186922 -273.281897) (xy 125.210265 -273.327709) (xy 125.226153 -273.376608) (xy 125.234196 -273.42739)
			(xy 125.2347 -273.453098) (xy 125.234196 -273.478806) (xy 125.234047 -273.479747) (xy 125.491738 -273.479747)
			(xy 125.491738 -273.426449) (xy 125.499681 -273.373745) (xy 125.515391 -273.322815) (xy 125.538517 -273.274794)
			(xy 125.568541 -273.230757) (xy 125.604793 -273.191686) (xy 125.646464 -273.158455) (xy 125.692622 -273.131806)
			(xy 125.742236 -273.112334) (xy 125.794198 -273.100474) (xy 125.847348 -273.096491) (xy 125.900498 -273.100474)
			(xy 125.95246 -273.112334) (xy 126.002074 -273.131806) (xy 126.048232 -273.158455) (xy 126.089903 -273.191686)
			(xy 126.126155 -273.230757) (xy 126.156179 -273.274794) (xy 126.179305 -273.322815) (xy 126.195015 -273.373745)
			(xy 126.202958 -273.426449) (xy 126.203456 -273.453098) (xy 126.202976 -273.478806) (xy 126.4605 -273.478806)
			(xy 126.4605 -273.42739) (xy 126.468543 -273.376608) (xy 126.484431 -273.327709) (xy 126.507774 -273.281897)
			(xy 126.537995 -273.240301) (xy 126.574351 -273.203945) (xy 126.615947 -273.173724) (xy 126.661759 -273.150381)
			(xy 126.710658 -273.134493) (xy 126.76144 -273.12645) (xy 126.812856 -273.12645) (xy 126.863638 -273.134493)
			(xy 126.912537 -273.150381) (xy 126.958349 -273.173724) (xy 126.999945 -273.203945) (xy 127.036301 -273.240301)
			(xy 127.066522 -273.281897) (xy 127.089865 -273.327709) (xy 127.105753 -273.376608) (xy 127.113796 -273.42739)
			(xy 127.1143 -273.453098) (xy 127.113796 -273.478806) (xy 127.113647 -273.479747) (xy 127.371338 -273.479747)
			(xy 127.371338 -273.426449) (xy 127.379281 -273.373745) (xy 127.394991 -273.322815) (xy 127.418117 -273.274794)
			(xy 127.448141 -273.230757) (xy 127.484393 -273.191686) (xy 127.526064 -273.158455) (xy 127.572222 -273.131806)
			(xy 127.621836 -273.112334) (xy 127.673798 -273.100474) (xy 127.726948 -273.096491) (xy 127.780098 -273.100474)
			(xy 127.83206 -273.112334) (xy 127.881674 -273.131806) (xy 127.927832 -273.158455) (xy 127.969503 -273.191686)
			(xy 128.005755 -273.230757) (xy 128.035779 -273.274794) (xy 128.058905 -273.322815) (xy 128.074615 -273.373745)
			(xy 128.082558 -273.426449) (xy 128.083056 -273.453098) (xy 128.082576 -273.478806) (xy 128.3401 -273.478806)
			(xy 128.3401 -273.42739) (xy 128.348143 -273.376608) (xy 128.364031 -273.327709) (xy 128.387374 -273.281897)
			(xy 128.417595 -273.240301) (xy 128.453951 -273.203945) (xy 128.495547 -273.173724) (xy 128.541359 -273.150381)
			(xy 128.590258 -273.134493) (xy 128.64104 -273.12645) (xy 128.692456 -273.12645) (xy 128.743238 -273.134493)
			(xy 128.792137 -273.150381) (xy 128.837949 -273.173724) (xy 128.879545 -273.203945) (xy 128.915901 -273.240301)
			(xy 128.946122 -273.281897) (xy 128.969465 -273.327709) (xy 128.985353 -273.376608) (xy 128.993396 -273.42739)
			(xy 128.9939 -273.453098) (xy 128.993396 -273.478806) (xy 128.993247 -273.479747) (xy 129.250938 -273.479747)
			(xy 129.250938 -273.426449) (xy 129.258881 -273.373745) (xy 129.274591 -273.322815) (xy 129.297717 -273.274794)
			(xy 129.327741 -273.230757) (xy 129.363993 -273.191686) (xy 129.405664 -273.158455) (xy 129.451822 -273.131806)
			(xy 129.501436 -273.112334) (xy 129.553398 -273.100474) (xy 129.606548 -273.096491) (xy 129.659698 -273.100474)
			(xy 129.71166 -273.112334) (xy 129.761274 -273.131806) (xy 129.807432 -273.158455) (xy 129.849103 -273.191686)
			(xy 129.885355 -273.230757) (xy 129.915379 -273.274794) (xy 129.938505 -273.322815) (xy 129.954215 -273.373745)
			(xy 129.962158 -273.426449) (xy 129.962656 -273.453098) (xy 129.962176 -273.478806) (xy 130.2197 -273.478806)
			(xy 130.2197 -273.42739) (xy 130.227743 -273.376608) (xy 130.243631 -273.327709) (xy 130.266974 -273.281897)
			(xy 130.297195 -273.240301) (xy 130.333551 -273.203945) (xy 130.375147 -273.173724) (xy 130.420959 -273.150381)
			(xy 130.469858 -273.134493) (xy 130.52064 -273.12645) (xy 130.572056 -273.12645) (xy 130.622838 -273.134493)
			(xy 130.671737 -273.150381) (xy 130.717549 -273.173724) (xy 130.759145 -273.203945) (xy 130.795501 -273.240301)
			(xy 130.825722 -273.281897) (xy 130.849065 -273.327709) (xy 130.864953 -273.376608) (xy 130.872996 -273.42739)
			(xy 130.8735 -273.453098) (xy 130.872996 -273.478806) (xy 131.1595 -273.478806) (xy 131.1595 -273.42739)
			(xy 131.167543 -273.376608) (xy 131.183431 -273.327709) (xy 131.206774 -273.281897) (xy 131.236995 -273.240301)
			(xy 131.273351 -273.203945) (xy 131.314947 -273.173724) (xy 131.360759 -273.150381) (xy 131.409658 -273.134493)
			(xy 131.46044 -273.12645) (xy 131.511856 -273.12645) (xy 131.562638 -273.134493) (xy 131.611537 -273.150381)
			(xy 131.657349 -273.173724) (xy 131.698945 -273.203945) (xy 131.735301 -273.240301) (xy 131.765522 -273.281897)
			(xy 131.788865 -273.327709) (xy 131.804753 -273.376608) (xy 131.812796 -273.42739) (xy 131.8133 -273.453098)
			(xy 131.812796 -273.478806) (xy 131.812647 -273.479747) (xy 132.070338 -273.479747) (xy 132.070338 -273.426449)
			(xy 132.078281 -273.373745) (xy 132.093991 -273.322815) (xy 132.117117 -273.274794) (xy 132.147141 -273.230757)
			(xy 132.183393 -273.191686) (xy 132.225064 -273.158455) (xy 132.271222 -273.131806) (xy 132.320836 -273.112334)
			(xy 132.372798 -273.100474) (xy 132.425948 -273.096491) (xy 132.479098 -273.100474) (xy 132.53106 -273.112334)
			(xy 132.580674 -273.131806) (xy 132.626832 -273.158455) (xy 132.668503 -273.191686) (xy 132.704755 -273.230757)
			(xy 132.734779 -273.274794) (xy 132.757905 -273.322815) (xy 132.773615 -273.373745) (xy 132.781558 -273.426449)
			(xy 132.782056 -273.453098) (xy 132.781576 -273.478806) (xy 133.0391 -273.478806) (xy 133.0391 -273.42739)
			(xy 133.047143 -273.376608) (xy 133.063031 -273.327709) (xy 133.086374 -273.281897) (xy 133.116595 -273.240301)
			(xy 133.152951 -273.203945) (xy 133.194547 -273.173724) (xy 133.240359 -273.150381) (xy 133.289258 -273.134493)
			(xy 133.34004 -273.12645) (xy 133.391456 -273.12645) (xy 133.442238 -273.134493) (xy 133.491137 -273.150381)
			(xy 133.536949 -273.173724) (xy 133.578545 -273.203945) (xy 133.614901 -273.240301) (xy 133.645122 -273.281897)
			(xy 133.668465 -273.327709) (xy 133.684353 -273.376608) (xy 133.692396 -273.42739) (xy 133.6929 -273.453098)
			(xy 133.692396 -273.478806) (xy 133.692247 -273.479747) (xy 133.949938 -273.479747) (xy 133.949938 -273.426449)
			(xy 133.957881 -273.373745) (xy 133.973591 -273.322815) (xy 133.996717 -273.274794) (xy 134.026741 -273.230757)
			(xy 134.062993 -273.191686) (xy 134.104664 -273.158455) (xy 134.150822 -273.131806) (xy 134.200436 -273.112334)
			(xy 134.252398 -273.100474) (xy 134.305548 -273.096491) (xy 134.358698 -273.100474) (xy 134.41066 -273.112334)
			(xy 134.460274 -273.131806) (xy 134.506432 -273.158455) (xy 134.548103 -273.191686) (xy 134.584355 -273.230757)
			(xy 134.614379 -273.274794) (xy 134.637505 -273.322815) (xy 134.653215 -273.373745) (xy 134.661158 -273.426449)
			(xy 134.661656 -273.453098) (xy 134.661176 -273.478806) (xy 134.9187 -273.478806) (xy 134.9187 -273.42739)
			(xy 134.926743 -273.376608) (xy 134.942631 -273.327709) (xy 134.965974 -273.281897) (xy 134.996195 -273.240301)
			(xy 135.032551 -273.203945) (xy 135.074147 -273.173724) (xy 135.119959 -273.150381) (xy 135.168858 -273.134493)
			(xy 135.21964 -273.12645) (xy 135.271056 -273.12645) (xy 135.321838 -273.134493) (xy 135.370737 -273.150381)
			(xy 135.416549 -273.173724) (xy 135.458145 -273.203945) (xy 135.494501 -273.240301) (xy 135.524722 -273.281897)
			(xy 135.548065 -273.327709) (xy 135.563953 -273.376608) (xy 135.571996 -273.42739) (xy 135.5725 -273.453098)
			(xy 135.571996 -273.478806) (xy 135.571847 -273.479747) (xy 135.829284 -273.479747) (xy 135.829284 -273.426449)
			(xy 135.837227 -273.373745) (xy 135.852937 -273.322815) (xy 135.876063 -273.274794) (xy 135.906087 -273.230757)
			(xy 135.942339 -273.191686) (xy 135.98401 -273.158455) (xy 136.030168 -273.131806) (xy 136.079782 -273.112334)
			(xy 136.131744 -273.100474) (xy 136.184894 -273.096491) (xy 136.238044 -273.100474) (xy 136.290006 -273.112334)
			(xy 136.33962 -273.131806) (xy 136.385778 -273.158455) (xy 136.427449 -273.191686) (xy 136.463701 -273.230757)
			(xy 136.493725 -273.274794) (xy 136.516851 -273.322815) (xy 136.532561 -273.373745) (xy 136.540504 -273.426449)
			(xy 136.541002 -273.453098) (xy 136.780781 -273.453098) (xy 136.784811 -273.4006) (xy 136.796808 -273.349332)
			(xy 136.816491 -273.300497) (xy 136.843397 -273.255238) (xy 136.876897 -273.214617) (xy 136.916205 -273.179586)
			(xy 136.9604 -273.150966) (xy 137.008445 -273.129427) (xy 137.059216 -273.115475) (xy 137.111521 -273.109437)
			(xy 137.164135 -273.111454) (xy 137.215825 -273.121478) (xy 137.265378 -273.139276) (xy 137.311634 -273.164429)
			(xy 137.353508 -273.196348) (xy 137.39002 -273.234286) (xy 137.420312 -273.277352) (xy 137.443675 -273.324537)
			(xy 137.459561 -273.374736) (xy 137.467598 -273.426772) (xy 137.468102 -273.453098) (xy 137.467598 -273.479424)
			(xy 137.459561 -273.53146) (xy 137.443675 -273.581659) (xy 137.420312 -273.628844) (xy 137.39002 -273.67191)
			(xy 137.353508 -273.709848) (xy 137.311634 -273.741767) (xy 137.265378 -273.76692) (xy 137.215825 -273.784718)
			(xy 137.164135 -273.794742) (xy 137.111521 -273.796759) (xy 137.059216 -273.790721) (xy 137.008445 -273.776769)
			(xy 136.9604 -273.75523) (xy 136.916205 -273.72661) (xy 136.876897 -273.691579) (xy 136.843397 -273.650958)
			(xy 136.816491 -273.605699) (xy 136.796808 -273.556864) (xy 136.784811 -273.505596) (xy 136.780781 -273.453098)
			(xy 136.541002 -273.453098) (xy 136.540504 -273.479747) (xy 136.532561 -273.532451) (xy 136.516851 -273.583381)
			(xy 136.493725 -273.631402) (xy 136.463701 -273.675439) (xy 136.427449 -273.71451) (xy 136.385778 -273.747741)
			(xy 136.33962 -273.77439) (xy 136.290006 -273.793862) (xy 136.238044 -273.805722) (xy 136.184894 -273.809706)
			(xy 136.131744 -273.805722) (xy 136.079782 -273.793862) (xy 136.030168 -273.77439) (xy 135.98401 -273.747741)
			(xy 135.942339 -273.71451) (xy 135.906087 -273.675439) (xy 135.876063 -273.631402) (xy 135.852937 -273.583381)
			(xy 135.837227 -273.532451) (xy 135.829284 -273.479747) (xy 135.571847 -273.479747) (xy 135.563953 -273.529588)
			(xy 135.548065 -273.578487) (xy 135.524722 -273.624299) (xy 135.494501 -273.665895) (xy 135.458145 -273.702251)
			(xy 135.416549 -273.732472) (xy 135.370737 -273.755815) (xy 135.321838 -273.771703) (xy 135.271056 -273.779746)
			(xy 135.21964 -273.779746) (xy 135.168858 -273.771703) (xy 135.119959 -273.755815) (xy 135.074147 -273.732472)
			(xy 135.032551 -273.702251) (xy 134.996195 -273.665895) (xy 134.965974 -273.624299) (xy 134.942631 -273.578487)
			(xy 134.926743 -273.529588) (xy 134.9187 -273.478806) (xy 134.661176 -273.478806) (xy 134.661158 -273.479747)
			(xy 134.653215 -273.532451) (xy 134.637505 -273.583381) (xy 134.614379 -273.631402) (xy 134.584355 -273.675439)
			(xy 134.548103 -273.71451) (xy 134.506432 -273.747741) (xy 134.460274 -273.77439) (xy 134.41066 -273.793862)
			(xy 134.358698 -273.805722) (xy 134.305548 -273.809706) (xy 134.252398 -273.805722) (xy 134.200436 -273.793862)
			(xy 134.150822 -273.77439) (xy 134.104664 -273.747741) (xy 134.062993 -273.71451) (xy 134.026741 -273.675439)
			(xy 133.996717 -273.631402) (xy 133.973591 -273.583381) (xy 133.957881 -273.532451) (xy 133.949938 -273.479747)
			(xy 133.692247 -273.479747) (xy 133.684353 -273.529588) (xy 133.668465 -273.578487) (xy 133.645122 -273.624299)
			(xy 133.614901 -273.665895) (xy 133.578545 -273.702251) (xy 133.536949 -273.732472) (xy 133.491137 -273.755815)
			(xy 133.442238 -273.771703) (xy 133.391456 -273.779746) (xy 133.34004 -273.779746) (xy 133.289258 -273.771703)
			(xy 133.240359 -273.755815) (xy 133.194547 -273.732472) (xy 133.152951 -273.702251) (xy 133.116595 -273.665895)
			(xy 133.086374 -273.624299) (xy 133.063031 -273.578487) (xy 133.047143 -273.529588) (xy 133.0391 -273.478806)
			(xy 132.781576 -273.478806) (xy 132.781558 -273.479747) (xy 132.773615 -273.532451) (xy 132.757905 -273.583381)
			(xy 132.734779 -273.631402) (xy 132.704755 -273.675439) (xy 132.668503 -273.71451) (xy 132.626832 -273.747741)
			(xy 132.580674 -273.77439) (xy 132.53106 -273.793862) (xy 132.479098 -273.805722) (xy 132.425948 -273.809706)
			(xy 132.372798 -273.805722) (xy 132.320836 -273.793862) (xy 132.271222 -273.77439) (xy 132.225064 -273.747741)
			(xy 132.183393 -273.71451) (xy 132.147141 -273.675439) (xy 132.117117 -273.631402) (xy 132.093991 -273.583381)
			(xy 132.078281 -273.532451) (xy 132.070338 -273.479747) (xy 131.812647 -273.479747) (xy 131.804753 -273.529588)
			(xy 131.788865 -273.578487) (xy 131.765522 -273.624299) (xy 131.735301 -273.665895) (xy 131.698945 -273.702251)
			(xy 131.657349 -273.732472) (xy 131.611537 -273.755815) (xy 131.562638 -273.771703) (xy 131.511856 -273.779746)
			(xy 131.46044 -273.779746) (xy 131.409658 -273.771703) (xy 131.360759 -273.755815) (xy 131.314947 -273.732472)
			(xy 131.273351 -273.702251) (xy 131.236995 -273.665895) (xy 131.206774 -273.624299) (xy 131.183431 -273.578487)
			(xy 131.167543 -273.529588) (xy 131.1595 -273.478806) (xy 130.872996 -273.478806) (xy 130.864953 -273.529588)
			(xy 130.849065 -273.578487) (xy 130.825722 -273.624299) (xy 130.795501 -273.665895) (xy 130.759145 -273.702251)
			(xy 130.717549 -273.732472) (xy 130.671737 -273.755815) (xy 130.622838 -273.771703) (xy 130.572056 -273.779746)
			(xy 130.52064 -273.779746) (xy 130.469858 -273.771703) (xy 130.420959 -273.755815) (xy 130.375147 -273.732472)
			(xy 130.333551 -273.702251) (xy 130.297195 -273.665895) (xy 130.266974 -273.624299) (xy 130.243631 -273.578487)
			(xy 130.227743 -273.529588) (xy 130.2197 -273.478806) (xy 129.962176 -273.478806) (xy 129.962158 -273.479747)
			(xy 129.954215 -273.532451) (xy 129.938505 -273.583381) (xy 129.915379 -273.631402) (xy 129.885355 -273.675439)
			(xy 129.849103 -273.71451) (xy 129.807432 -273.747741) (xy 129.761274 -273.77439) (xy 129.71166 -273.793862)
			(xy 129.659698 -273.805722) (xy 129.606548 -273.809706) (xy 129.553398 -273.805722) (xy 129.501436 -273.793862)
			(xy 129.451822 -273.77439) (xy 129.405664 -273.747741) (xy 129.363993 -273.71451) (xy 129.327741 -273.675439)
			(xy 129.297717 -273.631402) (xy 129.274591 -273.583381) (xy 129.258881 -273.532451) (xy 129.250938 -273.479747)
			(xy 128.993247 -273.479747) (xy 128.985353 -273.529588) (xy 128.969465 -273.578487) (xy 128.946122 -273.624299)
			(xy 128.915901 -273.665895) (xy 128.879545 -273.702251) (xy 128.837949 -273.732472) (xy 128.792137 -273.755815)
			(xy 128.743238 -273.771703) (xy 128.692456 -273.779746) (xy 128.64104 -273.779746) (xy 128.590258 -273.771703)
			(xy 128.541359 -273.755815) (xy 128.495547 -273.732472) (xy 128.453951 -273.702251) (xy 128.417595 -273.665895)
			(xy 128.387374 -273.624299) (xy 128.364031 -273.578487) (xy 128.348143 -273.529588) (xy 128.3401 -273.478806)
			(xy 128.082576 -273.478806) (xy 128.082558 -273.479747) (xy 128.074615 -273.532451) (xy 128.058905 -273.583381)
			(xy 128.035779 -273.631402) (xy 128.005755 -273.675439) (xy 127.969503 -273.71451) (xy 127.927832 -273.747741)
			(xy 127.881674 -273.77439) (xy 127.83206 -273.793862) (xy 127.780098 -273.805722) (xy 127.726948 -273.809706)
			(xy 127.673798 -273.805722) (xy 127.621836 -273.793862) (xy 127.572222 -273.77439) (xy 127.526064 -273.747741)
			(xy 127.484393 -273.71451) (xy 127.448141 -273.675439) (xy 127.418117 -273.631402) (xy 127.394991 -273.583381)
			(xy 127.379281 -273.532451) (xy 127.371338 -273.479747) (xy 127.113647 -273.479747) (xy 127.105753 -273.529588)
			(xy 127.089865 -273.578487) (xy 127.066522 -273.624299) (xy 127.036301 -273.665895) (xy 126.999945 -273.702251)
			(xy 126.958349 -273.732472) (xy 126.912537 -273.755815) (xy 126.863638 -273.771703) (xy 126.812856 -273.779746)
			(xy 126.76144 -273.779746) (xy 126.710658 -273.771703) (xy 126.661759 -273.755815) (xy 126.615947 -273.732472)
			(xy 126.574351 -273.702251) (xy 126.537995 -273.665895) (xy 126.507774 -273.624299) (xy 126.484431 -273.578487)
			(xy 126.468543 -273.529588) (xy 126.4605 -273.478806) (xy 126.202976 -273.478806) (xy 126.202958 -273.479747)
			(xy 126.195015 -273.532451) (xy 126.179305 -273.583381) (xy 126.156179 -273.631402) (xy 126.126155 -273.675439)
			(xy 126.089903 -273.71451) (xy 126.048232 -273.747741) (xy 126.002074 -273.77439) (xy 125.95246 -273.793862)
			(xy 125.900498 -273.805722) (xy 125.847348 -273.809706) (xy 125.794198 -273.805722) (xy 125.742236 -273.793862)
			(xy 125.692622 -273.77439) (xy 125.646464 -273.747741) (xy 125.604793 -273.71451) (xy 125.568541 -273.675439)
			(xy 125.538517 -273.631402) (xy 125.515391 -273.583381) (xy 125.499681 -273.532451) (xy 125.491738 -273.479747)
			(xy 125.234047 -273.479747) (xy 125.226153 -273.529588) (xy 125.210265 -273.578487) (xy 125.186922 -273.624299)
			(xy 125.156701 -273.665895) (xy 125.120345 -273.702251) (xy 125.078749 -273.732472) (xy 125.032937 -273.755815)
			(xy 124.984038 -273.771703) (xy 124.933256 -273.779746) (xy 124.88184 -273.779746) (xy 124.831058 -273.771703)
			(xy 124.782159 -273.755815) (xy 124.736347 -273.732472) (xy 124.694751 -273.702251) (xy 124.658395 -273.665895)
			(xy 124.628174 -273.624299) (xy 124.604831 -273.578487) (xy 124.588943 -273.529588) (xy 124.5809 -273.478806)
			(xy 124.294396 -273.478806) (xy 124.286353 -273.529588) (xy 124.270465 -273.578487) (xy 124.247122 -273.624299)
			(xy 124.216901 -273.665895) (xy 124.180545 -273.702251) (xy 124.138949 -273.732472) (xy 124.093137 -273.755815)
			(xy 124.044238 -273.771703) (xy 123.993456 -273.779746) (xy 123.94204 -273.779746) (xy 123.891258 -273.771703)
			(xy 123.842359 -273.755815) (xy 123.796547 -273.732472) (xy 123.754951 -273.702251) (xy 123.718595 -273.665895)
			(xy 123.688374 -273.624299) (xy 123.665031 -273.578487) (xy 123.649143 -273.529588) (xy 123.6411 -273.478806)
			(xy 123.383322 -273.478806) (xy 123.383304 -273.479747) (xy 123.375361 -273.532451) (xy 123.359651 -273.583381)
			(xy 123.336525 -273.631402) (xy 123.306501 -273.675439) (xy 123.270249 -273.71451) (xy 123.228578 -273.747741)
			(xy 123.18242 -273.77439) (xy 123.132806 -273.793862) (xy 123.080844 -273.805722) (xy 123.027694 -273.809706)
			(xy 122.974544 -273.805722) (xy 122.922582 -273.793862) (xy 122.872968 -273.77439) (xy 122.82681 -273.747741)
			(xy 122.785139 -273.71451) (xy 122.748887 -273.675439) (xy 122.718863 -273.631402) (xy 122.695737 -273.583381)
			(xy 122.680027 -273.532451) (xy 122.672084 -273.479747) (xy 122.443758 -273.479747) (xy 122.435815 -273.532451)
			(xy 122.420105 -273.583381) (xy 122.396979 -273.631402) (xy 122.366955 -273.675439) (xy 122.330703 -273.71451)
			(xy 122.289032 -273.747741) (xy 122.242874 -273.77439) (xy 122.19326 -273.793862) (xy 122.141298 -273.805722)
			(xy 122.088148 -273.809706) (xy 122.034998 -273.805722) (xy 121.983036 -273.793862) (xy 121.933422 -273.77439)
			(xy 121.887264 -273.747741) (xy 121.845593 -273.71451) (xy 121.809341 -273.675439) (xy 121.779317 -273.631402)
			(xy 121.756191 -273.583381) (xy 121.740481 -273.532451) (xy 121.732538 -273.479747) (xy 121.503958 -273.479747)
			(xy 121.496015 -273.532451) (xy 121.480305 -273.583381) (xy 121.457179 -273.631402) (xy 121.427155 -273.675439)
			(xy 121.390903 -273.71451) (xy 121.349232 -273.747741) (xy 121.303074 -273.77439) (xy 121.25346 -273.793862)
			(xy 121.201498 -273.805722) (xy 121.148348 -273.809706) (xy 121.095198 -273.805722) (xy 121.043236 -273.793862)
			(xy 120.993622 -273.77439) (xy 120.947464 -273.747741) (xy 120.905793 -273.71451) (xy 120.869541 -273.675439)
			(xy 120.839517 -273.631402) (xy 120.816391 -273.583381) (xy 120.800681 -273.532451) (xy 120.792738 -273.479747)
			(xy 120.564158 -273.479747) (xy 120.556215 -273.532451) (xy 120.540505 -273.583381) (xy 120.517379 -273.631402)
			(xy 120.487355 -273.675439) (xy 120.451103 -273.71451) (xy 120.409432 -273.747741) (xy 120.363274 -273.77439)
			(xy 120.31366 -273.793862) (xy 120.261698 -273.805722) (xy 120.208548 -273.809706) (xy 120.155398 -273.805722)
			(xy 120.103436 -273.793862) (xy 120.053822 -273.77439) (xy 120.007664 -273.747741) (xy 119.965993 -273.71451)
			(xy 119.929741 -273.675439) (xy 119.899717 -273.631402) (xy 119.876591 -273.583381) (xy 119.860881 -273.532451)
			(xy 119.852938 -273.479747) (xy 119.624358 -273.479747) (xy 119.616415 -273.532451) (xy 119.600705 -273.583381)
			(xy 119.577579 -273.631402) (xy 119.547555 -273.675439) (xy 119.511303 -273.71451) (xy 119.469632 -273.747741)
			(xy 119.423474 -273.77439) (xy 119.37386 -273.793862) (xy 119.321898 -273.805722) (xy 119.268748 -273.809706)
			(xy 119.215598 -273.805722) (xy 119.163636 -273.793862) (xy 119.114022 -273.77439) (xy 119.067864 -273.747741)
			(xy 119.026193 -273.71451) (xy 118.989941 -273.675439) (xy 118.959917 -273.631402) (xy 118.936791 -273.583381)
			(xy 118.921081 -273.532451) (xy 118.913138 -273.479747) (xy 118.684558 -273.479747) (xy 118.676615 -273.532451)
			(xy 118.660905 -273.583381) (xy 118.637779 -273.631402) (xy 118.607755 -273.675439) (xy 118.571503 -273.71451)
			(xy 118.529832 -273.747741) (xy 118.483674 -273.77439) (xy 118.43406 -273.793862) (xy 118.382098 -273.805722)
			(xy 118.328948 -273.809706) (xy 118.275798 -273.805722) (xy 118.223836 -273.793862) (xy 118.174222 -273.77439)
			(xy 118.128064 -273.747741) (xy 118.086393 -273.71451) (xy 118.050141 -273.675439) (xy 118.020117 -273.631402)
			(xy 117.996991 -273.583381) (xy 117.981281 -273.532451) (xy 117.973338 -273.479747) (xy 117.743713 -273.479747)
			(xy 117.741727 -273.506245) (xy 117.729869 -273.558204) (xy 117.7104 -273.607815) (xy 117.683755 -273.65397)
			(xy 117.650529 -273.695639) (xy 117.611464 -273.731891) (xy 117.567433 -273.761917) (xy 117.519418 -273.785045)
			(xy 117.468493 -273.800759) (xy 117.415795 -273.808709) (xy 117.389148 -273.809206) (xy 117.365163 -273.808821)
			(xy 117.317627 -273.802381) (xy 117.271391 -273.789599) (xy 117.249194 -273.780504) (xy 117.231596 -273.821996)
			(xy 117.188963 -273.901406) (xy 117.164104 -273.939) (xy 117.159786 -273.945096) (xy 117.150896 -273.973798)
			(xy 117.166136 -274.01012) (xy 117.172994 -274.016978) (xy 117.190182 -274.035025) (xy 117.219861 -274.075061)
			(xy 117.243672 -274.118842) (xy 117.26115 -274.165514) (xy 117.271954 -274.214166) (xy 117.27434 -274.238974)
			(xy 117.275864 -274.258786) (xy 117.355874 -274.332446) (xy 117.422422 -274.332446) (xy 117.502432 -274.258786)
			(xy 117.503956 -274.238974) (xy 117.506509 -274.212617) (xy 117.518421 -274.161023) (xy 117.537842 -274.111761)
			(xy 117.564346 -274.06592) (xy 117.597346 -274.024509) (xy 117.636116 -273.988443) (xy 117.679801 -273.958517)
			(xy 117.727435 -273.935391) (xy 117.77797 -273.919575) (xy 117.830289 -273.911418) (xy 117.856762 -273.910806)
			(xy 117.864128 -273.910806) (xy 117.873551 -273.911) (xy 117.892357 -273.912272) (xy 117.90172 -273.913346)
			(xy 117.927325 -273.916897) (xy 117.977211 -273.930438) (xy 118.024615 -273.95105) (xy 118.068541 -273.978298)
			(xy 118.108066 -274.011611) (xy 118.142359 -274.050288) (xy 118.1707 -274.093517) (xy 118.192494 -274.140389)
			(xy 118.207282 -274.18992) (xy 118.214753 -274.241068) (xy 118.215156 -274.266914) (xy 118.214675 -274.293425)
			(xy 118.214654 -274.293563) (xy 118.442984 -274.293563) (xy 118.442984 -274.240265) (xy 118.450927 -274.187561)
			(xy 118.466637 -274.136631) (xy 118.489763 -274.08861) (xy 118.519787 -274.044573) (xy 118.556039 -274.005502)
			(xy 118.59771 -273.972271) (xy 118.643868 -273.945622) (xy 118.693482 -273.92615) (xy 118.745444 -273.91429)
			(xy 118.798594 -273.910307) (xy 118.851744 -273.91429) (xy 118.903706 -273.92615) (xy 118.95332 -273.945622)
			(xy 118.999478 -273.972271) (xy 119.041149 -274.005502) (xy 119.077401 -274.044573) (xy 119.107425 -274.08861)
			(xy 119.130551 -274.136631) (xy 119.146261 -274.187561) (xy 119.154204 -274.240265) (xy 119.154702 -274.266914)
			(xy 119.154204 -274.293563) (xy 119.382784 -274.293563) (xy 119.382784 -274.240265) (xy 119.390727 -274.187561)
			(xy 119.406437 -274.136631) (xy 119.429563 -274.08861) (xy 119.459587 -274.044573) (xy 119.495839 -274.005502)
			(xy 119.53751 -273.972271) (xy 119.583668 -273.945622) (xy 119.633282 -273.92615) (xy 119.685244 -273.91429)
			(xy 119.738394 -273.910307) (xy 119.791544 -273.91429) (xy 119.843506 -273.92615) (xy 119.89312 -273.945622)
			(xy 119.939278 -273.972271) (xy 119.980949 -274.005502) (xy 120.017201 -274.044573) (xy 120.047225 -274.08861)
			(xy 120.070351 -274.136631) (xy 120.086061 -274.187561) (xy 120.094004 -274.240265) (xy 120.094502 -274.266914)
			(xy 120.094004 -274.293563) (xy 120.322584 -274.293563) (xy 120.322584 -274.240265) (xy 120.330527 -274.187561)
			(xy 120.346237 -274.136631) (xy 120.369363 -274.08861) (xy 120.399387 -274.044573) (xy 120.435639 -274.005502)
			(xy 120.47731 -273.972271) (xy 120.523468 -273.945622) (xy 120.573082 -273.92615) (xy 120.625044 -273.91429)
			(xy 120.678194 -273.910307) (xy 120.731344 -273.91429) (xy 120.783306 -273.92615) (xy 120.83292 -273.945622)
			(xy 120.879078 -273.972271) (xy 120.920749 -274.005502) (xy 120.957001 -274.044573) (xy 120.987025 -274.08861)
			(xy 121.010151 -274.136631) (xy 121.025861 -274.187561) (xy 121.033804 -274.240265) (xy 121.034302 -274.266914)
			(xy 121.033804 -274.293563) (xy 121.262638 -274.293563) (xy 121.262638 -274.240265) (xy 121.270581 -274.187561)
			(xy 121.286291 -274.136631) (xy 121.309417 -274.08861) (xy 121.339441 -274.044573) (xy 121.375693 -274.005502)
			(xy 121.417364 -273.972271) (xy 121.463522 -273.945622) (xy 121.513136 -273.92615) (xy 121.565098 -273.91429)
			(xy 121.618248 -273.910307) (xy 121.671398 -273.91429) (xy 121.72336 -273.92615) (xy 121.772974 -273.945622)
			(xy 121.819132 -273.972271) (xy 121.860803 -274.005502) (xy 121.897055 -274.044573) (xy 121.927079 -274.08861)
			(xy 121.950205 -274.136631) (xy 121.965915 -274.187561) (xy 121.973858 -274.240265) (xy 121.974356 -274.266914)
			(xy 121.973858 -274.293563) (xy 122.202184 -274.293563) (xy 122.202184 -274.240265) (xy 122.210127 -274.187561)
			(xy 122.225837 -274.136631) (xy 122.248963 -274.08861) (xy 122.278987 -274.044573) (xy 122.315239 -274.005502)
			(xy 122.35691 -273.972271) (xy 122.403068 -273.945622) (xy 122.452682 -273.92615) (xy 122.504644 -273.91429)
			(xy 122.557794 -273.910307) (xy 122.610944 -273.91429) (xy 122.662906 -273.92615) (xy 122.71252 -273.945622)
			(xy 122.758678 -273.972271) (xy 122.800349 -274.005502) (xy 122.836601 -274.044573) (xy 122.866625 -274.08861)
			(xy 122.889751 -274.136631) (xy 122.905461 -274.187561) (xy 122.913404 -274.240265) (xy 122.913902 -274.266914)
			(xy 122.913422 -274.292622) (xy 123.170946 -274.292622) (xy 123.170946 -274.241206) (xy 123.178989 -274.190424)
			(xy 123.194877 -274.141525) (xy 123.21822 -274.095713) (xy 123.248441 -274.054117) (xy 123.284797 -274.017761)
			(xy 123.326393 -273.98754) (xy 123.372205 -273.964197) (xy 123.421104 -273.948309) (xy 123.471886 -273.940266)
			(xy 123.523302 -273.940266) (xy 123.574084 -273.948309) (xy 123.622983 -273.964197) (xy 123.668795 -273.98754)
			(xy 123.710391 -274.017761) (xy 123.746747 -274.054117) (xy 123.776968 -274.095713) (xy 123.800311 -274.141525)
			(xy 123.816199 -274.190424) (xy 123.824242 -274.241206) (xy 123.824746 -274.266914) (xy 123.824242 -274.292622)
			(xy 123.824093 -274.293563) (xy 124.081784 -274.293563) (xy 124.081784 -274.240265) (xy 124.089727 -274.187561)
			(xy 124.105437 -274.136631) (xy 124.128563 -274.08861) (xy 124.158587 -274.044573) (xy 124.194839 -274.005502)
			(xy 124.23651 -273.972271) (xy 124.282668 -273.945622) (xy 124.332282 -273.92615) (xy 124.384244 -273.91429)
			(xy 124.437394 -273.910307) (xy 124.490544 -273.91429) (xy 124.542506 -273.92615) (xy 124.59212 -273.945622)
			(xy 124.638278 -273.972271) (xy 124.679949 -274.005502) (xy 124.716201 -274.044573) (xy 124.746225 -274.08861)
			(xy 124.769351 -274.136631) (xy 124.785061 -274.187561) (xy 124.793004 -274.240265) (xy 124.793502 -274.266914)
			(xy 124.793022 -274.292622) (xy 125.050546 -274.292622) (xy 125.050546 -274.241206) (xy 125.058589 -274.190424)
			(xy 125.074477 -274.141525) (xy 125.09782 -274.095713) (xy 125.128041 -274.054117) (xy 125.164397 -274.017761)
			(xy 125.205993 -273.98754) (xy 125.251805 -273.964197) (xy 125.300704 -273.948309) (xy 125.351486 -273.940266)
			(xy 125.402902 -273.940266) (xy 125.453684 -273.948309) (xy 125.502583 -273.964197) (xy 125.548395 -273.98754)
			(xy 125.589991 -274.017761) (xy 125.626347 -274.054117) (xy 125.656568 -274.095713) (xy 125.679911 -274.141525)
			(xy 125.695799 -274.190424) (xy 125.703842 -274.241206) (xy 125.704346 -274.266914) (xy 125.703842 -274.292622)
			(xy 125.703693 -274.293563) (xy 125.961638 -274.293563) (xy 125.961638 -274.240265) (xy 125.969581 -274.187561)
			(xy 125.985291 -274.136631) (xy 126.008417 -274.08861) (xy 126.038441 -274.044573) (xy 126.074693 -274.005502)
			(xy 126.116364 -273.972271) (xy 126.162522 -273.945622) (xy 126.212136 -273.92615) (xy 126.264098 -273.91429)
			(xy 126.317248 -273.910307) (xy 126.370398 -273.91429) (xy 126.42236 -273.92615) (xy 126.471974 -273.945622)
			(xy 126.518132 -273.972271) (xy 126.559803 -274.005502) (xy 126.596055 -274.044573) (xy 126.626079 -274.08861)
			(xy 126.649205 -274.136631) (xy 126.664915 -274.187561) (xy 126.672858 -274.240265) (xy 126.673356 -274.266914)
			(xy 126.672876 -274.292622) (xy 126.930146 -274.292622) (xy 126.930146 -274.241206) (xy 126.938189 -274.190424)
			(xy 126.954077 -274.141525) (xy 126.97742 -274.095713) (xy 127.007641 -274.054117) (xy 127.043997 -274.017761)
			(xy 127.085593 -273.98754) (xy 127.131405 -273.964197) (xy 127.180304 -273.948309) (xy 127.231086 -273.940266)
			(xy 127.282502 -273.940266) (xy 127.333284 -273.948309) (xy 127.382183 -273.964197) (xy 127.427995 -273.98754)
			(xy 127.469591 -274.017761) (xy 127.505947 -274.054117) (xy 127.536168 -274.095713) (xy 127.559511 -274.141525)
			(xy 127.575399 -274.190424) (xy 127.583442 -274.241206) (xy 127.583946 -274.266914) (xy 127.583442 -274.292622)
			(xy 127.869946 -274.292622) (xy 127.869946 -274.241206) (xy 127.877989 -274.190424) (xy 127.893877 -274.141525)
			(xy 127.91722 -274.095713) (xy 127.947441 -274.054117) (xy 127.983797 -274.017761) (xy 128.025393 -273.98754)
			(xy 128.071205 -273.964197) (xy 128.120104 -273.948309) (xy 128.170886 -273.940266) (xy 128.222302 -273.940266)
			(xy 128.273084 -273.948309) (xy 128.321983 -273.964197) (xy 128.367795 -273.98754) (xy 128.409391 -274.017761)
			(xy 128.445747 -274.054117) (xy 128.475968 -274.095713) (xy 128.499311 -274.141525) (xy 128.515199 -274.190424)
			(xy 128.523242 -274.241206) (xy 128.523746 -274.266914) (xy 128.523242 -274.292622) (xy 128.523093 -274.293563)
			(xy 128.780784 -274.293563) (xy 128.780784 -274.240265) (xy 128.788727 -274.187561) (xy 128.804437 -274.136631)
			(xy 128.827563 -274.08861) (xy 128.857587 -274.044573) (xy 128.893839 -274.005502) (xy 128.93551 -273.972271)
			(xy 128.981668 -273.945622) (xy 129.031282 -273.92615) (xy 129.083244 -273.91429) (xy 129.136394 -273.910307)
			(xy 129.189544 -273.91429) (xy 129.241506 -273.92615) (xy 129.29112 -273.945622) (xy 129.337278 -273.972271)
			(xy 129.378949 -274.005502) (xy 129.415201 -274.044573) (xy 129.445225 -274.08861) (xy 129.468351 -274.136631)
			(xy 129.484061 -274.187561) (xy 129.492004 -274.240265) (xy 129.492502 -274.266914) (xy 129.492022 -274.292622)
			(xy 129.749546 -274.292622) (xy 129.749546 -274.241206) (xy 129.757589 -274.190424) (xy 129.773477 -274.141525)
			(xy 129.79682 -274.095713) (xy 129.827041 -274.054117) (xy 129.863397 -274.017761) (xy 129.904993 -273.98754)
			(xy 129.950805 -273.964197) (xy 129.999704 -273.948309) (xy 130.050486 -273.940266) (xy 130.101902 -273.940266)
			(xy 130.152684 -273.948309) (xy 130.201583 -273.964197) (xy 130.247395 -273.98754) (xy 130.288991 -274.017761)
			(xy 130.325347 -274.054117) (xy 130.355568 -274.095713) (xy 130.378911 -274.141525) (xy 130.394799 -274.190424)
			(xy 130.402842 -274.241206) (xy 130.403346 -274.266914) (xy 130.402842 -274.292622) (xy 130.402693 -274.293563)
			(xy 130.660384 -274.293563) (xy 130.660384 -274.240265) (xy 130.668327 -274.187561) (xy 130.684037 -274.136631)
			(xy 130.707163 -274.08861) (xy 130.737187 -274.044573) (xy 130.773439 -274.005502) (xy 130.81511 -273.972271)
			(xy 130.861268 -273.945622) (xy 130.910882 -273.92615) (xy 130.962844 -273.91429) (xy 131.015994 -273.910307)
			(xy 131.069144 -273.91429) (xy 131.121106 -273.92615) (xy 131.17072 -273.945622) (xy 131.216878 -273.972271)
			(xy 131.258549 -274.005502) (xy 131.294801 -274.044573) (xy 131.324825 -274.08861) (xy 131.347951 -274.136631)
			(xy 131.363661 -274.187561) (xy 131.371604 -274.240265) (xy 131.372102 -274.266914) (xy 131.371622 -274.292622)
			(xy 131.629146 -274.292622) (xy 131.629146 -274.241206) (xy 131.637189 -274.190424) (xy 131.653077 -274.141525)
			(xy 131.67642 -274.095713) (xy 131.706641 -274.054117) (xy 131.742997 -274.017761) (xy 131.784593 -273.98754)
			(xy 131.830405 -273.964197) (xy 131.879304 -273.948309) (xy 131.930086 -273.940266) (xy 131.981502 -273.940266)
			(xy 132.032284 -273.948309) (xy 132.081183 -273.964197) (xy 132.126995 -273.98754) (xy 132.168591 -274.017761)
			(xy 132.204947 -274.054117) (xy 132.235168 -274.095713) (xy 132.258511 -274.141525) (xy 132.274399 -274.190424)
			(xy 132.282442 -274.241206) (xy 132.282946 -274.266914) (xy 132.282442 -274.292622) (xy 132.282293 -274.293563)
			(xy 132.540238 -274.293563) (xy 132.540238 -274.240265) (xy 132.548181 -274.187561) (xy 132.563891 -274.136631)
			(xy 132.587017 -274.08861) (xy 132.617041 -274.044573) (xy 132.653293 -274.005502) (xy 132.694964 -273.972271)
			(xy 132.741122 -273.945622) (xy 132.790736 -273.92615) (xy 132.842698 -273.91429) (xy 132.895848 -273.910307)
			(xy 132.948998 -273.91429) (xy 133.00096 -273.92615) (xy 133.050574 -273.945622) (xy 133.096732 -273.972271)
			(xy 133.138403 -274.005502) (xy 133.174655 -274.044573) (xy 133.204679 -274.08861) (xy 133.227805 -274.136631)
			(xy 133.243515 -274.187561) (xy 133.251458 -274.240265) (xy 133.251956 -274.266914) (xy 133.251476 -274.292622)
			(xy 133.508746 -274.292622) (xy 133.508746 -274.241206) (xy 133.516789 -274.190424) (xy 133.532677 -274.141525)
			(xy 133.55602 -274.095713) (xy 133.586241 -274.054117) (xy 133.622597 -274.017761) (xy 133.664193 -273.98754)
			(xy 133.710005 -273.964197) (xy 133.758904 -273.948309) (xy 133.809686 -273.940266) (xy 133.861102 -273.940266)
			(xy 133.911884 -273.948309) (xy 133.960783 -273.964197) (xy 134.006595 -273.98754) (xy 134.048191 -274.017761)
			(xy 134.084547 -274.054117) (xy 134.114768 -274.095713) (xy 134.138111 -274.141525) (xy 134.153999 -274.190424)
			(xy 134.162042 -274.241206) (xy 134.162546 -274.266914) (xy 134.162042 -274.292622) (xy 134.448546 -274.292622)
			(xy 134.448546 -274.241206) (xy 134.456589 -274.190424) (xy 134.472477 -274.141525) (xy 134.49582 -274.095713)
			(xy 134.526041 -274.054117) (xy 134.562397 -274.017761) (xy 134.603993 -273.98754) (xy 134.649805 -273.964197)
			(xy 134.698704 -273.948309) (xy 134.749486 -273.940266) (xy 134.800902 -273.940266) (xy 134.851684 -273.948309)
			(xy 134.900583 -273.964197) (xy 134.946395 -273.98754) (xy 134.987991 -274.017761) (xy 135.024347 -274.054117)
			(xy 135.054568 -274.095713) (xy 135.077911 -274.141525) (xy 135.093799 -274.190424) (xy 135.101842 -274.241206)
			(xy 135.102346 -274.266914) (xy 135.101842 -274.292622) (xy 135.101693 -274.293563) (xy 135.359384 -274.293563)
			(xy 135.359384 -274.240265) (xy 135.367327 -274.187561) (xy 135.383037 -274.136631) (xy 135.406163 -274.08861)
			(xy 135.436187 -274.044573) (xy 135.472439 -274.005502) (xy 135.51411 -273.972271) (xy 135.560268 -273.945622)
			(xy 135.609882 -273.92615) (xy 135.661844 -273.91429) (xy 135.714994 -273.910307) (xy 135.768144 -273.91429)
			(xy 135.820106 -273.92615) (xy 135.86972 -273.945622) (xy 135.915878 -273.972271) (xy 135.957549 -274.005502)
			(xy 135.993801 -274.044573) (xy 136.023825 -274.08861) (xy 136.046951 -274.136631) (xy 136.062661 -274.187561)
			(xy 136.070604 -274.240265) (xy 136.071102 -274.266914) (xy 136.070604 -274.293563) (xy 136.062661 -274.346267)
			(xy 136.046951 -274.397197) (xy 136.023825 -274.445218) (xy 135.993801 -274.489255) (xy 135.957549 -274.528326)
			(xy 135.915878 -274.561557) (xy 135.86972 -274.588206) (xy 135.820106 -274.607678) (xy 135.768144 -274.619538)
			(xy 135.714994 -274.623522) (xy 135.661844 -274.619538) (xy 135.609882 -274.607678) (xy 135.560268 -274.588206)
			(xy 135.51411 -274.561557) (xy 135.472439 -274.528326) (xy 135.436187 -274.489255) (xy 135.406163 -274.445218)
			(xy 135.383037 -274.397197) (xy 135.367327 -274.346267) (xy 135.359384 -274.293563) (xy 135.101693 -274.293563)
			(xy 135.093799 -274.343404) (xy 135.077911 -274.392303) (xy 135.054568 -274.438115) (xy 135.024347 -274.479711)
			(xy 134.987991 -274.516067) (xy 134.946395 -274.546288) (xy 134.900583 -274.569631) (xy 134.851684 -274.585519)
			(xy 134.800902 -274.593562) (xy 134.749486 -274.593562) (xy 134.698704 -274.585519) (xy 134.649805 -274.569631)
			(xy 134.603993 -274.546288) (xy 134.562397 -274.516067) (xy 134.526041 -274.479711) (xy 134.49582 -274.438115)
			(xy 134.472477 -274.392303) (xy 134.456589 -274.343404) (xy 134.448546 -274.292622) (xy 134.162042 -274.292622)
			(xy 134.153999 -274.343404) (xy 134.138111 -274.392303) (xy 134.114768 -274.438115) (xy 134.084547 -274.479711)
			(xy 134.048191 -274.516067) (xy 134.006595 -274.546288) (xy 133.960783 -274.569631) (xy 133.911884 -274.585519)
			(xy 133.861102 -274.593562) (xy 133.809686 -274.593562) (xy 133.758904 -274.585519) (xy 133.710005 -274.569631)
			(xy 133.664193 -274.546288) (xy 133.622597 -274.516067) (xy 133.586241 -274.479711) (xy 133.55602 -274.438115)
			(xy 133.532677 -274.392303) (xy 133.516789 -274.343404) (xy 133.508746 -274.292622) (xy 133.251476 -274.292622)
			(xy 133.251458 -274.293563) (xy 133.243515 -274.346267) (xy 133.227805 -274.397197) (xy 133.204679 -274.445218)
			(xy 133.174655 -274.489255) (xy 133.138403 -274.528326) (xy 133.096732 -274.561557) (xy 133.050574 -274.588206)
			(xy 133.00096 -274.607678) (xy 132.948998 -274.619538) (xy 132.895848 -274.623522) (xy 132.842698 -274.619538)
			(xy 132.790736 -274.607678) (xy 132.741122 -274.588206) (xy 132.694964 -274.561557) (xy 132.653293 -274.528326)
			(xy 132.617041 -274.489255) (xy 132.587017 -274.445218) (xy 132.563891 -274.397197) (xy 132.548181 -274.346267)
			(xy 132.540238 -274.293563) (xy 132.282293 -274.293563) (xy 132.274399 -274.343404) (xy 132.258511 -274.392303)
			(xy 132.235168 -274.438115) (xy 132.204947 -274.479711) (xy 132.168591 -274.516067) (xy 132.126995 -274.546288)
			(xy 132.081183 -274.569631) (xy 132.032284 -274.585519) (xy 131.981502 -274.593562) (xy 131.930086 -274.593562)
			(xy 131.879304 -274.585519) (xy 131.830405 -274.569631) (xy 131.784593 -274.546288) (xy 131.742997 -274.516067)
			(xy 131.706641 -274.479711) (xy 131.67642 -274.438115) (xy 131.653077 -274.392303) (xy 131.637189 -274.343404)
			(xy 131.629146 -274.292622) (xy 131.371622 -274.292622) (xy 131.371604 -274.293563) (xy 131.363661 -274.346267)
			(xy 131.347951 -274.397197) (xy 131.324825 -274.445218) (xy 131.294801 -274.489255) (xy 131.258549 -274.528326)
			(xy 131.216878 -274.561557) (xy 131.17072 -274.588206) (xy 131.121106 -274.607678) (xy 131.069144 -274.619538)
			(xy 131.015994 -274.623522) (xy 130.962844 -274.619538) (xy 130.910882 -274.607678) (xy 130.861268 -274.588206)
			(xy 130.81511 -274.561557) (xy 130.773439 -274.528326) (xy 130.737187 -274.489255) (xy 130.707163 -274.445218)
			(xy 130.684037 -274.397197) (xy 130.668327 -274.346267) (xy 130.660384 -274.293563) (xy 130.402693 -274.293563)
			(xy 130.394799 -274.343404) (xy 130.378911 -274.392303) (xy 130.355568 -274.438115) (xy 130.325347 -274.479711)
			(xy 130.288991 -274.516067) (xy 130.247395 -274.546288) (xy 130.201583 -274.569631) (xy 130.152684 -274.585519)
			(xy 130.101902 -274.593562) (xy 130.050486 -274.593562) (xy 129.999704 -274.585519) (xy 129.950805 -274.569631)
			(xy 129.904993 -274.546288) (xy 129.863397 -274.516067) (xy 129.827041 -274.479711) (xy 129.79682 -274.438115)
			(xy 129.773477 -274.392303) (xy 129.757589 -274.343404) (xy 129.749546 -274.292622) (xy 129.492022 -274.292622)
			(xy 129.492004 -274.293563) (xy 129.484061 -274.346267) (xy 129.468351 -274.397197) (xy 129.445225 -274.445218)
			(xy 129.415201 -274.489255) (xy 129.378949 -274.528326) (xy 129.337278 -274.561557) (xy 129.29112 -274.588206)
			(xy 129.241506 -274.607678) (xy 129.189544 -274.619538) (xy 129.136394 -274.623522) (xy 129.083244 -274.619538)
			(xy 129.031282 -274.607678) (xy 128.981668 -274.588206) (xy 128.93551 -274.561557) (xy 128.893839 -274.528326)
			(xy 128.857587 -274.489255) (xy 128.827563 -274.445218) (xy 128.804437 -274.397197) (xy 128.788727 -274.346267)
			(xy 128.780784 -274.293563) (xy 128.523093 -274.293563) (xy 128.515199 -274.343404) (xy 128.499311 -274.392303)
			(xy 128.475968 -274.438115) (xy 128.445747 -274.479711) (xy 128.409391 -274.516067) (xy 128.367795 -274.546288)
			(xy 128.321983 -274.569631) (xy 128.273084 -274.585519) (xy 128.222302 -274.593562) (xy 128.170886 -274.593562)
			(xy 128.120104 -274.585519) (xy 128.071205 -274.569631) (xy 128.025393 -274.546288) (xy 127.983797 -274.516067)
			(xy 127.947441 -274.479711) (xy 127.91722 -274.438115) (xy 127.893877 -274.392303) (xy 127.877989 -274.343404)
			(xy 127.869946 -274.292622) (xy 127.583442 -274.292622) (xy 127.575399 -274.343404) (xy 127.559511 -274.392303)
			(xy 127.536168 -274.438115) (xy 127.505947 -274.479711) (xy 127.469591 -274.516067) (xy 127.427995 -274.546288)
			(xy 127.382183 -274.569631) (xy 127.333284 -274.585519) (xy 127.282502 -274.593562) (xy 127.231086 -274.593562)
			(xy 127.180304 -274.585519) (xy 127.131405 -274.569631) (xy 127.085593 -274.546288) (xy 127.043997 -274.516067)
			(xy 127.007641 -274.479711) (xy 126.97742 -274.438115) (xy 126.954077 -274.392303) (xy 126.938189 -274.343404)
			(xy 126.930146 -274.292622) (xy 126.672876 -274.292622) (xy 126.672858 -274.293563) (xy 126.664915 -274.346267)
			(xy 126.649205 -274.397197) (xy 126.626079 -274.445218) (xy 126.596055 -274.489255) (xy 126.559803 -274.528326)
			(xy 126.518132 -274.561557) (xy 126.471974 -274.588206) (xy 126.42236 -274.607678) (xy 126.370398 -274.619538)
			(xy 126.317248 -274.623522) (xy 126.264098 -274.619538) (xy 126.212136 -274.607678) (xy 126.162522 -274.588206)
			(xy 126.116364 -274.561557) (xy 126.074693 -274.528326) (xy 126.038441 -274.489255) (xy 126.008417 -274.445218)
			(xy 125.985291 -274.397197) (xy 125.969581 -274.346267) (xy 125.961638 -274.293563) (xy 125.703693 -274.293563)
			(xy 125.695799 -274.343404) (xy 125.679911 -274.392303) (xy 125.656568 -274.438115) (xy 125.626347 -274.479711)
			(xy 125.589991 -274.516067) (xy 125.548395 -274.546288) (xy 125.502583 -274.569631) (xy 125.453684 -274.585519)
			(xy 125.402902 -274.593562) (xy 125.351486 -274.593562) (xy 125.300704 -274.585519) (xy 125.251805 -274.569631)
			(xy 125.205993 -274.546288) (xy 125.164397 -274.516067) (xy 125.128041 -274.479711) (xy 125.09782 -274.438115)
			(xy 125.074477 -274.392303) (xy 125.058589 -274.343404) (xy 125.050546 -274.292622) (xy 124.793022 -274.292622)
			(xy 124.793004 -274.293563) (xy 124.785061 -274.346267) (xy 124.769351 -274.397197) (xy 124.746225 -274.445218)
			(xy 124.716201 -274.489255) (xy 124.679949 -274.528326) (xy 124.638278 -274.561557) (xy 124.59212 -274.588206)
			(xy 124.542506 -274.607678) (xy 124.490544 -274.619538) (xy 124.437394 -274.623522) (xy 124.384244 -274.619538)
			(xy 124.332282 -274.607678) (xy 124.282668 -274.588206) (xy 124.23651 -274.561557) (xy 124.194839 -274.528326)
			(xy 124.158587 -274.489255) (xy 124.128563 -274.445218) (xy 124.105437 -274.397197) (xy 124.089727 -274.346267)
			(xy 124.081784 -274.293563) (xy 123.824093 -274.293563) (xy 123.816199 -274.343404) (xy 123.800311 -274.392303)
			(xy 123.776968 -274.438115) (xy 123.746747 -274.479711) (xy 123.710391 -274.516067) (xy 123.668795 -274.546288)
			(xy 123.622983 -274.569631) (xy 123.574084 -274.585519) (xy 123.523302 -274.593562) (xy 123.471886 -274.593562)
			(xy 123.421104 -274.585519) (xy 123.372205 -274.569631) (xy 123.326393 -274.546288) (xy 123.284797 -274.516067)
			(xy 123.248441 -274.479711) (xy 123.21822 -274.438115) (xy 123.194877 -274.392303) (xy 123.178989 -274.343404)
			(xy 123.170946 -274.292622) (xy 122.913422 -274.292622) (xy 122.913404 -274.293563) (xy 122.905461 -274.346267)
			(xy 122.889751 -274.397197) (xy 122.866625 -274.445218) (xy 122.836601 -274.489255) (xy 122.800349 -274.528326)
			(xy 122.758678 -274.561557) (xy 122.71252 -274.588206) (xy 122.662906 -274.607678) (xy 122.610944 -274.619538)
			(xy 122.557794 -274.623522) (xy 122.504644 -274.619538) (xy 122.452682 -274.607678) (xy 122.403068 -274.588206)
			(xy 122.35691 -274.561557) (xy 122.315239 -274.528326) (xy 122.278987 -274.489255) (xy 122.248963 -274.445218)
			(xy 122.225837 -274.397197) (xy 122.210127 -274.346267) (xy 122.202184 -274.293563) (xy 121.973858 -274.293563)
			(xy 121.965915 -274.346267) (xy 121.950205 -274.397197) (xy 121.927079 -274.445218) (xy 121.897055 -274.489255)
			(xy 121.860803 -274.528326) (xy 121.819132 -274.561557) (xy 121.772974 -274.588206) (xy 121.72336 -274.607678)
			(xy 121.671398 -274.619538) (xy 121.618248 -274.623522) (xy 121.565098 -274.619538) (xy 121.513136 -274.607678)
			(xy 121.463522 -274.588206) (xy 121.417364 -274.561557) (xy 121.375693 -274.528326) (xy 121.339441 -274.489255)
			(xy 121.309417 -274.445218) (xy 121.286291 -274.397197) (xy 121.270581 -274.346267) (xy 121.262638 -274.293563)
			(xy 121.033804 -274.293563) (xy 121.025861 -274.346267) (xy 121.010151 -274.397197) (xy 120.987025 -274.445218)
			(xy 120.957001 -274.489255) (xy 120.920749 -274.528326) (xy 120.879078 -274.561557) (xy 120.83292 -274.588206)
			(xy 120.783306 -274.607678) (xy 120.731344 -274.619538) (xy 120.678194 -274.623522) (xy 120.625044 -274.619538)
			(xy 120.573082 -274.607678) (xy 120.523468 -274.588206) (xy 120.47731 -274.561557) (xy 120.435639 -274.528326)
			(xy 120.399387 -274.489255) (xy 120.369363 -274.445218) (xy 120.346237 -274.397197) (xy 120.330527 -274.346267)
			(xy 120.322584 -274.293563) (xy 120.094004 -274.293563) (xy 120.086061 -274.346267) (xy 120.070351 -274.397197)
			(xy 120.047225 -274.445218) (xy 120.017201 -274.489255) (xy 119.980949 -274.528326) (xy 119.939278 -274.561557)
			(xy 119.89312 -274.588206) (xy 119.843506 -274.607678) (xy 119.791544 -274.619538) (xy 119.738394 -274.623522)
			(xy 119.685244 -274.619538) (xy 119.633282 -274.607678) (xy 119.583668 -274.588206) (xy 119.53751 -274.561557)
			(xy 119.495839 -274.528326) (xy 119.459587 -274.489255) (xy 119.429563 -274.445218) (xy 119.406437 -274.397197)
			(xy 119.390727 -274.346267) (xy 119.382784 -274.293563) (xy 119.154204 -274.293563) (xy 119.146261 -274.346267)
			(xy 119.130551 -274.397197) (xy 119.107425 -274.445218) (xy 119.077401 -274.489255) (xy 119.041149 -274.528326)
			(xy 118.999478 -274.561557) (xy 118.95332 -274.588206) (xy 118.903706 -274.607678) (xy 118.851744 -274.619538)
			(xy 118.798594 -274.623522) (xy 118.745444 -274.619538) (xy 118.693482 -274.607678) (xy 118.643868 -274.588206)
			(xy 118.59771 -274.561557) (xy 118.556039 -274.528326) (xy 118.519787 -274.489255) (xy 118.489763 -274.445218)
			(xy 118.466637 -274.397197) (xy 118.450927 -274.346267) (xy 118.442984 -274.293563) (xy 118.214654 -274.293563)
			(xy 118.206828 -274.345862) (xy 118.191293 -274.396556) (xy 118.168414 -274.444387) (xy 118.138698 -274.488297)
			(xy 118.102799 -274.527317) (xy 118.061513 -274.560584) (xy 118.015752 -274.587362) (xy 117.966526 -274.607061)
			(xy 117.940836 -274.613624) (xy 117.90172 -274.622768) (xy 117.90172 -274.759166) (xy 117.902267 -274.774204)
			(xy 117.911036 -274.802973) (xy 117.927795 -274.827947) (xy 117.951095 -274.846965) (xy 117.97892 -274.858381)
			(xy 118.008863 -274.861208) (xy 118.038333 -274.855202) (xy 118.064781 -274.840882) (xy 118.07571 -274.83054)
			(xy 118.095896 -274.810844) (xy 118.141337 -274.777447) (xy 118.191479 -274.751636) (xy 118.245064 -274.734058)
			(xy 118.300751 -274.725154) (xy 118.328948 -274.724622) (xy 118.355593 -274.725123) (xy 118.408286 -274.733072)
			(xy 118.459206 -274.748785) (xy 118.507216 -274.771911) (xy 118.551244 -274.801934) (xy 118.590305 -274.838183)
			(xy 118.623528 -274.879848) (xy 118.650171 -274.925999) (xy 118.669638 -274.975606) (xy 118.681495 -275.027559)
			(xy 118.685477 -275.0807) (xy 118.683478 -275.107379) (xy 118.913138 -275.107379) (xy 118.913138 -275.054081)
			(xy 118.921081 -275.001377) (xy 118.936791 -274.950447) (xy 118.959917 -274.902426) (xy 118.989941 -274.858389)
			(xy 119.026193 -274.819318) (xy 119.067864 -274.786087) (xy 119.114022 -274.759438) (xy 119.163636 -274.739966)
			(xy 119.215598 -274.728106) (xy 119.268748 -274.724123) (xy 119.321898 -274.728106) (xy 119.37386 -274.739966)
			(xy 119.423474 -274.759438) (xy 119.469632 -274.786087) (xy 119.511303 -274.819318) (xy 119.547555 -274.858389)
			(xy 119.577579 -274.902426) (xy 119.600705 -274.950447) (xy 119.616415 -275.001377) (xy 119.624358 -275.054081)
			(xy 119.624856 -275.08073) (xy 119.624358 -275.107379) (xy 119.852938 -275.107379) (xy 119.852938 -275.054081)
			(xy 119.860881 -275.001377) (xy 119.876591 -274.950447) (xy 119.899717 -274.902426) (xy 119.929741 -274.858389)
			(xy 119.965993 -274.819318) (xy 120.007664 -274.786087) (xy 120.053822 -274.759438) (xy 120.103436 -274.739966)
			(xy 120.155398 -274.728106) (xy 120.208548 -274.724123) (xy 120.261698 -274.728106) (xy 120.31366 -274.739966)
			(xy 120.363274 -274.759438) (xy 120.409432 -274.786087) (xy 120.451103 -274.819318) (xy 120.487355 -274.858389)
			(xy 120.517379 -274.902426) (xy 120.540505 -274.950447) (xy 120.556215 -275.001377) (xy 120.564158 -275.054081)
			(xy 120.564656 -275.08073) (xy 120.564163 -275.107125) (xy 120.792484 -275.107125) (xy 120.792484 -275.053827)
			(xy 120.800427 -275.001123) (xy 120.816137 -274.950193) (xy 120.839263 -274.902172) (xy 120.869287 -274.858135)
			(xy 120.905539 -274.819064) (xy 120.94721 -274.785833) (xy 120.993368 -274.759184) (xy 121.042982 -274.739712)
			(xy 121.094944 -274.727852) (xy 121.148094 -274.723869) (xy 121.201244 -274.727852) (xy 121.253206 -274.739712)
			(xy 121.30282 -274.759184) (xy 121.348978 -274.785833) (xy 121.390649 -274.819064) (xy 121.426901 -274.858135)
			(xy 121.456925 -274.902172) (xy 121.480051 -274.950193) (xy 121.495761 -275.001123) (xy 121.503704 -275.053827)
			(xy 121.504202 -275.080476) (xy 121.503704 -275.107125) (xy 121.503666 -275.107379) (xy 121.732538 -275.107379)
			(xy 121.732538 -275.054081) (xy 121.740481 -275.001377) (xy 121.756191 -274.950447) (xy 121.779317 -274.902426)
			(xy 121.809341 -274.858389) (xy 121.845593 -274.819318) (xy 121.887264 -274.786087) (xy 121.933422 -274.759438)
			(xy 121.983036 -274.739966) (xy 122.034998 -274.728106) (xy 122.088148 -274.724123) (xy 122.141298 -274.728106)
			(xy 122.19326 -274.739966) (xy 122.242874 -274.759438) (xy 122.289032 -274.786087) (xy 122.330703 -274.819318)
			(xy 122.366955 -274.858389) (xy 122.396979 -274.902426) (xy 122.420105 -274.950447) (xy 122.435815 -275.001377)
			(xy 122.443758 -275.054081) (xy 122.444256 -275.08073) (xy 122.443776 -275.106438) (xy 122.7013 -275.106438)
			(xy 122.7013 -275.055022) (xy 122.709343 -275.00424) (xy 122.725231 -274.955341) (xy 122.748574 -274.909529)
			(xy 122.778795 -274.867933) (xy 122.815151 -274.831577) (xy 122.856747 -274.801356) (xy 122.902559 -274.778013)
			(xy 122.951458 -274.762125) (xy 123.00224 -274.754082) (xy 123.053656 -274.754082) (xy 123.104438 -274.762125)
			(xy 123.153337 -274.778013) (xy 123.199149 -274.801356) (xy 123.240745 -274.831577) (xy 123.277101 -274.867933)
			(xy 123.307322 -274.909529) (xy 123.330665 -274.955341) (xy 123.346553 -275.00424) (xy 123.354596 -275.055022)
			(xy 123.3551 -275.08073) (xy 123.354596 -275.106438) (xy 123.6411 -275.106438) (xy 123.6411 -275.055022)
			(xy 123.649143 -275.00424) (xy 123.665031 -274.955341) (xy 123.688374 -274.909529) (xy 123.718595 -274.867933)
			(xy 123.754951 -274.831577) (xy 123.796547 -274.801356) (xy 123.842359 -274.778013) (xy 123.891258 -274.762125)
			(xy 123.94204 -274.754082) (xy 123.993456 -274.754082) (xy 124.044238 -274.762125) (xy 124.093137 -274.778013)
			(xy 124.138949 -274.801356) (xy 124.180545 -274.831577) (xy 124.216901 -274.867933) (xy 124.247122 -274.909529)
			(xy 124.270465 -274.955341) (xy 124.286353 -275.00424) (xy 124.294396 -275.055022) (xy 124.2949 -275.08073)
			(xy 124.294396 -275.106438) (xy 124.5809 -275.106438) (xy 124.5809 -275.055022) (xy 124.588943 -275.00424)
			(xy 124.604831 -274.955341) (xy 124.628174 -274.909529) (xy 124.658395 -274.867933) (xy 124.694751 -274.831577)
			(xy 124.736347 -274.801356) (xy 124.782159 -274.778013) (xy 124.831058 -274.762125) (xy 124.88184 -274.754082)
			(xy 124.933256 -274.754082) (xy 124.984038 -274.762125) (xy 125.032937 -274.778013) (xy 125.078749 -274.801356)
			(xy 125.120345 -274.831577) (xy 125.156701 -274.867933) (xy 125.186922 -274.909529) (xy 125.210265 -274.955341)
			(xy 125.226153 -275.00424) (xy 125.234196 -275.055022) (xy 125.2347 -275.08073) (xy 125.234196 -275.106438)
			(xy 125.5207 -275.106438) (xy 125.5207 -275.055022) (xy 125.528743 -275.00424) (xy 125.544631 -274.955341)
			(xy 125.567974 -274.909529) (xy 125.598195 -274.867933) (xy 125.634551 -274.831577) (xy 125.676147 -274.801356)
			(xy 125.721959 -274.778013) (xy 125.770858 -274.762125) (xy 125.82164 -274.754082) (xy 125.873056 -274.754082)
			(xy 125.923838 -274.762125) (xy 125.972737 -274.778013) (xy 126.018549 -274.801356) (xy 126.060145 -274.831577)
			(xy 126.096501 -274.867933) (xy 126.126722 -274.909529) (xy 126.150065 -274.955341) (xy 126.165953 -275.00424)
			(xy 126.173996 -275.055022) (xy 126.1745 -275.08073) (xy 126.173996 -275.106438) (xy 126.173847 -275.107379)
			(xy 126.431284 -275.107379) (xy 126.431284 -275.054081) (xy 126.439227 -275.001377) (xy 126.454937 -274.950447)
			(xy 126.478063 -274.902426) (xy 126.508087 -274.858389) (xy 126.544339 -274.819318) (xy 126.58601 -274.786087)
			(xy 126.632168 -274.759438) (xy 126.681782 -274.739966) (xy 126.733744 -274.728106) (xy 126.786894 -274.724123)
			(xy 126.840044 -274.728106) (xy 126.892006 -274.739966) (xy 126.94162 -274.759438) (xy 126.987778 -274.786087)
			(xy 127.029449 -274.819318) (xy 127.065701 -274.858389) (xy 127.095725 -274.902426) (xy 127.118851 -274.950447)
			(xy 127.134561 -275.001377) (xy 127.142504 -275.054081) (xy 127.143002 -275.08073) (xy 127.142504 -275.107379)
			(xy 127.371338 -275.107379) (xy 127.371338 -275.054081) (xy 127.379281 -275.001377) (xy 127.394991 -274.950447)
			(xy 127.418117 -274.902426) (xy 127.448141 -274.858389) (xy 127.484393 -274.819318) (xy 127.526064 -274.786087)
			(xy 127.572222 -274.759438) (xy 127.621836 -274.739966) (xy 127.673798 -274.728106) (xy 127.726948 -274.724123)
			(xy 127.780098 -274.728106) (xy 127.83206 -274.739966) (xy 127.881674 -274.759438) (xy 127.927832 -274.786087)
			(xy 127.969503 -274.819318) (xy 128.005755 -274.858389) (xy 128.035779 -274.902426) (xy 128.058905 -274.950447)
			(xy 128.074615 -275.001377) (xy 128.082558 -275.054081) (xy 128.083056 -275.08073) (xy 128.082558 -275.107379)
			(xy 128.311138 -275.107379) (xy 128.311138 -275.054081) (xy 128.319081 -275.001377) (xy 128.334791 -274.950447)
			(xy 128.357917 -274.902426) (xy 128.387941 -274.858389) (xy 128.424193 -274.819318) (xy 128.465864 -274.786087)
			(xy 128.512022 -274.759438) (xy 128.561636 -274.739966) (xy 128.613598 -274.728106) (xy 128.666748 -274.724123)
			(xy 128.719898 -274.728106) (xy 128.77186 -274.739966) (xy 128.821474 -274.759438) (xy 128.867632 -274.786087)
			(xy 128.909303 -274.819318) (xy 128.945555 -274.858389) (xy 128.975579 -274.902426) (xy 128.998705 -274.950447)
			(xy 129.014415 -275.001377) (xy 129.022358 -275.054081) (xy 129.022856 -275.08073) (xy 129.022376 -275.106438)
			(xy 129.2799 -275.106438) (xy 129.2799 -275.055022) (xy 129.287943 -275.00424) (xy 129.303831 -274.955341)
			(xy 129.327174 -274.909529) (xy 129.357395 -274.867933) (xy 129.393751 -274.831577) (xy 129.435347 -274.801356)
			(xy 129.481159 -274.778013) (xy 129.530058 -274.762125) (xy 129.58084 -274.754082) (xy 129.632256 -274.754082)
			(xy 129.683038 -274.762125) (xy 129.731937 -274.778013) (xy 129.777749 -274.801356) (xy 129.819345 -274.831577)
			(xy 129.855701 -274.867933) (xy 129.885922 -274.909529) (xy 129.909265 -274.955341) (xy 129.925153 -275.00424)
			(xy 129.933196 -275.055022) (xy 129.9337 -275.08073) (xy 129.933196 -275.106438) (xy 130.2197 -275.106438)
			(xy 130.2197 -275.055022) (xy 130.227743 -275.00424) (xy 130.243631 -274.955341) (xy 130.266974 -274.909529)
			(xy 130.297195 -274.867933) (xy 130.333551 -274.831577) (xy 130.375147 -274.801356) (xy 130.420959 -274.778013)
			(xy 130.469858 -274.762125) (xy 130.52064 -274.754082) (xy 130.572056 -274.754082) (xy 130.622838 -274.762125)
			(xy 130.671737 -274.778013) (xy 130.717549 -274.801356) (xy 130.759145 -274.831577) (xy 130.795501 -274.867933)
			(xy 130.825722 -274.909529) (xy 130.849065 -274.955341) (xy 130.864953 -275.00424) (xy 130.872996 -275.055022)
			(xy 130.8735 -275.08073) (xy 130.872996 -275.106438) (xy 131.1595 -275.106438) (xy 131.1595 -275.055022)
			(xy 131.167543 -275.00424) (xy 131.183431 -274.955341) (xy 131.206774 -274.909529) (xy 131.236995 -274.867933)
			(xy 131.273351 -274.831577) (xy 131.314947 -274.801356) (xy 131.360759 -274.778013) (xy 131.409658 -274.762125)
			(xy 131.46044 -274.754082) (xy 131.511856 -274.754082) (xy 131.562638 -274.762125) (xy 131.611537 -274.778013)
			(xy 131.657349 -274.801356) (xy 131.698945 -274.831577) (xy 131.735301 -274.867933) (xy 131.765522 -274.909529)
			(xy 131.788865 -274.955341) (xy 131.804753 -275.00424) (xy 131.812796 -275.055022) (xy 131.8133 -275.08073)
			(xy 131.812796 -275.106438) (xy 132.0993 -275.106438) (xy 132.0993 -275.055022) (xy 132.107343 -275.00424)
			(xy 132.123231 -274.955341) (xy 132.146574 -274.909529) (xy 132.176795 -274.867933) (xy 132.213151 -274.831577)
			(xy 132.254747 -274.801356) (xy 132.300559 -274.778013) (xy 132.349458 -274.762125) (xy 132.40024 -274.754082)
			(xy 132.451656 -274.754082) (xy 132.502438 -274.762125) (xy 132.551337 -274.778013) (xy 132.597149 -274.801356)
			(xy 132.638745 -274.831577) (xy 132.675101 -274.867933) (xy 132.705322 -274.909529) (xy 132.728665 -274.955341)
			(xy 132.744553 -275.00424) (xy 132.752596 -275.055022) (xy 132.7531 -275.08073) (xy 132.752596 -275.106438)
			(xy 132.752447 -275.107379) (xy 133.009884 -275.107379) (xy 133.009884 -275.054081) (xy 133.017827 -275.001377)
			(xy 133.033537 -274.950447) (xy 133.056663 -274.902426) (xy 133.086687 -274.858389) (xy 133.122939 -274.819318)
			(xy 133.16461 -274.786087) (xy 133.210768 -274.759438) (xy 133.260382 -274.739966) (xy 133.312344 -274.728106)
			(xy 133.365494 -274.724123) (xy 133.418644 -274.728106) (xy 133.470606 -274.739966) (xy 133.52022 -274.759438)
			(xy 133.566378 -274.786087) (xy 133.608049 -274.819318) (xy 133.644301 -274.858389) (xy 133.674325 -274.902426)
			(xy 133.697451 -274.950447) (xy 133.713161 -275.001377) (xy 133.721104 -275.054081) (xy 133.721602 -275.08073)
			(xy 133.721104 -275.107379) (xy 133.949938 -275.107379) (xy 133.949938 -275.054081) (xy 133.957881 -275.001377)
			(xy 133.973591 -274.950447) (xy 133.996717 -274.902426) (xy 134.026741 -274.858389) (xy 134.062993 -274.819318)
			(xy 134.104664 -274.786087) (xy 134.150822 -274.759438) (xy 134.200436 -274.739966) (xy 134.252398 -274.728106)
			(xy 134.305548 -274.724123) (xy 134.358698 -274.728106) (xy 134.41066 -274.739966) (xy 134.460274 -274.759438)
			(xy 134.506432 -274.786087) (xy 134.548103 -274.819318) (xy 134.584355 -274.858389) (xy 134.614379 -274.902426)
			(xy 134.637505 -274.950447) (xy 134.653215 -275.001377) (xy 134.661158 -275.054081) (xy 134.661656 -275.08073)
			(xy 134.661158 -275.107379) (xy 134.66112 -275.107633) (xy 134.889738 -275.107633) (xy 134.889738 -275.054335)
			(xy 134.897681 -275.001631) (xy 134.913391 -274.950701) (xy 134.936517 -274.90268) (xy 134.966541 -274.858643)
			(xy 135.002793 -274.819572) (xy 135.044464 -274.786341) (xy 135.090622 -274.759692) (xy 135.140236 -274.74022)
			(xy 135.192198 -274.72836) (xy 135.245348 -274.724377) (xy 135.298498 -274.72836) (xy 135.35046 -274.74022)
			(xy 135.400074 -274.759692) (xy 135.446232 -274.786341) (xy 135.487903 -274.819572) (xy 135.524155 -274.858643)
			(xy 135.554179 -274.90268) (xy 135.577305 -274.950701) (xy 135.593015 -275.001631) (xy 135.600958 -275.054335)
			(xy 135.601456 -275.080984) (xy 135.841235 -275.080984) (xy 135.845265 -275.028486) (xy 135.857262 -274.977218)
			(xy 135.876945 -274.928383) (xy 135.903851 -274.883124) (xy 135.937351 -274.842503) (xy 135.976659 -274.807472)
			(xy 136.020854 -274.778852) (xy 136.068899 -274.757313) (xy 136.11967 -274.743361) (xy 136.171975 -274.737323)
			(xy 136.224589 -274.73934) (xy 136.276279 -274.749364) (xy 136.325832 -274.767162) (xy 136.372088 -274.792315)
			(xy 136.413962 -274.824234) (xy 136.450474 -274.862172) (xy 136.480766 -274.905238) (xy 136.504129 -274.952423)
			(xy 136.520015 -275.002622) (xy 136.528052 -275.054658) (xy 136.528556 -275.080984) (xy 136.528052 -275.10731)
			(xy 136.528002 -275.107633) (xy 138.648938 -275.107633) (xy 138.648938 -275.054335) (xy 138.656881 -275.001631)
			(xy 138.672591 -274.950701) (xy 138.695717 -274.90268) (xy 138.725741 -274.858643) (xy 138.761993 -274.819572)
			(xy 138.803664 -274.786341) (xy 138.849822 -274.759692) (xy 138.899436 -274.74022) (xy 138.951398 -274.72836)
			(xy 139.004548 -274.724377) (xy 139.057698 -274.72836) (xy 139.10966 -274.74022) (xy 139.159274 -274.759692)
			(xy 139.205432 -274.786341) (xy 139.247103 -274.819572) (xy 139.283355 -274.858643) (xy 139.313379 -274.90268)
			(xy 139.336505 -274.950701) (xy 139.352215 -275.001631) (xy 139.360158 -275.054335) (xy 139.360656 -275.080984)
			(xy 139.360158 -275.107633) (xy 139.352215 -275.160337) (xy 139.336505 -275.211267) (xy 139.313379 -275.259288)
			(xy 139.283355 -275.303325) (xy 139.247103 -275.342396) (xy 139.205432 -275.375627) (xy 139.159274 -275.402276)
			(xy 139.10966 -275.421748) (xy 139.057698 -275.433608) (xy 139.004548 -275.437592) (xy 138.951398 -275.433608)
			(xy 138.899436 -275.421748) (xy 138.849822 -275.402276) (xy 138.803664 -275.375627) (xy 138.761993 -275.342396)
			(xy 138.725741 -275.303325) (xy 138.695717 -275.259288) (xy 138.672591 -275.211267) (xy 138.656881 -275.160337)
			(xy 138.648938 -275.107633) (xy 136.528002 -275.107633) (xy 136.520015 -275.159346) (xy 136.504129 -275.209545)
			(xy 136.480766 -275.25673) (xy 136.450474 -275.299796) (xy 136.413962 -275.337734) (xy 136.372088 -275.369653)
			(xy 136.325832 -275.394806) (xy 136.276279 -275.412604) (xy 136.224589 -275.422628) (xy 136.171975 -275.424645)
			(xy 136.11967 -275.418607) (xy 136.068899 -275.404655) (xy 136.020854 -275.383116) (xy 135.976659 -275.354496)
			(xy 135.937351 -275.319465) (xy 135.903851 -275.278844) (xy 135.876945 -275.233585) (xy 135.857262 -275.18475)
			(xy 135.845265 -275.133482) (xy 135.841235 -275.080984) (xy 135.601456 -275.080984) (xy 135.600958 -275.107633)
			(xy 135.593015 -275.160337) (xy 135.577305 -275.211267) (xy 135.554179 -275.259288) (xy 135.524155 -275.303325)
			(xy 135.487903 -275.342396) (xy 135.446232 -275.375627) (xy 135.400074 -275.402276) (xy 135.35046 -275.421748)
			(xy 135.298498 -275.433608) (xy 135.245348 -275.437592) (xy 135.192198 -275.433608) (xy 135.140236 -275.421748)
			(xy 135.090622 -275.402276) (xy 135.044464 -275.375627) (xy 135.002793 -275.342396) (xy 134.966541 -275.303325)
			(xy 134.936517 -275.259288) (xy 134.913391 -275.211267) (xy 134.897681 -275.160337) (xy 134.889738 -275.107633)
			(xy 134.66112 -275.107633) (xy 134.653215 -275.160083) (xy 134.637505 -275.211013) (xy 134.614379 -275.259034)
			(xy 134.584355 -275.303071) (xy 134.548103 -275.342142) (xy 134.506432 -275.375373) (xy 134.460274 -275.402022)
			(xy 134.41066 -275.421494) (xy 134.358698 -275.433354) (xy 134.305548 -275.437338) (xy 134.252398 -275.433354)
			(xy 134.200436 -275.421494) (xy 134.150822 -275.402022) (xy 134.104664 -275.375373) (xy 134.062993 -275.342142)
			(xy 134.026741 -275.303071) (xy 133.996717 -275.259034) (xy 133.973591 -275.211013) (xy 133.957881 -275.160083)
			(xy 133.949938 -275.107379) (xy 133.721104 -275.107379) (xy 133.713161 -275.160083) (xy 133.697451 -275.211013)
			(xy 133.674325 -275.259034) (xy 133.644301 -275.303071) (xy 133.608049 -275.342142) (xy 133.566378 -275.375373)
			(xy 133.52022 -275.402022) (xy 133.470606 -275.421494) (xy 133.418644 -275.433354) (xy 133.365494 -275.437338)
			(xy 133.312344 -275.433354) (xy 133.260382 -275.421494) (xy 133.210768 -275.402022) (xy 133.16461 -275.375373)
			(xy 133.122939 -275.342142) (xy 133.086687 -275.303071) (xy 133.056663 -275.259034) (xy 133.033537 -275.211013)
			(xy 133.017827 -275.160083) (xy 133.009884 -275.107379) (xy 132.752447 -275.107379) (xy 132.744553 -275.15722)
			(xy 132.728665 -275.206119) (xy 132.705322 -275.251931) (xy 132.675101 -275.293527) (xy 132.638745 -275.329883)
			(xy 132.597149 -275.360104) (xy 132.551337 -275.383447) (xy 132.502438 -275.399335) (xy 132.451656 -275.407378)
			(xy 132.40024 -275.407378) (xy 132.349458 -275.399335) (xy 132.300559 -275.383447) (xy 132.254747 -275.360104)
			(xy 132.213151 -275.329883) (xy 132.176795 -275.293527) (xy 132.146574 -275.251931) (xy 132.123231 -275.206119)
			(xy 132.107343 -275.15722) (xy 132.0993 -275.106438) (xy 131.812796 -275.106438) (xy 131.804753 -275.15722)
			(xy 131.788865 -275.206119) (xy 131.765522 -275.251931) (xy 131.735301 -275.293527) (xy 131.698945 -275.329883)
			(xy 131.657349 -275.360104) (xy 131.611537 -275.383447) (xy 131.562638 -275.399335) (xy 131.511856 -275.407378)
			(xy 131.46044 -275.407378) (xy 131.409658 -275.399335) (xy 131.360759 -275.383447) (xy 131.314947 -275.360104)
			(xy 131.273351 -275.329883) (xy 131.236995 -275.293527) (xy 131.206774 -275.251931) (xy 131.183431 -275.206119)
			(xy 131.167543 -275.15722) (xy 131.1595 -275.106438) (xy 130.872996 -275.106438) (xy 130.864953 -275.15722)
			(xy 130.849065 -275.206119) (xy 130.825722 -275.251931) (xy 130.795501 -275.293527) (xy 130.759145 -275.329883)
			(xy 130.717549 -275.360104) (xy 130.671737 -275.383447) (xy 130.622838 -275.399335) (xy 130.572056 -275.407378)
			(xy 130.52064 -275.407378) (xy 130.469858 -275.399335) (xy 130.420959 -275.383447) (xy 130.375147 -275.360104)
			(xy 130.333551 -275.329883) (xy 130.297195 -275.293527) (xy 130.266974 -275.251931) (xy 130.243631 -275.206119)
			(xy 130.227743 -275.15722) (xy 130.2197 -275.106438) (xy 129.933196 -275.106438) (xy 129.925153 -275.15722)
			(xy 129.909265 -275.206119) (xy 129.885922 -275.251931) (xy 129.855701 -275.293527) (xy 129.819345 -275.329883)
			(xy 129.777749 -275.360104) (xy 129.731937 -275.383447) (xy 129.683038 -275.399335) (xy 129.632256 -275.407378)
			(xy 129.58084 -275.407378) (xy 129.530058 -275.399335) (xy 129.481159 -275.383447) (xy 129.435347 -275.360104)
			(xy 129.393751 -275.329883) (xy 129.357395 -275.293527) (xy 129.327174 -275.251931) (xy 129.303831 -275.206119)
			(xy 129.287943 -275.15722) (xy 129.2799 -275.106438) (xy 129.022376 -275.106438) (xy 129.022358 -275.107379)
			(xy 129.014415 -275.160083) (xy 128.998705 -275.211013) (xy 128.975579 -275.259034) (xy 128.945555 -275.303071)
			(xy 128.909303 -275.342142) (xy 128.867632 -275.375373) (xy 128.821474 -275.402022) (xy 128.77186 -275.421494)
			(xy 128.719898 -275.433354) (xy 128.666748 -275.437338) (xy 128.613598 -275.433354) (xy 128.561636 -275.421494)
			(xy 128.512022 -275.402022) (xy 128.465864 -275.375373) (xy 128.424193 -275.342142) (xy 128.387941 -275.303071)
			(xy 128.357917 -275.259034) (xy 128.334791 -275.211013) (xy 128.319081 -275.160083) (xy 128.311138 -275.107379)
			(xy 128.082558 -275.107379) (xy 128.074615 -275.160083) (xy 128.058905 -275.211013) (xy 128.035779 -275.259034)
			(xy 128.005755 -275.303071) (xy 127.969503 -275.342142) (xy 127.927832 -275.375373) (xy 127.881674 -275.402022)
			(xy 127.83206 -275.421494) (xy 127.780098 -275.433354) (xy 127.726948 -275.437338) (xy 127.673798 -275.433354)
			(xy 127.621836 -275.421494) (xy 127.572222 -275.402022) (xy 127.526064 -275.375373) (xy 127.484393 -275.342142)
			(xy 127.448141 -275.303071) (xy 127.418117 -275.259034) (xy 127.394991 -275.211013) (xy 127.379281 -275.160083)
			(xy 127.371338 -275.107379) (xy 127.142504 -275.107379) (xy 127.134561 -275.160083) (xy 127.118851 -275.211013)
			(xy 127.095725 -275.259034) (xy 127.065701 -275.303071) (xy 127.029449 -275.342142) (xy 126.987778 -275.375373)
			(xy 126.94162 -275.402022) (xy 126.892006 -275.421494) (xy 126.840044 -275.433354) (xy 126.786894 -275.437338)
			(xy 126.733744 -275.433354) (xy 126.681782 -275.421494) (xy 126.632168 -275.402022) (xy 126.58601 -275.375373)
			(xy 126.544339 -275.342142) (xy 126.508087 -275.303071) (xy 126.478063 -275.259034) (xy 126.454937 -275.211013)
			(xy 126.439227 -275.160083) (xy 126.431284 -275.107379) (xy 126.173847 -275.107379) (xy 126.165953 -275.15722)
			(xy 126.150065 -275.206119) (xy 126.126722 -275.251931) (xy 126.096501 -275.293527) (xy 126.060145 -275.329883)
			(xy 126.018549 -275.360104) (xy 125.972737 -275.383447) (xy 125.923838 -275.399335) (xy 125.873056 -275.407378)
			(xy 125.82164 -275.407378) (xy 125.770858 -275.399335) (xy 125.721959 -275.383447) (xy 125.676147 -275.360104)
			(xy 125.634551 -275.329883) (xy 125.598195 -275.293527) (xy 125.567974 -275.251931) (xy 125.544631 -275.206119)
			(xy 125.528743 -275.15722) (xy 125.5207 -275.106438) (xy 125.234196 -275.106438) (xy 125.226153 -275.15722)
			(xy 125.210265 -275.206119) (xy 125.186922 -275.251931) (xy 125.156701 -275.293527) (xy 125.120345 -275.329883)
			(xy 125.078749 -275.360104) (xy 125.032937 -275.383447) (xy 124.984038 -275.399335) (xy 124.933256 -275.407378)
			(xy 124.88184 -275.407378) (xy 124.831058 -275.399335) (xy 124.782159 -275.383447) (xy 124.736347 -275.360104)
			(xy 124.694751 -275.329883) (xy 124.658395 -275.293527) (xy 124.628174 -275.251931) (xy 124.604831 -275.206119)
			(xy 124.588943 -275.15722) (xy 124.5809 -275.106438) (xy 124.294396 -275.106438) (xy 124.286353 -275.15722)
			(xy 124.270465 -275.206119) (xy 124.247122 -275.251931) (xy 124.216901 -275.293527) (xy 124.180545 -275.329883)
			(xy 124.138949 -275.360104) (xy 124.093137 -275.383447) (xy 124.044238 -275.399335) (xy 123.993456 -275.407378)
			(xy 123.94204 -275.407378) (xy 123.891258 -275.399335) (xy 123.842359 -275.383447) (xy 123.796547 -275.360104)
			(xy 123.754951 -275.329883) (xy 123.718595 -275.293527) (xy 123.688374 -275.251931) (xy 123.665031 -275.206119)
			(xy 123.649143 -275.15722) (xy 123.6411 -275.106438) (xy 123.354596 -275.106438) (xy 123.346553 -275.15722)
			(xy 123.330665 -275.206119) (xy 123.307322 -275.251931) (xy 123.277101 -275.293527) (xy 123.240745 -275.329883)
			(xy 123.199149 -275.360104) (xy 123.153337 -275.383447) (xy 123.104438 -275.399335) (xy 123.053656 -275.407378)
			(xy 123.00224 -275.407378) (xy 122.951458 -275.399335) (xy 122.902559 -275.383447) (xy 122.856747 -275.360104)
			(xy 122.815151 -275.329883) (xy 122.778795 -275.293527) (xy 122.748574 -275.251931) (xy 122.725231 -275.206119)
			(xy 122.709343 -275.15722) (xy 122.7013 -275.106438) (xy 122.443776 -275.106438) (xy 122.443758 -275.107379)
			(xy 122.435815 -275.160083) (xy 122.420105 -275.211013) (xy 122.396979 -275.259034) (xy 122.366955 -275.303071)
			(xy 122.330703 -275.342142) (xy 122.289032 -275.375373) (xy 122.242874 -275.402022) (xy 122.19326 -275.421494)
			(xy 122.141298 -275.433354) (xy 122.088148 -275.437338) (xy 122.034998 -275.433354) (xy 121.983036 -275.421494)
			(xy 121.933422 -275.402022) (xy 121.887264 -275.375373) (xy 121.845593 -275.342142) (xy 121.809341 -275.303071)
			(xy 121.779317 -275.259034) (xy 121.756191 -275.211013) (xy 121.740481 -275.160083) (xy 121.732538 -275.107379)
			(xy 121.503666 -275.107379) (xy 121.495761 -275.159829) (xy 121.480051 -275.210759) (xy 121.456925 -275.25878)
			(xy 121.426901 -275.302817) (xy 121.390649 -275.341888) (xy 121.348978 -275.375119) (xy 121.30282 -275.401768)
			(xy 121.253206 -275.42124) (xy 121.201244 -275.4331) (xy 121.148094 -275.437084) (xy 121.094944 -275.4331)
			(xy 121.042982 -275.42124) (xy 120.993368 -275.401768) (xy 120.94721 -275.375119) (xy 120.905539 -275.341888)
			(xy 120.869287 -275.302817) (xy 120.839263 -275.25878) (xy 120.816137 -275.210759) (xy 120.800427 -275.159829)
			(xy 120.792484 -275.107125) (xy 120.564163 -275.107125) (xy 120.564158 -275.107379) (xy 120.556215 -275.160083)
			(xy 120.540505 -275.211013) (xy 120.517379 -275.259034) (xy 120.487355 -275.303071) (xy 120.451103 -275.342142)
			(xy 120.409432 -275.375373) (xy 120.363274 -275.402022) (xy 120.31366 -275.421494) (xy 120.261698 -275.433354)
			(xy 120.208548 -275.437338) (xy 120.155398 -275.433354) (xy 120.103436 -275.421494) (xy 120.053822 -275.402022)
			(xy 120.007664 -275.375373) (xy 119.965993 -275.342142) (xy 119.929741 -275.303071) (xy 119.899717 -275.259034)
			(xy 119.876591 -275.211013) (xy 119.860881 -275.160083) (xy 119.852938 -275.107379) (xy 119.624358 -275.107379)
			(xy 119.616415 -275.160083) (xy 119.600705 -275.211013) (xy 119.577579 -275.259034) (xy 119.547555 -275.303071)
			(xy 119.511303 -275.342142) (xy 119.469632 -275.375373) (xy 119.423474 -275.402022) (xy 119.37386 -275.421494)
			(xy 119.321898 -275.433354) (xy 119.268748 -275.437338) (xy 119.215598 -275.433354) (xy 119.163636 -275.421494)
			(xy 119.114022 -275.402022) (xy 119.067864 -275.375373) (xy 119.026193 -275.342142) (xy 118.989941 -275.303071)
			(xy 118.959917 -275.259034) (xy 118.936791 -275.211013) (xy 118.921081 -275.160083) (xy 118.913138 -275.107379)
			(xy 118.683478 -275.107379) (xy 118.681495 -275.133841) (xy 118.669638 -275.185794) (xy 118.650171 -275.235401)
			(xy 118.623528 -275.281552) (xy 118.590305 -275.323217) (xy 118.551244 -275.359466) (xy 118.507216 -275.389489)
			(xy 118.459206 -275.412615) (xy 118.408286 -275.428328) (xy 118.355593 -275.436277) (xy 118.328948 -275.436838)
			(xy 118.300756 -275.436275) (xy 118.245082 -275.427343) (xy 118.191509 -275.409756) (xy 118.141373 -275.383954)
			(xy 118.095924 -275.350581) (xy 118.07571 -275.33092) (xy 118.064768 -275.320575) (xy 118.038321 -275.306208)
			(xy 118.008836 -275.300169) (xy 117.97887 -275.302982) (xy 117.951024 -275.314403) (xy 117.927714 -275.333441)
			(xy 117.910961 -275.358445) (xy 117.902219 -275.387245) (xy 117.90172 -275.402294) (xy 117.90172 -275.538946)
			(xy 117.940836 -275.548344) (xy 117.966495 -275.554919) (xy 118.015661 -275.574625) (xy 118.061364 -275.601398)
			(xy 118.102597 -275.634646) (xy 118.138449 -275.673635) (xy 118.168129 -275.717507) (xy 118.190982 -275.765291)
			(xy 118.206503 -275.815933) (xy 118.21435 -275.868316) (xy 118.21435 -275.921284) (xy 118.214325 -275.921449)
			(xy 118.443238 -275.921449) (xy 118.443238 -275.868151) (xy 118.451181 -275.815447) (xy 118.466891 -275.764517)
			(xy 118.490017 -275.716496) (xy 118.520041 -275.672459) (xy 118.556293 -275.633388) (xy 118.597964 -275.600157)
			(xy 118.644122 -275.573508) (xy 118.693736 -275.554036) (xy 118.745698 -275.542176) (xy 118.798848 -275.538193)
			(xy 118.851998 -275.542176) (xy 118.90396 -275.554036) (xy 118.953574 -275.573508) (xy 118.999732 -275.600157)
			(xy 119.041403 -275.633388) (xy 119.077655 -275.672459) (xy 119.107679 -275.716496) (xy 119.130805 -275.764517)
			(xy 119.146515 -275.815447) (xy 119.154458 -275.868151) (xy 119.154956 -275.8948) (xy 119.154463 -275.921195)
			(xy 119.383038 -275.921195) (xy 119.383038 -275.867897) (xy 119.390981 -275.815193) (xy 119.406691 -275.764263)
			(xy 119.429817 -275.716242) (xy 119.459841 -275.672205) (xy 119.496093 -275.633134) (xy 119.537764 -275.599903)
			(xy 119.583922 -275.573254) (xy 119.633536 -275.553782) (xy 119.685498 -275.541922) (xy 119.738648 -275.537939)
			(xy 119.791798 -275.541922) (xy 119.84376 -275.553782) (xy 119.893374 -275.573254) (xy 119.939532 -275.599903)
			(xy 119.981203 -275.633134) (xy 120.017455 -275.672205) (xy 120.047479 -275.716242) (xy 120.070605 -275.764263)
			(xy 120.086315 -275.815193) (xy 120.094258 -275.867897) (xy 120.094756 -275.894546) (xy 120.094258 -275.921195)
			(xy 120.322838 -275.921195) (xy 120.322838 -275.867897) (xy 120.330781 -275.815193) (xy 120.346491 -275.764263)
			(xy 120.369617 -275.716242) (xy 120.399641 -275.672205) (xy 120.435893 -275.633134) (xy 120.477564 -275.599903)
			(xy 120.523722 -275.573254) (xy 120.573336 -275.553782) (xy 120.625298 -275.541922) (xy 120.678448 -275.537939)
			(xy 120.731598 -275.541922) (xy 120.78356 -275.553782) (xy 120.833174 -275.573254) (xy 120.879332 -275.599903)
			(xy 120.921003 -275.633134) (xy 120.957255 -275.672205) (xy 120.987279 -275.716242) (xy 121.010405 -275.764263)
			(xy 121.026115 -275.815193) (xy 121.034058 -275.867897) (xy 121.034556 -275.894546) (xy 121.034058 -275.921195)
			(xy 121.262638 -275.921195) (xy 121.262638 -275.867897) (xy 121.270581 -275.815193) (xy 121.286291 -275.764263)
			(xy 121.309417 -275.716242) (xy 121.339441 -275.672205) (xy 121.375693 -275.633134) (xy 121.417364 -275.599903)
			(xy 121.463522 -275.573254) (xy 121.513136 -275.553782) (xy 121.565098 -275.541922) (xy 121.618248 -275.537939)
			(xy 121.671398 -275.541922) (xy 121.72336 -275.553782) (xy 121.772974 -275.573254) (xy 121.819132 -275.599903)
			(xy 121.860803 -275.633134) (xy 121.897055 -275.672205) (xy 121.927079 -275.716242) (xy 121.950205 -275.764263)
			(xy 121.965915 -275.815193) (xy 121.973858 -275.867897) (xy 121.974356 -275.894546) (xy 121.973858 -275.921195)
			(xy 121.97382 -275.921449) (xy 122.202438 -275.921449) (xy 122.202438 -275.868151) (xy 122.210381 -275.815447)
			(xy 122.226091 -275.764517) (xy 122.249217 -275.716496) (xy 122.279241 -275.672459) (xy 122.315493 -275.633388)
			(xy 122.357164 -275.600157) (xy 122.403322 -275.573508) (xy 122.452936 -275.554036) (xy 122.504898 -275.542176)
			(xy 122.558048 -275.538193) (xy 122.611198 -275.542176) (xy 122.66316 -275.554036) (xy 122.712774 -275.573508)
			(xy 122.758932 -275.600157) (xy 122.800603 -275.633388) (xy 122.836855 -275.672459) (xy 122.866879 -275.716496)
			(xy 122.890005 -275.764517) (xy 122.905715 -275.815447) (xy 122.913658 -275.868151) (xy 122.914156 -275.8948)
			(xy 122.913676 -275.920508) (xy 123.170946 -275.920508) (xy 123.170946 -275.869092) (xy 123.178989 -275.81831)
			(xy 123.194877 -275.769411) (xy 123.21822 -275.723599) (xy 123.248441 -275.682003) (xy 123.284797 -275.645647)
			(xy 123.326393 -275.615426) (xy 123.372205 -275.592083) (xy 123.421104 -275.576195) (xy 123.471886 -275.568152)
			(xy 123.523302 -275.568152) (xy 123.574084 -275.576195) (xy 123.622983 -275.592083) (xy 123.668795 -275.615426)
			(xy 123.710391 -275.645647) (xy 123.746747 -275.682003) (xy 123.776968 -275.723599) (xy 123.800311 -275.769411)
			(xy 123.816199 -275.81831) (xy 123.824242 -275.869092) (xy 123.824746 -275.8948) (xy 123.824242 -275.920508)
			(xy 123.824093 -275.921449) (xy 124.081784 -275.921449) (xy 124.081784 -275.868151) (xy 124.089727 -275.815447)
			(xy 124.105437 -275.764517) (xy 124.128563 -275.716496) (xy 124.158587 -275.672459) (xy 124.194839 -275.633388)
			(xy 124.23651 -275.600157) (xy 124.282668 -275.573508) (xy 124.332282 -275.554036) (xy 124.384244 -275.542176)
			(xy 124.437394 -275.538193) (xy 124.490544 -275.542176) (xy 124.542506 -275.554036) (xy 124.59212 -275.573508)
			(xy 124.638278 -275.600157) (xy 124.679949 -275.633388) (xy 124.716201 -275.672459) (xy 124.746225 -275.716496)
			(xy 124.769351 -275.764517) (xy 124.785061 -275.815447) (xy 124.793004 -275.868151) (xy 124.793502 -275.8948)
			(xy 124.793022 -275.920508) (xy 125.050546 -275.920508) (xy 125.050546 -275.869092) (xy 125.058589 -275.81831)
			(xy 125.074477 -275.769411) (xy 125.09782 -275.723599) (xy 125.128041 -275.682003) (xy 125.164397 -275.645647)
			(xy 125.205993 -275.615426) (xy 125.251805 -275.592083) (xy 125.300704 -275.576195) (xy 125.351486 -275.568152)
			(xy 125.402902 -275.568152) (xy 125.453684 -275.576195) (xy 125.502583 -275.592083) (xy 125.548395 -275.615426)
			(xy 125.589991 -275.645647) (xy 125.626347 -275.682003) (xy 125.656568 -275.723599) (xy 125.679911 -275.769411)
			(xy 125.695799 -275.81831) (xy 125.703842 -275.869092) (xy 125.704346 -275.8948) (xy 125.703842 -275.920508)
			(xy 125.703693 -275.921449) (xy 125.961384 -275.921449) (xy 125.961384 -275.868151) (xy 125.969327 -275.815447)
			(xy 125.985037 -275.764517) (xy 126.008163 -275.716496) (xy 126.038187 -275.672459) (xy 126.074439 -275.633388)
			(xy 126.11611 -275.600157) (xy 126.162268 -275.573508) (xy 126.211882 -275.554036) (xy 126.263844 -275.542176)
			(xy 126.316994 -275.538193) (xy 126.370144 -275.542176) (xy 126.422106 -275.554036) (xy 126.47172 -275.573508)
			(xy 126.517878 -275.600157) (xy 126.559549 -275.633388) (xy 126.595801 -275.672459) (xy 126.625825 -275.716496)
			(xy 126.648951 -275.764517) (xy 126.664661 -275.815447) (xy 126.672604 -275.868151) (xy 126.673102 -275.8948)
			(xy 126.672622 -275.920508) (xy 126.930146 -275.920508) (xy 126.930146 -275.869092) (xy 126.938189 -275.81831)
			(xy 126.954077 -275.769411) (xy 126.97742 -275.723599) (xy 127.007641 -275.682003) (xy 127.043997 -275.645647)
			(xy 127.085593 -275.615426) (xy 127.131405 -275.592083) (xy 127.180304 -275.576195) (xy 127.231086 -275.568152)
			(xy 127.282502 -275.568152) (xy 127.333284 -275.576195) (xy 127.382183 -275.592083) (xy 127.427995 -275.615426)
			(xy 127.469591 -275.645647) (xy 127.505947 -275.682003) (xy 127.536168 -275.723599) (xy 127.559511 -275.769411)
			(xy 127.575399 -275.81831) (xy 127.583442 -275.869092) (xy 127.583946 -275.8948) (xy 127.583442 -275.920508)
			(xy 127.869946 -275.920508) (xy 127.869946 -275.869092) (xy 127.877989 -275.81831) (xy 127.893877 -275.769411)
			(xy 127.91722 -275.723599) (xy 127.947441 -275.682003) (xy 127.983797 -275.645647) (xy 128.025393 -275.615426)
			(xy 128.071205 -275.592083) (xy 128.120104 -275.576195) (xy 128.170886 -275.568152) (xy 128.222302 -275.568152)
			(xy 128.273084 -275.576195) (xy 128.321983 -275.592083) (xy 128.367795 -275.615426) (xy 128.409391 -275.645647)
			(xy 128.445747 -275.682003) (xy 128.475968 -275.723599) (xy 128.499311 -275.769411) (xy 128.515199 -275.81831)
			(xy 128.523242 -275.869092) (xy 128.523746 -275.8948) (xy 128.523242 -275.920508) (xy 128.523093 -275.921449)
			(xy 128.781038 -275.921449) (xy 128.781038 -275.868151) (xy 128.788981 -275.815447) (xy 128.804691 -275.764517)
			(xy 128.827817 -275.716496) (xy 128.857841 -275.672459) (xy 128.894093 -275.633388) (xy 128.935764 -275.600157)
			(xy 128.981922 -275.573508) (xy 129.031536 -275.554036) (xy 129.083498 -275.542176) (xy 129.136648 -275.538193)
			(xy 129.189798 -275.542176) (xy 129.24176 -275.554036) (xy 129.291374 -275.573508) (xy 129.337532 -275.600157)
			(xy 129.379203 -275.633388) (xy 129.415455 -275.672459) (xy 129.445479 -275.716496) (xy 129.468605 -275.764517)
			(xy 129.484315 -275.815447) (xy 129.492258 -275.868151) (xy 129.492756 -275.8948) (xy 129.492276 -275.920508)
			(xy 129.749546 -275.920508) (xy 129.749546 -275.869092) (xy 129.757589 -275.81831) (xy 129.773477 -275.769411)
			(xy 129.79682 -275.723599) (xy 129.827041 -275.682003) (xy 129.863397 -275.645647) (xy 129.904993 -275.615426)
			(xy 129.950805 -275.592083) (xy 129.999704 -275.576195) (xy 130.050486 -275.568152) (xy 130.101902 -275.568152)
			(xy 130.152684 -275.576195) (xy 130.201583 -275.592083) (xy 130.247395 -275.615426) (xy 130.288991 -275.645647)
			(xy 130.325347 -275.682003) (xy 130.355568 -275.723599) (xy 130.378911 -275.769411) (xy 130.394799 -275.81831)
			(xy 130.402842 -275.869092) (xy 130.403346 -275.8948) (xy 130.402842 -275.920508) (xy 130.402693 -275.921449)
			(xy 130.660384 -275.921449) (xy 130.660384 -275.868151) (xy 130.668327 -275.815447) (xy 130.684037 -275.764517)
			(xy 130.707163 -275.716496) (xy 130.737187 -275.672459) (xy 130.773439 -275.633388) (xy 130.81511 -275.600157)
			(xy 130.861268 -275.573508) (xy 130.910882 -275.554036) (xy 130.962844 -275.542176) (xy 131.015994 -275.538193)
			(xy 131.069144 -275.542176) (xy 131.121106 -275.554036) (xy 131.17072 -275.573508) (xy 131.216878 -275.600157)
			(xy 131.258549 -275.633388) (xy 131.294801 -275.672459) (xy 131.324825 -275.716496) (xy 131.347951 -275.764517)
			(xy 131.363661 -275.815447) (xy 131.371604 -275.868151) (xy 131.372102 -275.8948) (xy 131.371622 -275.920508)
			(xy 131.629146 -275.920508) (xy 131.629146 -275.869092) (xy 131.637189 -275.81831) (xy 131.653077 -275.769411)
			(xy 131.67642 -275.723599) (xy 131.706641 -275.682003) (xy 131.742997 -275.645647) (xy 131.784593 -275.615426)
			(xy 131.830405 -275.592083) (xy 131.879304 -275.576195) (xy 131.930086 -275.568152) (xy 131.981502 -275.568152)
			(xy 132.032284 -275.576195) (xy 132.081183 -275.592083) (xy 132.126995 -275.615426) (xy 132.168591 -275.645647)
			(xy 132.204947 -275.682003) (xy 132.235168 -275.723599) (xy 132.258511 -275.769411) (xy 132.274399 -275.81831)
			(xy 132.282442 -275.869092) (xy 132.282946 -275.8948) (xy 132.282442 -275.920508) (xy 132.282293 -275.921449)
			(xy 132.539984 -275.921449) (xy 132.539984 -275.868151) (xy 132.547927 -275.815447) (xy 132.563637 -275.764517)
			(xy 132.586763 -275.716496) (xy 132.616787 -275.672459) (xy 132.653039 -275.633388) (xy 132.69471 -275.600157)
			(xy 132.740868 -275.573508) (xy 132.790482 -275.554036) (xy 132.842444 -275.542176) (xy 132.895594 -275.538193)
			(xy 132.948744 -275.542176) (xy 133.000706 -275.554036) (xy 133.05032 -275.573508) (xy 133.096478 -275.600157)
			(xy 133.138149 -275.633388) (xy 133.174401 -275.672459) (xy 133.204425 -275.716496) (xy 133.227551 -275.764517)
			(xy 133.243261 -275.815447) (xy 133.251204 -275.868151) (xy 133.251702 -275.8948) (xy 133.251222 -275.920508)
			(xy 133.508746 -275.920508) (xy 133.508746 -275.869092) (xy 133.516789 -275.81831) (xy 133.532677 -275.769411)
			(xy 133.55602 -275.723599) (xy 133.586241 -275.682003) (xy 133.622597 -275.645647) (xy 133.664193 -275.615426)
			(xy 133.710005 -275.592083) (xy 133.758904 -275.576195) (xy 133.809686 -275.568152) (xy 133.861102 -275.568152)
			(xy 133.911884 -275.576195) (xy 133.960783 -275.592083) (xy 134.006595 -275.615426) (xy 134.048191 -275.645647)
			(xy 134.084547 -275.682003) (xy 134.114768 -275.723599) (xy 134.138111 -275.769411) (xy 134.153999 -275.81831)
			(xy 134.162042 -275.869092) (xy 134.162546 -275.8948) (xy 134.162042 -275.920508) (xy 134.448546 -275.920508)
			(xy 134.448546 -275.869092) (xy 134.456589 -275.81831) (xy 134.472477 -275.769411) (xy 134.49582 -275.723599)
			(xy 134.526041 -275.682003) (xy 134.562397 -275.645647) (xy 134.603993 -275.615426) (xy 134.649805 -275.592083)
			(xy 134.698704 -275.576195) (xy 134.749486 -275.568152) (xy 134.800902 -275.568152) (xy 134.851684 -275.576195)
			(xy 134.900583 -275.592083) (xy 134.946395 -275.615426) (xy 134.987991 -275.645647) (xy 135.024347 -275.682003)
			(xy 135.054568 -275.723599) (xy 135.077911 -275.769411) (xy 135.093799 -275.81831) (xy 135.101842 -275.869092)
			(xy 135.102346 -275.8948) (xy 135.101842 -275.920508) (xy 135.101693 -275.921449) (xy 135.359384 -275.921449)
			(xy 135.359384 -275.868151) (xy 135.367327 -275.815447) (xy 135.383037 -275.764517) (xy 135.406163 -275.716496)
			(xy 135.436187 -275.672459) (xy 135.472439 -275.633388) (xy 135.51411 -275.600157) (xy 135.560268 -275.573508)
			(xy 135.609882 -275.554036) (xy 135.661844 -275.542176) (xy 135.714994 -275.538193) (xy 135.768144 -275.542176)
			(xy 135.820106 -275.554036) (xy 135.86972 -275.573508) (xy 135.915878 -275.600157) (xy 135.957549 -275.633388)
			(xy 135.993801 -275.672459) (xy 136.023825 -275.716496) (xy 136.046951 -275.764517) (xy 136.062661 -275.815447)
			(xy 136.070604 -275.868151) (xy 136.071102 -275.8948) (xy 136.070604 -275.921449) (xy 136.062661 -275.974153)
			(xy 136.046951 -276.025083) (xy 136.023825 -276.073104) (xy 135.993801 -276.117141) (xy 135.957549 -276.156212)
			(xy 135.915878 -276.189443) (xy 135.86972 -276.216092) (xy 135.820106 -276.235564) (xy 135.768144 -276.247424)
			(xy 135.714994 -276.251408) (xy 135.661844 -276.247424) (xy 135.609882 -276.235564) (xy 135.560268 -276.216092)
			(xy 135.51411 -276.189443) (xy 135.472439 -276.156212) (xy 135.436187 -276.117141) (xy 135.406163 -276.073104)
			(xy 135.383037 -276.025083) (xy 135.367327 -275.974153) (xy 135.359384 -275.921449) (xy 135.101693 -275.921449)
			(xy 135.093799 -275.97129) (xy 135.077911 -276.020189) (xy 135.054568 -276.066001) (xy 135.024347 -276.107597)
			(xy 134.987991 -276.143953) (xy 134.946395 -276.174174) (xy 134.900583 -276.197517) (xy 134.851684 -276.213405)
			(xy 134.800902 -276.221448) (xy 134.749486 -276.221448) (xy 134.698704 -276.213405) (xy 134.649805 -276.197517)
			(xy 134.603993 -276.174174) (xy 134.562397 -276.143953) (xy 134.526041 -276.107597) (xy 134.49582 -276.066001)
			(xy 134.472477 -276.020189) (xy 134.456589 -275.97129) (xy 134.448546 -275.920508) (xy 134.162042 -275.920508)
			(xy 134.153999 -275.97129) (xy 134.138111 -276.020189) (xy 134.114768 -276.066001) (xy 134.084547 -276.107597)
			(xy 134.048191 -276.143953) (xy 134.006595 -276.174174) (xy 133.960783 -276.197517) (xy 133.911884 -276.213405)
			(xy 133.861102 -276.221448) (xy 133.809686 -276.221448) (xy 133.758904 -276.213405) (xy 133.710005 -276.197517)
			(xy 133.664193 -276.174174) (xy 133.622597 -276.143953) (xy 133.586241 -276.107597) (xy 133.55602 -276.066001)
			(xy 133.532677 -276.020189) (xy 133.516789 -275.97129) (xy 133.508746 -275.920508) (xy 133.251222 -275.920508)
			(xy 133.251204 -275.921449) (xy 133.243261 -275.974153) (xy 133.227551 -276.025083) (xy 133.204425 -276.073104)
			(xy 133.174401 -276.117141) (xy 133.138149 -276.156212) (xy 133.096478 -276.189443) (xy 133.05032 -276.216092)
			(xy 133.000706 -276.235564) (xy 132.948744 -276.247424) (xy 132.895594 -276.251408) (xy 132.842444 -276.247424)
			(xy 132.790482 -276.235564) (xy 132.740868 -276.216092) (xy 132.69471 -276.189443) (xy 132.653039 -276.156212)
			(xy 132.616787 -276.117141) (xy 132.586763 -276.073104) (xy 132.563637 -276.025083) (xy 132.547927 -275.974153)
			(xy 132.539984 -275.921449) (xy 132.282293 -275.921449) (xy 132.274399 -275.97129) (xy 132.258511 -276.020189)
			(xy 132.235168 -276.066001) (xy 132.204947 -276.107597) (xy 132.168591 -276.143953) (xy 132.126995 -276.174174)
			(xy 132.081183 -276.197517) (xy 132.032284 -276.213405) (xy 131.981502 -276.221448) (xy 131.930086 -276.221448)
			(xy 131.879304 -276.213405) (xy 131.830405 -276.197517) (xy 131.784593 -276.174174) (xy 131.742997 -276.143953)
			(xy 131.706641 -276.107597) (xy 131.67642 -276.066001) (xy 131.653077 -276.020189) (xy 131.637189 -275.97129)
			(xy 131.629146 -275.920508) (xy 131.371622 -275.920508) (xy 131.371604 -275.921449) (xy 131.363661 -275.974153)
			(xy 131.347951 -276.025083) (xy 131.324825 -276.073104) (xy 131.294801 -276.117141) (xy 131.258549 -276.156212)
			(xy 131.216878 -276.189443) (xy 131.17072 -276.216092) (xy 131.121106 -276.235564) (xy 131.069144 -276.247424)
			(xy 131.015994 -276.251408) (xy 130.962844 -276.247424) (xy 130.910882 -276.235564) (xy 130.861268 -276.216092)
			(xy 130.81511 -276.189443) (xy 130.773439 -276.156212) (xy 130.737187 -276.117141) (xy 130.707163 -276.073104)
			(xy 130.684037 -276.025083) (xy 130.668327 -275.974153) (xy 130.660384 -275.921449) (xy 130.402693 -275.921449)
			(xy 130.394799 -275.97129) (xy 130.378911 -276.020189) (xy 130.355568 -276.066001) (xy 130.325347 -276.107597)
			(xy 130.288991 -276.143953) (xy 130.247395 -276.174174) (xy 130.201583 -276.197517) (xy 130.152684 -276.213405)
			(xy 130.101902 -276.221448) (xy 130.050486 -276.221448) (xy 129.999704 -276.213405) (xy 129.950805 -276.197517)
			(xy 129.904993 -276.174174) (xy 129.863397 -276.143953) (xy 129.827041 -276.107597) (xy 129.79682 -276.066001)
			(xy 129.773477 -276.020189) (xy 129.757589 -275.97129) (xy 129.749546 -275.920508) (xy 129.492276 -275.920508)
			(xy 129.492258 -275.921449) (xy 129.484315 -275.974153) (xy 129.468605 -276.025083) (xy 129.445479 -276.073104)
			(xy 129.415455 -276.117141) (xy 129.379203 -276.156212) (xy 129.337532 -276.189443) (xy 129.291374 -276.216092)
			(xy 129.24176 -276.235564) (xy 129.189798 -276.247424) (xy 129.136648 -276.251408) (xy 129.083498 -276.247424)
			(xy 129.031536 -276.235564) (xy 128.981922 -276.216092) (xy 128.935764 -276.189443) (xy 128.894093 -276.156212)
			(xy 128.857841 -276.117141) (xy 128.827817 -276.073104) (xy 128.804691 -276.025083) (xy 128.788981 -275.974153)
			(xy 128.781038 -275.921449) (xy 128.523093 -275.921449) (xy 128.515199 -275.97129) (xy 128.499311 -276.020189)
			(xy 128.475968 -276.066001) (xy 128.445747 -276.107597) (xy 128.409391 -276.143953) (xy 128.367795 -276.174174)
			(xy 128.321983 -276.197517) (xy 128.273084 -276.213405) (xy 128.222302 -276.221448) (xy 128.170886 -276.221448)
			(xy 128.120104 -276.213405) (xy 128.071205 -276.197517) (xy 128.025393 -276.174174) (xy 127.983797 -276.143953)
			(xy 127.947441 -276.107597) (xy 127.91722 -276.066001) (xy 127.893877 -276.020189) (xy 127.877989 -275.97129)
			(xy 127.869946 -275.920508) (xy 127.583442 -275.920508) (xy 127.575399 -275.97129) (xy 127.559511 -276.020189)
			(xy 127.536168 -276.066001) (xy 127.505947 -276.107597) (xy 127.469591 -276.143953) (xy 127.427995 -276.174174)
			(xy 127.382183 -276.197517) (xy 127.333284 -276.213405) (xy 127.282502 -276.221448) (xy 127.231086 -276.221448)
			(xy 127.180304 -276.213405) (xy 127.131405 -276.197517) (xy 127.085593 -276.174174) (xy 127.043997 -276.143953)
			(xy 127.007641 -276.107597) (xy 126.97742 -276.066001) (xy 126.954077 -276.020189) (xy 126.938189 -275.97129)
			(xy 126.930146 -275.920508) (xy 126.672622 -275.920508) (xy 126.672604 -275.921449) (xy 126.664661 -275.974153)
			(xy 126.648951 -276.025083) (xy 126.625825 -276.073104) (xy 126.595801 -276.117141) (xy 126.559549 -276.156212)
			(xy 126.517878 -276.189443) (xy 126.47172 -276.216092) (xy 126.422106 -276.235564) (xy 126.370144 -276.247424)
			(xy 126.316994 -276.251408) (xy 126.263844 -276.247424) (xy 126.211882 -276.235564) (xy 126.162268 -276.216092)
			(xy 126.11611 -276.189443) (xy 126.074439 -276.156212) (xy 126.038187 -276.117141) (xy 126.008163 -276.073104)
			(xy 125.985037 -276.025083) (xy 125.969327 -275.974153) (xy 125.961384 -275.921449) (xy 125.703693 -275.921449)
			(xy 125.695799 -275.97129) (xy 125.679911 -276.020189) (xy 125.656568 -276.066001) (xy 125.626347 -276.107597)
			(xy 125.589991 -276.143953) (xy 125.548395 -276.174174) (xy 125.502583 -276.197517) (xy 125.453684 -276.213405)
			(xy 125.402902 -276.221448) (xy 125.351486 -276.221448) (xy 125.300704 -276.213405) (xy 125.251805 -276.197517)
			(xy 125.205993 -276.174174) (xy 125.164397 -276.143953) (xy 125.128041 -276.107597) (xy 125.09782 -276.066001)
			(xy 125.074477 -276.020189) (xy 125.058589 -275.97129) (xy 125.050546 -275.920508) (xy 124.793022 -275.920508)
			(xy 124.793004 -275.921449) (xy 124.785061 -275.974153) (xy 124.769351 -276.025083) (xy 124.746225 -276.073104)
			(xy 124.716201 -276.117141) (xy 124.679949 -276.156212) (xy 124.638278 -276.189443) (xy 124.59212 -276.216092)
			(xy 124.542506 -276.235564) (xy 124.490544 -276.247424) (xy 124.437394 -276.251408) (xy 124.384244 -276.247424)
			(xy 124.332282 -276.235564) (xy 124.282668 -276.216092) (xy 124.23651 -276.189443) (xy 124.194839 -276.156212)
			(xy 124.158587 -276.117141) (xy 124.128563 -276.073104) (xy 124.105437 -276.025083) (xy 124.089727 -275.974153)
			(xy 124.081784 -275.921449) (xy 123.824093 -275.921449) (xy 123.816199 -275.97129) (xy 123.800311 -276.020189)
			(xy 123.776968 -276.066001) (xy 123.746747 -276.107597) (xy 123.710391 -276.143953) (xy 123.668795 -276.174174)
			(xy 123.622983 -276.197517) (xy 123.574084 -276.213405) (xy 123.523302 -276.221448) (xy 123.471886 -276.221448)
			(xy 123.421104 -276.213405) (xy 123.372205 -276.197517) (xy 123.326393 -276.174174) (xy 123.284797 -276.143953)
			(xy 123.248441 -276.107597) (xy 123.21822 -276.066001) (xy 123.194877 -276.020189) (xy 123.178989 -275.97129)
			(xy 123.170946 -275.920508) (xy 122.913676 -275.920508) (xy 122.913658 -275.921449) (xy 122.905715 -275.974153)
			(xy 122.890005 -276.025083) (xy 122.866879 -276.073104) (xy 122.836855 -276.117141) (xy 122.800603 -276.156212)
			(xy 122.758932 -276.189443) (xy 122.712774 -276.216092) (xy 122.66316 -276.235564) (xy 122.611198 -276.247424)
			(xy 122.558048 -276.251408) (xy 122.504898 -276.247424) (xy 122.452936 -276.235564) (xy 122.403322 -276.216092)
			(xy 122.357164 -276.189443) (xy 122.315493 -276.156212) (xy 122.279241 -276.117141) (xy 122.249217 -276.073104)
			(xy 122.226091 -276.025083) (xy 122.210381 -275.974153) (xy 122.202438 -275.921449) (xy 121.97382 -275.921449)
			(xy 121.965915 -275.973899) (xy 121.950205 -276.024829) (xy 121.927079 -276.07285) (xy 121.897055 -276.116887)
			(xy 121.860803 -276.155958) (xy 121.819132 -276.189189) (xy 121.772974 -276.215838) (xy 121.72336 -276.23531)
			(xy 121.671398 -276.24717) (xy 121.618248 -276.251154) (xy 121.565098 -276.24717) (xy 121.513136 -276.23531)
			(xy 121.463522 -276.215838) (xy 121.417364 -276.189189) (xy 121.375693 -276.155958) (xy 121.339441 -276.116887)
			(xy 121.309417 -276.07285) (xy 121.286291 -276.024829) (xy 121.270581 -275.973899) (xy 121.262638 -275.921195)
			(xy 121.034058 -275.921195) (xy 121.026115 -275.973899) (xy 121.010405 -276.024829) (xy 120.987279 -276.07285)
			(xy 120.957255 -276.116887) (xy 120.921003 -276.155958) (xy 120.879332 -276.189189) (xy 120.833174 -276.215838)
			(xy 120.78356 -276.23531) (xy 120.731598 -276.24717) (xy 120.678448 -276.251154) (xy 120.625298 -276.24717)
			(xy 120.573336 -276.23531) (xy 120.523722 -276.215838) (xy 120.477564 -276.189189) (xy 120.435893 -276.155958)
			(xy 120.399641 -276.116887) (xy 120.369617 -276.07285) (xy 120.346491 -276.024829) (xy 120.330781 -275.973899)
			(xy 120.322838 -275.921195) (xy 120.094258 -275.921195) (xy 120.086315 -275.973899) (xy 120.070605 -276.024829)
			(xy 120.047479 -276.07285) (xy 120.017455 -276.116887) (xy 119.981203 -276.155958) (xy 119.939532 -276.189189)
			(xy 119.893374 -276.215838) (xy 119.84376 -276.23531) (xy 119.791798 -276.24717) (xy 119.738648 -276.251154)
			(xy 119.685498 -276.24717) (xy 119.633536 -276.23531) (xy 119.583922 -276.215838) (xy 119.537764 -276.189189)
			(xy 119.496093 -276.155958) (xy 119.459841 -276.116887) (xy 119.429817 -276.07285) (xy 119.406691 -276.024829)
			(xy 119.390981 -275.973899) (xy 119.383038 -275.921195) (xy 119.154463 -275.921195) (xy 119.154458 -275.921449)
			(xy 119.146515 -275.974153) (xy 119.130805 -276.025083) (xy 119.107679 -276.073104) (xy 119.077655 -276.117141)
			(xy 119.041403 -276.156212) (xy 118.999732 -276.189443) (xy 118.953574 -276.216092) (xy 118.90396 -276.235564)
			(xy 118.851998 -276.247424) (xy 118.798848 -276.251408) (xy 118.745698 -276.247424) (xy 118.693736 -276.235564)
			(xy 118.644122 -276.216092) (xy 118.597964 -276.189443) (xy 118.556293 -276.156212) (xy 118.520041 -276.117141)
			(xy 118.490017 -276.073104) (xy 118.466891 -276.025083) (xy 118.451181 -275.974153) (xy 118.443238 -275.921449)
			(xy 118.214325 -275.921449) (xy 118.206503 -275.973667) (xy 118.190982 -276.024309) (xy 118.168129 -276.072093)
			(xy 118.138449 -276.115965) (xy 118.102597 -276.154954) (xy 118.061364 -276.188202) (xy 118.015661 -276.214975)
			(xy 117.966495 -276.234681) (xy 117.940836 -276.241256) (xy 117.90172 -276.250654) (xy 117.90172 -276.386544)
			(xy 117.90225 -276.401563) (xy 117.910979 -276.430305) (xy 117.927698 -276.45526) (xy 117.950957 -276.474267)
			(xy 117.978743 -276.485679) (xy 118.008648 -276.488508) (xy 118.03808 -276.482507) (xy 118.064491 -276.468198)
			(xy 118.075456 -276.457918) (xy 118.095664 -276.438263) (xy 118.14113 -276.404942) (xy 118.191274 -276.379192)
			(xy 118.244846 -276.361655) (xy 118.30051 -276.352767) (xy 118.328694 -276.352254) (xy 118.355348 -276.352727)
			(xy 118.408062 -276.360671) (xy 118.459002 -276.376384) (xy 118.507032 -276.399513) (xy 118.551077 -276.429542)
			(xy 118.590156 -276.465801) (xy 118.623393 -276.507479) (xy 118.650048 -276.553645) (xy 118.669524 -276.603269)
			(xy 118.681386 -276.655241) (xy 118.68537 -276.7084) (xy 118.683357 -276.735265) (xy 118.912884 -276.735265)
			(xy 118.912884 -276.681967) (xy 118.920827 -276.629263) (xy 118.936537 -276.578333) (xy 118.959663 -276.530312)
			(xy 118.989687 -276.486275) (xy 119.025939 -276.447204) (xy 119.06761 -276.413973) (xy 119.113768 -276.387324)
			(xy 119.163382 -276.367852) (xy 119.215344 -276.355992) (xy 119.268494 -276.352009) (xy 119.321644 -276.355992)
			(xy 119.373606 -276.367852) (xy 119.42322 -276.387324) (xy 119.469378 -276.413973) (xy 119.511049 -276.447204)
			(xy 119.547301 -276.486275) (xy 119.577325 -276.530312) (xy 119.600451 -276.578333) (xy 119.616161 -276.629263)
			(xy 119.624104 -276.681967) (xy 119.624602 -276.708616) (xy 119.624109 -276.735011) (xy 119.852684 -276.735011)
			(xy 119.852684 -276.681713) (xy 119.860627 -276.629009) (xy 119.876337 -276.578079) (xy 119.899463 -276.530058)
			(xy 119.929487 -276.486021) (xy 119.965739 -276.44695) (xy 120.00741 -276.413719) (xy 120.053568 -276.38707)
			(xy 120.103182 -276.367598) (xy 120.155144 -276.355738) (xy 120.208294 -276.351755) (xy 120.261444 -276.355738)
			(xy 120.313406 -276.367598) (xy 120.36302 -276.38707) (xy 120.409178 -276.413719) (xy 120.450849 -276.44695)
			(xy 120.487101 -276.486021) (xy 120.517125 -276.530058) (xy 120.540251 -276.578079) (xy 120.555961 -276.629009)
			(xy 120.563904 -276.681713) (xy 120.564402 -276.708362) (xy 120.563904 -276.735011) (xy 120.563866 -276.735265)
			(xy 120.792738 -276.735265) (xy 120.792738 -276.681967) (xy 120.800681 -276.629263) (xy 120.816391 -276.578333)
			(xy 120.839517 -276.530312) (xy 120.869541 -276.486275) (xy 120.905793 -276.447204) (xy 120.947464 -276.413973)
			(xy 120.993622 -276.387324) (xy 121.043236 -276.367852) (xy 121.095198 -276.355992) (xy 121.148348 -276.352009)
			(xy 121.201498 -276.355992) (xy 121.25346 -276.367852) (xy 121.303074 -276.387324) (xy 121.349232 -276.413973)
			(xy 121.390903 -276.447204) (xy 121.427155 -276.486275) (xy 121.457179 -276.530312) (xy 121.480305 -276.578333)
			(xy 121.496015 -276.629263) (xy 121.503958 -276.681967) (xy 121.504456 -276.708616) (xy 121.503958 -276.735265)
			(xy 121.732538 -276.735265) (xy 121.732538 -276.681967) (xy 121.740481 -276.629263) (xy 121.756191 -276.578333)
			(xy 121.779317 -276.530312) (xy 121.809341 -276.486275) (xy 121.845593 -276.447204) (xy 121.887264 -276.413973)
			(xy 121.933422 -276.387324) (xy 121.983036 -276.367852) (xy 122.034998 -276.355992) (xy 122.088148 -276.352009)
			(xy 122.141298 -276.355992) (xy 122.19326 -276.367852) (xy 122.242874 -276.387324) (xy 122.289032 -276.413973)
			(xy 122.330703 -276.447204) (xy 122.366955 -276.486275) (xy 122.396979 -276.530312) (xy 122.420105 -276.578333)
			(xy 122.435815 -276.629263) (xy 122.443758 -276.681967) (xy 122.444256 -276.708616) (xy 122.443758 -276.735265)
			(xy 122.672338 -276.735265) (xy 122.672338 -276.681967) (xy 122.680281 -276.629263) (xy 122.695991 -276.578333)
			(xy 122.719117 -276.530312) (xy 122.749141 -276.486275) (xy 122.785393 -276.447204) (xy 122.827064 -276.413973)
			(xy 122.873222 -276.387324) (xy 122.922836 -276.367852) (xy 122.974798 -276.355992) (xy 123.027948 -276.352009)
			(xy 123.081098 -276.355992) (xy 123.13306 -276.367852) (xy 123.182674 -276.387324) (xy 123.228832 -276.413973)
			(xy 123.270503 -276.447204) (xy 123.306755 -276.486275) (xy 123.336779 -276.530312) (xy 123.359905 -276.578333)
			(xy 123.375615 -276.629263) (xy 123.383558 -276.681967) (xy 123.384056 -276.708616) (xy 123.383576 -276.734324)
			(xy 123.6411 -276.734324) (xy 123.6411 -276.682908) (xy 123.649143 -276.632126) (xy 123.665031 -276.583227)
			(xy 123.688374 -276.537415) (xy 123.718595 -276.495819) (xy 123.754951 -276.459463) (xy 123.796547 -276.429242)
			(xy 123.842359 -276.405899) (xy 123.891258 -276.390011) (xy 123.94204 -276.381968) (xy 123.993456 -276.381968)
			(xy 124.044238 -276.390011) (xy 124.093137 -276.405899) (xy 124.138949 -276.429242) (xy 124.180545 -276.459463)
			(xy 124.216901 -276.495819) (xy 124.247122 -276.537415) (xy 124.270465 -276.583227) (xy 124.286353 -276.632126)
			(xy 124.294396 -276.682908) (xy 124.2949 -276.708616) (xy 124.294396 -276.734324) (xy 124.5809 -276.734324)
			(xy 124.5809 -276.682908) (xy 124.588943 -276.632126) (xy 124.604831 -276.583227) (xy 124.628174 -276.537415)
			(xy 124.658395 -276.495819) (xy 124.694751 -276.459463) (xy 124.736347 -276.429242) (xy 124.782159 -276.405899)
			(xy 124.831058 -276.390011) (xy 124.88184 -276.381968) (xy 124.933256 -276.381968) (xy 124.984038 -276.390011)
			(xy 125.032937 -276.405899) (xy 125.078749 -276.429242) (xy 125.120345 -276.459463) (xy 125.156701 -276.495819)
			(xy 125.186922 -276.537415) (xy 125.210265 -276.583227) (xy 125.226153 -276.632126) (xy 125.234196 -276.682908)
			(xy 125.2347 -276.708616) (xy 125.234196 -276.734324) (xy 125.234047 -276.735265) (xy 125.491484 -276.735265)
			(xy 125.491484 -276.681967) (xy 125.499427 -276.629263) (xy 125.515137 -276.578333) (xy 125.538263 -276.530312)
			(xy 125.568287 -276.486275) (xy 125.604539 -276.447204) (xy 125.64621 -276.413973) (xy 125.692368 -276.387324)
			(xy 125.741982 -276.367852) (xy 125.793944 -276.355992) (xy 125.847094 -276.352009) (xy 125.900244 -276.355992)
			(xy 125.952206 -276.367852) (xy 126.00182 -276.387324) (xy 126.047978 -276.413973) (xy 126.089649 -276.447204)
			(xy 126.125901 -276.486275) (xy 126.155925 -276.530312) (xy 126.179051 -276.578333) (xy 126.194761 -276.629263)
			(xy 126.202704 -276.681967) (xy 126.203202 -276.708616) (xy 126.202722 -276.734324) (xy 126.4605 -276.734324)
			(xy 126.4605 -276.682908) (xy 126.468543 -276.632126) (xy 126.484431 -276.583227) (xy 126.507774 -276.537415)
			(xy 126.537995 -276.495819) (xy 126.574351 -276.459463) (xy 126.615947 -276.429242) (xy 126.661759 -276.405899)
			(xy 126.710658 -276.390011) (xy 126.76144 -276.381968) (xy 126.812856 -276.381968) (xy 126.863638 -276.390011)
			(xy 126.912537 -276.405899) (xy 126.958349 -276.429242) (xy 126.999945 -276.459463) (xy 127.036301 -276.495819)
			(xy 127.066522 -276.537415) (xy 127.089865 -276.583227) (xy 127.105753 -276.632126) (xy 127.113796 -276.682908)
			(xy 127.1143 -276.708616) (xy 127.113796 -276.734324) (xy 127.113647 -276.735265) (xy 127.371338 -276.735265)
			(xy 127.371338 -276.681967) (xy 127.379281 -276.629263) (xy 127.394991 -276.578333) (xy 127.418117 -276.530312)
			(xy 127.448141 -276.486275) (xy 127.484393 -276.447204) (xy 127.526064 -276.413973) (xy 127.572222 -276.387324)
			(xy 127.621836 -276.367852) (xy 127.673798 -276.355992) (xy 127.726948 -276.352009) (xy 127.780098 -276.355992)
			(xy 127.83206 -276.367852) (xy 127.881674 -276.387324) (xy 127.927832 -276.413973) (xy 127.969503 -276.447204)
			(xy 128.005755 -276.486275) (xy 128.035779 -276.530312) (xy 128.058905 -276.578333) (xy 128.074615 -276.629263)
			(xy 128.082558 -276.681967) (xy 128.083056 -276.708616) (xy 128.082576 -276.734324) (xy 128.3401 -276.734324)
			(xy 128.3401 -276.682908) (xy 128.348143 -276.632126) (xy 128.364031 -276.583227) (xy 128.387374 -276.537415)
			(xy 128.417595 -276.495819) (xy 128.453951 -276.459463) (xy 128.495547 -276.429242) (xy 128.541359 -276.405899)
			(xy 128.590258 -276.390011) (xy 128.64104 -276.381968) (xy 128.692456 -276.381968) (xy 128.743238 -276.390011)
			(xy 128.792137 -276.405899) (xy 128.837949 -276.429242) (xy 128.879545 -276.459463) (xy 128.915901 -276.495819)
			(xy 128.946122 -276.537415) (xy 128.969465 -276.583227) (xy 128.985353 -276.632126) (xy 128.993396 -276.682908)
			(xy 128.9939 -276.708616) (xy 128.993396 -276.734324) (xy 128.993247 -276.735265) (xy 129.250938 -276.735265)
			(xy 129.250938 -276.681967) (xy 129.258881 -276.629263) (xy 129.274591 -276.578333) (xy 129.297717 -276.530312)
			(xy 129.327741 -276.486275) (xy 129.363993 -276.447204) (xy 129.405664 -276.413973) (xy 129.451822 -276.387324)
			(xy 129.501436 -276.367852) (xy 129.553398 -276.355992) (xy 129.606548 -276.352009) (xy 129.659698 -276.355992)
			(xy 129.71166 -276.367852) (xy 129.761274 -276.387324) (xy 129.807432 -276.413973) (xy 129.849103 -276.447204)
			(xy 129.885355 -276.486275) (xy 129.915379 -276.530312) (xy 129.938505 -276.578333) (xy 129.954215 -276.629263)
			(xy 129.962158 -276.681967) (xy 129.962656 -276.708616) (xy 129.962176 -276.734324) (xy 130.2197 -276.734324)
			(xy 130.2197 -276.682908) (xy 130.227743 -276.632126) (xy 130.243631 -276.583227) (xy 130.266974 -276.537415)
			(xy 130.297195 -276.495819) (xy 130.333551 -276.459463) (xy 130.375147 -276.429242) (xy 130.420959 -276.405899)
			(xy 130.469858 -276.390011) (xy 130.52064 -276.381968) (xy 130.572056 -276.381968) (xy 130.622838 -276.390011)
			(xy 130.671737 -276.405899) (xy 130.717549 -276.429242) (xy 130.759145 -276.459463) (xy 130.795501 -276.495819)
			(xy 130.825722 -276.537415) (xy 130.849065 -276.583227) (xy 130.864953 -276.632126) (xy 130.872996 -276.682908)
			(xy 130.8735 -276.708616) (xy 130.872996 -276.734324) (xy 131.1595 -276.734324) (xy 131.1595 -276.682908)
			(xy 131.167543 -276.632126) (xy 131.183431 -276.583227) (xy 131.206774 -276.537415) (xy 131.236995 -276.495819)
			(xy 131.273351 -276.459463) (xy 131.314947 -276.429242) (xy 131.360759 -276.405899) (xy 131.409658 -276.390011)
			(xy 131.46044 -276.381968) (xy 131.511856 -276.381968) (xy 131.562638 -276.390011) (xy 131.611537 -276.405899)
			(xy 131.657349 -276.429242) (xy 131.698945 -276.459463) (xy 131.735301 -276.495819) (xy 131.765522 -276.537415)
			(xy 131.788865 -276.583227) (xy 131.804753 -276.632126) (xy 131.812796 -276.682908) (xy 131.8133 -276.708616)
			(xy 131.812796 -276.734324) (xy 131.812647 -276.735265) (xy 132.070084 -276.735265) (xy 132.070084 -276.681967)
			(xy 132.078027 -276.629263) (xy 132.093737 -276.578333) (xy 132.116863 -276.530312) (xy 132.146887 -276.486275)
			(xy 132.183139 -276.447204) (xy 132.22481 -276.413973) (xy 132.270968 -276.387324) (xy 132.320582 -276.367852)
			(xy 132.372544 -276.355992) (xy 132.425694 -276.352009) (xy 132.478844 -276.355992) (xy 132.530806 -276.367852)
			(xy 132.58042 -276.387324) (xy 132.626578 -276.413973) (xy 132.668249 -276.447204) (xy 132.704501 -276.486275)
			(xy 132.734525 -276.530312) (xy 132.757651 -276.578333) (xy 132.773361 -276.629263) (xy 132.781304 -276.681967)
			(xy 132.781802 -276.708616) (xy 132.781322 -276.734324) (xy 133.0391 -276.734324) (xy 133.0391 -276.682908)
			(xy 133.047143 -276.632126) (xy 133.063031 -276.583227) (xy 133.086374 -276.537415) (xy 133.116595 -276.495819)
			(xy 133.152951 -276.459463) (xy 133.194547 -276.429242) (xy 133.240359 -276.405899) (xy 133.289258 -276.390011)
			(xy 133.34004 -276.381968) (xy 133.391456 -276.381968) (xy 133.442238 -276.390011) (xy 133.491137 -276.405899)
			(xy 133.536949 -276.429242) (xy 133.578545 -276.459463) (xy 133.614901 -276.495819) (xy 133.645122 -276.537415)
			(xy 133.668465 -276.583227) (xy 133.684353 -276.632126) (xy 133.692396 -276.682908) (xy 133.6929 -276.708616)
			(xy 133.692396 -276.734324) (xy 133.692247 -276.735265) (xy 133.949938 -276.735265) (xy 133.949938 -276.681967)
			(xy 133.957881 -276.629263) (xy 133.973591 -276.578333) (xy 133.996717 -276.530312) (xy 134.026741 -276.486275)
			(xy 134.062993 -276.447204) (xy 134.104664 -276.413973) (xy 134.150822 -276.387324) (xy 134.200436 -276.367852)
			(xy 134.252398 -276.355992) (xy 134.305548 -276.352009) (xy 134.358698 -276.355992) (xy 134.41066 -276.367852)
			(xy 134.460274 -276.387324) (xy 134.506432 -276.413973) (xy 134.548103 -276.447204) (xy 134.584355 -276.486275)
			(xy 134.614379 -276.530312) (xy 134.637505 -276.578333) (xy 134.653215 -276.629263) (xy 134.661158 -276.681967)
			(xy 134.661656 -276.708616) (xy 134.661176 -276.734324) (xy 134.9187 -276.734324) (xy 134.9187 -276.682908)
			(xy 134.926743 -276.632126) (xy 134.942631 -276.583227) (xy 134.965974 -276.537415) (xy 134.996195 -276.495819)
			(xy 135.032551 -276.459463) (xy 135.074147 -276.429242) (xy 135.119959 -276.405899) (xy 135.168858 -276.390011)
			(xy 135.21964 -276.381968) (xy 135.271056 -276.381968) (xy 135.321838 -276.390011) (xy 135.370737 -276.405899)
			(xy 135.416549 -276.429242) (xy 135.458145 -276.459463) (xy 135.494501 -276.495819) (xy 135.524722 -276.537415)
			(xy 135.548065 -276.583227) (xy 135.563953 -276.632126) (xy 135.571996 -276.682908) (xy 135.5725 -276.708616)
			(xy 135.571996 -276.734324) (xy 135.571847 -276.735265) (xy 135.829284 -276.735265) (xy 135.829284 -276.681967)
			(xy 135.837227 -276.629263) (xy 135.852937 -276.578333) (xy 135.876063 -276.530312) (xy 135.906087 -276.486275)
			(xy 135.942339 -276.447204) (xy 135.98401 -276.413973) (xy 136.030168 -276.387324) (xy 136.079782 -276.367852)
			(xy 136.131744 -276.355992) (xy 136.184894 -276.352009) (xy 136.238044 -276.355992) (xy 136.290006 -276.367852)
			(xy 136.33962 -276.387324) (xy 136.385778 -276.413973) (xy 136.427449 -276.447204) (xy 136.463701 -276.486275)
			(xy 136.493725 -276.530312) (xy 136.516851 -276.578333) (xy 136.532561 -276.629263) (xy 136.540504 -276.681967)
			(xy 136.541002 -276.708616) (xy 136.540504 -276.735265) (xy 136.532561 -276.787969) (xy 136.516851 -276.838899)
			(xy 136.493725 -276.88692) (xy 136.463701 -276.930957) (xy 136.427449 -276.970028) (xy 136.385778 -277.003259)
			(xy 136.33962 -277.029908) (xy 136.290006 -277.04938) (xy 136.238044 -277.06124) (xy 136.184894 -277.065224)
			(xy 136.131744 -277.06124) (xy 136.079782 -277.04938) (xy 136.030168 -277.029908) (xy 135.98401 -277.003259)
			(xy 135.942339 -276.970028) (xy 135.906087 -276.930957) (xy 135.876063 -276.88692) (xy 135.852937 -276.838899)
			(xy 135.837227 -276.787969) (xy 135.829284 -276.735265) (xy 135.571847 -276.735265) (xy 135.563953 -276.785106)
			(xy 135.548065 -276.834005) (xy 135.524722 -276.879817) (xy 135.494501 -276.921413) (xy 135.458145 -276.957769)
			(xy 135.416549 -276.98799) (xy 135.370737 -277.011333) (xy 135.321838 -277.027221) (xy 135.271056 -277.035264)
			(xy 135.21964 -277.035264) (xy 135.168858 -277.027221) (xy 135.119959 -277.011333) (xy 135.074147 -276.98799)
			(xy 135.032551 -276.957769) (xy 134.996195 -276.921413) (xy 134.965974 -276.879817) (xy 134.942631 -276.834005)
			(xy 134.926743 -276.785106) (xy 134.9187 -276.734324) (xy 134.661176 -276.734324) (xy 134.661158 -276.735265)
			(xy 134.653215 -276.787969) (xy 134.637505 -276.838899) (xy 134.614379 -276.88692) (xy 134.584355 -276.930957)
			(xy 134.548103 -276.970028) (xy 134.506432 -277.003259) (xy 134.460274 -277.029908) (xy 134.41066 -277.04938)
			(xy 134.358698 -277.06124) (xy 134.305548 -277.065224) (xy 134.252398 -277.06124) (xy 134.200436 -277.04938)
			(xy 134.150822 -277.029908) (xy 134.104664 -277.003259) (xy 134.062993 -276.970028) (xy 134.026741 -276.930957)
			(xy 133.996717 -276.88692) (xy 133.973591 -276.838899) (xy 133.957881 -276.787969) (xy 133.949938 -276.735265)
			(xy 133.692247 -276.735265) (xy 133.684353 -276.785106) (xy 133.668465 -276.834005) (xy 133.645122 -276.879817)
			(xy 133.614901 -276.921413) (xy 133.578545 -276.957769) (xy 133.536949 -276.98799) (xy 133.491137 -277.011333)
			(xy 133.442238 -277.027221) (xy 133.391456 -277.035264) (xy 133.34004 -277.035264) (xy 133.289258 -277.027221)
			(xy 133.240359 -277.011333) (xy 133.194547 -276.98799) (xy 133.152951 -276.957769) (xy 133.116595 -276.921413)
			(xy 133.086374 -276.879817) (xy 133.063031 -276.834005) (xy 133.047143 -276.785106) (xy 133.0391 -276.734324)
			(xy 132.781322 -276.734324) (xy 132.781304 -276.735265) (xy 132.773361 -276.787969) (xy 132.757651 -276.838899)
			(xy 132.734525 -276.88692) (xy 132.704501 -276.930957) (xy 132.668249 -276.970028) (xy 132.626578 -277.003259)
			(xy 132.58042 -277.029908) (xy 132.530806 -277.04938) (xy 132.478844 -277.06124) (xy 132.425694 -277.065224)
			(xy 132.372544 -277.06124) (xy 132.320582 -277.04938) (xy 132.270968 -277.029908) (xy 132.22481 -277.003259)
			(xy 132.183139 -276.970028) (xy 132.146887 -276.930957) (xy 132.116863 -276.88692) (xy 132.093737 -276.838899)
			(xy 132.078027 -276.787969) (xy 132.070084 -276.735265) (xy 131.812647 -276.735265) (xy 131.804753 -276.785106)
			(xy 131.788865 -276.834005) (xy 131.765522 -276.879817) (xy 131.735301 -276.921413) (xy 131.698945 -276.957769)
			(xy 131.657349 -276.98799) (xy 131.611537 -277.011333) (xy 131.562638 -277.027221) (xy 131.511856 -277.035264)
			(xy 131.46044 -277.035264) (xy 131.409658 -277.027221) (xy 131.360759 -277.011333) (xy 131.314947 -276.98799)
			(xy 131.273351 -276.957769) (xy 131.236995 -276.921413) (xy 131.206774 -276.879817) (xy 131.183431 -276.834005)
			(xy 131.167543 -276.785106) (xy 131.1595 -276.734324) (xy 130.872996 -276.734324) (xy 130.864953 -276.785106)
			(xy 130.849065 -276.834005) (xy 130.825722 -276.879817) (xy 130.795501 -276.921413) (xy 130.759145 -276.957769)
			(xy 130.717549 -276.98799) (xy 130.671737 -277.011333) (xy 130.622838 -277.027221) (xy 130.572056 -277.035264)
			(xy 130.52064 -277.035264) (xy 130.469858 -277.027221) (xy 130.420959 -277.011333) (xy 130.375147 -276.98799)
			(xy 130.333551 -276.957769) (xy 130.297195 -276.921413) (xy 130.266974 -276.879817) (xy 130.243631 -276.834005)
			(xy 130.227743 -276.785106) (xy 130.2197 -276.734324) (xy 129.962176 -276.734324) (xy 129.962158 -276.735265)
			(xy 129.954215 -276.787969) (xy 129.938505 -276.838899) (xy 129.915379 -276.88692) (xy 129.885355 -276.930957)
			(xy 129.849103 -276.970028) (xy 129.807432 -277.003259) (xy 129.761274 -277.029908) (xy 129.71166 -277.04938)
			(xy 129.659698 -277.06124) (xy 129.606548 -277.065224) (xy 129.553398 -277.06124) (xy 129.501436 -277.04938)
			(xy 129.451822 -277.029908) (xy 129.405664 -277.003259) (xy 129.363993 -276.970028) (xy 129.327741 -276.930957)
			(xy 129.297717 -276.88692) (xy 129.274591 -276.838899) (xy 129.258881 -276.787969) (xy 129.250938 -276.735265)
			(xy 128.993247 -276.735265) (xy 128.985353 -276.785106) (xy 128.969465 -276.834005) (xy 128.946122 -276.879817)
			(xy 128.915901 -276.921413) (xy 128.879545 -276.957769) (xy 128.837949 -276.98799) (xy 128.792137 -277.011333)
			(xy 128.743238 -277.027221) (xy 128.692456 -277.035264) (xy 128.64104 -277.035264) (xy 128.590258 -277.027221)
			(xy 128.541359 -277.011333) (xy 128.495547 -276.98799) (xy 128.453951 -276.957769) (xy 128.417595 -276.921413)
			(xy 128.387374 -276.879817) (xy 128.364031 -276.834005) (xy 128.348143 -276.785106) (xy 128.3401 -276.734324)
			(xy 128.082576 -276.734324) (xy 128.082558 -276.735265) (xy 128.074615 -276.787969) (xy 128.058905 -276.838899)
			(xy 128.035779 -276.88692) (xy 128.005755 -276.930957) (xy 127.969503 -276.970028) (xy 127.927832 -277.003259)
			(xy 127.881674 -277.029908) (xy 127.83206 -277.04938) (xy 127.780098 -277.06124) (xy 127.726948 -277.065224)
			(xy 127.673798 -277.06124) (xy 127.621836 -277.04938) (xy 127.572222 -277.029908) (xy 127.526064 -277.003259)
			(xy 127.484393 -276.970028) (xy 127.448141 -276.930957) (xy 127.418117 -276.88692) (xy 127.394991 -276.838899)
			(xy 127.379281 -276.787969) (xy 127.371338 -276.735265) (xy 127.113647 -276.735265) (xy 127.105753 -276.785106)
			(xy 127.089865 -276.834005) (xy 127.066522 -276.879817) (xy 127.036301 -276.921413) (xy 126.999945 -276.957769)
			(xy 126.958349 -276.98799) (xy 126.912537 -277.011333) (xy 126.863638 -277.027221) (xy 126.812856 -277.035264)
			(xy 126.76144 -277.035264) (xy 126.710658 -277.027221) (xy 126.661759 -277.011333) (xy 126.615947 -276.98799)
			(xy 126.574351 -276.957769) (xy 126.537995 -276.921413) (xy 126.507774 -276.879817) (xy 126.484431 -276.834005)
			(xy 126.468543 -276.785106) (xy 126.4605 -276.734324) (xy 126.202722 -276.734324) (xy 126.202704 -276.735265)
			(xy 126.194761 -276.787969) (xy 126.179051 -276.838899) (xy 126.155925 -276.88692) (xy 126.125901 -276.930957)
			(xy 126.089649 -276.970028) (xy 126.047978 -277.003259) (xy 126.00182 -277.029908) (xy 125.952206 -277.04938)
			(xy 125.900244 -277.06124) (xy 125.847094 -277.065224) (xy 125.793944 -277.06124) (xy 125.741982 -277.04938)
			(xy 125.692368 -277.029908) (xy 125.64621 -277.003259) (xy 125.604539 -276.970028) (xy 125.568287 -276.930957)
			(xy 125.538263 -276.88692) (xy 125.515137 -276.838899) (xy 125.499427 -276.787969) (xy 125.491484 -276.735265)
			(xy 125.234047 -276.735265) (xy 125.226153 -276.785106) (xy 125.210265 -276.834005) (xy 125.186922 -276.879817)
			(xy 125.156701 -276.921413) (xy 125.120345 -276.957769) (xy 125.078749 -276.98799) (xy 125.032937 -277.011333)
			(xy 124.984038 -277.027221) (xy 124.933256 -277.035264) (xy 124.88184 -277.035264) (xy 124.831058 -277.027221)
			(xy 124.782159 -277.011333) (xy 124.736347 -276.98799) (xy 124.694751 -276.957769) (xy 124.658395 -276.921413)
			(xy 124.628174 -276.879817) (xy 124.604831 -276.834005) (xy 124.588943 -276.785106) (xy 124.5809 -276.734324)
			(xy 124.294396 -276.734324) (xy 124.286353 -276.785106) (xy 124.270465 -276.834005) (xy 124.247122 -276.879817)
			(xy 124.216901 -276.921413) (xy 124.180545 -276.957769) (xy 124.138949 -276.98799) (xy 124.093137 -277.011333)
			(xy 124.044238 -277.027221) (xy 123.993456 -277.035264) (xy 123.94204 -277.035264) (xy 123.891258 -277.027221)
			(xy 123.842359 -277.011333) (xy 123.796547 -276.98799) (xy 123.754951 -276.957769) (xy 123.718595 -276.921413)
			(xy 123.688374 -276.879817) (xy 123.665031 -276.834005) (xy 123.649143 -276.785106) (xy 123.6411 -276.734324)
			(xy 123.383576 -276.734324) (xy 123.383558 -276.735265) (xy 123.375615 -276.787969) (xy 123.359905 -276.838899)
			(xy 123.336779 -276.88692) (xy 123.306755 -276.930957) (xy 123.270503 -276.970028) (xy 123.228832 -277.003259)
			(xy 123.182674 -277.029908) (xy 123.13306 -277.04938) (xy 123.081098 -277.06124) (xy 123.027948 -277.065224)
			(xy 122.974798 -277.06124) (xy 122.922836 -277.04938) (xy 122.873222 -277.029908) (xy 122.827064 -277.003259)
			(xy 122.785393 -276.970028) (xy 122.749141 -276.930957) (xy 122.719117 -276.88692) (xy 122.695991 -276.838899)
			(xy 122.680281 -276.787969) (xy 122.672338 -276.735265) (xy 122.443758 -276.735265) (xy 122.435815 -276.787969)
			(xy 122.420105 -276.838899) (xy 122.396979 -276.88692) (xy 122.366955 -276.930957) (xy 122.330703 -276.970028)
			(xy 122.289032 -277.003259) (xy 122.242874 -277.029908) (xy 122.19326 -277.04938) (xy 122.141298 -277.06124)
			(xy 122.088148 -277.065224) (xy 122.034998 -277.06124) (xy 121.983036 -277.04938) (xy 121.933422 -277.029908)
			(xy 121.887264 -277.003259) (xy 121.845593 -276.970028) (xy 121.809341 -276.930957) (xy 121.779317 -276.88692)
			(xy 121.756191 -276.838899) (xy 121.740481 -276.787969) (xy 121.732538 -276.735265) (xy 121.503958 -276.735265)
			(xy 121.496015 -276.787969) (xy 121.480305 -276.838899) (xy 121.457179 -276.88692) (xy 121.427155 -276.930957)
			(xy 121.390903 -276.970028) (xy 121.349232 -277.003259) (xy 121.303074 -277.029908) (xy 121.25346 -277.04938)
			(xy 121.201498 -277.06124) (xy 121.148348 -277.065224) (xy 121.095198 -277.06124) (xy 121.043236 -277.04938)
			(xy 120.993622 -277.029908) (xy 120.947464 -277.003259) (xy 120.905793 -276.970028) (xy 120.869541 -276.930957)
			(xy 120.839517 -276.88692) (xy 120.816391 -276.838899) (xy 120.800681 -276.787969) (xy 120.792738 -276.735265)
			(xy 120.563866 -276.735265) (xy 120.555961 -276.787715) (xy 120.540251 -276.838645) (xy 120.517125 -276.886666)
			(xy 120.487101 -276.930703) (xy 120.450849 -276.969774) (xy 120.409178 -277.003005) (xy 120.36302 -277.029654)
			(xy 120.313406 -277.049126) (xy 120.261444 -277.060986) (xy 120.208294 -277.06497) (xy 120.155144 -277.060986)
			(xy 120.103182 -277.049126) (xy 120.053568 -277.029654) (xy 120.00741 -277.003005) (xy 119.965739 -276.969774)
			(xy 119.929487 -276.930703) (xy 119.899463 -276.886666) (xy 119.876337 -276.838645) (xy 119.860627 -276.787715)
			(xy 119.852684 -276.735011) (xy 119.624109 -276.735011) (xy 119.624104 -276.735265) (xy 119.616161 -276.787969)
			(xy 119.600451 -276.838899) (xy 119.577325 -276.88692) (xy 119.547301 -276.930957) (xy 119.511049 -276.970028)
			(xy 119.469378 -277.003259) (xy 119.42322 -277.029908) (xy 119.373606 -277.04938) (xy 119.321644 -277.06124)
			(xy 119.268494 -277.065224) (xy 119.215344 -277.06124) (xy 119.163382 -277.04938) (xy 119.113768 -277.029908)
			(xy 119.06761 -277.003259) (xy 119.025939 -276.970028) (xy 118.989687 -276.930957) (xy 118.959663 -276.88692)
			(xy 118.936537 -276.838899) (xy 118.920827 -276.787969) (xy 118.912884 -276.735265) (xy 118.683357 -276.735265)
			(xy 118.681386 -276.761559) (xy 118.669524 -276.813531) (xy 118.650048 -276.863155) (xy 118.623393 -276.909321)
			(xy 118.590156 -276.950999) (xy 118.551077 -276.987258) (xy 118.507032 -277.017287) (xy 118.459002 -277.040416)
			(xy 118.408062 -277.056129) (xy 118.355348 -277.064073) (xy 118.328694 -277.06447) (xy 118.30051 -277.063934)
			(xy 118.244846 -277.055057) (xy 118.191274 -277.037526) (xy 118.141131 -277.011778) (xy 118.095668 -276.978455)
			(xy 118.075456 -276.958806) (xy 118.064511 -276.94852) (xy 118.038095 -276.934258) (xy 118.008673 -276.928291)
			(xy 117.978788 -276.931134) (xy 117.951019 -276.942542) (xy 117.927766 -276.96153) (xy 117.911037 -276.986457)
			(xy 117.902276 -277.01517) (xy 117.90172 -277.03018) (xy 117.90172 -277.061168) (xy 118.35892 -277.518368)
			(xy 118.439946 -277.518368) (xy 118.446042 -277.474426) (xy 118.45016 -277.447822) (xy 118.465365 -277.396182)
			(xy 118.48817 -277.347419) (xy 118.518057 -277.302645) (xy 118.554342 -277.26288) (xy 118.596201 -277.229031)
			(xy 118.642678 -277.201868) (xy 118.692714 -277.182012) (xy 118.745169 -277.169914) (xy 118.798848 -277.165851)
			(xy 118.852527 -277.169914) (xy 118.904982 -277.182012) (xy 118.955018 -277.201868) (xy 119.001495 -277.229031)
			(xy 119.043354 -277.26288) (xy 119.079639 -277.302645) (xy 119.109526 -277.347419) (xy 119.132331 -277.396182)
			(xy 119.147536 -277.447822) (xy 119.151654 -277.474426) (xy 119.15775 -277.518368) (xy 119.379746 -277.518368)
			(xy 119.385842 -277.474426) (xy 119.389943 -277.447809) (xy 119.405122 -277.396139) (xy 119.427909 -277.347344)
			(xy 119.457785 -277.302538) (xy 119.494069 -277.262742) (xy 119.535933 -277.228865) (xy 119.582421 -277.20168)
			(xy 119.632474 -277.181807) (xy 119.684948 -277.169698) (xy 119.738648 -277.165631) (xy 119.792348 -277.169698)
			(xy 119.844822 -277.181807) (xy 119.894875 -277.20168) (xy 119.941363 -277.228865) (xy 119.983227 -277.262742)
			(xy 120.019511 -277.302538) (xy 120.049387 -277.347344) (xy 120.072174 -277.396139) (xy 120.087353 -277.447809)
			(xy 120.091454 -277.474426) (xy 120.09755 -277.518368) (xy 120.319546 -277.518368) (xy 120.325642 -277.474426)
			(xy 120.329743 -277.447809) (xy 120.344922 -277.396139) (xy 120.367709 -277.347344) (xy 120.397585 -277.302538)
			(xy 120.433869 -277.262742) (xy 120.475733 -277.228865) (xy 120.522221 -277.20168) (xy 120.572274 -277.181807)
			(xy 120.624748 -277.169698) (xy 120.678448 -277.165631) (xy 120.732148 -277.169698) (xy 120.784622 -277.181807)
			(xy 120.834675 -277.20168) (xy 120.881163 -277.228865) (xy 120.923027 -277.262742) (xy 120.959311 -277.302538)
			(xy 120.989187 -277.347344) (xy 121.011974 -277.396139) (xy 121.027153 -277.447809) (xy 121.031254 -277.474426)
			(xy 121.03735 -277.518368) (xy 121.259346 -277.518368) (xy 121.265442 -277.474426) (xy 121.269543 -277.447809)
			(xy 121.284722 -277.396139) (xy 121.307509 -277.347344) (xy 121.337385 -277.302538) (xy 121.373669 -277.262742)
			(xy 121.415533 -277.228865) (xy 121.462021 -277.20168) (xy 121.512074 -277.181807) (xy 121.564548 -277.169698)
			(xy 121.618248 -277.165631) (xy 121.671948 -277.169698) (xy 121.724422 -277.181807) (xy 121.774475 -277.20168)
			(xy 121.820963 -277.228865) (xy 121.862827 -277.262742) (xy 121.899111 -277.302538) (xy 121.928987 -277.347344)
			(xy 121.951774 -277.396139) (xy 121.966953 -277.447809) (xy 121.971054 -277.474426) (xy 121.97715 -277.518368)
			(xy 122.199146 -277.518368) (xy 122.205242 -277.474426) (xy 122.209343 -277.447809) (xy 122.224522 -277.396139)
			(xy 122.247309 -277.347344) (xy 122.277185 -277.302538) (xy 122.313469 -277.262742) (xy 122.355333 -277.228865)
			(xy 122.401821 -277.20168) (xy 122.451874 -277.181807) (xy 122.504348 -277.169698) (xy 122.558048 -277.165631)
			(xy 122.611748 -277.169698) (xy 122.664222 -277.181807) (xy 122.714275 -277.20168) (xy 122.760763 -277.228865)
			(xy 122.802627 -277.262742) (xy 122.838911 -277.302538) (xy 122.868787 -277.347344) (xy 122.891574 -277.396139)
			(xy 122.906753 -277.447809) (xy 122.910854 -277.474426) (xy 122.91695 -277.518368) (xy 123.138692 -277.518368)
			(xy 123.144788 -277.474426) (xy 123.148906 -277.447822) (xy 123.164111 -277.396182) (xy 123.186916 -277.347419)
			(xy 123.216803 -277.302645) (xy 123.253088 -277.26288) (xy 123.294947 -277.229031) (xy 123.341424 -277.201868)
			(xy 123.39146 -277.182012) (xy 123.443915 -277.169914) (xy 123.497594 -277.165851) (xy 123.551273 -277.169914)
			(xy 123.603728 -277.182012) (xy 123.653764 -277.201868) (xy 123.700241 -277.229031) (xy 123.7421 -277.26288)
			(xy 123.778385 -277.302645) (xy 123.808272 -277.347419) (xy 123.831077 -277.396182) (xy 123.846282 -277.447822)
			(xy 123.8504 -277.474426) (xy 123.856496 -277.518368) (xy 124.078492 -277.518368) (xy 124.084588 -277.474426)
			(xy 124.088706 -277.447822) (xy 124.103911 -277.396182) (xy 124.126716 -277.347419) (xy 124.156603 -277.302645)
			(xy 124.192888 -277.26288) (xy 124.234747 -277.229031) (xy 124.281224 -277.201868) (xy 124.33126 -277.182012)
			(xy 124.383715 -277.169914) (xy 124.437394 -277.165851) (xy 124.491073 -277.169914) (xy 124.543528 -277.182012)
			(xy 124.593564 -277.201868) (xy 124.640041 -277.229031) (xy 124.6819 -277.26288) (xy 124.718185 -277.302645)
			(xy 124.748072 -277.347419) (xy 124.770877 -277.396182) (xy 124.786082 -277.447822) (xy 124.7902 -277.474426)
			(xy 124.796296 -277.518368) (xy 125.018546 -277.518368) (xy 125.024642 -277.474426) (xy 125.02876 -277.447822)
			(xy 125.043965 -277.396182) (xy 125.06677 -277.347419) (xy 125.096657 -277.302645) (xy 125.132942 -277.26288)
			(xy 125.174801 -277.229031) (xy 125.221278 -277.201868) (xy 125.271314 -277.182012) (xy 125.323769 -277.169914)
			(xy 125.377448 -277.165851) (xy 125.431127 -277.169914) (xy 125.483582 -277.182012) (xy 125.533618 -277.201868)
			(xy 125.580095 -277.229031) (xy 125.621954 -277.26288) (xy 125.658239 -277.302645) (xy 125.688126 -277.347419)
			(xy 125.710931 -277.396182) (xy 125.726136 -277.447822) (xy 125.730254 -277.474426) (xy 125.73635 -277.518368)
			(xy 125.987048 -277.518368) (xy 125.993398 -277.474934) (xy 125.997649 -277.449372) (xy 126.013164 -277.399932)
			(xy 126.036281 -277.353557) (xy 126.06642 -277.311407) (xy 126.102829 -277.274537) (xy 126.144596 -277.243869)
			(xy 126.190676 -277.22017) (xy 126.239917 -277.204033) (xy 126.291085 -277.195863) (xy 126.342903 -277.195863)
			(xy 126.394071 -277.204033) (xy 126.443312 -277.22017) (xy 126.489392 -277.243869) (xy 126.531159 -277.274537)
			(xy 126.567568 -277.311407) (xy 126.597707 -277.353557) (xy 126.620824 -277.399932) (xy 126.636339 -277.449372)
			(xy 126.64059 -277.474934) (xy 126.64694 -277.518368) (xy 126.926848 -277.518368) (xy 126.933198 -277.474934)
			(xy 126.937449 -277.449372) (xy 126.952964 -277.399932) (xy 126.976081 -277.353557) (xy 127.00622 -277.311407)
			(xy 127.042629 -277.274537) (xy 127.084396 -277.243869) (xy 127.130476 -277.22017) (xy 127.179717 -277.204033)
			(xy 127.230885 -277.195863) (xy 127.282703 -277.195863) (xy 127.333871 -277.204033) (xy 127.383112 -277.22017)
			(xy 127.429192 -277.243869) (xy 127.470959 -277.274537) (xy 127.507368 -277.311407) (xy 127.537507 -277.353557)
			(xy 127.560624 -277.399932) (xy 127.576139 -277.449372) (xy 127.58039 -277.474934) (xy 127.58674 -277.518368)
			(xy 127.866648 -277.518368) (xy 127.872998 -277.474934) (xy 127.877249 -277.449372) (xy 127.892764 -277.399932)
			(xy 127.915881 -277.353557) (xy 127.94602 -277.311407) (xy 127.982429 -277.274537) (xy 128.024196 -277.243869)
			(xy 128.070276 -277.22017) (xy 128.119517 -277.204033) (xy 128.170685 -277.195863) (xy 128.222503 -277.195863)
			(xy 128.273671 -277.204033) (xy 128.322912 -277.22017) (xy 128.368992 -277.243869) (xy 128.410759 -277.274537)
			(xy 128.447168 -277.311407) (xy 128.477307 -277.353557) (xy 128.500424 -277.399932) (xy 128.515939 -277.449372)
			(xy 128.52019 -277.474934) (xy 128.52654 -277.518368) (xy 128.806448 -277.518368) (xy 128.812798 -277.474934)
			(xy 128.817049 -277.449372) (xy 128.832564 -277.399932) (xy 128.855681 -277.353557) (xy 128.88582 -277.311407)
			(xy 128.922229 -277.274537) (xy 128.963996 -277.243869) (xy 129.010076 -277.22017) (xy 129.059317 -277.204033)
			(xy 129.110485 -277.195863) (xy 129.162303 -277.195863) (xy 129.213471 -277.204033) (xy 129.262712 -277.22017)
			(xy 129.308792 -277.243869) (xy 129.350559 -277.274537) (xy 129.386968 -277.311407) (xy 129.417107 -277.353557)
			(xy 129.440224 -277.399932) (xy 129.455739 -277.449372) (xy 129.45999 -277.474934) (xy 129.46634 -277.518368)
			(xy 129.717546 -277.518368) (xy 129.723642 -277.474426) (xy 129.72776 -277.447822) (xy 129.742965 -277.396182)
			(xy 129.76577 -277.347419) (xy 129.795657 -277.302645) (xy 129.831942 -277.26288) (xy 129.873801 -277.229031)
			(xy 129.920278 -277.201868) (xy 129.970314 -277.182012) (xy 130.022769 -277.169914) (xy 130.076448 -277.165851)
			(xy 130.130127 -277.169914) (xy 130.182582 -277.182012) (xy 130.232618 -277.201868) (xy 130.279095 -277.229031)
			(xy 130.320954 -277.26288) (xy 130.357239 -277.302645) (xy 130.387126 -277.347419) (xy 130.409931 -277.396182)
			(xy 130.425136 -277.447822) (xy 130.429254 -277.474426) (xy 130.43535 -277.518368) (xy 130.657346 -277.518368)
			(xy 130.663442 -277.474426) (xy 130.66756 -277.447822) (xy 130.682765 -277.396182) (xy 130.70557 -277.347419)
			(xy 130.735457 -277.302645) (xy 130.771742 -277.26288) (xy 130.813601 -277.229031) (xy 130.860078 -277.201868)
			(xy 130.910114 -277.182012) (xy 130.962569 -277.169914) (xy 131.016248 -277.165851) (xy 131.069927 -277.169914)
			(xy 131.122382 -277.182012) (xy 131.172418 -277.201868) (xy 131.218895 -277.229031) (xy 131.260754 -277.26288)
			(xy 131.297039 -277.302645) (xy 131.326926 -277.347419) (xy 131.349731 -277.396182) (xy 131.364936 -277.447822)
			(xy 131.369054 -277.474426) (xy 131.37515 -277.518368) (xy 131.596892 -277.518368) (xy 131.602988 -277.474426)
			(xy 131.607106 -277.447822) (xy 131.622311 -277.396182) (xy 131.645116 -277.347419) (xy 131.675003 -277.302645)
			(xy 131.711288 -277.26288) (xy 131.753147 -277.229031) (xy 131.799624 -277.201868) (xy 131.84966 -277.182012)
			(xy 131.902115 -277.169914) (xy 131.955794 -277.165851) (xy 132.009473 -277.169914) (xy 132.061928 -277.182012)
			(xy 132.111964 -277.201868) (xy 132.158441 -277.229031) (xy 132.2003 -277.26288) (xy 132.236585 -277.302645)
			(xy 132.266472 -277.347419) (xy 132.289277 -277.396182) (xy 132.304482 -277.447822) (xy 132.3086 -277.474426)
			(xy 132.314696 -277.518368) (xy 132.565648 -277.518368) (xy 132.571998 -277.474934) (xy 132.576249 -277.449372)
			(xy 132.591764 -277.399932) (xy 132.614881 -277.353557) (xy 132.64502 -277.311407) (xy 132.681429 -277.274537)
			(xy 132.723196 -277.243869) (xy 132.769276 -277.22017) (xy 132.818517 -277.204033) (xy 132.869685 -277.195863)
			(xy 132.921503 -277.195863) (xy 132.972671 -277.204033) (xy 133.021912 -277.22017) (xy 133.067992 -277.243869)
			(xy 133.109759 -277.274537) (xy 133.146168 -277.311407) (xy 133.176307 -277.353557) (xy 133.199424 -277.399932)
			(xy 133.214939 -277.449372) (xy 133.21919 -277.474934) (xy 133.22554 -277.518368) (xy 133.505448 -277.518368)
			(xy 133.511798 -277.474934) (xy 133.516049 -277.449372) (xy 133.531564 -277.399932) (xy 133.554681 -277.353557)
			(xy 133.58482 -277.311407) (xy 133.621229 -277.274537) (xy 133.662996 -277.243869) (xy 133.709076 -277.22017)
			(xy 133.758317 -277.204033) (xy 133.809485 -277.195863) (xy 133.861303 -277.195863) (xy 133.912471 -277.204033)
			(xy 133.961712 -277.22017) (xy 134.007792 -277.243869) (xy 134.049559 -277.274537) (xy 134.085968 -277.311407)
			(xy 134.116107 -277.353557) (xy 134.139224 -277.399932) (xy 134.154739 -277.449372) (xy 134.15899 -277.474934)
			(xy 134.16534 -277.518368) (xy 134.445248 -277.518368) (xy 134.451598 -277.474934) (xy 134.455849 -277.449372)
			(xy 134.471364 -277.399932) (xy 134.494481 -277.353557) (xy 134.52462 -277.311407) (xy 134.561029 -277.274537)
			(xy 134.602796 -277.243869) (xy 134.648876 -277.22017) (xy 134.698117 -277.204033) (xy 134.749285 -277.195863)
			(xy 134.801103 -277.195863) (xy 134.852271 -277.204033) (xy 134.901512 -277.22017) (xy 134.947592 -277.243869)
			(xy 134.989359 -277.274537) (xy 135.025768 -277.311407) (xy 135.055907 -277.353557) (xy 135.079024 -277.399932)
			(xy 135.094539 -277.449372) (xy 135.09879 -277.474934) (xy 135.10514 -277.518368) (xy 135.384794 -277.518368)
			(xy 135.391144 -277.474934) (xy 135.395395 -277.449372) (xy 135.41091 -277.399932) (xy 135.434027 -277.353557)
			(xy 135.464166 -277.311407) (xy 135.500575 -277.274537) (xy 135.542342 -277.243869) (xy 135.588422 -277.22017)
			(xy 135.637663 -277.204033) (xy 135.688831 -277.195863) (xy 135.740649 -277.195863) (xy 135.791817 -277.204033)
			(xy 135.841058 -277.22017) (xy 135.887138 -277.243869) (xy 135.928905 -277.274537) (xy 135.965314 -277.311407)
			(xy 135.995453 -277.353557) (xy 136.01857 -277.399932) (xy 136.034085 -277.449372) (xy 136.038336 -277.474934)
			(xy 136.044686 -277.518368) (xy 136.295892 -277.518368) (xy 136.301988 -277.474426) (xy 136.306106 -277.447822)
			(xy 136.321311 -277.396182) (xy 136.344116 -277.347419) (xy 136.374003 -277.302645) (xy 136.410288 -277.26288)
			(xy 136.452147 -277.229031) (xy 136.498624 -277.201868) (xy 136.54866 -277.182012) (xy 136.601115 -277.169914)
			(xy 136.654794 -277.165851) (xy 136.708473 -277.169914) (xy 136.760928 -277.182012) (xy 136.810964 -277.201868)
			(xy 136.857441 -277.229031) (xy 136.8993 -277.26288) (xy 136.935585 -277.302645) (xy 136.965472 -277.347419)
			(xy 136.988277 -277.396182) (xy 137.003482 -277.447822) (xy 137.0076 -277.474426) (xy 137.013696 -277.518368)
			(xy 138.175492 -277.518368) (xy 138.181588 -277.474426) (xy 138.185476 -277.44915) (xy 138.199555 -277.399987)
			(xy 138.22052 -277.353343) (xy 138.24794 -277.310177) (xy 138.281252 -277.271376) (xy 138.319771 -277.237738)
			(xy 138.362705 -277.209955) (xy 138.409171 -277.188598) (xy 138.458214 -277.174107) (xy 138.508825 -277.166778)
			(xy 138.534394 -277.166324) (xy 138.562379 -277.166844) (xy 138.617659 -277.175599) (xy 138.670889 -277.192895)
			(xy 138.720758 -277.218305) (xy 138.766037 -277.251205) (xy 138.805612 -277.290782) (xy 138.838508 -277.336064)
			(xy 138.863915 -277.385935) (xy 138.881207 -277.439166) (xy 138.889958 -277.494447) (xy 138.890502 -277.522432)
			(xy 138.889983 -277.549999) (xy 138.88148 -277.604474) (xy 138.864683 -277.656988) (xy 138.839993 -277.706285)
			(xy 138.808 -277.751188) (xy 138.769469 -277.790623) (xy 138.725319 -277.823649) (xy 138.676608 -277.849475)
			(xy 138.650726 -277.858982) (xy 138.636985 -277.864263) (xy 138.61308 -277.88142) (xy 138.595054 -277.904678)
			(xy 138.584403 -277.932108) (xy 138.582009 -277.961435) (xy 138.58807 -277.990229) (xy 138.602085 -278.016102)
			(xy 138.612118 -278.026876) (xy 138.64082 -278.055578) (xy 138.651831 -278.065838) (xy 138.678369 -278.079998)
			(xy 138.707883 -278.085804) (xy 138.737807 -278.08275) (xy 138.76554 -278.071101) (xy 138.777472 -278.061928)
			(xy 138.796707 -278.046589) (xy 138.838596 -278.02079) (xy 138.883635 -278.000995) (xy 138.930968 -277.98758)
			(xy 138.979696 -277.980801) (xy 139.004294 -277.980394) (xy 139.03228 -277.980914) (xy 139.087562 -277.989669)
			(xy 139.140794 -278.006964) (xy 139.190665 -278.032374) (xy 139.235947 -278.065273) (xy 139.275524 -278.10485)
			(xy 139.308424 -278.150132) (xy 139.333834 -278.200003) (xy 139.35113 -278.253234) (xy 139.359886 -278.308516)
			(xy 139.360402 -278.336502) (xy 139.359988 -278.3611) (xy 139.353217 -278.409829) (xy 139.339805 -278.457162)
			(xy 139.320007 -278.502199) (xy 139.294199 -278.544083) (xy 139.278868 -278.563324) (xy 139.269696 -278.575252)
			(xy 139.25809 -278.602997) (xy 139.255047 -278.632916) (xy 139.260831 -278.662429) (xy 139.274942 -278.688987)
			(xy 139.285218 -278.699976) (xy 143.90243 -283.317188) (xy 143.90243 -334.043782) (xy 143.902684 -334.051402)
			(xy 143.902684 -338.968588) (xy 143.90243 -338.979256) (xy 143.90243 -339.154516) (xy 146.546824 -341.799164)
			(xy 146.546824 -358.151684) (xy 142.87754 -361.820968) (xy 144.809462 -361.820968) (xy 144.813533 -361.765346)
			(xy 144.825659 -361.710909) (xy 144.845582 -361.658818) (xy 144.872878 -361.610183) (xy 144.906964 -361.56604)
			(xy 144.947113 -361.527331) (xy 144.992471 -361.49488) (xy 145.042071 -361.469379) (xy 145.094855 -361.451372)
			(xy 145.149698 -361.441242) (xy 145.205432 -361.439205) (xy 145.260869 -361.445305) (xy 145.314826 -361.459411)
			(xy 145.366155 -361.481223) (xy 145.413761 -361.510277) (xy 145.456629 -361.545952) (xy 145.493846 -361.587489)
			(xy 145.524619 -361.634002) (xy 145.537251 -361.660948) (xy 145.977862 -361.660948) (xy 145.981933 -361.605326)
			(xy 145.994059 -361.550889) (xy 146.013982 -361.498798) (xy 146.041278 -361.450163) (xy 146.075364 -361.40602)
			(xy 146.115513 -361.367311) (xy 146.160871 -361.33486) (xy 146.210471 -361.309359) (xy 146.263255 -361.291352)
			(xy 146.318098 -361.281222) (xy 146.373832 -361.279185) (xy 146.429269 -361.285285) (xy 146.483226 -361.299391)
			(xy 146.534555 -361.321203) (xy 146.582161 -361.350257) (xy 146.625029 -361.385932) (xy 146.662246 -361.427469)
			(xy 146.693019 -361.473982) (xy 146.716691 -361.524479) (xy 146.732759 -361.577886) (xy 146.740879 -361.633062)
			(xy 146.741388 -361.660948) (xy 146.740879 -361.688834) (xy 146.732759 -361.74401) (xy 146.716691 -361.797417)
			(xy 146.693019 -361.847914) (xy 146.662246 -361.894427) (xy 146.625029 -361.935964) (xy 146.582161 -361.971639)
			(xy 146.534555 -362.000693) (xy 146.483226 -362.022505) (xy 146.429269 -362.036611) (xy 146.373832 -362.042711)
			(xy 146.318098 -362.040674) (xy 146.263255 -362.030544) (xy 146.210471 -362.012537) (xy 146.160871 -361.987036)
			(xy 146.115513 -361.954585) (xy 146.075364 -361.915876) (xy 146.041278 -361.871733) (xy 146.013982 -361.823098)
			(xy 145.994059 -361.771007) (xy 145.981933 -361.71657) (xy 145.977862 -361.660948) (xy 145.537251 -361.660948)
			(xy 145.548291 -361.684499) (xy 145.564359 -361.737906) (xy 145.572479 -361.793082) (xy 145.572988 -361.820968)
			(xy 145.572479 -361.848854) (xy 145.564359 -361.90403) (xy 145.548291 -361.957437) (xy 145.524619 -362.007934)
			(xy 145.493846 -362.054447) (xy 145.456629 -362.095984) (xy 145.413761 -362.131659) (xy 145.366155 -362.160713)
			(xy 145.314826 -362.182525) (xy 145.260869 -362.196631) (xy 145.205432 -362.202731) (xy 145.149698 -362.200694)
			(xy 145.094855 -362.190564) (xy 145.042071 -362.172557) (xy 144.992471 -362.147056) (xy 144.947113 -362.114605)
			(xy 144.906964 -362.075896) (xy 144.872878 -362.031753) (xy 144.845582 -361.983118) (xy 144.825659 -361.931027)
			(xy 144.813533 -361.87659) (xy 144.809462 -361.820968) (xy 142.87754 -361.820968) (xy 139.707366 -364.991142)
			(xy 139.697136 -365.002121) (xy 139.682995 -365.028572) (xy 139.677143 -365.05799) (xy 139.680085 -365.087839)
			(xy 139.691568 -365.115548) (xy 139.710601 -365.138729) (xy 139.735545 -365.155385) (xy 139.764251 -365.16408)
			(xy 139.779248 -365.164624) (xy 140.280644 -365.164624) (xy 140.297332 -365.165172) (xy 140.329573 -365.173811)
			(xy 140.358484 -365.190489) (xy 140.382102 -365.214074) (xy 140.398821 -365.242962) (xy 140.407504 -365.27519)
			(xy 140.408152 -365.291878) (xy 140.408152 -366.066578) (xy 141.14324 -366.066578) (xy 141.147206 -365.982047)
			(xy 141.159071 -365.89826) (xy 141.178729 -365.815951) (xy 141.206009 -365.735845) (xy 141.24067 -365.658646)
			(xy 141.282408 -365.585031) (xy 141.330855 -365.515648) (xy 141.385587 -365.451107) (xy 141.446123 -365.391975)
			(xy 141.511929 -365.338771) (xy 141.582429 -365.291963) (xy 141.657001 -365.251962) (xy 141.734992 -365.21912)
			(xy 141.815716 -365.193726) (xy 141.898463 -365.176003) (xy 141.982505 -365.166105) (xy 142.067106 -365.164122)
			(xy 142.15152 -365.170069) (xy 142.235007 -365.183894) (xy 142.316832 -365.205477) (xy 142.396276 -365.234627)
			(xy 142.472642 -365.271088) (xy 142.545258 -365.31454) (xy 142.613486 -365.364601) (xy 142.676726 -365.420831)
			(xy 142.734423 -365.482736) (xy 142.78607 -365.549772) (xy 142.831212 -365.621349) (xy 142.869454 -365.696839)
			(xy 142.900458 -365.775578) (xy 142.923953 -365.856875) (xy 142.939732 -365.940014) (xy 142.947656 -366.024266)
			(xy 142.948152 -366.066578) (xy 143.68324 -366.066578) (xy 143.687206 -365.982047) (xy 143.699071 -365.89826)
			(xy 143.718729 -365.815951) (xy 143.746009 -365.735845) (xy 143.78067 -365.658646) (xy 143.822408 -365.585031)
			(xy 143.870855 -365.515648) (xy 143.925587 -365.451107) (xy 143.986123 -365.391975) (xy 144.051929 -365.338771)
			(xy 144.122429 -365.291963) (xy 144.197001 -365.251962) (xy 144.274992 -365.21912) (xy 144.355716 -365.193726)
			(xy 144.438463 -365.176003) (xy 144.522505 -365.166105) (xy 144.607106 -365.164122) (xy 144.69152 -365.170069)
			(xy 144.775007 -365.183894) (xy 144.856832 -365.205477) (xy 144.936276 -365.234627) (xy 145.012642 -365.271088)
			(xy 145.085258 -365.31454) (xy 145.153486 -365.364601) (xy 145.216726 -365.420831) (xy 145.274423 -365.482736)
			(xy 145.32607 -365.549772) (xy 145.371212 -365.621349) (xy 145.409454 -365.696839) (xy 145.440458 -365.775578)
			(xy 145.463953 -365.856875) (xy 145.479732 -365.940014) (xy 145.487656 -366.024266) (xy 145.488152 -366.066578)
			(xy 145.487656 -366.10889) (xy 145.479732 -366.193142) (xy 145.463953 -366.276281) (xy 145.440458 -366.357578)
			(xy 145.409454 -366.436317) (xy 145.371212 -366.511807) (xy 145.32607 -366.583384) (xy 145.274423 -366.65042)
			(xy 145.216726 -366.712325) (xy 145.153486 -366.768555) (xy 145.085258 -366.818616) (xy 145.012642 -366.862068)
			(xy 144.936276 -366.898529) (xy 144.856832 -366.927679) (xy 144.775007 -366.949262) (xy 144.69152 -366.963087)
			(xy 144.607106 -366.969034) (xy 144.522505 -366.967051) (xy 144.438463 -366.957153) (xy 144.355716 -366.93943)
			(xy 144.274992 -366.914036) (xy 144.197001 -366.881194) (xy 144.122429 -366.841193) (xy 144.051929 -366.794385)
			(xy 143.986123 -366.741181) (xy 143.925587 -366.682049) (xy 143.870855 -366.617508) (xy 143.822408 -366.548125)
			(xy 143.78067 -366.47451) (xy 143.746009 -366.397311) (xy 143.718729 -366.317205) (xy 143.699071 -366.234896)
			(xy 143.687206 -366.151109) (xy 143.68324 -366.066578) (xy 142.948152 -366.066578) (xy 142.947656 -366.10889)
			(xy 142.939732 -366.193142) (xy 142.923953 -366.276281) (xy 142.900458 -366.357578) (xy 142.869454 -366.436317)
			(xy 142.831212 -366.511807) (xy 142.78607 -366.583384) (xy 142.734423 -366.65042) (xy 142.676726 -366.712325)
			(xy 142.613486 -366.768555) (xy 142.545258 -366.818616) (xy 142.472642 -366.862068) (xy 142.396276 -366.898529)
			(xy 142.316832 -366.927679) (xy 142.235007 -366.949262) (xy 142.15152 -366.963087) (xy 142.067106 -366.969034)
			(xy 141.982505 -366.967051) (xy 141.898463 -366.957153) (xy 141.815716 -366.93943) (xy 141.734992 -366.914036)
			(xy 141.657001 -366.881194) (xy 141.582429 -366.841193) (xy 141.511929 -366.794385) (xy 141.446123 -366.741181)
			(xy 141.385587 -366.682049) (xy 141.330855 -366.617508) (xy 141.282408 -366.548125) (xy 141.24067 -366.47451)
			(xy 141.206009 -366.397311) (xy 141.178729 -366.317205) (xy 141.159071 -366.234896) (xy 141.147206 -366.151109)
			(xy 141.14324 -366.066578) (xy 140.408152 -366.066578) (xy 140.408152 -366.841278) (xy 140.407656 -366.857989)
			(xy 140.399 -366.89027) (xy 140.382273 -366.919205) (xy 140.358618 -366.942816) (xy 140.329653 -366.95949)
			(xy 140.297356 -366.968087) (xy 140.280644 -366.968532) (xy 138.731244 -366.968532) (xy 138.714545 -366.967995)
			(xy 138.68228 -366.959372) (xy 138.653341 -366.942701) (xy 138.629696 -366.919115) (xy 138.612952 -366.890219)
			(xy 138.604248 -366.857976) (xy 138.603736 -366.841278) (xy 138.603736 -366.339882) (xy 138.603216 -366.324899)
			(xy 138.594541 -366.296216) (xy 138.577912 -366.271287) (xy 138.554763 -366.252259) (xy 138.527088 -366.24077)
			(xy 138.497268 -366.23781) (xy 138.467874 -366.243633) (xy 138.441435 -366.257739) (xy 138.430508 -366.268)
			(xy 137.64006 -367.058448) (xy 121.32056 -367.058448) (xy 121.05386 -367.325148) (xy 121.05386 -368.14633)
			(xy 140.60246 -368.14633) (xy 140.606531 -368.090708) (xy 140.618657 -368.036271) (xy 140.63858 -367.98418)
			(xy 140.665876 -367.935545) (xy 140.699962 -367.891402) (xy 140.740111 -367.852693) (xy 140.785469 -367.820242)
			(xy 140.835069 -367.794741) (xy 140.887853 -367.776734) (xy 140.942696 -367.766604) (xy 140.99843 -367.764567)
			(xy 141.053867 -367.770667) (xy 141.107824 -367.784773) (xy 141.159153 -367.806585) (xy 141.206759 -367.835639)
			(xy 141.249627 -367.871314) (xy 141.286844 -367.912851) (xy 141.317617 -367.959364) (xy 141.341289 -368.009861)
			(xy 141.357357 -368.063268) (xy 141.365477 -368.118444) (xy 141.365986 -368.14633) (xy 141.365477 -368.174216)
			(xy 141.357357 -368.229392) (xy 141.341289 -368.282799) (xy 141.317617 -368.333296) (xy 141.286844 -368.379809)
			(xy 141.249627 -368.421346) (xy 141.206759 -368.457021) (xy 141.159153 -368.486075) (xy 141.107824 -368.507887)
			(xy 141.053867 -368.521993) (xy 140.99843 -368.528093) (xy 140.942696 -368.526056) (xy 140.887853 -368.515926)
			(xy 140.835069 -368.497919) (xy 140.785469 -368.472418) (xy 140.740111 -368.439967) (xy 140.699962 -368.401258)
			(xy 140.665876 -368.357115) (xy 140.63858 -368.30848) (xy 140.618657 -368.256389) (xy 140.606531 -368.201952)
			(xy 140.60246 -368.14633) (xy 121.05386 -368.14633) (xy 121.05386 -379.291088) (xy 122.21718 -380.454408)
			(xy 161.08172 -380.454408)
		)
		(stroke
			(width 0)
			(type solid)
		)
		(fill yes)
		(layer "B.Cu")
		(net "PVPP_HBM_CPU1")
	)
	(gr_poly
		(pts
			(xy 87.436706 -288.843974) (xy 87.44274 -288.817658) (xy 87.461681 -288.767099) (xy 87.488037 -288.71998)
			(xy 87.521205 -288.67738) (xy 87.560423 -288.640275) (xy 87.604794 -288.609515) (xy 87.6533 -288.585807)
			(xy 87.704828 -288.569693) (xy 87.758199 -288.561542) (xy 87.812189 -288.561542) (xy 87.86556 -288.569693)
			(xy 87.917088 -288.585807) (xy 87.965594 -288.609515) (xy 88.009965 -288.640275) (xy 88.049183 -288.67738)
			(xy 88.082351 -288.71998) (xy 88.108707 -288.767099) (xy 88.127648 -288.817658) (xy 88.133682 -288.843974)
			(xy 88.142064 -288.88436) (xy 88.394794 -288.88436) (xy 88.403684 -288.844736) (xy 88.410227 -288.818154)
			(xy 88.430913 -288.767475) (xy 88.459686 -288.720908) (xy 88.495756 -288.679733) (xy 88.53813 -288.645081)
			(xy 88.585646 -288.617904) (xy 88.636999 -288.598948) (xy 88.66378 -288.593276) (xy 88.68664 -288.588958)
			(xy 88.891618 -288.233866) (xy 88.883744 -288.212022) (xy 88.875165 -288.185603) (xy 88.865969 -288.130828)
			(xy 88.865456 -288.103056) (xy 88.865964 -288.077169) (xy 88.874063 -288.026031) (xy 88.890062 -287.976791)
			(xy 88.913568 -287.930659) (xy 88.944 -287.888772) (xy 88.98061 -287.852162) (xy 89.022497 -287.82173)
			(xy 89.068629 -287.798224) (xy 89.117869 -287.782225) (xy 89.169007 -287.774126) (xy 89.220781 -287.774126)
			(xy 89.271919 -287.782225) (xy 89.321159 -287.798224) (xy 89.367291 -287.82173) (xy 89.409178 -287.852162)
			(xy 89.445788 -287.888772) (xy 89.47622 -287.930659) (xy 89.499726 -287.976791) (xy 89.515725 -288.026031)
			(xy 89.523824 -288.077169) (xy 89.524332 -288.103056) (xy 89.523871 -288.128392) (xy 89.516123 -288.178469)
			(xy 89.500803 -288.226771) (xy 89.478271 -288.272159) (xy 89.449059 -288.313564) (xy 89.413854 -288.350011)
			(xy 89.373487 -288.380641) (xy 89.328907 -288.404732) (xy 89.281166 -288.421717) (xy 89.256362 -288.426906)
			(xy 89.233502 -288.431224) (xy 89.028524 -288.786316) (xy 89.036398 -288.80816) (xy 89.039464 -288.817166)
			(xy 89.044677 -288.835465) (xy 89.046812 -288.844736) (xy 89.055702 -288.88436) (xy 89.307924 -288.88436)
			(xy 89.316306 -288.843974) (xy 89.32234 -288.817658) (xy 89.341281 -288.767099) (xy 89.367637 -288.71998)
			(xy 89.400805 -288.67738) (xy 89.440023 -288.640275) (xy 89.484394 -288.609515) (xy 89.5329 -288.585807)
			(xy 89.584428 -288.569693) (xy 89.637799 -288.561542) (xy 89.691789 -288.561542) (xy 89.74516 -288.569693)
			(xy 89.796688 -288.585807) (xy 89.845194 -288.609515) (xy 89.889565 -288.640275) (xy 89.928783 -288.67738)
			(xy 89.961951 -288.71998) (xy 89.988307 -288.767099) (xy 90.007248 -288.817658) (xy 90.013282 -288.843974)
			(xy 90.021664 -288.88436) (xy 90.274394 -288.88436) (xy 90.283284 -288.844736) (xy 90.289827 -288.818154)
			(xy 90.310513 -288.767475) (xy 90.339286 -288.720908) (xy 90.375356 -288.679733) (xy 90.41773 -288.645081)
			(xy 90.465246 -288.617904) (xy 90.516599 -288.598948) (xy 90.54338 -288.593276) (xy 90.56624 -288.588958)
			(xy 90.771218 -288.233866) (xy 90.763344 -288.212022) (xy 90.754765 -288.185603) (xy 90.745569 -288.130828)
			(xy 90.745056 -288.103056) (xy 90.745564 -288.077169) (xy 90.753663 -288.026031) (xy 90.769662 -287.976791)
			(xy 90.793168 -287.930659) (xy 90.8236 -287.888772) (xy 90.86021 -287.852162) (xy 90.902097 -287.82173)
			(xy 90.948229 -287.798224) (xy 90.997469 -287.782225) (xy 91.048607 -287.774126) (xy 91.100381 -287.774126)
			(xy 91.151519 -287.782225) (xy 91.200759 -287.798224) (xy 91.246891 -287.82173) (xy 91.288778 -287.852162)
			(xy 91.325388 -287.888772) (xy 91.35582 -287.930659) (xy 91.379326 -287.976791) (xy 91.395325 -288.026031)
			(xy 91.403424 -288.077169) (xy 91.403932 -288.103056) (xy 91.403471 -288.128392) (xy 91.395723 -288.178469)
			(xy 91.380403 -288.226771) (xy 91.357871 -288.272159) (xy 91.328659 -288.313564) (xy 91.293454 -288.350011)
			(xy 91.253087 -288.380641) (xy 91.208507 -288.404732) (xy 91.160766 -288.421717) (xy 91.135962 -288.426906)
			(xy 91.113102 -288.431224) (xy 90.908124 -288.786316) (xy 90.915998 -288.80816) (xy 90.919064 -288.817166)
			(xy 90.924277 -288.835465) (xy 90.926412 -288.844736) (xy 90.935302 -288.88436) (xy 91.214194 -288.88436)
			(xy 91.223084 -288.844736) (xy 91.22934 -288.819322) (xy 91.248793 -288.770736) (xy 91.275679 -288.725835)
			(xy 91.30932 -288.685744) (xy 91.348874 -288.651473) (xy 91.393345 -288.623881) (xy 91.441617 -288.603662)
			(xy 91.492477 -288.591324) (xy 91.544648 -288.587177) (xy 91.596819 -288.591324) (xy 91.647679 -288.603662)
			(xy 91.695951 -288.623881) (xy 91.740422 -288.651473) (xy 91.779976 -288.685744) (xy 91.813617 -288.725835)
			(xy 91.840503 -288.770736) (xy 91.859956 -288.819322) (xy 91.866212 -288.844736) (xy 91.875102 -288.88436)
			(xy 92.153994 -288.88436) (xy 92.162884 -288.844736) (xy 92.169427 -288.818154) (xy 92.190113 -288.767475)
			(xy 92.218886 -288.720908) (xy 92.254956 -288.679733) (xy 92.29733 -288.645081) (xy 92.344846 -288.617904)
			(xy 92.396199 -288.598948) (xy 92.42298 -288.593276) (xy 92.44584 -288.588958) (xy 92.651072 -288.233866)
			(xy 92.643198 -288.211768) (xy 92.634576 -288.18542) (xy 92.625258 -288.130773) (xy 92.624656 -288.103056)
			(xy 92.625164 -288.077149) (xy 92.63327 -288.025972) (xy 92.649282 -287.976693) (xy 92.672805 -287.930526)
			(xy 92.703261 -287.888607) (xy 92.739899 -287.851969) (xy 92.781818 -287.821513) (xy 92.827985 -287.79799)
			(xy 92.877264 -287.781978) (xy 92.928441 -287.773872) (xy 92.980255 -287.773872) (xy 93.031432 -287.781978)
			(xy 93.080711 -287.79799) (xy 93.126878 -287.821513) (xy 93.168797 -287.851969) (xy 93.205435 -287.888607)
			(xy 93.235891 -287.930526) (xy 93.259414 -287.976693) (xy 93.275426 -288.025972) (xy 93.283532 -288.077149)
			(xy 93.28404 -288.103056) (xy 93.283578 -288.128404) (xy 93.275821 -288.178504) (xy 93.260482 -288.226824)
			(xy 93.237924 -288.272225) (xy 93.208679 -288.313636) (xy 93.173437 -288.35008) (xy 93.13303 -288.380696)
			(xy 93.08841 -288.404763) (xy 93.040631 -288.421713) (xy 93.015816 -288.426906) (xy 92.992956 -288.431224)
			(xy 92.787724 -288.786316) (xy 92.795598 -288.808414) (xy 92.798661 -288.817356) (xy 92.803873 -288.835529)
			(xy 92.806012 -288.844736) (xy 92.814902 -288.88436) (xy 93.093794 -288.88436) (xy 93.102684 -288.844736)
			(xy 93.10894 -288.819322) (xy 93.128393 -288.770736) (xy 93.155279 -288.725835) (xy 93.18892 -288.685744)
			(xy 93.228474 -288.651473) (xy 93.272945 -288.623881) (xy 93.321217 -288.603662) (xy 93.372077 -288.591324)
			(xy 93.424248 -288.587177) (xy 93.476419 -288.591324) (xy 93.527279 -288.603662) (xy 93.575551 -288.623881)
			(xy 93.620022 -288.651473) (xy 93.659576 -288.685744) (xy 93.693217 -288.725835) (xy 93.720103 -288.770736)
			(xy 93.739556 -288.819322) (xy 93.745812 -288.844736) (xy 93.754702 -288.88436) (xy 94.033594 -288.88436)
			(xy 94.042484 -288.844736) (xy 94.049027 -288.818154) (xy 94.069713 -288.767475) (xy 94.098486 -288.720908)
			(xy 94.134556 -288.679733) (xy 94.17693 -288.645081) (xy 94.224446 -288.617904) (xy 94.275799 -288.598948)
			(xy 94.30258 -288.593276) (xy 94.32544 -288.588958) (xy 94.530672 -288.233866) (xy 94.522798 -288.211768)
			(xy 94.514176 -288.18542) (xy 94.504858 -288.130773) (xy 94.504256 -288.103056) (xy 94.504764 -288.077149)
			(xy 94.51287 -288.025972) (xy 94.528882 -287.976693) (xy 94.552405 -287.930526) (xy 94.582861 -287.888607)
			(xy 94.619499 -287.851969) (xy 94.661418 -287.821513) (xy 94.707585 -287.79799) (xy 94.756864 -287.781978)
			(xy 94.808041 -287.773872) (xy 94.859855 -287.773872) (xy 94.911032 -287.781978) (xy 94.960311 -287.79799)
			(xy 95.006478 -287.821513) (xy 95.048397 -287.851969) (xy 95.085035 -287.888607) (xy 95.115491 -287.930526)
			(xy 95.139014 -287.976693) (xy 95.155026 -288.025972) (xy 95.163132 -288.077149) (xy 95.16364 -288.103056)
			(xy 95.163178 -288.128404) (xy 95.155421 -288.178504) (xy 95.140082 -288.226824) (xy 95.117524 -288.272225)
			(xy 95.088279 -288.313636) (xy 95.053037 -288.35008) (xy 95.01263 -288.380696) (xy 94.96801 -288.404763)
			(xy 94.920231 -288.421713) (xy 94.895416 -288.426906) (xy 94.872556 -288.431224) (xy 94.667324 -288.786316)
			(xy 94.675198 -288.808414) (xy 94.678261 -288.817356) (xy 94.683473 -288.835529) (xy 94.685612 -288.844736)
			(xy 94.694502 -288.88436) (xy 94.973394 -288.88436) (xy 94.982284 -288.844736) (xy 94.98854 -288.819322)
			(xy 95.007993 -288.770736) (xy 95.034879 -288.725835) (xy 95.06852 -288.685744) (xy 95.108074 -288.651473)
			(xy 95.152545 -288.623881) (xy 95.200817 -288.603662) (xy 95.251677 -288.591324) (xy 95.303848 -288.587177)
			(xy 95.356019 -288.591324) (xy 95.406879 -288.603662) (xy 95.455151 -288.623881) (xy 95.499622 -288.651473)
			(xy 95.539176 -288.685744) (xy 95.572817 -288.725835) (xy 95.599703 -288.770736) (xy 95.619156 -288.819322)
			(xy 95.625412 -288.844736) (xy 95.634302 -288.88436) (xy 95.913194 -288.88436) (xy 95.922084 -288.844736)
			(xy 95.928627 -288.818154) (xy 95.949313 -288.767475) (xy 95.978086 -288.720908) (xy 96.014156 -288.679733)
			(xy 96.05653 -288.645081) (xy 96.104046 -288.617904) (xy 96.155399 -288.598948) (xy 96.18218 -288.593276)
			(xy 96.20504 -288.588958) (xy 96.410272 -288.233866) (xy 96.402398 -288.211768) (xy 96.393776 -288.18542)
			(xy 96.384458 -288.130773) (xy 96.383856 -288.103056) (xy 96.384364 -288.077149) (xy 96.39247 -288.025972)
			(xy 96.408482 -287.976693) (xy 96.432005 -287.930526) (xy 96.462461 -287.888607) (xy 96.499099 -287.851969)
			(xy 96.541018 -287.821513) (xy 96.587185 -287.79799) (xy 96.636464 -287.781978) (xy 96.687641 -287.773872)
			(xy 96.739455 -287.773872) (xy 96.790632 -287.781978) (xy 96.839911 -287.79799) (xy 96.886078 -287.821513)
			(xy 96.927997 -287.851969) (xy 96.964635 -287.888607) (xy 96.995091 -287.930526) (xy 97.018614 -287.976693)
			(xy 97.034626 -288.025972) (xy 97.042732 -288.077149) (xy 97.04324 -288.103056) (xy 97.042778 -288.128404)
			(xy 97.035021 -288.178504) (xy 97.019682 -288.226824) (xy 96.997124 -288.272225) (xy 96.967879 -288.313636)
			(xy 96.932637 -288.35008) (xy 96.89223 -288.380696) (xy 96.84761 -288.404763) (xy 96.799831 -288.421713)
			(xy 96.775016 -288.426906) (xy 96.752156 -288.431224) (xy 96.546924 -288.786316) (xy 96.554798 -288.808414)
			(xy 96.557861 -288.817356) (xy 96.563073 -288.835529) (xy 96.565212 -288.844736) (xy 96.574102 -288.88436)
			(xy 96.852994 -288.88436) (xy 96.861884 -288.844736) (xy 96.86814 -288.819322) (xy 96.887593 -288.770736)
			(xy 96.914479 -288.725835) (xy 96.94812 -288.685744) (xy 96.987674 -288.651473) (xy 97.032145 -288.623881)
			(xy 97.080417 -288.603662) (xy 97.131277 -288.591324) (xy 97.183448 -288.587177) (xy 97.235619 -288.591324)
			(xy 97.286479 -288.603662) (xy 97.334751 -288.623881) (xy 97.379222 -288.651473) (xy 97.418776 -288.685744)
			(xy 97.452417 -288.725835) (xy 97.479303 -288.770736) (xy 97.498756 -288.819322) (xy 97.505012 -288.844736)
			(xy 97.513902 -288.88436) (xy 97.792794 -288.88436) (xy 97.801684 -288.844736) (xy 97.808227 -288.818154)
			(xy 97.828913 -288.767475) (xy 97.857686 -288.720908) (xy 97.893756 -288.679733) (xy 97.93613 -288.645081)
			(xy 97.983646 -288.617904) (xy 98.034999 -288.598948) (xy 98.06178 -288.593276) (xy 98.08464 -288.588958)
			(xy 98.289872 -288.233866) (xy 98.281998 -288.211768) (xy 98.273376 -288.18542) (xy 98.264058 -288.130773)
			(xy 98.263456 -288.103056) (xy 98.263964 -288.077149) (xy 98.27207 -288.025972) (xy 98.288082 -287.976693)
			(xy 98.311605 -287.930526) (xy 98.342061 -287.888607) (xy 98.378699 -287.851969) (xy 98.420618 -287.821513)
			(xy 98.466785 -287.79799) (xy 98.516064 -287.781978) (xy 98.567241 -287.773872) (xy 98.619055 -287.773872)
			(xy 98.670232 -287.781978) (xy 98.719511 -287.79799) (xy 98.765678 -287.821513) (xy 98.807597 -287.851969)
			(xy 98.844235 -287.888607) (xy 98.874691 -287.930526) (xy 98.898214 -287.976693) (xy 98.914226 -288.025972)
			(xy 98.922332 -288.077149) (xy 98.92284 -288.103056) (xy 98.922378 -288.128404) (xy 98.914621 -288.178504)
			(xy 98.899282 -288.226824) (xy 98.876724 -288.272225) (xy 98.847479 -288.313636) (xy 98.812237 -288.35008)
			(xy 98.77183 -288.380696) (xy 98.72721 -288.404763) (xy 98.679431 -288.421713) (xy 98.654616 -288.426906)
			(xy 98.631756 -288.431224) (xy 98.426524 -288.786316) (xy 98.434398 -288.808414) (xy 98.437461 -288.817356)
			(xy 98.442673 -288.835529) (xy 98.444812 -288.844736) (xy 98.453702 -288.88436) (xy 98.732594 -288.88436)
			(xy 98.741484 -288.844736) (xy 98.74774 -288.819322) (xy 98.767193 -288.770736) (xy 98.794079 -288.725835)
			(xy 98.82772 -288.685744) (xy 98.867274 -288.651473) (xy 98.911745 -288.623881) (xy 98.960017 -288.603662)
			(xy 99.010877 -288.591324) (xy 99.063048 -288.587177) (xy 99.115219 -288.591324) (xy 99.166079 -288.603662)
			(xy 99.214351 -288.623881) (xy 99.258822 -288.651473) (xy 99.298376 -288.685744) (xy 99.332017 -288.725835)
			(xy 99.358903 -288.770736) (xy 99.378356 -288.819322) (xy 99.384612 -288.844736) (xy 99.393502 -288.88436)
			(xy 99.672394 -288.88436) (xy 99.681284 -288.844736) (xy 99.687827 -288.818154) (xy 99.708513 -288.767475)
			(xy 99.737286 -288.720908) (xy 99.773356 -288.679733) (xy 99.81573 -288.645081) (xy 99.863246 -288.617904)
			(xy 99.914599 -288.598948) (xy 99.94138 -288.593276) (xy 99.96424 -288.588958) (xy 100.134166 -288.294826)
			(xy 100.134166 -287.745932) (xy 100.1337 -287.732058) (xy 100.126234 -287.705335) (xy 100.111845 -287.681611)
			(xy 100.091597 -287.66264) (xy 100.066987 -287.649825) (xy 100.039834 -287.644113) (xy 100.025962 -287.644586)
			(xy 100.002594 -287.645348) (xy 99.975942 -287.64485) (xy 99.923233 -287.636904) (xy 99.872298 -287.621192)
			(xy 99.824273 -287.598064) (xy 99.780231 -287.568036) (xy 99.741157 -287.53178) (xy 99.707923 -287.490105)
			(xy 99.681271 -287.443942) (xy 99.661797 -287.394323) (xy 99.649936 -287.342355) (xy 99.645952 -287.2892)
			(xy 99.649936 -287.236045) (xy 99.661797 -287.184077) (xy 99.681271 -287.134458) (xy 99.707923 -287.088295)
			(xy 99.741157 -287.04662) (xy 99.780231 -287.010364) (xy 99.824273 -286.980336) (xy 99.872298 -286.957208)
			(xy 99.923233 -286.941496) (xy 99.975942 -286.93355) (xy 100.002594 -286.933132) (xy 100.025962 -286.933894)
			(xy 100.039827 -286.934319) (xy 100.066955 -286.928592) (xy 100.091542 -286.915775) (xy 100.111773 -286.896816)
			(xy 100.126156 -286.873111) (xy 100.13363 -286.846411) (xy 100.134166 -286.832548) (xy 100.134166 -286.586676)
			(xy 100.13188 -286.579564) (xy 100.124628 -286.554142) (xy 100.116844 -286.501856) (xy 100.116386 -286.475424)
			(xy 100.116852 -286.448993) (xy 100.124637 -286.396708) (xy 100.13188 -286.371284) (xy 100.134166 -286.364172)
			(xy 100.134166 -286.091376) (xy 100.133732 -286.07746) (xy 100.126208 -286.050663) (xy 100.111726 -286.026894)
			(xy 100.091363 -286.00792) (xy 100.066631 -285.995151) (xy 100.03937 -285.989537) (xy 100.025454 -285.99003)
			(xy 100.002594 -285.990792) (xy 99.976706 -285.99031) (xy 99.925568 -285.982209) (xy 99.876327 -285.966208)
			(xy 99.830196 -285.942699) (xy 99.788311 -285.912264) (xy 99.751703 -285.87565) (xy 99.721273 -285.83376)
			(xy 99.697772 -285.787625) (xy 99.681779 -285.738381) (xy 99.673686 -285.687242) (xy 99.673156 -285.661354)
			(xy 99.673616 -285.636017) (xy 99.681363 -285.585938) (xy 99.696682 -285.537635) (xy 99.719213 -285.492245)
			(xy 99.748424 -285.450838) (xy 99.783629 -285.414389) (xy 99.823996 -285.383756) (xy 99.868576 -285.359662)
			(xy 99.916318 -285.342674) (xy 99.941126 -285.337504) (xy 99.963986 -285.333186) (xy 100.134166 -285.038546)
			(xy 100.134166 -284.48508) (xy 100.197666 -284.42158) (xy 100.140008 -284.363668) (xy 100.110544 -284.373066)
			(xy 100.084248 -284.380907) (xy 100.030029 -284.389331) (xy 100.002594 -284.38983) (xy 99.975943 -284.389332)
			(xy 99.923237 -284.381387) (xy 99.872304 -284.365675) (xy 99.824282 -284.342548) (xy 99.780242 -284.312522)
			(xy 99.74117 -284.276268) (xy 99.707938 -284.234595) (xy 99.681287 -284.188434) (xy 99.661814 -284.138817)
			(xy 99.649954 -284.086852) (xy 99.64597 -284.0337) (xy 99.649954 -283.980548) (xy 99.661814 -283.928583)
			(xy 99.681287 -283.878966) (xy 99.707938 -283.832805) (xy 99.74117 -283.791132) (xy 99.780242 -283.754878)
			(xy 99.824282 -283.724852) (xy 99.872304 -283.701725) (xy 99.923237 -283.686013) (xy 99.975943 -283.678068)
			(xy 100.002594 -283.677614) (xy 100.02988 -283.678135) (xy 100.083813 -283.686458) (xy 100.135845 -283.702911)
			(xy 100.184759 -283.727108) (xy 100.22941 -283.758483) (xy 100.268752 -283.796302) (xy 100.301865 -283.839679)
			(xy 100.327973 -283.8876) (xy 100.346466 -283.938943) (xy 100.356912 -283.992506) (xy 100.358448 -284.019752)
			(xy 100.359517 -284.034458) (xy 100.369028 -284.062353) (xy 100.38611 -284.086369) (xy 100.409341 -284.104506)
			(xy 100.436784 -284.115251) (xy 100.466153 -284.117711) (xy 100.495001 -284.111679) (xy 100.520925 -284.097659)
			(xy 100.531676 -284.08757) (xy 100.585778 -284.033468) (xy 100.586794 -284.014164) (xy 100.588696 -283.988202)
			(xy 100.599087 -283.937196) (xy 100.616793 -283.888246) (xy 100.641436 -283.842395) (xy 100.672491 -283.80062)
			(xy 100.709298 -283.763811) (xy 100.75107 -283.732752) (xy 100.796919 -283.708105) (xy 100.845868 -283.690395)
			(xy 100.896873 -283.679999) (xy 100.922836 -283.678122) (xy 100.94214 -283.677106) (xy 101.170994 -283.448252)
			(xy 101.145594 -283.4132) (xy 101.130837 -283.391987) (xy 101.107412 -283.34593) (xy 101.091469 -283.296779)
			(xy 101.083397 -283.245742) (xy 101.082856 -283.219906) (xy 101.083338 -283.194003) (xy 101.091445 -283.142836)
			(xy 101.10746 -283.093569) (xy 101.130989 -283.047415) (xy 101.161452 -283.005513) (xy 101.198097 -282.968894)
			(xy 101.240022 -282.938463) (xy 101.286193 -282.914968) (xy 101.335472 -282.898988) (xy 101.386645 -282.890919)
			(xy 101.412548 -282.890468) (xy 101.438375 -282.890951) (xy 101.489402 -282.898974) (xy 101.538551 -282.914862)
			(xy 101.584618 -282.938227) (xy 101.605842 -282.952952) (xy 101.640894 -282.978352) (xy 101.757734 -282.861512)
			(xy 101.767107 -282.851518) (xy 101.780634 -282.827702) (xy 101.787335 -282.801144) (xy 101.786726 -282.773761)
			(xy 101.778851 -282.747528) (xy 101.764278 -282.724337) (xy 101.744059 -282.705861) (xy 101.73208 -282.699206)
			(xy 101.709308 -282.686966) (xy 101.667549 -282.656491) (xy 101.631059 -282.619872) (xy 101.60073 -282.578008)
			(xy 101.577307 -282.531922) (xy 101.561363 -282.482746) (xy 101.553289 -282.431684) (xy 101.552756 -282.405836)
			(xy 101.553217 -282.3805) (xy 101.560966 -282.330423) (xy 101.576287 -282.282122) (xy 101.598819 -282.236734)
			(xy 101.628031 -282.195329) (xy 101.663235 -282.158883) (xy 101.703603 -282.128252) (xy 101.748182 -282.10416)
			(xy 101.795922 -282.087173) (xy 101.820726 -282.081986) (xy 101.843586 -282.077668) (xy 102.048818 -281.722322)
			(xy 102.041198 -281.700478) (xy 102.032591 -281.674191) (xy 102.023272 -281.619673) (xy 102.022656 -281.59202)
			(xy 102.023164 -281.566113) (xy 102.03127 -281.514936) (xy 102.047282 -281.465657) (xy 102.070805 -281.41949)
			(xy 102.101261 -281.377571) (xy 102.137899 -281.340933) (xy 102.179818 -281.310477) (xy 102.225985 -281.286954)
			(xy 102.275264 -281.270942) (xy 102.326441 -281.262836) (xy 102.378255 -281.262836) (xy 102.429432 -281.270942)
			(xy 102.478711 -281.286954) (xy 102.524878 -281.310477) (xy 102.566797 -281.340933) (xy 102.603435 -281.377571)
			(xy 102.633891 -281.41949) (xy 102.657414 -281.465657) (xy 102.673426 -281.514936) (xy 102.681532 -281.566113)
			(xy 102.68204 -281.59202) (xy 102.681571 -281.617393) (xy 102.673789 -281.667539) (xy 102.658411 -281.715899)
			(xy 102.635802 -281.76133) (xy 102.606496 -281.802758) (xy 102.571185 -281.839204) (xy 102.530704 -281.869806)
			(xy 102.486011 -281.89384) (xy 102.438161 -281.910739) (xy 102.413308 -281.91587) (xy 102.390448 -281.920188)
			(xy 102.18547 -282.275026) (xy 102.193344 -282.297124) (xy 102.198678 -282.314142) (xy 102.202234 -282.326588)
			(xy 102.247446 -282.3718) (xy 102.944422 -281.674824) (xy 102.940358 -281.648916) (xy 102.938216 -281.63479)
			(xy 102.935926 -281.606307) (xy 102.935786 -281.59202) (xy 102.93626 -281.566077) (xy 102.943802 -281.514741)
			(xy 102.958714 -281.465043) (xy 102.98068 -281.418035) (xy 103.009235 -281.374712) (xy 103.043776 -281.335992)
			(xy 103.083569 -281.302695) (xy 103.127774 -281.275525) (xy 103.151432 -281.264868) (xy 103.182166 -281.25166)
			(xy 103.182166 -281.156156) (xy 103.181738 -281.142332) (xy 103.174384 -281.115681) (xy 103.160146 -281.091983)
			(xy 103.14007 -281.072977) (xy 103.115628 -281.060057) (xy 103.088616 -281.054171) (xy 103.061015 -281.055753)
			(xy 103.034851 -281.064686) (xy 103.023162 -281.072082) (xy 103.000858 -281.086777) (xy 102.952777 -281.110031)
			(xy 102.901759 -281.125838) (xy 102.848953 -281.133842) (xy 102.822248 -281.134312) (xy 102.795594 -281.133842)
			(xy 102.742881 -281.125904) (xy 102.69194 -281.110196) (xy 102.64391 -281.087072) (xy 102.599863 -281.057046)
			(xy 102.560783 -281.020791) (xy 102.527544 -280.979115) (xy 102.500888 -280.932951) (xy 102.481411 -280.883329)
			(xy 102.469548 -280.831358) (xy 102.465564 -280.7782) (xy 102.469548 -280.725042) (xy 102.481411 -280.673071)
			(xy 102.500888 -280.623449) (xy 102.527544 -280.577285) (xy 102.560783 -280.535609) (xy 102.599863 -280.499354)
			(xy 102.64391 -280.469328) (xy 102.69194 -280.446204) (xy 102.742881 -280.430496) (xy 102.795594 -280.422558)
			(xy 102.822248 -280.422096) (xy 102.848949 -280.422598) (xy 102.901747 -280.430617) (xy 102.952758 -280.446424)
			(xy 103.000839 -280.469665) (xy 103.023162 -280.484326) (xy 103.034832 -280.491761) (xy 103.061007 -280.500696)
			(xy 103.08862 -280.502279) (xy 103.115645 -280.496391) (xy 103.140097 -280.483466) (xy 103.160183 -280.464451)
			(xy 103.174428 -280.440744) (xy 103.181787 -280.414082) (xy 103.182166 -280.400252) (xy 103.182166 -280.304494)
			(xy 103.151432 -280.291286) (xy 103.127762 -280.280635) (xy 103.083528 -280.253483) (xy 103.043705 -280.220196)
			(xy 103.009139 -280.181477) (xy 102.980563 -280.138149) (xy 102.958583 -280.09113) (xy 102.943665 -280.041417)
			(xy 102.936125 -279.990065) (xy 102.936123 -279.938162) (xy 102.943659 -279.886809) (xy 102.958574 -279.837095)
			(xy 102.98055 -279.790075) (xy 103.009123 -279.746744) (xy 103.043686 -279.708023) (xy 103.083506 -279.674732)
			(xy 103.127739 -279.647578) (xy 103.151432 -279.636982) (xy 103.182166 -279.623774) (xy 103.182166 -279.347676)
			(xy 103.086916 -279.347676) (xy 103.071676 -279.365456) (xy 103.055943 -279.38307) (xy 103.020302 -279.414057)
			(xy 102.980605 -279.43964) (xy 102.937662 -279.459297) (xy 102.892354 -279.472624) (xy 102.845608 -279.479349)
			(xy 102.821994 -279.479756) (xy 102.796106 -279.479248) (xy 102.744966 -279.471147) (xy 102.695724 -279.455147)
			(xy 102.64959 -279.43164) (xy 102.607702 -279.401206) (xy 102.571091 -279.364593) (xy 102.540657 -279.322705)
			(xy 102.517151 -279.276571) (xy 102.501151 -279.227328) (xy 102.493052 -279.176188) (xy 102.493052 -279.124412)
			(xy 102.501151 -279.073272) (xy 102.517151 -279.024029) (xy 102.540657 -278.977895) (xy 102.571091 -278.936007)
			(xy 102.607702 -278.899394) (xy 102.64959 -278.86896) (xy 102.695724 -278.845453) (xy 102.744966 -278.829453)
			(xy 102.796106 -278.821352) (xy 102.821994 -278.82088) (xy 102.845611 -278.821265) (xy 102.892365 -278.827971)
			(xy 102.937681 -278.841291) (xy 102.980629 -278.860949) (xy 103.020326 -278.886544) (xy 103.055958 -278.917549)
			(xy 103.071676 -278.93518) (xy 103.086916 -278.95296) (xy 103.182166 -278.95296) (xy 103.182166 -278.676862)
			(xy 103.151432 -278.663654) (xy 103.127791 -278.65298) (xy 103.083616 -278.625794) (xy 103.043852 -278.592488)
			(xy 103.00934 -278.553764) (xy 102.980812 -278.510444) (xy 102.95887 -278.463444) (xy 102.943979 -278.413757)
			(xy 102.936454 -278.362436) (xy 102.936454 -278.310566) (xy 102.943979 -278.259244) (xy 102.95887 -278.209558)
			(xy 102.980811 -278.162557) (xy 103.009339 -278.119237) (xy 103.043851 -278.080514) (xy 103.083614 -278.047207)
			(xy 103.127789 -278.020021) (xy 103.151432 -278.00935) (xy 103.182166 -277.996142) (xy 103.182166 -277.021036)
			(xy 103.152956 -277.00732) (xy 103.128935 -276.995573) (xy 103.084731 -276.96549) (xy 103.045966 -276.928663)
			(xy 103.013656 -276.886059) (xy 102.988651 -276.838797) (xy 102.971606 -276.788118) (xy 102.962969 -276.735351)
			(xy 102.962456 -276.708616) (xy 102.962727 -276.689776) (xy 102.967051 -276.652344) (xy 102.971092 -276.63394)
			(xy 102.974022 -276.618975) (xy 102.971813 -276.588575) (xy 102.960739 -276.560177) (xy 102.941785 -276.536306)
			(xy 102.916635 -276.519085) (xy 102.887525 -276.510045) (xy 102.872286 -276.50948) (xy 102.694994 -276.50948)
			(xy 102.65537 -276.577806) (xy 102.663244 -276.599904) (xy 102.671806 -276.626261) (xy 102.680997 -276.680908)
			(xy 102.681532 -276.708616) (xy 102.681024 -276.734503) (xy 102.672925 -276.785641) (xy 102.656926 -276.834881)
			(xy 102.63342 -276.881013) (xy 102.602988 -276.9229) (xy 102.566378 -276.95951) (xy 102.524491 -276.989942)
			(xy 102.478359 -277.013448) (xy 102.429119 -277.029447) (xy 102.377981 -277.037546) (xy 102.326207 -277.037546)
			(xy 102.275069 -277.029447) (xy 102.225829 -277.013448) (xy 102.179697 -276.989942) (xy 102.13781 -276.95951)
			(xy 102.1012 -276.9229) (xy 102.070768 -276.881013) (xy 102.047262 -276.834881) (xy 102.031263 -276.785641)
			(xy 102.023164 -276.734503) (xy 102.022656 -276.708616) (xy 102.022881 -276.689783) (xy 102.027079 -276.652353)
			(xy 102.031038 -276.63394) (xy 102.033969 -276.618978) (xy 102.031761 -276.588582) (xy 102.020686 -276.560189)
			(xy 102.001729 -276.536326) (xy 101.976578 -276.519116) (xy 101.947469 -276.510089) (xy 101.932232 -276.50948)
			(xy 101.859842 -276.50948) (xy 101.844706 -276.510042) (xy 101.815766 -276.518928) (xy 101.790699 -276.535902)
			(xy 101.771704 -276.559475) (xy 101.76045 -276.587579) (xy 101.757922 -276.617746) (xy 101.760528 -276.63267)
			(xy 101.764348 -276.651423) (xy 101.768418 -276.689479) (xy 101.768656 -276.708616) (xy 101.768158 -276.735265)
			(xy 101.760215 -276.787969) (xy 101.744505 -276.838899) (xy 101.721379 -276.88692) (xy 101.691355 -276.930957)
			(xy 101.655103 -276.970028) (xy 101.613432 -277.003259) (xy 101.567274 -277.029908) (xy 101.51766 -277.04938)
			(xy 101.465698 -277.06124) (xy 101.412548 -277.065224) (xy 101.359398 -277.06124) (xy 101.307436 -277.04938)
			(xy 101.257822 -277.029908) (xy 101.211664 -277.003259) (xy 101.169993 -276.970028) (xy 101.133741 -276.930957)
			(xy 101.103717 -276.88692) (xy 101.080591 -276.838899) (xy 101.064881 -276.787969) (xy 101.056938 -276.735265)
			(xy 101.05644 -276.708616) (xy 101.05668 -276.689479) (xy 101.060752 -276.651424) (xy 101.064568 -276.63267)
			(xy 101.067241 -276.617756) (xy 101.064713 -276.587578) (xy 101.053449 -276.559467) (xy 101.034439 -276.535893)
			(xy 101.009353 -276.518929) (xy 100.980396 -276.510064) (xy 100.965254 -276.50948) (xy 100.89007 -276.50948)
			(xy 100.874793 -276.509987) (xy 100.845601 -276.519012) (xy 100.82039 -276.536274) (xy 100.801419 -276.560225)
			(xy 100.790388 -276.588718) (xy 100.788286 -276.6192) (xy 100.791264 -276.634194) (xy 100.795306 -276.652533)
			(xy 100.799637 -276.689838) (xy 100.7999 -276.708616) (xy 100.799396 -276.734324) (xy 100.791353 -276.785106)
			(xy 100.775465 -276.834005) (xy 100.752122 -276.879817) (xy 100.721901 -276.921413) (xy 100.685545 -276.957769)
			(xy 100.643949 -276.98799) (xy 100.598137 -277.011333) (xy 100.549238 -277.027221) (xy 100.498456 -277.035264)
			(xy 100.44704 -277.035264) (xy 100.396258 -277.027221) (xy 100.347359 -277.011333) (xy 100.301547 -276.98799)
			(xy 100.259951 -276.957769) (xy 100.223595 -276.921413) (xy 100.193374 -276.879817) (xy 100.170031 -276.834005)
			(xy 100.154143 -276.785106) (xy 100.1461 -276.734324) (xy 100.145596 -276.708616) (xy 100.145862 -276.689838)
			(xy 100.150187 -276.652533) (xy 100.154232 -276.634194) (xy 100.157202 -276.619205) (xy 100.15505 -276.588739)
			(xy 100.144002 -276.560264) (xy 100.125041 -276.536319) (xy 100.099858 -276.519037) (xy 100.070696 -276.509957)
			(xy 100.055426 -276.50948) (xy 99.980242 -276.50948) (xy 99.965106 -276.510042) (xy 99.936166 -276.518928)
			(xy 99.911099 -276.535902) (xy 99.892104 -276.559475) (xy 99.88085 -276.587579) (xy 99.878322 -276.617746)
			(xy 99.880928 -276.63267) (xy 99.884748 -276.651423) (xy 99.888818 -276.689479) (xy 99.889056 -276.708616)
			(xy 99.888558 -276.735265) (xy 99.880615 -276.787969) (xy 99.864905 -276.838899) (xy 99.841779 -276.88692)
			(xy 99.811755 -276.930957) (xy 99.775503 -276.970028) (xy 99.733832 -277.003259) (xy 99.687674 -277.029908)
			(xy 99.63806 -277.04938) (xy 99.586098 -277.06124) (xy 99.532948 -277.065224) (xy 99.479798 -277.06124)
			(xy 99.427836 -277.04938) (xy 99.378222 -277.029908) (xy 99.332064 -277.003259) (xy 99.290393 -276.970028)
			(xy 99.254141 -276.930957) (xy 99.224117 -276.88692) (xy 99.200991 -276.838899) (xy 99.185281 -276.787969)
			(xy 99.177338 -276.735265) (xy 99.17684 -276.708616) (xy 99.17708 -276.689479) (xy 99.181152 -276.651424)
			(xy 99.184968 -276.63267) (xy 99.187641 -276.617756) (xy 99.185113 -276.587578) (xy 99.173849 -276.559467)
			(xy 99.154839 -276.535893) (xy 99.129753 -276.518929) (xy 99.100796 -276.510064) (xy 99.085654 -276.50948)
			(xy 99.01047 -276.50948) (xy 98.995193 -276.509987) (xy 98.966001 -276.519012) (xy 98.94079 -276.536274)
			(xy 98.921819 -276.560225) (xy 98.910788 -276.588718) (xy 98.908686 -276.6192) (xy 98.911664 -276.634194)
			(xy 98.915706 -276.652533) (xy 98.920037 -276.689838) (xy 98.9203 -276.708616) (xy 98.919796 -276.734324)
			(xy 98.911753 -276.785106) (xy 98.895865 -276.834005) (xy 98.872522 -276.879817) (xy 98.842301 -276.921413)
			(xy 98.805945 -276.957769) (xy 98.764349 -276.98799) (xy 98.718537 -277.011333) (xy 98.669638 -277.027221)
			(xy 98.618856 -277.035264) (xy 98.56744 -277.035264) (xy 98.516658 -277.027221) (xy 98.467759 -277.011333)
			(xy 98.421947 -276.98799) (xy 98.380351 -276.957769) (xy 98.343995 -276.921413) (xy 98.313774 -276.879817)
			(xy 98.290431 -276.834005) (xy 98.274543 -276.785106) (xy 98.2665 -276.734324) (xy 98.265996 -276.708616)
			(xy 98.266262 -276.689838) (xy 98.270587 -276.652533) (xy 98.274632 -276.634194) (xy 98.277602 -276.619205)
			(xy 98.27545 -276.588739) (xy 98.264402 -276.560264) (xy 98.245441 -276.536319) (xy 98.220258 -276.519037)
			(xy 98.191096 -276.509957) (xy 98.175826 -276.50948) (xy 98.100388 -276.50948) (xy 98.085247 -276.510036)
			(xy 98.056295 -276.518914) (xy 98.031215 -276.535886) (xy 98.012211 -276.559463) (xy 98.000951 -276.587575)
			(xy 97.998423 -276.617752) (xy 98.001074 -276.63267) (xy 98.004894 -276.651423) (xy 98.008963 -276.689479)
			(xy 98.009202 -276.708616) (xy 98.008704 -276.735265) (xy 98.000761 -276.787969) (xy 97.985051 -276.838899)
			(xy 97.961925 -276.88692) (xy 97.931901 -276.930957) (xy 97.895649 -276.970028) (xy 97.853978 -277.003259)
			(xy 97.80782 -277.029908) (xy 97.758206 -277.04938) (xy 97.706244 -277.06124) (xy 97.653094 -277.065224)
			(xy 97.599944 -277.06124) (xy 97.547982 -277.04938) (xy 97.498368 -277.029908) (xy 97.45221 -277.003259)
			(xy 97.410539 -276.970028) (xy 97.374287 -276.930957) (xy 97.344263 -276.88692) (xy 97.321137 -276.838899)
			(xy 97.305427 -276.787969) (xy 97.297484 -276.735265) (xy 97.296986 -276.708616) (xy 97.297226 -276.689479)
			(xy 97.301299 -276.651424) (xy 97.305114 -276.63267) (xy 97.307787 -276.617753) (xy 97.305258 -276.587571)
			(xy 97.293995 -276.559456) (xy 97.274987 -276.535875) (xy 97.249902 -276.518901) (xy 97.220944 -276.510025)
			(xy 97.2058 -276.50948) (xy 97.13087 -276.50948) (xy 97.115593 -276.509987) (xy 97.086401 -276.519012)
			(xy 97.06119 -276.536274) (xy 97.042219 -276.560225) (xy 97.031188 -276.588718) (xy 97.029086 -276.6192)
			(xy 97.032064 -276.634194) (xy 97.036106 -276.652533) (xy 97.040437 -276.689838) (xy 97.0407 -276.708616)
			(xy 97.040196 -276.734324) (xy 97.032153 -276.785106) (xy 97.016265 -276.834005) (xy 96.992922 -276.879817)
			(xy 96.962701 -276.921413) (xy 96.926345 -276.957769) (xy 96.884749 -276.98799) (xy 96.838937 -277.011333)
			(xy 96.790038 -277.027221) (xy 96.739256 -277.035264) (xy 96.68784 -277.035264) (xy 96.637058 -277.027221)
			(xy 96.588159 -277.011333) (xy 96.542347 -276.98799) (xy 96.500751 -276.957769) (xy 96.464395 -276.921413)
			(xy 96.434174 -276.879817) (xy 96.410831 -276.834005) (xy 96.394943 -276.785106) (xy 96.3869 -276.734324)
			(xy 96.386396 -276.708616) (xy 96.386662 -276.689838) (xy 96.390987 -276.652533) (xy 96.395032 -276.634194)
			(xy 96.398002 -276.619205) (xy 96.39585 -276.588739) (xy 96.384802 -276.560264) (xy 96.365841 -276.536319)
			(xy 96.340658 -276.519037) (xy 96.311496 -276.509957) (xy 96.296226 -276.50948) (xy 96.19107 -276.50948)
			(xy 96.175793 -276.509987) (xy 96.146601 -276.519012) (xy 96.12139 -276.536274) (xy 96.102419 -276.560225)
			(xy 96.091388 -276.588718) (xy 96.089286 -276.6192) (xy 96.092264 -276.634194) (xy 96.096306 -276.652533)
			(xy 96.100637 -276.689838) (xy 96.1009 -276.708616) (xy 96.100396 -276.734324) (xy 96.092353 -276.785106)
			(xy 96.076465 -276.834005) (xy 96.053122 -276.879817) (xy 96.022901 -276.921413) (xy 95.986545 -276.957769)
			(xy 95.944949 -276.98799) (xy 95.899137 -277.011333) (xy 95.850238 -277.027221) (xy 95.799456 -277.035264)
			(xy 95.74804 -277.035264) (xy 95.697258 -277.027221) (xy 95.648359 -277.011333) (xy 95.602547 -276.98799)
			(xy 95.560951 -276.957769) (xy 95.524595 -276.921413) (xy 95.494374 -276.879817) (xy 95.471031 -276.834005)
			(xy 95.455143 -276.785106) (xy 95.4471 -276.734324) (xy 95.446596 -276.708616) (xy 95.446862 -276.689838)
			(xy 95.451187 -276.652533) (xy 95.455232 -276.634194) (xy 95.458202 -276.619205) (xy 95.45605 -276.588739)
			(xy 95.445002 -276.560264) (xy 95.426041 -276.536319) (xy 95.400858 -276.519037) (xy 95.371696 -276.509957)
			(xy 95.356426 -276.50948) (xy 95.281242 -276.50948) (xy 95.266106 -276.510042) (xy 95.237166 -276.518928)
			(xy 95.212099 -276.535902) (xy 95.193104 -276.559475) (xy 95.18185 -276.587579) (xy 95.179322 -276.617746)
			(xy 95.181928 -276.63267) (xy 95.185748 -276.651423) (xy 95.189818 -276.689479) (xy 95.190056 -276.708616)
			(xy 95.189558 -276.735265) (xy 95.181615 -276.787969) (xy 95.165905 -276.838899) (xy 95.142779 -276.88692)
			(xy 95.112755 -276.930957) (xy 95.076503 -276.970028) (xy 95.034832 -277.003259) (xy 94.988674 -277.029908)
			(xy 94.93906 -277.04938) (xy 94.887098 -277.06124) (xy 94.833948 -277.065224) (xy 94.780798 -277.06124)
			(xy 94.728836 -277.04938) (xy 94.679222 -277.029908) (xy 94.633064 -277.003259) (xy 94.591393 -276.970028)
			(xy 94.555141 -276.930957) (xy 94.525117 -276.88692) (xy 94.501991 -276.838899) (xy 94.486281 -276.787969)
			(xy 94.478338 -276.735265) (xy 94.47784 -276.708616) (xy 94.47808 -276.689479) (xy 94.482152 -276.651424)
			(xy 94.485968 -276.63267) (xy 94.488641 -276.617756) (xy 94.486113 -276.587578) (xy 94.474849 -276.559467)
			(xy 94.455839 -276.535893) (xy 94.430753 -276.518929) (xy 94.401796 -276.510064) (xy 94.386654 -276.50948)
			(xy 94.31147 -276.50948) (xy 94.296193 -276.509987) (xy 94.267001 -276.519012) (xy 94.24179 -276.536274)
			(xy 94.222819 -276.560225) (xy 94.211788 -276.588718) (xy 94.209686 -276.6192) (xy 94.212664 -276.634194)
			(xy 94.216706 -276.652533) (xy 94.221037 -276.689838) (xy 94.2213 -276.708616) (xy 94.220796 -276.734324)
			(xy 94.212753 -276.785106) (xy 94.196865 -276.834005) (xy 94.173522 -276.879817) (xy 94.143301 -276.921413)
			(xy 94.106945 -276.957769) (xy 94.065349 -276.98799) (xy 94.019537 -277.011333) (xy 93.970638 -277.027221)
			(xy 93.919856 -277.035264) (xy 93.86844 -277.035264) (xy 93.817658 -277.027221) (xy 93.768759 -277.011333)
			(xy 93.722947 -276.98799) (xy 93.681351 -276.957769) (xy 93.644995 -276.921413) (xy 93.614774 -276.879817)
			(xy 93.591431 -276.834005) (xy 93.575543 -276.785106) (xy 93.5675 -276.734324) (xy 93.566996 -276.708616)
			(xy 93.567262 -276.689838) (xy 93.571587 -276.652533) (xy 93.575632 -276.634194) (xy 93.578602 -276.619205)
			(xy 93.57645 -276.588739) (xy 93.565402 -276.560264) (xy 93.546441 -276.536319) (xy 93.521258 -276.519037)
			(xy 93.492096 -276.509957) (xy 93.476826 -276.50948) (xy 93.401642 -276.50948) (xy 93.386506 -276.510042)
			(xy 93.357566 -276.518928) (xy 93.332499 -276.535902) (xy 93.313504 -276.559475) (xy 93.30225 -276.587579)
			(xy 93.299722 -276.617746) (xy 93.302328 -276.63267) (xy 93.306148 -276.651423) (xy 93.310218 -276.689479)
			(xy 93.310456 -276.708616) (xy 93.309958 -276.735265) (xy 93.302015 -276.787969) (xy 93.286305 -276.838899)
			(xy 93.263179 -276.88692) (xy 93.233155 -276.930957) (xy 93.196903 -276.970028) (xy 93.155232 -277.003259)
			(xy 93.109074 -277.029908) (xy 93.05946 -277.04938) (xy 93.007498 -277.06124) (xy 92.954348 -277.065224)
			(xy 92.901198 -277.06124) (xy 92.849236 -277.04938) (xy 92.799622 -277.029908) (xy 92.753464 -277.003259)
			(xy 92.711793 -276.970028) (xy 92.675541 -276.930957) (xy 92.645517 -276.88692) (xy 92.622391 -276.838899)
			(xy 92.606681 -276.787969) (xy 92.598738 -276.735265) (xy 92.59824 -276.708616) (xy 92.59848 -276.689479)
			(xy 92.602552 -276.651424) (xy 92.606368 -276.63267) (xy 92.609041 -276.617756) (xy 92.606513 -276.587578)
			(xy 92.595249 -276.559467) (xy 92.576239 -276.535893) (xy 92.551153 -276.518929) (xy 92.522196 -276.510064)
			(xy 92.507054 -276.50948) (xy 92.43187 -276.50948) (xy 92.416593 -276.509987) (xy 92.387401 -276.519012)
			(xy 92.36219 -276.536274) (xy 92.343219 -276.560225) (xy 92.332188 -276.588718) (xy 92.330086 -276.6192)
			(xy 92.333064 -276.634194) (xy 92.337106 -276.652533) (xy 92.341437 -276.689838) (xy 92.3417 -276.708616)
			(xy 92.341196 -276.734324) (xy 92.333153 -276.785106) (xy 92.317265 -276.834005) (xy 92.293922 -276.879817)
			(xy 92.263701 -276.921413) (xy 92.227345 -276.957769) (xy 92.185749 -276.98799) (xy 92.139937 -277.011333)
			(xy 92.091038 -277.027221) (xy 92.040256 -277.035264) (xy 91.98884 -277.035264) (xy 91.938058 -277.027221)
			(xy 91.889159 -277.011333) (xy 91.843347 -276.98799) (xy 91.801751 -276.957769) (xy 91.765395 -276.921413)
			(xy 91.735174 -276.879817) (xy 91.711831 -276.834005) (xy 91.695943 -276.785106) (xy 91.6879 -276.734324)
			(xy 91.687396 -276.708616) (xy 91.687662 -276.689838) (xy 91.691987 -276.652533) (xy 91.696032 -276.634194)
			(xy 91.699002 -276.619205) (xy 91.69685 -276.588739) (xy 91.685802 -276.560264) (xy 91.666841 -276.536319)
			(xy 91.641658 -276.519037) (xy 91.612496 -276.509957) (xy 91.597226 -276.50948) (xy 91.521788 -276.50948)
			(xy 91.506647 -276.510036) (xy 91.477695 -276.518914) (xy 91.452615 -276.535886) (xy 91.433611 -276.559463)
			(xy 91.422351 -276.587575) (xy 91.419823 -276.617752) (xy 91.422474 -276.63267) (xy 91.426294 -276.651423)
			(xy 91.430363 -276.689479) (xy 91.430602 -276.708616) (xy 91.430104 -276.735265) (xy 91.422161 -276.787969)
			(xy 91.406451 -276.838899) (xy 91.383325 -276.88692) (xy 91.353301 -276.930957) (xy 91.317049 -276.970028)
			(xy 91.275378 -277.003259) (xy 91.22922 -277.029908) (xy 91.179606 -277.04938) (xy 91.127644 -277.06124)
			(xy 91.074494 -277.065224) (xy 91.021344 -277.06124) (xy 90.969382 -277.04938) (xy 90.919768 -277.029908)
			(xy 90.87361 -277.003259) (xy 90.831939 -276.970028) (xy 90.795687 -276.930957) (xy 90.765663 -276.88692)
			(xy 90.742537 -276.838899) (xy 90.726827 -276.787969) (xy 90.718884 -276.735265) (xy 90.718386 -276.708616)
			(xy 90.718626 -276.689479) (xy 90.722699 -276.651424) (xy 90.726514 -276.63267) (xy 90.729187 -276.617753)
			(xy 90.726658 -276.587571) (xy 90.715395 -276.559456) (xy 90.696387 -276.535875) (xy 90.671302 -276.518901)
			(xy 90.642344 -276.510025) (xy 90.6272 -276.50948) (xy 90.552016 -276.50948) (xy 90.536734 -276.509981)
			(xy 90.50753 -276.518998) (xy 90.482307 -276.536258) (xy 90.463325 -276.560213) (xy 90.452289 -276.588715)
			(xy 90.450186 -276.619206) (xy 90.45321 -276.634194) (xy 90.457188 -276.65254) (xy 90.461394 -276.689845)
			(xy 90.461592 -276.708616) (xy 90.461088 -276.734304) (xy 90.453051 -276.785047) (xy 90.437175 -276.833908)
			(xy 90.413851 -276.879684) (xy 90.383654 -276.921248) (xy 90.347326 -276.957576) (xy 90.305762 -276.987773)
			(xy 90.259986 -277.011097) (xy 90.211125 -277.026973) (xy 90.160382 -277.03501) (xy 90.109006 -277.03501)
			(xy 90.058263 -277.026973) (xy 90.009402 -277.011097) (xy 89.963626 -276.987773) (xy 89.922062 -276.957576)
			(xy 89.885734 -276.921248) (xy 89.855537 -276.879684) (xy 89.832213 -276.833908) (xy 89.816337 -276.785047)
			(xy 89.8083 -276.734304) (xy 89.807796 -276.708616) (xy 89.808023 -276.689846) (xy 89.812219 -276.652543)
			(xy 89.816178 -276.634194) (xy 89.819148 -276.619208) (xy 89.816997 -276.588746) (xy 89.805948 -276.560277)
			(xy 89.786986 -276.53634) (xy 89.761801 -276.519068) (xy 89.73264 -276.510002) (xy 89.717372 -276.50948)
			(xy 89.612216 -276.50948) (xy 89.596934 -276.509981) (xy 89.56773 -276.518998) (xy 89.542507 -276.536258)
			(xy 89.523525 -276.560213) (xy 89.512489 -276.588715) (xy 89.510386 -276.619206) (xy 89.51341 -276.634194)
			(xy 89.517388 -276.65254) (xy 89.521594 -276.689845) (xy 89.521792 -276.708616) (xy 89.521288 -276.734304)
			(xy 89.513251 -276.785047) (xy 89.497375 -276.833908) (xy 89.474051 -276.879684) (xy 89.443854 -276.921248)
			(xy 89.407526 -276.957576) (xy 89.365962 -276.987773) (xy 89.320186 -277.011097) (xy 89.271325 -277.026973)
			(xy 89.220582 -277.03501) (xy 89.169206 -277.03501) (xy 89.118463 -277.026973) (xy 89.069602 -277.011097)
			(xy 89.023826 -276.987773) (xy 88.982262 -276.957576) (xy 88.945934 -276.921248) (xy 88.915737 -276.879684)
			(xy 88.892413 -276.833908) (xy 88.876537 -276.785047) (xy 88.8685 -276.734304) (xy 88.867996 -276.708616)
			(xy 88.868223 -276.689846) (xy 88.872419 -276.652543) (xy 88.876378 -276.634194) (xy 88.879348 -276.619208)
			(xy 88.877197 -276.588746) (xy 88.866148 -276.560277) (xy 88.847186 -276.53634) (xy 88.822001 -276.519068)
			(xy 88.79284 -276.510002) (xy 88.777572 -276.50948) (xy 88.702388 -276.50948) (xy 88.687247 -276.510036)
			(xy 88.658295 -276.518914) (xy 88.633215 -276.535886) (xy 88.614211 -276.559463) (xy 88.602951 -276.587575)
			(xy 88.600423 -276.617752) (xy 88.603074 -276.63267) (xy 88.606894 -276.651423) (xy 88.610963 -276.689479)
			(xy 88.611202 -276.708616) (xy 88.610704 -276.735265) (xy 88.602761 -276.787969) (xy 88.587051 -276.838899)
			(xy 88.563925 -276.88692) (xy 88.533901 -276.930957) (xy 88.497649 -276.970028) (xy 88.455978 -277.003259)
			(xy 88.40982 -277.029908) (xy 88.360206 -277.04938) (xy 88.308244 -277.06124) (xy 88.255094 -277.065224)
			(xy 88.201944 -277.06124) (xy 88.149982 -277.04938) (xy 88.100368 -277.029908) (xy 88.05421 -277.003259)
			(xy 88.012539 -276.970028) (xy 87.976287 -276.930957) (xy 87.946263 -276.88692) (xy 87.923137 -276.838899)
			(xy 87.907427 -276.787969) (xy 87.899484 -276.735265) (xy 87.898986 -276.708616) (xy 87.899226 -276.689479)
			(xy 87.903299 -276.651424) (xy 87.907114 -276.63267) (xy 87.909787 -276.617753) (xy 87.907258 -276.587571)
			(xy 87.895995 -276.559456) (xy 87.876987 -276.535875) (xy 87.851902 -276.518901) (xy 87.822944 -276.510025)
			(xy 87.8078 -276.50948) (xy 85.767926 -276.50948) (xy 85.006455 -277.270951) (xy 86.945968 -277.270951)
			(xy 86.945968 -277.217653) (xy 86.953911 -277.164949) (xy 86.969621 -277.114019) (xy 86.992747 -277.065998)
			(xy 87.022771 -277.021961) (xy 87.059023 -276.98289) (xy 87.100694 -276.949659) (xy 87.146852 -276.92301)
			(xy 87.196466 -276.903538) (xy 87.248428 -276.891678) (xy 87.301578 -276.887695) (xy 87.354728 -276.891678)
			(xy 87.40669 -276.903538) (xy 87.456304 -276.92301) (xy 87.502462 -276.949659) (xy 87.544133 -276.98289)
			(xy 87.580385 -277.021961) (xy 87.610409 -277.065998) (xy 87.633535 -277.114019) (xy 87.649245 -277.164949)
			(xy 87.657188 -277.217653) (xy 87.657686 -277.244302) (xy 87.657188 -277.270951) (xy 87.649245 -277.323655)
			(xy 87.633535 -277.374585) (xy 87.610409 -277.422606) (xy 87.580385 -277.466643) (xy 87.544133 -277.505714)
			(xy 87.502462 -277.538945) (xy 87.484466 -277.549335) (xy 88.36913 -277.549335) (xy 88.36913 -277.496037)
			(xy 88.377073 -277.443333) (xy 88.392783 -277.392403) (xy 88.415909 -277.344382) (xy 88.445933 -277.300345)
			(xy 88.482185 -277.261274) (xy 88.523856 -277.228043) (xy 88.570014 -277.201394) (xy 88.619628 -277.181922)
			(xy 88.67159 -277.170062) (xy 88.72474 -277.166079) (xy 88.77789 -277.170062) (xy 88.829852 -277.181922)
			(xy 88.879466 -277.201394) (xy 88.925624 -277.228043) (xy 88.967295 -277.261274) (xy 89.003547 -277.300345)
			(xy 89.033571 -277.344382) (xy 89.056697 -277.392403) (xy 89.072407 -277.443333) (xy 89.08035 -277.496037)
			(xy 89.080848 -277.522686) (xy 89.080355 -277.549081) (xy 89.309184 -277.549081) (xy 89.309184 -277.495783)
			(xy 89.317127 -277.443079) (xy 89.332837 -277.392149) (xy 89.355963 -277.344128) (xy 89.385987 -277.300091)
			(xy 89.422239 -277.26102) (xy 89.46391 -277.227789) (xy 89.510068 -277.20114) (xy 89.559682 -277.181668)
			(xy 89.611644 -277.169808) (xy 89.664794 -277.165825) (xy 89.717944 -277.169808) (xy 89.769906 -277.181668)
			(xy 89.81952 -277.20114) (xy 89.865678 -277.227789) (xy 89.907349 -277.26102) (xy 89.943601 -277.300091)
			(xy 89.973625 -277.344128) (xy 89.996751 -277.392149) (xy 90.012461 -277.443079) (xy 90.020404 -277.495783)
			(xy 90.020902 -277.522432) (xy 90.020404 -277.549081) (xy 90.249238 -277.549081) (xy 90.249238 -277.495783)
			(xy 90.257181 -277.443079) (xy 90.272891 -277.392149) (xy 90.296017 -277.344128) (xy 90.326041 -277.300091)
			(xy 90.362293 -277.26102) (xy 90.403964 -277.227789) (xy 90.450122 -277.20114) (xy 90.499736 -277.181668)
			(xy 90.551698 -277.169808) (xy 90.604848 -277.165825) (xy 90.657998 -277.169808) (xy 90.70996 -277.181668)
			(xy 90.759574 -277.20114) (xy 90.805732 -277.227789) (xy 90.847403 -277.26102) (xy 90.883655 -277.300091)
			(xy 90.913679 -277.344128) (xy 90.936805 -277.392149) (xy 90.952515 -277.443079) (xy 90.960458 -277.495783)
			(xy 90.960956 -277.522432) (xy 90.960476 -277.54814) (xy 91.217746 -277.54814) (xy 91.217746 -277.496724)
			(xy 91.225789 -277.445942) (xy 91.241677 -277.397043) (xy 91.26502 -277.351231) (xy 91.295241 -277.309635)
			(xy 91.331597 -277.273279) (xy 91.373193 -277.243058) (xy 91.419005 -277.219715) (xy 91.467904 -277.203827)
			(xy 91.518686 -277.195784) (xy 91.570102 -277.195784) (xy 91.620884 -277.203827) (xy 91.669783 -277.219715)
			(xy 91.715595 -277.243058) (xy 91.757191 -277.273279) (xy 91.793547 -277.309635) (xy 91.823768 -277.351231)
			(xy 91.847111 -277.397043) (xy 91.862999 -277.445942) (xy 91.871042 -277.496724) (xy 91.871546 -277.522432)
			(xy 91.871042 -277.54814) (xy 92.157546 -277.54814) (xy 92.157546 -277.496724) (xy 92.165589 -277.445942)
			(xy 92.181477 -277.397043) (xy 92.20482 -277.351231) (xy 92.235041 -277.309635) (xy 92.271397 -277.273279)
			(xy 92.312993 -277.243058) (xy 92.358805 -277.219715) (xy 92.407704 -277.203827) (xy 92.458486 -277.195784)
			(xy 92.509902 -277.195784) (xy 92.560684 -277.203827) (xy 92.609583 -277.219715) (xy 92.655395 -277.243058)
			(xy 92.696991 -277.273279) (xy 92.733347 -277.309635) (xy 92.763568 -277.351231) (xy 92.786911 -277.397043)
			(xy 92.802799 -277.445942) (xy 92.810842 -277.496724) (xy 92.811346 -277.522432) (xy 92.810842 -277.54814)
			(xy 93.097346 -277.54814) (xy 93.097346 -277.496724) (xy 93.105389 -277.445942) (xy 93.121277 -277.397043)
			(xy 93.14462 -277.351231) (xy 93.174841 -277.309635) (xy 93.211197 -277.273279) (xy 93.252793 -277.243058)
			(xy 93.298605 -277.219715) (xy 93.347504 -277.203827) (xy 93.398286 -277.195784) (xy 93.449702 -277.195784)
			(xy 93.500484 -277.203827) (xy 93.549383 -277.219715) (xy 93.595195 -277.243058) (xy 93.636791 -277.273279)
			(xy 93.673147 -277.309635) (xy 93.703368 -277.351231) (xy 93.726711 -277.397043) (xy 93.742599 -277.445942)
			(xy 93.750642 -277.496724) (xy 93.751146 -277.522432) (xy 93.750642 -277.54814) (xy 94.037146 -277.54814)
			(xy 94.037146 -277.496724) (xy 94.045189 -277.445942) (xy 94.061077 -277.397043) (xy 94.08442 -277.351231)
			(xy 94.114641 -277.309635) (xy 94.150997 -277.273279) (xy 94.192593 -277.243058) (xy 94.238405 -277.219715)
			(xy 94.287304 -277.203827) (xy 94.338086 -277.195784) (xy 94.389502 -277.195784) (xy 94.440284 -277.203827)
			(xy 94.489183 -277.219715) (xy 94.534995 -277.243058) (xy 94.576591 -277.273279) (xy 94.612947 -277.309635)
			(xy 94.643168 -277.351231) (xy 94.666511 -277.397043) (xy 94.682399 -277.445942) (xy 94.690442 -277.496724)
			(xy 94.690946 -277.522432) (xy 94.690442 -277.54814) (xy 94.690293 -277.549081) (xy 94.947984 -277.549081)
			(xy 94.947984 -277.495783) (xy 94.955927 -277.443079) (xy 94.971637 -277.392149) (xy 94.994763 -277.344128)
			(xy 95.024787 -277.300091) (xy 95.061039 -277.26102) (xy 95.10271 -277.227789) (xy 95.148868 -277.20114)
			(xy 95.198482 -277.181668) (xy 95.250444 -277.169808) (xy 95.303594 -277.165825) (xy 95.356744 -277.169808)
			(xy 95.408706 -277.181668) (xy 95.45832 -277.20114) (xy 95.504478 -277.227789) (xy 95.546149 -277.26102)
			(xy 95.582401 -277.300091) (xy 95.612425 -277.344128) (xy 95.635551 -277.392149) (xy 95.651261 -277.443079)
			(xy 95.659204 -277.495783) (xy 95.659702 -277.522432) (xy 95.659204 -277.549081) (xy 95.887784 -277.549081)
			(xy 95.887784 -277.495783) (xy 95.895727 -277.443079) (xy 95.911437 -277.392149) (xy 95.934563 -277.344128)
			(xy 95.964587 -277.300091) (xy 96.000839 -277.26102) (xy 96.04251 -277.227789) (xy 96.088668 -277.20114)
			(xy 96.138282 -277.181668) (xy 96.190244 -277.169808) (xy 96.243394 -277.165825) (xy 96.296544 -277.169808)
			(xy 96.348506 -277.181668) (xy 96.39812 -277.20114) (xy 96.444278 -277.227789) (xy 96.485949 -277.26102)
			(xy 96.522201 -277.300091) (xy 96.552225 -277.344128) (xy 96.575351 -277.392149) (xy 96.591061 -277.443079)
			(xy 96.599004 -277.495783) (xy 96.599502 -277.522432) (xy 96.599004 -277.549081) (xy 96.827584 -277.549081)
			(xy 96.827584 -277.495783) (xy 96.835527 -277.443079) (xy 96.851237 -277.392149) (xy 96.874363 -277.344128)
			(xy 96.904387 -277.300091) (xy 96.940639 -277.26102) (xy 96.98231 -277.227789) (xy 97.028468 -277.20114)
			(xy 97.078082 -277.181668) (xy 97.130044 -277.169808) (xy 97.183194 -277.165825) (xy 97.236344 -277.169808)
			(xy 97.288306 -277.181668) (xy 97.33792 -277.20114) (xy 97.384078 -277.227789) (xy 97.425749 -277.26102)
			(xy 97.462001 -277.300091) (xy 97.492025 -277.344128) (xy 97.515151 -277.392149) (xy 97.530861 -277.443079)
			(xy 97.538804 -277.495783) (xy 97.539302 -277.522432) (xy 97.538822 -277.54814) (xy 97.796346 -277.54814)
			(xy 97.796346 -277.496724) (xy 97.804389 -277.445942) (xy 97.820277 -277.397043) (xy 97.84362 -277.351231)
			(xy 97.873841 -277.309635) (xy 97.910197 -277.273279) (xy 97.951793 -277.243058) (xy 97.997605 -277.219715)
			(xy 98.046504 -277.203827) (xy 98.097286 -277.195784) (xy 98.148702 -277.195784) (xy 98.199484 -277.203827)
			(xy 98.248383 -277.219715) (xy 98.294195 -277.243058) (xy 98.335791 -277.273279) (xy 98.372147 -277.309635)
			(xy 98.402368 -277.351231) (xy 98.425711 -277.397043) (xy 98.441599 -277.445942) (xy 98.449642 -277.496724)
			(xy 98.450146 -277.522432) (xy 98.449642 -277.54814) (xy 98.736146 -277.54814) (xy 98.736146 -277.496724)
			(xy 98.744189 -277.445942) (xy 98.760077 -277.397043) (xy 98.78342 -277.351231) (xy 98.813641 -277.309635)
			(xy 98.849997 -277.273279) (xy 98.891593 -277.243058) (xy 98.937405 -277.219715) (xy 98.986304 -277.203827)
			(xy 99.037086 -277.195784) (xy 99.088502 -277.195784) (xy 99.139284 -277.203827) (xy 99.188183 -277.219715)
			(xy 99.233995 -277.243058) (xy 99.275591 -277.273279) (xy 99.311947 -277.309635) (xy 99.342168 -277.351231)
			(xy 99.365511 -277.397043) (xy 99.381399 -277.445942) (xy 99.389442 -277.496724) (xy 99.389946 -277.522432)
			(xy 99.389442 -277.54814) (xy 99.675946 -277.54814) (xy 99.675946 -277.496724) (xy 99.683989 -277.445942)
			(xy 99.699877 -277.397043) (xy 99.72322 -277.351231) (xy 99.753441 -277.309635) (xy 99.789797 -277.273279)
			(xy 99.831393 -277.243058) (xy 99.877205 -277.219715) (xy 99.926104 -277.203827) (xy 99.976886 -277.195784)
			(xy 100.028302 -277.195784) (xy 100.079084 -277.203827) (xy 100.127983 -277.219715) (xy 100.173795 -277.243058)
			(xy 100.215391 -277.273279) (xy 100.251747 -277.309635) (xy 100.281968 -277.351231) (xy 100.305311 -277.397043)
			(xy 100.321199 -277.445942) (xy 100.329242 -277.496724) (xy 100.329746 -277.522432) (xy 100.329242 -277.54814)
			(xy 100.615746 -277.54814) (xy 100.615746 -277.496724) (xy 100.623789 -277.445942) (xy 100.639677 -277.397043)
			(xy 100.66302 -277.351231) (xy 100.693241 -277.309635) (xy 100.729597 -277.273279) (xy 100.771193 -277.243058)
			(xy 100.817005 -277.219715) (xy 100.865904 -277.203827) (xy 100.916686 -277.195784) (xy 100.968102 -277.195784)
			(xy 101.018884 -277.203827) (xy 101.067783 -277.219715) (xy 101.113595 -277.243058) (xy 101.155191 -277.273279)
			(xy 101.191547 -277.309635) (xy 101.221768 -277.351231) (xy 101.245111 -277.397043) (xy 101.260999 -277.445942)
			(xy 101.269042 -277.496724) (xy 101.269546 -277.522432) (xy 101.269042 -277.54814) (xy 101.268893 -277.549081)
			(xy 101.526838 -277.549081) (xy 101.526838 -277.495783) (xy 101.534781 -277.443079) (xy 101.550491 -277.392149)
			(xy 101.573617 -277.344128) (xy 101.603641 -277.300091) (xy 101.639893 -277.26102) (xy 101.681564 -277.227789)
			(xy 101.727722 -277.20114) (xy 101.777336 -277.181668) (xy 101.829298 -277.169808) (xy 101.882448 -277.165825)
			(xy 101.935598 -277.169808) (xy 101.98756 -277.181668) (xy 102.037174 -277.20114) (xy 102.083332 -277.227789)
			(xy 102.125003 -277.26102) (xy 102.161255 -277.300091) (xy 102.191279 -277.344128) (xy 102.214405 -277.392149)
			(xy 102.230115 -277.443079) (xy 102.238058 -277.495783) (xy 102.238556 -277.522432) (xy 102.238058 -277.549081)
			(xy 102.230115 -277.601785) (xy 102.214405 -277.652715) (xy 102.191279 -277.700736) (xy 102.161255 -277.744773)
			(xy 102.125003 -277.783844) (xy 102.083332 -277.817075) (xy 102.037174 -277.843724) (xy 101.98756 -277.863196)
			(xy 101.935598 -277.875056) (xy 101.882448 -277.87904) (xy 101.829298 -277.875056) (xy 101.777336 -277.863196)
			(xy 101.727722 -277.843724) (xy 101.681564 -277.817075) (xy 101.639893 -277.783844) (xy 101.603641 -277.744773)
			(xy 101.573617 -277.700736) (xy 101.550491 -277.652715) (xy 101.534781 -277.601785) (xy 101.526838 -277.549081)
			(xy 101.268893 -277.549081) (xy 101.260999 -277.598922) (xy 101.245111 -277.647821) (xy 101.221768 -277.693633)
			(xy 101.191547 -277.735229) (xy 101.155191 -277.771585) (xy 101.113595 -277.801806) (xy 101.067783 -277.825149)
			(xy 101.018884 -277.841037) (xy 100.968102 -277.84908) (xy 100.916686 -277.84908) (xy 100.865904 -277.841037)
			(xy 100.817005 -277.825149) (xy 100.771193 -277.801806) (xy 100.729597 -277.771585) (xy 100.693241 -277.735229)
			(xy 100.66302 -277.693633) (xy 100.639677 -277.647821) (xy 100.623789 -277.598922) (xy 100.615746 -277.54814)
			(xy 100.329242 -277.54814) (xy 100.321199 -277.598922) (xy 100.305311 -277.647821) (xy 100.281968 -277.693633)
			(xy 100.251747 -277.735229) (xy 100.215391 -277.771585) (xy 100.173795 -277.801806) (xy 100.127983 -277.825149)
			(xy 100.079084 -277.841037) (xy 100.028302 -277.84908) (xy 99.976886 -277.84908) (xy 99.926104 -277.841037)
			(xy 99.877205 -277.825149) (xy 99.831393 -277.801806) (xy 99.789797 -277.771585) (xy 99.753441 -277.735229)
			(xy 99.72322 -277.693633) (xy 99.699877 -277.647821) (xy 99.683989 -277.598922) (xy 99.675946 -277.54814)
			(xy 99.389442 -277.54814) (xy 99.381399 -277.598922) (xy 99.365511 -277.647821) (xy 99.342168 -277.693633)
			(xy 99.311947 -277.735229) (xy 99.275591 -277.771585) (xy 99.233995 -277.801806) (xy 99.188183 -277.825149)
			(xy 99.139284 -277.841037) (xy 99.088502 -277.84908) (xy 99.037086 -277.84908) (xy 98.986304 -277.841037)
			(xy 98.937405 -277.825149) (xy 98.891593 -277.801806) (xy 98.849997 -277.771585) (xy 98.813641 -277.735229)
			(xy 98.78342 -277.693633) (xy 98.760077 -277.647821) (xy 98.744189 -277.598922) (xy 98.736146 -277.54814)
			(xy 98.449642 -277.54814) (xy 98.441599 -277.598922) (xy 98.425711 -277.647821) (xy 98.402368 -277.693633)
			(xy 98.372147 -277.735229) (xy 98.335791 -277.771585) (xy 98.294195 -277.801806) (xy 98.248383 -277.825149)
			(xy 98.199484 -277.841037) (xy 98.148702 -277.84908) (xy 98.097286 -277.84908) (xy 98.046504 -277.841037)
			(xy 97.997605 -277.825149) (xy 97.951793 -277.801806) (xy 97.910197 -277.771585) (xy 97.873841 -277.735229)
			(xy 97.84362 -277.693633) (xy 97.820277 -277.647821) (xy 97.804389 -277.598922) (xy 97.796346 -277.54814)
			(xy 97.538822 -277.54814) (xy 97.538804 -277.549081) (xy 97.530861 -277.601785) (xy 97.515151 -277.652715)
			(xy 97.492025 -277.700736) (xy 97.462001 -277.744773) (xy 97.425749 -277.783844) (xy 97.384078 -277.817075)
			(xy 97.33792 -277.843724) (xy 97.288306 -277.863196) (xy 97.236344 -277.875056) (xy 97.183194 -277.87904)
			(xy 97.130044 -277.875056) (xy 97.078082 -277.863196) (xy 97.028468 -277.843724) (xy 96.98231 -277.817075)
			(xy 96.940639 -277.783844) (xy 96.904387 -277.744773) (xy 96.874363 -277.700736) (xy 96.851237 -277.652715)
			(xy 96.835527 -277.601785) (xy 96.827584 -277.549081) (xy 96.599004 -277.549081) (xy 96.591061 -277.601785)
			(xy 96.575351 -277.652715) (xy 96.552225 -277.700736) (xy 96.522201 -277.744773) (xy 96.485949 -277.783844)
			(xy 96.444278 -277.817075) (xy 96.39812 -277.843724) (xy 96.348506 -277.863196) (xy 96.296544 -277.875056)
			(xy 96.243394 -277.87904) (xy 96.190244 -277.875056) (xy 96.138282 -277.863196) (xy 96.088668 -277.843724)
			(xy 96.04251 -277.817075) (xy 96.000839 -277.783844) (xy 95.964587 -277.744773) (xy 95.934563 -277.700736)
			(xy 95.911437 -277.652715) (xy 95.895727 -277.601785) (xy 95.887784 -277.549081) (xy 95.659204 -277.549081)
			(xy 95.651261 -277.601785) (xy 95.635551 -277.652715) (xy 95.612425 -277.700736) (xy 95.582401 -277.744773)
			(xy 95.546149 -277.783844) (xy 95.504478 -277.817075) (xy 95.45832 -277.843724) (xy 95.408706 -277.863196)
			(xy 95.356744 -277.875056) (xy 95.303594 -277.87904) (xy 95.250444 -277.875056) (xy 95.198482 -277.863196)
			(xy 95.148868 -277.843724) (xy 95.10271 -277.817075) (xy 95.061039 -277.783844) (xy 95.024787 -277.744773)
			(xy 94.994763 -277.700736) (xy 94.971637 -277.652715) (xy 94.955927 -277.601785) (xy 94.947984 -277.549081)
			(xy 94.690293 -277.549081) (xy 94.682399 -277.598922) (xy 94.666511 -277.647821) (xy 94.643168 -277.693633)
			(xy 94.612947 -277.735229) (xy 94.576591 -277.771585) (xy 94.534995 -277.801806) (xy 94.489183 -277.825149)
			(xy 94.440284 -277.841037) (xy 94.389502 -277.84908) (xy 94.338086 -277.84908) (xy 94.287304 -277.841037)
			(xy 94.238405 -277.825149) (xy 94.192593 -277.801806) (xy 94.150997 -277.771585) (xy 94.114641 -277.735229)
			(xy 94.08442 -277.693633) (xy 94.061077 -277.647821) (xy 94.045189 -277.598922) (xy 94.037146 -277.54814)
			(xy 93.750642 -277.54814) (xy 93.742599 -277.598922) (xy 93.726711 -277.647821) (xy 93.703368 -277.693633)
			(xy 93.673147 -277.735229) (xy 93.636791 -277.771585) (xy 93.595195 -277.801806) (xy 93.549383 -277.825149)
			(xy 93.500484 -277.841037) (xy 93.449702 -277.84908) (xy 93.398286 -277.84908) (xy 93.347504 -277.841037)
			(xy 93.298605 -277.825149) (xy 93.252793 -277.801806) (xy 93.211197 -277.771585) (xy 93.174841 -277.735229)
			(xy 93.14462 -277.693633) (xy 93.121277 -277.647821) (xy 93.105389 -277.598922) (xy 93.097346 -277.54814)
			(xy 92.810842 -277.54814) (xy 92.802799 -277.598922) (xy 92.786911 -277.647821) (xy 92.763568 -277.693633)
			(xy 92.733347 -277.735229) (xy 92.696991 -277.771585) (xy 92.655395 -277.801806) (xy 92.609583 -277.825149)
			(xy 92.560684 -277.841037) (xy 92.509902 -277.84908) (xy 92.458486 -277.84908) (xy 92.407704 -277.841037)
			(xy 92.358805 -277.825149) (xy 92.312993 -277.801806) (xy 92.271397 -277.771585) (xy 92.235041 -277.735229)
			(xy 92.20482 -277.693633) (xy 92.181477 -277.647821) (xy 92.165589 -277.598922) (xy 92.157546 -277.54814)
			(xy 91.871042 -277.54814) (xy 91.862999 -277.598922) (xy 91.847111 -277.647821) (xy 91.823768 -277.693633)
			(xy 91.793547 -277.735229) (xy 91.757191 -277.771585) (xy 91.715595 -277.801806) (xy 91.669783 -277.825149)
			(xy 91.620884 -277.841037) (xy 91.570102 -277.84908) (xy 91.518686 -277.84908) (xy 91.467904 -277.841037)
			(xy 91.419005 -277.825149) (xy 91.373193 -277.801806) (xy 91.331597 -277.771585) (xy 91.295241 -277.735229)
			(xy 91.26502 -277.693633) (xy 91.241677 -277.647821) (xy 91.225789 -277.598922) (xy 91.217746 -277.54814)
			(xy 90.960476 -277.54814) (xy 90.960458 -277.549081) (xy 90.952515 -277.601785) (xy 90.936805 -277.652715)
			(xy 90.913679 -277.700736) (xy 90.883655 -277.744773) (xy 90.847403 -277.783844) (xy 90.805732 -277.817075)
			(xy 90.759574 -277.843724) (xy 90.70996 -277.863196) (xy 90.657998 -277.875056) (xy 90.604848 -277.87904)
			(xy 90.551698 -277.875056) (xy 90.499736 -277.863196) (xy 90.450122 -277.843724) (xy 90.403964 -277.817075)
			(xy 90.362293 -277.783844) (xy 90.326041 -277.744773) (xy 90.296017 -277.700736) (xy 90.272891 -277.652715)
			(xy 90.257181 -277.601785) (xy 90.249238 -277.549081) (xy 90.020404 -277.549081) (xy 90.012461 -277.601785)
			(xy 89.996751 -277.652715) (xy 89.973625 -277.700736) (xy 89.943601 -277.744773) (xy 89.907349 -277.783844)
			(xy 89.865678 -277.817075) (xy 89.81952 -277.843724) (xy 89.769906 -277.863196) (xy 89.717944 -277.875056)
			(xy 89.664794 -277.87904) (xy 89.611644 -277.875056) (xy 89.559682 -277.863196) (xy 89.510068 -277.843724)
			(xy 89.46391 -277.817075) (xy 89.422239 -277.783844) (xy 89.385987 -277.744773) (xy 89.355963 -277.700736)
			(xy 89.332837 -277.652715) (xy 89.317127 -277.601785) (xy 89.309184 -277.549081) (xy 89.080355 -277.549081)
			(xy 89.08035 -277.549335) (xy 89.072407 -277.602039) (xy 89.056697 -277.652969) (xy 89.033571 -277.70099)
			(xy 89.003547 -277.745027) (xy 88.967295 -277.784098) (xy 88.925624 -277.817329) (xy 88.879466 -277.843978)
			(xy 88.829852 -277.86345) (xy 88.77789 -277.87531) (xy 88.72474 -277.879294) (xy 88.67159 -277.87531)
			(xy 88.619628 -277.86345) (xy 88.570014 -277.843978) (xy 88.523856 -277.817329) (xy 88.482185 -277.784098)
			(xy 88.445933 -277.745027) (xy 88.415909 -277.70099) (xy 88.392783 -277.652969) (xy 88.377073 -277.602039)
			(xy 88.36913 -277.549335) (xy 87.484466 -277.549335) (xy 87.456304 -277.565594) (xy 87.40669 -277.585066)
			(xy 87.354728 -277.596926) (xy 87.301578 -277.60091) (xy 87.248428 -277.596926) (xy 87.196466 -277.585066)
			(xy 87.146852 -277.565594) (xy 87.100694 -277.538945) (xy 87.059023 -277.505714) (xy 87.022771 -277.466643)
			(xy 86.992747 -277.422606) (xy 86.969621 -277.374585) (xy 86.953911 -277.323655) (xy 86.945968 -277.270951)
			(xy 85.006455 -277.270951) (xy 84.734146 -277.54326) (xy 84.734146 -278.336502) (xy 86.031581 -278.336502)
			(xy 86.035611 -278.284004) (xy 86.047608 -278.232736) (xy 86.067291 -278.183901) (xy 86.094197 -278.138642)
			(xy 86.127697 -278.098021) (xy 86.167005 -278.06299) (xy 86.2112 -278.03437) (xy 86.259245 -278.012831)
			(xy 86.310016 -277.998879) (xy 86.362321 -277.992841) (xy 86.414935 -277.994858) (xy 86.466625 -278.004882)
			(xy 86.516178 -278.02268) (xy 86.562434 -278.047833) (xy 86.604308 -278.079752) (xy 86.64082 -278.11769)
			(xy 86.671112 -278.160756) (xy 86.694475 -278.207941) (xy 86.710361 -278.25814) (xy 86.718398 -278.310176)
			(xy 86.718902 -278.336502) (xy 86.718398 -278.362828) (xy 86.718348 -278.363151) (xy 90.718884 -278.363151)
			(xy 90.718884 -278.309853) (xy 90.726827 -278.257149) (xy 90.742537 -278.206219) (xy 90.765663 -278.158198)
			(xy 90.795687 -278.114161) (xy 90.831939 -278.07509) (xy 90.87361 -278.041859) (xy 90.919768 -278.01521)
			(xy 90.969382 -277.995738) (xy 91.021344 -277.983878) (xy 91.074494 -277.979895) (xy 91.127644 -277.983878)
			(xy 91.179606 -277.995738) (xy 91.22922 -278.01521) (xy 91.275378 -278.041859) (xy 91.317049 -278.07509)
			(xy 91.353301 -278.114161) (xy 91.383325 -278.158198) (xy 91.406451 -278.206219) (xy 91.422161 -278.257149)
			(xy 91.430104 -278.309853) (xy 91.430602 -278.336502) (xy 91.430122 -278.36221) (xy 91.6879 -278.36221)
			(xy 91.6879 -278.310794) (xy 91.695943 -278.260012) (xy 91.711831 -278.211113) (xy 91.735174 -278.165301)
			(xy 91.765395 -278.123705) (xy 91.801751 -278.087349) (xy 91.843347 -278.057128) (xy 91.889159 -278.033785)
			(xy 91.938058 -278.017897) (xy 91.98884 -278.009854) (xy 92.040256 -278.009854) (xy 92.091038 -278.017897)
			(xy 92.139937 -278.033785) (xy 92.185749 -278.057128) (xy 92.227345 -278.087349) (xy 92.263701 -278.123705)
			(xy 92.293922 -278.165301) (xy 92.317265 -278.211113) (xy 92.333153 -278.260012) (xy 92.341196 -278.310794)
			(xy 92.3417 -278.336502) (xy 92.341196 -278.36221) (xy 92.341047 -278.363151) (xy 92.598738 -278.363151)
			(xy 92.598738 -278.309853) (xy 92.606681 -278.257149) (xy 92.622391 -278.206219) (xy 92.645517 -278.158198)
			(xy 92.675541 -278.114161) (xy 92.711793 -278.07509) (xy 92.753464 -278.041859) (xy 92.799622 -278.01521)
			(xy 92.849236 -277.995738) (xy 92.901198 -277.983878) (xy 92.954348 -277.979895) (xy 93.007498 -277.983878)
			(xy 93.05946 -277.995738) (xy 93.109074 -278.01521) (xy 93.155232 -278.041859) (xy 93.196903 -278.07509)
			(xy 93.233155 -278.114161) (xy 93.263179 -278.158198) (xy 93.286305 -278.206219) (xy 93.302015 -278.257149)
			(xy 93.309958 -278.309853) (xy 93.310456 -278.336502) (xy 93.309976 -278.36221) (xy 93.5675 -278.36221)
			(xy 93.5675 -278.310794) (xy 93.575543 -278.260012) (xy 93.591431 -278.211113) (xy 93.614774 -278.165301)
			(xy 93.644995 -278.123705) (xy 93.681351 -278.087349) (xy 93.722947 -278.057128) (xy 93.768759 -278.033785)
			(xy 93.817658 -278.017897) (xy 93.86844 -278.009854) (xy 93.919856 -278.009854) (xy 93.970638 -278.017897)
			(xy 94.019537 -278.033785) (xy 94.065349 -278.057128) (xy 94.106945 -278.087349) (xy 94.143301 -278.123705)
			(xy 94.173522 -278.165301) (xy 94.196865 -278.211113) (xy 94.212753 -278.260012) (xy 94.220796 -278.310794)
			(xy 94.2213 -278.336502) (xy 94.220796 -278.36221) (xy 94.220647 -278.363151) (xy 94.478338 -278.363151)
			(xy 94.478338 -278.309853) (xy 94.486281 -278.257149) (xy 94.501991 -278.206219) (xy 94.525117 -278.158198)
			(xy 94.555141 -278.114161) (xy 94.591393 -278.07509) (xy 94.633064 -278.041859) (xy 94.679222 -278.01521)
			(xy 94.728836 -277.995738) (xy 94.780798 -277.983878) (xy 94.833948 -277.979895) (xy 94.887098 -277.983878)
			(xy 94.93906 -277.995738) (xy 94.988674 -278.01521) (xy 95.034832 -278.041859) (xy 95.076503 -278.07509)
			(xy 95.112755 -278.114161) (xy 95.142779 -278.158198) (xy 95.165905 -278.206219) (xy 95.181615 -278.257149)
			(xy 95.189558 -278.309853) (xy 95.190056 -278.336502) (xy 95.189558 -278.363151) (xy 97.297738 -278.363151)
			(xy 97.297738 -278.309853) (xy 97.305681 -278.257149) (xy 97.321391 -278.206219) (xy 97.344517 -278.158198)
			(xy 97.374541 -278.114161) (xy 97.410793 -278.07509) (xy 97.452464 -278.041859) (xy 97.498622 -278.01521)
			(xy 97.548236 -277.995738) (xy 97.600198 -277.983878) (xy 97.653348 -277.979895) (xy 97.706498 -277.983878)
			(xy 97.75846 -277.995738) (xy 97.808074 -278.01521) (xy 97.854232 -278.041859) (xy 97.895903 -278.07509)
			(xy 97.932155 -278.114161) (xy 97.962179 -278.158198) (xy 97.985305 -278.206219) (xy 98.001015 -278.257149)
			(xy 98.008958 -278.309853) (xy 98.009456 -278.336502) (xy 98.008976 -278.36221) (xy 98.2665 -278.36221)
			(xy 98.2665 -278.310794) (xy 98.274543 -278.260012) (xy 98.290431 -278.211113) (xy 98.313774 -278.165301)
			(xy 98.343995 -278.123705) (xy 98.380351 -278.087349) (xy 98.421947 -278.057128) (xy 98.467759 -278.033785)
			(xy 98.516658 -278.017897) (xy 98.56744 -278.009854) (xy 98.618856 -278.009854) (xy 98.669638 -278.017897)
			(xy 98.718537 -278.033785) (xy 98.764349 -278.057128) (xy 98.805945 -278.087349) (xy 98.842301 -278.123705)
			(xy 98.872522 -278.165301) (xy 98.895865 -278.211113) (xy 98.911753 -278.260012) (xy 98.919796 -278.310794)
			(xy 98.9203 -278.336502) (xy 98.919796 -278.36221) (xy 98.919647 -278.363151) (xy 99.177338 -278.363151)
			(xy 99.177338 -278.309853) (xy 99.185281 -278.257149) (xy 99.200991 -278.206219) (xy 99.224117 -278.158198)
			(xy 99.254141 -278.114161) (xy 99.290393 -278.07509) (xy 99.332064 -278.041859) (xy 99.378222 -278.01521)
			(xy 99.427836 -277.995738) (xy 99.479798 -277.983878) (xy 99.532948 -277.979895) (xy 99.586098 -277.983878)
			(xy 99.63806 -277.995738) (xy 99.687674 -278.01521) (xy 99.733832 -278.041859) (xy 99.775503 -278.07509)
			(xy 99.811755 -278.114161) (xy 99.841779 -278.158198) (xy 99.864905 -278.206219) (xy 99.880615 -278.257149)
			(xy 99.888558 -278.309853) (xy 99.889056 -278.336502) (xy 99.888576 -278.36221) (xy 100.1461 -278.36221)
			(xy 100.1461 -278.310794) (xy 100.154143 -278.260012) (xy 100.170031 -278.211113) (xy 100.193374 -278.165301)
			(xy 100.223595 -278.123705) (xy 100.259951 -278.087349) (xy 100.301547 -278.057128) (xy 100.347359 -278.033785)
			(xy 100.396258 -278.017897) (xy 100.44704 -278.009854) (xy 100.498456 -278.009854) (xy 100.549238 -278.017897)
			(xy 100.598137 -278.033785) (xy 100.643949 -278.057128) (xy 100.685545 -278.087349) (xy 100.721901 -278.123705)
			(xy 100.752122 -278.165301) (xy 100.775465 -278.211113) (xy 100.791353 -278.260012) (xy 100.799396 -278.310794)
			(xy 100.7999 -278.336502) (xy 100.799396 -278.36221) (xy 100.799247 -278.363151) (xy 101.056684 -278.363151)
			(xy 101.056684 -278.309853) (xy 101.064627 -278.257149) (xy 101.080337 -278.206219) (xy 101.103463 -278.158198)
			(xy 101.133487 -278.114161) (xy 101.169739 -278.07509) (xy 101.21141 -278.041859) (xy 101.257568 -278.01521)
			(xy 101.307182 -277.995738) (xy 101.359144 -277.983878) (xy 101.412294 -277.979895) (xy 101.465444 -277.983878)
			(xy 101.517406 -277.995738) (xy 101.56702 -278.01521) (xy 101.613178 -278.041859) (xy 101.654849 -278.07509)
			(xy 101.691101 -278.114161) (xy 101.721125 -278.158198) (xy 101.744251 -278.206219) (xy 101.759961 -278.257149)
			(xy 101.767904 -278.309853) (xy 101.768402 -278.336502) (xy 101.767904 -278.363151) (xy 101.996738 -278.363151)
			(xy 101.996738 -278.309853) (xy 102.004681 -278.257149) (xy 102.020391 -278.206219) (xy 102.043517 -278.158198)
			(xy 102.073541 -278.114161) (xy 102.109793 -278.07509) (xy 102.151464 -278.041859) (xy 102.197622 -278.01521)
			(xy 102.247236 -277.995738) (xy 102.299198 -277.983878) (xy 102.352348 -277.979895) (xy 102.405498 -277.983878)
			(xy 102.45746 -277.995738) (xy 102.507074 -278.01521) (xy 102.553232 -278.041859) (xy 102.594903 -278.07509)
			(xy 102.631155 -278.114161) (xy 102.661179 -278.158198) (xy 102.684305 -278.206219) (xy 102.700015 -278.257149)
			(xy 102.707958 -278.309853) (xy 102.708456 -278.336502) (xy 102.707958 -278.363151) (xy 102.700015 -278.415855)
			(xy 102.684305 -278.466785) (xy 102.661179 -278.514806) (xy 102.631155 -278.558843) (xy 102.594903 -278.597914)
			(xy 102.553232 -278.631145) (xy 102.507074 -278.657794) (xy 102.45746 -278.677266) (xy 102.405498 -278.689126)
			(xy 102.352348 -278.69311) (xy 102.299198 -278.689126) (xy 102.247236 -278.677266) (xy 102.197622 -278.657794)
			(xy 102.151464 -278.631145) (xy 102.109793 -278.597914) (xy 102.073541 -278.558843) (xy 102.043517 -278.514806)
			(xy 102.020391 -278.466785) (xy 102.004681 -278.415855) (xy 101.996738 -278.363151) (xy 101.767904 -278.363151)
			(xy 101.759961 -278.415855) (xy 101.744251 -278.466785) (xy 101.721125 -278.514806) (xy 101.691101 -278.558843)
			(xy 101.654849 -278.597914) (xy 101.613178 -278.631145) (xy 101.56702 -278.657794) (xy 101.517406 -278.677266)
			(xy 101.465444 -278.689126) (xy 101.412294 -278.69311) (xy 101.359144 -278.689126) (xy 101.307182 -278.677266)
			(xy 101.257568 -278.657794) (xy 101.21141 -278.631145) (xy 101.169739 -278.597914) (xy 101.133487 -278.558843)
			(xy 101.103463 -278.514806) (xy 101.080337 -278.466785) (xy 101.064627 -278.415855) (xy 101.056684 -278.363151)
			(xy 100.799247 -278.363151) (xy 100.791353 -278.412992) (xy 100.775465 -278.461891) (xy 100.752122 -278.507703)
			(xy 100.721901 -278.549299) (xy 100.685545 -278.585655) (xy 100.643949 -278.615876) (xy 100.598137 -278.639219)
			(xy 100.549238 -278.655107) (xy 100.498456 -278.66315) (xy 100.44704 -278.66315) (xy 100.396258 -278.655107)
			(xy 100.347359 -278.639219) (xy 100.301547 -278.615876) (xy 100.259951 -278.585655) (xy 100.223595 -278.549299)
			(xy 100.193374 -278.507703) (xy 100.170031 -278.461891) (xy 100.154143 -278.412992) (xy 100.1461 -278.36221)
			(xy 99.888576 -278.36221) (xy 99.888558 -278.363151) (xy 99.880615 -278.415855) (xy 99.864905 -278.466785)
			(xy 99.841779 -278.514806) (xy 99.811755 -278.558843) (xy 99.775503 -278.597914) (xy 99.733832 -278.631145)
			(xy 99.687674 -278.657794) (xy 99.63806 -278.677266) (xy 99.586098 -278.689126) (xy 99.532948 -278.69311)
			(xy 99.479798 -278.689126) (xy 99.427836 -278.677266) (xy 99.378222 -278.657794) (xy 99.332064 -278.631145)
			(xy 99.290393 -278.597914) (xy 99.254141 -278.558843) (xy 99.224117 -278.514806) (xy 99.200991 -278.466785)
			(xy 99.185281 -278.415855) (xy 99.177338 -278.363151) (xy 98.919647 -278.363151) (xy 98.911753 -278.412992)
			(xy 98.895865 -278.461891) (xy 98.872522 -278.507703) (xy 98.842301 -278.549299) (xy 98.805945 -278.585655)
			(xy 98.764349 -278.615876) (xy 98.718537 -278.639219) (xy 98.669638 -278.655107) (xy 98.618856 -278.66315)
			(xy 98.56744 -278.66315) (xy 98.516658 -278.655107) (xy 98.467759 -278.639219) (xy 98.421947 -278.615876)
			(xy 98.380351 -278.585655) (xy 98.343995 -278.549299) (xy 98.313774 -278.507703) (xy 98.290431 -278.461891)
			(xy 98.274543 -278.412992) (xy 98.2665 -278.36221) (xy 98.008976 -278.36221) (xy 98.008958 -278.363151)
			(xy 98.001015 -278.415855) (xy 97.985305 -278.466785) (xy 97.962179 -278.514806) (xy 97.932155 -278.558843)
			(xy 97.895903 -278.597914) (xy 97.854232 -278.631145) (xy 97.808074 -278.657794) (xy 97.75846 -278.677266)
			(xy 97.706498 -278.689126) (xy 97.653348 -278.69311) (xy 97.600198 -278.689126) (xy 97.548236 -278.677266)
			(xy 97.498622 -278.657794) (xy 97.452464 -278.631145) (xy 97.410793 -278.597914) (xy 97.374541 -278.558843)
			(xy 97.344517 -278.514806) (xy 97.321391 -278.466785) (xy 97.305681 -278.415855) (xy 97.297738 -278.363151)
			(xy 95.189558 -278.363151) (xy 95.181615 -278.415855) (xy 95.165905 -278.466785) (xy 95.142779 -278.514806)
			(xy 95.112755 -278.558843) (xy 95.076503 -278.597914) (xy 95.034832 -278.631145) (xy 94.988674 -278.657794)
			(xy 94.93906 -278.677266) (xy 94.887098 -278.689126) (xy 94.833948 -278.69311) (xy 94.780798 -278.689126)
			(xy 94.728836 -278.677266) (xy 94.679222 -278.657794) (xy 94.633064 -278.631145) (xy 94.591393 -278.597914)
			(xy 94.555141 -278.558843) (xy 94.525117 -278.514806) (xy 94.501991 -278.466785) (xy 94.486281 -278.415855)
			(xy 94.478338 -278.363151) (xy 94.220647 -278.363151) (xy 94.212753 -278.412992) (xy 94.196865 -278.461891)
			(xy 94.173522 -278.507703) (xy 94.143301 -278.549299) (xy 94.106945 -278.585655) (xy 94.065349 -278.615876)
			(xy 94.019537 -278.639219) (xy 93.970638 -278.655107) (xy 93.919856 -278.66315) (xy 93.86844 -278.66315)
			(xy 93.817658 -278.655107) (xy 93.768759 -278.639219) (xy 93.722947 -278.615876) (xy 93.681351 -278.585655)
			(xy 93.644995 -278.549299) (xy 93.614774 -278.507703) (xy 93.591431 -278.461891) (xy 93.575543 -278.412992)
			(xy 93.5675 -278.36221) (xy 93.309976 -278.36221) (xy 93.309958 -278.363151) (xy 93.302015 -278.415855)
			(xy 93.286305 -278.466785) (xy 93.263179 -278.514806) (xy 93.233155 -278.558843) (xy 93.196903 -278.597914)
			(xy 93.155232 -278.631145) (xy 93.109074 -278.657794) (xy 93.05946 -278.677266) (xy 93.007498 -278.689126)
			(xy 92.954348 -278.69311) (xy 92.901198 -278.689126) (xy 92.849236 -278.677266) (xy 92.799622 -278.657794)
			(xy 92.753464 -278.631145) (xy 92.711793 -278.597914) (xy 92.675541 -278.558843) (xy 92.645517 -278.514806)
			(xy 92.622391 -278.466785) (xy 92.606681 -278.415855) (xy 92.598738 -278.363151) (xy 92.341047 -278.363151)
			(xy 92.333153 -278.412992) (xy 92.317265 -278.461891) (xy 92.293922 -278.507703) (xy 92.263701 -278.549299)
			(xy 92.227345 -278.585655) (xy 92.185749 -278.615876) (xy 92.139937 -278.639219) (xy 92.091038 -278.655107)
			(xy 92.040256 -278.66315) (xy 91.98884 -278.66315) (xy 91.938058 -278.655107) (xy 91.889159 -278.639219)
			(xy 91.843347 -278.615876) (xy 91.801751 -278.585655) (xy 91.765395 -278.549299) (xy 91.735174 -278.507703)
			(xy 91.711831 -278.461891) (xy 91.695943 -278.412992) (xy 91.6879 -278.36221) (xy 91.430122 -278.36221)
			(xy 91.430104 -278.363151) (xy 91.422161 -278.415855) (xy 91.406451 -278.466785) (xy 91.383325 -278.514806)
			(xy 91.353301 -278.558843) (xy 91.317049 -278.597914) (xy 91.275378 -278.631145) (xy 91.22922 -278.657794)
			(xy 91.179606 -278.677266) (xy 91.127644 -278.689126) (xy 91.074494 -278.69311) (xy 91.021344 -278.689126)
			(xy 90.969382 -278.677266) (xy 90.919768 -278.657794) (xy 90.87361 -278.631145) (xy 90.831939 -278.597914)
			(xy 90.795687 -278.558843) (xy 90.765663 -278.514806) (xy 90.742537 -278.466785) (xy 90.726827 -278.415855)
			(xy 90.718884 -278.363151) (xy 86.718348 -278.363151) (xy 86.710361 -278.414864) (xy 86.694475 -278.465063)
			(xy 86.671112 -278.512248) (xy 86.64082 -278.555314) (xy 86.604308 -278.593252) (xy 86.562434 -278.625171)
			(xy 86.516178 -278.650324) (xy 86.466625 -278.668122) (xy 86.414935 -278.678146) (xy 86.362321 -278.680163)
			(xy 86.310016 -278.674125) (xy 86.259245 -278.660173) (xy 86.2112 -278.638634) (xy 86.167005 -278.610014)
			(xy 86.127697 -278.574983) (xy 86.094197 -278.534362) (xy 86.067291 -278.489103) (xy 86.047608 -278.440268)
			(xy 86.035611 -278.389) (xy 86.031581 -278.336502) (xy 84.734146 -278.336502) (xy 84.734146 -278.40686)
			(xy 84.734593 -278.420511) (xy 84.741841 -278.446834) (xy 84.755804 -278.470295) (xy 84.775484 -278.48922)
			(xy 84.799475 -278.502254) (xy 84.826061 -278.508467) (xy 84.853343 -278.507414) (xy 84.879372 -278.499171)
			(xy 84.902286 -278.484327) (xy 84.911692 -278.474424) (xy 84.928647 -278.456035) (xy 84.966823 -278.42372)
			(xy 85.009148 -278.397068) (xy 85.054788 -278.376605) (xy 85.102843 -278.362734) (xy 85.152367 -278.355727)
			(xy 85.177376 -278.355298) (xy 85.204028 -278.355769) (xy 85.256737 -278.363711) (xy 85.307673 -278.37942)
			(xy 85.355699 -278.402545) (xy 85.399742 -278.43257) (xy 85.438818 -278.468824) (xy 85.472053 -278.510498)
			(xy 85.498706 -278.55666) (xy 85.518181 -278.606278) (xy 85.530042 -278.658245) (xy 85.534026 -278.7114)
			(xy 85.530042 -278.764555) (xy 85.518181 -278.816522) (xy 85.498706 -278.86614) (xy 85.472053 -278.912302)
			(xy 85.438818 -278.953976) (xy 85.399742 -278.99023) (xy 85.355699 -279.020255) (xy 85.307673 -279.04338)
			(xy 85.256737 -279.059089) (xy 85.204028 -279.067031) (xy 85.177376 -279.067514) (xy 85.152368 -279.067088)
			(xy 85.102845 -279.06008) (xy 85.054791 -279.046206) (xy 85.009154 -279.025739) (xy 84.966833 -278.999083)
			(xy 84.928662 -278.966762) (xy 84.911692 -278.948388) (xy 84.90229 -278.938481) (xy 84.879384 -278.923623)
			(xy 84.853358 -278.915369) (xy 84.826076 -278.914312) (xy 84.79949 -278.920526) (xy 84.775502 -278.933566)
			(xy 84.755831 -278.952499) (xy 84.741883 -278.975971) (xy 84.734658 -279.0023) (xy 84.734146 -279.015952)
			(xy 84.734146 -279.176967) (xy 88.369384 -279.176967) (xy 88.369384 -279.123669) (xy 88.377327 -279.070965)
			(xy 88.393037 -279.020035) (xy 88.416163 -278.972014) (xy 88.446187 -278.927977) (xy 88.482439 -278.888906)
			(xy 88.52411 -278.855675) (xy 88.570268 -278.829026) (xy 88.619882 -278.809554) (xy 88.671844 -278.797694)
			(xy 88.724994 -278.793711) (xy 88.778144 -278.797694) (xy 88.830106 -278.809554) (xy 88.87972 -278.829026)
			(xy 88.925878 -278.855675) (xy 88.967549 -278.888906) (xy 89.003801 -278.927977) (xy 89.033825 -278.972014)
			(xy 89.056951 -279.020035) (xy 89.072661 -279.070965) (xy 89.080604 -279.123669) (xy 89.081102 -279.150318)
			(xy 89.080604 -279.176967) (xy 89.309184 -279.176967) (xy 89.309184 -279.123669) (xy 89.317127 -279.070965)
			(xy 89.332837 -279.020035) (xy 89.355963 -278.972014) (xy 89.385987 -278.927977) (xy 89.422239 -278.888906)
			(xy 89.46391 -278.855675) (xy 89.510068 -278.829026) (xy 89.559682 -278.809554) (xy 89.611644 -278.797694)
			(xy 89.664794 -278.793711) (xy 89.717944 -278.797694) (xy 89.769906 -278.809554) (xy 89.81952 -278.829026)
			(xy 89.865678 -278.855675) (xy 89.907349 -278.888906) (xy 89.943601 -278.927977) (xy 89.973625 -278.972014)
			(xy 89.996751 -279.020035) (xy 90.012461 -279.070965) (xy 90.020404 -279.123669) (xy 90.020902 -279.150318)
			(xy 90.020404 -279.176967) (xy 90.248984 -279.176967) (xy 90.248984 -279.123669) (xy 90.256927 -279.070965)
			(xy 90.272637 -279.020035) (xy 90.295763 -278.972014) (xy 90.325787 -278.927977) (xy 90.362039 -278.888906)
			(xy 90.40371 -278.855675) (xy 90.449868 -278.829026) (xy 90.499482 -278.809554) (xy 90.551444 -278.797694)
			(xy 90.604594 -278.793711) (xy 90.657744 -278.797694) (xy 90.709706 -278.809554) (xy 90.75932 -278.829026)
			(xy 90.805478 -278.855675) (xy 90.847149 -278.888906) (xy 90.883401 -278.927977) (xy 90.913425 -278.972014)
			(xy 90.936551 -279.020035) (xy 90.952261 -279.070965) (xy 90.960204 -279.123669) (xy 90.960702 -279.150318)
			(xy 90.960204 -279.176967) (xy 91.188784 -279.176967) (xy 91.188784 -279.123669) (xy 91.196727 -279.070965)
			(xy 91.212437 -279.020035) (xy 91.235563 -278.972014) (xy 91.265587 -278.927977) (xy 91.301839 -278.888906)
			(xy 91.34351 -278.855675) (xy 91.389668 -278.829026) (xy 91.439282 -278.809554) (xy 91.491244 -278.797694)
			(xy 91.544394 -278.793711) (xy 91.597544 -278.797694) (xy 91.649506 -278.809554) (xy 91.69912 -278.829026)
			(xy 91.745278 -278.855675) (xy 91.786949 -278.888906) (xy 91.823201 -278.927977) (xy 91.853225 -278.972014)
			(xy 91.876351 -279.020035) (xy 91.892061 -279.070965) (xy 91.900004 -279.123669) (xy 91.900502 -279.150318)
			(xy 91.900022 -279.176026) (xy 92.157546 -279.176026) (xy 92.157546 -279.12461) (xy 92.165589 -279.073828)
			(xy 92.181477 -279.024929) (xy 92.20482 -278.979117) (xy 92.235041 -278.937521) (xy 92.271397 -278.901165)
			(xy 92.312993 -278.870944) (xy 92.358805 -278.847601) (xy 92.407704 -278.831713) (xy 92.458486 -278.82367)
			(xy 92.509902 -278.82367) (xy 92.560684 -278.831713) (xy 92.609583 -278.847601) (xy 92.655395 -278.870944)
			(xy 92.696991 -278.901165) (xy 92.733347 -278.937521) (xy 92.763568 -278.979117) (xy 92.786911 -279.024929)
			(xy 92.802799 -279.073828) (xy 92.810842 -279.12461) (xy 92.811346 -279.150318) (xy 92.810842 -279.176026)
			(xy 93.097346 -279.176026) (xy 93.097346 -279.12461) (xy 93.105389 -279.073828) (xy 93.121277 -279.024929)
			(xy 93.14462 -278.979117) (xy 93.174841 -278.937521) (xy 93.211197 -278.901165) (xy 93.252793 -278.870944)
			(xy 93.298605 -278.847601) (xy 93.347504 -278.831713) (xy 93.398286 -278.82367) (xy 93.449702 -278.82367)
			(xy 93.500484 -278.831713) (xy 93.549383 -278.847601) (xy 93.595195 -278.870944) (xy 93.636791 -278.901165)
			(xy 93.673147 -278.937521) (xy 93.703368 -278.979117) (xy 93.726711 -279.024929) (xy 93.742599 -279.073828)
			(xy 93.750642 -279.12461) (xy 93.751146 -279.150318) (xy 93.750642 -279.176026) (xy 93.750493 -279.176967)
			(xy 94.008438 -279.176967) (xy 94.008438 -279.123669) (xy 94.016381 -279.070965) (xy 94.032091 -279.020035)
			(xy 94.055217 -278.972014) (xy 94.085241 -278.927977) (xy 94.121493 -278.888906) (xy 94.163164 -278.855675)
			(xy 94.209322 -278.829026) (xy 94.258936 -278.809554) (xy 94.310898 -278.797694) (xy 94.364048 -278.793711)
			(xy 94.417198 -278.797694) (xy 94.46916 -278.809554) (xy 94.518774 -278.829026) (xy 94.564932 -278.855675)
			(xy 94.606603 -278.888906) (xy 94.642855 -278.927977) (xy 94.672879 -278.972014) (xy 94.696005 -279.020035)
			(xy 94.711715 -279.070965) (xy 94.719658 -279.123669) (xy 94.720156 -279.150318) (xy 94.719658 -279.176967)
			(xy 94.947984 -279.176967) (xy 94.947984 -279.123669) (xy 94.955927 -279.070965) (xy 94.971637 -279.020035)
			(xy 94.994763 -278.972014) (xy 95.024787 -278.927977) (xy 95.061039 -278.888906) (xy 95.10271 -278.855675)
			(xy 95.148868 -278.829026) (xy 95.198482 -278.809554) (xy 95.250444 -278.797694) (xy 95.303594 -278.793711)
			(xy 95.356744 -278.797694) (xy 95.408706 -278.809554) (xy 95.45832 -278.829026) (xy 95.504478 -278.855675)
			(xy 95.546149 -278.888906) (xy 95.582401 -278.927977) (xy 95.612425 -278.972014) (xy 95.635551 -279.020035)
			(xy 95.651261 -279.070965) (xy 95.659204 -279.123669) (xy 95.659702 -279.150318) (xy 95.659204 -279.176967)
			(xy 95.887784 -279.176967) (xy 95.887784 -279.123669) (xy 95.895727 -279.070965) (xy 95.911437 -279.020035)
			(xy 95.934563 -278.972014) (xy 95.964587 -278.927977) (xy 96.000839 -278.888906) (xy 96.04251 -278.855675)
			(xy 96.088668 -278.829026) (xy 96.138282 -278.809554) (xy 96.190244 -278.797694) (xy 96.243394 -278.793711)
			(xy 96.296544 -278.797694) (xy 96.348506 -278.809554) (xy 96.39812 -278.829026) (xy 96.444278 -278.855675)
			(xy 96.485949 -278.888906) (xy 96.522201 -278.927977) (xy 96.552225 -278.972014) (xy 96.575351 -279.020035)
			(xy 96.591061 -279.070965) (xy 96.599004 -279.123669) (xy 96.599502 -279.150318) (xy 96.599004 -279.176967)
			(xy 97.767638 -279.176967) (xy 97.767638 -279.123669) (xy 97.775581 -279.070965) (xy 97.791291 -279.020035)
			(xy 97.814417 -278.972014) (xy 97.844441 -278.927977) (xy 97.880693 -278.888906) (xy 97.922364 -278.855675)
			(xy 97.968522 -278.829026) (xy 98.018136 -278.809554) (xy 98.070098 -278.797694) (xy 98.123248 -278.793711)
			(xy 98.176398 -278.797694) (xy 98.22836 -278.809554) (xy 98.277974 -278.829026) (xy 98.324132 -278.855675)
			(xy 98.365803 -278.888906) (xy 98.402055 -278.927977) (xy 98.432079 -278.972014) (xy 98.455205 -279.020035)
			(xy 98.470915 -279.070965) (xy 98.478858 -279.123669) (xy 98.479356 -279.150318) (xy 98.478876 -279.176026)
			(xy 98.736146 -279.176026) (xy 98.736146 -279.12461) (xy 98.744189 -279.073828) (xy 98.760077 -279.024929)
			(xy 98.78342 -278.979117) (xy 98.813641 -278.937521) (xy 98.849997 -278.901165) (xy 98.891593 -278.870944)
			(xy 98.937405 -278.847601) (xy 98.986304 -278.831713) (xy 99.037086 -278.82367) (xy 99.088502 -278.82367)
			(xy 99.139284 -278.831713) (xy 99.188183 -278.847601) (xy 99.233995 -278.870944) (xy 99.275591 -278.901165)
			(xy 99.311947 -278.937521) (xy 99.342168 -278.979117) (xy 99.365511 -279.024929) (xy 99.381399 -279.073828)
			(xy 99.389442 -279.12461) (xy 99.389946 -279.150318) (xy 99.389442 -279.176026) (xy 99.675946 -279.176026)
			(xy 99.675946 -279.12461) (xy 99.683989 -279.073828) (xy 99.699877 -279.024929) (xy 99.72322 -278.979117)
			(xy 99.753441 -278.937521) (xy 99.789797 -278.901165) (xy 99.831393 -278.870944) (xy 99.877205 -278.847601)
			(xy 99.926104 -278.831713) (xy 99.976886 -278.82367) (xy 100.028302 -278.82367) (xy 100.079084 -278.831713)
			(xy 100.127983 -278.847601) (xy 100.173795 -278.870944) (xy 100.215391 -278.901165) (xy 100.251747 -278.937521)
			(xy 100.281968 -278.979117) (xy 100.305311 -279.024929) (xy 100.321199 -279.073828) (xy 100.329242 -279.12461)
			(xy 100.329746 -279.150318) (xy 100.329242 -279.176026) (xy 100.329093 -279.176967) (xy 100.587038 -279.176967)
			(xy 100.587038 -279.123669) (xy 100.594981 -279.070965) (xy 100.610691 -279.020035) (xy 100.633817 -278.972014)
			(xy 100.663841 -278.927977) (xy 100.700093 -278.888906) (xy 100.741764 -278.855675) (xy 100.787922 -278.829026)
			(xy 100.837536 -278.809554) (xy 100.889498 -278.797694) (xy 100.942648 -278.793711) (xy 100.995798 -278.797694)
			(xy 101.04776 -278.809554) (xy 101.097374 -278.829026) (xy 101.143532 -278.855675) (xy 101.185203 -278.888906)
			(xy 101.221455 -278.927977) (xy 101.251479 -278.972014) (xy 101.274605 -279.020035) (xy 101.290315 -279.070965)
			(xy 101.298258 -279.123669) (xy 101.298756 -279.150318) (xy 101.552756 -279.150318) (xy 101.553264 -279.124431)
			(xy 101.561363 -279.073293) (xy 101.577362 -279.024053) (xy 101.600868 -278.977921) (xy 101.6313 -278.936034)
			(xy 101.66791 -278.899424) (xy 101.709797 -278.868992) (xy 101.755929 -278.845486) (xy 101.805169 -278.829487)
			(xy 101.856307 -278.821388) (xy 101.908081 -278.821388) (xy 101.959219 -278.829487) (xy 102.008459 -278.845486)
			(xy 102.054591 -278.868992) (xy 102.096478 -278.899424) (xy 102.133088 -278.936034) (xy 102.16352 -278.977921)
			(xy 102.187026 -279.024053) (xy 102.203025 -279.073293) (xy 102.211124 -279.124431) (xy 102.211632 -279.150318)
			(xy 102.211076 -279.177962) (xy 102.201888 -279.23248) (xy 102.193344 -279.258776) (xy 102.185724 -279.28062)
			(xy 102.390956 -279.635966) (xy 102.413816 -279.640284) (xy 102.438629 -279.645487) (xy 102.486407 -279.662435)
			(xy 102.531027 -279.686501) (xy 102.571434 -279.717117) (xy 102.606676 -279.753559) (xy 102.635921 -279.794969)
			(xy 102.658479 -279.840369) (xy 102.673819 -279.888688) (xy 102.681577 -279.938786) (xy 102.68204 -279.964134)
			(xy 102.681532 -279.990041) (xy 102.673426 -280.041218) (xy 102.657414 -280.090497) (xy 102.633891 -280.136664)
			(xy 102.603435 -280.178583) (xy 102.566797 -280.215221) (xy 102.524878 -280.245677) (xy 102.478711 -280.2692)
			(xy 102.429432 -280.285212) (xy 102.378255 -280.293318) (xy 102.326441 -280.293318) (xy 102.275264 -280.285212)
			(xy 102.225985 -280.2692) (xy 102.179818 -280.245677) (xy 102.137899 -280.215221) (xy 102.101261 -280.178583)
			(xy 102.070805 -280.136664) (xy 102.047282 -280.090497) (xy 102.03127 -280.041218) (xy 102.023164 -279.990041)
			(xy 102.022656 -279.964134) (xy 102.023255 -279.936417) (xy 102.032575 -279.88177) (xy 102.041198 -279.855422)
			(xy 102.049072 -279.833324) (xy 101.844094 -279.478486) (xy 101.821234 -279.474168) (xy 101.796412 -279.468959)
			(xy 101.748608 -279.452029) (xy 101.70396 -279.427978) (xy 101.663522 -279.397372) (xy 101.628249 -279.360934)
			(xy 101.598973 -279.319523) (xy 101.576384 -279.274117) (xy 101.561016 -279.225788) (xy 101.553231 -279.175675)
			(xy 101.552756 -279.150318) (xy 101.298756 -279.150318) (xy 101.298258 -279.176967) (xy 101.290315 -279.229671)
			(xy 101.274605 -279.280601) (xy 101.251479 -279.328622) (xy 101.221455 -279.372659) (xy 101.185203 -279.41173)
			(xy 101.143532 -279.444961) (xy 101.097374 -279.47161) (xy 101.04776 -279.491082) (xy 100.995798 -279.502942)
			(xy 100.942648 -279.506926) (xy 100.889498 -279.502942) (xy 100.837536 -279.491082) (xy 100.787922 -279.47161)
			(xy 100.741764 -279.444961) (xy 100.700093 -279.41173) (xy 100.663841 -279.372659) (xy 100.633817 -279.328622)
			(xy 100.610691 -279.280601) (xy 100.594981 -279.229671) (xy 100.587038 -279.176967) (xy 100.329093 -279.176967)
			(xy 100.321199 -279.226808) (xy 100.305311 -279.275707) (xy 100.281968 -279.321519) (xy 100.251747 -279.363115)
			(xy 100.215391 -279.399471) (xy 100.173795 -279.429692) (xy 100.127983 -279.453035) (xy 100.079084 -279.468923)
			(xy 100.028302 -279.476966) (xy 99.976886 -279.476966) (xy 99.926104 -279.468923) (xy 99.877205 -279.453035)
			(xy 99.831393 -279.429692) (xy 99.789797 -279.399471) (xy 99.753441 -279.363115) (xy 99.72322 -279.321519)
			(xy 99.699877 -279.275707) (xy 99.683989 -279.226808) (xy 99.675946 -279.176026) (xy 99.389442 -279.176026)
			(xy 99.381399 -279.226808) (xy 99.365511 -279.275707) (xy 99.342168 -279.321519) (xy 99.311947 -279.363115)
			(xy 99.275591 -279.399471) (xy 99.233995 -279.429692) (xy 99.188183 -279.453035) (xy 99.139284 -279.468923)
			(xy 99.088502 -279.476966) (xy 99.037086 -279.476966) (xy 98.986304 -279.468923) (xy 98.937405 -279.453035)
			(xy 98.891593 -279.429692) (xy 98.849997 -279.399471) (xy 98.813641 -279.363115) (xy 98.78342 -279.321519)
			(xy 98.760077 -279.275707) (xy 98.744189 -279.226808) (xy 98.736146 -279.176026) (xy 98.478876 -279.176026)
			(xy 98.478858 -279.176967) (xy 98.470915 -279.229671) (xy 98.455205 -279.280601) (xy 98.432079 -279.328622)
			(xy 98.402055 -279.372659) (xy 98.365803 -279.41173) (xy 98.324132 -279.444961) (xy 98.277974 -279.47161)
			(xy 98.22836 -279.491082) (xy 98.176398 -279.502942) (xy 98.123248 -279.506926) (xy 98.070098 -279.502942)
			(xy 98.018136 -279.491082) (xy 97.968522 -279.47161) (xy 97.922364 -279.444961) (xy 97.880693 -279.41173)
			(xy 97.844441 -279.372659) (xy 97.814417 -279.328622) (xy 97.791291 -279.280601) (xy 97.775581 -279.229671)
			(xy 97.767638 -279.176967) (xy 96.599004 -279.176967) (xy 96.591061 -279.229671) (xy 96.575351 -279.280601)
			(xy 96.552225 -279.328622) (xy 96.522201 -279.372659) (xy 96.485949 -279.41173) (xy 96.444278 -279.444961)
			(xy 96.39812 -279.47161) (xy 96.348506 -279.491082) (xy 96.296544 -279.502942) (xy 96.243394 -279.506926)
			(xy 96.190244 -279.502942) (xy 96.138282 -279.491082) (xy 96.088668 -279.47161) (xy 96.04251 -279.444961)
			(xy 96.000839 -279.41173) (xy 95.964587 -279.372659) (xy 95.934563 -279.328622) (xy 95.911437 -279.280601)
			(xy 95.895727 -279.229671) (xy 95.887784 -279.176967) (xy 95.659204 -279.176967) (xy 95.651261 -279.229671)
			(xy 95.635551 -279.280601) (xy 95.612425 -279.328622) (xy 95.582401 -279.372659) (xy 95.546149 -279.41173)
			(xy 95.504478 -279.444961) (xy 95.45832 -279.47161) (xy 95.408706 -279.491082) (xy 95.356744 -279.502942)
			(xy 95.303594 -279.506926) (xy 95.250444 -279.502942) (xy 95.198482 -279.491082) (xy 95.148868 -279.47161)
			(xy 95.10271 -279.444961) (xy 95.061039 -279.41173) (xy 95.024787 -279.372659) (xy 94.994763 -279.328622)
			(xy 94.971637 -279.280601) (xy 94.955927 -279.229671) (xy 94.947984 -279.176967) (xy 94.719658 -279.176967)
			(xy 94.711715 -279.229671) (xy 94.696005 -279.280601) (xy 94.672879 -279.328622) (xy 94.642855 -279.372659)
			(xy 94.606603 -279.41173) (xy 94.564932 -279.444961) (xy 94.518774 -279.47161) (xy 94.46916 -279.491082)
			(xy 94.417198 -279.502942) (xy 94.364048 -279.506926) (xy 94.310898 -279.502942) (xy 94.258936 -279.491082)
			(xy 94.209322 -279.47161) (xy 94.163164 -279.444961) (xy 94.121493 -279.41173) (xy 94.085241 -279.372659)
			(xy 94.055217 -279.328622) (xy 94.032091 -279.280601) (xy 94.016381 -279.229671) (xy 94.008438 -279.176967)
			(xy 93.750493 -279.176967) (xy 93.742599 -279.226808) (xy 93.726711 -279.275707) (xy 93.703368 -279.321519)
			(xy 93.673147 -279.363115) (xy 93.636791 -279.399471) (xy 93.595195 -279.429692) (xy 93.549383 -279.453035)
			(xy 93.500484 -279.468923) (xy 93.449702 -279.476966) (xy 93.398286 -279.476966) (xy 93.347504 -279.468923)
			(xy 93.298605 -279.453035) (xy 93.252793 -279.429692) (xy 93.211197 -279.399471) (xy 93.174841 -279.363115)
			(xy 93.14462 -279.321519) (xy 93.121277 -279.275707) (xy 93.105389 -279.226808) (xy 93.097346 -279.176026)
			(xy 92.810842 -279.176026) (xy 92.802799 -279.226808) (xy 92.786911 -279.275707) (xy 92.763568 -279.321519)
			(xy 92.733347 -279.363115) (xy 92.696991 -279.399471) (xy 92.655395 -279.429692) (xy 92.609583 -279.453035)
			(xy 92.560684 -279.468923) (xy 92.509902 -279.476966) (xy 92.458486 -279.476966) (xy 92.407704 -279.468923)
			(xy 92.358805 -279.453035) (xy 92.312993 -279.429692) (xy 92.271397 -279.399471) (xy 92.235041 -279.363115)
			(xy 92.20482 -279.321519) (xy 92.181477 -279.275707) (xy 92.165589 -279.226808) (xy 92.157546 -279.176026)
			(xy 91.900022 -279.176026) (xy 91.900004 -279.176967) (xy 91.892061 -279.229671) (xy 91.876351 -279.280601)
			(xy 91.853225 -279.328622) (xy 91.823201 -279.372659) (xy 91.786949 -279.41173) (xy 91.745278 -279.444961)
			(xy 91.69912 -279.47161) (xy 91.649506 -279.491082) (xy 91.597544 -279.502942) (xy 91.544394 -279.506926)
			(xy 91.491244 -279.502942) (xy 91.439282 -279.491082) (xy 91.389668 -279.47161) (xy 91.34351 -279.444961)
			(xy 91.301839 -279.41173) (xy 91.265587 -279.372659) (xy 91.235563 -279.328622) (xy 91.212437 -279.280601)
			(xy 91.196727 -279.229671) (xy 91.188784 -279.176967) (xy 90.960204 -279.176967) (xy 90.952261 -279.229671)
			(xy 90.936551 -279.280601) (xy 90.913425 -279.328622) (xy 90.883401 -279.372659) (xy 90.847149 -279.41173)
			(xy 90.805478 -279.444961) (xy 90.75932 -279.47161) (xy 90.709706 -279.491082) (xy 90.657744 -279.502942)
			(xy 90.604594 -279.506926) (xy 90.551444 -279.502942) (xy 90.499482 -279.491082) (xy 90.449868 -279.47161)
			(xy 90.40371 -279.444961) (xy 90.362039 -279.41173) (xy 90.325787 -279.372659) (xy 90.295763 -279.328622)
			(xy 90.272637 -279.280601) (xy 90.256927 -279.229671) (xy 90.248984 -279.176967) (xy 90.020404 -279.176967)
			(xy 90.012461 -279.229671) (xy 89.996751 -279.280601) (xy 89.973625 -279.328622) (xy 89.943601 -279.372659)
			(xy 89.907349 -279.41173) (xy 89.865678 -279.444961) (xy 89.81952 -279.47161) (xy 89.769906 -279.491082)
			(xy 89.717944 -279.502942) (xy 89.664794 -279.506926) (xy 89.611644 -279.502942) (xy 89.559682 -279.491082)
			(xy 89.510068 -279.47161) (xy 89.46391 -279.444961) (xy 89.422239 -279.41173) (xy 89.385987 -279.372659)
			(xy 89.355963 -279.328622) (xy 89.332837 -279.280601) (xy 89.317127 -279.229671) (xy 89.309184 -279.176967)
			(xy 89.080604 -279.176967) (xy 89.072661 -279.229671) (xy 89.056951 -279.280601) (xy 89.033825 -279.328622)
			(xy 89.003801 -279.372659) (xy 88.967549 -279.41173) (xy 88.925878 -279.444961) (xy 88.87972 -279.47161)
			(xy 88.830106 -279.491082) (xy 88.778144 -279.502942) (xy 88.724994 -279.506926) (xy 88.671844 -279.502942)
			(xy 88.619882 -279.491082) (xy 88.570268 -279.47161) (xy 88.52411 -279.444961) (xy 88.482439 -279.41173)
			(xy 88.446187 -279.372659) (xy 88.416163 -279.328622) (xy 88.393037 -279.280601) (xy 88.377327 -279.229671)
			(xy 88.369384 -279.176967) (xy 84.734146 -279.176967) (xy 84.734146 -279.990783) (xy 86.019884 -279.990783)
			(xy 86.019884 -279.937485) (xy 86.027827 -279.884781) (xy 86.043537 -279.833851) (xy 86.066663 -279.78583)
			(xy 86.096687 -279.741793) (xy 86.132939 -279.702722) (xy 86.17461 -279.669491) (xy 86.220768 -279.642842)
			(xy 86.270382 -279.62337) (xy 86.322344 -279.61151) (xy 86.375494 -279.607527) (xy 86.428644 -279.61151)
			(xy 86.480606 -279.62337) (xy 86.53022 -279.642842) (xy 86.576378 -279.669491) (xy 86.618049 -279.702722)
			(xy 86.654301 -279.741793) (xy 86.684325 -279.78583) (xy 86.707451 -279.833851) (xy 86.723161 -279.884781)
			(xy 86.731104 -279.937485) (xy 86.731602 -279.964134) (xy 86.731104 -279.990783) (xy 86.959684 -279.990783)
			(xy 86.959684 -279.937485) (xy 86.967627 -279.884781) (xy 86.983337 -279.833851) (xy 87.006463 -279.78583)
			(xy 87.036487 -279.741793) (xy 87.072739 -279.702722) (xy 87.11441 -279.669491) (xy 87.160568 -279.642842)
			(xy 87.210182 -279.62337) (xy 87.262144 -279.61151) (xy 87.315294 -279.607527) (xy 87.368444 -279.61151)
			(xy 87.420406 -279.62337) (xy 87.47002 -279.642842) (xy 87.516178 -279.669491) (xy 87.557849 -279.702722)
			(xy 87.594101 -279.741793) (xy 87.624125 -279.78583) (xy 87.647251 -279.833851) (xy 87.662961 -279.884781)
			(xy 87.670904 -279.937485) (xy 87.671402 -279.964134) (xy 87.670904 -279.990783) (xy 87.899484 -279.990783)
			(xy 87.899484 -279.937485) (xy 87.907427 -279.884781) (xy 87.923137 -279.833851) (xy 87.946263 -279.78583)
			(xy 87.976287 -279.741793) (xy 88.012539 -279.702722) (xy 88.05421 -279.669491) (xy 88.100368 -279.642842)
			(xy 88.149982 -279.62337) (xy 88.201944 -279.61151) (xy 88.255094 -279.607527) (xy 88.308244 -279.61151)
			(xy 88.360206 -279.62337) (xy 88.40982 -279.642842) (xy 88.455978 -279.669491) (xy 88.497649 -279.702722)
			(xy 88.533901 -279.741793) (xy 88.563925 -279.78583) (xy 88.587051 -279.833851) (xy 88.602761 -279.884781)
			(xy 88.610704 -279.937485) (xy 88.611202 -279.964134) (xy 88.610719 -279.989984) (xy 88.866003 -279.989984)
			(xy 88.866003 -279.938216) (xy 88.874102 -279.887084) (xy 88.890099 -279.837849) (xy 88.913601 -279.791722)
			(xy 88.94403 -279.74984) (xy 88.980636 -279.713234) (xy 89.022517 -279.682805) (xy 89.068643 -279.659301)
			(xy 89.117878 -279.643303) (xy 89.16901 -279.635204) (xy 89.194894 -279.634696) (xy 89.220406 -279.635183)
			(xy 89.27082 -279.643042) (xy 89.319421 -279.658575) (xy 89.365049 -279.681409) (xy 89.406615 -279.711)
			(xy 89.443126 -279.746642) (xy 89.4588 -279.766776) (xy 89.870788 -279.766776) (xy 89.886462 -279.746641)
			(xy 89.922972 -279.710998) (xy 89.964538 -279.681405) (xy 90.010166 -279.658569) (xy 90.058768 -279.643035)
			(xy 90.109182 -279.635173) (xy 90.134694 -279.634696) (xy 90.160586 -279.635109) (xy 90.211734 -279.643209)
			(xy 90.260984 -279.659211) (xy 90.307125 -279.68272) (xy 90.349021 -279.713158) (xy 90.385638 -279.749775)
			(xy 90.416077 -279.791669) (xy 90.439587 -279.83781) (xy 90.45559 -279.88706) (xy 90.463691 -279.938208)
			(xy 90.463691 -279.989992) (xy 90.463566 -279.990783) (xy 91.658938 -279.990783) (xy 91.658938 -279.937485)
			(xy 91.666881 -279.884781) (xy 91.682591 -279.833851) (xy 91.705717 -279.78583) (xy 91.735741 -279.741793)
			(xy 91.771993 -279.702722) (xy 91.813664 -279.669491) (xy 91.859822 -279.642842) (xy 91.909436 -279.62337)
			(xy 91.961398 -279.61151) (xy 92.014548 -279.607527) (xy 92.067698 -279.61151) (xy 92.11966 -279.62337)
			(xy 92.169274 -279.642842) (xy 92.215432 -279.669491) (xy 92.257103 -279.702722) (xy 92.293355 -279.741793)
			(xy 92.323379 -279.78583) (xy 92.346505 -279.833851) (xy 92.362215 -279.884781) (xy 92.370158 -279.937485)
			(xy 92.370656 -279.964134) (xy 92.370158 -279.990783) (xy 92.598738 -279.990783) (xy 92.598738 -279.937485)
			(xy 92.606681 -279.884781) (xy 92.622391 -279.833851) (xy 92.645517 -279.78583) (xy 92.675541 -279.741793)
			(xy 92.711793 -279.702722) (xy 92.753464 -279.669491) (xy 92.799622 -279.642842) (xy 92.849236 -279.62337)
			(xy 92.901198 -279.61151) (xy 92.954348 -279.607527) (xy 93.007498 -279.61151) (xy 93.05946 -279.62337)
			(xy 93.109074 -279.642842) (xy 93.155232 -279.669491) (xy 93.196903 -279.702722) (xy 93.233155 -279.741793)
			(xy 93.263179 -279.78583) (xy 93.286305 -279.833851) (xy 93.302015 -279.884781) (xy 93.309958 -279.937485)
			(xy 93.310456 -279.964134) (xy 93.309958 -279.990783) (xy 94.478084 -279.990783) (xy 94.478084 -279.937485)
			(xy 94.486027 -279.884781) (xy 94.501737 -279.833851) (xy 94.524863 -279.78583) (xy 94.554887 -279.741793)
			(xy 94.591139 -279.702722) (xy 94.63281 -279.669491) (xy 94.678968 -279.642842) (xy 94.728582 -279.62337)
			(xy 94.780544 -279.61151) (xy 94.833694 -279.607527) (xy 94.886844 -279.61151) (xy 94.938806 -279.62337)
			(xy 94.98842 -279.642842) (xy 95.034578 -279.669491) (xy 95.076249 -279.702722) (xy 95.112501 -279.741793)
			(xy 95.142525 -279.78583) (xy 95.165651 -279.833851) (xy 95.181361 -279.884781) (xy 95.189304 -279.937485)
			(xy 95.189802 -279.964134) (xy 95.189304 -279.990783) (xy 95.418138 -279.990783) (xy 95.418138 -279.937485)
			(xy 95.426081 -279.884781) (xy 95.441791 -279.833851) (xy 95.464917 -279.78583) (xy 95.494941 -279.741793)
			(xy 95.531193 -279.702722) (xy 95.572864 -279.669491) (xy 95.619022 -279.642842) (xy 95.668636 -279.62337)
			(xy 95.720598 -279.61151) (xy 95.773748 -279.607527) (xy 95.826898 -279.61151) (xy 95.87886 -279.62337)
			(xy 95.928474 -279.642842) (xy 95.974632 -279.669491) (xy 96.016303 -279.702722) (xy 96.052555 -279.741793)
			(xy 96.082579 -279.78583) (xy 96.105705 -279.833851) (xy 96.121415 -279.884781) (xy 96.129358 -279.937485)
			(xy 96.129856 -279.964134) (xy 96.383856 -279.964134) (xy 96.384364 -279.938227) (xy 96.39247 -279.88705)
			(xy 96.408482 -279.837771) (xy 96.432005 -279.791604) (xy 96.462461 -279.749685) (xy 96.499099 -279.713047)
			(xy 96.541018 -279.682591) (xy 96.587185 -279.659068) (xy 96.636464 -279.643056) (xy 96.687641 -279.63495)
			(xy 96.739455 -279.63495) (xy 96.790632 -279.643056) (xy 96.839911 -279.659068) (xy 96.886078 -279.682591)
			(xy 96.927997 -279.713047) (xy 96.964635 -279.749685) (xy 96.995091 -279.791604) (xy 97.018614 -279.837771)
			(xy 97.034626 -279.88705) (xy 97.042732 -279.938227) (xy 97.04324 -279.964134) (xy 97.042632 -279.990783)
			(xy 97.297738 -279.990783) (xy 97.297738 -279.937485) (xy 97.305681 -279.884781) (xy 97.321391 -279.833851)
			(xy 97.344517 -279.78583) (xy 97.374541 -279.741793) (xy 97.410793 -279.702722) (xy 97.452464 -279.669491)
			(xy 97.498622 -279.642842) (xy 97.548236 -279.62337) (xy 97.600198 -279.61151) (xy 97.653348 -279.607527)
			(xy 97.706498 -279.61151) (xy 97.75846 -279.62337) (xy 97.808074 -279.642842) (xy 97.854232 -279.669491)
			(xy 97.895903 -279.702722) (xy 97.932155 -279.741793) (xy 97.962179 -279.78583) (xy 97.985305 -279.833851)
			(xy 98.001015 -279.884781) (xy 98.008958 -279.937485) (xy 98.009456 -279.964134) (xy 98.008958 -279.990783)
			(xy 98.237538 -279.990783) (xy 98.237538 -279.937485) (xy 98.245481 -279.884781) (xy 98.261191 -279.833851)
			(xy 98.284317 -279.78583) (xy 98.314341 -279.741793) (xy 98.350593 -279.702722) (xy 98.392264 -279.669491)
			(xy 98.438422 -279.642842) (xy 98.488036 -279.62337) (xy 98.539998 -279.61151) (xy 98.593148 -279.607527)
			(xy 98.646298 -279.61151) (xy 98.69826 -279.62337) (xy 98.747874 -279.642842) (xy 98.794032 -279.669491)
			(xy 98.835703 -279.702722) (xy 98.871955 -279.741793) (xy 98.901979 -279.78583) (xy 98.925105 -279.833851)
			(xy 98.940815 -279.884781) (xy 98.948758 -279.937485) (xy 98.949256 -279.964134) (xy 98.948758 -279.990783)
			(xy 100.117138 -279.990783) (xy 100.117138 -279.937485) (xy 100.125081 -279.884781) (xy 100.140791 -279.833851)
			(xy 100.163917 -279.78583) (xy 100.193941 -279.741793) (xy 100.230193 -279.702722) (xy 100.271864 -279.669491)
			(xy 100.318022 -279.642842) (xy 100.367636 -279.62337) (xy 100.419598 -279.61151) (xy 100.472748 -279.607527)
			(xy 100.525898 -279.61151) (xy 100.57786 -279.62337) (xy 100.627474 -279.642842) (xy 100.673632 -279.669491)
			(xy 100.715303 -279.702722) (xy 100.751555 -279.741793) (xy 100.781579 -279.78583) (xy 100.804705 -279.833851)
			(xy 100.820415 -279.884781) (xy 100.828358 -279.937485) (xy 100.828856 -279.964134) (xy 100.828358 -279.990783)
			(xy 101.056938 -279.990783) (xy 101.056938 -279.937485) (xy 101.064881 -279.884781) (xy 101.080591 -279.833851)
			(xy 101.103717 -279.78583) (xy 101.133741 -279.741793) (xy 101.169993 -279.702722) (xy 101.211664 -279.669491)
			(xy 101.257822 -279.642842) (xy 101.307436 -279.62337) (xy 101.359398 -279.61151) (xy 101.412548 -279.607527)
			(xy 101.465698 -279.61151) (xy 101.51766 -279.62337) (xy 101.567274 -279.642842) (xy 101.613432 -279.669491)
			(xy 101.655103 -279.702722) (xy 101.691355 -279.741793) (xy 101.721379 -279.78583) (xy 101.744505 -279.833851)
			(xy 101.760215 -279.884781) (xy 101.768158 -279.937485) (xy 101.768656 -279.964134) (xy 101.768158 -279.990783)
			(xy 101.760215 -280.043487) (xy 101.744505 -280.094417) (xy 101.721379 -280.142438) (xy 101.691355 -280.186475)
			(xy 101.655103 -280.225546) (xy 101.613432 -280.258777) (xy 101.567274 -280.285426) (xy 101.51766 -280.304898)
			(xy 101.465698 -280.316758) (xy 101.412548 -280.320742) (xy 101.359398 -280.316758) (xy 101.307436 -280.304898)
			(xy 101.257822 -280.285426) (xy 101.211664 -280.258777) (xy 101.169993 -280.225546) (xy 101.133741 -280.186475)
			(xy 101.103717 -280.142438) (xy 101.080591 -280.094417) (xy 101.064881 -280.043487) (xy 101.056938 -279.990783)
			(xy 100.828358 -279.990783) (xy 100.820415 -280.043487) (xy 100.804705 -280.094417) (xy 100.781579 -280.142438)
			(xy 100.751555 -280.186475) (xy 100.715303 -280.225546) (xy 100.673632 -280.258777) (xy 100.627474 -280.285426)
			(xy 100.57786 -280.304898) (xy 100.525898 -280.316758) (xy 100.472748 -280.320742) (xy 100.419598 -280.316758)
			(xy 100.367636 -280.304898) (xy 100.318022 -280.285426) (xy 100.271864 -280.258777) (xy 100.230193 -280.225546)
			(xy 100.193941 -280.186475) (xy 100.163917 -280.142438) (xy 100.140791 -280.094417) (xy 100.125081 -280.043487)
			(xy 100.117138 -279.990783) (xy 98.948758 -279.990783) (xy 98.940815 -280.043487) (xy 98.925105 -280.094417)
			(xy 98.901979 -280.142438) (xy 98.871955 -280.186475) (xy 98.835703 -280.225546) (xy 98.794032 -280.258777)
			(xy 98.747874 -280.285426) (xy 98.69826 -280.304898) (xy 98.646298 -280.316758) (xy 98.593148 -280.320742)
			(xy 98.539998 -280.316758) (xy 98.488036 -280.304898) (xy 98.438422 -280.285426) (xy 98.392264 -280.258777)
			(xy 98.350593 -280.225546) (xy 98.314341 -280.186475) (xy 98.284317 -280.142438) (xy 98.261191 -280.094417)
			(xy 98.245481 -280.043487) (xy 98.237538 -279.990783) (xy 98.008958 -279.990783) (xy 98.001015 -280.043487)
			(xy 97.985305 -280.094417) (xy 97.962179 -280.142438) (xy 97.932155 -280.186475) (xy 97.895903 -280.225546)
			(xy 97.854232 -280.258777) (xy 97.808074 -280.285426) (xy 97.75846 -280.304898) (xy 97.706498 -280.316758)
			(xy 97.653348 -280.320742) (xy 97.600198 -280.316758) (xy 97.548236 -280.304898) (xy 97.498622 -280.285426)
			(xy 97.452464 -280.258777) (xy 97.410793 -280.225546) (xy 97.374541 -280.186475) (xy 97.344517 -280.142438)
			(xy 97.321391 -280.094417) (xy 97.305681 -280.043487) (xy 97.297738 -279.990783) (xy 97.042632 -279.990783)
			(xy 97.042606 -279.991926) (xy 97.033158 -280.046702) (xy 97.024444 -280.0731) (xy 97.016824 -280.095198)
			(xy 97.221802 -280.450036) (xy 97.244662 -280.454354) (xy 97.269457 -280.45958) (xy 97.317195 -280.476563)
			(xy 97.361773 -280.50065) (xy 97.402139 -280.531276) (xy 97.437344 -280.567718) (xy 97.466557 -280.609118)
			(xy 97.489091 -280.6545) (xy 97.504415 -280.702797) (xy 97.512168 -280.752869) (xy 97.512632 -280.778204)
			(xy 97.512124 -280.804091) (xy 97.504025 -280.855229) (xy 97.488026 -280.904469) (xy 97.46452 -280.950601)
			(xy 97.434088 -280.992488) (xy 97.397478 -281.029098) (xy 97.355591 -281.05953) (xy 97.309459 -281.083036)
			(xy 97.260219 -281.099035) (xy 97.209081 -281.107134) (xy 97.157307 -281.107134) (xy 97.106169 -281.099035)
			(xy 97.056929 -281.083036) (xy 97.010797 -281.05953) (xy 96.96891 -281.029098) (xy 96.9323 -280.992488)
			(xy 96.901868 -280.950601) (xy 96.878362 -280.904469) (xy 96.862363 -280.855229) (xy 96.854264 -280.804091)
			(xy 96.853756 -280.778204) (xy 96.854288 -280.750496) (xy 96.863482 -280.695849) (xy 96.872044 -280.669492)
			(xy 96.879918 -280.647394) (xy 96.674686 -280.292302) (xy 96.651826 -280.287984) (xy 96.627038 -280.282731)
			(xy 96.579302 -280.265749) (xy 96.534727 -280.241664) (xy 96.494362 -280.211041) (xy 96.459158 -280.174603)
			(xy 96.429944 -280.133207) (xy 96.407407 -280.087828) (xy 96.39208 -280.039536) (xy 96.384322 -279.989467)
			(xy 96.383856 -279.964134) (xy 96.129856 -279.964134) (xy 96.129358 -279.990783) (xy 96.121415 -280.043487)
			(xy 96.105705 -280.094417) (xy 96.082579 -280.142438) (xy 96.052555 -280.186475) (xy 96.016303 -280.225546)
			(xy 95.974632 -280.258777) (xy 95.928474 -280.285426) (xy 95.87886 -280.304898) (xy 95.826898 -280.316758)
			(xy 95.773748 -280.320742) (xy 95.720598 -280.316758) (xy 95.668636 -280.304898) (xy 95.619022 -280.285426)
			(xy 95.572864 -280.258777) (xy 95.531193 -280.225546) (xy 95.494941 -280.186475) (xy 95.464917 -280.142438)
			(xy 95.441791 -280.094417) (xy 95.426081 -280.043487) (xy 95.418138 -279.990783) (xy 95.189304 -279.990783)
			(xy 95.181361 -280.043487) (xy 95.165651 -280.094417) (xy 95.142525 -280.142438) (xy 95.112501 -280.186475)
			(xy 95.076249 -280.225546) (xy 95.034578 -280.258777) (xy 94.98842 -280.285426) (xy 94.938806 -280.304898)
			(xy 94.886844 -280.316758) (xy 94.833694 -280.320742) (xy 94.780544 -280.316758) (xy 94.728582 -280.304898)
			(xy 94.678968 -280.285426) (xy 94.63281 -280.258777) (xy 94.591139 -280.225546) (xy 94.554887 -280.186475)
			(xy 94.524863 -280.142438) (xy 94.501737 -280.094417) (xy 94.486027 -280.043487) (xy 94.478084 -279.990783)
			(xy 93.309958 -279.990783) (xy 93.302015 -280.043487) (xy 93.286305 -280.094417) (xy 93.263179 -280.142438)
			(xy 93.233155 -280.186475) (xy 93.196903 -280.225546) (xy 93.155232 -280.258777) (xy 93.109074 -280.285426)
			(xy 93.05946 -280.304898) (xy 93.007498 -280.316758) (xy 92.954348 -280.320742) (xy 92.901198 -280.316758)
			(xy 92.849236 -280.304898) (xy 92.799622 -280.285426) (xy 92.753464 -280.258777) (xy 92.711793 -280.225546)
			(xy 92.675541 -280.186475) (xy 92.645517 -280.142438) (xy 92.622391 -280.094417) (xy 92.606681 -280.043487)
			(xy 92.598738 -279.990783) (xy 92.370158 -279.990783) (xy 92.362215 -280.043487) (xy 92.346505 -280.094417)
			(xy 92.323379 -280.142438) (xy 92.293355 -280.186475) (xy 92.257103 -280.225546) (xy 92.215432 -280.258777)
			(xy 92.169274 -280.285426) (xy 92.11966 -280.304898) (xy 92.067698 -280.316758) (xy 92.014548 -280.320742)
			(xy 91.961398 -280.316758) (xy 91.909436 -280.304898) (xy 91.859822 -280.285426) (xy 91.813664 -280.258777)
			(xy 91.771993 -280.225546) (xy 91.735741 -280.186475) (xy 91.705717 -280.142438) (xy 91.682591 -280.094417)
			(xy 91.666881 -280.043487) (xy 91.658938 -279.990783) (xy 90.463566 -279.990783) (xy 90.45559 -280.04114)
			(xy 90.439587 -280.09039) (xy 90.416077 -280.13653) (xy 90.385638 -280.178425) (xy 90.349021 -280.215042)
			(xy 90.307125 -280.24548) (xy 90.260984 -280.268989) (xy 90.211734 -280.284991) (xy 90.160586 -280.293091)
			(xy 90.134694 -280.293572) (xy 90.109181 -280.293107) (xy 90.058766 -280.285245) (xy 90.010163 -280.269709)
			(xy 89.964535 -280.24687) (xy 89.92297 -280.217275) (xy 89.886461 -280.181628) (xy 89.870788 -280.161492)
			(xy 89.4588 -280.161492) (xy 89.443124 -280.181626) (xy 89.406615 -280.21727) (xy 89.365051 -280.246864)
			(xy 89.319422 -280.269701) (xy 89.270821 -280.285235) (xy 89.220406 -280.293095) (xy 89.194894 -280.293572)
			(xy 89.16901 -280.292996) (xy 89.117878 -280.284897) (xy 89.068643 -280.268899) (xy 89.022517 -280.245395)
			(xy 88.980636 -280.214966) (xy 88.94403 -280.17836) (xy 88.913601 -280.136478) (xy 88.890099 -280.090351)
			(xy 88.874102 -280.041116) (xy 88.866003 -279.989984) (xy 88.610719 -279.989984) (xy 88.610704 -279.990783)
			(xy 88.602761 -280.043487) (xy 88.587051 -280.094417) (xy 88.563925 -280.142438) (xy 88.533901 -280.186475)
			(xy 88.497649 -280.225546) (xy 88.455978 -280.258777) (xy 88.40982 -280.285426) (xy 88.360206 -280.304898)
			(xy 88.308244 -280.316758) (xy 88.255094 -280.320742) (xy 88.201944 -280.316758) (xy 88.149982 -280.304898)
			(xy 88.100368 -280.285426) (xy 88.05421 -280.258777) (xy 88.012539 -280.225546) (xy 87.976287 -280.186475)
			(xy 87.946263 -280.142438) (xy 87.923137 -280.094417) (xy 87.907427 -280.043487) (xy 87.899484 -279.990783)
			(xy 87.670904 -279.990783) (xy 87.662961 -280.043487) (xy 87.647251 -280.094417) (xy 87.624125 -280.142438)
			(xy 87.594101 -280.186475) (xy 87.557849 -280.225546) (xy 87.516178 -280.258777) (xy 87.47002 -280.285426)
			(xy 87.420406 -280.304898) (xy 87.368444 -280.316758) (xy 87.315294 -280.320742) (xy 87.262144 -280.316758)
			(xy 87.210182 -280.304898) (xy 87.160568 -280.285426) (xy 87.11441 -280.258777) (xy 87.072739 -280.225546)
			(xy 87.036487 -280.186475) (xy 87.006463 -280.142438) (xy 86.983337 -280.094417) (xy 86.967627 -280.043487)
			(xy 86.959684 -279.990783) (xy 86.731104 -279.990783) (xy 86.723161 -280.043487) (xy 86.707451 -280.094417)
			(xy 86.684325 -280.142438) (xy 86.654301 -280.186475) (xy 86.618049 -280.225546) (xy 86.576378 -280.258777)
			(xy 86.53022 -280.285426) (xy 86.480606 -280.304898) (xy 86.428644 -280.316758) (xy 86.375494 -280.320742)
			(xy 86.322344 -280.316758) (xy 86.270382 -280.304898) (xy 86.220768 -280.285426) (xy 86.17461 -280.258777)
			(xy 86.132939 -280.225546) (xy 86.096687 -280.186475) (xy 86.066663 -280.142438) (xy 86.043537 -280.094417)
			(xy 86.027827 -280.043487) (xy 86.019884 -279.990783) (xy 84.734146 -279.990783) (xy 84.734146 -280.778204)
			(xy 85.561681 -280.778204) (xy 85.565711 -280.725706) (xy 85.577708 -280.674438) (xy 85.597391 -280.625603)
			(xy 85.624297 -280.580344) (xy 85.657797 -280.539723) (xy 85.697105 -280.504692) (xy 85.7413 -280.476072)
			(xy 85.789345 -280.454533) (xy 85.840116 -280.440581) (xy 85.892421 -280.434543) (xy 85.945035 -280.43656)
			(xy 85.996725 -280.446584) (xy 86.046278 -280.464382) (xy 86.092534 -280.489535) (xy 86.134408 -280.521454)
			(xy 86.17092 -280.559392) (xy 86.201212 -280.602458) (xy 86.224575 -280.649643) (xy 86.240461 -280.699842)
			(xy 86.248498 -280.751878) (xy 86.249002 -280.778204) (xy 86.248506 -280.804107) (xy 86.51622 -280.804107)
			(xy 86.51622 -280.752293) (xy 86.524326 -280.701118) (xy 86.540337 -280.65184) (xy 86.563859 -280.605674)
			(xy 86.594314 -280.563756) (xy 86.630951 -280.527118) (xy 86.672869 -280.496662) (xy 86.719035 -280.473139)
			(xy 86.768312 -280.457127) (xy 86.819487 -280.449021) (xy 86.845394 -280.448512) (xy 86.870888 -280.448996)
			(xy 86.921265 -280.456856) (xy 86.969828 -280.472391) (xy 87.015416 -280.495227) (xy 87.056936 -280.52482)
			(xy 87.093398 -280.56046) (xy 87.109046 -280.580592) (xy 87.521542 -280.580592) (xy 87.537192 -280.560462)
			(xy 87.573653 -280.52482) (xy 87.615173 -280.495227) (xy 87.66076 -280.472389) (xy 87.709323 -280.456853)
			(xy 87.7597 -280.448991) (xy 87.785194 -280.448512) (xy 87.811104 -280.448985) (xy 87.862286 -280.457091)
			(xy 87.91157 -280.473103) (xy 87.957743 -280.496628) (xy 87.999666 -280.527087) (xy 88.036309 -280.563729)
			(xy 88.066768 -280.605652) (xy 88.090294 -280.651824) (xy 88.106308 -280.701108) (xy 88.114414 -280.75229)
			(xy 88.114414 -280.80411) (xy 88.106308 -280.855292) (xy 88.090294 -280.904576) (xy 88.066768 -280.950748)
			(xy 88.036309 -280.992671) (xy 87.999666 -281.029313) (xy 87.957743 -281.059772) (xy 87.91157 -281.083297)
			(xy 87.862286 -281.099309) (xy 87.811104 -281.107415) (xy 87.785194 -281.107896) (xy 87.7597 -281.107418)
			(xy 87.709323 -281.099555) (xy 87.660759 -281.08402) (xy 87.615172 -281.061182) (xy 87.573652 -281.031589)
			(xy 87.53719 -280.995948) (xy 87.521542 -280.975816) (xy 87.109046 -280.975816) (xy 87.093405 -280.995954)
			(xy 87.056942 -281.031594) (xy 87.01542 -281.061187) (xy 86.969831 -281.084023) (xy 86.921267 -281.099558)
			(xy 86.870888 -281.107418) (xy 86.845394 -281.107896) (xy 86.819487 -281.107379) (xy 86.768312 -281.099273)
			(xy 86.719035 -281.083261) (xy 86.672869 -281.059738) (xy 86.630951 -281.029282) (xy 86.594314 -280.992644)
			(xy 86.563859 -280.950726) (xy 86.540337 -280.90456) (xy 86.524326 -280.855282) (xy 86.51622 -280.804107)
			(xy 86.248506 -280.804107) (xy 86.248498 -280.80453) (xy 86.240461 -280.856566) (xy 86.224575 -280.906765)
			(xy 86.201212 -280.95395) (xy 86.17092 -280.997016) (xy 86.134408 -281.034954) (xy 86.092534 -281.066873)
			(xy 86.046278 -281.092026) (xy 85.996725 -281.109824) (xy 85.945035 -281.119848) (xy 85.892421 -281.121865)
			(xy 85.840116 -281.115827) (xy 85.789345 -281.101875) (xy 85.7413 -281.080336) (xy 85.697105 -281.051716)
			(xy 85.657797 -281.016685) (xy 85.624297 -280.976064) (xy 85.597391 -280.930805) (xy 85.577708 -280.88197)
			(xy 85.565711 -280.830702) (xy 85.561681 -280.778204) (xy 84.734146 -280.778204) (xy 84.734146 -281.618669)
			(xy 86.019884 -281.618669) (xy 86.019884 -281.565371) (xy 86.027827 -281.512667) (xy 86.043537 -281.461737)
			(xy 86.066663 -281.413716) (xy 86.096687 -281.369679) (xy 86.132939 -281.330608) (xy 86.17461 -281.297377)
			(xy 86.220768 -281.270728) (xy 86.270382 -281.251256) (xy 86.322344 -281.239396) (xy 86.375494 -281.235413)
			(xy 86.428644 -281.239396) (xy 86.480606 -281.251256) (xy 86.53022 -281.270728) (xy 86.576378 -281.297377)
			(xy 86.618049 -281.330608) (xy 86.654301 -281.369679) (xy 86.684325 -281.413716) (xy 86.707451 -281.461737)
			(xy 86.723161 -281.512667) (xy 86.731104 -281.565371) (xy 86.731602 -281.59202) (xy 86.731104 -281.618669)
			(xy 86.723161 -281.671373) (xy 86.707451 -281.722303) (xy 86.684325 -281.770324) (xy 86.654301 -281.814361)
			(xy 86.618049 -281.853432) (xy 86.576378 -281.886663) (xy 86.53022 -281.913312) (xy 86.480606 -281.932784)
			(xy 86.428644 -281.944644) (xy 86.375494 -281.948628) (xy 86.322344 -281.944644) (xy 86.270382 -281.932784)
			(xy 86.220768 -281.913312) (xy 86.17461 -281.886663) (xy 86.132939 -281.853432) (xy 86.096687 -281.814361)
			(xy 86.066663 -281.770324) (xy 86.043537 -281.722303) (xy 86.027827 -281.671373) (xy 86.019884 -281.618669)
			(xy 84.734146 -281.618669) (xy 84.734146 -282.432485) (xy 85.549984 -282.432485) (xy 85.549984 -282.379187)
			(xy 85.557927 -282.326483) (xy 85.573637 -282.275553) (xy 85.596763 -282.227532) (xy 85.626787 -282.183495)
			(xy 85.663039 -282.144424) (xy 85.70471 -282.111193) (xy 85.750868 -282.084544) (xy 85.800482 -282.065072)
			(xy 85.852444 -282.053212) (xy 85.905594 -282.049229) (xy 85.958744 -282.053212) (xy 86.010706 -282.065072)
			(xy 86.06032 -282.084544) (xy 86.106478 -282.111193) (xy 86.148149 -282.144424) (xy 86.184401 -282.183495)
			(xy 86.214425 -282.227532) (xy 86.237551 -282.275553) (xy 86.253261 -282.326483) (xy 86.261204 -282.379187)
			(xy 86.261702 -282.405836) (xy 86.515956 -282.405836) (xy 86.516374 -282.380488) (xy 86.524157 -282.330393)
			(xy 86.539514 -282.282079) (xy 86.562083 -282.236685) (xy 86.591333 -282.195278) (xy 86.626575 -282.158835)
			(xy 86.666978 -282.128214) (xy 86.711591 -282.104137) (xy 86.759364 -282.08717) (xy 86.78418 -282.081986)
			(xy 86.80704 -282.077668) (xy 87.012018 -281.722576) (xy 87.004398 -281.700732) (xy 86.995753 -281.67439)
			(xy 86.986439 -281.619739) (xy 86.985856 -281.59202) (xy 86.986364 -281.566113) (xy 86.99447 -281.514936)
			(xy 87.010482 -281.465657) (xy 87.034005 -281.41949) (xy 87.064461 -281.377571) (xy 87.101099 -281.340933)
			(xy 87.143018 -281.310477) (xy 87.189185 -281.286954) (xy 87.238464 -281.270942) (xy 87.289641 -281.262836)
			(xy 87.341455 -281.262836) (xy 87.392632 -281.270942) (xy 87.441911 -281.286954) (xy 87.488078 -281.310477)
			(xy 87.529997 -281.340933) (xy 87.566635 -281.377571) (xy 87.597091 -281.41949) (xy 87.620614 -281.465657)
			(xy 87.636626 -281.514936) (xy 87.644732 -281.566113) (xy 87.64524 -281.59202) (xy 87.644785 -281.617367)
			(xy 87.644583 -281.618669) (xy 87.899484 -281.618669) (xy 87.899484 -281.565371) (xy 87.907427 -281.512667)
			(xy 87.923137 -281.461737) (xy 87.946263 -281.413716) (xy 87.976287 -281.369679) (xy 88.012539 -281.330608)
			(xy 88.05421 -281.297377) (xy 88.100368 -281.270728) (xy 88.149982 -281.251256) (xy 88.201944 -281.239396)
			(xy 88.255094 -281.235413) (xy 88.308244 -281.239396) (xy 88.360206 -281.251256) (xy 88.40982 -281.270728)
			(xy 88.455978 -281.297377) (xy 88.497649 -281.330608) (xy 88.533901 -281.369679) (xy 88.563925 -281.413716)
			(xy 88.587051 -281.461737) (xy 88.602761 -281.512667) (xy 88.610704 -281.565371) (xy 88.611202 -281.59202)
			(xy 88.865456 -281.59202) (xy 88.86595 -281.566675) (xy 88.87372 -281.516583) (xy 88.889066 -281.468271)
			(xy 88.911624 -281.422876) (xy 88.940864 -281.381469) (xy 88.976098 -281.345025) (xy 89.016493 -281.314403)
			(xy 89.0611 -281.290323) (xy 89.108866 -281.273355) (xy 89.13368 -281.26817) (xy 89.15654 -281.263852)
			(xy 89.361518 -280.909014) (xy 89.353898 -280.88717) (xy 89.345254 -280.860761) (xy 89.335932 -280.805986)
			(xy 89.335356 -280.778204) (xy 89.335819 -280.752307) (xy 89.343918 -280.70115) (xy 89.359916 -280.651889)
			(xy 89.383421 -280.605736) (xy 89.413854 -280.563826) (xy 89.450466 -280.527191) (xy 89.492357 -280.496731)
			(xy 89.538495 -280.473197) (xy 89.587746 -280.457167) (xy 89.638897 -280.449036) (xy 89.664794 -280.448512)
			(xy 89.690698 -280.44895) (xy 89.741869 -280.457058) (xy 89.79114 -280.473077) (xy 89.837295 -280.49661)
			(xy 89.879199 -280.527077) (xy 89.915817 -280.563728) (xy 89.946246 -280.605659) (xy 89.969738 -280.651836)
			(xy 89.985711 -280.701121) (xy 89.993774 -280.752299) (xy 89.994232 -280.778204) (xy 89.993765 -280.803528)
			(xy 89.99356 -280.804853) (xy 90.248984 -280.804853) (xy 90.248984 -280.751555) (xy 90.256927 -280.698851)
			(xy 90.272637 -280.647921) (xy 90.295763 -280.5999) (xy 90.325787 -280.555863) (xy 90.362039 -280.516792)
			(xy 90.40371 -280.483561) (xy 90.449868 -280.456912) (xy 90.499482 -280.43744) (xy 90.551444 -280.42558)
			(xy 90.604594 -280.421597) (xy 90.657744 -280.42558) (xy 90.709706 -280.43744) (xy 90.75932 -280.456912)
			(xy 90.805478 -280.483561) (xy 90.847149 -280.516792) (xy 90.883401 -280.555863) (xy 90.913425 -280.5999)
			(xy 90.936551 -280.647921) (xy 90.952261 -280.698851) (xy 90.960204 -280.751555) (xy 90.960702 -280.778204)
			(xy 92.154756 -280.778204) (xy 92.155193 -280.752292) (xy 92.163301 -280.701107) (xy 92.179316 -280.65182)
			(xy 92.202845 -280.605646) (xy 92.233308 -280.563722) (xy 92.269955 -280.527079) (xy 92.311884 -280.496622)
			(xy 92.358061 -280.473099) (xy 92.40735 -280.45709) (xy 92.458536 -280.44899) (xy 92.484448 -280.448512)
			(xy 92.510354 -280.4489) (xy 92.561526 -280.457017) (xy 92.610798 -280.473042) (xy 92.656954 -280.496582)
			(xy 92.698857 -280.527055) (xy 92.735474 -280.563712) (xy 92.765902 -280.605647) (xy 92.789393 -280.651828)
			(xy 92.805366 -280.701117) (xy 92.813428 -280.752298) (xy 92.813886 -280.778204) (xy 92.813338 -280.804853)
			(xy 94.008438 -280.804853) (xy 94.008438 -280.751555) (xy 94.016381 -280.698851) (xy 94.032091 -280.647921)
			(xy 94.055217 -280.5999) (xy 94.085241 -280.555863) (xy 94.121493 -280.516792) (xy 94.163164 -280.483561)
			(xy 94.209322 -280.456912) (xy 94.258936 -280.43744) (xy 94.310898 -280.42558) (xy 94.364048 -280.421597)
			(xy 94.417198 -280.42558) (xy 94.46916 -280.43744) (xy 94.518774 -280.456912) (xy 94.564932 -280.483561)
			(xy 94.606603 -280.516792) (xy 94.642855 -280.555863) (xy 94.672879 -280.5999) (xy 94.696005 -280.647921)
			(xy 94.711715 -280.698851) (xy 94.719658 -280.751555) (xy 94.720156 -280.778204) (xy 94.719672 -280.804107)
			(xy 94.97442 -280.804107) (xy 94.97442 -280.752293) (xy 94.982526 -280.701118) (xy 94.998537 -280.65184)
			(xy 95.022059 -280.605674) (xy 95.052514 -280.563756) (xy 95.089151 -280.527118) (xy 95.131069 -280.496662)
			(xy 95.177235 -280.473139) (xy 95.226512 -280.457127) (xy 95.277687 -280.449021) (xy 95.303594 -280.448512)
			(xy 95.329106 -280.448992) (xy 95.379521 -280.456852) (xy 95.428122 -280.472385) (xy 95.473751 -280.495221)
			(xy 95.515316 -280.524814) (xy 95.551826 -280.560457) (xy 95.5675 -280.580592) (xy 95.979742 -280.580592)
			(xy 95.995389 -280.560435) (xy 96.031904 -280.524793) (xy 96.073475 -280.495202) (xy 96.119109 -280.472369)
			(xy 96.167716 -280.45684) (xy 96.218134 -280.448986) (xy 96.243648 -280.448512) (xy 96.269553 -280.449016)
			(xy 96.320725 -280.457128) (xy 96.369997 -280.473144) (xy 96.416159 -280.49667) (xy 96.458071 -280.527127)
			(xy 96.494704 -280.563765) (xy 96.525155 -280.605682) (xy 96.548675 -280.651847) (xy 96.564684 -280.701122)
			(xy 96.572788 -280.752295) (xy 96.572788 -280.804105) (xy 96.564684 -280.855278) (xy 96.548675 -280.904553)
			(xy 96.525155 -280.950718) (xy 96.494704 -280.992635) (xy 96.458071 -281.029273) (xy 96.416159 -281.05973)
			(xy 96.369997 -281.083256) (xy 96.320725 -281.099272) (xy 96.269553 -281.107384) (xy 96.243648 -281.107896)
			(xy 96.218137 -281.107382) (xy 96.167724 -281.099529) (xy 96.119123 -281.084002) (xy 96.073495 -281.061173)
			(xy 96.031928 -281.031586) (xy 95.995417 -280.995948) (xy 95.979742 -280.975816) (xy 95.5675 -280.975816)
			(xy 95.551831 -280.995955) (xy 95.51532 -281.031598) (xy 95.473753 -281.06119) (xy 95.428124 -281.084026)
			(xy 95.379522 -281.099559) (xy 95.329106 -281.107419) (xy 95.303594 -281.107896) (xy 95.277687 -281.107379)
			(xy 95.226512 -281.099273) (xy 95.177235 -281.083261) (xy 95.131069 -281.059738) (xy 95.089151 -281.029282)
			(xy 95.052514 -280.992644) (xy 95.022059 -280.950726) (xy 94.998537 -280.90456) (xy 94.982526 -280.855282)
			(xy 94.97442 -280.804107) (xy 94.719672 -280.804107) (xy 94.719658 -280.804853) (xy 94.711715 -280.857557)
			(xy 94.696005 -280.908487) (xy 94.672879 -280.956508) (xy 94.642855 -281.000545) (xy 94.606603 -281.039616)
			(xy 94.564932 -281.072847) (xy 94.518774 -281.099496) (xy 94.46916 -281.118968) (xy 94.417198 -281.130828)
			(xy 94.364048 -281.134812) (xy 94.310898 -281.130828) (xy 94.258936 -281.118968) (xy 94.209322 -281.099496)
			(xy 94.163164 -281.072847) (xy 94.121493 -281.039616) (xy 94.085241 -281.000545) (xy 94.055217 -280.956508)
			(xy 94.032091 -280.908487) (xy 94.016381 -280.857557) (xy 94.008438 -280.804853) (xy 92.813338 -280.804853)
			(xy 92.813315 -280.805986) (xy 92.803991 -280.860762) (xy 92.795344 -280.88717) (xy 92.787724 -280.909014)
			(xy 92.992702 -281.263852) (xy 93.015562 -281.26817) (xy 93.04036 -281.273381) (xy 93.0881 -281.290365)
			(xy 93.132678 -281.314454) (xy 93.173045 -281.345081) (xy 93.20825 -281.381525) (xy 93.237463 -281.422927)
			(xy 93.259996 -281.468312) (xy 93.275318 -281.51661) (xy 93.283069 -281.566685) (xy 93.283532 -281.59202)
			(xy 93.283024 -281.617907) (xy 93.274925 -281.669045) (xy 93.258926 -281.718285) (xy 93.23542 -281.764417)
			(xy 93.204988 -281.806304) (xy 93.168378 -281.842914) (xy 93.126491 -281.873346) (xy 93.080359 -281.896852)
			(xy 93.031119 -281.912851) (xy 92.979981 -281.92095) (xy 92.928207 -281.92095) (xy 92.877069 -281.912851)
			(xy 92.827829 -281.896852) (xy 92.781697 -281.873346) (xy 92.73981 -281.842914) (xy 92.7032 -281.806304)
			(xy 92.672768 -281.764417) (xy 92.649262 -281.718285) (xy 92.633263 -281.669045) (xy 92.625164 -281.617907)
			(xy 92.624656 -281.59202) (xy 92.625203 -281.564313) (xy 92.634391 -281.509667) (xy 92.642944 -281.483308)
			(xy 92.650564 -281.461464) (xy 92.445586 -281.106372) (xy 92.422726 -281.102054) (xy 92.397931 -281.096829)
			(xy 92.350193 -281.079845) (xy 92.305616 -281.055757) (xy 92.265251 -281.025131) (xy 92.230046 -280.988689)
			(xy 92.200833 -280.947289) (xy 92.178299 -280.901907) (xy 92.162974 -280.853611) (xy 92.15522 -280.803539)
			(xy 92.154756 -280.778204) (xy 90.960702 -280.778204) (xy 90.960204 -280.804853) (xy 90.952261 -280.857557)
			(xy 90.936551 -280.908487) (xy 90.913425 -280.956508) (xy 90.883401 -281.000545) (xy 90.847149 -281.039616)
			(xy 90.805478 -281.072847) (xy 90.75932 -281.099496) (xy 90.709706 -281.118968) (xy 90.657744 -281.130828)
			(xy 90.604594 -281.134812) (xy 90.551444 -281.130828) (xy 90.499482 -281.118968) (xy 90.449868 -281.099496)
			(xy 90.40371 -281.072847) (xy 90.362039 -281.039616) (xy 90.325787 -281.000545) (xy 90.295763 -280.956508)
			(xy 90.272637 -280.908487) (xy 90.256927 -280.857557) (xy 90.248984 -280.804853) (xy 89.99356 -280.804853)
			(xy 89.986033 -280.853583) (xy 89.970734 -280.901865) (xy 89.94823 -280.947239) (xy 89.91905 -280.988637)
			(xy 89.883881 -281.025084) (xy 89.843551 -281.055722) (xy 89.799008 -281.079831) (xy 89.751302 -281.096842)
			(xy 89.726516 -281.102054) (xy 89.703656 -281.106372) (xy 89.498678 -281.46121) (xy 89.506298 -281.483054)
			(xy 89.51491 -281.50934) (xy 89.524233 -281.563858) (xy 89.52484 -281.591512) (xy 89.52484 -281.59202)
			(xy 89.524332 -281.617927) (xy 89.524214 -281.618669) (xy 89.779084 -281.618669) (xy 89.779084 -281.565371)
			(xy 89.787027 -281.512667) (xy 89.802737 -281.461737) (xy 89.825863 -281.413716) (xy 89.855887 -281.369679)
			(xy 89.892139 -281.330608) (xy 89.93381 -281.297377) (xy 89.979968 -281.270728) (xy 90.029582 -281.251256)
			(xy 90.081544 -281.239396) (xy 90.134694 -281.235413) (xy 90.187844 -281.239396) (xy 90.239806 -281.251256)
			(xy 90.28942 -281.270728) (xy 90.335578 -281.297377) (xy 90.377249 -281.330608) (xy 90.413501 -281.369679)
			(xy 90.443525 -281.413716) (xy 90.466651 -281.461737) (xy 90.482361 -281.512667) (xy 90.490304 -281.565371)
			(xy 90.490802 -281.59202) (xy 90.490318 -281.617905) (xy 90.745336 -281.617905) (xy 90.745336 -281.566095)
			(xy 90.753441 -281.514922) (xy 90.769451 -281.465646) (xy 90.792973 -281.419482) (xy 90.823426 -281.377566)
			(xy 90.860062 -281.34093) (xy 90.901977 -281.310476) (xy 90.948141 -281.286954) (xy 90.997416 -281.270943)
			(xy 91.048589 -281.262837) (xy 91.074494 -281.262328) (xy 91.100006 -281.262802) (xy 91.150421 -281.270662)
			(xy 91.199024 -281.286196) (xy 91.244652 -281.309033) (xy 91.286218 -281.338627) (xy 91.322727 -281.374272)
			(xy 91.3384 -281.394408) (xy 91.750388 -281.394408) (xy 91.766071 -281.37428) (xy 91.802578 -281.338635)
			(xy 91.844142 -281.309041) (xy 91.889768 -281.286203) (xy 91.938369 -281.270668) (xy 91.988782 -281.262806)
			(xy 92.014294 -281.262328) (xy 92.040205 -281.262769) (xy 92.09139 -281.270875) (xy 92.140676 -281.286888)
			(xy 92.186851 -281.310415) (xy 92.228777 -281.340875) (xy 92.265421 -281.377519) (xy 92.295882 -281.419444)
			(xy 92.319409 -281.465618) (xy 92.335423 -281.514904) (xy 92.34353 -281.566089) (xy 92.34353 -281.617911)
			(xy 92.335423 -281.669096) (xy 92.319409 -281.718382) (xy 92.295882 -281.764556) (xy 92.265421 -281.806481)
			(xy 92.228777 -281.843125) (xy 92.186851 -281.873585) (xy 92.140676 -281.897112) (xy 92.09139 -281.913125)
			(xy 92.040205 -281.921231) (xy 92.014294 -281.921712) (xy 91.988782 -281.921231) (xy 91.938368 -281.91337)
			(xy 91.889767 -281.897836) (xy 91.844138 -281.875001) (xy 91.802573 -281.845409) (xy 91.766062 -281.809767)
			(xy 91.750388 -281.789632) (xy 91.3384 -281.789632) (xy 91.322735 -281.809774) (xy 91.286223 -281.845417)
			(xy 91.244655 -281.875008) (xy 91.199025 -281.897843) (xy 91.150422 -281.913376) (xy 91.100006 -281.921235)
			(xy 91.074494 -281.921712) (xy 91.048589 -281.921163) (xy 90.997416 -281.913057) (xy 90.948141 -281.897046)
			(xy 90.901977 -281.873524) (xy 90.860062 -281.84307) (xy 90.823426 -281.806434) (xy 90.792973 -281.764518)
			(xy 90.769451 -281.718354) (xy 90.753441 -281.669078) (xy 90.745336 -281.617905) (xy 90.490318 -281.617905)
			(xy 90.490304 -281.618669) (xy 90.482361 -281.671373) (xy 90.466651 -281.722303) (xy 90.443525 -281.770324)
			(xy 90.413501 -281.814361) (xy 90.377249 -281.853432) (xy 90.335578 -281.886663) (xy 90.28942 -281.913312)
			(xy 90.239806 -281.932784) (xy 90.187844 -281.944644) (xy 90.134694 -281.948628) (xy 90.081544 -281.944644)
			(xy 90.029582 -281.932784) (xy 89.979968 -281.913312) (xy 89.93381 -281.886663) (xy 89.892139 -281.853432)
			(xy 89.855887 -281.814361) (xy 89.825863 -281.770324) (xy 89.802737 -281.722303) (xy 89.787027 -281.671373)
			(xy 89.779084 -281.618669) (xy 89.524214 -281.618669) (xy 89.516226 -281.669104) (xy 89.500214 -281.718383)
			(xy 89.476691 -281.76455) (xy 89.446235 -281.806469) (xy 89.409597 -281.843107) (xy 89.367678 -281.873563)
			(xy 89.321511 -281.897086) (xy 89.272232 -281.913098) (xy 89.221055 -281.921204) (xy 89.169241 -281.921204)
			(xy 89.118064 -281.913098) (xy 89.068785 -281.897086) (xy 89.022618 -281.873563) (xy 88.980699 -281.843107)
			(xy 88.944061 -281.806469) (xy 88.913605 -281.76455) (xy 88.890082 -281.718383) (xy 88.87407 -281.669104)
			(xy 88.865964 -281.617927) (xy 88.865456 -281.59202) (xy 88.611202 -281.59202) (xy 88.610704 -281.618669)
			(xy 88.602761 -281.671373) (xy 88.587051 -281.722303) (xy 88.563925 -281.770324) (xy 88.533901 -281.814361)
			(xy 88.497649 -281.853432) (xy 88.455978 -281.886663) (xy 88.40982 -281.913312) (xy 88.360206 -281.932784)
			(xy 88.308244 -281.944644) (xy 88.255094 -281.948628) (xy 88.201944 -281.944644) (xy 88.149982 -281.932784)
			(xy 88.100368 -281.913312) (xy 88.05421 -281.886663) (xy 88.012539 -281.853432) (xy 87.976287 -281.814361)
			(xy 87.946263 -281.770324) (xy 87.923137 -281.722303) (xy 87.907427 -281.671373) (xy 87.899484 -281.618669)
			(xy 87.644583 -281.618669) (xy 87.637009 -281.66746) (xy 87.621658 -281.715773) (xy 87.599094 -281.761168)
			(xy 87.569849 -281.802575) (xy 87.534611 -281.839019) (xy 87.494211 -281.86964) (xy 87.449601 -281.893718)
			(xy 87.401831 -281.910686) (xy 87.377016 -281.91587) (xy 87.354156 -281.920188) (xy 87.149178 -282.27528)
			(xy 87.156798 -282.297124) (xy 87.165433 -282.32347) (xy 87.174753 -282.378118) (xy 87.17534 -282.405836)
			(xy 87.455756 -282.405836) (xy 87.456264 -282.379949) (xy 87.464363 -282.328811) (xy 87.480362 -282.279571)
			(xy 87.503868 -282.233439) (xy 87.5343 -282.191552) (xy 87.57091 -282.154942) (xy 87.612797 -282.12451)
			(xy 87.658929 -282.101004) (xy 87.708169 -282.085005) (xy 87.759307 -282.076906) (xy 87.811081 -282.076906)
			(xy 87.862219 -282.085005) (xy 87.911459 -282.101004) (xy 87.957591 -282.12451) (xy 87.999478 -282.154942)
			(xy 88.036088 -282.191552) (xy 88.06652 -282.233439) (xy 88.090026 -282.279571) (xy 88.106025 -282.328811)
			(xy 88.114124 -282.379949) (xy 88.114632 -282.405836) (xy 88.114145 -282.431709) (xy 88.396026 -282.431709)
			(xy 88.396026 -282.379891) (xy 88.404133 -282.328711) (xy 88.420147 -282.27943) (xy 88.443674 -282.233261)
			(xy 88.474134 -282.191341) (xy 88.510778 -282.154703) (xy 88.552702 -282.124249) (xy 88.598874 -282.100729)
			(xy 88.648158 -282.084722) (xy 88.699339 -282.076622) (xy 88.725248 -282.076144) (xy 88.750741 -282.076648)
			(xy 88.801118 -282.084503) (xy 88.849682 -282.100032) (xy 88.895269 -282.122865) (xy 88.936791 -282.152454)
			(xy 88.973252 -282.188093) (xy 88.9889 -282.208224) (xy 89.401396 -282.208224) (xy 89.417024 -282.188075)
			(xy 89.453488 -282.152433) (xy 89.495013 -282.122841) (xy 89.540604 -282.100006) (xy 89.589171 -282.084474)
			(xy 89.639553 -282.076619) (xy 89.665048 -282.076144) (xy 89.690956 -282.076584) (xy 89.742132 -282.084696)
			(xy 89.79141 -282.100714) (xy 89.837576 -282.124242) (xy 89.879493 -282.154702) (xy 89.916129 -282.191344)
			(xy 89.946583 -282.233265) (xy 89.970105 -282.279434) (xy 89.986115 -282.328714) (xy 89.99422 -282.379892)
			(xy 89.99422 -282.431708) (xy 89.994097 -282.432485) (xy 90.249238 -282.432485) (xy 90.249238 -282.379187)
			(xy 90.257181 -282.326483) (xy 90.272891 -282.275553) (xy 90.296017 -282.227532) (xy 90.326041 -282.183495)
			(xy 90.362293 -282.144424) (xy 90.403964 -282.111193) (xy 90.450122 -282.084544) (xy 90.499736 -282.065072)
			(xy 90.551698 -282.053212) (xy 90.604848 -282.049229) (xy 90.657998 -282.053212) (xy 90.70996 -282.065072)
			(xy 90.759574 -282.084544) (xy 90.805732 -282.111193) (xy 90.847403 -282.144424) (xy 90.883655 -282.183495)
			(xy 90.913679 -282.227532) (xy 90.936805 -282.275553) (xy 90.952515 -282.326483) (xy 90.960458 -282.379187)
			(xy 90.960956 -282.405836) (xy 90.960458 -282.432485) (xy 90.952515 -282.485189) (xy 90.936805 -282.536119)
			(xy 90.913679 -282.58414) (xy 90.883655 -282.628177) (xy 90.847403 -282.667248) (xy 90.805732 -282.700479)
			(xy 90.759574 -282.727128) (xy 90.70996 -282.7466) (xy 90.657998 -282.75846) (xy 90.604848 -282.762444)
			(xy 90.551698 -282.75846) (xy 90.499736 -282.7466) (xy 90.450122 -282.727128) (xy 90.403964 -282.700479)
			(xy 90.362293 -282.667248) (xy 90.326041 -282.628177) (xy 90.296017 -282.58414) (xy 90.272891 -282.536119)
			(xy 90.257181 -282.485189) (xy 90.249238 -282.432485) (xy 89.994097 -282.432485) (xy 89.986115 -282.482886)
			(xy 89.970105 -282.532166) (xy 89.946583 -282.578335) (xy 89.916129 -282.620256) (xy 89.879493 -282.656898)
			(xy 89.837576 -282.687358) (xy 89.79141 -282.710886) (xy 89.742132 -282.726904) (xy 89.690956 -282.735016)
			(xy 89.665048 -282.735528) (xy 89.639556 -282.734998) (xy 89.589182 -282.727145) (xy 89.54062 -282.711619)
			(xy 89.495033 -282.688791) (xy 89.453511 -282.659207) (xy 89.417046 -282.623576) (xy 89.401396 -282.603448)
			(xy 88.9889 -282.603448) (xy 88.973236 -282.623567) (xy 88.936776 -282.659207) (xy 88.895259 -282.6888)
			(xy 88.849675 -282.71164) (xy 88.801115 -282.727179) (xy 88.750741 -282.735046) (xy 88.725248 -282.735528)
			(xy 88.699339 -282.734978) (xy 88.648158 -282.726878) (xy 88.598874 -282.710871) (xy 88.552702 -282.687351)
			(xy 88.510778 -282.656897) (xy 88.474134 -282.620259) (xy 88.443674 -282.578339) (xy 88.420147 -282.53217)
			(xy 88.404133 -282.482889) (xy 88.396026 -282.431709) (xy 88.114145 -282.431709) (xy 88.11411 -282.433545)
			(xy 88.10491 -282.488191) (xy 88.096344 -282.514548) (xy 88.08847 -282.536646) (xy 88.293702 -282.891738)
			(xy 88.316562 -282.896056) (xy 88.341357 -282.90128) (xy 88.389096 -282.918263) (xy 88.433673 -282.942351)
			(xy 88.47404 -282.972977) (xy 88.509244 -283.009419) (xy 88.538458 -283.050819) (xy 88.560992 -283.096202)
			(xy 88.576316 -283.144498) (xy 88.584068 -283.194571) (xy 88.584532 -283.219906) (xy 88.584024 -283.245793)
			(xy 88.583903 -283.246555) (xy 88.839284 -283.246555) (xy 88.839284 -283.193257) (xy 88.847227 -283.140553)
			(xy 88.862937 -283.089623) (xy 88.886063 -283.041602) (xy 88.916087 -282.997565) (xy 88.952339 -282.958494)
			(xy 88.99401 -282.925263) (xy 89.040168 -282.898614) (xy 89.089782 -282.879142) (xy 89.141744 -282.867282)
			(xy 89.194894 -282.863299) (xy 89.248044 -282.867282) (xy 89.300006 -282.879142) (xy 89.34962 -282.898614)
			(xy 89.395778 -282.925263) (xy 89.437449 -282.958494) (xy 89.473701 -282.997565) (xy 89.503725 -283.041602)
			(xy 89.526851 -283.089623) (xy 89.542561 -283.140553) (xy 89.550504 -283.193257) (xy 89.551002 -283.219906)
			(xy 89.550504 -283.246555) (xy 89.779084 -283.246555) (xy 89.779084 -283.193257) (xy 89.787027 -283.140553)
			(xy 89.802737 -283.089623) (xy 89.825863 -283.041602) (xy 89.855887 -282.997565) (xy 89.892139 -282.958494)
			(xy 89.93381 -282.925263) (xy 89.979968 -282.898614) (xy 90.029582 -282.879142) (xy 90.081544 -282.867282)
			(xy 90.134694 -282.863299) (xy 90.187844 -282.867282) (xy 90.239806 -282.879142) (xy 90.28942 -282.898614)
			(xy 90.335578 -282.925263) (xy 90.377249 -282.958494) (xy 90.413501 -282.997565) (xy 90.443525 -283.041602)
			(xy 90.466651 -283.089623) (xy 90.482361 -283.140553) (xy 90.490304 -283.193257) (xy 90.490802 -283.219906)
			(xy 90.745056 -283.219906) (xy 90.74558 -283.194573) (xy 90.75333 -283.144505) (xy 90.768649 -283.096211)
			(xy 90.791176 -283.05083) (xy 90.820381 -283.009429) (xy 90.855576 -282.972983) (xy 90.895932 -282.942351)
			(xy 90.9405 -282.918254) (xy 90.988229 -282.901258) (xy 91.013026 -282.896056) (xy 91.035886 -282.891738)
			(xy 91.241118 -282.536392) (xy 91.233498 -282.514548) (xy 91.224857 -282.488204) (xy 91.215541 -282.433555)
			(xy 91.214956 -282.405836) (xy 91.215464 -282.379929) (xy 91.22357 -282.328752) (xy 91.239582 -282.279473)
			(xy 91.263105 -282.233306) (xy 91.293561 -282.191387) (xy 91.330199 -282.154749) (xy 91.372118 -282.124293)
			(xy 91.418285 -282.10077) (xy 91.467564 -282.084758) (xy 91.518741 -282.076652) (xy 91.570555 -282.076652)
			(xy 91.621732 -282.084758) (xy 91.671011 -282.10077) (xy 91.717178 -282.124293) (xy 91.759097 -282.154749)
			(xy 91.795735 -282.191387) (xy 91.826191 -282.233306) (xy 91.849714 -282.279473) (xy 91.865726 -282.328752)
			(xy 91.873832 -282.379929) (xy 91.87434 -282.405836) (xy 91.873903 -282.431201) (xy 91.873704 -282.432485)
			(xy 92.128838 -282.432485) (xy 92.128838 -282.379187) (xy 92.136781 -282.326483) (xy 92.152491 -282.275553)
			(xy 92.175617 -282.227532) (xy 92.205641 -282.183495) (xy 92.241893 -282.144424) (xy 92.283564 -282.111193)
			(xy 92.329722 -282.084544) (xy 92.379336 -282.065072) (xy 92.431298 -282.053212) (xy 92.484448 -282.049229)
			(xy 92.537598 -282.053212) (xy 92.58956 -282.065072) (xy 92.639174 -282.084544) (xy 92.685332 -282.111193)
			(xy 92.727003 -282.144424) (xy 92.763255 -282.183495) (xy 92.793279 -282.227532) (xy 92.816405 -282.275553)
			(xy 92.832115 -282.326483) (xy 92.840058 -282.379187) (xy 92.840556 -282.405836) (xy 93.094556 -282.405836)
			(xy 93.094974 -282.380488) (xy 93.102757 -282.330393) (xy 93.118114 -282.282079) (xy 93.140683 -282.236685)
			(xy 93.169933 -282.195278) (xy 93.205175 -282.158835) (xy 93.245578 -282.128214) (xy 93.290191 -282.104137)
			(xy 93.337964 -282.08717) (xy 93.36278 -282.081986) (xy 93.38564 -282.077668) (xy 93.590618 -281.72283)
			(xy 93.582744 -281.700986) (xy 93.574162 -281.674568) (xy 93.564967 -281.619792) (xy 93.564456 -281.59202)
			(xy 93.564964 -281.566133) (xy 93.573063 -281.514995) (xy 93.589062 -281.465755) (xy 93.612568 -281.419623)
			(xy 93.643 -281.377736) (xy 93.67961 -281.341126) (xy 93.721497 -281.310694) (xy 93.767629 -281.287188)
			(xy 93.816869 -281.271189) (xy 93.868007 -281.26309) (xy 93.919781 -281.26309) (xy 93.970919 -281.271189)
			(xy 94.020159 -281.287188) (xy 94.066291 -281.310694) (xy 94.108178 -281.341126) (xy 94.144788 -281.377736)
			(xy 94.17522 -281.419623) (xy 94.198726 -281.465755) (xy 94.214725 -281.514995) (xy 94.222824 -281.566133)
			(xy 94.223332 -281.59202) (xy 94.222842 -281.617354) (xy 94.222638 -281.618669) (xy 94.478084 -281.618669)
			(xy 94.478084 -281.565371) (xy 94.486027 -281.512667) (xy 94.501737 -281.461737) (xy 94.524863 -281.413716)
			(xy 94.554887 -281.369679) (xy 94.591139 -281.330608) (xy 94.63281 -281.297377) (xy 94.678968 -281.270728)
			(xy 94.728582 -281.251256) (xy 94.780544 -281.239396) (xy 94.833694 -281.235413) (xy 94.886844 -281.239396)
			(xy 94.938806 -281.251256) (xy 94.98842 -281.270728) (xy 95.034578 -281.297377) (xy 95.076249 -281.330608)
			(xy 95.112501 -281.369679) (xy 95.142525 -281.413716) (xy 95.165651 -281.461737) (xy 95.181361 -281.512667)
			(xy 95.189304 -281.565371) (xy 95.189802 -281.59202) (xy 95.189304 -281.618669) (xy 95.181361 -281.671373)
			(xy 95.165651 -281.722303) (xy 95.142525 -281.770324) (xy 95.112501 -281.814361) (xy 95.076249 -281.853432)
			(xy 95.034578 -281.886663) (xy 94.98842 -281.913312) (xy 94.938806 -281.932784) (xy 94.886844 -281.944644)
			(xy 94.833694 -281.948628) (xy 94.780544 -281.944644) (xy 94.728582 -281.932784) (xy 94.678968 -281.913312)
			(xy 94.63281 -281.886663) (xy 94.591139 -281.853432) (xy 94.554887 -281.814361) (xy 94.524863 -281.770324)
			(xy 94.501737 -281.722303) (xy 94.486027 -281.671373) (xy 94.478084 -281.618669) (xy 94.222638 -281.618669)
			(xy 94.215087 -281.667425) (xy 94.199764 -281.71572) (xy 94.177233 -281.761102) (xy 94.148024 -281.802503)
			(xy 94.112825 -281.838948) (xy 94.072465 -281.869579) (xy 94.027893 -281.893676) (xy 93.980161 -281.910669)
			(xy 93.955362 -281.91587) (xy 93.932502 -281.920188) (xy 93.727524 -282.275026) (xy 93.735398 -282.297124)
			(xy 93.744018 -282.323474) (xy 93.753346 -282.378119) (xy 93.75394 -282.405836) (xy 93.753432 -282.431743)
			(xy 93.753314 -282.432485) (xy 94.008438 -282.432485) (xy 94.008438 -282.379187) (xy 94.016381 -282.326483)
			(xy 94.032091 -282.275553) (xy 94.055217 -282.227532) (xy 94.085241 -282.183495) (xy 94.121493 -282.144424)
			(xy 94.163164 -282.111193) (xy 94.209322 -282.084544) (xy 94.258936 -282.065072) (xy 94.310898 -282.053212)
			(xy 94.364048 -282.049229) (xy 94.417198 -282.053212) (xy 94.46916 -282.065072) (xy 94.518774 -282.084544)
			(xy 94.564932 -282.111193) (xy 94.606603 -282.144424) (xy 94.642855 -282.183495) (xy 94.672879 -282.227532)
			(xy 94.696005 -282.275553) (xy 94.711715 -282.326483) (xy 94.719658 -282.379187) (xy 94.720156 -282.405836)
			(xy 94.974156 -282.405836) (xy 94.974616 -282.380501) (xy 94.982377 -282.33043) (xy 94.997705 -282.282135)
			(xy 95.020241 -282.236753) (xy 95.049454 -282.195352) (xy 95.084656 -282.158908) (xy 95.125019 -282.128277)
			(xy 95.169592 -282.104181) (xy 95.217327 -282.087187) (xy 95.242126 -282.081986) (xy 95.264986 -282.077668)
			(xy 95.470218 -281.722322) (xy 95.462598 -281.700478) (xy 95.45397 -281.674197) (xy 95.444658 -281.619675)
			(xy 95.444056 -281.59202) (xy 95.444564 -281.566113) (xy 95.45267 -281.514936) (xy 95.468682 -281.465657)
			(xy 95.492205 -281.41949) (xy 95.522661 -281.377571) (xy 95.559299 -281.340933) (xy 95.601218 -281.310477)
			(xy 95.647385 -281.286954) (xy 95.696664 -281.270942) (xy 95.747841 -281.262836) (xy 95.799655 -281.262836)
			(xy 95.850832 -281.270942) (xy 95.900111 -281.286954) (xy 95.946278 -281.310477) (xy 95.988197 -281.340933)
			(xy 96.024835 -281.377571) (xy 96.055291 -281.41949) (xy 96.078814 -281.465657) (xy 96.094826 -281.514936)
			(xy 96.102932 -281.566113) (xy 96.10344 -281.59202) (xy 96.103032 -281.617397) (xy 96.102835 -281.618669)
			(xy 96.357938 -281.618669) (xy 96.357938 -281.565371) (xy 96.365881 -281.512667) (xy 96.381591 -281.461737)
			(xy 96.404717 -281.413716) (xy 96.434741 -281.369679) (xy 96.470993 -281.330608) (xy 96.512664 -281.297377)
			(xy 96.558822 -281.270728) (xy 96.608436 -281.251256) (xy 96.660398 -281.239396) (xy 96.713548 -281.235413)
			(xy 96.766698 -281.239396) (xy 96.81866 -281.251256) (xy 96.868274 -281.270728) (xy 96.914432 -281.297377)
			(xy 96.956103 -281.330608) (xy 96.992355 -281.369679) (xy 97.022379 -281.413716) (xy 97.045505 -281.461737)
			(xy 97.061215 -281.512667) (xy 97.069158 -281.565371) (xy 97.069656 -281.59202) (xy 97.323656 -281.59202)
			(xy 97.32415 -281.566675) (xy 97.33192 -281.516583) (xy 97.347266 -281.468271) (xy 97.369824 -281.422876)
			(xy 97.399064 -281.381469) (xy 97.434298 -281.345025) (xy 97.474693 -281.314403) (xy 97.5193 -281.290323)
			(xy 97.567066 -281.273355) (xy 97.59188 -281.26817) (xy 97.61474 -281.263852) (xy 97.819718 -280.909014)
			(xy 97.811844 -280.88717) (xy 97.803259 -280.860753) (xy 97.794066 -280.805977) (xy 97.793556 -280.778204)
			(xy 97.794064 -280.752317) (xy 97.802163 -280.701179) (xy 97.818162 -280.651939) (xy 97.841668 -280.605807)
			(xy 97.8721 -280.56392) (xy 97.90871 -280.52731) (xy 97.950597 -280.496878) (xy 97.996729 -280.473372)
			(xy 98.045969 -280.457373) (xy 98.097107 -280.449274) (xy 98.148881 -280.449274) (xy 98.200019 -280.457373)
			(xy 98.249259 -280.473372) (xy 98.295391 -280.496878) (xy 98.337278 -280.52731) (xy 98.373888 -280.56392)
			(xy 98.40432 -280.605807) (xy 98.427826 -280.651939) (xy 98.443825 -280.701179) (xy 98.451924 -280.752317)
			(xy 98.452432 -280.778204) (xy 98.451927 -280.803537) (xy 98.451723 -280.804853) (xy 98.707184 -280.804853)
			(xy 98.707184 -280.751555) (xy 98.715127 -280.698851) (xy 98.730837 -280.647921) (xy 98.753963 -280.5999)
			(xy 98.783987 -280.555863) (xy 98.820239 -280.516792) (xy 98.86191 -280.483561) (xy 98.908068 -280.456912)
			(xy 98.957682 -280.43744) (xy 99.009644 -280.42558) (xy 99.062794 -280.421597) (xy 99.115944 -280.42558)
			(xy 99.167906 -280.43744) (xy 99.21752 -280.456912) (xy 99.263678 -280.483561) (xy 99.305349 -280.516792)
			(xy 99.341601 -280.555863) (xy 99.371625 -280.5999) (xy 99.394751 -280.647921) (xy 99.410461 -280.698851)
			(xy 99.418404 -280.751555) (xy 99.418902 -280.778204) (xy 100.612956 -280.778204) (xy 100.613464 -280.752317)
			(xy 100.621563 -280.701179) (xy 100.637562 -280.651939) (xy 100.661068 -280.605807) (xy 100.6915 -280.56392)
			(xy 100.72811 -280.52731) (xy 100.769997 -280.496878) (xy 100.816129 -280.473372) (xy 100.865369 -280.457373)
			(xy 100.916507 -280.449274) (xy 100.968281 -280.449274) (xy 101.019419 -280.457373) (xy 101.068659 -280.473372)
			(xy 101.114791 -280.496878) (xy 101.156678 -280.52731) (xy 101.193288 -280.56392) (xy 101.22372 -280.605807)
			(xy 101.247226 -280.651939) (xy 101.263225 -280.701179) (xy 101.271324 -280.752317) (xy 101.271832 -280.778204)
			(xy 101.271293 -280.804853) (xy 101.526584 -280.804853) (xy 101.526584 -280.751555) (xy 101.534527 -280.698851)
			(xy 101.550237 -280.647921) (xy 101.573363 -280.5999) (xy 101.603387 -280.555863) (xy 101.639639 -280.516792)
			(xy 101.68131 -280.483561) (xy 101.727468 -280.456912) (xy 101.777082 -280.43744) (xy 101.829044 -280.42558)
			(xy 101.882194 -280.421597) (xy 101.935344 -280.42558) (xy 101.987306 -280.43744) (xy 102.03692 -280.456912)
			(xy 102.083078 -280.483561) (xy 102.124749 -280.516792) (xy 102.161001 -280.555863) (xy 102.191025 -280.5999)
			(xy 102.214151 -280.647921) (xy 102.229861 -280.698851) (xy 102.237804 -280.751555) (xy 102.238302 -280.778204)
			(xy 102.237804 -280.804853) (xy 102.229861 -280.857557) (xy 102.214151 -280.908487) (xy 102.191025 -280.956508)
			(xy 102.161001 -281.000545) (xy 102.124749 -281.039616) (xy 102.083078 -281.072847) (xy 102.03692 -281.099496)
			(xy 101.987306 -281.118968) (xy 101.935344 -281.130828) (xy 101.882194 -281.134812) (xy 101.829044 -281.130828)
			(xy 101.777082 -281.118968) (xy 101.727468 -281.099496) (xy 101.68131 -281.072847) (xy 101.639639 -281.039616)
			(xy 101.603387 -281.000545) (xy 101.573363 -280.956508) (xy 101.550237 -280.908487) (xy 101.534527 -280.857557)
			(xy 101.526584 -280.804853) (xy 101.271293 -280.804853) (xy 101.271273 -280.805848) (xy 101.262087 -280.860366)
			(xy 101.253544 -280.886662) (xy 101.245924 -280.908506) (xy 101.451156 -281.263852) (xy 101.474016 -281.26817)
			(xy 101.498826 -281.273386) (xy 101.546603 -281.290334) (xy 101.591222 -281.314398) (xy 101.631628 -281.345012)
			(xy 101.66687 -281.381453) (xy 101.696116 -281.422861) (xy 101.718675 -281.468259) (xy 101.734016 -281.516576)
			(xy 101.741776 -281.566673) (xy 101.74224 -281.59202) (xy 101.741732 -281.617927) (xy 101.733626 -281.669104)
			(xy 101.717614 -281.718383) (xy 101.694091 -281.76455) (xy 101.663635 -281.806469) (xy 101.626997 -281.843107)
			(xy 101.585078 -281.873563) (xy 101.538911 -281.897086) (xy 101.489632 -281.913098) (xy 101.438455 -281.921204)
			(xy 101.386641 -281.921204) (xy 101.335464 -281.913098) (xy 101.286185 -281.897086) (xy 101.240018 -281.873563)
			(xy 101.198099 -281.843107) (xy 101.161461 -281.806469) (xy 101.131005 -281.76455) (xy 101.107482 -281.718383)
			(xy 101.09147 -281.669104) (xy 101.083364 -281.617927) (xy 101.082856 -281.59202) (xy 101.083452 -281.564303)
			(xy 101.092774 -281.509656) (xy 101.101398 -281.483308) (xy 101.109272 -281.46121) (xy 100.904294 -281.106372)
			(xy 100.881434 -281.102054) (xy 100.856609 -281.096858) (xy 100.808803 -281.079927) (xy 100.764155 -281.055874)
			(xy 100.723717 -281.025267) (xy 100.688444 -280.988827) (xy 100.659168 -280.947415) (xy 100.63658 -280.902007)
			(xy 100.621213 -280.853676) (xy 100.61343 -280.803562) (xy 100.612956 -280.778204) (xy 99.418902 -280.778204)
			(xy 99.418404 -280.804853) (xy 99.410461 -280.857557) (xy 99.394751 -280.908487) (xy 99.371625 -280.956508)
			(xy 99.341601 -281.000545) (xy 99.305349 -281.039616) (xy 99.263678 -281.072847) (xy 99.21752 -281.099496)
			(xy 99.167906 -281.118968) (xy 99.115944 -281.130828) (xy 99.062794 -281.134812) (xy 99.009644 -281.130828)
			(xy 98.957682 -281.118968) (xy 98.908068 -281.099496) (xy 98.86191 -281.072847) (xy 98.820239 -281.039616)
			(xy 98.783987 -281.000545) (xy 98.753963 -280.956508) (xy 98.730837 -280.908487) (xy 98.715127 -280.857557)
			(xy 98.707184 -280.804853) (xy 98.451723 -280.804853) (xy 98.444175 -280.853607) (xy 98.428854 -280.901902)
			(xy 98.406324 -280.947284) (xy 98.377117 -280.988685) (xy 98.34192 -281.025131) (xy 98.301561 -281.055762)
			(xy 98.256992 -281.079859) (xy 98.20926 -281.096853) (xy 98.184462 -281.102054) (xy 98.161602 -281.106372)
			(xy 97.956624 -281.46121) (xy 97.964498 -281.483308) (xy 97.973138 -281.509652) (xy 97.982453 -281.564301)
			(xy 97.98304 -281.59202) (xy 97.982532 -281.617927) (xy 97.982414 -281.618669) (xy 98.237538 -281.618669)
			(xy 98.237538 -281.565371) (xy 98.245481 -281.512667) (xy 98.261191 -281.461737) (xy 98.284317 -281.413716)
			(xy 98.314341 -281.369679) (xy 98.350593 -281.330608) (xy 98.392264 -281.297377) (xy 98.438422 -281.270728)
			(xy 98.488036 -281.251256) (xy 98.539998 -281.239396) (xy 98.593148 -281.235413) (xy 98.646298 -281.239396)
			(xy 98.69826 -281.251256) (xy 98.747874 -281.270728) (xy 98.794032 -281.297377) (xy 98.835703 -281.330608)
			(xy 98.871955 -281.369679) (xy 98.901979 -281.413716) (xy 98.925105 -281.461737) (xy 98.940815 -281.512667)
			(xy 98.948758 -281.565371) (xy 98.949256 -281.59202) (xy 98.948772 -281.61791) (xy 99.20371 -281.61791)
			(xy 99.20371 -281.56609) (xy 99.211817 -281.514907) (xy 99.227832 -281.465624) (xy 99.25136 -281.419452)
			(xy 99.281822 -281.37753) (xy 99.318467 -281.34089) (xy 99.360393 -281.310435) (xy 99.406568 -281.286913)
			(xy 99.455854 -281.270906) (xy 99.507038 -281.262806) (xy 99.532948 -281.262328) (xy 99.558462 -281.262762)
			(xy 99.608879 -281.270631) (xy 99.657482 -281.286173) (xy 99.70311 -281.309017) (xy 99.744675 -281.338618)
			(xy 99.781182 -281.374269) (xy 99.796854 -281.394408) (xy 100.208842 -281.394408) (xy 100.224493 -281.374254)
			(xy 100.261007 -281.338611) (xy 100.302577 -281.309019) (xy 100.34821 -281.286186) (xy 100.396816 -281.270657)
			(xy 100.447235 -281.262802) (xy 100.472748 -281.262328) (xy 100.498654 -281.2628) (xy 100.549829 -281.270912)
			(xy 100.599104 -281.286928) (xy 100.645267 -281.310456) (xy 100.687182 -281.340914) (xy 100.723817 -281.377554)
			(xy 100.754269 -281.419474) (xy 100.77779 -281.465641) (xy 100.7938 -281.514918) (xy 100.801904 -281.566093)
			(xy 100.801904 -281.617907) (xy 100.7938 -281.669082) (xy 100.77779 -281.718359) (xy 100.754269 -281.764526)
			(xy 100.723817 -281.806446) (xy 100.687182 -281.843086) (xy 100.645267 -281.873544) (xy 100.599104 -281.897072)
			(xy 100.549829 -281.913088) (xy 100.498654 -281.9212) (xy 100.472748 -281.921712) (xy 100.447238 -281.921192)
			(xy 100.396825 -281.913339) (xy 100.348225 -281.897813) (xy 100.302596 -281.874985) (xy 100.26103 -281.8454)
			(xy 100.224517 -281.809764) (xy 100.208842 -281.789632) (xy 99.796854 -281.789632) (xy 99.781158 -281.809749)
			(xy 99.744652 -281.845392) (xy 99.703091 -281.874987) (xy 99.657467 -281.897826) (xy 99.60887 -281.913365)
			(xy 99.558459 -281.921231) (xy 99.532948 -281.921712) (xy 99.507038 -281.921194) (xy 99.455854 -281.913094)
			(xy 99.406568 -281.897087) (xy 99.360393 -281.873565) (xy 99.318467 -281.84311) (xy 99.281822 -281.80647)
			(xy 99.25136 -281.764548) (xy 99.227832 -281.718376) (xy 99.211817 -281.669093) (xy 99.20371 -281.61791)
			(xy 98.948772 -281.61791) (xy 98.948758 -281.618669) (xy 98.940815 -281.671373) (xy 98.925105 -281.722303)
			(xy 98.901979 -281.770324) (xy 98.871955 -281.814361) (xy 98.835703 -281.853432) (xy 98.794032 -281.886663)
			(xy 98.747874 -281.913312) (xy 98.69826 -281.932784) (xy 98.646298 -281.944644) (xy 98.593148 -281.948628)
			(xy 98.539998 -281.944644) (xy 98.488036 -281.932784) (xy 98.438422 -281.913312) (xy 98.392264 -281.886663)
			(xy 98.350593 -281.853432) (xy 98.314341 -281.814361) (xy 98.284317 -281.770324) (xy 98.261191 -281.722303)
			(xy 98.245481 -281.671373) (xy 98.237538 -281.618669) (xy 97.982414 -281.618669) (xy 97.974426 -281.669104)
			(xy 97.958414 -281.718383) (xy 97.934891 -281.76455) (xy 97.904435 -281.806469) (xy 97.867797 -281.843107)
			(xy 97.825878 -281.873563) (xy 97.779711 -281.897086) (xy 97.730432 -281.913098) (xy 97.679255 -281.921204)
			(xy 97.627441 -281.921204) (xy 97.576264 -281.913098) (xy 97.526985 -281.897086) (xy 97.480818 -281.873563)
			(xy 97.438899 -281.843107) (xy 97.402261 -281.806469) (xy 97.371805 -281.76455) (xy 97.348282 -281.718383)
			(xy 97.33227 -281.669104) (xy 97.324164 -281.617927) (xy 97.323656 -281.59202) (xy 97.069656 -281.59202)
			(xy 97.069158 -281.618669) (xy 97.061215 -281.671373) (xy 97.045505 -281.722303) (xy 97.022379 -281.770324)
			(xy 96.992355 -281.814361) (xy 96.956103 -281.853432) (xy 96.914432 -281.886663) (xy 96.868274 -281.913312)
			(xy 96.81866 -281.932784) (xy 96.766698 -281.944644) (xy 96.713548 -281.948628) (xy 96.660398 -281.944644)
			(xy 96.608436 -281.932784) (xy 96.558822 -281.913312) (xy 96.512664 -281.886663) (xy 96.470993 -281.853432)
			(xy 96.434741 -281.814361) (xy 96.404717 -281.770324) (xy 96.381591 -281.722303) (xy 96.365881 -281.671373)
			(xy 96.357938 -281.618669) (xy 96.102835 -281.618669) (xy 96.095259 -281.667553) (xy 96.079885 -281.715923)
			(xy 96.057273 -281.761362) (xy 96.027958 -281.802795) (xy 95.992635 -281.839241) (xy 95.95214 -281.869837)
			(xy 95.907431 -281.89386) (xy 95.859566 -281.910741) (xy 95.834708 -281.91587) (xy 95.811848 -281.920188)
			(xy 95.60687 -282.275026) (xy 95.614744 -282.297124) (xy 95.623311 -282.32348) (xy 95.632506 -282.378127)
			(xy 95.633032 -282.405836) (xy 95.913956 -282.405836) (xy 95.914464 -282.379949) (xy 95.922563 -282.328811)
			(xy 95.938562 -282.279571) (xy 95.962068 -282.233439) (xy 95.9925 -282.191552) (xy 96.02911 -282.154942)
			(xy 96.070997 -282.12451) (xy 96.117129 -282.101004) (xy 96.166369 -282.085005) (xy 96.217507 -282.076906)
			(xy 96.269281 -282.076906) (xy 96.320419 -282.085005) (xy 96.369659 -282.101004) (xy 96.415791 -282.12451)
			(xy 96.457678 -282.154942) (xy 96.494288 -282.191552) (xy 96.52472 -282.233439) (xy 96.548226 -282.279571)
			(xy 96.564225 -282.328811) (xy 96.572324 -282.379949) (xy 96.572832 -282.405836) (xy 96.572316 -282.431704)
			(xy 96.854052 -282.431704) (xy 96.854052 -282.379896) (xy 96.862157 -282.328725) (xy 96.878166 -282.279453)
			(xy 96.901687 -282.233291) (xy 96.932138 -282.191377) (xy 96.968772 -282.154742) (xy 97.010686 -282.12429)
			(xy 97.056847 -282.100769) (xy 97.106119 -282.084758) (xy 97.15729 -282.076653) (xy 97.183194 -282.076144)
			(xy 97.208707 -282.076611) (xy 97.259122 -282.084472) (xy 97.307725 -282.100007) (xy 97.353354 -282.122845)
			(xy 97.394919 -282.152441) (xy 97.431427 -282.188087) (xy 97.4471 -282.208224) (xy 97.859088 -282.208224)
			(xy 97.874775 -282.188099) (xy 97.911281 -282.152454) (xy 97.952843 -282.122858) (xy 97.998469 -282.10002)
			(xy 98.047069 -282.084484) (xy 98.097483 -282.076622) (xy 98.122994 -282.076144) (xy 98.148907 -282.076553)
			(xy 98.200094 -282.08466) (xy 98.249383 -282.100674) (xy 98.295559 -282.124201) (xy 98.337487 -282.154663)
			(xy 98.374133 -282.191308) (xy 98.404596 -282.233235) (xy 98.428124 -282.279412) (xy 98.444139 -282.3287)
			(xy 98.452246 -282.379887) (xy 98.452246 -282.431713) (xy 98.452124 -282.432485) (xy 98.707184 -282.432485)
			(xy 98.707184 -282.379187) (xy 98.715127 -282.326483) (xy 98.730837 -282.275553) (xy 98.753963 -282.227532)
			(xy 98.783987 -282.183495) (xy 98.820239 -282.144424) (xy 98.86191 -282.111193) (xy 98.908068 -282.084544)
			(xy 98.957682 -282.065072) (xy 99.009644 -282.053212) (xy 99.062794 -282.049229) (xy 99.115944 -282.053212)
			(xy 99.167906 -282.065072) (xy 99.21752 -282.084544) (xy 99.263678 -282.111193) (xy 99.305349 -282.144424)
			(xy 99.341601 -282.183495) (xy 99.371625 -282.227532) (xy 99.394751 -282.275553) (xy 99.410461 -282.326483)
			(xy 99.418404 -282.379187) (xy 99.418902 -282.405836) (xy 99.418404 -282.432485) (xy 99.410461 -282.485189)
			(xy 99.394751 -282.536119) (xy 99.371625 -282.58414) (xy 99.341601 -282.628177) (xy 99.305349 -282.667248)
			(xy 99.263678 -282.700479) (xy 99.21752 -282.727128) (xy 99.167906 -282.7466) (xy 99.115944 -282.75846)
			(xy 99.062794 -282.762444) (xy 99.009644 -282.75846) (xy 98.957682 -282.7466) (xy 98.908068 -282.727128)
			(xy 98.86191 -282.700479) (xy 98.820239 -282.667248) (xy 98.783987 -282.628177) (xy 98.753963 -282.58414)
			(xy 98.730837 -282.536119) (xy 98.715127 -282.485189) (xy 98.707184 -282.432485) (xy 98.452124 -282.432485)
			(xy 98.444139 -282.4829) (xy 98.428124 -282.532188) (xy 98.404596 -282.578365) (xy 98.374133 -282.620292)
			(xy 98.337487 -282.656937) (xy 98.295559 -282.687399) (xy 98.249383 -282.710926) (xy 98.200094 -282.72694)
			(xy 98.148907 -282.735047) (xy 98.122994 -282.735528) (xy 98.097483 -282.735041) (xy 98.047069 -282.72718)
			(xy 97.998468 -282.711647) (xy 97.95284 -282.688813) (xy 97.911274 -282.659222) (xy 97.874762 -282.623582)
			(xy 97.859088 -282.603448) (xy 97.4471 -282.603448) (xy 97.43144 -282.623594) (xy 97.394926 -282.659235)
			(xy 97.353357 -282.688826) (xy 97.307726 -282.71166) (xy 97.259123 -282.727192) (xy 97.208707 -282.735052)
			(xy 97.183194 -282.735528) (xy 97.15729 -282.734947) (xy 97.106119 -282.726842) (xy 97.056847 -282.710831)
			(xy 97.010686 -282.68731) (xy 96.968772 -282.656858) (xy 96.932138 -282.620223) (xy 96.901687 -282.578309)
			(xy 96.878166 -282.532147) (xy 96.862157 -282.482875) (xy 96.854052 -282.431704) (xy 96.572316 -282.431704)
			(xy 96.572281 -282.43348) (xy 96.56309 -282.487998) (xy 96.554544 -282.514294) (xy 96.546924 -282.536392)
			(xy 96.752156 -282.891738) (xy 96.775016 -282.896056) (xy 96.799823 -282.901285) (xy 96.847599 -282.918232)
			(xy 96.892217 -282.942295) (xy 96.932623 -282.972907) (xy 96.967865 -283.009346) (xy 96.997111 -283.050752)
			(xy 97.019671 -283.096149) (xy 97.035013 -283.144464) (xy 97.042775 -283.194559) (xy 97.04324 -283.219906)
			(xy 97.042732 -283.245813) (xy 97.042614 -283.246555) (xy 97.297484 -283.246555) (xy 97.297484 -283.193257)
			(xy 97.305427 -283.140553) (xy 97.321137 -283.089623) (xy 97.344263 -283.041602) (xy 97.374287 -282.997565)
			(xy 97.410539 -282.958494) (xy 97.45221 -282.925263) (xy 97.498368 -282.898614) (xy 97.547982 -282.879142)
			(xy 97.599944 -282.867282) (xy 97.653094 -282.863299) (xy 97.706244 -282.867282) (xy 97.758206 -282.879142)
			(xy 97.80782 -282.898614) (xy 97.853978 -282.925263) (xy 97.895649 -282.958494) (xy 97.931901 -282.997565)
			(xy 97.961925 -283.041602) (xy 97.985051 -283.089623) (xy 98.000761 -283.140553) (xy 98.008704 -283.193257)
			(xy 98.009202 -283.219906) (xy 98.008704 -283.246555) (xy 98.237284 -283.246555) (xy 98.237284 -283.193257)
			(xy 98.245227 -283.140553) (xy 98.260937 -283.089623) (xy 98.284063 -283.041602) (xy 98.314087 -282.997565)
			(xy 98.350339 -282.958494) (xy 98.39201 -282.925263) (xy 98.438168 -282.898614) (xy 98.487782 -282.879142)
			(xy 98.539744 -282.867282) (xy 98.592894 -282.863299) (xy 98.646044 -282.867282) (xy 98.698006 -282.879142)
			(xy 98.74762 -282.898614) (xy 98.793778 -282.925263) (xy 98.835449 -282.958494) (xy 98.871701 -282.997565)
			(xy 98.901725 -283.041602) (xy 98.924851 -283.089623) (xy 98.940561 -283.140553) (xy 98.948504 -283.193257)
			(xy 98.949002 -283.219906) (xy 99.203256 -283.219906) (xy 99.203737 -283.19456) (xy 99.21151 -283.144468)
			(xy 99.226857 -283.096156) (xy 99.249417 -283.050761) (xy 99.278659 -283.009354) (xy 99.313894 -282.97291)
			(xy 99.354291 -282.942288) (xy 99.398899 -282.918209) (xy 99.446666 -282.901241) (xy 99.47148 -282.896056)
			(xy 99.49434 -282.891738) (xy 99.699318 -282.5369) (xy 99.691698 -282.514802) (xy 99.683062 -282.488391)
			(xy 99.673735 -282.433617) (xy 99.673156 -282.405836) (xy 99.673664 -282.379949) (xy 99.681763 -282.328811)
			(xy 99.697762 -282.279571) (xy 99.721268 -282.233439) (xy 99.7517 -282.191552) (xy 99.78831 -282.154942)
			(xy 99.830197 -282.12451) (xy 99.876329 -282.101004) (xy 99.925569 -282.085005) (xy 99.976707 -282.076906)
			(xy 100.028481 -282.076906) (xy 100.079619 -282.085005) (xy 100.128859 -282.101004) (xy 100.174991 -282.12451)
			(xy 100.216878 -282.154942) (xy 100.253488 -282.191552) (xy 100.28392 -282.233439) (xy 100.307426 -282.279571)
			(xy 100.323425 -282.328811) (xy 100.331524 -282.379949) (xy 100.332032 -282.405836) (xy 100.331594 -282.431161)
			(xy 100.331389 -282.432485) (xy 100.586784 -282.432485) (xy 100.586784 -282.379187) (xy 100.594727 -282.326483)
			(xy 100.610437 -282.275553) (xy 100.633563 -282.227532) (xy 100.663587 -282.183495) (xy 100.699839 -282.144424)
			(xy 100.74151 -282.111193) (xy 100.787668 -282.084544) (xy 100.837282 -282.065072) (xy 100.889244 -282.053212)
			(xy 100.942394 -282.049229) (xy 100.995544 -282.053212) (xy 101.047506 -282.065072) (xy 101.09712 -282.084544)
			(xy 101.143278 -282.111193) (xy 101.184949 -282.144424) (xy 101.221201 -282.183495) (xy 101.251225 -282.227532)
			(xy 101.274351 -282.275553) (xy 101.290061 -282.326483) (xy 101.298004 -282.379187) (xy 101.298502 -282.405836)
			(xy 101.298004 -282.432485) (xy 101.290061 -282.485189) (xy 101.274351 -282.536119) (xy 101.251225 -282.58414)
			(xy 101.221201 -282.628177) (xy 101.184949 -282.667248) (xy 101.143278 -282.700479) (xy 101.09712 -282.727128)
			(xy 101.047506 -282.7466) (xy 100.995544 -282.75846) (xy 100.942394 -282.762444) (xy 100.889244 -282.75846)
			(xy 100.837282 -282.7466) (xy 100.787668 -282.727128) (xy 100.74151 -282.700479) (xy 100.699839 -282.667248)
			(xy 100.663587 -282.628177) (xy 100.633563 -282.58414) (xy 100.610437 -282.536119) (xy 100.594727 -282.485189)
			(xy 100.586784 -282.432485) (xy 100.331389 -282.432485) (xy 100.323857 -282.481217) (xy 100.308554 -282.5295)
			(xy 100.286046 -282.574874) (xy 100.256862 -282.616272) (xy 100.22169 -282.652718) (xy 100.181356 -282.683356)
			(xy 100.136812 -282.707464) (xy 100.089103 -282.724474) (xy 100.064316 -282.729686) (xy 100.041456 -282.734004)
			(xy 99.836224 -283.089096) (xy 99.844098 -283.111194) (xy 99.852735 -283.137539) (xy 99.862052 -283.192188)
			(xy 99.86264 -283.219906) (xy 99.862132 -283.245813) (xy 99.862014 -283.246555) (xy 100.116884 -283.246555)
			(xy 100.116884 -283.193257) (xy 100.124827 -283.140553) (xy 100.140537 -283.089623) (xy 100.163663 -283.041602)
			(xy 100.193687 -282.997565) (xy 100.229939 -282.958494) (xy 100.27161 -282.925263) (xy 100.317768 -282.898614)
			(xy 100.367382 -282.879142) (xy 100.419344 -282.867282) (xy 100.472494 -282.863299) (xy 100.525644 -282.867282)
			(xy 100.577606 -282.879142) (xy 100.62722 -282.898614) (xy 100.673378 -282.925263) (xy 100.715049 -282.958494)
			(xy 100.751301 -282.997565) (xy 100.781325 -283.041602) (xy 100.804451 -283.089623) (xy 100.820161 -283.140553)
			(xy 100.828104 -283.193257) (xy 100.828602 -283.219906) (xy 100.828104 -283.246555) (xy 100.820161 -283.299259)
			(xy 100.804451 -283.350189) (xy 100.781325 -283.39821) (xy 100.751301 -283.442247) (xy 100.715049 -283.481318)
			(xy 100.673378 -283.514549) (xy 100.62722 -283.541198) (xy 100.577606 -283.56067) (xy 100.525644 -283.57253)
			(xy 100.472494 -283.576514) (xy 100.419344 -283.57253) (xy 100.367382 -283.56067) (xy 100.317768 -283.541198)
			(xy 100.27161 -283.514549) (xy 100.229939 -283.481318) (xy 100.193687 -283.442247) (xy 100.163663 -283.39821)
			(xy 100.140537 -283.350189) (xy 100.124827 -283.299259) (xy 100.116884 -283.246555) (xy 99.862014 -283.246555)
			(xy 99.854026 -283.29699) (xy 99.838014 -283.346269) (xy 99.814491 -283.392436) (xy 99.784035 -283.434355)
			(xy 99.747397 -283.470993) (xy 99.705478 -283.501449) (xy 99.659311 -283.524972) (xy 99.610032 -283.540984)
			(xy 99.558855 -283.54909) (xy 99.507041 -283.54909) (xy 99.455864 -283.540984) (xy 99.406585 -283.524972)
			(xy 99.360418 -283.501449) (xy 99.318499 -283.470993) (xy 99.281861 -283.434355) (xy 99.251405 -283.392436)
			(xy 99.227882 -283.346269) (xy 99.21187 -283.29699) (xy 99.203764 -283.245813) (xy 99.203256 -283.219906)
			(xy 98.949002 -283.219906) (xy 98.948504 -283.246555) (xy 98.940561 -283.299259) (xy 98.924851 -283.350189)
			(xy 98.901725 -283.39821) (xy 98.871701 -283.442247) (xy 98.835449 -283.481318) (xy 98.793778 -283.514549)
			(xy 98.74762 -283.541198) (xy 98.698006 -283.56067) (xy 98.646044 -283.57253) (xy 98.592894 -283.576514)
			(xy 98.539744 -283.57253) (xy 98.487782 -283.56067) (xy 98.438168 -283.541198) (xy 98.39201 -283.514549)
			(xy 98.350339 -283.481318) (xy 98.314087 -283.442247) (xy 98.284063 -283.39821) (xy 98.260937 -283.350189)
			(xy 98.245227 -283.299259) (xy 98.237284 -283.246555) (xy 98.008704 -283.246555) (xy 98.000761 -283.299259)
			(xy 97.985051 -283.350189) (xy 97.961925 -283.39821) (xy 97.931901 -283.442247) (xy 97.895649 -283.481318)
			(xy 97.853978 -283.514549) (xy 97.80782 -283.541198) (xy 97.758206 -283.56067) (xy 97.706244 -283.57253)
			(xy 97.653094 -283.576514) (xy 97.599944 -283.57253) (xy 97.547982 -283.56067) (xy 97.498368 -283.541198)
			(xy 97.45221 -283.514549) (xy 97.410539 -283.481318) (xy 97.374287 -283.442247) (xy 97.344263 -283.39821)
			(xy 97.321137 -283.350189) (xy 97.305427 -283.299259) (xy 97.297484 -283.246555) (xy 97.042614 -283.246555)
			(xy 97.034626 -283.29699) (xy 97.018614 -283.346269) (xy 96.995091 -283.392436) (xy 96.964635 -283.434355)
			(xy 96.927997 -283.470993) (xy 96.886078 -283.501449) (xy 96.839911 -283.524972) (xy 96.790632 -283.540984)
			(xy 96.739455 -283.54909) (xy 96.687641 -283.54909) (xy 96.636464 -283.540984) (xy 96.587185 -283.524972)
			(xy 96.541018 -283.501449) (xy 96.499099 -283.470993) (xy 96.462461 -283.434355) (xy 96.432005 -283.392436)
			(xy 96.408482 -283.346269) (xy 96.39247 -283.29699) (xy 96.384364 -283.245813) (xy 96.383856 -283.219906)
			(xy 96.384448 -283.192189) (xy 96.393773 -283.137542) (xy 96.402398 -283.111194) (xy 96.410272 -283.089096)
			(xy 96.205294 -282.734004) (xy 96.18218 -282.729686) (xy 96.15736 -282.724514) (xy 96.109579 -282.707563)
			(xy 96.064958 -282.683494) (xy 96.024551 -282.652875) (xy 95.989309 -282.616428) (xy 95.960065 -282.575014)
			(xy 95.937508 -282.52961) (xy 95.922171 -282.481287) (xy 95.914416 -282.431185) (xy 95.913956 -282.405836)
			(xy 95.633032 -282.405836) (xy 95.632524 -282.431723) (xy 95.624425 -282.482861) (xy 95.608426 -282.532101)
			(xy 95.58492 -282.578233) (xy 95.554488 -282.62012) (xy 95.517878 -282.65673) (xy 95.475991 -282.687162)
			(xy 95.429859 -282.710668) (xy 95.380619 -282.726667) (xy 95.329481 -282.734766) (xy 95.277707 -282.734766)
			(xy 95.226569 -282.726667) (xy 95.177329 -282.710668) (xy 95.131197 -282.687162) (xy 95.08931 -282.65673)
			(xy 95.0527 -282.62012) (xy 95.022268 -282.578233) (xy 94.998762 -282.532101) (xy 94.982763 -282.482861)
			(xy 94.974664 -282.431723) (xy 94.974156 -282.405836) (xy 94.720156 -282.405836) (xy 94.719658 -282.432485)
			(xy 94.711715 -282.485189) (xy 94.696005 -282.536119) (xy 94.672879 -282.58414) (xy 94.642855 -282.628177)
			(xy 94.606603 -282.667248) (xy 94.564932 -282.700479) (xy 94.518774 -282.727128) (xy 94.46916 -282.7466)
			(xy 94.417198 -282.75846) (xy 94.364048 -282.762444) (xy 94.310898 -282.75846) (xy 94.258936 -282.7466)
			(xy 94.209322 -282.727128) (xy 94.163164 -282.700479) (xy 94.121493 -282.667248) (xy 94.085241 -282.628177)
			(xy 94.055217 -282.58414) (xy 94.032091 -282.536119) (xy 94.016381 -282.485189) (xy 94.008438 -282.432485)
			(xy 93.753314 -282.432485) (xy 93.745326 -282.48292) (xy 93.729314 -282.532199) (xy 93.705791 -282.578366)
			(xy 93.675335 -282.620285) (xy 93.638697 -282.656923) (xy 93.596778 -282.687379) (xy 93.550611 -282.710902)
			(xy 93.501332 -282.726914) (xy 93.450155 -282.73502) (xy 93.398341 -282.73502) (xy 93.347164 -282.726914)
			(xy 93.297885 -282.710902) (xy 93.251718 -282.687379) (xy 93.209799 -282.656923) (xy 93.173161 -282.620285)
			(xy 93.142705 -282.578366) (xy 93.119182 -282.532199) (xy 93.10317 -282.48292) (xy 93.095064 -282.431743)
			(xy 93.094556 -282.405836) (xy 92.840556 -282.405836) (xy 92.840058 -282.432485) (xy 92.832115 -282.485189)
			(xy 92.816405 -282.536119) (xy 92.793279 -282.58414) (xy 92.763255 -282.628177) (xy 92.727003 -282.667248)
			(xy 92.685332 -282.700479) (xy 92.639174 -282.727128) (xy 92.58956 -282.7466) (xy 92.537598 -282.75846)
			(xy 92.484448 -282.762444) (xy 92.431298 -282.75846) (xy 92.379336 -282.7466) (xy 92.329722 -282.727128)
			(xy 92.283564 -282.700479) (xy 92.241893 -282.667248) (xy 92.205641 -282.628177) (xy 92.175617 -282.58414)
			(xy 92.152491 -282.536119) (xy 92.136781 -282.485189) (xy 92.128838 -282.432485) (xy 91.873704 -282.432485)
			(xy 91.86615 -282.481333) (xy 91.850801 -282.529685) (xy 91.828221 -282.575111) (xy 91.798942 -282.616537)
			(xy 91.763657 -282.652984) (xy 91.723202 -282.683591) (xy 91.678531 -282.707632) (xy 91.630703 -282.724539)
			(xy 91.605862 -282.729686) (xy 91.583002 -282.734004) (xy 91.378024 -283.089096) (xy 91.385644 -283.11094)
			(xy 91.394193 -283.137235) (xy 91.40339 -283.191753) (xy 91.403932 -283.219398) (xy 91.403932 -283.219906)
			(xy 91.403424 -283.245793) (xy 91.403303 -283.246555) (xy 91.658684 -283.246555) (xy 91.658684 -283.193257)
			(xy 91.666627 -283.140553) (xy 91.682337 -283.089623) (xy 91.705463 -283.041602) (xy 91.735487 -282.997565)
			(xy 91.771739 -282.958494) (xy 91.81341 -282.925263) (xy 91.859568 -282.898614) (xy 91.909182 -282.879142)
			(xy 91.961144 -282.867282) (xy 92.014294 -282.863299) (xy 92.067444 -282.867282) (xy 92.119406 -282.879142)
			(xy 92.16902 -282.898614) (xy 92.215178 -282.925263) (xy 92.256849 -282.958494) (xy 92.293101 -282.997565)
			(xy 92.323125 -283.041602) (xy 92.346251 -283.089623) (xy 92.361961 -283.140553) (xy 92.369904 -283.193257)
			(xy 92.370402 -283.219906) (xy 92.369918 -283.245787) (xy 92.625176 -283.245787) (xy 92.625176 -283.194013)
			(xy 92.633275 -283.142878) (xy 92.649273 -283.093638) (xy 92.672778 -283.047508) (xy 92.703209 -283.005622)
			(xy 92.739818 -282.969013) (xy 92.781703 -282.938581) (xy 92.827833 -282.915076) (xy 92.877072 -282.899076)
			(xy 92.928207 -282.890976) (xy 92.954094 -282.890468) (xy 92.979605 -282.890965) (xy 93.030018 -282.898824)
			(xy 93.078619 -282.914355) (xy 93.124247 -282.937187) (xy 93.165813 -282.966776) (xy 93.202325 -283.002415)
			(xy 93.218 -283.022548) (xy 93.629988 -283.022548) (xy 93.645654 -283.002407) (xy 93.682167 -282.966766)
			(xy 93.723734 -282.937174) (xy 93.769364 -282.91434) (xy 93.817967 -282.898806) (xy 93.868382 -282.890945)
			(xy 93.893894 -282.890468) (xy 93.919784 -282.890937) (xy 93.970927 -282.899036) (xy 94.020174 -282.915037)
			(xy 94.066311 -282.938544) (xy 94.108202 -282.968979) (xy 94.144817 -283.005593) (xy 94.175253 -283.047484)
			(xy 94.198761 -283.093621) (xy 94.214762 -283.142867) (xy 94.222863 -283.19401) (xy 94.222863 -283.24579)
			(xy 94.222742 -283.246555) (xy 94.478084 -283.246555) (xy 94.478084 -283.193257) (xy 94.486027 -283.140553)
			(xy 94.501737 -283.089623) (xy 94.524863 -283.041602) (xy 94.554887 -282.997565) (xy 94.591139 -282.958494)
			(xy 94.63281 -282.925263) (xy 94.678968 -282.898614) (xy 94.728582 -282.879142) (xy 94.780544 -282.867282)
			(xy 94.833694 -282.863299) (xy 94.886844 -282.867282) (xy 94.938806 -282.879142) (xy 94.98842 -282.898614)
			(xy 95.034578 -282.925263) (xy 95.076249 -282.958494) (xy 95.112501 -282.997565) (xy 95.142525 -283.041602)
			(xy 95.165651 -283.089623) (xy 95.181361 -283.140553) (xy 95.189304 -283.193257) (xy 95.189802 -283.219906)
			(xy 95.189304 -283.246555) (xy 95.417884 -283.246555) (xy 95.417884 -283.193257) (xy 95.425827 -283.140553)
			(xy 95.441537 -283.089623) (xy 95.464663 -283.041602) (xy 95.494687 -282.997565) (xy 95.530939 -282.958494)
			(xy 95.57261 -282.925263) (xy 95.618768 -282.898614) (xy 95.668382 -282.879142) (xy 95.720344 -282.867282)
			(xy 95.773494 -282.863299) (xy 95.826644 -282.867282) (xy 95.878606 -282.879142) (xy 95.92822 -282.898614)
			(xy 95.974378 -282.925263) (xy 96.016049 -282.958494) (xy 96.052301 -282.997565) (xy 96.082325 -283.041602)
			(xy 96.105451 -283.089623) (xy 96.121161 -283.140553) (xy 96.129104 -283.193257) (xy 96.129602 -283.219906)
			(xy 96.129104 -283.246555) (xy 96.121161 -283.299259) (xy 96.105451 -283.350189) (xy 96.082325 -283.39821)
			(xy 96.052301 -283.442247) (xy 96.016049 -283.481318) (xy 95.974378 -283.514549) (xy 95.92822 -283.541198)
			(xy 95.878606 -283.56067) (xy 95.826644 -283.57253) (xy 95.773494 -283.576514) (xy 95.720344 -283.57253)
			(xy 95.668382 -283.56067) (xy 95.618768 -283.541198) (xy 95.57261 -283.514549) (xy 95.530939 -283.481318)
			(xy 95.494687 -283.442247) (xy 95.464663 -283.39821) (xy 95.441537 -283.350189) (xy 95.425827 -283.299259)
			(xy 95.417884 -283.246555) (xy 95.189304 -283.246555) (xy 95.181361 -283.299259) (xy 95.165651 -283.350189)
			(xy 95.142525 -283.39821) (xy 95.112501 -283.442247) (xy 95.076249 -283.481318) (xy 95.034578 -283.514549)
			(xy 94.98842 -283.541198) (xy 94.938806 -283.56067) (xy 94.886844 -283.57253) (xy 94.833694 -283.576514)
			(xy 94.780544 -283.57253) (xy 94.728582 -283.56067) (xy 94.678968 -283.541198) (xy 94.63281 -283.514549)
			(xy 94.591139 -283.481318) (xy 94.554887 -283.442247) (xy 94.524863 -283.39821) (xy 94.501737 -283.350189)
			(xy 94.486027 -283.299259) (xy 94.478084 -283.246555) (xy 94.222742 -283.246555) (xy 94.214762 -283.296933)
			(xy 94.198761 -283.346179) (xy 94.175253 -283.392316) (xy 94.144817 -283.434207) (xy 94.108202 -283.470821)
			(xy 94.066311 -283.501256) (xy 94.020174 -283.524763) (xy 93.970927 -283.540764) (xy 93.919784 -283.548863)
			(xy 93.893894 -283.549344) (xy 93.868381 -283.54889) (xy 93.817964 -283.541027) (xy 93.769361 -283.52549)
			(xy 93.723732 -283.502649) (xy 93.682168 -283.473051) (xy 93.64566 -283.437402) (xy 93.629988 -283.417264)
			(xy 93.218 -283.417264) (xy 93.202317 -283.437392) (xy 93.16581 -283.473038) (xy 93.124247 -283.502633)
			(xy 93.078621 -283.525471) (xy 93.03002 -283.541006) (xy 92.979606 -283.548867) (xy 92.954094 -283.549344)
			(xy 92.928207 -283.548824) (xy 92.877072 -283.540724) (xy 92.827833 -283.524724) (xy 92.781703 -283.501219)
			(xy 92.739818 -283.470787) (xy 92.703209 -283.434178) (xy 92.672778 -283.392292) (xy 92.649273 -283.346162)
			(xy 92.633275 -283.296922) (xy 92.625176 -283.245787) (xy 92.369918 -283.245787) (xy 92.369904 -283.246555)
			(xy 92.361961 -283.299259) (xy 92.346251 -283.350189) (xy 92.323125 -283.39821) (xy 92.293101 -283.442247)
			(xy 92.256849 -283.481318) (xy 92.215178 -283.514549) (xy 92.16902 -283.541198) (xy 92.119406 -283.56067)
			(xy 92.067444 -283.57253) (xy 92.014294 -283.576514) (xy 91.961144 -283.57253) (xy 91.909182 -283.56067)
			(xy 91.859568 -283.541198) (xy 91.81341 -283.514549) (xy 91.771739 -283.481318) (xy 91.735487 -283.442247)
			(xy 91.705463 -283.39821) (xy 91.682337 -283.350189) (xy 91.666627 -283.299259) (xy 91.658684 -283.246555)
			(xy 91.403303 -283.246555) (xy 91.395325 -283.296931) (xy 91.379326 -283.346171) (xy 91.35582 -283.392303)
			(xy 91.325388 -283.43419) (xy 91.288778 -283.4708) (xy 91.246891 -283.501232) (xy 91.200759 -283.524738)
			(xy 91.151519 -283.540737) (xy 91.100381 -283.548836) (xy 91.048607 -283.548836) (xy 90.997469 -283.540737)
			(xy 90.948229 -283.524738) (xy 90.902097 -283.501232) (xy 90.86021 -283.4708) (xy 90.8236 -283.43419)
			(xy 90.793168 -283.392303) (xy 90.769662 -283.346171) (xy 90.753663 -283.296931) (xy 90.745564 -283.245793)
			(xy 90.745056 -283.219906) (xy 90.490802 -283.219906) (xy 90.490304 -283.246555) (xy 90.482361 -283.299259)
			(xy 90.466651 -283.350189) (xy 90.443525 -283.39821) (xy 90.413501 -283.442247) (xy 90.377249 -283.481318)
			(xy 90.335578 -283.514549) (xy 90.28942 -283.541198) (xy 90.239806 -283.56067) (xy 90.187844 -283.57253)
			(xy 90.134694 -283.576514) (xy 90.081544 -283.57253) (xy 90.029582 -283.56067) (xy 89.979968 -283.541198)
			(xy 89.93381 -283.514549) (xy 89.892139 -283.481318) (xy 89.855887 -283.442247) (xy 89.825863 -283.39821)
			(xy 89.802737 -283.350189) (xy 89.787027 -283.299259) (xy 89.779084 -283.246555) (xy 89.550504 -283.246555)
			(xy 89.542561 -283.299259) (xy 89.526851 -283.350189) (xy 89.503725 -283.39821) (xy 89.473701 -283.442247)
			(xy 89.437449 -283.481318) (xy 89.395778 -283.514549) (xy 89.34962 -283.541198) (xy 89.300006 -283.56067)
			(xy 89.248044 -283.57253) (xy 89.194894 -283.576514) (xy 89.141744 -283.57253) (xy 89.089782 -283.56067)
			(xy 89.040168 -283.541198) (xy 88.99401 -283.514549) (xy 88.952339 -283.481318) (xy 88.916087 -283.442247)
			(xy 88.886063 -283.39821) (xy 88.862937 -283.350189) (xy 88.847227 -283.299259) (xy 88.839284 -283.246555)
			(xy 88.583903 -283.246555) (xy 88.575925 -283.296931) (xy 88.559926 -283.346171) (xy 88.53642 -283.392303)
			(xy 88.505988 -283.43419) (xy 88.469378 -283.4708) (xy 88.427491 -283.501232) (xy 88.381359 -283.524738)
			(xy 88.332119 -283.540737) (xy 88.280981 -283.548836) (xy 88.229207 -283.548836) (xy 88.178069 -283.540737)
			(xy 88.128829 -283.524738) (xy 88.082697 -283.501232) (xy 88.04081 -283.4708) (xy 88.0042 -283.43419)
			(xy 87.973768 -283.392303) (xy 87.950262 -283.346171) (xy 87.934263 -283.296931) (xy 87.926164 -283.245793)
			(xy 87.925656 -283.219906) (xy 87.926189 -283.192198) (xy 87.935382 -283.137551) (xy 87.943944 -283.111194)
			(xy 87.951818 -283.089096) (xy 87.746586 -282.734004) (xy 87.723726 -282.729686) (xy 87.698938 -282.724431)
			(xy 87.651203 -282.70745) (xy 87.606628 -282.683364) (xy 87.566263 -282.652742) (xy 87.531059 -282.616304)
			(xy 87.501844 -282.574908) (xy 87.479308 -282.52953) (xy 87.463981 -282.481238) (xy 87.456223 -282.431169)
			(xy 87.455756 -282.405836) (xy 87.17534 -282.405836) (xy 87.174832 -282.431743) (xy 87.166726 -282.48292)
			(xy 87.150714 -282.532199) (xy 87.127191 -282.578366) (xy 87.096735 -282.620285) (xy 87.060097 -282.656923)
			(xy 87.018178 -282.687379) (xy 86.972011 -282.710902) (xy 86.922732 -282.726914) (xy 86.871555 -282.73502)
			(xy 86.819741 -282.73502) (xy 86.768564 -282.726914) (xy 86.719285 -282.710902) (xy 86.673118 -282.687379)
			(xy 86.631199 -282.656923) (xy 86.594561 -282.620285) (xy 86.564105 -282.578366) (xy 86.540582 -282.532199)
			(xy 86.52457 -282.48292) (xy 86.516464 -282.431743) (xy 86.515956 -282.405836) (xy 86.261702 -282.405836)
			(xy 86.261204 -282.432485) (xy 86.253261 -282.485189) (xy 86.237551 -282.536119) (xy 86.214425 -282.58414)
			(xy 86.184401 -282.628177) (xy 86.148149 -282.667248) (xy 86.106478 -282.700479) (xy 86.06032 -282.727128)
			(xy 86.010706 -282.7466) (xy 85.958744 -282.75846) (xy 85.905594 -282.762444) (xy 85.852444 -282.75846)
			(xy 85.800482 -282.7466) (xy 85.750868 -282.727128) (xy 85.70471 -282.700479) (xy 85.663039 -282.667248)
			(xy 85.626787 -282.628177) (xy 85.596763 -282.58414) (xy 85.573637 -282.536119) (xy 85.557927 -282.485189)
			(xy 85.549984 -282.432485) (xy 84.734146 -282.432485) (xy 84.734146 -283.246555) (xy 85.080084 -283.246555)
			(xy 85.080084 -283.193257) (xy 85.088027 -283.140553) (xy 85.103737 -283.089623) (xy 85.126863 -283.041602)
			(xy 85.156887 -282.997565) (xy 85.193139 -282.958494) (xy 85.23481 -282.925263) (xy 85.280968 -282.898614)
			(xy 85.330582 -282.879142) (xy 85.382544 -282.867282) (xy 85.435694 -282.863299) (xy 85.488844 -282.867282)
			(xy 85.540806 -282.879142) (xy 85.59042 -282.898614) (xy 85.636578 -282.925263) (xy 85.678249 -282.958494)
			(xy 85.714501 -282.997565) (xy 85.744525 -283.041602) (xy 85.767651 -283.089623) (xy 85.783361 -283.140553)
			(xy 85.791304 -283.193257) (xy 85.791802 -283.219906) (xy 85.791304 -283.246555) (xy 86.019884 -283.246555)
			(xy 86.019884 -283.193257) (xy 86.027827 -283.140553) (xy 86.043537 -283.089623) (xy 86.066663 -283.041602)
			(xy 86.096687 -282.997565) (xy 86.132939 -282.958494) (xy 86.17461 -282.925263) (xy 86.220768 -282.898614)
			(xy 86.270382 -282.879142) (xy 86.322344 -282.867282) (xy 86.375494 -282.863299) (xy 86.428644 -282.867282)
			(xy 86.480606 -282.879142) (xy 86.53022 -282.898614) (xy 86.576378 -282.925263) (xy 86.618049 -282.958494)
			(xy 86.654301 -282.997565) (xy 86.684325 -283.041602) (xy 86.707451 -283.089623) (xy 86.723161 -283.140553)
			(xy 86.731104 -283.193257) (xy 86.731602 -283.219906) (xy 86.731104 -283.246555) (xy 86.959684 -283.246555)
			(xy 86.959684 -283.193257) (xy 86.967627 -283.140553) (xy 86.983337 -283.089623) (xy 87.006463 -283.041602)
			(xy 87.036487 -282.997565) (xy 87.072739 -282.958494) (xy 87.11441 -282.925263) (xy 87.160568 -282.898614)
			(xy 87.210182 -282.879142) (xy 87.262144 -282.867282) (xy 87.315294 -282.863299) (xy 87.368444 -282.867282)
			(xy 87.420406 -282.879142) (xy 87.47002 -282.898614) (xy 87.516178 -282.925263) (xy 87.557849 -282.958494)
			(xy 87.594101 -282.997565) (xy 87.624125 -283.041602) (xy 87.647251 -283.089623) (xy 87.662961 -283.140553)
			(xy 87.670904 -283.193257) (xy 87.671402 -283.219906) (xy 87.670904 -283.246555) (xy 87.662961 -283.299259)
			(xy 87.647251 -283.350189) (xy 87.624125 -283.39821) (xy 87.594101 -283.442247) (xy 87.557849 -283.481318)
			(xy 87.516178 -283.514549) (xy 87.47002 -283.541198) (xy 87.420406 -283.56067) (xy 87.368444 -283.57253)
			(xy 87.315294 -283.576514) (xy 87.262144 -283.57253) (xy 87.210182 -283.56067) (xy 87.160568 -283.541198)
			(xy 87.11441 -283.514549) (xy 87.072739 -283.481318) (xy 87.036487 -283.442247) (xy 87.006463 -283.39821)
			(xy 86.983337 -283.350189) (xy 86.967627 -283.299259) (xy 86.959684 -283.246555) (xy 86.731104 -283.246555)
			(xy 86.723161 -283.299259) (xy 86.707451 -283.350189) (xy 86.684325 -283.39821) (xy 86.654301 -283.442247)
			(xy 86.618049 -283.481318) (xy 86.576378 -283.514549) (xy 86.53022 -283.541198) (xy 86.480606 -283.56067)
			(xy 86.428644 -283.57253) (xy 86.375494 -283.576514) (xy 86.322344 -283.57253) (xy 86.270382 -283.56067)
			(xy 86.220768 -283.541198) (xy 86.17461 -283.514549) (xy 86.132939 -283.481318) (xy 86.096687 -283.442247)
			(xy 86.066663 -283.39821) (xy 86.043537 -283.350189) (xy 86.027827 -283.299259) (xy 86.019884 -283.246555)
			(xy 85.791304 -283.246555) (xy 85.783361 -283.299259) (xy 85.767651 -283.350189) (xy 85.744525 -283.39821)
			(xy 85.714501 -283.442247) (xy 85.678249 -283.481318) (xy 85.636578 -283.514549) (xy 85.59042 -283.541198)
			(xy 85.540806 -283.56067) (xy 85.488844 -283.57253) (xy 85.435694 -283.576514) (xy 85.382544 -283.57253)
			(xy 85.330582 -283.56067) (xy 85.280968 -283.541198) (xy 85.23481 -283.514549) (xy 85.193139 -283.481318)
			(xy 85.156887 -283.442247) (xy 85.126863 -283.39821) (xy 85.103737 -283.350189) (xy 85.088027 -283.299259)
			(xy 85.080084 -283.246555) (xy 84.734146 -283.246555) (xy 84.734146 -284.033722) (xy 86.515956 -284.033722)
			(xy 86.516464 -284.007815) (xy 86.52457 -283.956638) (xy 86.540582 -283.907359) (xy 86.564105 -283.861192)
			(xy 86.594561 -283.819273) (xy 86.631199 -283.782635) (xy 86.673118 -283.752179) (xy 86.719285 -283.728656)
			(xy 86.768564 -283.712644) (xy 86.819741 -283.704538) (xy 86.871555 -283.704538) (xy 86.922732 -283.712644)
			(xy 86.972011 -283.728656) (xy 87.018178 -283.752179) (xy 87.060097 -283.782635) (xy 87.096735 -283.819273)
			(xy 87.127191 -283.861192) (xy 87.150714 -283.907359) (xy 87.166726 -283.956638) (xy 87.174832 -284.007815)
			(xy 87.17534 -284.033722) (xy 87.174778 -284.060371) (xy 87.429584 -284.060371) (xy 87.429584 -284.007073)
			(xy 87.437527 -283.954369) (xy 87.453237 -283.903439) (xy 87.476363 -283.855418) (xy 87.506387 -283.811381)
			(xy 87.542639 -283.77231) (xy 87.58431 -283.739079) (xy 87.630468 -283.71243) (xy 87.680082 -283.692958)
			(xy 87.732044 -283.681098) (xy 87.785194 -283.677115) (xy 87.838344 -283.681098) (xy 87.890306 -283.692958)
			(xy 87.93992 -283.71243) (xy 87.986078 -283.739079) (xy 88.027749 -283.77231) (xy 88.064001 -283.811381)
			(xy 88.094025 -283.855418) (xy 88.117151 -283.903439) (xy 88.132861 -283.954369) (xy 88.140804 -284.007073)
			(xy 88.141302 -284.033722) (xy 88.140804 -284.060371) (xy 88.369638 -284.060371) (xy 88.369638 -284.007073)
			(xy 88.377581 -283.954369) (xy 88.393291 -283.903439) (xy 88.416417 -283.855418) (xy 88.446441 -283.811381)
			(xy 88.482693 -283.77231) (xy 88.524364 -283.739079) (xy 88.570522 -283.71243) (xy 88.620136 -283.692958)
			(xy 88.672098 -283.681098) (xy 88.725248 -283.677115) (xy 88.778398 -283.681098) (xy 88.83036 -283.692958)
			(xy 88.879974 -283.71243) (xy 88.926132 -283.739079) (xy 88.967803 -283.77231) (xy 89.004055 -283.811381)
			(xy 89.034079 -283.855418) (xy 89.057205 -283.903439) (xy 89.072915 -283.954369) (xy 89.080858 -284.007073)
			(xy 89.081356 -284.033722) (xy 89.080858 -284.060371) (xy 90.248984 -284.060371) (xy 90.248984 -284.007073)
			(xy 90.256927 -283.954369) (xy 90.272637 -283.903439) (xy 90.295763 -283.855418) (xy 90.325787 -283.811381)
			(xy 90.362039 -283.77231) (xy 90.40371 -283.739079) (xy 90.449868 -283.71243) (xy 90.499482 -283.692958)
			(xy 90.551444 -283.681098) (xy 90.604594 -283.677115) (xy 90.657744 -283.681098) (xy 90.709706 -283.692958)
			(xy 90.75932 -283.71243) (xy 90.805478 -283.739079) (xy 90.847149 -283.77231) (xy 90.883401 -283.811381)
			(xy 90.913425 -283.855418) (xy 90.936551 -283.903439) (xy 90.952261 -283.954369) (xy 90.960204 -284.007073)
			(xy 90.960702 -284.033722) (xy 90.960204 -284.060371) (xy 91.188784 -284.060371) (xy 91.188784 -284.007073)
			(xy 91.196727 -283.954369) (xy 91.212437 -283.903439) (xy 91.235563 -283.855418) (xy 91.265587 -283.811381)
			(xy 91.301839 -283.77231) (xy 91.34351 -283.739079) (xy 91.389668 -283.71243) (xy 91.439282 -283.692958)
			(xy 91.491244 -283.681098) (xy 91.544394 -283.677115) (xy 91.597544 -283.681098) (xy 91.649506 -283.692958)
			(xy 91.69912 -283.71243) (xy 91.745278 -283.739079) (xy 91.786949 -283.77231) (xy 91.823201 -283.811381)
			(xy 91.853225 -283.855418) (xy 91.876351 -283.903439) (xy 91.892061 -283.954369) (xy 91.900004 -284.007073)
			(xy 91.900502 -284.033722) (xy 91.900004 -284.060371) (xy 92.128584 -284.060371) (xy 92.128584 -284.007073)
			(xy 92.136527 -283.954369) (xy 92.152237 -283.903439) (xy 92.175363 -283.855418) (xy 92.205387 -283.811381)
			(xy 92.241639 -283.77231) (xy 92.28331 -283.739079) (xy 92.329468 -283.71243) (xy 92.379082 -283.692958)
			(xy 92.431044 -283.681098) (xy 92.484194 -283.677115) (xy 92.537344 -283.681098) (xy 92.589306 -283.692958)
			(xy 92.63892 -283.71243) (xy 92.685078 -283.739079) (xy 92.726749 -283.77231) (xy 92.763001 -283.811381)
			(xy 92.793025 -283.855418) (xy 92.816151 -283.903439) (xy 92.831861 -283.954369) (xy 92.839804 -284.007073)
			(xy 92.840302 -284.033722) (xy 92.839804 -284.060371) (xy 93.068384 -284.060371) (xy 93.068384 -284.007073)
			(xy 93.076327 -283.954369) (xy 93.092037 -283.903439) (xy 93.115163 -283.855418) (xy 93.145187 -283.811381)
			(xy 93.181439 -283.77231) (xy 93.22311 -283.739079) (xy 93.269268 -283.71243) (xy 93.318882 -283.692958)
			(xy 93.370844 -283.681098) (xy 93.423994 -283.677115) (xy 93.477144 -283.681098) (xy 93.529106 -283.692958)
			(xy 93.57872 -283.71243) (xy 93.624878 -283.739079) (xy 93.666549 -283.77231) (xy 93.702801 -283.811381)
			(xy 93.732825 -283.855418) (xy 93.755951 -283.903439) (xy 93.771661 -283.954369) (xy 93.779604 -284.007073)
			(xy 93.780102 -284.033722) (xy 93.779604 -284.060371) (xy 94.008184 -284.060371) (xy 94.008184 -284.007073)
			(xy 94.016127 -283.954369) (xy 94.031837 -283.903439) (xy 94.054963 -283.855418) (xy 94.084987 -283.811381)
			(xy 94.121239 -283.77231) (xy 94.16291 -283.739079) (xy 94.209068 -283.71243) (xy 94.258682 -283.692958)
			(xy 94.310644 -283.681098) (xy 94.363794 -283.677115) (xy 94.416944 -283.681098) (xy 94.468906 -283.692958)
			(xy 94.51852 -283.71243) (xy 94.564678 -283.739079) (xy 94.606349 -283.77231) (xy 94.642601 -283.811381)
			(xy 94.672625 -283.855418) (xy 94.695751 -283.903439) (xy 94.711461 -283.954369) (xy 94.719404 -284.007073)
			(xy 94.719902 -284.033722) (xy 94.719404 -284.060371) (xy 94.947984 -284.060371) (xy 94.947984 -284.007073)
			(xy 94.955927 -283.954369) (xy 94.971637 -283.903439) (xy 94.994763 -283.855418) (xy 95.024787 -283.811381)
			(xy 95.061039 -283.77231) (xy 95.10271 -283.739079) (xy 95.148868 -283.71243) (xy 95.198482 -283.692958)
			(xy 95.250444 -283.681098) (xy 95.303594 -283.677115) (xy 95.356744 -283.681098) (xy 95.408706 -283.692958)
			(xy 95.45832 -283.71243) (xy 95.504478 -283.739079) (xy 95.546149 -283.77231) (xy 95.582401 -283.811381)
			(xy 95.612425 -283.855418) (xy 95.635551 -283.903439) (xy 95.651261 -283.954369) (xy 95.659204 -284.007073)
			(xy 95.659702 -284.033722) (xy 95.659204 -284.060371) (xy 95.887784 -284.060371) (xy 95.887784 -284.007073)
			(xy 95.895727 -283.954369) (xy 95.911437 -283.903439) (xy 95.934563 -283.855418) (xy 95.964587 -283.811381)
			(xy 96.000839 -283.77231) (xy 96.04251 -283.739079) (xy 96.088668 -283.71243) (xy 96.138282 -283.692958)
			(xy 96.190244 -283.681098) (xy 96.243394 -283.677115) (xy 96.296544 -283.681098) (xy 96.348506 -283.692958)
			(xy 96.39812 -283.71243) (xy 96.444278 -283.739079) (xy 96.485949 -283.77231) (xy 96.522201 -283.811381)
			(xy 96.552225 -283.855418) (xy 96.575351 -283.903439) (xy 96.591061 -283.954369) (xy 96.599004 -284.007073)
			(xy 96.599502 -284.033722) (xy 96.599004 -284.060371) (xy 96.827584 -284.060371) (xy 96.827584 -284.007073)
			(xy 96.835527 -283.954369) (xy 96.851237 -283.903439) (xy 96.874363 -283.855418) (xy 96.904387 -283.811381)
			(xy 96.940639 -283.77231) (xy 96.98231 -283.739079) (xy 97.028468 -283.71243) (xy 97.078082 -283.692958)
			(xy 97.130044 -283.681098) (xy 97.183194 -283.677115) (xy 97.236344 -283.681098) (xy 97.288306 -283.692958)
			(xy 97.33792 -283.71243) (xy 97.384078 -283.739079) (xy 97.425749 -283.77231) (xy 97.462001 -283.811381)
			(xy 97.492025 -283.855418) (xy 97.515151 -283.903439) (xy 97.530861 -283.954369) (xy 97.538804 -284.007073)
			(xy 97.539302 -284.033722) (xy 97.538804 -284.060371) (xy 97.767384 -284.060371) (xy 97.767384 -284.007073)
			(xy 97.775327 -283.954369) (xy 97.791037 -283.903439) (xy 97.814163 -283.855418) (xy 97.844187 -283.811381)
			(xy 97.880439 -283.77231) (xy 97.92211 -283.739079) (xy 97.968268 -283.71243) (xy 98.017882 -283.692958)
			(xy 98.069844 -283.681098) (xy 98.122994 -283.677115) (xy 98.176144 -283.681098) (xy 98.228106 -283.692958)
			(xy 98.27772 -283.71243) (xy 98.323878 -283.739079) (xy 98.365549 -283.77231) (xy 98.401801 -283.811381)
			(xy 98.431825 -283.855418) (xy 98.454951 -283.903439) (xy 98.470661 -283.954369) (xy 98.478604 -284.007073)
			(xy 98.479102 -284.033722) (xy 98.478604 -284.060371) (xy 98.707184 -284.060371) (xy 98.707184 -284.007073)
			(xy 98.715127 -283.954369) (xy 98.730837 -283.903439) (xy 98.753963 -283.855418) (xy 98.783987 -283.811381)
			(xy 98.820239 -283.77231) (xy 98.86191 -283.739079) (xy 98.908068 -283.71243) (xy 98.957682 -283.692958)
			(xy 99.009644 -283.681098) (xy 99.062794 -283.677115) (xy 99.115944 -283.681098) (xy 99.167906 -283.692958)
			(xy 99.21752 -283.71243) (xy 99.263678 -283.739079) (xy 99.305349 -283.77231) (xy 99.341601 -283.811381)
			(xy 99.371625 -283.855418) (xy 99.394751 -283.903439) (xy 99.410461 -283.954369) (xy 99.418404 -284.007073)
			(xy 99.418902 -284.033722) (xy 99.418404 -284.060371) (xy 99.410461 -284.113075) (xy 99.394751 -284.164005)
			(xy 99.371625 -284.212026) (xy 99.341601 -284.256063) (xy 99.305349 -284.295134) (xy 99.263678 -284.328365)
			(xy 99.21752 -284.355014) (xy 99.167906 -284.374486) (xy 99.115944 -284.386346) (xy 99.062794 -284.39033)
			(xy 99.009644 -284.386346) (xy 98.957682 -284.374486) (xy 98.908068 -284.355014) (xy 98.86191 -284.328365)
			(xy 98.820239 -284.295134) (xy 98.783987 -284.256063) (xy 98.753963 -284.212026) (xy 98.730837 -284.164005)
			(xy 98.715127 -284.113075) (xy 98.707184 -284.060371) (xy 98.478604 -284.060371) (xy 98.470661 -284.113075)
			(xy 98.454951 -284.164005) (xy 98.431825 -284.212026) (xy 98.401801 -284.256063) (xy 98.365549 -284.295134)
			(xy 98.323878 -284.328365) (xy 98.27772 -284.355014) (xy 98.228106 -284.374486) (xy 98.176144 -284.386346)
			(xy 98.122994 -284.39033) (xy 98.069844 -284.386346) (xy 98.017882 -284.374486) (xy 97.968268 -284.355014)
			(xy 97.92211 -284.328365) (xy 97.880439 -284.295134) (xy 97.844187 -284.256063) (xy 97.814163 -284.212026)
			(xy 97.791037 -284.164005) (xy 97.775327 -284.113075) (xy 97.767384 -284.060371) (xy 97.538804 -284.060371)
			(xy 97.530861 -284.113075) (xy 97.515151 -284.164005) (xy 97.492025 -284.212026) (xy 97.462001 -284.256063)
			(xy 97.425749 -284.295134) (xy 97.384078 -284.328365) (xy 97.33792 -284.355014) (xy 97.288306 -284.374486)
			(xy 97.236344 -284.386346) (xy 97.183194 -284.39033) (xy 97.130044 -284.386346) (xy 97.078082 -284.374486)
			(xy 97.028468 -284.355014) (xy 96.98231 -284.328365) (xy 96.940639 -284.295134) (xy 96.904387 -284.256063)
			(xy 96.874363 -284.212026) (xy 96.851237 -284.164005) (xy 96.835527 -284.113075) (xy 96.827584 -284.060371)
			(xy 96.599004 -284.060371) (xy 96.591061 -284.113075) (xy 96.575351 -284.164005) (xy 96.552225 -284.212026)
			(xy 96.522201 -284.256063) (xy 96.485949 -284.295134) (xy 96.444278 -284.328365) (xy 96.39812 -284.355014)
			(xy 96.348506 -284.374486) (xy 96.296544 -284.386346) (xy 96.243394 -284.39033) (xy 96.190244 -284.386346)
			(xy 96.138282 -284.374486) (xy 96.088668 -284.355014) (xy 96.04251 -284.328365) (xy 96.000839 -284.295134)
			(xy 95.964587 -284.256063) (xy 95.934563 -284.212026) (xy 95.911437 -284.164005) (xy 95.895727 -284.113075)
			(xy 95.887784 -284.060371) (xy 95.659204 -284.060371) (xy 95.651261 -284.113075) (xy 95.635551 -284.164005)
			(xy 95.612425 -284.212026) (xy 95.582401 -284.256063) (xy 95.546149 -284.295134) (xy 95.504478 -284.328365)
			(xy 95.45832 -284.355014) (xy 95.408706 -284.374486) (xy 95.356744 -284.386346) (xy 95.303594 -284.39033)
			(xy 95.250444 -284.386346) (xy 95.198482 -284.374486) (xy 95.148868 -284.355014) (xy 95.10271 -284.328365)
			(xy 95.061039 -284.295134) (xy 95.024787 -284.256063) (xy 94.994763 -284.212026) (xy 94.971637 -284.164005)
			(xy 94.955927 -284.113075) (xy 94.947984 -284.060371) (xy 94.719404 -284.060371) (xy 94.711461 -284.113075)
			(xy 94.695751 -284.164005) (xy 94.672625 -284.212026) (xy 94.642601 -284.256063) (xy 94.606349 -284.295134)
			(xy 94.564678 -284.328365) (xy 94.51852 -284.355014) (xy 94.468906 -284.374486) (xy 94.416944 -284.386346)
			(xy 94.363794 -284.39033) (xy 94.310644 -284.386346) (xy 94.258682 -284.374486) (xy 94.209068 -284.355014)
			(xy 94.16291 -284.328365) (xy 94.121239 -284.295134) (xy 94.084987 -284.256063) (xy 94.054963 -284.212026)
			(xy 94.031837 -284.164005) (xy 94.016127 -284.113075) (xy 94.008184 -284.060371) (xy 93.779604 -284.060371)
			(xy 93.771661 -284.113075) (xy 93.755951 -284.164005) (xy 93.732825 -284.212026) (xy 93.702801 -284.256063)
			(xy 93.666549 -284.295134) (xy 93.624878 -284.328365) (xy 93.57872 -284.355014) (xy 93.529106 -284.374486)
			(xy 93.477144 -284.386346) (xy 93.423994 -284.39033) (xy 93.370844 -284.386346) (xy 93.318882 -284.374486)
			(xy 93.269268 -284.355014) (xy 93.22311 -284.328365) (xy 93.181439 -284.295134) (xy 93.145187 -284.256063)
			(xy 93.115163 -284.212026) (xy 93.092037 -284.164005) (xy 93.076327 -284.113075) (xy 93.068384 -284.060371)
			(xy 92.839804 -284.060371) (xy 92.831861 -284.113075) (xy 92.816151 -284.164005) (xy 92.793025 -284.212026)
			(xy 92.763001 -284.256063) (xy 92.726749 -284.295134) (xy 92.685078 -284.328365) (xy 92.63892 -284.355014)
			(xy 92.589306 -284.374486) (xy 92.537344 -284.386346) (xy 92.484194 -284.39033) (xy 92.431044 -284.386346)
			(xy 92.379082 -284.374486) (xy 92.329468 -284.355014) (xy 92.28331 -284.328365) (xy 92.241639 -284.295134)
			(xy 92.205387 -284.256063) (xy 92.175363 -284.212026) (xy 92.152237 -284.164005) (xy 92.136527 -284.113075)
			(xy 92.128584 -284.060371) (xy 91.900004 -284.060371) (xy 91.892061 -284.113075) (xy 91.876351 -284.164005)
			(xy 91.853225 -284.212026) (xy 91.823201 -284.256063) (xy 91.786949 -284.295134) (xy 91.745278 -284.328365)
			(xy 91.69912 -284.355014) (xy 91.649506 -284.374486) (xy 91.597544 -284.386346) (xy 91.544394 -284.39033)
			(xy 91.491244 -284.386346) (xy 91.439282 -284.374486) (xy 91.389668 -284.355014) (xy 91.34351 -284.328365)
			(xy 91.301839 -284.295134) (xy 91.265587 -284.256063) (xy 91.235563 -284.212026) (xy 91.212437 -284.164005)
			(xy 91.196727 -284.113075) (xy 91.188784 -284.060371) (xy 90.960204 -284.060371) (xy 90.952261 -284.113075)
			(xy 90.936551 -284.164005) (xy 90.913425 -284.212026) (xy 90.883401 -284.256063) (xy 90.847149 -284.295134)
			(xy 90.805478 -284.328365) (xy 90.75932 -284.355014) (xy 90.709706 -284.374486) (xy 90.657744 -284.386346)
			(xy 90.604594 -284.39033) (xy 90.551444 -284.386346) (xy 90.499482 -284.374486) (xy 90.449868 -284.355014)
			(xy 90.40371 -284.328365) (xy 90.362039 -284.295134) (xy 90.325787 -284.256063) (xy 90.295763 -284.212026)
			(xy 90.272637 -284.164005) (xy 90.256927 -284.113075) (xy 90.248984 -284.060371) (xy 89.080858 -284.060371)
			(xy 89.072915 -284.113075) (xy 89.057205 -284.164005) (xy 89.034079 -284.212026) (xy 89.004055 -284.256063)
			(xy 88.967803 -284.295134) (xy 88.926132 -284.328365) (xy 88.879974 -284.355014) (xy 88.83036 -284.374486)
			(xy 88.778398 -284.386346) (xy 88.725248 -284.39033) (xy 88.672098 -284.386346) (xy 88.620136 -284.374486)
			(xy 88.570522 -284.355014) (xy 88.524364 -284.328365) (xy 88.482693 -284.295134) (xy 88.446441 -284.256063)
			(xy 88.416417 -284.212026) (xy 88.393291 -284.164005) (xy 88.377581 -284.113075) (xy 88.369638 -284.060371)
			(xy 88.140804 -284.060371) (xy 88.132861 -284.113075) (xy 88.117151 -284.164005) (xy 88.094025 -284.212026)
			(xy 88.064001 -284.256063) (xy 88.027749 -284.295134) (xy 87.986078 -284.328365) (xy 87.93992 -284.355014)
			(xy 87.890306 -284.374486) (xy 87.838344 -284.386346) (xy 87.785194 -284.39033) (xy 87.732044 -284.386346)
			(xy 87.680082 -284.374486) (xy 87.630468 -284.355014) (xy 87.58431 -284.328365) (xy 87.542639 -284.295134)
			(xy 87.506387 -284.256063) (xy 87.476363 -284.212026) (xy 87.453237 -284.164005) (xy 87.437527 -284.113075)
			(xy 87.429584 -284.060371) (xy 87.174778 -284.060371) (xy 87.174755 -284.06144) (xy 87.165426 -284.116086)
			(xy 87.156798 -284.142434) (xy 87.148924 -284.164532) (xy 87.353902 -284.51937) (xy 87.376762 -284.523688)
			(xy 87.401564 -284.528882) (xy 87.449305 -284.545867) (xy 87.493884 -284.569958) (xy 87.534252 -284.600587)
			(xy 87.569457 -284.637033) (xy 87.598669 -284.678438) (xy 87.621201 -284.723825) (xy 87.636522 -284.772125)
			(xy 87.644271 -284.822202) (xy 87.644732 -284.847538) (xy 87.644224 -284.873425) (xy 87.636125 -284.924563)
			(xy 87.620126 -284.973803) (xy 87.59662 -285.019935) (xy 87.566188 -285.061822) (xy 87.529578 -285.098432)
			(xy 87.487691 -285.128864) (xy 87.441559 -285.15237) (xy 87.392319 -285.168369) (xy 87.341181 -285.176468)
			(xy 87.289407 -285.176468) (xy 87.238269 -285.168369) (xy 87.189029 -285.15237) (xy 87.142897 -285.128864)
			(xy 87.10101 -285.098432) (xy 87.0644 -285.061822) (xy 87.033968 -285.019935) (xy 87.010462 -284.973803)
			(xy 86.994463 -284.924563) (xy 86.986364 -284.873425) (xy 86.985856 -284.847538) (xy 86.986397 -284.81983)
			(xy 86.995584 -284.765184) (xy 87.004144 -284.738826) (xy 87.012018 -284.716728) (xy 86.80704 -284.36189)
			(xy 86.78418 -284.357572) (xy 86.759356 -284.352414) (xy 86.711575 -284.335461) (xy 86.666954 -284.311391)
			(xy 86.626545 -284.28077) (xy 86.591303 -284.244322) (xy 86.56206 -284.202906) (xy 86.539504 -284.1575)
			(xy 86.524169 -284.109175) (xy 86.516415 -284.059072) (xy 86.515956 -284.033722) (xy 84.734146 -284.033722)
			(xy 84.734146 -284.873384) (xy 85.106807 -284.873384) (xy 85.106807 -284.821616) (xy 85.114906 -284.770485)
			(xy 85.130903 -284.72125) (xy 85.154405 -284.675125) (xy 85.184833 -284.633243) (xy 85.221438 -284.596637)
			(xy 85.263319 -284.566208) (xy 85.309445 -284.542705) (xy 85.358679 -284.526707) (xy 85.40981 -284.518608)
			(xy 85.435694 -284.5181) (xy 85.461187 -284.518588) (xy 85.511565 -284.526449) (xy 85.560127 -284.541983)
			(xy 85.605714 -284.564818) (xy 85.647235 -284.594409) (xy 85.683698 -284.630049) (xy 85.699346 -284.65018)
			(xy 86.111842 -284.65018) (xy 86.127489 -284.630047) (xy 86.163951 -284.594407) (xy 86.205472 -284.564814)
			(xy 86.251059 -284.541976) (xy 86.299622 -284.526441) (xy 86.35 -284.518579) (xy 86.375494 -284.5181)
			(xy 86.401387 -284.518505) (xy 86.452535 -284.526605) (xy 86.501786 -284.542607) (xy 86.547927 -284.566116)
			(xy 86.589823 -284.596555) (xy 86.626441 -284.633172) (xy 86.65688 -284.675067) (xy 86.680391 -284.721208)
			(xy 86.696394 -284.770459) (xy 86.704495 -284.821607) (xy 86.704495 -284.873393) (xy 86.696394 -284.924541)
			(xy 86.680391 -284.973792) (xy 86.65688 -285.019933) (xy 86.626441 -285.061828) (xy 86.589823 -285.098445)
			(xy 86.547927 -285.128884) (xy 86.501786 -285.152393) (xy 86.452535 -285.168395) (xy 86.401387 -285.176495)
			(xy 86.375494 -285.176976) (xy 86.35 -285.176506) (xy 86.299621 -285.168643) (xy 86.251058 -285.153106)
			(xy 86.205471 -285.130267) (xy 86.16395 -285.100672) (xy 86.127489 -285.065029) (xy 86.111842 -285.044896)
			(xy 85.699346 -285.044896) (xy 85.683699 -285.065029) (xy 85.647238 -285.100671) (xy 85.605717 -285.130265)
			(xy 85.56013 -285.153102) (xy 85.511566 -285.168637) (xy 85.461188 -285.176498) (xy 85.435694 -285.176976)
			(xy 85.40981 -285.176392) (xy 85.358679 -285.168293) (xy 85.309445 -285.152295) (xy 85.263319 -285.128792)
			(xy 85.221438 -285.098363) (xy 85.184833 -285.061757) (xy 85.154405 -285.019875) (xy 85.130903 -284.97375)
			(xy 85.114906 -284.924515) (xy 85.106807 -284.873384) (xy 84.734146 -284.873384) (xy 84.734146 -285.688003)
			(xy 85.549984 -285.688003) (xy 85.549984 -285.634705) (xy 85.557927 -285.582001) (xy 85.573637 -285.531071)
			(xy 85.596763 -285.48305) (xy 85.626787 -285.439013) (xy 85.663039 -285.399942) (xy 85.70471 -285.366711)
			(xy 85.750868 -285.340062) (xy 85.800482 -285.32059) (xy 85.852444 -285.30873) (xy 85.905594 -285.304747)
			(xy 85.958744 -285.30873) (xy 86.010706 -285.32059) (xy 86.06032 -285.340062) (xy 86.106478 -285.366711)
			(xy 86.148149 -285.399942) (xy 86.184401 -285.439013) (xy 86.214425 -285.48305) (xy 86.237551 -285.531071)
			(xy 86.253261 -285.582001) (xy 86.261204 -285.634705) (xy 86.261702 -285.661354) (xy 86.261204 -285.688003)
			(xy 86.489784 -285.688003) (xy 86.489784 -285.634705) (xy 86.497727 -285.582001) (xy 86.513437 -285.531071)
			(xy 86.536563 -285.48305) (xy 86.566587 -285.439013) (xy 86.602839 -285.399942) (xy 86.64451 -285.366711)
			(xy 86.690668 -285.340062) (xy 86.740282 -285.32059) (xy 86.792244 -285.30873) (xy 86.845394 -285.304747)
			(xy 86.898544 -285.30873) (xy 86.950506 -285.32059) (xy 87.00012 -285.340062) (xy 87.046278 -285.366711)
			(xy 87.087949 -285.399942) (xy 87.124201 -285.439013) (xy 87.154225 -285.48305) (xy 87.177351 -285.531071)
			(xy 87.193061 -285.582001) (xy 87.201004 -285.634705) (xy 87.201502 -285.661354) (xy 87.455756 -285.661354)
			(xy 87.456232 -285.63602) (xy 87.46399 -285.585949) (xy 87.479317 -285.537654) (xy 87.50185 -285.492273)
			(xy 87.531061 -285.450872) (xy 87.566261 -285.414427) (xy 87.606622 -285.383796) (xy 87.651194 -285.3597)
			(xy 87.698927 -285.342705) (xy 87.723726 -285.337504) (xy 87.746586 -285.333186) (xy 87.951564 -284.978094)
			(xy 87.943944 -284.95625) (xy 87.935376 -284.929894) (xy 87.926181 -284.875247) (xy 87.925656 -284.847538)
			(xy 87.926164 -284.821651) (xy 87.934263 -284.770513) (xy 87.950262 -284.721273) (xy 87.973768 -284.675141)
			(xy 88.0042 -284.633254) (xy 88.04081 -284.596644) (xy 88.082697 -284.566212) (xy 88.128829 -284.542706)
			(xy 88.178069 -284.526707) (xy 88.229207 -284.518608) (xy 88.280981 -284.518608) (xy 88.332119 -284.526707)
			(xy 88.381359 -284.542706) (xy 88.427491 -284.566212) (xy 88.469378 -284.596644) (xy 88.505988 -284.633254)
			(xy 88.53642 -284.675141) (xy 88.559926 -284.721273) (xy 88.575925 -284.770513) (xy 88.584024 -284.821651)
			(xy 88.584532 -284.847538) (xy 88.584058 -284.872872) (xy 88.583854 -284.874187) (xy 88.839284 -284.874187)
			(xy 88.839284 -284.820889) (xy 88.847227 -284.768185) (xy 88.862937 -284.717255) (xy 88.886063 -284.669234)
			(xy 88.916087 -284.625197) (xy 88.952339 -284.586126) (xy 88.99401 -284.552895) (xy 89.040168 -284.526246)
			(xy 89.089782 -284.506774) (xy 89.141744 -284.494914) (xy 89.194894 -284.490931) (xy 89.248044 -284.494914)
			(xy 89.300006 -284.506774) (xy 89.34962 -284.526246) (xy 89.395778 -284.552895) (xy 89.437449 -284.586126)
			(xy 89.473701 -284.625197) (xy 89.503725 -284.669234) (xy 89.526851 -284.717255) (xy 89.542561 -284.768185)
			(xy 89.550504 -284.820889) (xy 89.551002 -284.847538) (xy 89.550504 -284.874187) (xy 89.542561 -284.926891)
			(xy 89.526851 -284.977821) (xy 89.503725 -285.025842) (xy 89.473701 -285.069879) (xy 89.437449 -285.10895)
			(xy 89.395778 -285.142181) (xy 89.34962 -285.16883) (xy 89.300006 -285.188302) (xy 89.248044 -285.200162)
			(xy 89.194894 -285.204146) (xy 89.141744 -285.200162) (xy 89.089782 -285.188302) (xy 89.040168 -285.16883)
			(xy 88.99401 -285.142181) (xy 88.952339 -285.10895) (xy 88.916087 -285.069879) (xy 88.886063 -285.025842)
			(xy 88.862937 -284.977821) (xy 88.847227 -284.926891) (xy 88.839284 -284.874187) (xy 88.583854 -284.874187)
			(xy 88.576301 -284.922944) (xy 88.560975 -284.971239) (xy 88.538441 -285.016622) (xy 88.50923 -285.058022)
			(xy 88.47403 -285.094467) (xy 88.433668 -285.125098) (xy 88.389095 -285.149194) (xy 88.341361 -285.166187)
			(xy 88.316562 -285.171388) (xy 88.293702 -285.175706) (xy 88.088724 -285.530798) (xy 88.096344 -285.552642)
			(xy 88.104909 -285.578999) (xy 88.114106 -285.633646) (xy 88.114632 -285.661354) (xy 88.114124 -285.687241)
			(xy 88.114003 -285.688003) (xy 88.369384 -285.688003) (xy 88.369384 -285.634705) (xy 88.377327 -285.582001)
			(xy 88.393037 -285.531071) (xy 88.416163 -285.48305) (xy 88.446187 -285.439013) (xy 88.482439 -285.399942)
			(xy 88.52411 -285.366711) (xy 88.570268 -285.340062) (xy 88.619882 -285.32059) (xy 88.671844 -285.30873)
			(xy 88.724994 -285.304747) (xy 88.778144 -285.30873) (xy 88.830106 -285.32059) (xy 88.87972 -285.340062)
			(xy 88.925878 -285.366711) (xy 88.967549 -285.399942) (xy 89.003801 -285.439013) (xy 89.033825 -285.48305)
			(xy 89.056951 -285.531071) (xy 89.072661 -285.582001) (xy 89.080604 -285.634705) (xy 89.081102 -285.661354)
			(xy 89.335356 -285.661354) (xy 89.335864 -285.635467) (xy 89.343963 -285.584329) (xy 89.359962 -285.535089)
			(xy 89.383468 -285.488957) (xy 89.4139 -285.44707) (xy 89.45051 -285.41046) (xy 89.492397 -285.380028)
			(xy 89.538529 -285.356522) (xy 89.587769 -285.340523) (xy 89.638907 -285.332424) (xy 89.690681 -285.332424)
			(xy 89.741819 -285.340523) (xy 89.791059 -285.356522) (xy 89.837191 -285.380028) (xy 89.879078 -285.41046)
			(xy 89.915688 -285.44707) (xy 89.94612 -285.488957) (xy 89.969626 -285.535089) (xy 89.985625 -285.584329)
			(xy 89.993724 -285.635467) (xy 89.994232 -285.661354) (xy 90.275156 -285.661354) (xy 90.27559 -285.636007)
			(xy 90.28337 -285.585913) (xy 90.298725 -285.537599) (xy 90.321292 -285.492204) (xy 90.35054 -285.450798)
			(xy 90.385779 -285.414354) (xy 90.426181 -285.383733) (xy 90.470793 -285.359656) (xy 90.518564 -285.342688)
			(xy 90.54338 -285.337504) (xy 90.56624 -285.333186) (xy 90.771218 -284.978348) (xy 90.763344 -284.956504)
			(xy 90.754767 -284.930085) (xy 90.745569 -284.87531) (xy 90.745056 -284.847538) (xy 90.745564 -284.821651)
			(xy 90.753663 -284.770513) (xy 90.769662 -284.721273) (xy 90.793168 -284.675141) (xy 90.8236 -284.633254)
			(xy 90.86021 -284.596644) (xy 90.902097 -284.566212) (xy 90.948229 -284.542706) (xy 90.997469 -284.526707)
			(xy 91.048607 -284.518608) (xy 91.100381 -284.518608) (xy 91.151519 -284.526707) (xy 91.200759 -284.542706)
			(xy 91.246891 -284.566212) (xy 91.288778 -284.596644) (xy 91.325388 -284.633254) (xy 91.35582 -284.675141)
			(xy 91.379326 -284.721273) (xy 91.395325 -284.770513) (xy 91.403424 -284.821651) (xy 91.403932 -284.847538)
			(xy 91.403458 -284.872872) (xy 91.395701 -284.922944) (xy 91.380375 -284.971239) (xy 91.357841 -285.016622)
			(xy 91.32863 -285.058022) (xy 91.29343 -285.094467) (xy 91.253068 -285.125098) (xy 91.208495 -285.149194)
			(xy 91.160761 -285.166187) (xy 91.135962 -285.171388) (xy 91.113102 -285.175706) (xy 90.908124 -285.530544)
			(xy 90.915998 -285.552642) (xy 90.924622 -285.57899) (xy 90.933948 -285.633636) (xy 90.93454 -285.661354)
			(xy 91.214956 -285.661354) (xy 91.215464 -285.635447) (xy 91.22357 -285.58427) (xy 91.239582 -285.534991)
			(xy 91.263105 -285.488824) (xy 91.293561 -285.446905) (xy 91.330199 -285.410267) (xy 91.372118 -285.379811)
			(xy 91.418285 -285.356288) (xy 91.467564 -285.340276) (xy 91.518741 -285.33217) (xy 91.570555 -285.33217)
			(xy 91.621732 -285.340276) (xy 91.671011 -285.356288) (xy 91.717178 -285.379811) (xy 91.759097 -285.410267)
			(xy 91.795735 -285.446905) (xy 91.826191 -285.488824) (xy 91.849714 -285.534991) (xy 91.865726 -285.58427)
			(xy 91.873832 -285.635447) (xy 91.87434 -285.661354) (xy 92.154756 -285.661354) (xy 92.155232 -285.63602)
			(xy 92.16299 -285.585949) (xy 92.178317 -285.537654) (xy 92.20085 -285.492273) (xy 92.230061 -285.450872)
			(xy 92.265261 -285.414427) (xy 92.305622 -285.383796) (xy 92.350194 -285.3597) (xy 92.397927 -285.342705)
			(xy 92.422726 -285.337504) (xy 92.445586 -285.333186) (xy 92.650818 -284.97784) (xy 92.643198 -284.955996)
			(xy 92.634574 -284.929714) (xy 92.625259 -284.875193) (xy 92.624656 -284.847538) (xy 92.625164 -284.821631)
			(xy 92.63327 -284.770454) (xy 92.649282 -284.721175) (xy 92.672805 -284.675008) (xy 92.703261 -284.633089)
			(xy 92.739899 -284.596451) (xy 92.781818 -284.565995) (xy 92.827985 -284.542472) (xy 92.877264 -284.52646)
			(xy 92.928441 -284.518354) (xy 92.980255 -284.518354) (xy 93.031432 -284.52646) (xy 93.080711 -284.542472)
			(xy 93.126878 -284.565995) (xy 93.168797 -284.596451) (xy 93.205435 -284.633089) (xy 93.235891 -284.675008)
			(xy 93.259414 -284.721175) (xy 93.275426 -284.770454) (xy 93.283532 -284.821631) (xy 93.28404 -284.847538)
			(xy 93.283648 -284.872916) (xy 93.275873 -284.923072) (xy 93.260496 -284.971442) (xy 93.237881 -285.016882)
			(xy 93.208565 -285.058314) (xy 93.17324 -285.09476) (xy 93.132743 -285.125356) (xy 93.088033 -285.149379)
			(xy 93.040166 -285.166259) (xy 93.015308 -285.171388) (xy 92.992448 -285.175706) (xy 92.78747 -285.530544)
			(xy 92.795344 -285.552642) (xy 92.803916 -285.578997) (xy 92.813107 -285.633645) (xy 92.813632 -285.661354)
			(xy 93.094556 -285.661354) (xy 93.095064 -285.635467) (xy 93.103163 -285.584329) (xy 93.119162 -285.535089)
			(xy 93.142668 -285.488957) (xy 93.1731 -285.44707) (xy 93.20971 -285.41046) (xy 93.251597 -285.380028)
			(xy 93.297729 -285.356522) (xy 93.346969 -285.340523) (xy 93.398107 -285.332424) (xy 93.449881 -285.332424)
			(xy 93.501019 -285.340523) (xy 93.550259 -285.356522) (xy 93.596391 -285.380028) (xy 93.638278 -285.41046)
			(xy 93.674888 -285.44707) (xy 93.70532 -285.488957) (xy 93.728826 -285.535089) (xy 93.744825 -285.584329)
			(xy 93.752924 -285.635467) (xy 93.753432 -285.661354) (xy 94.034356 -285.661354) (xy 94.034832 -285.63602)
			(xy 94.04259 -285.585949) (xy 94.057917 -285.537654) (xy 94.08045 -285.492273) (xy 94.109661 -285.450872)
			(xy 94.144861 -285.414427) (xy 94.185222 -285.383796) (xy 94.229794 -285.3597) (xy 94.277527 -285.342705)
			(xy 94.302326 -285.337504) (xy 94.325186 -285.333186) (xy 94.530418 -284.97784) (xy 94.522798 -284.955996)
			(xy 94.514174 -284.929714) (xy 94.504859 -284.875193) (xy 94.504256 -284.847538) (xy 94.504764 -284.821631)
			(xy 94.51287 -284.770454) (xy 94.528882 -284.721175) (xy 94.552405 -284.675008) (xy 94.582861 -284.633089)
			(xy 94.619499 -284.596451) (xy 94.661418 -284.565995) (xy 94.707585 -284.542472) (xy 94.756864 -284.52646)
			(xy 94.808041 -284.518354) (xy 94.859855 -284.518354) (xy 94.911032 -284.52646) (xy 94.960311 -284.542472)
			(xy 95.006478 -284.565995) (xy 95.048397 -284.596451) (xy 95.085035 -284.633089) (xy 95.115491 -284.675008)
			(xy 95.139014 -284.721175) (xy 95.155026 -284.770454) (xy 95.163132 -284.821631) (xy 95.16364 -284.847538)
			(xy 95.163248 -284.872916) (xy 95.155473 -284.923072) (xy 95.140096 -284.971442) (xy 95.117481 -285.016882)
			(xy 95.088165 -285.058314) (xy 95.05284 -285.09476) (xy 95.012343 -285.125356) (xy 94.967633 -285.149379)
			(xy 94.919766 -285.166259) (xy 94.894908 -285.171388) (xy 94.872048 -285.175706) (xy 94.66707 -285.530544)
			(xy 94.674944 -285.552642) (xy 94.683516 -285.578997) (xy 94.692707 -285.633645) (xy 94.693232 -285.661354)
			(xy 94.974156 -285.661354) (xy 94.974664 -285.635467) (xy 94.982763 -285.584329) (xy 94.998762 -285.535089)
			(xy 95.022268 -285.488957) (xy 95.0527 -285.44707) (xy 95.08931 -285.41046) (xy 95.131197 -285.380028)
			(xy 95.177329 -285.356522) (xy 95.226569 -285.340523) (xy 95.277707 -285.332424) (xy 95.329481 -285.332424)
			(xy 95.380619 -285.340523) (xy 95.429859 -285.356522) (xy 95.475991 -285.380028) (xy 95.517878 -285.41046)
			(xy 95.554488 -285.44707) (xy 95.58492 -285.488957) (xy 95.608426 -285.535089) (xy 95.624425 -285.584329)
			(xy 95.632524 -285.635467) (xy 95.633032 -285.661354) (xy 95.913956 -285.661354) (xy 95.914432 -285.63602)
			(xy 95.92219 -285.585949) (xy 95.937517 -285.537654) (xy 95.96005 -285.492273) (xy 95.989261 -285.450872)
			(xy 96.024461 -285.414427) (xy 96.064822 -285.383796) (xy 96.109394 -285.3597) (xy 96.157127 -285.342705)
			(xy 96.181926 -285.337504) (xy 96.204786 -285.333186) (xy 96.410018 -284.97784) (xy 96.402398 -284.955996)
			(xy 96.393774 -284.929714) (xy 96.384459 -284.875193) (xy 96.383856 -284.847538) (xy 96.384364 -284.821631)
			(xy 96.39247 -284.770454) (xy 96.408482 -284.721175) (xy 96.432005 -284.675008) (xy 96.462461 -284.633089)
			(xy 96.499099 -284.596451) (xy 96.541018 -284.565995) (xy 96.587185 -284.542472) (xy 96.636464 -284.52646)
			(xy 96.687641 -284.518354) (xy 96.739455 -284.518354) (xy 96.790632 -284.52646) (xy 96.839911 -284.542472)
			(xy 96.886078 -284.565995) (xy 96.927997 -284.596451) (xy 96.964635 -284.633089) (xy 96.995091 -284.675008)
			(xy 97.018614 -284.721175) (xy 97.034626 -284.770454) (xy 97.042732 -284.821631) (xy 97.04324 -284.847538)
			(xy 97.042848 -284.872916) (xy 97.035073 -284.923072) (xy 97.019696 -284.971442) (xy 96.997081 -285.016882)
			(xy 96.967765 -285.058314) (xy 96.93244 -285.09476) (xy 96.891943 -285.125356) (xy 96.847233 -285.149379)
			(xy 96.799366 -285.166259) (xy 96.774508 -285.171388) (xy 96.751648 -285.175706) (xy 96.54667 -285.530544)
			(xy 96.554544 -285.552642) (xy 96.563116 -285.578997) (xy 96.572307 -285.633645) (xy 96.572832 -285.661354)
			(xy 96.853756 -285.661354) (xy 96.854264 -285.635467) (xy 96.862363 -285.584329) (xy 96.878362 -285.535089)
			(xy 96.901868 -285.488957) (xy 96.9323 -285.44707) (xy 96.96891 -285.41046) (xy 97.010797 -285.380028)
			(xy 97.056929 -285.356522) (xy 97.106169 -285.340523) (xy 97.157307 -285.332424) (xy 97.209081 -285.332424)
			(xy 97.260219 -285.340523) (xy 97.309459 -285.356522) (xy 97.355591 -285.380028) (xy 97.397478 -285.41046)
			(xy 97.434088 -285.44707) (xy 97.46452 -285.488957) (xy 97.488026 -285.535089) (xy 97.504025 -285.584329)
			(xy 97.512124 -285.635467) (xy 97.512632 -285.661354) (xy 97.793556 -285.661354) (xy 97.794032 -285.63602)
			(xy 97.80179 -285.585949) (xy 97.817117 -285.537654) (xy 97.83965 -285.492273) (xy 97.868861 -285.450872)
			(xy 97.904061 -285.414427) (xy 97.944422 -285.383796) (xy 97.988994 -285.3597) (xy 98.036727 -285.342705)
			(xy 98.061526 -285.337504) (xy 98.084386 -285.333186) (xy 98.289618 -284.97784) (xy 98.281998 -284.955996)
			(xy 98.273374 -284.929714) (xy 98.264059 -284.875193) (xy 98.263456 -284.847538) (xy 98.263964 -284.821631)
			(xy 98.27207 -284.770454) (xy 98.288082 -284.721175) (xy 98.311605 -284.675008) (xy 98.342061 -284.633089)
			(xy 98.378699 -284.596451) (xy 98.420618 -284.565995) (xy 98.466785 -284.542472) (xy 98.516064 -284.52646)
			(xy 98.567241 -284.518354) (xy 98.619055 -284.518354) (xy 98.670232 -284.52646) (xy 98.719511 -284.542472)
			(xy 98.765678 -284.565995) (xy 98.807597 -284.596451) (xy 98.844235 -284.633089) (xy 98.874691 -284.675008)
			(xy 98.898214 -284.721175) (xy 98.914226 -284.770454) (xy 98.922332 -284.821631) (xy 98.92284 -284.847538)
			(xy 98.922448 -284.872916) (xy 98.914673 -284.923072) (xy 98.899296 -284.971442) (xy 98.876681 -285.016882)
			(xy 98.847365 -285.058314) (xy 98.81204 -285.09476) (xy 98.771543 -285.125356) (xy 98.726833 -285.149379)
			(xy 98.678966 -285.166259) (xy 98.654108 -285.171388) (xy 98.631248 -285.175706) (xy 98.42627 -285.530544)
			(xy 98.434144 -285.552642) (xy 98.442716 -285.578997) (xy 98.451907 -285.633645) (xy 98.452432 -285.661354)
			(xy 98.733356 -285.661354) (xy 98.733864 -285.635467) (xy 98.741963 -285.584329) (xy 98.757962 -285.535089)
			(xy 98.781468 -285.488957) (xy 98.8119 -285.44707) (xy 98.84851 -285.41046) (xy 98.890397 -285.380028)
			(xy 98.936529 -285.356522) (xy 98.985769 -285.340523) (xy 99.036907 -285.332424) (xy 99.088681 -285.332424)
			(xy 99.139819 -285.340523) (xy 99.189059 -285.356522) (xy 99.235191 -285.380028) (xy 99.277078 -285.41046)
			(xy 99.313688 -285.44707) (xy 99.34412 -285.488957) (xy 99.367626 -285.535089) (xy 99.383625 -285.584329)
			(xy 99.391724 -285.635467) (xy 99.392232 -285.661354) (xy 99.391685 -285.688998) (xy 99.382491 -285.743516)
			(xy 99.373944 -285.769812) (xy 99.366324 -285.79191) (xy 99.571556 -286.147256) (xy 99.594416 -286.151574)
			(xy 99.619227 -286.156786) (xy 99.667004 -286.173734) (xy 99.711623 -286.197799) (xy 99.75203 -286.228413)
			(xy 99.787272 -286.264855) (xy 99.816517 -286.306263) (xy 99.839076 -286.351662) (xy 99.854417 -286.399979)
			(xy 99.862177 -286.450077) (xy 99.86264 -286.475424) (xy 99.862132 -286.501331) (xy 99.854026 -286.552508)
			(xy 99.838014 -286.601787) (xy 99.814491 -286.647954) (xy 99.784035 -286.689873) (xy 99.747397 -286.726511)
			(xy 99.705478 -286.756967) (xy 99.659311 -286.78049) (xy 99.610032 -286.796502) (xy 99.558855 -286.804608)
			(xy 99.507041 -286.804608) (xy 99.455864 -286.796502) (xy 99.406585 -286.78049) (xy 99.360418 -286.756967)
			(xy 99.318499 -286.726511) (xy 99.281861 -286.689873) (xy 99.251405 -286.647954) (xy 99.227882 -286.601787)
			(xy 99.21187 -286.552508) (xy 99.203764 -286.501331) (xy 99.203256 -286.475424) (xy 99.203853 -286.447707)
			(xy 99.213174 -286.39306) (xy 99.221798 -286.366712) (xy 99.229672 -286.344614) (xy 99.024694 -285.989522)
			(xy 99.00158 -285.985204) (xy 98.976764 -285.980016) (xy 98.928984 -285.963065) (xy 98.884365 -285.938998)
			(xy 98.843957 -285.908381) (xy 98.808716 -285.871936) (xy 98.779471 -285.830525) (xy 98.756913 -285.785123)
			(xy 98.741575 -285.736802) (xy 98.733818 -285.686702) (xy 98.733356 -285.661354) (xy 98.452432 -285.661354)
			(xy 98.451924 -285.687241) (xy 98.443825 -285.738379) (xy 98.427826 -285.787619) (xy 98.40432 -285.833751)
			(xy 98.373888 -285.875638) (xy 98.337278 -285.912248) (xy 98.295391 -285.94268) (xy 98.249259 -285.966186)
			(xy 98.200019 -285.982185) (xy 98.148881 -285.990284) (xy 98.097107 -285.990284) (xy 98.045969 -285.982185)
			(xy 97.996729 -285.966186) (xy 97.950597 -285.94268) (xy 97.90871 -285.912248) (xy 97.8721 -285.875638)
			(xy 97.841668 -285.833751) (xy 97.818162 -285.787619) (xy 97.802163 -285.738379) (xy 97.794064 -285.687241)
			(xy 97.793556 -285.661354) (xy 97.512632 -285.661354) (xy 97.512085 -285.688998) (xy 97.502891 -285.743516)
			(xy 97.494344 -285.769812) (xy 97.486724 -285.79191) (xy 97.691956 -286.147256) (xy 97.714816 -286.151574)
			(xy 97.739627 -286.156786) (xy 97.787404 -286.173734) (xy 97.832023 -286.197799) (xy 97.87243 -286.228413)
			(xy 97.907672 -286.264855) (xy 97.936917 -286.306263) (xy 97.959476 -286.351662) (xy 97.974817 -286.399979)
			(xy 97.982577 -286.450077) (xy 97.98304 -286.475424) (xy 97.982532 -286.501331) (xy 97.982414 -286.502073)
			(xy 98.237284 -286.502073) (xy 98.237284 -286.448775) (xy 98.245227 -286.396071) (xy 98.260937 -286.345141)
			(xy 98.284063 -286.29712) (xy 98.314087 -286.253083) (xy 98.350339 -286.214012) (xy 98.39201 -286.180781)
			(xy 98.438168 -286.154132) (xy 98.487782 -286.13466) (xy 98.539744 -286.1228) (xy 98.592894 -286.118817)
			(xy 98.646044 -286.1228) (xy 98.698006 -286.13466) (xy 98.74762 -286.154132) (xy 98.793778 -286.180781)
			(xy 98.835449 -286.214012) (xy 98.871701 -286.253083) (xy 98.901725 -286.29712) (xy 98.924851 -286.345141)
			(xy 98.940561 -286.396071) (xy 98.948504 -286.448775) (xy 98.949002 -286.475424) (xy 98.948504 -286.502073)
			(xy 98.940561 -286.554777) (xy 98.924851 -286.605707) (xy 98.901725 -286.653728) (xy 98.871701 -286.697765)
			(xy 98.835449 -286.736836) (xy 98.793778 -286.770067) (xy 98.74762 -286.796716) (xy 98.698006 -286.816188)
			(xy 98.646044 -286.828048) (xy 98.592894 -286.832032) (xy 98.539744 -286.828048) (xy 98.487782 -286.816188)
			(xy 98.438168 -286.796716) (xy 98.39201 -286.770067) (xy 98.350339 -286.736836) (xy 98.314087 -286.697765)
			(xy 98.284063 -286.653728) (xy 98.260937 -286.605707) (xy 98.245227 -286.554777) (xy 98.237284 -286.502073)
			(xy 97.982414 -286.502073) (xy 97.974426 -286.552508) (xy 97.958414 -286.601787) (xy 97.934891 -286.647954)
			(xy 97.904435 -286.689873) (xy 97.867797 -286.726511) (xy 97.825878 -286.756967) (xy 97.779711 -286.78049)
			(xy 97.730432 -286.796502) (xy 97.679255 -286.804608) (xy 97.627441 -286.804608) (xy 97.576264 -286.796502)
			(xy 97.526985 -286.78049) (xy 97.480818 -286.756967) (xy 97.438899 -286.726511) (xy 97.402261 -286.689873)
			(xy 97.371805 -286.647954) (xy 97.348282 -286.601787) (xy 97.33227 -286.552508) (xy 97.324164 -286.501331)
			(xy 97.323656 -286.475424) (xy 97.324253 -286.447707) (xy 97.333574 -286.39306) (xy 97.342198 -286.366712)
			(xy 97.350072 -286.344614) (xy 97.145094 -285.989522) (xy 97.12198 -285.985204) (xy 97.097164 -285.980016)
			(xy 97.049384 -285.963065) (xy 97.004765 -285.938998) (xy 96.964357 -285.908381) (xy 96.929116 -285.871936)
			(xy 96.899871 -285.830525) (xy 96.877313 -285.785123) (xy 96.861975 -285.736802) (xy 96.854218 -285.686702)
			(xy 96.853756 -285.661354) (xy 96.572832 -285.661354) (xy 96.572324 -285.687241) (xy 96.564225 -285.738379)
			(xy 96.548226 -285.787619) (xy 96.52472 -285.833751) (xy 96.494288 -285.875638) (xy 96.457678 -285.912248)
			(xy 96.415791 -285.94268) (xy 96.369659 -285.966186) (xy 96.320419 -285.982185) (xy 96.269281 -285.990284)
			(xy 96.217507 -285.990284) (xy 96.166369 -285.982185) (xy 96.117129 -285.966186) (xy 96.070997 -285.94268)
			(xy 96.02911 -285.912248) (xy 95.9925 -285.875638) (xy 95.962068 -285.833751) (xy 95.938562 -285.787619)
			(xy 95.922563 -285.738379) (xy 95.914464 -285.687241) (xy 95.913956 -285.661354) (xy 95.633032 -285.661354)
			(xy 95.632485 -285.688998) (xy 95.623291 -285.743516) (xy 95.614744 -285.769812) (xy 95.607124 -285.79191)
			(xy 95.812356 -286.147256) (xy 95.835216 -286.151574) (xy 95.860027 -286.156786) (xy 95.907804 -286.173734)
			(xy 95.952423 -286.197799) (xy 95.99283 -286.228413) (xy 96.028072 -286.264855) (xy 96.057317 -286.306263)
			(xy 96.079876 -286.351662) (xy 96.095217 -286.399979) (xy 96.102977 -286.450077) (xy 96.10344 -286.475424)
			(xy 96.102932 -286.501331) (xy 96.102814 -286.502073) (xy 96.357684 -286.502073) (xy 96.357684 -286.448775)
			(xy 96.365627 -286.396071) (xy 96.381337 -286.345141) (xy 96.404463 -286.29712) (xy 96.434487 -286.253083)
			(xy 96.470739 -286.214012) (xy 96.51241 -286.180781) (xy 96.558568 -286.154132) (xy 96.608182 -286.13466)
			(xy 96.660144 -286.1228) (xy 96.713294 -286.118817) (xy 96.766444 -286.1228) (xy 96.818406 -286.13466)
			(xy 96.86802 -286.154132) (xy 96.914178 -286.180781) (xy 96.955849 -286.214012) (xy 96.992101 -286.253083)
			(xy 97.022125 -286.29712) (xy 97.045251 -286.345141) (xy 97.060961 -286.396071) (xy 97.068904 -286.448775)
			(xy 97.069402 -286.475424) (xy 97.068904 -286.502073) (xy 97.060961 -286.554777) (xy 97.045251 -286.605707)
			(xy 97.022125 -286.653728) (xy 96.992101 -286.697765) (xy 96.955849 -286.736836) (xy 96.914178 -286.770067)
			(xy 96.86802 -286.796716) (xy 96.818406 -286.816188) (xy 96.766444 -286.828048) (xy 96.713294 -286.832032)
			(xy 96.660144 -286.828048) (xy 96.608182 -286.816188) (xy 96.558568 -286.796716) (xy 96.51241 -286.770067)
			(xy 96.470739 -286.736836) (xy 96.434487 -286.697765) (xy 96.404463 -286.653728) (xy 96.381337 -286.605707)
			(xy 96.365627 -286.554777) (xy 96.357684 -286.502073) (xy 96.102814 -286.502073) (xy 96.094826 -286.552508)
			(xy 96.078814 -286.601787) (xy 96.055291 -286.647954) (xy 96.024835 -286.689873) (xy 95.988197 -286.726511)
			(xy 95.946278 -286.756967) (xy 95.900111 -286.78049) (xy 95.850832 -286.796502) (xy 95.799655 -286.804608)
			(xy 95.747841 -286.804608) (xy 95.696664 -286.796502) (xy 95.647385 -286.78049) (xy 95.601218 -286.756967)
			(xy 95.559299 -286.726511) (xy 95.522661 -286.689873) (xy 95.492205 -286.647954) (xy 95.468682 -286.601787)
			(xy 95.45267 -286.552508) (xy 95.444564 -286.501331) (xy 95.444056 -286.475424) (xy 95.444653 -286.447707)
			(xy 95.453974 -286.39306) (xy 95.462598 -286.366712) (xy 95.470472 -286.344614) (xy 95.265494 -285.989522)
			(xy 95.24238 -285.985204) (xy 95.217564 -285.980016) (xy 95.169784 -285.963065) (xy 95.125165 -285.938998)
			(xy 95.084757 -285.908381) (xy 95.049516 -285.871936) (xy 95.020271 -285.830525) (xy 94.997713 -285.785123)
			(xy 94.982375 -285.736802) (xy 94.974618 -285.686702) (xy 94.974156 -285.661354) (xy 94.693232 -285.661354)
			(xy 94.692724 -285.687241) (xy 94.684625 -285.738379) (xy 94.668626 -285.787619) (xy 94.64512 -285.833751)
			(xy 94.614688 -285.875638) (xy 94.578078 -285.912248) (xy 94.536191 -285.94268) (xy 94.490059 -285.966186)
			(xy 94.440819 -285.982185) (xy 94.389681 -285.990284) (xy 94.337907 -285.990284) (xy 94.286769 -285.982185)
			(xy 94.237529 -285.966186) (xy 94.191397 -285.94268) (xy 94.14951 -285.912248) (xy 94.1129 -285.875638)
			(xy 94.082468 -285.833751) (xy 94.058962 -285.787619) (xy 94.042963 -285.738379) (xy 94.034864 -285.687241)
			(xy 94.034356 -285.661354) (xy 93.753432 -285.661354) (xy 93.752885 -285.688998) (xy 93.743691 -285.743516)
			(xy 93.735144 -285.769812) (xy 93.727524 -285.79191) (xy 93.932756 -286.147256) (xy 93.955616 -286.151574)
			(xy 93.980427 -286.156786) (xy 94.028204 -286.173734) (xy 94.072823 -286.197799) (xy 94.11323 -286.228413)
			(xy 94.148472 -286.264855) (xy 94.177717 -286.306263) (xy 94.200276 -286.351662) (xy 94.215617 -286.399979)
			(xy 94.223377 -286.450077) (xy 94.22384 -286.475424) (xy 94.223332 -286.501331) (xy 94.223214 -286.502073)
			(xy 94.478084 -286.502073) (xy 94.478084 -286.448775) (xy 94.486027 -286.396071) (xy 94.501737 -286.345141)
			(xy 94.524863 -286.29712) (xy 94.554887 -286.253083) (xy 94.591139 -286.214012) (xy 94.63281 -286.180781)
			(xy 94.678968 -286.154132) (xy 94.728582 -286.13466) (xy 94.780544 -286.1228) (xy 94.833694 -286.118817)
			(xy 94.886844 -286.1228) (xy 94.938806 -286.13466) (xy 94.98842 -286.154132) (xy 95.034578 -286.180781)
			(xy 95.076249 -286.214012) (xy 95.112501 -286.253083) (xy 95.142525 -286.29712) (xy 95.165651 -286.345141)
			(xy 95.181361 -286.396071) (xy 95.189304 -286.448775) (xy 95.189802 -286.475424) (xy 95.189304 -286.502073)
			(xy 95.181361 -286.554777) (xy 95.165651 -286.605707) (xy 95.142525 -286.653728) (xy 95.112501 -286.697765)
			(xy 95.076249 -286.736836) (xy 95.034578 -286.770067) (xy 94.98842 -286.796716) (xy 94.938806 -286.816188)
			(xy 94.886844 -286.828048) (xy 94.833694 -286.832032) (xy 94.780544 -286.828048) (xy 94.728582 -286.816188)
			(xy 94.678968 -286.796716) (xy 94.63281 -286.770067) (xy 94.591139 -286.736836) (xy 94.554887 -286.697765)
			(xy 94.524863 -286.653728) (xy 94.501737 -286.605707) (xy 94.486027 -286.554777) (xy 94.478084 -286.502073)
			(xy 94.223214 -286.502073) (xy 94.215226 -286.552508) (xy 94.199214 -286.601787) (xy 94.175691 -286.647954)
			(xy 94.145235 -286.689873) (xy 94.108597 -286.726511) (xy 94.066678 -286.756967) (xy 94.020511 -286.78049)
			(xy 93.971232 -286.796502) (xy 93.920055 -286.804608) (xy 93.868241 -286.804608) (xy 93.817064 -286.796502)
			(xy 93.767785 -286.78049) (xy 93.721618 -286.756967) (xy 93.679699 -286.726511) (xy 93.643061 -286.689873)
			(xy 93.612605 -286.647954) (xy 93.589082 -286.601787) (xy 93.57307 -286.552508) (xy 93.564964 -286.501331)
			(xy 93.564456 -286.475424) (xy 93.565053 -286.447707) (xy 93.574374 -286.39306) (xy 93.582998 -286.366712)
			(xy 93.590872 -286.344614) (xy 93.385894 -285.989522) (xy 93.36278 -285.985204) (xy 93.337964 -285.980016)
			(xy 93.290184 -285.963065) (xy 93.245565 -285.938998) (xy 93.205157 -285.908381) (xy 93.169916 -285.871936)
			(xy 93.140671 -285.830525) (xy 93.118113 -285.785123) (xy 93.102775 -285.736802) (xy 93.095018 -285.686702)
			(xy 93.094556 -285.661354) (xy 92.813632 -285.661354) (xy 92.813124 -285.687241) (xy 92.805025 -285.738379)
			(xy 92.789026 -285.787619) (xy 92.76552 -285.833751) (xy 92.735088 -285.875638) (xy 92.698478 -285.912248)
			(xy 92.656591 -285.94268) (xy 92.610459 -285.966186) (xy 92.561219 -285.982185) (xy 92.510081 -285.990284)
			(xy 92.458307 -285.990284) (xy 92.407169 -285.982185) (xy 92.357929 -285.966186) (xy 92.311797 -285.94268)
			(xy 92.26991 -285.912248) (xy 92.2333 -285.875638) (xy 92.202868 -285.833751) (xy 92.179362 -285.787619)
			(xy 92.163363 -285.738379) (xy 92.155264 -285.687241) (xy 92.154756 -285.661354) (xy 91.87434 -285.661354)
			(xy 91.873738 -285.689071) (xy 91.86442 -285.743718) (xy 91.855798 -285.770066) (xy 91.847924 -285.792164)
			(xy 92.053156 -286.147256) (xy 92.076016 -286.151574) (xy 92.100827 -286.156786) (xy 92.148604 -286.173734)
			(xy 92.193223 -286.197799) (xy 92.23363 -286.228413) (xy 92.268872 -286.264855) (xy 92.298117 -286.306263)
			(xy 92.320676 -286.351662) (xy 92.336017 -286.399979) (xy 92.343777 -286.450077) (xy 92.34424 -286.475424)
			(xy 92.343732 -286.501331) (xy 92.343614 -286.502073) (xy 92.598738 -286.502073) (xy 92.598738 -286.448775)
			(xy 92.606681 -286.396071) (xy 92.622391 -286.345141) (xy 92.645517 -286.29712) (xy 92.675541 -286.253083)
			(xy 92.711793 -286.214012) (xy 92.753464 -286.180781) (xy 92.799622 -286.154132) (xy 92.849236 -286.13466)
			(xy 92.901198 -286.1228) (xy 92.954348 -286.118817) (xy 93.007498 -286.1228) (xy 93.05946 -286.13466)
			(xy 93.109074 -286.154132) (xy 93.155232 -286.180781) (xy 93.196903 -286.214012) (xy 93.233155 -286.253083)
			(xy 93.263179 -286.29712) (xy 93.286305 -286.345141) (xy 93.302015 -286.396071) (xy 93.309958 -286.448775)
			(xy 93.310456 -286.475424) (xy 93.309958 -286.502073) (xy 93.302015 -286.554777) (xy 93.286305 -286.605707)
			(xy 93.263179 -286.653728) (xy 93.233155 -286.697765) (xy 93.196903 -286.736836) (xy 93.155232 -286.770067)
			(xy 93.109074 -286.796716) (xy 93.05946 -286.816188) (xy 93.007498 -286.828048) (xy 92.954348 -286.832032)
			(xy 92.901198 -286.828048) (xy 92.849236 -286.816188) (xy 92.799622 -286.796716) (xy 92.753464 -286.770067)
			(xy 92.711793 -286.736836) (xy 92.675541 -286.697765) (xy 92.645517 -286.653728) (xy 92.622391 -286.605707)
			(xy 92.606681 -286.554777) (xy 92.598738 -286.502073) (xy 92.343614 -286.502073) (xy 92.335626 -286.552508)
			(xy 92.319614 -286.601787) (xy 92.296091 -286.647954) (xy 92.265635 -286.689873) (xy 92.228997 -286.726511)
			(xy 92.187078 -286.756967) (xy 92.140911 -286.78049) (xy 92.091632 -286.796502) (xy 92.040455 -286.804608)
			(xy 91.988641 -286.804608) (xy 91.937464 -286.796502) (xy 91.888185 -286.78049) (xy 91.842018 -286.756967)
			(xy 91.800099 -286.726511) (xy 91.763461 -286.689873) (xy 91.733005 -286.647954) (xy 91.709482 -286.601787)
			(xy 91.69347 -286.552508) (xy 91.685364 -286.501331) (xy 91.684856 -286.475424) (xy 91.685453 -286.447707)
			(xy 91.694774 -286.39306) (xy 91.703398 -286.366712) (xy 91.711272 -286.344614) (xy 91.50604 -285.989522)
			(xy 91.48318 -285.985204) (xy 91.458364 -285.980016) (xy 91.410584 -285.963065) (xy 91.365965 -285.938998)
			(xy 91.325557 -285.908381) (xy 91.290316 -285.871936) (xy 91.261071 -285.830525) (xy 91.238513 -285.785123)
			(xy 91.223175 -285.736802) (xy 91.215418 -285.686702) (xy 91.214956 -285.661354) (xy 90.93454 -285.661354)
			(xy 90.934032 -285.687261) (xy 90.925926 -285.738438) (xy 90.909914 -285.787717) (xy 90.886391 -285.833884)
			(xy 90.855935 -285.875803) (xy 90.819297 -285.912441) (xy 90.777378 -285.942897) (xy 90.731211 -285.96642)
			(xy 90.681932 -285.982432) (xy 90.630755 -285.990538) (xy 90.578941 -285.990538) (xy 90.527764 -285.982432)
			(xy 90.478485 -285.96642) (xy 90.432318 -285.942897) (xy 90.390399 -285.912441) (xy 90.353761 -285.875803)
			(xy 90.323305 -285.833884) (xy 90.299782 -285.787717) (xy 90.28377 -285.738438) (xy 90.275664 -285.687261)
			(xy 90.275156 -285.661354) (xy 89.994232 -285.661354) (xy 89.993689 -285.689062) (xy 89.984503 -285.743708)
			(xy 89.975944 -285.770066) (xy 89.96807 -285.792164) (xy 90.173302 -286.147256) (xy 90.196162 -286.151574)
			(xy 90.220961 -286.156781) (xy 90.268701 -286.173765) (xy 90.31328 -286.197855) (xy 90.353647 -286.228483)
			(xy 90.388851 -286.264927) (xy 90.418064 -286.30633) (xy 90.440597 -286.351715) (xy 90.455919 -286.400014)
			(xy 90.46367 -286.450088) (xy 90.464132 -286.475424) (xy 90.463624 -286.501311) (xy 90.463503 -286.502073)
			(xy 90.718884 -286.502073) (xy 90.718884 -286.448775) (xy 90.726827 -286.396071) (xy 90.742537 -286.345141)
			(xy 90.765663 -286.29712) (xy 90.795687 -286.253083) (xy 90.831939 -286.214012) (xy 90.87361 -286.180781)
			(xy 90.919768 -286.154132) (xy 90.969382 -286.13466) (xy 91.021344 -286.1228) (xy 91.074494 -286.118817)
			(xy 91.127644 -286.1228) (xy 91.179606 -286.13466) (xy 91.22922 -286.154132) (xy 91.275378 -286.180781)
			(xy 91.317049 -286.214012) (xy 91.353301 -286.253083) (xy 91.383325 -286.29712) (xy 91.406451 -286.345141)
			(xy 91.422161 -286.396071) (xy 91.430104 -286.448775) (xy 91.430602 -286.475424) (xy 91.430104 -286.502073)
			(xy 91.422161 -286.554777) (xy 91.406451 -286.605707) (xy 91.383325 -286.653728) (xy 91.353301 -286.697765)
			(xy 91.317049 -286.736836) (xy 91.275378 -286.770067) (xy 91.22922 -286.796716) (xy 91.179606 -286.816188)
			(xy 91.127644 -286.828048) (xy 91.074494 -286.832032) (xy 91.021344 -286.828048) (xy 90.969382 -286.816188)
			(xy 90.919768 -286.796716) (xy 90.87361 -286.770067) (xy 90.831939 -286.736836) (xy 90.795687 -286.697765)
			(xy 90.765663 -286.653728) (xy 90.742537 -286.605707) (xy 90.726827 -286.554777) (xy 90.718884 -286.502073)
			(xy 90.463503 -286.502073) (xy 90.455525 -286.552449) (xy 90.439526 -286.601689) (xy 90.41602 -286.647821)
			(xy 90.385588 -286.689708) (xy 90.348978 -286.726318) (xy 90.307091 -286.75675) (xy 90.260959 -286.780256)
			(xy 90.211719 -286.796255) (xy 90.160581 -286.804354) (xy 90.108807 -286.804354) (xy 90.057669 -286.796255)
			(xy 90.008429 -286.780256) (xy 89.962297 -286.75675) (xy 89.92041 -286.726318) (xy 89.8838 -286.689708)
			(xy 89.853368 -286.647821) (xy 89.829862 -286.601689) (xy 89.813863 -286.552449) (xy 89.805764 -286.501311)
			(xy 89.805256 -286.475424) (xy 89.805793 -286.447716) (xy 89.814983 -286.393069) (xy 89.823544 -286.366712)
			(xy 89.831418 -286.344614) (xy 89.626186 -285.989522) (xy 89.603326 -285.985204) (xy 89.57852 -285.980026)
			(xy 89.530779 -285.963039) (xy 89.486199 -285.938946) (xy 89.445832 -285.908314) (xy 89.410627 -285.871866)
			(xy 89.381416 -285.83046) (xy 89.358884 -285.785071) (xy 89.343564 -285.736769) (xy 89.335817 -285.686691)
			(xy 89.335356 -285.661354) (xy 89.081102 -285.661354) (xy 89.080604 -285.688003) (xy 89.072661 -285.740707)
			(xy 89.056951 -285.791637) (xy 89.033825 -285.839658) (xy 89.003801 -285.883695) (xy 88.967549 -285.922766)
			(xy 88.925878 -285.955997) (xy 88.87972 -285.982646) (xy 88.830106 -286.002118) (xy 88.778144 -286.013978)
			(xy 88.724994 -286.017962) (xy 88.671844 -286.013978) (xy 88.619882 -286.002118) (xy 88.570268 -285.982646)
			(xy 88.52411 -285.955997) (xy 88.482439 -285.922766) (xy 88.446187 -285.883695) (xy 88.416163 -285.839658)
			(xy 88.393037 -285.791637) (xy 88.377327 -285.740707) (xy 88.369384 -285.688003) (xy 88.114003 -285.688003)
			(xy 88.106025 -285.738379) (xy 88.090026 -285.787619) (xy 88.06652 -285.833751) (xy 88.036088 -285.875638)
			(xy 87.999478 -285.912248) (xy 87.957591 -285.94268) (xy 87.911459 -285.966186) (xy 87.862219 -285.982185)
			(xy 87.811081 -285.990284) (xy 87.759307 -285.990284) (xy 87.708169 -285.982185) (xy 87.658929 -285.966186)
			(xy 87.612797 -285.94268) (xy 87.57091 -285.912248) (xy 87.5343 -285.875638) (xy 87.503868 -285.833751)
			(xy 87.480362 -285.787619) (xy 87.464363 -285.738379) (xy 87.456264 -285.687241) (xy 87.455756 -285.661354)
			(xy 87.201502 -285.661354) (xy 87.201004 -285.688003) (xy 87.193061 -285.740707) (xy 87.177351 -285.791637)
			(xy 87.154225 -285.839658) (xy 87.124201 -285.883695) (xy 87.087949 -285.922766) (xy 87.046278 -285.955997)
			(xy 87.00012 -285.982646) (xy 86.950506 -286.002118) (xy 86.898544 -286.013978) (xy 86.845394 -286.017962)
			(xy 86.792244 -286.013978) (xy 86.740282 -286.002118) (xy 86.690668 -285.982646) (xy 86.64451 -285.955997)
			(xy 86.602839 -285.922766) (xy 86.566587 -285.883695) (xy 86.536563 -285.839658) (xy 86.513437 -285.791637)
			(xy 86.497727 -285.740707) (xy 86.489784 -285.688003) (xy 86.261204 -285.688003) (xy 86.253261 -285.740707)
			(xy 86.237551 -285.791637) (xy 86.214425 -285.839658) (xy 86.184401 -285.883695) (xy 86.148149 -285.922766)
			(xy 86.106478 -285.955997) (xy 86.06032 -285.982646) (xy 86.010706 -286.002118) (xy 85.958744 -286.013978)
			(xy 85.905594 -286.017962) (xy 85.852444 -286.013978) (xy 85.800482 -286.002118) (xy 85.750868 -285.982646)
			(xy 85.70471 -285.955997) (xy 85.663039 -285.922766) (xy 85.626787 -285.883695) (xy 85.596763 -285.839658)
			(xy 85.573637 -285.791637) (xy 85.557927 -285.740707) (xy 85.549984 -285.688003) (xy 84.734146 -285.688003)
			(xy 84.734146 -286.502073) (xy 85.080084 -286.502073) (xy 85.080084 -286.448775) (xy 85.088027 -286.396071)
			(xy 85.103737 -286.345141) (xy 85.126863 -286.29712) (xy 85.156887 -286.253083) (xy 85.193139 -286.214012)
			(xy 85.23481 -286.180781) (xy 85.280968 -286.154132) (xy 85.330582 -286.13466) (xy 85.382544 -286.1228)
			(xy 85.435694 -286.118817) (xy 85.488844 -286.1228) (xy 85.540806 -286.13466) (xy 85.59042 -286.154132)
			(xy 85.636578 -286.180781) (xy 85.678249 -286.214012) (xy 85.714501 -286.253083) (xy 85.744525 -286.29712)
			(xy 85.767651 -286.345141) (xy 85.783361 -286.396071) (xy 85.791304 -286.448775) (xy 85.791802 -286.475424)
			(xy 86.046056 -286.475424) (xy 86.046564 -286.449537) (xy 86.054663 -286.398399) (xy 86.070662 -286.349159)
			(xy 86.094168 -286.303027) (xy 86.1246 -286.26114) (xy 86.16121 -286.22453) (xy 86.203097 -286.194098)
			(xy 86.249229 -286.170592) (xy 86.298469 -286.154593) (xy 86.349607 -286.146494) (xy 86.401381 -286.146494)
			(xy 86.452519 -286.154593) (xy 86.501759 -286.170592) (xy 86.547891 -286.194098) (xy 86.589778 -286.22453)
			(xy 86.626388 -286.26114) (xy 86.65682 -286.303027) (xy 86.680326 -286.349159) (xy 86.696325 -286.398399)
			(xy 86.704424 -286.449537) (xy 86.704932 -286.475424) (xy 86.704442 -286.501305) (xy 86.98614 -286.501305)
			(xy 86.98614 -286.449495) (xy 86.994245 -286.398322) (xy 87.010255 -286.349048) (xy 87.033776 -286.302885)
			(xy 87.064229 -286.260969) (xy 87.100864 -286.224333) (xy 87.142779 -286.193879) (xy 87.188942 -286.170357)
			(xy 87.238217 -286.154347) (xy 87.289389 -286.146241) (xy 87.315294 -286.145732) (xy 87.340788 -286.146208)
			(xy 87.391166 -286.154069) (xy 87.43973 -286.169604) (xy 87.485317 -286.192442) (xy 87.526838 -286.222037)
			(xy 87.563299 -286.257679) (xy 87.578946 -286.277812) (xy 87.991442 -286.277812) (xy 88.007098 -286.257686)
			(xy 88.043557 -286.222043) (xy 88.085076 -286.192449) (xy 88.130661 -286.16961) (xy 88.179224 -286.154073)
			(xy 88.229601 -286.146211) (xy 88.255094 -286.145732) (xy 88.281006 -286.146165) (xy 88.332191 -286.154271)
			(xy 88.381478 -286.170285) (xy 88.427653 -286.193811) (xy 88.469579 -286.224272) (xy 88.506224 -286.260916)
			(xy 88.536685 -286.302842) (xy 88.560213 -286.349016) (xy 88.576227 -286.398303) (xy 88.584334 -286.449488)
			(xy 88.584334 -286.501312) (xy 88.576227 -286.552497) (xy 88.560213 -286.601784) (xy 88.536685 -286.647958)
			(xy 88.506224 -286.689884) (xy 88.469579 -286.726528) (xy 88.427653 -286.756989) (xy 88.381478 -286.780515)
			(xy 88.332191 -286.796529) (xy 88.281006 -286.804635) (xy 88.255094 -286.805116) (xy 88.229601 -286.80463)
			(xy 88.179224 -286.796768) (xy 88.130661 -286.781233) (xy 88.085074 -286.758397) (xy 88.043553 -286.728806)
			(xy 88.007091 -286.693167) (xy 87.991442 -286.673036) (xy 87.578946 -286.673036) (xy 87.56331 -286.693178)
			(xy 87.526845 -286.728817) (xy 87.485322 -286.758409) (xy 87.439733 -286.781244) (xy 87.391168 -286.796778)
			(xy 87.340788 -286.804638) (xy 87.315294 -286.805116) (xy 87.289389 -286.804559) (xy 87.238217 -286.796453)
			(xy 87.188942 -286.780443) (xy 87.142779 -286.756921) (xy 87.100864 -286.726467) (xy 87.064229 -286.689831)
			(xy 87.033776 -286.647915) (xy 87.010255 -286.601752) (xy 86.994245 -286.552478) (xy 86.98614 -286.501305)
			(xy 86.704442 -286.501305) (xy 86.704407 -286.503132) (xy 86.695209 -286.557779) (xy 86.686644 -286.584136)
			(xy 86.679024 -286.60598) (xy 86.884002 -286.961072) (xy 86.906862 -286.96539) (xy 86.931665 -286.970582)
			(xy 86.979406 -286.987567) (xy 87.023985 -287.011659) (xy 87.064353 -287.042288) (xy 87.099557 -287.078734)
			(xy 87.12877 -287.120139) (xy 87.151302 -287.165526) (xy 87.166622 -287.213827) (xy 87.174371 -287.263904)
			(xy 87.174832 -287.28924) (xy 87.174324 -287.315127) (xy 87.174203 -287.315889) (xy 87.429584 -287.315889)
			(xy 87.429584 -287.262591) (xy 87.437527 -287.209887) (xy 87.453237 -287.158957) (xy 87.476363 -287.110936)
			(xy 87.506387 -287.066899) (xy 87.542639 -287.027828) (xy 87.58431 -286.994597) (xy 87.630468 -286.967948)
			(xy 87.680082 -286.948476) (xy 87.732044 -286.936616) (xy 87.785194 -286.932633) (xy 87.838344 -286.936616)
			(xy 87.890306 -286.948476) (xy 87.93992 -286.967948) (xy 87.986078 -286.994597) (xy 88.027749 -287.027828)
			(xy 88.064001 -287.066899) (xy 88.094025 -287.110936) (xy 88.117151 -287.158957) (xy 88.132861 -287.209887)
			(xy 88.140804 -287.262591) (xy 88.141302 -287.28924) (xy 88.140804 -287.315889) (xy 88.369384 -287.315889)
			(xy 88.369384 -287.262591) (xy 88.377327 -287.209887) (xy 88.393037 -287.158957) (xy 88.416163 -287.110936)
			(xy 88.446187 -287.066899) (xy 88.482439 -287.027828) (xy 88.52411 -286.994597) (xy 88.570268 -286.967948)
			(xy 88.619882 -286.948476) (xy 88.671844 -286.936616) (xy 88.724994 -286.932633) (xy 88.778144 -286.936616)
			(xy 88.830106 -286.948476) (xy 88.87972 -286.967948) (xy 88.925878 -286.994597) (xy 88.967549 -287.027828)
			(xy 89.003801 -287.066899) (xy 89.033825 -287.110936) (xy 89.056951 -287.158957) (xy 89.072661 -287.209887)
			(xy 89.080604 -287.262591) (xy 89.081102 -287.28924) (xy 89.080604 -287.315889) (xy 89.309184 -287.315889)
			(xy 89.309184 -287.262591) (xy 89.317127 -287.209887) (xy 89.332837 -287.158957) (xy 89.355963 -287.110936)
			(xy 89.385987 -287.066899) (xy 89.422239 -287.027828) (xy 89.46391 -286.994597) (xy 89.510068 -286.967948)
			(xy 89.559682 -286.948476) (xy 89.611644 -286.936616) (xy 89.664794 -286.932633) (xy 89.717944 -286.936616)
			(xy 89.769906 -286.948476) (xy 89.81952 -286.967948) (xy 89.865678 -286.994597) (xy 89.907349 -287.027828)
			(xy 89.943601 -287.066899) (xy 89.973625 -287.110936) (xy 89.996751 -287.158957) (xy 90.012461 -287.209887)
			(xy 90.020404 -287.262591) (xy 90.020902 -287.28924) (xy 90.020404 -287.315889) (xy 90.249238 -287.315889)
			(xy 90.249238 -287.262591) (xy 90.257181 -287.209887) (xy 90.272891 -287.158957) (xy 90.296017 -287.110936)
			(xy 90.326041 -287.066899) (xy 90.362293 -287.027828) (xy 90.403964 -286.994597) (xy 90.450122 -286.967948)
			(xy 90.499736 -286.948476) (xy 90.551698 -286.936616) (xy 90.604848 -286.932633) (xy 90.657998 -286.936616)
			(xy 90.70996 -286.948476) (xy 90.759574 -286.967948) (xy 90.805732 -286.994597) (xy 90.847403 -287.027828)
			(xy 90.883655 -287.066899) (xy 90.913679 -287.110936) (xy 90.936805 -287.158957) (xy 90.952515 -287.209887)
			(xy 90.960458 -287.262591) (xy 90.960956 -287.28924) (xy 90.960458 -287.315889) (xy 91.189038 -287.315889)
			(xy 91.189038 -287.262591) (xy 91.196981 -287.209887) (xy 91.212691 -287.158957) (xy 91.235817 -287.110936)
			(xy 91.265841 -287.066899) (xy 91.302093 -287.027828) (xy 91.343764 -286.994597) (xy 91.389922 -286.967948)
			(xy 91.439536 -286.948476) (xy 91.491498 -286.936616) (xy 91.544648 -286.932633) (xy 91.597798 -286.936616)
			(xy 91.64976 -286.948476) (xy 91.699374 -286.967948) (xy 91.745532 -286.994597) (xy 91.787203 -287.027828)
			(xy 91.823455 -287.066899) (xy 91.853479 -287.110936) (xy 91.876605 -287.158957) (xy 91.892315 -287.209887)
			(xy 91.900258 -287.262591) (xy 91.900756 -287.28924) (xy 91.900258 -287.315889) (xy 92.128838 -287.315889)
			(xy 92.128838 -287.262591) (xy 92.136781 -287.209887) (xy 92.152491 -287.158957) (xy 92.175617 -287.110936)
			(xy 92.205641 -287.066899) (xy 92.241893 -287.027828) (xy 92.283564 -286.994597) (xy 92.329722 -286.967948)
			(xy 92.379336 -286.948476) (xy 92.431298 -286.936616) (xy 92.484448 -286.932633) (xy 92.537598 -286.936616)
			(xy 92.58956 -286.948476) (xy 92.639174 -286.967948) (xy 92.685332 -286.994597) (xy 92.727003 -287.027828)
			(xy 92.763255 -287.066899) (xy 92.793279 -287.110936) (xy 92.816405 -287.158957) (xy 92.832115 -287.209887)
			(xy 92.840058 -287.262591) (xy 92.840556 -287.28924) (xy 92.840058 -287.315889) (xy 93.068384 -287.315889)
			(xy 93.068384 -287.262591) (xy 93.076327 -287.209887) (xy 93.092037 -287.158957) (xy 93.115163 -287.110936)
			(xy 93.145187 -287.066899) (xy 93.181439 -287.027828) (xy 93.22311 -286.994597) (xy 93.269268 -286.967948)
			(xy 93.318882 -286.948476) (xy 93.370844 -286.936616) (xy 93.423994 -286.932633) (xy 93.477144 -286.936616)
			(xy 93.529106 -286.948476) (xy 93.57872 -286.967948) (xy 93.624878 -286.994597) (xy 93.666549 -287.027828)
			(xy 93.702801 -287.066899) (xy 93.732825 -287.110936) (xy 93.755951 -287.158957) (xy 93.771661 -287.209887)
			(xy 93.779604 -287.262591) (xy 93.780102 -287.28924) (xy 93.779604 -287.315889) (xy 94.008184 -287.315889)
			(xy 94.008184 -287.262591) (xy 94.016127 -287.209887) (xy 94.031837 -287.158957) (xy 94.054963 -287.110936)
			(xy 94.084987 -287.066899) (xy 94.121239 -287.027828) (xy 94.16291 -286.994597) (xy 94.209068 -286.967948)
			(xy 94.258682 -286.948476) (xy 94.310644 -286.936616) (xy 94.363794 -286.932633) (xy 94.416944 -286.936616)
			(xy 94.468906 -286.948476) (xy 94.51852 -286.967948) (xy 94.564678 -286.994597) (xy 94.606349 -287.027828)
			(xy 94.642601 -287.066899) (xy 94.672625 -287.110936) (xy 94.695751 -287.158957) (xy 94.711461 -287.209887)
			(xy 94.719404 -287.262591) (xy 94.719902 -287.28924) (xy 94.719404 -287.315889) (xy 94.947984 -287.315889)
			(xy 94.947984 -287.262591) (xy 94.955927 -287.209887) (xy 94.971637 -287.158957) (xy 94.994763 -287.110936)
			(xy 95.024787 -287.066899) (xy 95.061039 -287.027828) (xy 95.10271 -286.994597) (xy 95.148868 -286.967948)
			(xy 95.198482 -286.948476) (xy 95.250444 -286.936616) (xy 95.303594 -286.932633) (xy 95.356744 -286.936616)
			(xy 95.408706 -286.948476) (xy 95.45832 -286.967948) (xy 95.504478 -286.994597) (xy 95.546149 -287.027828)
			(xy 95.582401 -287.066899) (xy 95.612425 -287.110936) (xy 95.635551 -287.158957) (xy 95.651261 -287.209887)
			(xy 95.659204 -287.262591) (xy 95.659702 -287.28924) (xy 95.659204 -287.315889) (xy 95.887784 -287.315889)
			(xy 95.887784 -287.262591) (xy 95.895727 -287.209887) (xy 95.911437 -287.158957) (xy 95.934563 -287.110936)
			(xy 95.964587 -287.066899) (xy 96.000839 -287.027828) (xy 96.04251 -286.994597) (xy 96.088668 -286.967948)
			(xy 96.138282 -286.948476) (xy 96.190244 -286.936616) (xy 96.243394 -286.932633) (xy 96.296544 -286.936616)
			(xy 96.348506 -286.948476) (xy 96.39812 -286.967948) (xy 96.444278 -286.994597) (xy 96.485949 -287.027828)
			(xy 96.522201 -287.066899) (xy 96.552225 -287.110936) (xy 96.575351 -287.158957) (xy 96.591061 -287.209887)
			(xy 96.599004 -287.262591) (xy 96.599502 -287.28924) (xy 96.599004 -287.315889) (xy 96.827584 -287.315889)
			(xy 96.827584 -287.262591) (xy 96.835527 -287.209887) (xy 96.851237 -287.158957) (xy 96.874363 -287.110936)
			(xy 96.904387 -287.066899) (xy 96.940639 -287.027828) (xy 96.98231 -286.994597) (xy 97.028468 -286.967948)
			(xy 97.078082 -286.948476) (xy 97.130044 -286.936616) (xy 97.183194 -286.932633) (xy 97.236344 -286.936616)
			(xy 97.288306 -286.948476) (xy 97.33792 -286.967948) (xy 97.384078 -286.994597) (xy 97.425749 -287.027828)
			(xy 97.462001 -287.066899) (xy 97.492025 -287.110936) (xy 97.515151 -287.158957) (xy 97.530861 -287.209887)
			(xy 97.538804 -287.262591) (xy 97.539302 -287.28924) (xy 97.538804 -287.315889) (xy 97.767384 -287.315889)
			(xy 97.767384 -287.262591) (xy 97.775327 -287.209887) (xy 97.791037 -287.158957) (xy 97.814163 -287.110936)
			(xy 97.844187 -287.066899) (xy 97.880439 -287.027828) (xy 97.92211 -286.994597) (xy 97.968268 -286.967948)
			(xy 98.017882 -286.948476) (xy 98.069844 -286.936616) (xy 98.122994 -286.932633) (xy 98.176144 -286.936616)
			(xy 98.228106 -286.948476) (xy 98.27772 -286.967948) (xy 98.323878 -286.994597) (xy 98.365549 -287.027828)
			(xy 98.401801 -287.066899) (xy 98.431825 -287.110936) (xy 98.454951 -287.158957) (xy 98.470661 -287.209887)
			(xy 98.478604 -287.262591) (xy 98.479102 -287.28924) (xy 98.478604 -287.315889) (xy 98.707184 -287.315889)
			(xy 98.707184 -287.262591) (xy 98.715127 -287.209887) (xy 98.730837 -287.158957) (xy 98.753963 -287.110936)
			(xy 98.783987 -287.066899) (xy 98.820239 -287.027828) (xy 98.86191 -286.994597) (xy 98.908068 -286.967948)
			(xy 98.957682 -286.948476) (xy 99.009644 -286.936616) (xy 99.062794 -286.932633) (xy 99.115944 -286.936616)
			(xy 99.167906 -286.948476) (xy 99.21752 -286.967948) (xy 99.263678 -286.994597) (xy 99.305349 -287.027828)
			(xy 99.341601 -287.066899) (xy 99.371625 -287.110936) (xy 99.394751 -287.158957) (xy 99.410461 -287.209887)
			(xy 99.418404 -287.262591) (xy 99.418902 -287.28924) (xy 99.418404 -287.315889) (xy 99.410461 -287.368593)
			(xy 99.394751 -287.419523) (xy 99.371625 -287.467544) (xy 99.341601 -287.511581) (xy 99.305349 -287.550652)
			(xy 99.263678 -287.583883) (xy 99.21752 -287.610532) (xy 99.167906 -287.630004) (xy 99.115944 -287.641864)
			(xy 99.062794 -287.645848) (xy 99.009644 -287.641864) (xy 98.957682 -287.630004) (xy 98.908068 -287.610532)
			(xy 98.86191 -287.583883) (xy 98.820239 -287.550652) (xy 98.783987 -287.511581) (xy 98.753963 -287.467544)
			(xy 98.730837 -287.419523) (xy 98.715127 -287.368593) (xy 98.707184 -287.315889) (xy 98.478604 -287.315889)
			(xy 98.470661 -287.368593) (xy 98.454951 -287.419523) (xy 98.431825 -287.467544) (xy 98.401801 -287.511581)
			(xy 98.365549 -287.550652) (xy 98.323878 -287.583883) (xy 98.27772 -287.610532) (xy 98.228106 -287.630004)
			(xy 98.176144 -287.641864) (xy 98.122994 -287.645848) (xy 98.069844 -287.641864) (xy 98.017882 -287.630004)
			(xy 97.968268 -287.610532) (xy 97.92211 -287.583883) (xy 97.880439 -287.550652) (xy 97.844187 -287.511581)
			(xy 97.814163 -287.467544) (xy 97.791037 -287.419523) (xy 97.775327 -287.368593) (xy 97.767384 -287.315889)
			(xy 97.538804 -287.315889) (xy 97.530861 -287.368593) (xy 97.515151 -287.419523) (xy 97.492025 -287.467544)
			(xy 97.462001 -287.511581) (xy 97.425749 -287.550652) (xy 97.384078 -287.583883) (xy 97.33792 -287.610532)
			(xy 97.288306 -287.630004) (xy 97.236344 -287.641864) (xy 97.183194 -287.645848) (xy 97.130044 -287.641864)
			(xy 97.078082 -287.630004) (xy 97.028468 -287.610532) (xy 96.98231 -287.583883) (xy 96.940639 -287.550652)
			(xy 96.904387 -287.511581) (xy 96.874363 -287.467544) (xy 96.851237 -287.419523) (xy 96.835527 -287.368593)
			(xy 96.827584 -287.315889) (xy 96.599004 -287.315889) (xy 96.591061 -287.368593) (xy 96.575351 -287.419523)
			(xy 96.552225 -287.467544) (xy 96.522201 -287.511581) (xy 96.485949 -287.550652) (xy 96.444278 -287.583883)
			(xy 96.39812 -287.610532) (xy 96.348506 -287.630004) (xy 96.296544 -287.641864) (xy 96.243394 -287.645848)
			(xy 96.190244 -287.641864) (xy 96.138282 -287.630004) (xy 96.088668 -287.610532) (xy 96.04251 -287.583883)
			(xy 96.000839 -287.550652) (xy 95.964587 -287.511581) (xy 95.934563 -287.467544) (xy 95.911437 -287.419523)
			(xy 95.895727 -287.368593) (xy 95.887784 -287.315889) (xy 95.659204 -287.315889) (xy 95.651261 -287.368593)
			(xy 95.635551 -287.419523) (xy 95.612425 -287.467544) (xy 95.582401 -287.511581) (xy 95.546149 -287.550652)
			(xy 95.504478 -287.583883) (xy 95.45832 -287.610532) (xy 95.408706 -287.630004) (xy 95.356744 -287.641864)
			(xy 95.303594 -287.645848) (xy 95.250444 -287.641864) (xy 95.198482 -287.630004) (xy 95.148868 -287.610532)
			(xy 95.10271 -287.583883) (xy 95.061039 -287.550652) (xy 95.024787 -287.511581) (xy 94.994763 -287.467544)
			(xy 94.971637 -287.419523) (xy 94.955927 -287.368593) (xy 94.947984 -287.315889) (xy 94.719404 -287.315889)
			(xy 94.711461 -287.368593) (xy 94.695751 -287.419523) (xy 94.672625 -287.467544) (xy 94.642601 -287.511581)
			(xy 94.606349 -287.550652) (xy 94.564678 -287.583883) (xy 94.51852 -287.610532) (xy 94.468906 -287.630004)
			(xy 94.416944 -287.641864) (xy 94.363794 -287.645848) (xy 94.310644 -287.641864) (xy 94.258682 -287.630004)
			(xy 94.209068 -287.610532) (xy 94.16291 -287.583883) (xy 94.121239 -287.550652) (xy 94.084987 -287.511581)
			(xy 94.054963 -287.467544) (xy 94.031837 -287.419523) (xy 94.016127 -287.368593) (xy 94.008184 -287.315889)
			(xy 93.779604 -287.315889) (xy 93.771661 -287.368593) (xy 93.755951 -287.419523) (xy 93.732825 -287.467544)
			(xy 93.702801 -287.511581) (xy 93.666549 -287.550652) (xy 93.624878 -287.583883) (xy 93.57872 -287.610532)
			(xy 93.529106 -287.630004) (xy 93.477144 -287.641864) (xy 93.423994 -287.645848) (xy 93.370844 -287.641864)
			(xy 93.318882 -287.630004) (xy 93.269268 -287.610532) (xy 93.22311 -287.583883) (xy 93.181439 -287.550652)
			(xy 93.145187 -287.511581) (xy 93.115163 -287.467544) (xy 93.092037 -287.419523) (xy 93.076327 -287.368593)
			(xy 93.068384 -287.315889) (xy 92.840058 -287.315889) (xy 92.832115 -287.368593) (xy 92.816405 -287.419523)
			(xy 92.793279 -287.467544) (xy 92.763255 -287.511581) (xy 92.727003 -287.550652) (xy 92.685332 -287.583883)
			(xy 92.639174 -287.610532) (xy 92.58956 -287.630004) (xy 92.537598 -287.641864) (xy 92.484448 -287.645848)
			(xy 92.431298 -287.641864) (xy 92.379336 -287.630004) (xy 92.329722 -287.610532) (xy 92.283564 -287.583883)
			(xy 92.241893 -287.550652) (xy 92.205641 -287.511581) (xy 92.175617 -287.467544) (xy 92.152491 -287.419523)
			(xy 92.136781 -287.368593) (xy 92.128838 -287.315889) (xy 91.900258 -287.315889) (xy 91.892315 -287.368593)
			(xy 91.876605 -287.419523) (xy 91.853479 -287.467544) (xy 91.823455 -287.511581) (xy 91.787203 -287.550652)
			(xy 91.745532 -287.583883) (xy 91.699374 -287.610532) (xy 91.64976 -287.630004) (xy 91.597798 -287.641864)
			(xy 91.544648 -287.645848) (xy 91.491498 -287.641864) (xy 91.439536 -287.630004) (xy 91.389922 -287.610532)
			(xy 91.343764 -287.583883) (xy 91.302093 -287.550652) (xy 91.265841 -287.511581) (xy 91.235817 -287.467544)
			(xy 91.212691 -287.419523) (xy 91.196981 -287.368593) (xy 91.189038 -287.315889) (xy 90.960458 -287.315889)
			(xy 90.952515 -287.368593) (xy 90.936805 -287.419523) (xy 90.913679 -287.467544) (xy 90.883655 -287.511581)
			(xy 90.847403 -287.550652) (xy 90.805732 -287.583883) (xy 90.759574 -287.610532) (xy 90.70996 -287.630004)
			(xy 90.657998 -287.641864) (xy 90.604848 -287.645848) (xy 90.551698 -287.641864) (xy 90.499736 -287.630004)
			(xy 90.450122 -287.610532) (xy 90.403964 -287.583883) (xy 90.362293 -287.550652) (xy 90.326041 -287.511581)
			(xy 90.296017 -287.467544) (xy 90.272891 -287.419523) (xy 90.257181 -287.368593) (xy 90.249238 -287.315889)
			(xy 90.020404 -287.315889) (xy 90.012461 -287.368593) (xy 89.996751 -287.419523) (xy 89.973625 -287.467544)
			(xy 89.943601 -287.511581) (xy 89.907349 -287.550652) (xy 89.865678 -287.583883) (xy 89.81952 -287.610532)
			(xy 89.769906 -287.630004) (xy 89.717944 -287.641864) (xy 89.664794 -287.645848) (xy 89.611644 -287.641864)
			(xy 89.559682 -287.630004) (xy 89.510068 -287.610532) (xy 89.46391 -287.583883) (xy 89.422239 -287.550652)
			(xy 89.385987 -287.511581) (xy 89.355963 -287.467544) (xy 89.332837 -287.419523) (xy 89.317127 -287.368593)
			(xy 89.309184 -287.315889) (xy 89.080604 -287.315889) (xy 89.072661 -287.368593) (xy 89.056951 -287.419523)
			(xy 89.033825 -287.467544) (xy 89.003801 -287.511581) (xy 88.967549 -287.550652) (xy 88.925878 -287.583883)
			(xy 88.87972 -287.610532) (xy 88.830106 -287.630004) (xy 88.778144 -287.641864) (xy 88.724994 -287.645848)
			(xy 88.671844 -287.641864) (xy 88.619882 -287.630004) (xy 88.570268 -287.610532) (xy 88.52411 -287.583883)
			(xy 88.482439 -287.550652) (xy 88.446187 -287.511581) (xy 88.416163 -287.467544) (xy 88.393037 -287.419523)
			(xy 88.377327 -287.368593) (xy 88.369384 -287.315889) (xy 88.140804 -287.315889) (xy 88.132861 -287.368593)
			(xy 88.117151 -287.419523) (xy 88.094025 -287.467544) (xy 88.064001 -287.511581) (xy 88.027749 -287.550652)
			(xy 87.986078 -287.583883) (xy 87.93992 -287.610532) (xy 87.890306 -287.630004) (xy 87.838344 -287.641864)
			(xy 87.785194 -287.645848) (xy 87.732044 -287.641864) (xy 87.680082 -287.630004) (xy 87.630468 -287.610532)
			(xy 87.58431 -287.583883) (xy 87.542639 -287.550652) (xy 87.506387 -287.511581) (xy 87.476363 -287.467544)
			(xy 87.453237 -287.419523) (xy 87.437527 -287.368593) (xy 87.429584 -287.315889) (xy 87.174203 -287.315889)
			(xy 87.166225 -287.366265) (xy 87.150226 -287.415505) (xy 87.12672 -287.461637) (xy 87.096288 -287.503524)
			(xy 87.059678 -287.540134) (xy 87.017791 -287.570566) (xy 86.971659 -287.594072) (xy 86.922419 -287.610071)
			(xy 86.871281 -287.61817) (xy 86.819507 -287.61817) (xy 86.768369 -287.610071) (xy 86.719129 -287.594072)
			(xy 86.672997 -287.570566) (xy 86.63111 -287.540134) (xy 86.5945 -287.503524) (xy 86.564068 -287.461637)
			(xy 86.540562 -287.415505) (xy 86.524563 -287.366265) (xy 86.516464 -287.315127) (xy 86.515956 -287.28924)
			(xy 86.516497 -287.261532) (xy 86.525685 -287.206886) (xy 86.534244 -287.180528) (xy 86.541864 -287.158684)
			(xy 86.336886 -286.803592) (xy 86.314026 -286.799274) (xy 86.289236 -286.79403) (xy 86.241499 -286.777048)
			(xy 86.196923 -286.752961) (xy 86.156558 -286.722338) (xy 86.121354 -286.685898) (xy 86.09214 -286.644501)
			(xy 86.069605 -286.599121) (xy 86.054278 -286.550828) (xy 86.046522 -286.500758) (xy 86.046056 -286.475424)
			(xy 85.791802 -286.475424) (xy 85.791304 -286.502073) (xy 85.783361 -286.554777) (xy 85.767651 -286.605707)
			(xy 85.744525 -286.653728) (xy 85.714501 -286.697765) (xy 85.678249 -286.736836) (xy 85.636578 -286.770067)
			(xy 85.59042 -286.796716) (xy 85.540806 -286.816188) (xy 85.488844 -286.828048) (xy 85.435694 -286.832032)
			(xy 85.382544 -286.828048) (xy 85.330582 -286.816188) (xy 85.280968 -286.796716) (xy 85.23481 -286.770067)
			(xy 85.193139 -286.736836) (xy 85.156887 -286.697765) (xy 85.126863 -286.653728) (xy 85.103737 -286.605707)
			(xy 85.088027 -286.554777) (xy 85.080084 -286.502073) (xy 84.734146 -286.502073) (xy 84.734146 -288.129705)
			(xy 86.959684 -288.129705) (xy 86.959684 -288.076407) (xy 86.967627 -288.023703) (xy 86.983337 -287.972773)
			(xy 87.006463 -287.924752) (xy 87.036487 -287.880715) (xy 87.072739 -287.841644) (xy 87.11441 -287.808413)
			(xy 87.160568 -287.781764) (xy 87.210182 -287.762292) (xy 87.262144 -287.750432) (xy 87.315294 -287.746449)
			(xy 87.368444 -287.750432) (xy 87.420406 -287.762292) (xy 87.47002 -287.781764) (xy 87.516178 -287.808413)
			(xy 87.557849 -287.841644) (xy 87.594101 -287.880715) (xy 87.624125 -287.924752) (xy 87.647251 -287.972773)
			(xy 87.662961 -288.023703) (xy 87.670904 -288.076407) (xy 87.671402 -288.103056) (xy 87.670904 -288.129705)
			(xy 87.662961 -288.182409) (xy 87.647251 -288.233339) (xy 87.624125 -288.28136) (xy 87.594101 -288.325397)
			(xy 87.557849 -288.364468) (xy 87.516178 -288.397699) (xy 87.47002 -288.424348) (xy 87.420406 -288.44382)
			(xy 87.368444 -288.45568) (xy 87.315294 -288.459664) (xy 87.262144 -288.45568) (xy 87.210182 -288.44382)
			(xy 87.160568 -288.424348) (xy 87.11441 -288.397699) (xy 87.072739 -288.364468) (xy 87.036487 -288.325397)
			(xy 87.006463 -288.28136) (xy 86.983337 -288.233339) (xy 86.967627 -288.182409) (xy 86.959684 -288.129705)
			(xy 84.734146 -288.129705) (xy 84.734146 -288.88436) (xy 87.428324 -288.88436)
		)
		(stroke
			(width 0)
			(type solid)
		)
		(fill yes)
		(layer "B.Cu")
		(net "PVCCFA_EHV_FIVRA_CPU1")
	)
	(gr_poly
		(pts
			(xy 335.276444 -289.110166) (xy 335.291478 -289.109622) (xy 335.320241 -289.100863) (xy 335.345213 -289.084116)
			(xy 335.364234 -289.060829) (xy 335.375657 -289.033016) (xy 335.378496 -289.003082) (xy 335.376012 -288.988246)
			(xy 335.372664 -288.970657) (xy 335.369098 -288.935029) (xy 335.3689 -288.917126) (xy 335.369398 -288.890477)
			(xy 335.377341 -288.837773) (xy 335.393051 -288.786843) (xy 335.416177 -288.738822) (xy 335.446201 -288.694785)
			(xy 335.482453 -288.655714) (xy 335.524124 -288.622483) (xy 335.570282 -288.595834) (xy 335.619896 -288.576362)
			(xy 335.671858 -288.564502) (xy 335.725008 -288.560519) (xy 335.778158 -288.564502) (xy 335.83012 -288.576362)
			(xy 335.879734 -288.595834) (xy 335.925892 -288.622483) (xy 335.967563 -288.655714) (xy 336.003815 -288.694785)
			(xy 336.033839 -288.738822) (xy 336.056965 -288.786843) (xy 336.072675 -288.837773) (xy 336.080618 -288.890477)
			(xy 336.081116 -288.917126) (xy 336.080905 -288.935029) (xy 336.07734 -288.970656) (xy 336.074004 -288.988246)
			(xy 336.071519 -289.003086) (xy 336.074335 -289.033029) (xy 336.085749 -289.060853) (xy 336.104774 -289.084146)
			(xy 336.129757 -289.100888) (xy 336.158534 -289.109628) (xy 336.173572 -289.110166) (xy 336.24393 -289.110166)
			(xy 336.259072 -289.109608) (xy 336.288026 -289.100727) (xy 336.313108 -289.083754) (xy 336.332118 -289.060178)
			(xy 336.343387 -289.032067) (xy 336.345926 -289.001889) (xy 336.343244 -288.986976) (xy 336.33972 -288.969728)
			(xy 336.335905 -288.934729) (xy 336.335624 -288.917126) (xy 336.336087 -288.891778) (xy 336.343847 -288.841679)
			(xy 336.359186 -288.793359) (xy 336.381744 -288.747957) (xy 336.410988 -288.706546) (xy 336.446229 -288.670102)
			(xy 336.486635 -288.639483) (xy 336.531253 -288.615414) (xy 336.579031 -288.59846) (xy 336.603848 -288.593276)
			(xy 336.626708 -288.588958) (xy 336.831686 -288.233866) (xy 336.823812 -288.212022) (xy 336.815234 -288.185603)
			(xy 336.806039 -288.130828) (xy 336.805524 -288.103056) (xy 336.806032 -288.077169) (xy 336.814131 -288.026031)
			(xy 336.83013 -287.976791) (xy 336.853636 -287.930659) (xy 336.884068 -287.888772) (xy 336.920678 -287.852162)
			(xy 336.962565 -287.82173) (xy 337.008697 -287.798224) (xy 337.057937 -287.782225) (xy 337.109075 -287.774126)
			(xy 337.160849 -287.774126) (xy 337.211987 -287.782225) (xy 337.261227 -287.798224) (xy 337.307359 -287.82173)
			(xy 337.349246 -287.852162) (xy 337.385856 -287.888772) (xy 337.416288 -287.930659) (xy 337.439794 -287.976791)
			(xy 337.455793 -288.026031) (xy 337.463892 -288.077169) (xy 337.4644 -288.103056) (xy 337.463939 -288.128394)
			(xy 337.456192 -288.178474) (xy 337.440873 -288.226779) (xy 337.418343 -288.272171) (xy 337.389133 -288.313581)
			(xy 337.35393 -288.350034) (xy 337.313564 -288.380672) (xy 337.268986 -288.404772) (xy 337.221244 -288.421767)
			(xy 337.19643 -288.426906) (xy 337.17357 -288.431224) (xy 336.968592 -288.786316) (xy 336.976466 -288.80816)
			(xy 336.98511 -288.834569) (xy 336.994428 -288.889345) (xy 336.995008 -288.917126) (xy 336.994752 -288.93473)
			(xy 336.990929 -288.96973) (xy 336.987388 -288.986976) (xy 336.984707 -289.001897) (xy 336.987223 -289.032092)
			(xy 336.998481 -289.060223) (xy 337.017491 -289.083817) (xy 337.042583 -289.100802) (xy 337.071552 -289.109684)
			(xy 337.086702 -289.110166) (xy 337.156044 -289.110166) (xy 337.171078 -289.109622) (xy 337.199841 -289.100863)
			(xy 337.224813 -289.084116) (xy 337.243834 -289.060829) (xy 337.255257 -289.033016) (xy 337.258096 -289.003082)
			(xy 337.255612 -288.988246) (xy 337.252264 -288.970657) (xy 337.248698 -288.935029) (xy 337.2485 -288.917126)
			(xy 337.248998 -288.890477) (xy 337.256941 -288.837773) (xy 337.272651 -288.786843) (xy 337.295777 -288.738822)
			(xy 337.325801 -288.694785) (xy 337.362053 -288.655714) (xy 337.403724 -288.622483) (xy 337.449882 -288.595834)
			(xy 337.499496 -288.576362) (xy 337.551458 -288.564502) (xy 337.604608 -288.560519) (xy 337.657758 -288.564502)
			(xy 337.70972 -288.576362) (xy 337.759334 -288.595834) (xy 337.805492 -288.622483) (xy 337.847163 -288.655714)
			(xy 337.883415 -288.694785) (xy 337.913439 -288.738822) (xy 337.936565 -288.786843) (xy 337.952275 -288.837773)
			(xy 337.960218 -288.890477) (xy 337.960716 -288.917126) (xy 337.960505 -288.935029) (xy 337.95694 -288.970656)
			(xy 337.953604 -288.988246) (xy 337.951119 -289.003086) (xy 337.953935 -289.033029) (xy 337.965349 -289.060853)
			(xy 337.984374 -289.084146) (xy 338.009357 -289.100888) (xy 338.038134 -289.109628) (xy 338.053172 -289.110166)
			(xy 338.12353 -289.110166) (xy 338.138672 -289.109608) (xy 338.167626 -289.100727) (xy 338.192708 -289.083754)
			(xy 338.211718 -289.060178) (xy 338.222987 -289.032067) (xy 338.225526 -289.001889) (xy 338.222844 -288.986976)
			(xy 338.21932 -288.969728) (xy 338.215505 -288.934729) (xy 338.215224 -288.917126) (xy 338.215687 -288.891778)
			(xy 338.223447 -288.841679) (xy 338.238786 -288.793359) (xy 338.261344 -288.747957) (xy 338.290588 -288.706546)
			(xy 338.325829 -288.670102) (xy 338.366235 -288.639483) (xy 338.410853 -288.615414) (xy 338.458631 -288.59846)
			(xy 338.483448 -288.593276) (xy 338.506308 -288.588958) (xy 338.711286 -288.233866) (xy 338.703412 -288.212022)
			(xy 338.694834 -288.185603) (xy 338.685639 -288.130828) (xy 338.685124 -288.103056) (xy 338.685632 -288.077169)
			(xy 338.693731 -288.026031) (xy 338.70973 -287.976791) (xy 338.733236 -287.930659) (xy 338.763668 -287.888772)
			(xy 338.800278 -287.852162) (xy 338.842165 -287.82173) (xy 338.888297 -287.798224) (xy 338.937537 -287.782225)
			(xy 338.988675 -287.774126) (xy 339.040449 -287.774126) (xy 339.091587 -287.782225) (xy 339.140827 -287.798224)
			(xy 339.186959 -287.82173) (xy 339.228846 -287.852162) (xy 339.265456 -287.888772) (xy 339.295888 -287.930659)
			(xy 339.319394 -287.976791) (xy 339.335393 -288.026031) (xy 339.343492 -288.077169) (xy 339.344 -288.103056)
			(xy 339.343539 -288.128394) (xy 339.335792 -288.178474) (xy 339.320473 -288.226779) (xy 339.297943 -288.272171)
			(xy 339.268733 -288.313581) (xy 339.23353 -288.350034) (xy 339.193164 -288.380672) (xy 339.148586 -288.404772)
			(xy 339.100844 -288.421767) (xy 339.07603 -288.426906) (xy 339.05317 -288.431224) (xy 338.848192 -288.786316)
			(xy 338.856066 -288.80816) (xy 338.86471 -288.834569) (xy 338.874028 -288.889345) (xy 338.874608 -288.917126)
			(xy 338.874352 -288.93473) (xy 338.870529 -288.96973) (xy 338.866988 -288.986976) (xy 338.864307 -289.001897)
			(xy 338.866823 -289.032092) (xy 338.878081 -289.060223) (xy 338.897091 -289.083817) (xy 338.922183 -289.100802)
			(xy 338.951152 -289.109684) (xy 338.966302 -289.110166) (xy 339.06333 -289.110166) (xy 339.078472 -289.109608)
			(xy 339.107426 -289.100727) (xy 339.132508 -289.083754) (xy 339.151518 -289.060178) (xy 339.162787 -289.032067)
			(xy 339.165326 -289.001889) (xy 339.162644 -288.986976) (xy 339.15912 -288.969728) (xy 339.155305 -288.934729)
			(xy 339.155024 -288.917126) (xy 339.155532 -288.891219) (xy 339.163638 -288.840042) (xy 339.17965 -288.790763)
			(xy 339.203173 -288.744596) (xy 339.233629 -288.702677) (xy 339.270267 -288.666039) (xy 339.312186 -288.635583)
			(xy 339.358353 -288.61206) (xy 339.407632 -288.596048) (xy 339.458809 -288.587942) (xy 339.510623 -288.587942)
			(xy 339.5618 -288.596048) (xy 339.611079 -288.61206) (xy 339.657246 -288.635583) (xy 339.699165 -288.666039)
			(xy 339.735803 -288.702677) (xy 339.766259 -288.744596) (xy 339.789782 -288.790763) (xy 339.805794 -288.840042)
			(xy 339.8139 -288.891219) (xy 339.814408 -288.917126) (xy 339.814152 -288.93473) (xy 339.810329 -288.96973)
			(xy 339.806788 -288.986976) (xy 339.804107 -289.001897) (xy 339.806623 -289.032092) (xy 339.817881 -289.060223)
			(xy 339.836891 -289.083817) (xy 339.861983 -289.100802) (xy 339.890952 -289.109684) (xy 339.906102 -289.110166)
			(xy 340.00313 -289.110166) (xy 340.018272 -289.109608) (xy 340.047226 -289.100727) (xy 340.072308 -289.083754)
			(xy 340.091318 -289.060178) (xy 340.102587 -289.032067) (xy 340.105126 -289.001889) (xy 340.102444 -288.986976)
			(xy 340.09892 -288.969728) (xy 340.095105 -288.934729) (xy 340.094824 -288.917126) (xy 340.095287 -288.891778)
			(xy 340.103047 -288.841679) (xy 340.118386 -288.793359) (xy 340.140944 -288.747957) (xy 340.170188 -288.706546)
			(xy 340.205429 -288.670102) (xy 340.245835 -288.639483) (xy 340.290453 -288.615414) (xy 340.338231 -288.59846)
			(xy 340.363048 -288.593276) (xy 340.385908 -288.588958) (xy 340.59114 -288.233866) (xy 340.583266 -288.211768)
			(xy 340.574644 -288.185419) (xy 340.565327 -288.130773) (xy 340.564724 -288.103056) (xy 340.565232 -288.077149)
			(xy 340.573338 -288.025972) (xy 340.58935 -287.976693) (xy 340.612873 -287.930526) (xy 340.643329 -287.888607)
			(xy 340.679967 -287.851969) (xy 340.721886 -287.821513) (xy 340.768053 -287.79799) (xy 340.817332 -287.781978)
			(xy 340.868509 -287.773872) (xy 340.920323 -287.773872) (xy 340.9715 -287.781978) (xy 341.020779 -287.79799)
			(xy 341.066946 -287.821513) (xy 341.108865 -287.851969) (xy 341.145503 -287.888607) (xy 341.175959 -287.930526)
			(xy 341.199482 -287.976693) (xy 341.215494 -288.025972) (xy 341.2236 -288.077149) (xy 341.224108 -288.103056)
			(xy 341.223646 -288.128406) (xy 341.215889 -288.178508) (xy 341.200552 -288.226832) (xy 341.177996 -288.272238)
			(xy 341.148753 -288.313654) (xy 341.113513 -288.350104) (xy 341.073107 -288.380727) (xy 341.028489 -288.404803)
			(xy 340.98071 -288.421762) (xy 340.955884 -288.426906) (xy 340.933024 -288.431224) (xy 340.727792 -288.786316)
			(xy 340.735666 -288.808414) (xy 340.744288 -288.834763) (xy 340.753607 -288.889409) (xy 340.754208 -288.917126)
			(xy 340.753952 -288.93473) (xy 340.750129 -288.96973) (xy 340.746588 -288.986976) (xy 340.743907 -289.001897)
			(xy 340.746423 -289.032092) (xy 340.757681 -289.060223) (xy 340.776691 -289.083817) (xy 340.801783 -289.100802)
			(xy 340.830752 -289.109684) (xy 340.845902 -289.110166) (xy 340.94293 -289.110166) (xy 340.958072 -289.109608)
			(xy 340.987026 -289.100727) (xy 341.012108 -289.083754) (xy 341.031118 -289.060178) (xy 341.042387 -289.032067)
			(xy 341.044926 -289.001889) (xy 341.042244 -288.986976) (xy 341.03872 -288.969728) (xy 341.034905 -288.934729)
			(xy 341.034624 -288.917126) (xy 341.035132 -288.891219) (xy 341.043238 -288.840042) (xy 341.05925 -288.790763)
			(xy 341.082773 -288.744596) (xy 341.113229 -288.702677) (xy 341.149867 -288.666039) (xy 341.191786 -288.635583)
			(xy 341.237953 -288.61206) (xy 341.287232 -288.596048) (xy 341.338409 -288.587942) (xy 341.390223 -288.587942)
			(xy 341.4414 -288.596048) (xy 341.490679 -288.61206) (xy 341.536846 -288.635583) (xy 341.578765 -288.666039)
			(xy 341.615403 -288.702677) (xy 341.645859 -288.744596) (xy 341.669382 -288.790763) (xy 341.685394 -288.840042)
			(xy 341.6935 -288.891219) (xy 341.694008 -288.917126) (xy 341.693752 -288.93473) (xy 341.689929 -288.96973)
			(xy 341.686388 -288.986976) (xy 341.683707 -289.001897) (xy 341.686223 -289.032092) (xy 341.697481 -289.060223)
			(xy 341.716491 -289.083817) (xy 341.741583 -289.100802) (xy 341.770552 -289.109684) (xy 341.785702 -289.110166)
			(xy 341.88273 -289.110166) (xy 341.897872 -289.109608) (xy 341.926826 -289.100727) (xy 341.951908 -289.083754)
			(xy 341.970918 -289.060178) (xy 341.982187 -289.032067) (xy 341.984726 -289.001889) (xy 341.982044 -288.986976)
			(xy 341.97852 -288.969728) (xy 341.974705 -288.934729) (xy 341.974424 -288.917126) (xy 341.974887 -288.891778)
			(xy 341.982647 -288.841679) (xy 341.997986 -288.793359) (xy 342.020544 -288.747957) (xy 342.049788 -288.706546)
			(xy 342.085029 -288.670102) (xy 342.125435 -288.639483) (xy 342.170053 -288.615414) (xy 342.217831 -288.59846)
			(xy 342.242648 -288.593276) (xy 342.265508 -288.588958) (xy 342.47074 -288.233866) (xy 342.462866 -288.211768)
			(xy 342.454244 -288.185419) (xy 342.444927 -288.130773) (xy 342.444324 -288.103056) (xy 342.444832 -288.077149)
			(xy 342.452938 -288.025972) (xy 342.46895 -287.976693) (xy 342.492473 -287.930526) (xy 342.522929 -287.888607)
			(xy 342.559567 -287.851969) (xy 342.601486 -287.821513) (xy 342.647653 -287.79799) (xy 342.696932 -287.781978)
			(xy 342.748109 -287.773872) (xy 342.799923 -287.773872) (xy 342.8511 -287.781978) (xy 342.900379 -287.79799)
			(xy 342.946546 -287.821513) (xy 342.988465 -287.851969) (xy 343.025103 -287.888607) (xy 343.055559 -287.930526)
			(xy 343.079082 -287.976693) (xy 343.095094 -288.025972) (xy 343.1032 -288.077149) (xy 343.103708 -288.103056)
			(xy 343.103246 -288.128406) (xy 343.095489 -288.178508) (xy 343.080152 -288.226832) (xy 343.057596 -288.272238)
			(xy 343.028353 -288.313654) (xy 342.993113 -288.350104) (xy 342.952707 -288.380727) (xy 342.908089 -288.404803)
			(xy 342.86031 -288.421762) (xy 342.835484 -288.426906) (xy 342.812624 -288.431224) (xy 342.607392 -288.786316)
			(xy 342.615266 -288.808414) (xy 342.623888 -288.834763) (xy 342.633207 -288.889409) (xy 342.633808 -288.917126)
			(xy 342.633552 -288.93473) (xy 342.629729 -288.96973) (xy 342.626188 -288.986976) (xy 342.623507 -289.001897)
			(xy 342.626023 -289.032092) (xy 342.637281 -289.060223) (xy 342.656291 -289.083817) (xy 342.681383 -289.100802)
			(xy 342.710352 -289.109684) (xy 342.725502 -289.110166) (xy 342.82253 -289.110166) (xy 342.837672 -289.109608)
			(xy 342.866626 -289.100727) (xy 342.891708 -289.083754) (xy 342.910718 -289.060178) (xy 342.921987 -289.032067)
			(xy 342.924526 -289.001889) (xy 342.921844 -288.986976) (xy 342.91832 -288.969728) (xy 342.914505 -288.934729)
			(xy 342.914224 -288.917126) (xy 342.914732 -288.891219) (xy 342.922838 -288.840042) (xy 342.93885 -288.790763)
			(xy 342.962373 -288.744596) (xy 342.992829 -288.702677) (xy 343.029467 -288.666039) (xy 343.071386 -288.635583)
			(xy 343.117553 -288.61206) (xy 343.166832 -288.596048) (xy 343.218009 -288.587942) (xy 343.269823 -288.587942)
			(xy 343.321 -288.596048) (xy 343.370279 -288.61206) (xy 343.416446 -288.635583) (xy 343.458365 -288.666039)
			(xy 343.495003 -288.702677) (xy 343.525459 -288.744596) (xy 343.548982 -288.790763) (xy 343.564994 -288.840042)
			(xy 343.5731 -288.891219) (xy 343.573608 -288.917126) (xy 343.573352 -288.93473) (xy 343.569529 -288.96973)
			(xy 343.565988 -288.986976) (xy 343.563307 -289.001897) (xy 343.565823 -289.032092) (xy 343.577081 -289.060223)
			(xy 343.596091 -289.083817) (xy 343.621183 -289.100802) (xy 343.650152 -289.109684) (xy 343.665302 -289.110166)
			(xy 343.76233 -289.110166) (xy 343.777472 -289.109608) (xy 343.806426 -289.100727) (xy 343.831508 -289.083754)
			(xy 343.850518 -289.060178) (xy 343.861787 -289.032067) (xy 343.864326 -289.001889) (xy 343.861644 -288.986976)
			(xy 343.85812 -288.969728) (xy 343.854305 -288.934729) (xy 343.854024 -288.917126) (xy 343.854487 -288.891778)
			(xy 343.862247 -288.841679) (xy 343.877586 -288.793359) (xy 343.900144 -288.747957) (xy 343.929388 -288.706546)
			(xy 343.964629 -288.670102) (xy 344.005035 -288.639483) (xy 344.049653 -288.615414) (xy 344.097431 -288.59846)
			(xy 344.122248 -288.593276) (xy 344.145108 -288.588958) (xy 344.35034 -288.233866) (xy 344.342466 -288.211768)
			(xy 344.333844 -288.185419) (xy 344.324527 -288.130773) (xy 344.323924 -288.103056) (xy 344.324432 -288.077149)
			(xy 344.332538 -288.025972) (xy 344.34855 -287.976693) (xy 344.372073 -287.930526) (xy 344.402529 -287.888607)
			(xy 344.439167 -287.851969) (xy 344.481086 -287.821513) (xy 344.527253 -287.79799) (xy 344.576532 -287.781978)
			(xy 344.627709 -287.773872) (xy 344.679523 -287.773872) (xy 344.7307 -287.781978) (xy 344.779979 -287.79799)
			(xy 344.826146 -287.821513) (xy 344.868065 -287.851969) (xy 344.904703 -287.888607) (xy 344.935159 -287.930526)
			(xy 344.958682 -287.976693) (xy 344.974694 -288.025972) (xy 344.9828 -288.077149) (xy 344.983308 -288.103056)
			(xy 344.982846 -288.128406) (xy 344.975089 -288.178508) (xy 344.959752 -288.226832) (xy 344.937196 -288.272238)
			(xy 344.907953 -288.313654) (xy 344.872713 -288.350104) (xy 344.832307 -288.380727) (xy 344.787689 -288.404803)
			(xy 344.73991 -288.421762) (xy 344.715084 -288.426906) (xy 344.692224 -288.431224) (xy 344.486992 -288.786316)
			(xy 344.494866 -288.808414) (xy 344.503488 -288.834763) (xy 344.512807 -288.889409) (xy 344.513408 -288.917126)
			(xy 344.513152 -288.93473) (xy 344.509329 -288.96973) (xy 344.505788 -288.986976) (xy 344.503107 -289.001897)
			(xy 344.505623 -289.032092) (xy 344.516881 -289.060223) (xy 344.535891 -289.083817) (xy 344.560983 -289.100802)
			(xy 344.589952 -289.109684) (xy 344.605102 -289.110166) (xy 344.70213 -289.110166) (xy 344.717272 -289.109608)
			(xy 344.746226 -289.100727) (xy 344.771308 -289.083754) (xy 344.790318 -289.060178) (xy 344.801587 -289.032067)
			(xy 344.804126 -289.001889) (xy 344.801444 -288.986976) (xy 344.79792 -288.969728) (xy 344.794105 -288.934729)
			(xy 344.793824 -288.917126) (xy 344.794332 -288.891219) (xy 344.802438 -288.840042) (xy 344.81845 -288.790763)
			(xy 344.841973 -288.744596) (xy 344.872429 -288.702677) (xy 344.909067 -288.666039) (xy 344.950986 -288.635583)
			(xy 344.997153 -288.61206) (xy 345.046432 -288.596048) (xy 345.097609 -288.587942) (xy 345.149423 -288.587942)
			(xy 345.2006 -288.596048) (xy 345.249879 -288.61206) (xy 345.296046 -288.635583) (xy 345.337965 -288.666039)
			(xy 345.374603 -288.702677) (xy 345.405059 -288.744596) (xy 345.428582 -288.790763) (xy 345.444594 -288.840042)
			(xy 345.4527 -288.891219) (xy 345.453208 -288.917126) (xy 345.452952 -288.93473) (xy 345.449129 -288.96973)
			(xy 345.445588 -288.986976) (xy 345.442907 -289.001897) (xy 345.445423 -289.032092) (xy 345.456681 -289.060223)
			(xy 345.475691 -289.083817) (xy 345.500783 -289.100802) (xy 345.529752 -289.109684) (xy 345.544902 -289.110166)
			(xy 345.64193 -289.110166) (xy 345.657072 -289.109608) (xy 345.686026 -289.100727) (xy 345.711108 -289.083754)
			(xy 345.730118 -289.060178) (xy 345.741387 -289.032067) (xy 345.743926 -289.001889) (xy 345.741244 -288.986976)
			(xy 345.73772 -288.969728) (xy 345.733905 -288.934729) (xy 345.733624 -288.917126) (xy 345.734087 -288.891778)
			(xy 345.741847 -288.841679) (xy 345.757186 -288.793359) (xy 345.779744 -288.747957) (xy 345.808988 -288.706546)
			(xy 345.844229 -288.670102) (xy 345.884635 -288.639483) (xy 345.929253 -288.615414) (xy 345.977031 -288.59846)
			(xy 346.001848 -288.593276) (xy 346.024708 -288.588958) (xy 346.22994 -288.233866) (xy 346.222066 -288.211768)
			(xy 346.213444 -288.185419) (xy 346.204127 -288.130773) (xy 346.203524 -288.103056) (xy 346.204032 -288.077149)
			(xy 346.212138 -288.025972) (xy 346.22815 -287.976693) (xy 346.251673 -287.930526) (xy 346.282129 -287.888607)
			(xy 346.318767 -287.851969) (xy 346.360686 -287.821513) (xy 346.406853 -287.79799) (xy 346.456132 -287.781978)
			(xy 346.507309 -287.773872) (xy 346.559123 -287.773872) (xy 346.6103 -287.781978) (xy 346.659579 -287.79799)
			(xy 346.705746 -287.821513) (xy 346.747665 -287.851969) (xy 346.784303 -287.888607) (xy 346.814759 -287.930526)
			(xy 346.838282 -287.976693) (xy 346.854294 -288.025972) (xy 346.8624 -288.077149) (xy 346.862908 -288.103056)
			(xy 346.862446 -288.128406) (xy 346.854689 -288.178508) (xy 346.839352 -288.226832) (xy 346.816796 -288.272238)
			(xy 346.787553 -288.313654) (xy 346.752313 -288.350104) (xy 346.711907 -288.380727) (xy 346.667289 -288.404803)
			(xy 346.61951 -288.421762) (xy 346.594684 -288.426906) (xy 346.571824 -288.431224) (xy 346.366592 -288.786316)
			(xy 346.374466 -288.808414) (xy 346.383088 -288.834763) (xy 346.392407 -288.889409) (xy 346.393008 -288.917126)
			(xy 346.392752 -288.93473) (xy 346.388929 -288.96973) (xy 346.385388 -288.986976) (xy 346.382707 -289.001897)
			(xy 346.385223 -289.032092) (xy 346.396481 -289.060223) (xy 346.415491 -289.083817) (xy 346.440583 -289.100802)
			(xy 346.469552 -289.109684) (xy 346.484702 -289.110166) (xy 346.58173 -289.110166) (xy 346.596872 -289.109608)
			(xy 346.625826 -289.100727) (xy 346.650908 -289.083754) (xy 346.669918 -289.060178) (xy 346.681187 -289.032067)
			(xy 346.683726 -289.001889) (xy 346.681044 -288.986976) (xy 346.67752 -288.969728) (xy 346.673705 -288.934729)
			(xy 346.673424 -288.917126) (xy 346.673932 -288.891219) (xy 346.682038 -288.840042) (xy 346.69805 -288.790763)
			(xy 346.721573 -288.744596) (xy 346.752029 -288.702677) (xy 346.788667 -288.666039) (xy 346.830586 -288.635583)
			(xy 346.876753 -288.61206) (xy 346.926032 -288.596048) (xy 346.977209 -288.587942) (xy 347.029023 -288.587942)
			(xy 347.0802 -288.596048) (xy 347.129479 -288.61206) (xy 347.175646 -288.635583) (xy 347.217565 -288.666039)
			(xy 347.254203 -288.702677) (xy 347.284659 -288.744596) (xy 347.308182 -288.790763) (xy 347.324194 -288.840042)
			(xy 347.3323 -288.891219) (xy 347.332808 -288.917126) (xy 347.332552 -288.93473) (xy 347.328729 -288.96973)
			(xy 347.325188 -288.986976) (xy 347.322507 -289.001897) (xy 347.325023 -289.032092) (xy 347.336281 -289.060223)
			(xy 347.355291 -289.083817) (xy 347.380383 -289.100802) (xy 347.409352 -289.109684) (xy 347.424502 -289.110166)
			(xy 347.52153 -289.110166) (xy 347.536672 -289.109608) (xy 347.565626 -289.100727) (xy 347.590708 -289.083754)
			(xy 347.609718 -289.060178) (xy 347.620987 -289.032067) (xy 347.623526 -289.001889) (xy 347.620844 -288.986976)
			(xy 347.61732 -288.969728) (xy 347.613505 -288.934729) (xy 347.613224 -288.917126) (xy 347.613687 -288.891778)
			(xy 347.621447 -288.841679) (xy 347.636786 -288.793359) (xy 347.659344 -288.747957) (xy 347.688588 -288.706546)
			(xy 347.723829 -288.670102) (xy 347.764235 -288.639483) (xy 347.808853 -288.615414) (xy 347.856631 -288.59846)
			(xy 347.881448 -288.593276) (xy 347.904308 -288.588958) (xy 348.10954 -288.233866) (xy 348.101666 -288.211768)
			(xy 348.093044 -288.185419) (xy 348.083727 -288.130773) (xy 348.083124 -288.103056) (xy 348.083632 -288.077149)
			(xy 348.091738 -288.025972) (xy 348.10775 -287.976693) (xy 348.131273 -287.930526) (xy 348.161729 -287.888607)
			(xy 348.198367 -287.851969) (xy 348.240286 -287.821513) (xy 348.286453 -287.79799) (xy 348.335732 -287.781978)
			(xy 348.386909 -287.773872) (xy 348.438723 -287.773872) (xy 348.4899 -287.781978) (xy 348.539179 -287.79799)
			(xy 348.585346 -287.821513) (xy 348.627265 -287.851969) (xy 348.663903 -287.888607) (xy 348.694359 -287.930526)
			(xy 348.717882 -287.976693) (xy 348.733894 -288.025972) (xy 348.742 -288.077149) (xy 348.742508 -288.103056)
			(xy 348.742046 -288.128406) (xy 348.734289 -288.178508) (xy 348.718952 -288.226832) (xy 348.696396 -288.272238)
			(xy 348.667153 -288.313654) (xy 348.631913 -288.350104) (xy 348.591507 -288.380727) (xy 348.546889 -288.404803)
			(xy 348.49911 -288.421762) (xy 348.474284 -288.426906) (xy 348.451424 -288.431224) (xy 348.246192 -288.786316)
			(xy 348.254066 -288.808414) (xy 348.262688 -288.834763) (xy 348.272007 -288.889409) (xy 348.272608 -288.917126)
			(xy 348.272352 -288.93473) (xy 348.268529 -288.96973) (xy 348.264988 -288.986976) (xy 348.262307 -289.001897)
			(xy 348.264823 -289.032092) (xy 348.276081 -289.060223) (xy 348.295091 -289.083817) (xy 348.320183 -289.100802)
			(xy 348.349152 -289.109684) (xy 348.364302 -289.110166) (xy 348.46133 -289.110166) (xy 348.476472 -289.109608)
			(xy 348.505426 -289.100727) (xy 348.530508 -289.083754) (xy 348.549518 -289.060178) (xy 348.560787 -289.032067)
			(xy 348.563326 -289.001889) (xy 348.560644 -288.986976) (xy 348.55712 -288.969728) (xy 348.553305 -288.934729)
			(xy 348.553024 -288.917126) (xy 348.553532 -288.891219) (xy 348.561638 -288.840042) (xy 348.57765 -288.790763)
			(xy 348.601173 -288.744596) (xy 348.631629 -288.702677) (xy 348.668267 -288.666039) (xy 348.710186 -288.635583)
			(xy 348.756353 -288.61206) (xy 348.805632 -288.596048) (xy 348.856809 -288.587942) (xy 348.908623 -288.587942)
			(xy 348.9598 -288.596048) (xy 349.009079 -288.61206) (xy 349.055246 -288.635583) (xy 349.097165 -288.666039)
			(xy 349.133803 -288.702677) (xy 349.164259 -288.744596) (xy 349.187782 -288.790763) (xy 349.203794 -288.840042)
			(xy 349.2119 -288.891219) (xy 349.212408 -288.917126) (xy 349.212313 -288.927825) (xy 349.210917 -288.949178)
			(xy 349.209614 -288.959798) (xy 349.206312 -288.98469) (xy 349.259906 -289.038284) (xy 349.342964 -288.955226)
			(xy 349.342964 -288.436558) (xy 349.300292 -288.4297) (xy 349.274739 -288.425094) (xy 349.225385 -288.408973)
			(xy 349.179155 -288.38534) (xy 349.137187 -288.354773) (xy 349.100509 -288.318024) (xy 349.070024 -288.275996)
			(xy 349.04648 -288.229721) (xy 349.030456 -288.180336) (xy 349.022344 -288.129053) (xy 349.022346 -288.077133)
			(xy 349.030459 -288.025851) (xy 349.046485 -287.976466) (xy 349.070031 -287.930192) (xy 349.100518 -287.888165)
			(xy 349.137197 -287.851418) (xy 349.179167 -287.820853) (xy 349.225397 -287.797221) (xy 349.274752 -287.781103)
			(xy 349.300292 -287.776412) (xy 349.342964 -287.769554) (xy 349.342964 -286.807656) (xy 349.300292 -286.800798)
			(xy 349.274835 -286.796214) (xy 349.225667 -286.780162) (xy 349.179612 -286.756621) (xy 349.137804 -286.72617)
			(xy 349.10127 -286.689558) (xy 349.070909 -286.647684) (xy 349.047467 -286.601579) (xy 349.03152 -286.552376)
			(xy 349.023462 -286.501285) (xy 349.022924 -286.475424) (xy 349.02351 -286.447705) (xy 349.032823 -286.393055)
			(xy 349.041466 -286.366712) (xy 349.04934 -286.344614) (xy 348.844362 -285.989522) (xy 348.821248 -285.985204)
			(xy 348.796434 -285.980018) (xy 348.748666 -285.963048) (xy 348.704057 -285.938968) (xy 348.663659 -285.908346)
			(xy 348.628422 -285.871903) (xy 348.599176 -285.830497) (xy 348.576611 -285.785104) (xy 348.561257 -285.736792)
			(xy 348.553477 -285.6867) (xy 348.553024 -285.661354) (xy 348.553535 -285.635468) (xy 348.56164 -285.584334)
			(xy 348.577643 -285.535097) (xy 348.60115 -285.488969) (xy 348.631582 -285.447085) (xy 348.668191 -285.410477)
			(xy 348.710076 -285.380046) (xy 348.756204 -285.35654) (xy 348.805442 -285.340538) (xy 348.856576 -285.332434)
			(xy 348.882462 -285.331916) (xy 348.918276 -285.333694) (xy 348.92107 -285.333948) (xy 348.974664 -285.333948)
			(xy 348.974664 -285.251652) (xy 348.959932 -285.236666) (xy 348.936542 -285.212385) (xy 348.895226 -285.159107)
			(xy 348.860704 -285.101194) (xy 348.846648 -285.07055) (xy 348.840107 -285.057007) (xy 348.820522 -285.034202)
			(xy 348.795145 -285.018088) (xy 348.766176 -285.010063) (xy 348.736124 -285.010822) (xy 348.707597 -285.020299)
			(xy 348.683066 -285.037673) (xy 348.67342 -285.049214) (xy 348.658429 -285.067883) (xy 348.623955 -285.101105)
			(xy 348.585037 -285.12899) (xy 348.542493 -285.15095) (xy 348.497219 -285.166523) (xy 348.473776 -285.171388)
			(xy 348.450916 -285.175706) (xy 348.245938 -285.530544) (xy 348.253812 -285.552642) (xy 348.262371 -285.579)
			(xy 348.271557 -285.633646) (xy 348.2721 -285.661354) (xy 348.271592 -285.687241) (xy 348.263493 -285.738379)
			(xy 348.247494 -285.787619) (xy 348.223988 -285.833751) (xy 348.193556 -285.875638) (xy 348.156946 -285.912248)
			(xy 348.115059 -285.94268) (xy 348.068927 -285.966186) (xy 348.019687 -285.982185) (xy 347.968549 -285.990284)
			(xy 347.916775 -285.990284) (xy 347.865637 -285.982185) (xy 347.816397 -285.966186) (xy 347.770265 -285.94268)
			(xy 347.728378 -285.912248) (xy 347.691768 -285.875638) (xy 347.661336 -285.833751) (xy 347.63783 -285.787619)
			(xy 347.621831 -285.738379) (xy 347.613732 -285.687241) (xy 347.613224 -285.661354) (xy 347.613684 -285.636016)
			(xy 347.62143 -285.585936) (xy 347.636749 -285.537631) (xy 347.659279 -285.492239) (xy 347.68849 -285.450829)
			(xy 347.723693 -285.414377) (xy 347.76406 -285.383742) (xy 347.808639 -285.359644) (xy 347.856381 -285.342651)
			(xy 347.881194 -285.337504) (xy 347.904054 -285.333186) (xy 348.109286 -284.97784) (xy 348.101666 -284.955996)
			(xy 348.093058 -284.929709) (xy 348.083737 -284.875191) (xy 348.083124 -284.847538) (xy 348.083603 -284.821633)
			(xy 348.091706 -284.77046) (xy 348.107718 -284.721186) (xy 348.131245 -284.675026) (xy 348.161707 -284.633116)
			(xy 348.198352 -284.596491) (xy 348.240278 -284.566052) (xy 348.286451 -284.54255) (xy 348.335734 -284.526565)
			(xy 348.386911 -284.518489) (xy 348.412816 -284.5181) (xy 348.437872 -284.518569) (xy 348.487407 -284.526157)
			(xy 348.535222 -284.541156) (xy 348.580215 -284.563221) (xy 348.62135 -284.591843) (xy 348.657678 -284.626361)
			(xy 348.67342 -284.645862) (xy 348.683057 -284.65741) (xy 348.707596 -284.674775) (xy 348.736127 -284.684246)
			(xy 348.766179 -284.685004) (xy 348.795151 -284.676982) (xy 348.820534 -284.660876) (xy 348.840131 -284.63808)
			(xy 348.846648 -284.624526) (xy 348.856438 -284.602936) (xy 348.879201 -284.561348) (xy 348.892114 -284.541468)
			(xy 348.899741 -284.529136) (xy 348.908417 -284.501485) (xy 348.908962 -284.472509) (xy 348.901331 -284.444551)
			(xy 348.886141 -284.41987) (xy 348.864619 -284.400461) (xy 348.838506 -284.387892) (xy 348.824296 -284.385004)
			(xy 348.796915 -284.379924) (xy 348.744062 -284.362385) (xy 348.694582 -284.336836) (xy 348.649682 -284.303897)
			(xy 348.610454 -284.264373) (xy 348.577855 -284.219225) (xy 348.55268 -284.169554) (xy 348.535541 -284.11657)
			(xy 348.526856 -284.061565) (xy 348.526354 -284.033722) (xy 348.526901 -284.005737) (xy 348.535653 -283.950455)
			(xy 348.552945 -283.897222) (xy 348.578352 -283.84735) (xy 348.611247 -283.802066) (xy 348.650821 -283.762486)
			(xy 348.696099 -283.729583) (xy 348.745967 -283.704168) (xy 348.799196 -283.686867) (xy 348.854477 -283.678106)
			(xy 348.882462 -283.677614) (xy 348.908051 -283.678054) (xy 348.958703 -283.685371) (xy 349.007787 -283.69986)
			(xy 349.054293 -283.721223) (xy 349.07601 -283.734764) (xy 349.110554 -283.757116) (xy 349.204788 -283.662882)
			(xy 349.215346 -283.65157) (xy 349.229692 -283.624169) (xy 349.235187 -283.593732) (xy 349.231326 -283.563045)
			(xy 349.218465 -283.534917) (xy 349.19778 -283.511923) (xy 349.184722 -283.503624) (xy 349.163937 -283.490805)
			(xy 349.126045 -283.460001) (xy 349.09311 -283.423945) (xy 349.065854 -283.383426) (xy 349.044873 -283.33933)
			(xy 349.030624 -283.292622) (xy 349.023421 -283.244323) (xy 349.022924 -283.219906) (xy 349.023406 -283.194002)
			(xy 349.031513 -283.142834) (xy 349.047528 -283.093564) (xy 349.071056 -283.047408) (xy 349.101518 -283.005503)
			(xy 349.138163 -282.968881) (xy 349.180087 -282.938446) (xy 349.226258 -282.914947) (xy 349.275538 -282.898964)
			(xy 349.326712 -282.890889) (xy 349.352616 -282.890468) (xy 349.378128 -282.890946) (xy 349.428542 -282.898808)
			(xy 349.477144 -282.914343) (xy 349.522772 -282.937178) (xy 349.564338 -282.96677) (xy 349.60085 -283.002412)
			(xy 349.616522 -283.022548) (xy 350.02851 -283.022548) (xy 350.044185 -283.002415) (xy 350.080697 -282.966778)
			(xy 350.122264 -282.93719) (xy 350.167892 -282.914359) (xy 350.216492 -282.89883) (xy 350.266905 -282.890972)
			(xy 350.292416 -282.890468) (xy 350.318311 -282.890976) (xy 350.369464 -282.899075) (xy 350.418721 -282.915073)
			(xy 350.464872 -282.938574) (xy 350.506781 -282.969002) (xy 350.543417 -283.005607) (xy 350.57388 -283.047491)
			(xy 350.597421 -283.093622) (xy 350.613459 -283.142866) (xy 350.621602 -283.194011) (xy 350.622108 -283.219906)
			(xy 350.6216 -283.233622) (xy 350.621493 -283.247297) (xy 350.627685 -283.273923) (xy 350.640723 -283.29795)
			(xy 350.65967 -283.317655) (xy 350.683168 -283.331623) (xy 350.709531 -283.338853) (xy 350.7232 -283.339286)
			(xy 350.774508 -283.339286) (xy 350.788173 -283.338845) (xy 350.814523 -283.331598) (xy 350.83801 -283.317624)
			(xy 350.856953 -283.297925) (xy 350.869995 -283.273908) (xy 350.876203 -283.247293) (xy 350.876108 -283.233622)
			(xy 350.875854 -283.219906) (xy 350.876402 -283.191922) (xy 350.885157 -283.136641) (xy 350.90245 -283.083411)
			(xy 350.927857 -283.033541) (xy 350.960753 -282.98826) (xy 351.000326 -282.948681) (xy 351.045604 -282.91578)
			(xy 351.09547 -282.890367) (xy 351.148699 -282.873067) (xy 351.203978 -282.864306) (xy 351.231962 -282.863798)
			(xy 351.258689 -282.86428) (xy 351.311542 -282.87227) (xy 351.36261 -282.888061) (xy 351.410748 -282.911299)
			(xy 351.454876 -282.941464) (xy 351.474786 -282.959302) (xy 351.5106 -282.99283) (xy 351.622106 -282.881324)
			(xy 351.632012 -282.870706) (xy 351.645945 -282.845247) (xy 351.652145 -282.816893) (xy 351.650109 -282.787942)
			(xy 351.640003 -282.760735) (xy 351.622643 -282.737475) (xy 351.599437 -282.720046) (xy 351.586038 -282.714446)
			(xy 351.562831 -282.705225) (xy 351.519279 -282.680796) (xy 351.47991 -282.650077) (xy 351.445624 -282.613773)
			(xy 351.417206 -282.572713) (xy 351.395306 -282.527836) (xy 351.380425 -282.480169) (xy 351.372903 -282.430804)
			(xy 351.372424 -282.405836) (xy 351.372869 -282.381343) (xy 351.380115 -282.332896) (xy 351.394451 -282.286055)
			(xy 351.415563 -282.241852) (xy 351.442985 -282.201261) (xy 351.476112 -282.165176) (xy 351.514217 -282.134392)
			(xy 351.556458 -282.109586) (xy 351.601905 -282.091307) (xy 351.649557 -282.079955) (xy 351.673922 -282.077414)
			(xy 351.683312 -282.076214) (xy 351.700288 -282.067865) (xy 351.713094 -282.05394) (xy 351.719996 -282.036326)
			(xy 351.720404 -282.026868) (xy 351.720404 -281.204416) (xy 351.663762 -281.106372) (xy 351.640902 -281.102054)
			(xy 351.616058 -281.096911) (xy 351.568225 -281.080009) (xy 351.523549 -281.055972) (xy 351.483088 -281.025367)
			(xy 351.447799 -280.988919) (xy 351.418518 -280.947491) (xy 351.395936 -280.902061) (xy 351.380588 -280.853707)
			(xy 351.372838 -280.80357) (xy 351.372424 -280.778204) (xy 351.372872 -280.753713) (xy 351.380121 -280.705269)
			(xy 351.39446 -280.658432) (xy 351.415574 -280.614234) (xy 351.442996 -280.573646) (xy 351.476124 -280.537565)
			(xy 351.514227 -280.506784) (xy 351.556467 -280.481982) (xy 351.601912 -280.463705) (xy 351.649561 -280.452355)
			(xy 351.673922 -280.449782) (xy 351.68331 -280.448582) (xy 351.70028 -280.440231) (xy 351.713078 -280.426305)
			(xy 351.71997 -280.408692) (xy 351.720404 -280.399236) (xy 351.720404 -279.529286) (xy 351.720032 -279.51981)
			(xy 351.71317 -279.502147) (xy 351.700353 -279.488189) (xy 351.683337 -279.479849) (xy 351.673922 -279.47874)
			(xy 351.64624 -279.475813) (xy 351.592357 -279.461856) (xy 351.541589 -279.439037) (xy 351.495381 -279.408006)
			(xy 351.455049 -279.369646) (xy 351.437956 -279.347676) (xy 351.025968 -279.347676) (xy 351.010295 -279.367811)
			(xy 350.973785 -279.403454) (xy 350.932219 -279.433045) (xy 350.886591 -279.455879) (xy 350.837988 -279.471409)
			(xy 350.787574 -279.479265) (xy 350.762062 -279.479756) (xy 350.736175 -279.479245) (xy 350.68504 -279.471141)
			(xy 350.635801 -279.455137) (xy 350.589672 -279.431629) (xy 350.547789 -279.401194) (xy 350.511181 -279.364582)
			(xy 350.480751 -279.322695) (xy 350.457248 -279.276564) (xy 350.44125 -279.227323) (xy 350.433152 -279.176187)
			(xy 350.433152 -279.124413) (xy 350.44125 -279.073277) (xy 350.457248 -279.024036) (xy 350.480751 -278.977905)
			(xy 350.511181 -278.936018) (xy 350.547789 -278.899406) (xy 350.589672 -278.868971) (xy 350.635801 -278.845463)
			(xy 350.68504 -278.829459) (xy 350.736175 -278.821355) (xy 350.762062 -278.82088) (xy 350.787576 -278.821354)
			(xy 350.837994 -278.829209) (xy 350.886601 -278.844738) (xy 350.932235 -278.86757) (xy 350.973807 -278.89716)
			(xy 351.010324 -278.932801) (xy 351.025968 -278.95296) (xy 351.437956 -278.95296) (xy 351.455088 -278.931027)
			(xy 351.495431 -278.892694) (xy 351.541633 -278.861674) (xy 351.592386 -278.838846) (xy 351.646249 -278.824857)
			(xy 351.673922 -278.821896) (xy 351.683311 -278.820696) (xy 351.700284 -278.812346) (xy 351.713085 -278.79842)
			(xy 351.719981 -278.780807) (xy 351.720404 -278.77135) (xy 351.720404 -277.9014) (xy 351.720035 -277.891923)
			(xy 351.713175 -277.874255) (xy 351.700358 -277.860293) (xy 351.68334 -277.85195) (xy 351.673922 -277.850854)
			(xy 351.649561 -277.848309) (xy 351.60192 -277.836937) (xy 351.556485 -277.818644) (xy 351.514256 -277.793832)
			(xy 351.476161 -277.763047) (xy 351.443039 -277.726966) (xy 351.415617 -277.686382) (xy 351.3945 -277.642189)
			(xy 351.380152 -277.595359) (xy 351.372888 -277.546921) (xy 351.372424 -277.522432) (xy 351.372951 -277.494723)
			(xy 351.382144 -277.440076) (xy 351.390712 -277.41372) (xy 351.398586 -277.391622) (xy 351.193608 -277.036784)
			(xy 351.170748 -277.032466) (xy 351.145935 -277.027279) (xy 351.09817 -277.010308) (xy 351.053564 -276.986228)
			(xy 351.013169 -276.955605) (xy 350.977936 -276.919162) (xy 350.948695 -276.877756) (xy 350.926134 -276.832362)
			(xy 350.910786 -276.784052) (xy 350.903011 -276.733961) (xy 350.902524 -276.708616) (xy 350.903045 -276.681839)
			(xy 350.911702 -276.628989) (xy 350.928789 -276.578234) (xy 350.953857 -276.530909) (xy 350.986248 -276.48826)
			(xy 351.025107 -276.451409) (xy 351.069414 -276.421326) (xy 351.118001 -276.398802) (xy 351.169591 -276.384431)
			(xy 351.196148 -276.380956) (xy 351.210269 -276.378887) (xy 351.23663 -276.367983) (xy 351.258945 -276.350212)
			(xy 351.275475 -276.326962) (xy 351.284927 -276.300047) (xy 351.286565 -276.271567) (xy 351.280261 -276.243745)
			(xy 351.266507 -276.218753) (xy 351.256854 -276.208236) (xy 351.157032 -276.108414) (xy 351.146906 -276.098941)
			(xy 351.122766 -276.085324) (xy 351.095855 -276.078695) (xy 351.068152 -276.079543) (xy 351.041696 -276.087805)
			(xy 351.018434 -276.102873) (xy 351.00895 -276.112986) (xy 350.990523 -276.133016) (xy 350.94829 -276.167339)
			(xy 350.900988 -276.194251) (xy 350.849904 -276.213017) (xy 350.823276 -276.21865) (xy 350.800416 -276.222968)
			(xy 350.595438 -276.577806) (xy 350.603312 -276.599904) (xy 350.611874 -276.626261) (xy 350.621066 -276.680908)
			(xy 350.6216 -276.708616) (xy 350.621092 -276.734503) (xy 350.612993 -276.785641) (xy 350.596994 -276.834881)
			(xy 350.573488 -276.881013) (xy 350.543056 -276.9229) (xy 350.506446 -276.95951) (xy 350.464559 -276.989942)
			(xy 350.418427 -277.013448) (xy 350.369187 -277.029447) (xy 350.318049 -277.037546) (xy 350.266275 -277.037546)
			(xy 350.215137 -277.029447) (xy 350.165897 -277.013448) (xy 350.119765 -276.989942) (xy 350.077878 -276.95951)
			(xy 350.041268 -276.9229) (xy 350.010836 -276.881013) (xy 349.98733 -276.834881) (xy 349.971331 -276.785641)
			(xy 349.963232 -276.734503) (xy 349.962724 -276.708616) (xy 349.963187 -276.68328) (xy 349.970938 -276.633204)
			(xy 349.98626 -276.584904) (xy 350.008792 -276.539517) (xy 350.038004 -276.498112) (xy 350.073207 -276.461665)
			(xy 350.113573 -276.431033) (xy 350.15815 -276.406939) (xy 350.20589 -276.389949) (xy 350.230694 -276.384766)
			(xy 350.253554 -276.380448) (xy 350.458532 -276.025356) (xy 350.450912 -276.003512) (xy 350.443038 -275.977604)
			(xy 350.440339 -275.968924) (xy 350.429847 -275.954097) (xy 350.414861 -275.943832) (xy 350.397244 -275.939407)
			(xy 350.388174 -275.940012) (xy 350.352861 -275.943556) (xy 350.281911 -275.945539) (xy 350.211038 -275.941685)
			(xy 350.17583 -275.937218) (xy 350.172076 -275.964179) (xy 350.157443 -276.016607) (xy 350.135001 -276.066198)
			(xy 350.105275 -276.111795) (xy 350.068955 -276.152338) (xy 350.026888 -276.186881) (xy 349.980054 -276.21462)
			(xy 349.929544 -276.234908) (xy 349.876535 -276.247273) (xy 349.822262 -276.251427) (xy 349.767989 -276.247273)
			(xy 349.71498 -276.234908) (xy 349.66447 -276.21462) (xy 349.617636 -276.186881) (xy 349.575569 -276.152338)
			(xy 349.539249 -276.111795) (xy 349.509523 -276.066198) (xy 349.487081 -276.016607) (xy 349.472448 -275.964179)
			(xy 349.468694 -275.937218) (xy 349.430128 -275.942) (xy 349.352489 -275.945484) (xy 349.27485 -275.942)
			(xy 349.236284 -275.937218) (xy 349.23253 -275.964179) (xy 349.217897 -276.016607) (xy 349.195455 -276.066198)
			(xy 349.165729 -276.111795) (xy 349.129409 -276.152338) (xy 349.087342 -276.186881) (xy 349.040508 -276.21462)
			(xy 348.989998 -276.234908) (xy 348.936989 -276.247273) (xy 348.882716 -276.251427) (xy 348.828443 -276.247273)
			(xy 348.775434 -276.234908) (xy 348.724924 -276.21462) (xy 348.67809 -276.186881) (xy 348.636023 -276.152338)
			(xy 348.599703 -276.111795) (xy 348.569977 -276.066198) (xy 348.547535 -276.016607) (xy 348.532902 -275.964179)
			(xy 348.529148 -275.937218) (xy 348.49347 -275.941699) (xy 348.421655 -275.945443) (xy 348.349776 -275.943217)
			(xy 348.31401 -275.939504) (xy 348.304926 -275.938819) (xy 348.287252 -275.943178) (xy 348.272236 -275.953468)
			(xy 348.261793 -275.968379) (xy 348.259146 -275.977096) (xy 348.251858 -276.003024) (xy 348.229981 -276.052236)
			(xy 348.200331 -276.097195) (xy 348.163711 -276.136684) (xy 348.121112 -276.169635) (xy 348.073687 -276.195155)
			(xy 348.02272 -276.212554) (xy 347.96959 -276.221362) (xy 347.942662 -276.221952) (xy 347.915747 -276.22141)
			(xy 347.862641 -276.212602) (xy 347.811696 -276.195214) (xy 347.764288 -276.169716) (xy 347.721696 -276.136797)
			(xy 347.685072 -276.097346) (xy 347.655405 -276.052428) (xy 347.633497 -276.003257) (xy 347.626178 -275.97735)
			(xy 347.623542 -275.968617) (xy 347.613106 -275.953672) (xy 347.598098 -275.943328) (xy 347.580417 -275.938895)
			(xy 347.571314 -275.939504) (xy 347.37421 -275.939504) (xy 347.365126 -275.938819) (xy 347.347452 -275.943178)
			(xy 347.332436 -275.953468) (xy 347.321993 -275.968379) (xy 347.319346 -275.977096) (xy 347.312524 -276.001511)
			(xy 347.292383 -276.048028) (xy 347.265304 -276.09088) (xy 347.231936 -276.129039) (xy 347.193078 -276.16159)
			(xy 347.149662 -276.187754) (xy 347.102728 -276.206904) (xy 347.053401 -276.218581) (xy 347.002862 -276.222504)
			(xy 346.952323 -276.218581) (xy 346.902996 -276.206904) (xy 346.856062 -276.187754) (xy 346.812646 -276.16159)
			(xy 346.773788 -276.129039) (xy 346.74042 -276.09088) (xy 346.713341 -276.048028) (xy 346.6932 -276.001511)
			(xy 346.686378 -275.977096) (xy 346.683679 -275.968414) (xy 346.673188 -275.95358) (xy 346.658202 -275.943306)
			(xy 346.640583 -275.938869) (xy 346.631514 -275.939504) (xy 346.606961 -275.942129) (xy 346.557655 -275.944926)
			(xy 346.532962 -275.945092) (xy 346.503787 -275.944852) (xy 346.445571 -275.94091) (xy 346.41663 -275.937218)
			(xy 346.413091 -275.962832) (xy 346.39957 -276.012739) (xy 346.378973 -276.060166) (xy 346.351733 -276.104115)
			(xy 346.318423 -276.143662) (xy 346.279743 -276.177975) (xy 346.236506 -276.206332) (xy 346.189623 -276.228138)
			(xy 346.140078 -276.242933) (xy 346.088915 -276.250406) (xy 346.063062 -276.250908) (xy 346.037219 -276.250444)
			(xy 345.986078 -276.242969) (xy 345.936553 -276.228181) (xy 345.889686 -276.206391) (xy 345.84646 -276.178056)
			(xy 345.807783 -276.143772) (xy 345.774466 -276.104258) (xy 345.74721 -276.060343) (xy 345.726588 -276.012951)
			(xy 345.71303 -275.963075) (xy 345.709494 -275.937472) (xy 345.673853 -275.941912) (xy 345.602119 -275.945578)
			(xy 345.530327 -275.943277) (xy 345.49461 -275.939504) (xy 345.485526 -275.938819) (xy 345.467852 -275.943178)
			(xy 345.452836 -275.953468) (xy 345.442393 -275.968379) (xy 345.439746 -275.977096) (xy 345.432458 -276.003024)
			(xy 345.410581 -276.052236) (xy 345.380931 -276.097195) (xy 345.344311 -276.136684) (xy 345.301712 -276.169635)
			(xy 345.254287 -276.195155) (xy 345.20332 -276.212554) (xy 345.15019 -276.221362) (xy 345.123262 -276.221952)
			(xy 345.096347 -276.22141) (xy 345.043241 -276.212602) (xy 344.992296 -276.195214) (xy 344.944888 -276.169716)
			(xy 344.902296 -276.136797) (xy 344.865672 -276.097346) (xy 344.836005 -276.052428) (xy 344.814097 -276.003257)
			(xy 344.806778 -275.97735) (xy 344.804142 -275.968617) (xy 344.793706 -275.953672) (xy 344.778698 -275.943328)
			(xy 344.761017 -275.938895) (xy 344.751914 -275.939504) (xy 344.716191 -275.943223) (xy 344.644397 -275.945442)
			(xy 344.572666 -275.941696) (xy 344.53703 -275.937218) (xy 344.533491 -275.962832) (xy 344.51997 -276.012739)
			(xy 344.499373 -276.060166) (xy 344.472133 -276.104115) (xy 344.438823 -276.143662) (xy 344.400143 -276.177975)
			(xy 344.356906 -276.206332) (xy 344.310023 -276.228138) (xy 344.260478 -276.242933) (xy 344.209315 -276.250406)
			(xy 344.183462 -276.250908) (xy 344.157619 -276.250444) (xy 344.106478 -276.242969) (xy 344.056953 -276.228181)
			(xy 344.010086 -276.206391) (xy 343.96686 -276.178056) (xy 343.928183 -276.143772) (xy 343.894866 -276.104258)
			(xy 343.86761 -276.060343) (xy 343.846988 -276.012951) (xy 343.83343 -275.963075) (xy 343.829894 -275.937472)
			(xy 343.794253 -275.941912) (xy 343.722519 -275.945578) (xy 343.650727 -275.943277) (xy 343.61501 -275.939504)
			(xy 343.605926 -275.938819) (xy 343.588252 -275.943178) (xy 343.573236 -275.953468) (xy 343.562793 -275.968379)
			(xy 343.560146 -275.977096) (xy 343.553324 -276.001511) (xy 343.533183 -276.048028) (xy 343.506104 -276.09088)
			(xy 343.472736 -276.129039) (xy 343.433878 -276.16159) (xy 343.390462 -276.187754) (xy 343.343528 -276.206904)
			(xy 343.294201 -276.218581) (xy 343.243662 -276.222504) (xy 343.193123 -276.218581) (xy 343.143796 -276.206904)
			(xy 343.096862 -276.187754) (xy 343.053446 -276.16159) (xy 343.014588 -276.129039) (xy 342.98122 -276.09088)
			(xy 342.954141 -276.048028) (xy 342.934 -276.001511) (xy 342.927178 -275.977096) (xy 342.924479 -275.968414)
			(xy 342.913988 -275.95358) (xy 342.899002 -275.943306) (xy 342.881383 -275.938869) (xy 342.872314 -275.939504)
			(xy 342.836633 -275.943224) (xy 342.764923 -275.945444) (xy 342.693277 -275.941699) (xy 342.657684 -275.937218)
			(xy 342.65393 -275.964179) (xy 342.639297 -276.016607) (xy 342.616855 -276.066198) (xy 342.587129 -276.111795)
			(xy 342.550809 -276.152338) (xy 342.508742 -276.186881) (xy 342.461908 -276.21462) (xy 342.411398 -276.234908)
			(xy 342.358389 -276.247273) (xy 342.304116 -276.251427) (xy 342.249843 -276.247273) (xy 342.196834 -276.234908)
			(xy 342.146324 -276.21462) (xy 342.09949 -276.186881) (xy 342.057423 -276.152338) (xy 342.021103 -276.111795)
			(xy 341.991377 -276.066198) (xy 341.968935 -276.016607) (xy 341.954302 -275.964179) (xy 341.950548 -275.937218)
			(xy 341.91487 -275.941699) (xy 341.843055 -275.945443) (xy 341.771176 -275.943217) (xy 341.73541 -275.939504)
			(xy 341.726326 -275.938819) (xy 341.708652 -275.943178) (xy 341.693636 -275.953468) (xy 341.683193 -275.968379)
			(xy 341.680546 -275.977096) (xy 341.673258 -276.003024) (xy 341.651381 -276.052236) (xy 341.621731 -276.097195)
			(xy 341.585111 -276.136684) (xy 341.542512 -276.169635) (xy 341.495087 -276.195155) (xy 341.44412 -276.212554)
			(xy 341.39099 -276.221362) (xy 341.364062 -276.221952) (xy 341.337147 -276.22141) (xy 341.284041 -276.212602)
			(xy 341.233096 -276.195214) (xy 341.185688 -276.169716) (xy 341.143096 -276.136797) (xy 341.106472 -276.097346)
			(xy 341.076805 -276.052428) (xy 341.054897 -276.003257) (xy 341.047578 -275.97735) (xy 341.044942 -275.968617)
			(xy 341.034506 -275.953672) (xy 341.019498 -275.943328) (xy 341.001817 -275.938895) (xy 340.992714 -275.939504)
			(xy 340.79561 -275.939504) (xy 340.786526 -275.938819) (xy 340.768852 -275.943178) (xy 340.753836 -275.953468)
			(xy 340.743393 -275.968379) (xy 340.740746 -275.977096) (xy 340.733924 -276.001511) (xy 340.713783 -276.048028)
			(xy 340.686704 -276.09088) (xy 340.653336 -276.129039) (xy 340.614478 -276.16159) (xy 340.571062 -276.187754)
			(xy 340.524128 -276.206904) (xy 340.474801 -276.218581) (xy 340.424262 -276.222504) (xy 340.373723 -276.218581)
			(xy 340.324396 -276.206904) (xy 340.277462 -276.187754) (xy 340.234046 -276.16159) (xy 340.195188 -276.129039)
			(xy 340.16182 -276.09088) (xy 340.134741 -276.048028) (xy 340.1146 -276.001511) (xy 340.107778 -275.977096)
			(xy 340.105079 -275.968414) (xy 340.094588 -275.95358) (xy 340.079602 -275.943306) (xy 340.061983 -275.938869)
			(xy 340.052914 -275.939504) (xy 340.028361 -275.942129) (xy 339.979055 -275.944926) (xy 339.954362 -275.945092)
			(xy 339.925187 -275.944852) (xy 339.866971 -275.94091) (xy 339.83803 -275.937218) (xy 339.834491 -275.962832)
			(xy 339.82097 -276.012739) (xy 339.800373 -276.060166) (xy 339.773133 -276.104115) (xy 339.739823 -276.143662)
			(xy 339.701143 -276.177975) (xy 339.657906 -276.206332) (xy 339.611023 -276.228138) (xy 339.561478 -276.242933)
			(xy 339.510315 -276.250406) (xy 339.484462 -276.250908) (xy 339.458619 -276.250444) (xy 339.407478 -276.242969)
			(xy 339.357953 -276.228181) (xy 339.311086 -276.206391) (xy 339.26786 -276.178056) (xy 339.229183 -276.143772)
			(xy 339.195866 -276.104258) (xy 339.16861 -276.060343) (xy 339.147988 -276.012951) (xy 339.13443 -275.963075)
			(xy 339.130894 -275.937472) (xy 339.095253 -275.941912) (xy 339.023519 -275.945578) (xy 338.951727 -275.943277)
			(xy 338.91601 -275.939504) (xy 338.906926 -275.938819) (xy 338.889252 -275.943178) (xy 338.874236 -275.953468)
			(xy 338.863793 -275.968379) (xy 338.861146 -275.977096) (xy 338.854324 -276.001511) (xy 338.834183 -276.048028)
			(xy 338.807104 -276.09088) (xy 338.773736 -276.129039) (xy 338.734878 -276.16159) (xy 338.691462 -276.187754)
			(xy 338.644528 -276.206904) (xy 338.595201 -276.218581) (xy 338.544662 -276.222504) (xy 338.494123 -276.218581)
			(xy 338.444796 -276.206904) (xy 338.397862 -276.187754) (xy 338.354446 -276.16159) (xy 338.315588 -276.129039)
			(xy 338.28222 -276.09088) (xy 338.255141 -276.048028) (xy 338.235 -276.001511) (xy 338.228178 -275.977096)
			(xy 338.225479 -275.968414) (xy 338.214988 -275.95358) (xy 338.200002 -275.943306) (xy 338.182383 -275.938869)
			(xy 338.173314 -275.939504) (xy 338.148761 -275.942129) (xy 338.099455 -275.944926) (xy 338.074762 -275.945092)
			(xy 338.045587 -275.944852) (xy 337.987371 -275.94091) (xy 337.95843 -275.937218) (xy 337.954676 -275.964179)
			(xy 337.940043 -276.016607) (xy 337.917601 -276.066198) (xy 337.887875 -276.111795) (xy 337.851555 -276.152338)
			(xy 337.809488 -276.186881) (xy 337.762654 -276.21462) (xy 337.712144 -276.234908) (xy 337.659135 -276.247273)
			(xy 337.604862 -276.251427) (xy 337.550589 -276.247273) (xy 337.49758 -276.234908) (xy 337.44707 -276.21462)
			(xy 337.400236 -276.186881) (xy 337.358169 -276.152338) (xy 337.321849 -276.111795) (xy 337.292123 -276.066198)
			(xy 337.269681 -276.016607) (xy 337.255048 -275.964179) (xy 337.251294 -275.937218) (xy 337.222352 -275.940902)
			(xy 337.164136 -275.944846) (xy 337.134962 -275.945092) (xy 337.110269 -275.944933) (xy 337.060963 -275.942135)
			(xy 337.03641 -275.939504) (xy 337.027326 -275.938819) (xy 337.009652 -275.943178) (xy 336.994636 -275.953468)
			(xy 336.984193 -275.968379) (xy 336.981546 -275.977096) (xy 336.974258 -276.003024) (xy 336.952381 -276.052236)
			(xy 336.922731 -276.097195) (xy 336.886111 -276.136684) (xy 336.843512 -276.169635) (xy 336.796087 -276.195155)
			(xy 336.74512 -276.212554) (xy 336.69199 -276.221362) (xy 336.665062 -276.221952) (xy 336.638147 -276.22141)
			(xy 336.585041 -276.212602) (xy 336.534096 -276.195214) (xy 336.486688 -276.169716) (xy 336.444096 -276.136797)
			(xy 336.407472 -276.097346) (xy 336.377805 -276.052428) (xy 336.355897 -276.003257) (xy 336.348578 -275.97735)
			(xy 336.345942 -275.968617) (xy 336.335506 -275.953672) (xy 336.320498 -275.943328) (xy 336.302817 -275.938895)
			(xy 336.293714 -275.939504) (xy 336.257949 -275.943242) (xy 336.186069 -275.945477) (xy 336.114252 -275.941722)
			(xy 336.078576 -275.937218) (xy 336.075038 -275.962833) (xy 336.061518 -276.012743) (xy 336.040922 -276.060174)
			(xy 336.013682 -276.104126) (xy 335.980373 -276.143677) (xy 335.941693 -276.177994) (xy 335.898457 -276.206357)
			(xy 335.851573 -276.228168) (xy 335.802027 -276.242969) (xy 335.750862 -276.250449) (xy 335.725008 -276.250908)
			(xy 335.698966 -276.250456) (xy 335.647436 -276.242872) (xy 335.59756 -276.227866) (xy 335.550401 -276.205756)
			(xy 335.506965 -276.177014) (xy 335.487264 -276.159976) (xy 335.475427 -276.150069) (xy 335.447362 -276.137252)
			(xy 335.41675 -276.133411) (xy 335.386389 -276.138896) (xy 335.359055 -276.153207) (xy 335.347818 -276.163786)
			(xy 334.776339 -276.735265) (xy 335.839552 -276.735265) (xy 335.839552 -276.681967) (xy 335.847495 -276.629263)
			(xy 335.863205 -276.578333) (xy 335.886331 -276.530312) (xy 335.916355 -276.486275) (xy 335.952607 -276.447204)
			(xy 335.994278 -276.413973) (xy 336.040436 -276.387324) (xy 336.09005 -276.367852) (xy 336.142012 -276.355992)
			(xy 336.195162 -276.352009) (xy 336.248312 -276.355992) (xy 336.300274 -276.367852) (xy 336.349888 -276.387324)
			(xy 336.396046 -276.413973) (xy 336.437717 -276.447204) (xy 336.473969 -276.486275) (xy 336.503993 -276.530312)
			(xy 336.527119 -276.578333) (xy 336.542829 -276.629263) (xy 336.550772 -276.681967) (xy 336.55127 -276.708616)
			(xy 336.55079 -276.734324) (xy 336.808314 -276.734324) (xy 336.808314 -276.682908) (xy 336.816357 -276.632126)
			(xy 336.832245 -276.583227) (xy 336.855588 -276.537415) (xy 336.885809 -276.495819) (xy 336.922165 -276.459463)
			(xy 336.963761 -276.429242) (xy 337.009573 -276.405899) (xy 337.058472 -276.390011) (xy 337.109254 -276.381968)
			(xy 337.16067 -276.381968) (xy 337.211452 -276.390011) (xy 337.260351 -276.405899) (xy 337.306163 -276.429242)
			(xy 337.347759 -276.459463) (xy 337.384115 -276.495819) (xy 337.414336 -276.537415) (xy 337.437679 -276.583227)
			(xy 337.453567 -276.632126) (xy 337.46161 -276.682908) (xy 337.462114 -276.708616) (xy 337.46161 -276.734324)
			(xy 337.748114 -276.734324) (xy 337.748114 -276.682908) (xy 337.756157 -276.632126) (xy 337.772045 -276.583227)
			(xy 337.795388 -276.537415) (xy 337.825609 -276.495819) (xy 337.861965 -276.459463) (xy 337.903561 -276.429242)
			(xy 337.949373 -276.405899) (xy 337.998272 -276.390011) (xy 338.049054 -276.381968) (xy 338.10047 -276.381968)
			(xy 338.151252 -276.390011) (xy 338.200151 -276.405899) (xy 338.245963 -276.429242) (xy 338.287559 -276.459463)
			(xy 338.323915 -276.495819) (xy 338.354136 -276.537415) (xy 338.377479 -276.583227) (xy 338.393367 -276.632126)
			(xy 338.40141 -276.682908) (xy 338.401914 -276.708616) (xy 338.40141 -276.734324) (xy 338.401261 -276.735265)
			(xy 338.658952 -276.735265) (xy 338.658952 -276.681967) (xy 338.666895 -276.629263) (xy 338.682605 -276.578333)
			(xy 338.705731 -276.530312) (xy 338.735755 -276.486275) (xy 338.772007 -276.447204) (xy 338.813678 -276.413973)
			(xy 338.859836 -276.387324) (xy 338.90945 -276.367852) (xy 338.961412 -276.355992) (xy 339.014562 -276.352009)
			(xy 339.067712 -276.355992) (xy 339.119674 -276.367852) (xy 339.169288 -276.387324) (xy 339.215446 -276.413973)
			(xy 339.257117 -276.447204) (xy 339.293369 -276.486275) (xy 339.323393 -276.530312) (xy 339.346519 -276.578333)
			(xy 339.362229 -276.629263) (xy 339.370172 -276.681967) (xy 339.37067 -276.708616) (xy 339.37019 -276.734324)
			(xy 339.627968 -276.734324) (xy 339.627968 -276.682908) (xy 339.636011 -276.632126) (xy 339.651899 -276.583227)
			(xy 339.675242 -276.537415) (xy 339.705463 -276.495819) (xy 339.741819 -276.459463) (xy 339.783415 -276.429242)
			(xy 339.829227 -276.405899) (xy 339.878126 -276.390011) (xy 339.928908 -276.381968) (xy 339.980324 -276.381968)
			(xy 340.031106 -276.390011) (xy 340.080005 -276.405899) (xy 340.125817 -276.429242) (xy 340.167413 -276.459463)
			(xy 340.203769 -276.495819) (xy 340.23399 -276.537415) (xy 340.257333 -276.583227) (xy 340.273221 -276.632126)
			(xy 340.281264 -276.682908) (xy 340.281768 -276.708616) (xy 340.281264 -276.734324) (xy 340.281115 -276.735265)
			(xy 340.538806 -276.735265) (xy 340.538806 -276.681967) (xy 340.546749 -276.629263) (xy 340.562459 -276.578333)
			(xy 340.585585 -276.530312) (xy 340.615609 -276.486275) (xy 340.651861 -276.447204) (xy 340.693532 -276.413973)
			(xy 340.73969 -276.387324) (xy 340.789304 -276.367852) (xy 340.841266 -276.355992) (xy 340.894416 -276.352009)
			(xy 340.947566 -276.355992) (xy 340.999528 -276.367852) (xy 341.049142 -276.387324) (xy 341.0953 -276.413973)
			(xy 341.136971 -276.447204) (xy 341.173223 -276.486275) (xy 341.203247 -276.530312) (xy 341.226373 -276.578333)
			(xy 341.242083 -276.629263) (xy 341.250026 -276.681967) (xy 341.250524 -276.708616) (xy 341.250044 -276.734324)
			(xy 341.507568 -276.734324) (xy 341.507568 -276.682908) (xy 341.515611 -276.632126) (xy 341.531499 -276.583227)
			(xy 341.554842 -276.537415) (xy 341.585063 -276.495819) (xy 341.621419 -276.459463) (xy 341.663015 -276.429242)
			(xy 341.708827 -276.405899) (xy 341.757726 -276.390011) (xy 341.808508 -276.381968) (xy 341.859924 -276.381968)
			(xy 341.910706 -276.390011) (xy 341.959605 -276.405899) (xy 342.005417 -276.429242) (xy 342.047013 -276.459463)
			(xy 342.083369 -276.495819) (xy 342.11359 -276.537415) (xy 342.136933 -276.583227) (xy 342.152821 -276.632126)
			(xy 342.160864 -276.682908) (xy 342.161368 -276.708616) (xy 342.160864 -276.734324) (xy 342.160715 -276.735265)
			(xy 342.418406 -276.735265) (xy 342.418406 -276.681967) (xy 342.426349 -276.629263) (xy 342.442059 -276.578333)
			(xy 342.465185 -276.530312) (xy 342.495209 -276.486275) (xy 342.531461 -276.447204) (xy 342.573132 -276.413973)
			(xy 342.61929 -276.387324) (xy 342.668904 -276.367852) (xy 342.720866 -276.355992) (xy 342.774016 -276.352009)
			(xy 342.827166 -276.355992) (xy 342.879128 -276.367852) (xy 342.928742 -276.387324) (xy 342.9749 -276.413973)
			(xy 343.016571 -276.447204) (xy 343.052823 -276.486275) (xy 343.082847 -276.530312) (xy 343.105973 -276.578333)
			(xy 343.121683 -276.629263) (xy 343.129626 -276.681967) (xy 343.130124 -276.708616) (xy 343.129644 -276.734324)
			(xy 343.387168 -276.734324) (xy 343.387168 -276.682908) (xy 343.395211 -276.632126) (xy 343.411099 -276.583227)
			(xy 343.434442 -276.537415) (xy 343.464663 -276.495819) (xy 343.501019 -276.459463) (xy 343.542615 -276.429242)
			(xy 343.588427 -276.405899) (xy 343.637326 -276.390011) (xy 343.688108 -276.381968) (xy 343.739524 -276.381968)
			(xy 343.790306 -276.390011) (xy 343.839205 -276.405899) (xy 343.885017 -276.429242) (xy 343.926613 -276.459463)
			(xy 343.962969 -276.495819) (xy 343.99319 -276.537415) (xy 344.016533 -276.583227) (xy 344.032421 -276.632126)
			(xy 344.040464 -276.682908) (xy 344.040968 -276.708616) (xy 344.040464 -276.734324) (xy 344.326968 -276.734324)
			(xy 344.326968 -276.682908) (xy 344.335011 -276.632126) (xy 344.350899 -276.583227) (xy 344.374242 -276.537415)
			(xy 344.404463 -276.495819) (xy 344.440819 -276.459463) (xy 344.482415 -276.429242) (xy 344.528227 -276.405899)
			(xy 344.577126 -276.390011) (xy 344.627908 -276.381968) (xy 344.679324 -276.381968) (xy 344.730106 -276.390011)
			(xy 344.779005 -276.405899) (xy 344.824817 -276.429242) (xy 344.866413 -276.459463) (xy 344.902769 -276.495819)
			(xy 344.93299 -276.537415) (xy 344.956333 -276.583227) (xy 344.972221 -276.632126) (xy 344.980264 -276.682908)
			(xy 344.980768 -276.708616) (xy 344.980264 -276.734324) (xy 344.980115 -276.735265) (xy 345.237552 -276.735265)
			(xy 345.237552 -276.681967) (xy 345.245495 -276.629263) (xy 345.261205 -276.578333) (xy 345.284331 -276.530312)
			(xy 345.314355 -276.486275) (xy 345.350607 -276.447204) (xy 345.392278 -276.413973) (xy 345.438436 -276.387324)
			(xy 345.48805 -276.367852) (xy 345.540012 -276.355992) (xy 345.593162 -276.352009) (xy 345.646312 -276.355992)
			(xy 345.698274 -276.367852) (xy 345.747888 -276.387324) (xy 345.794046 -276.413973) (xy 345.835717 -276.447204)
			(xy 345.871969 -276.486275) (xy 345.901993 -276.530312) (xy 345.925119 -276.578333) (xy 345.940829 -276.629263)
			(xy 345.948772 -276.681967) (xy 345.94927 -276.708616) (xy 345.94879 -276.734324) (xy 346.206568 -276.734324)
			(xy 346.206568 -276.682908) (xy 346.214611 -276.632126) (xy 346.230499 -276.583227) (xy 346.253842 -276.537415)
			(xy 346.284063 -276.495819) (xy 346.320419 -276.459463) (xy 346.362015 -276.429242) (xy 346.407827 -276.405899)
			(xy 346.456726 -276.390011) (xy 346.507508 -276.381968) (xy 346.558924 -276.381968) (xy 346.609706 -276.390011)
			(xy 346.658605 -276.405899) (xy 346.704417 -276.429242) (xy 346.746013 -276.459463) (xy 346.782369 -276.495819)
			(xy 346.81259 -276.537415) (xy 346.835933 -276.583227) (xy 346.851821 -276.632126) (xy 346.859864 -276.682908)
			(xy 346.860368 -276.708616) (xy 346.859864 -276.734324) (xy 346.859715 -276.735265) (xy 347.117406 -276.735265)
			(xy 347.117406 -276.681967) (xy 347.125349 -276.629263) (xy 347.141059 -276.578333) (xy 347.164185 -276.530312)
			(xy 347.194209 -276.486275) (xy 347.230461 -276.447204) (xy 347.272132 -276.413973) (xy 347.31829 -276.387324)
			(xy 347.367904 -276.367852) (xy 347.419866 -276.355992) (xy 347.473016 -276.352009) (xy 347.526166 -276.355992)
			(xy 347.578128 -276.367852) (xy 347.627742 -276.387324) (xy 347.6739 -276.413973) (xy 347.715571 -276.447204)
			(xy 347.751823 -276.486275) (xy 347.781847 -276.530312) (xy 347.804973 -276.578333) (xy 347.820683 -276.629263)
			(xy 347.828626 -276.681967) (xy 347.829124 -276.708616) (xy 347.828644 -276.734324) (xy 348.086168 -276.734324)
			(xy 348.086168 -276.682908) (xy 348.094211 -276.632126) (xy 348.110099 -276.583227) (xy 348.133442 -276.537415)
			(xy 348.163663 -276.495819) (xy 348.200019 -276.459463) (xy 348.241615 -276.429242) (xy 348.287427 -276.405899)
			(xy 348.336326 -276.390011) (xy 348.387108 -276.381968) (xy 348.438524 -276.381968) (xy 348.489306 -276.390011)
			(xy 348.538205 -276.405899) (xy 348.584017 -276.429242) (xy 348.625613 -276.459463) (xy 348.661969 -276.495819)
			(xy 348.69219 -276.537415) (xy 348.715533 -276.583227) (xy 348.731421 -276.632126) (xy 348.739464 -276.682908)
			(xy 348.739968 -276.708616) (xy 348.739464 -276.734324) (xy 348.739315 -276.735265) (xy 348.997006 -276.735265)
			(xy 348.997006 -276.681967) (xy 349.004949 -276.629263) (xy 349.020659 -276.578333) (xy 349.043785 -276.530312)
			(xy 349.073809 -276.486275) (xy 349.110061 -276.447204) (xy 349.151732 -276.413973) (xy 349.19789 -276.387324)
			(xy 349.247504 -276.367852) (xy 349.299466 -276.355992) (xy 349.352616 -276.352009) (xy 349.405766 -276.355992)
			(xy 349.457728 -276.367852) (xy 349.507342 -276.387324) (xy 349.5535 -276.413973) (xy 349.595171 -276.447204)
			(xy 349.631423 -276.486275) (xy 349.661447 -276.530312) (xy 349.684573 -276.578333) (xy 349.700283 -276.629263)
			(xy 349.708226 -276.681967) (xy 349.708724 -276.708616) (xy 349.708226 -276.735265) (xy 349.700283 -276.787969)
			(xy 349.684573 -276.838899) (xy 349.661447 -276.88692) (xy 349.631423 -276.930957) (xy 349.595171 -276.970028)
			(xy 349.5535 -277.003259) (xy 349.507342 -277.029908) (xy 349.457728 -277.04938) (xy 349.405766 -277.06124)
			(xy 349.352616 -277.065224) (xy 349.299466 -277.06124) (xy 349.247504 -277.04938) (xy 349.19789 -277.029908)
			(xy 349.151732 -277.003259) (xy 349.110061 -276.970028) (xy 349.073809 -276.930957) (xy 349.043785 -276.88692)
			(xy 349.020659 -276.838899) (xy 349.004949 -276.787969) (xy 348.997006 -276.735265) (xy 348.739315 -276.735265)
			(xy 348.731421 -276.785106) (xy 348.715533 -276.834005) (xy 348.69219 -276.879817) (xy 348.661969 -276.921413)
			(xy 348.625613 -276.957769) (xy 348.584017 -276.98799) (xy 348.538205 -277.011333) (xy 348.489306 -277.027221)
			(xy 348.438524 -277.035264) (xy 348.387108 -277.035264) (xy 348.336326 -277.027221) (xy 348.287427 -277.011333)
			(xy 348.241615 -276.98799) (xy 348.200019 -276.957769) (xy 348.163663 -276.921413) (xy 348.133442 -276.879817)
			(xy 348.110099 -276.834005) (xy 348.094211 -276.785106) (xy 348.086168 -276.734324) (xy 347.828644 -276.734324)
			(xy 347.828626 -276.735265) (xy 347.820683 -276.787969) (xy 347.804973 -276.838899) (xy 347.781847 -276.88692)
			(xy 347.751823 -276.930957) (xy 347.715571 -276.970028) (xy 347.6739 -277.003259) (xy 347.627742 -277.029908)
			(xy 347.578128 -277.04938) (xy 347.526166 -277.06124) (xy 347.473016 -277.065224) (xy 347.419866 -277.06124)
			(xy 347.367904 -277.04938) (xy 347.31829 -277.029908) (xy 347.272132 -277.003259) (xy 347.230461 -276.970028)
			(xy 347.194209 -276.930957) (xy 347.164185 -276.88692) (xy 347.141059 -276.838899) (xy 347.125349 -276.787969)
			(xy 347.117406 -276.735265) (xy 346.859715 -276.735265) (xy 346.851821 -276.785106) (xy 346.835933 -276.834005)
			(xy 346.81259 -276.879817) (xy 346.782369 -276.921413) (xy 346.746013 -276.957769) (xy 346.704417 -276.98799)
			(xy 346.658605 -277.011333) (xy 346.609706 -277.027221) (xy 346.558924 -277.035264) (xy 346.507508 -277.035264)
			(xy 346.456726 -277.027221) (xy 346.407827 -277.011333) (xy 346.362015 -276.98799) (xy 346.320419 -276.957769)
			(xy 346.284063 -276.921413) (xy 346.253842 -276.879817) (xy 346.230499 -276.834005) (xy 346.214611 -276.785106)
			(xy 346.206568 -276.734324) (xy 345.94879 -276.734324) (xy 345.948772 -276.735265) (xy 345.940829 -276.787969)
			(xy 345.925119 -276.838899) (xy 345.901993 -276.88692) (xy 345.871969 -276.930957) (xy 345.835717 -276.970028)
			(xy 345.794046 -277.003259) (xy 345.747888 -277.029908) (xy 345.698274 -277.04938) (xy 345.646312 -277.06124)
			(xy 345.593162 -277.065224) (xy 345.540012 -277.06124) (xy 345.48805 -277.04938) (xy 345.438436 -277.029908)
			(xy 345.392278 -277.003259) (xy 345.350607 -276.970028) (xy 345.314355 -276.930957) (xy 345.284331 -276.88692)
			(xy 345.261205 -276.838899) (xy 345.245495 -276.787969) (xy 345.237552 -276.735265) (xy 344.980115 -276.735265)
			(xy 344.972221 -276.785106) (xy 344.956333 -276.834005) (xy 344.93299 -276.879817) (xy 344.902769 -276.921413)
			(xy 344.866413 -276.957769) (xy 344.824817 -276.98799) (xy 344.779005 -277.011333) (xy 344.730106 -277.027221)
			(xy 344.679324 -277.035264) (xy 344.627908 -277.035264) (xy 344.577126 -277.027221) (xy 344.528227 -277.011333)
			(xy 344.482415 -276.98799) (xy 344.440819 -276.957769) (xy 344.404463 -276.921413) (xy 344.374242 -276.879817)
			(xy 344.350899 -276.834005) (xy 344.335011 -276.785106) (xy 344.326968 -276.734324) (xy 344.040464 -276.734324)
			(xy 344.032421 -276.785106) (xy 344.016533 -276.834005) (xy 343.99319 -276.879817) (xy 343.962969 -276.921413)
			(xy 343.926613 -276.957769) (xy 343.885017 -276.98799) (xy 343.839205 -277.011333) (xy 343.790306 -277.027221)
			(xy 343.739524 -277.035264) (xy 343.688108 -277.035264) (xy 343.637326 -277.027221) (xy 343.588427 -277.011333)
			(xy 343.542615 -276.98799) (xy 343.501019 -276.957769) (xy 343.464663 -276.921413) (xy 343.434442 -276.879817)
			(xy 343.411099 -276.834005) (xy 343.395211 -276.785106) (xy 343.387168 -276.734324) (xy 343.129644 -276.734324)
			(xy 343.129626 -276.735265) (xy 343.121683 -276.787969) (xy 343.105973 -276.838899) (xy 343.082847 -276.88692)
			(xy 343.052823 -276.930957) (xy 343.016571 -276.970028) (xy 342.9749 -277.003259) (xy 342.928742 -277.029908)
			(xy 342.879128 -277.04938) (xy 342.827166 -277.06124) (xy 342.774016 -277.065224) (xy 342.720866 -277.06124)
			(xy 342.668904 -277.04938) (xy 342.61929 -277.029908) (xy 342.573132 -277.003259) (xy 342.531461 -276.970028)
			(xy 342.495209 -276.930957) (xy 342.465185 -276.88692) (xy 342.442059 -276.838899) (xy 342.426349 -276.787969)
			(xy 342.418406 -276.735265) (xy 342.160715 -276.735265) (xy 342.152821 -276.785106) (xy 342.136933 -276.834005)
			(xy 342.11359 -276.879817) (xy 342.083369 -276.921413) (xy 342.047013 -276.957769) (xy 342.005417 -276.98799)
			(xy 341.959605 -277.011333) (xy 341.910706 -277.027221) (xy 341.859924 -277.035264) (xy 341.808508 -277.035264)
			(xy 341.757726 -277.027221) (xy 341.708827 -277.011333) (xy 341.663015 -276.98799) (xy 341.621419 -276.957769)
			(xy 341.585063 -276.921413) (xy 341.554842 -276.879817) (xy 341.531499 -276.834005) (xy 341.515611 -276.785106)
			(xy 341.507568 -276.734324) (xy 341.250044 -276.734324) (xy 341.250026 -276.735265) (xy 341.242083 -276.787969)
			(xy 341.226373 -276.838899) (xy 341.203247 -276.88692) (xy 341.173223 -276.930957) (xy 341.136971 -276.970028)
			(xy 341.0953 -277.003259) (xy 341.049142 -277.029908) (xy 340.999528 -277.04938) (xy 340.947566 -277.06124)
			(xy 340.894416 -277.065224) (xy 340.841266 -277.06124) (xy 340.789304 -277.04938) (xy 340.73969 -277.029908)
			(xy 340.693532 -277.003259) (xy 340.651861 -276.970028) (xy 340.615609 -276.930957) (xy 340.585585 -276.88692)
			(xy 340.562459 -276.838899) (xy 340.546749 -276.787969) (xy 340.538806 -276.735265) (xy 340.281115 -276.735265)
			(xy 340.273221 -276.785106) (xy 340.257333 -276.834005) (xy 340.23399 -276.879817) (xy 340.203769 -276.921413)
			(xy 340.167413 -276.957769) (xy 340.125817 -276.98799) (xy 340.080005 -277.011333) (xy 340.031106 -277.027221)
			(xy 339.980324 -277.035264) (xy 339.928908 -277.035264) (xy 339.878126 -277.027221) (xy 339.829227 -277.011333)
			(xy 339.783415 -276.98799) (xy 339.741819 -276.957769) (xy 339.705463 -276.921413) (xy 339.675242 -276.879817)
			(xy 339.651899 -276.834005) (xy 339.636011 -276.785106) (xy 339.627968 -276.734324) (xy 339.37019 -276.734324)
			(xy 339.370172 -276.735265) (xy 339.362229 -276.787969) (xy 339.346519 -276.838899) (xy 339.323393 -276.88692)
			(xy 339.293369 -276.930957) (xy 339.257117 -276.970028) (xy 339.215446 -277.003259) (xy 339.169288 -277.029908)
			(xy 339.119674 -277.04938) (xy 339.067712 -277.06124) (xy 339.014562 -277.065224) (xy 338.961412 -277.06124)
			(xy 338.90945 -277.04938) (xy 338.859836 -277.029908) (xy 338.813678 -277.003259) (xy 338.772007 -276.970028)
			(xy 338.735755 -276.930957) (xy 338.705731 -276.88692) (xy 338.682605 -276.838899) (xy 338.666895 -276.787969)
			(xy 338.658952 -276.735265) (xy 338.401261 -276.735265) (xy 338.393367 -276.785106) (xy 338.377479 -276.834005)
			(xy 338.354136 -276.879817) (xy 338.323915 -276.921413) (xy 338.287559 -276.957769) (xy 338.245963 -276.98799)
			(xy 338.200151 -277.011333) (xy 338.151252 -277.027221) (xy 338.10047 -277.035264) (xy 338.049054 -277.035264)
			(xy 337.998272 -277.027221) (xy 337.949373 -277.011333) (xy 337.903561 -276.98799) (xy 337.861965 -276.957769)
			(xy 337.825609 -276.921413) (xy 337.795388 -276.879817) (xy 337.772045 -276.834005) (xy 337.756157 -276.785106)
			(xy 337.748114 -276.734324) (xy 337.46161 -276.734324) (xy 337.453567 -276.785106) (xy 337.437679 -276.834005)
			(xy 337.414336 -276.879817) (xy 337.384115 -276.921413) (xy 337.347759 -276.957769) (xy 337.306163 -276.98799)
			(xy 337.260351 -277.011333) (xy 337.211452 -277.027221) (xy 337.16067 -277.035264) (xy 337.109254 -277.035264)
			(xy 337.058472 -277.027221) (xy 337.009573 -277.011333) (xy 336.963761 -276.98799) (xy 336.922165 -276.957769)
			(xy 336.885809 -276.921413) (xy 336.855588 -276.879817) (xy 336.832245 -276.834005) (xy 336.816357 -276.785106)
			(xy 336.808314 -276.734324) (xy 336.55079 -276.734324) (xy 336.550772 -276.735265) (xy 336.542829 -276.787969)
			(xy 336.527119 -276.838899) (xy 336.503993 -276.88692) (xy 336.473969 -276.930957) (xy 336.437717 -276.970028)
			(xy 336.396046 -277.003259) (xy 336.349888 -277.029908) (xy 336.300274 -277.04938) (xy 336.248312 -277.06124)
			(xy 336.195162 -277.065224) (xy 336.142012 -277.06124) (xy 336.09005 -277.04938) (xy 336.040436 -277.029908)
			(xy 335.994278 -277.003259) (xy 335.952607 -276.970028) (xy 335.916355 -276.930957) (xy 335.886331 -276.88692)
			(xy 335.863205 -276.838899) (xy 335.847495 -276.787969) (xy 335.839552 -276.735265) (xy 334.776339 -276.735265)
			(xy 334.240653 -277.270951) (xy 334.886036 -277.270951) (xy 334.886036 -277.217653) (xy 334.893979 -277.164949)
			(xy 334.909689 -277.114019) (xy 334.932815 -277.065998) (xy 334.962839 -277.021961) (xy 334.999091 -276.98289)
			(xy 335.040762 -276.949659) (xy 335.08692 -276.92301) (xy 335.136534 -276.903538) (xy 335.188496 -276.891678)
			(xy 335.241646 -276.887695) (xy 335.294796 -276.891678) (xy 335.346758 -276.903538) (xy 335.396372 -276.92301)
			(xy 335.44253 -276.949659) (xy 335.484201 -276.98289) (xy 335.520453 -277.021961) (xy 335.550477 -277.065998)
			(xy 335.573603 -277.114019) (xy 335.589313 -277.164949) (xy 335.597256 -277.217653) (xy 335.597754 -277.244302)
			(xy 335.597256 -277.270951) (xy 335.589313 -277.323655) (xy 335.573603 -277.374585) (xy 335.550477 -277.422606)
			(xy 335.520453 -277.466643) (xy 335.484201 -277.505714) (xy 335.44253 -277.538945) (xy 335.424534 -277.549335)
			(xy 336.309198 -277.549335) (xy 336.309198 -277.496037) (xy 336.317141 -277.443333) (xy 336.332851 -277.392403)
			(xy 336.355977 -277.344382) (xy 336.386001 -277.300345) (xy 336.422253 -277.261274) (xy 336.463924 -277.228043)
			(xy 336.510082 -277.201394) (xy 336.559696 -277.181922) (xy 336.611658 -277.170062) (xy 336.664808 -277.166079)
			(xy 336.717958 -277.170062) (xy 336.76992 -277.181922) (xy 336.819534 -277.201394) (xy 336.865692 -277.228043)
			(xy 336.907363 -277.261274) (xy 336.943615 -277.300345) (xy 336.973639 -277.344382) (xy 336.996765 -277.392403)
			(xy 337.012475 -277.443333) (xy 337.020418 -277.496037) (xy 337.020916 -277.522686) (xy 337.020423 -277.549081)
			(xy 337.249252 -277.549081) (xy 337.249252 -277.495783) (xy 337.257195 -277.443079) (xy 337.272905 -277.392149)
			(xy 337.296031 -277.344128) (xy 337.326055 -277.300091) (xy 337.362307 -277.26102) (xy 337.403978 -277.227789)
			(xy 337.450136 -277.20114) (xy 337.49975 -277.181668) (xy 337.551712 -277.169808) (xy 337.604862 -277.165825)
			(xy 337.658012 -277.169808) (xy 337.709974 -277.181668) (xy 337.759588 -277.20114) (xy 337.805746 -277.227789)
			(xy 337.847417 -277.26102) (xy 337.883669 -277.300091) (xy 337.913693 -277.344128) (xy 337.936819 -277.392149)
			(xy 337.952529 -277.443079) (xy 337.960472 -277.495783) (xy 337.96097 -277.522432) (xy 337.960472 -277.549081)
			(xy 338.189306 -277.549081) (xy 338.189306 -277.495783) (xy 338.197249 -277.443079) (xy 338.212959 -277.392149)
			(xy 338.236085 -277.344128) (xy 338.266109 -277.300091) (xy 338.302361 -277.26102) (xy 338.344032 -277.227789)
			(xy 338.39019 -277.20114) (xy 338.439804 -277.181668) (xy 338.491766 -277.169808) (xy 338.544916 -277.165825)
			(xy 338.598066 -277.169808) (xy 338.650028 -277.181668) (xy 338.699642 -277.20114) (xy 338.7458 -277.227789)
			(xy 338.787471 -277.26102) (xy 338.823723 -277.300091) (xy 338.853747 -277.344128) (xy 338.876873 -277.392149)
			(xy 338.892583 -277.443079) (xy 338.900526 -277.495783) (xy 338.901024 -277.522432) (xy 338.900544 -277.54814)
			(xy 339.157814 -277.54814) (xy 339.157814 -277.496724) (xy 339.165857 -277.445942) (xy 339.181745 -277.397043)
			(xy 339.205088 -277.351231) (xy 339.235309 -277.309635) (xy 339.271665 -277.273279) (xy 339.313261 -277.243058)
			(xy 339.359073 -277.219715) (xy 339.407972 -277.203827) (xy 339.458754 -277.195784) (xy 339.51017 -277.195784)
			(xy 339.560952 -277.203827) (xy 339.609851 -277.219715) (xy 339.655663 -277.243058) (xy 339.697259 -277.273279)
			(xy 339.733615 -277.309635) (xy 339.763836 -277.351231) (xy 339.787179 -277.397043) (xy 339.803067 -277.445942)
			(xy 339.81111 -277.496724) (xy 339.811614 -277.522432) (xy 339.81111 -277.54814) (xy 340.097614 -277.54814)
			(xy 340.097614 -277.496724) (xy 340.105657 -277.445942) (xy 340.121545 -277.397043) (xy 340.144888 -277.351231)
			(xy 340.175109 -277.309635) (xy 340.211465 -277.273279) (xy 340.253061 -277.243058) (xy 340.298873 -277.219715)
			(xy 340.347772 -277.203827) (xy 340.398554 -277.195784) (xy 340.44997 -277.195784) (xy 340.500752 -277.203827)
			(xy 340.549651 -277.219715) (xy 340.595463 -277.243058) (xy 340.637059 -277.273279) (xy 340.673415 -277.309635)
			(xy 340.703636 -277.351231) (xy 340.726979 -277.397043) (xy 340.742867 -277.445942) (xy 340.75091 -277.496724)
			(xy 340.751414 -277.522432) (xy 340.75091 -277.54814) (xy 341.037414 -277.54814) (xy 341.037414 -277.496724)
			(xy 341.045457 -277.445942) (xy 341.061345 -277.397043) (xy 341.084688 -277.351231) (xy 341.114909 -277.309635)
			(xy 341.151265 -277.273279) (xy 341.192861 -277.243058) (xy 341.238673 -277.219715) (xy 341.287572 -277.203827)
			(xy 341.338354 -277.195784) (xy 341.38977 -277.195784) (xy 341.440552 -277.203827) (xy 341.489451 -277.219715)
			(xy 341.535263 -277.243058) (xy 341.576859 -277.273279) (xy 341.613215 -277.309635) (xy 341.643436 -277.351231)
			(xy 341.666779 -277.397043) (xy 341.682667 -277.445942) (xy 341.69071 -277.496724) (xy 341.691214 -277.522432)
			(xy 341.69071 -277.54814) (xy 341.977214 -277.54814) (xy 341.977214 -277.496724) (xy 341.985257 -277.445942)
			(xy 342.001145 -277.397043) (xy 342.024488 -277.351231) (xy 342.054709 -277.309635) (xy 342.091065 -277.273279)
			(xy 342.132661 -277.243058) (xy 342.178473 -277.219715) (xy 342.227372 -277.203827) (xy 342.278154 -277.195784)
			(xy 342.32957 -277.195784) (xy 342.380352 -277.203827) (xy 342.429251 -277.219715) (xy 342.475063 -277.243058)
			(xy 342.516659 -277.273279) (xy 342.553015 -277.309635) (xy 342.583236 -277.351231) (xy 342.606579 -277.397043)
			(xy 342.622467 -277.445942) (xy 342.63051 -277.496724) (xy 342.631014 -277.522432) (xy 342.63051 -277.54814)
			(xy 342.630361 -277.549081) (xy 342.888052 -277.549081) (xy 342.888052 -277.495783) (xy 342.895995 -277.443079)
			(xy 342.911705 -277.392149) (xy 342.934831 -277.344128) (xy 342.964855 -277.300091) (xy 343.001107 -277.26102)
			(xy 343.042778 -277.227789) (xy 343.088936 -277.20114) (xy 343.13855 -277.181668) (xy 343.190512 -277.169808)
			(xy 343.243662 -277.165825) (xy 343.296812 -277.169808) (xy 343.348774 -277.181668) (xy 343.398388 -277.20114)
			(xy 343.444546 -277.227789) (xy 343.486217 -277.26102) (xy 343.522469 -277.300091) (xy 343.552493 -277.344128)
			(xy 343.575619 -277.392149) (xy 343.591329 -277.443079) (xy 343.599272 -277.495783) (xy 343.59977 -277.522432)
			(xy 343.599272 -277.549081) (xy 343.827852 -277.549081) (xy 343.827852 -277.495783) (xy 343.835795 -277.443079)
			(xy 343.851505 -277.392149) (xy 343.874631 -277.344128) (xy 343.904655 -277.300091) (xy 343.940907 -277.26102)
			(xy 343.982578 -277.227789) (xy 344.028736 -277.20114) (xy 344.07835 -277.181668) (xy 344.130312 -277.169808)
			(xy 344.183462 -277.165825) (xy 344.236612 -277.169808) (xy 344.288574 -277.181668) (xy 344.338188 -277.20114)
			(xy 344.384346 -277.227789) (xy 344.426017 -277.26102) (xy 344.462269 -277.300091) (xy 344.492293 -277.344128)
			(xy 344.515419 -277.392149) (xy 344.531129 -277.443079) (xy 344.539072 -277.495783) (xy 344.53957 -277.522432)
			(xy 344.539072 -277.549081) (xy 344.767652 -277.549081) (xy 344.767652 -277.495783) (xy 344.775595 -277.443079)
			(xy 344.791305 -277.392149) (xy 344.814431 -277.344128) (xy 344.844455 -277.300091) (xy 344.880707 -277.26102)
			(xy 344.922378 -277.227789) (xy 344.968536 -277.20114) (xy 345.01815 -277.181668) (xy 345.070112 -277.169808)
			(xy 345.123262 -277.165825) (xy 345.176412 -277.169808) (xy 345.228374 -277.181668) (xy 345.277988 -277.20114)
			(xy 345.324146 -277.227789) (xy 345.365817 -277.26102) (xy 345.402069 -277.300091) (xy 345.432093 -277.344128)
			(xy 345.455219 -277.392149) (xy 345.470929 -277.443079) (xy 345.478872 -277.495783) (xy 345.47937 -277.522432)
			(xy 345.47889 -277.54814) (xy 345.736414 -277.54814) (xy 345.736414 -277.496724) (xy 345.744457 -277.445942)
			(xy 345.760345 -277.397043) (xy 345.783688 -277.351231) (xy 345.813909 -277.309635) (xy 345.850265 -277.273279)
			(xy 345.891861 -277.243058) (xy 345.937673 -277.219715) (xy 345.986572 -277.203827) (xy 346.037354 -277.195784)
			(xy 346.08877 -277.195784) (xy 346.139552 -277.203827) (xy 346.188451 -277.219715) (xy 346.234263 -277.243058)
			(xy 346.275859 -277.273279) (xy 346.312215 -277.309635) (xy 346.342436 -277.351231) (xy 346.365779 -277.397043)
			(xy 346.381667 -277.445942) (xy 346.38971 -277.496724) (xy 346.390214 -277.522432) (xy 346.38971 -277.54814)
			(xy 346.676214 -277.54814) (xy 346.676214 -277.496724) (xy 346.684257 -277.445942) (xy 346.700145 -277.397043)
			(xy 346.723488 -277.351231) (xy 346.753709 -277.309635) (xy 346.790065 -277.273279) (xy 346.831661 -277.243058)
			(xy 346.877473 -277.219715) (xy 346.926372 -277.203827) (xy 346.977154 -277.195784) (xy 347.02857 -277.195784)
			(xy 347.079352 -277.203827) (xy 347.128251 -277.219715) (xy 347.174063 -277.243058) (xy 347.215659 -277.273279)
			(xy 347.252015 -277.309635) (xy 347.282236 -277.351231) (xy 347.305579 -277.397043) (xy 347.321467 -277.445942)
			(xy 347.32951 -277.496724) (xy 347.330014 -277.522432) (xy 347.32951 -277.54814) (xy 347.616014 -277.54814)
			(xy 347.616014 -277.496724) (xy 347.624057 -277.445942) (xy 347.639945 -277.397043) (xy 347.663288 -277.351231)
			(xy 347.693509 -277.309635) (xy 347.729865 -277.273279) (xy 347.771461 -277.243058) (xy 347.817273 -277.219715)
			(xy 347.866172 -277.203827) (xy 347.916954 -277.195784) (xy 347.96837 -277.195784) (xy 348.019152 -277.203827)
			(xy 348.068051 -277.219715) (xy 348.113863 -277.243058) (xy 348.155459 -277.273279) (xy 348.191815 -277.309635)
			(xy 348.222036 -277.351231) (xy 348.245379 -277.397043) (xy 348.261267 -277.445942) (xy 348.26931 -277.496724)
			(xy 348.269814 -277.522432) (xy 348.26931 -277.54814) (xy 348.555814 -277.54814) (xy 348.555814 -277.496724)
			(xy 348.563857 -277.445942) (xy 348.579745 -277.397043) (xy 348.603088 -277.351231) (xy 348.633309 -277.309635)
			(xy 348.669665 -277.273279) (xy 348.711261 -277.243058) (xy 348.757073 -277.219715) (xy 348.805972 -277.203827)
			(xy 348.856754 -277.195784) (xy 348.90817 -277.195784) (xy 348.958952 -277.203827) (xy 349.007851 -277.219715)
			(xy 349.053663 -277.243058) (xy 349.095259 -277.273279) (xy 349.131615 -277.309635) (xy 349.161836 -277.351231)
			(xy 349.185179 -277.397043) (xy 349.201067 -277.445942) (xy 349.20911 -277.496724) (xy 349.209614 -277.522432)
			(xy 349.20911 -277.54814) (xy 349.208961 -277.549081) (xy 349.466906 -277.549081) (xy 349.466906 -277.495783)
			(xy 349.474849 -277.443079) (xy 349.490559 -277.392149) (xy 349.513685 -277.344128) (xy 349.543709 -277.300091)
			(xy 349.579961 -277.26102) (xy 349.621632 -277.227789) (xy 349.66779 -277.20114) (xy 349.717404 -277.181668)
			(xy 349.769366 -277.169808) (xy 349.822516 -277.165825) (xy 349.875666 -277.169808) (xy 349.927628 -277.181668)
			(xy 349.977242 -277.20114) (xy 350.0234 -277.227789) (xy 350.065071 -277.26102) (xy 350.101323 -277.300091)
			(xy 350.131347 -277.344128) (xy 350.154473 -277.392149) (xy 350.170183 -277.443079) (xy 350.178126 -277.495783)
			(xy 350.178624 -277.522432) (xy 350.178126 -277.549081) (xy 350.170183 -277.601785) (xy 350.154473 -277.652715)
			(xy 350.131347 -277.700736) (xy 350.101323 -277.744773) (xy 350.065071 -277.783844) (xy 350.0234 -277.817075)
			(xy 349.977242 -277.843724) (xy 349.927628 -277.863196) (xy 349.875666 -277.875056) (xy 349.822516 -277.87904)
			(xy 349.769366 -277.875056) (xy 349.717404 -277.863196) (xy 349.66779 -277.843724) (xy 349.621632 -277.817075)
			(xy 349.579961 -277.783844) (xy 349.543709 -277.744773) (xy 349.513685 -277.700736) (xy 349.490559 -277.652715)
			(xy 349.474849 -277.601785) (xy 349.466906 -277.549081) (xy 349.208961 -277.549081) (xy 349.201067 -277.598922)
			(xy 349.185179 -277.647821) (xy 349.161836 -277.693633) (xy 349.131615 -277.735229) (xy 349.095259 -277.771585)
			(xy 349.053663 -277.801806) (xy 349.007851 -277.825149) (xy 348.958952 -277.841037) (xy 348.90817 -277.84908)
			(xy 348.856754 -277.84908) (xy 348.805972 -277.841037) (xy 348.757073 -277.825149) (xy 348.711261 -277.801806)
			(xy 348.669665 -277.771585) (xy 348.633309 -277.735229) (xy 348.603088 -277.693633) (xy 348.579745 -277.647821)
			(xy 348.563857 -277.598922) (xy 348.555814 -277.54814) (xy 348.26931 -277.54814) (xy 348.261267 -277.598922)
			(xy 348.245379 -277.647821) (xy 348.222036 -277.693633) (xy 348.191815 -277.735229) (xy 348.155459 -277.771585)
			(xy 348.113863 -277.801806) (xy 348.068051 -277.825149) (xy 348.019152 -277.841037) (xy 347.96837 -277.84908)
			(xy 347.916954 -277.84908) (xy 347.866172 -277.841037) (xy 347.817273 -277.825149) (xy 347.771461 -277.801806)
			(xy 347.729865 -277.771585) (xy 347.693509 -277.735229) (xy 347.663288 -277.693633) (xy 347.639945 -277.647821)
			(xy 347.624057 -277.598922) (xy 347.616014 -277.54814) (xy 347.32951 -277.54814) (xy 347.321467 -277.598922)
			(xy 347.305579 -277.647821) (xy 347.282236 -277.693633) (xy 347.252015 -277.735229) (xy 347.215659 -277.771585)
			(xy 347.174063 -277.801806) (xy 347.128251 -277.825149) (xy 347.079352 -277.841037) (xy 347.02857 -277.84908)
			(xy 346.977154 -277.84908) (xy 346.926372 -277.841037) (xy 346.877473 -277.825149) (xy 346.831661 -277.801806)
			(xy 346.790065 -277.771585) (xy 346.753709 -277.735229) (xy 346.723488 -277.693633) (xy 346.700145 -277.647821)
			(xy 346.684257 -277.598922) (xy 346.676214 -277.54814) (xy 346.38971 -277.54814) (xy 346.381667 -277.598922)
			(xy 346.365779 -277.647821) (xy 346.342436 -277.693633) (xy 346.312215 -277.735229) (xy 346.275859 -277.771585)
			(xy 346.234263 -277.801806) (xy 346.188451 -277.825149) (xy 346.139552 -277.841037) (xy 346.08877 -277.84908)
			(xy 346.037354 -277.84908) (xy 345.986572 -277.841037) (xy 345.937673 -277.825149) (xy 345.891861 -277.801806)
			(xy 345.850265 -277.771585) (xy 345.813909 -277.735229) (xy 345.783688 -277.693633) (xy 345.760345 -277.647821)
			(xy 345.744457 -277.598922) (xy 345.736414 -277.54814) (xy 345.47889 -277.54814) (xy 345.478872 -277.549081)
			(xy 345.470929 -277.601785) (xy 345.455219 -277.652715) (xy 345.432093 -277.700736) (xy 345.402069 -277.744773)
			(xy 345.365817 -277.783844) (xy 345.324146 -277.817075) (xy 345.277988 -277.843724) (xy 345.228374 -277.863196)
			(xy 345.176412 -277.875056) (xy 345.123262 -277.87904) (xy 345.070112 -277.875056) (xy 345.01815 -277.863196)
			(xy 344.968536 -277.843724) (xy 344.922378 -277.817075) (xy 344.880707 -277.783844) (xy 344.844455 -277.744773)
			(xy 344.814431 -277.700736) (xy 344.791305 -277.652715) (xy 344.775595 -277.601785) (xy 344.767652 -277.549081)
			(xy 344.539072 -277.549081) (xy 344.531129 -277.601785) (xy 344.515419 -277.652715) (xy 344.492293 -277.700736)
			(xy 344.462269 -277.744773) (xy 344.426017 -277.783844) (xy 344.384346 -277.817075) (xy 344.338188 -277.843724)
			(xy 344.288574 -277.863196) (xy 344.236612 -277.875056) (xy 344.183462 -277.87904) (xy 344.130312 -277.875056)
			(xy 344.07835 -277.863196) (xy 344.028736 -277.843724) (xy 343.982578 -277.817075) (xy 343.940907 -277.783844)
			(xy 343.904655 -277.744773) (xy 343.874631 -277.700736) (xy 343.851505 -277.652715) (xy 343.835795 -277.601785)
			(xy 343.827852 -277.549081) (xy 343.599272 -277.549081) (xy 343.591329 -277.601785) (xy 343.575619 -277.652715)
			(xy 343.552493 -277.700736) (xy 343.522469 -277.744773) (xy 343.486217 -277.783844) (xy 343.444546 -277.817075)
			(xy 343.398388 -277.843724) (xy 343.348774 -277.863196) (xy 343.296812 -277.875056) (xy 343.243662 -277.87904)
			(xy 343.190512 -277.875056) (xy 343.13855 -277.863196) (xy 343.088936 -277.843724) (xy 343.042778 -277.817075)
			(xy 343.001107 -277.783844) (xy 342.964855 -277.744773) (xy 342.934831 -277.700736) (xy 342.911705 -277.652715)
			(xy 342.895995 -277.601785) (xy 342.888052 -277.549081) (xy 342.630361 -277.549081) (xy 342.622467 -277.598922)
			(xy 342.606579 -277.647821) (xy 342.583236 -277.693633) (xy 342.553015 -277.735229) (xy 342.516659 -277.771585)
			(xy 342.475063 -277.801806) (xy 342.429251 -277.825149) (xy 342.380352 -277.841037) (xy 342.32957 -277.84908)
			(xy 342.278154 -277.84908) (xy 342.227372 -277.841037) (xy 342.178473 -277.825149) (xy 342.132661 -277.801806)
			(xy 342.091065 -277.771585) (xy 342.054709 -277.735229) (xy 342.024488 -277.693633) (xy 342.001145 -277.647821)
			(xy 341.985257 -277.598922) (xy 341.977214 -277.54814) (xy 341.69071 -277.54814) (xy 341.682667 -277.598922)
			(xy 341.666779 -277.647821) (xy 341.643436 -277.693633) (xy 341.613215 -277.735229) (xy 341.576859 -277.771585)
			(xy 341.535263 -277.801806) (xy 341.489451 -277.825149) (xy 341.440552 -277.841037) (xy 341.38977 -277.84908)
			(xy 341.338354 -277.84908) (xy 341.287572 -277.841037) (xy 341.238673 -277.825149) (xy 341.192861 -277.801806)
			(xy 341.151265 -277.771585) (xy 341.114909 -277.735229) (xy 341.084688 -277.693633) (xy 341.061345 -277.647821)
			(xy 341.045457 -277.598922) (xy 341.037414 -277.54814) (xy 340.75091 -277.54814) (xy 340.742867 -277.598922)
			(xy 340.726979 -277.647821) (xy 340.703636 -277.693633) (xy 340.673415 -277.735229) (xy 340.637059 -277.771585)
			(xy 340.595463 -277.801806) (xy 340.549651 -277.825149) (xy 340.500752 -277.841037) (xy 340.44997 -277.84908)
			(xy 340.398554 -277.84908) (xy 340.347772 -277.841037) (xy 340.298873 -277.825149) (xy 340.253061 -277.801806)
			(xy 340.211465 -277.771585) (xy 340.175109 -277.735229) (xy 340.144888 -277.693633) (xy 340.121545 -277.647821)
			(xy 340.105657 -277.598922) (xy 340.097614 -277.54814) (xy 339.81111 -277.54814) (xy 339.803067 -277.598922)
			(xy 339.787179 -277.647821) (xy 339.763836 -277.693633) (xy 339.733615 -277.735229) (xy 339.697259 -277.771585)
			(xy 339.655663 -277.801806) (xy 339.609851 -277.825149) (xy 339.560952 -277.841037) (xy 339.51017 -277.84908)
			(xy 339.458754 -277.84908) (xy 339.407972 -277.841037) (xy 339.359073 -277.825149) (xy 339.313261 -277.801806)
			(xy 339.271665 -277.771585) (xy 339.235309 -277.735229) (xy 339.205088 -277.693633) (xy 339.181745 -277.647821)
			(xy 339.165857 -277.598922) (xy 339.157814 -277.54814) (xy 338.900544 -277.54814) (xy 338.900526 -277.549081)
			(xy 338.892583 -277.601785) (xy 338.876873 -277.652715) (xy 338.853747 -277.700736) (xy 338.823723 -277.744773)
			(xy 338.787471 -277.783844) (xy 338.7458 -277.817075) (xy 338.699642 -277.843724) (xy 338.650028 -277.863196)
			(xy 338.598066 -277.875056) (xy 338.544916 -277.87904) (xy 338.491766 -277.875056) (xy 338.439804 -277.863196)
			(xy 338.39019 -277.843724) (xy 338.344032 -277.817075) (xy 338.302361 -277.783844) (xy 338.266109 -277.744773)
			(xy 338.236085 -277.700736) (xy 338.212959 -277.652715) (xy 338.197249 -277.601785) (xy 338.189306 -277.549081)
			(xy 337.960472 -277.549081) (xy 337.952529 -277.601785) (xy 337.936819 -277.652715) (xy 337.913693 -277.700736)
			(xy 337.883669 -277.744773) (xy 337.847417 -277.783844) (xy 337.805746 -277.817075) (xy 337.759588 -277.843724)
			(xy 337.709974 -277.863196) (xy 337.658012 -277.875056) (xy 337.604862 -277.87904) (xy 337.551712 -277.875056)
			(xy 337.49975 -277.863196) (xy 337.450136 -277.843724) (xy 337.403978 -277.817075) (xy 337.362307 -277.783844)
			(xy 337.326055 -277.744773) (xy 337.296031 -277.700736) (xy 337.272905 -277.652715) (xy 337.257195 -277.601785)
			(xy 337.249252 -277.549081) (xy 337.020423 -277.549081) (xy 337.020418 -277.549335) (xy 337.012475 -277.602039)
			(xy 336.996765 -277.652969) (xy 336.973639 -277.70099) (xy 336.943615 -277.745027) (xy 336.907363 -277.784098)
			(xy 336.865692 -277.817329) (xy 336.819534 -277.843978) (xy 336.76992 -277.86345) (xy 336.717958 -277.87531)
			(xy 336.664808 -277.879294) (xy 336.611658 -277.87531) (xy 336.559696 -277.86345) (xy 336.510082 -277.843978)
			(xy 336.463924 -277.817329) (xy 336.422253 -277.784098) (xy 336.386001 -277.745027) (xy 336.355977 -277.70099)
			(xy 336.332851 -277.652969) (xy 336.317141 -277.602039) (xy 336.309198 -277.549335) (xy 335.424534 -277.549335)
			(xy 335.396372 -277.565594) (xy 335.346758 -277.585066) (xy 335.294796 -277.596926) (xy 335.241646 -277.60091)
			(xy 335.188496 -277.596926) (xy 335.136534 -277.585066) (xy 335.08692 -277.565594) (xy 335.040762 -277.538945)
			(xy 334.999091 -277.505714) (xy 334.962839 -277.466643) (xy 334.932815 -277.422606) (xy 334.909689 -277.374585)
			(xy 334.893979 -277.323655) (xy 334.886036 -277.270951) (xy 334.240653 -277.270951) (xy 334.072484 -277.43912)
			(xy 334.055547 -277.455388) (xy 334.017541 -277.482969) (xy 333.975689 -277.504266) (xy 333.931021 -277.518754)
			(xy 333.884636 -277.526077) (xy 333.861156 -277.526496) (xy 333.487014 -277.526496) (xy 332.677008 -278.336502)
			(xy 333.971649 -278.336502) (xy 333.975679 -278.284004) (xy 333.987676 -278.232736) (xy 334.007359 -278.183901)
			(xy 334.034265 -278.138642) (xy 334.067765 -278.098021) (xy 334.107073 -278.06299) (xy 334.151268 -278.03437)
			(xy 334.199313 -278.012831) (xy 334.250084 -277.998879) (xy 334.302389 -277.992841) (xy 334.355003 -277.994858)
			(xy 334.406693 -278.004882) (xy 334.456246 -278.02268) (xy 334.502502 -278.047833) (xy 334.544376 -278.079752)
			(xy 334.580888 -278.11769) (xy 334.61118 -278.160756) (xy 334.634543 -278.207941) (xy 334.650429 -278.25814)
			(xy 334.658466 -278.310176) (xy 334.65897 -278.336502) (xy 334.658466 -278.362828) (xy 334.658416 -278.363151)
			(xy 338.658952 -278.363151) (xy 338.658952 -278.309853) (xy 338.666895 -278.257149) (xy 338.682605 -278.206219)
			(xy 338.705731 -278.158198) (xy 338.735755 -278.114161) (xy 338.772007 -278.07509) (xy 338.813678 -278.041859)
			(xy 338.859836 -278.01521) (xy 338.90945 -277.995738) (xy 338.961412 -277.983878) (xy 339.014562 -277.979895)
			(xy 339.067712 -277.983878) (xy 339.119674 -277.995738) (xy 339.169288 -278.01521) (xy 339.215446 -278.041859)
			(xy 339.257117 -278.07509) (xy 339.293369 -278.114161) (xy 339.323393 -278.158198) (xy 339.346519 -278.206219)
			(xy 339.362229 -278.257149) (xy 339.370172 -278.309853) (xy 339.37067 -278.336502) (xy 339.37019 -278.36221)
			(xy 339.627968 -278.36221) (xy 339.627968 -278.310794) (xy 339.636011 -278.260012) (xy 339.651899 -278.211113)
			(xy 339.675242 -278.165301) (xy 339.705463 -278.123705) (xy 339.741819 -278.087349) (xy 339.783415 -278.057128)
			(xy 339.829227 -278.033785) (xy 339.878126 -278.017897) (xy 339.928908 -278.009854) (xy 339.980324 -278.009854)
			(xy 340.031106 -278.017897) (xy 340.080005 -278.033785) (xy 340.125817 -278.057128) (xy 340.167413 -278.087349)
			(xy 340.203769 -278.123705) (xy 340.23399 -278.165301) (xy 340.257333 -278.211113) (xy 340.273221 -278.260012)
			(xy 340.281264 -278.310794) (xy 340.281768 -278.336502) (xy 340.281264 -278.36221) (xy 340.281115 -278.363151)
			(xy 340.538806 -278.363151) (xy 340.538806 -278.309853) (xy 340.546749 -278.257149) (xy 340.562459 -278.206219)
			(xy 340.585585 -278.158198) (xy 340.615609 -278.114161) (xy 340.651861 -278.07509) (xy 340.693532 -278.041859)
			(xy 340.73969 -278.01521) (xy 340.789304 -277.995738) (xy 340.841266 -277.983878) (xy 340.894416 -277.979895)
			(xy 340.947566 -277.983878) (xy 340.999528 -277.995738) (xy 341.049142 -278.01521) (xy 341.0953 -278.041859)
			(xy 341.136971 -278.07509) (xy 341.173223 -278.114161) (xy 341.203247 -278.158198) (xy 341.226373 -278.206219)
			(xy 341.242083 -278.257149) (xy 341.250026 -278.309853) (xy 341.250524 -278.336502) (xy 341.250044 -278.36221)
			(xy 341.507568 -278.36221) (xy 341.507568 -278.310794) (xy 341.515611 -278.260012) (xy 341.531499 -278.211113)
			(xy 341.554842 -278.165301) (xy 341.585063 -278.123705) (xy 341.621419 -278.087349) (xy 341.663015 -278.057128)
			(xy 341.708827 -278.033785) (xy 341.757726 -278.017897) (xy 341.808508 -278.009854) (xy 341.859924 -278.009854)
			(xy 341.910706 -278.017897) (xy 341.959605 -278.033785) (xy 342.005417 -278.057128) (xy 342.047013 -278.087349)
			(xy 342.083369 -278.123705) (xy 342.11359 -278.165301) (xy 342.136933 -278.211113) (xy 342.152821 -278.260012)
			(xy 342.160864 -278.310794) (xy 342.161368 -278.336502) (xy 342.160864 -278.36221) (xy 342.160715 -278.363151)
			(xy 342.418406 -278.363151) (xy 342.418406 -278.309853) (xy 342.426349 -278.257149) (xy 342.442059 -278.206219)
			(xy 342.465185 -278.158198) (xy 342.495209 -278.114161) (xy 342.531461 -278.07509) (xy 342.573132 -278.041859)
			(xy 342.61929 -278.01521) (xy 342.668904 -277.995738) (xy 342.720866 -277.983878) (xy 342.774016 -277.979895)
			(xy 342.827166 -277.983878) (xy 342.879128 -277.995738) (xy 342.928742 -278.01521) (xy 342.9749 -278.041859)
			(xy 343.016571 -278.07509) (xy 343.052823 -278.114161) (xy 343.082847 -278.158198) (xy 343.105973 -278.206219)
			(xy 343.121683 -278.257149) (xy 343.129626 -278.309853) (xy 343.130124 -278.336502) (xy 343.129626 -278.363151)
			(xy 345.237806 -278.363151) (xy 345.237806 -278.309853) (xy 345.245749 -278.257149) (xy 345.261459 -278.206219)
			(xy 345.284585 -278.158198) (xy 345.314609 -278.114161) (xy 345.350861 -278.07509) (xy 345.392532 -278.041859)
			(xy 345.43869 -278.01521) (xy 345.488304 -277.995738) (xy 345.540266 -277.983878) (xy 345.593416 -277.979895)
			(xy 345.646566 -277.983878) (xy 345.698528 -277.995738) (xy 345.748142 -278.01521) (xy 345.7943 -278.041859)
			(xy 345.835971 -278.07509) (xy 345.872223 -278.114161) (xy 345.902247 -278.158198) (xy 345.925373 -278.206219)
			(xy 345.941083 -278.257149) (xy 345.949026 -278.309853) (xy 345.949524 -278.336502) (xy 345.949044 -278.36221)
			(xy 346.206568 -278.36221) (xy 346.206568 -278.310794) (xy 346.214611 -278.260012) (xy 346.230499 -278.211113)
			(xy 346.253842 -278.165301) (xy 346.284063 -278.123705) (xy 346.320419 -278.087349) (xy 346.362015 -278.057128)
			(xy 346.407827 -278.033785) (xy 346.456726 -278.017897) (xy 346.507508 -278.009854) (xy 346.558924 -278.009854)
			(xy 346.609706 -278.017897) (xy 346.658605 -278.033785) (xy 346.704417 -278.057128) (xy 346.746013 -278.087349)
			(xy 346.782369 -278.123705) (xy 346.81259 -278.165301) (xy 346.835933 -278.211113) (xy 346.851821 -278.260012)
			(xy 346.859864 -278.310794) (xy 346.860368 -278.336502) (xy 346.859864 -278.36221) (xy 346.859715 -278.363151)
			(xy 347.117406 -278.363151) (xy 347.117406 -278.309853) (xy 347.125349 -278.257149) (xy 347.141059 -278.206219)
			(xy 347.164185 -278.158198) (xy 347.194209 -278.114161) (xy 347.230461 -278.07509) (xy 347.272132 -278.041859)
			(xy 347.31829 -278.01521) (xy 347.367904 -277.995738) (xy 347.419866 -277.983878) (xy 347.473016 -277.979895)
			(xy 347.526166 -277.983878) (xy 347.578128 -277.995738) (xy 347.627742 -278.01521) (xy 347.6739 -278.041859)
			(xy 347.715571 -278.07509) (xy 347.751823 -278.114161) (xy 347.781847 -278.158198) (xy 347.804973 -278.206219)
			(xy 347.820683 -278.257149) (xy 347.828626 -278.309853) (xy 347.829124 -278.336502) (xy 347.828644 -278.36221)
			(xy 348.086168 -278.36221) (xy 348.086168 -278.310794) (xy 348.094211 -278.260012) (xy 348.110099 -278.211113)
			(xy 348.133442 -278.165301) (xy 348.163663 -278.123705) (xy 348.200019 -278.087349) (xy 348.241615 -278.057128)
			(xy 348.287427 -278.033785) (xy 348.336326 -278.017897) (xy 348.387108 -278.009854) (xy 348.438524 -278.009854)
			(xy 348.489306 -278.017897) (xy 348.538205 -278.033785) (xy 348.584017 -278.057128) (xy 348.625613 -278.087349)
			(xy 348.661969 -278.123705) (xy 348.69219 -278.165301) (xy 348.715533 -278.211113) (xy 348.731421 -278.260012)
			(xy 348.739464 -278.310794) (xy 348.739968 -278.336502) (xy 348.739464 -278.36221) (xy 348.739315 -278.363151)
			(xy 348.996752 -278.363151) (xy 348.996752 -278.309853) (xy 349.004695 -278.257149) (xy 349.020405 -278.206219)
			(xy 349.043531 -278.158198) (xy 349.073555 -278.114161) (xy 349.109807 -278.07509) (xy 349.151478 -278.041859)
			(xy 349.197636 -278.01521) (xy 349.24725 -277.995738) (xy 349.299212 -277.983878) (xy 349.352362 -277.979895)
			(xy 349.405512 -277.983878) (xy 349.457474 -277.995738) (xy 349.507088 -278.01521) (xy 349.553246 -278.041859)
			(xy 349.594917 -278.07509) (xy 349.631169 -278.114161) (xy 349.661193 -278.158198) (xy 349.684319 -278.206219)
			(xy 349.700029 -278.257149) (xy 349.707972 -278.309853) (xy 349.70847 -278.336502) (xy 349.707972 -278.363151)
			(xy 349.936806 -278.363151) (xy 349.936806 -278.309853) (xy 349.944749 -278.257149) (xy 349.960459 -278.206219)
			(xy 349.983585 -278.158198) (xy 350.013609 -278.114161) (xy 350.049861 -278.07509) (xy 350.091532 -278.041859)
			(xy 350.13769 -278.01521) (xy 350.187304 -277.995738) (xy 350.239266 -277.983878) (xy 350.292416 -277.979895)
			(xy 350.345566 -277.983878) (xy 350.397528 -277.995738) (xy 350.447142 -278.01521) (xy 350.4933 -278.041859)
			(xy 350.534971 -278.07509) (xy 350.571223 -278.114161) (xy 350.601247 -278.158198) (xy 350.624373 -278.206219)
			(xy 350.640083 -278.257149) (xy 350.648026 -278.309853) (xy 350.648524 -278.336502) (xy 350.648026 -278.363151)
			(xy 350.876606 -278.363151) (xy 350.876606 -278.309853) (xy 350.884549 -278.257149) (xy 350.900259 -278.206219)
			(xy 350.923385 -278.158198) (xy 350.953409 -278.114161) (xy 350.989661 -278.07509) (xy 351.031332 -278.041859)
			(xy 351.07749 -278.01521) (xy 351.127104 -277.995738) (xy 351.179066 -277.983878) (xy 351.232216 -277.979895)
			(xy 351.285366 -277.983878) (xy 351.337328 -277.995738) (xy 351.386942 -278.01521) (xy 351.4331 -278.041859)
			(xy 351.474771 -278.07509) (xy 351.511023 -278.114161) (xy 351.541047 -278.158198) (xy 351.564173 -278.206219)
			(xy 351.579883 -278.257149) (xy 351.587826 -278.309853) (xy 351.588324 -278.336502) (xy 351.587826 -278.363151)
			(xy 351.579883 -278.415855) (xy 351.564173 -278.466785) (xy 351.541047 -278.514806) (xy 351.511023 -278.558843)
			(xy 351.474771 -278.597914) (xy 351.4331 -278.631145) (xy 351.386942 -278.657794) (xy 351.337328 -278.677266)
			(xy 351.285366 -278.689126) (xy 351.232216 -278.69311) (xy 351.179066 -278.689126) (xy 351.127104 -278.677266)
			(xy 351.07749 -278.657794) (xy 351.031332 -278.631145) (xy 350.989661 -278.597914) (xy 350.953409 -278.558843)
			(xy 350.923385 -278.514806) (xy 350.900259 -278.466785) (xy 350.884549 -278.415855) (xy 350.876606 -278.363151)
			(xy 350.648026 -278.363151) (xy 350.640083 -278.415855) (xy 350.624373 -278.466785) (xy 350.601247 -278.514806)
			(xy 350.571223 -278.558843) (xy 350.534971 -278.597914) (xy 350.4933 -278.631145) (xy 350.447142 -278.657794)
			(xy 350.397528 -278.677266) (xy 350.345566 -278.689126) (xy 350.292416 -278.69311) (xy 350.239266 -278.689126)
			(xy 350.187304 -278.677266) (xy 350.13769 -278.657794) (xy 350.091532 -278.631145) (xy 350.049861 -278.597914)
			(xy 350.013609 -278.558843) (xy 349.983585 -278.514806) (xy 349.960459 -278.466785) (xy 349.944749 -278.415855)
			(xy 349.936806 -278.363151) (xy 349.707972 -278.363151) (xy 349.700029 -278.415855) (xy 349.684319 -278.466785)
			(xy 349.661193 -278.514806) (xy 349.631169 -278.558843) (xy 349.594917 -278.597914) (xy 349.553246 -278.631145)
			(xy 349.507088 -278.657794) (xy 349.457474 -278.677266) (xy 349.405512 -278.689126) (xy 349.352362 -278.69311)
			(xy 349.299212 -278.689126) (xy 349.24725 -278.677266) (xy 349.197636 -278.657794) (xy 349.151478 -278.631145)
			(xy 349.109807 -278.597914) (xy 349.073555 -278.558843) (xy 349.043531 -278.514806) (xy 349.020405 -278.466785)
			(xy 349.004695 -278.415855) (xy 348.996752 -278.363151) (xy 348.739315 -278.363151) (xy 348.731421 -278.412992)
			(xy 348.715533 -278.461891) (xy 348.69219 -278.507703) (xy 348.661969 -278.549299) (xy 348.625613 -278.585655)
			(xy 348.584017 -278.615876) (xy 348.538205 -278.639219) (xy 348.489306 -278.655107) (xy 348.438524 -278.66315)
			(xy 348.387108 -278.66315) (xy 348.336326 -278.655107) (xy 348.287427 -278.639219) (xy 348.241615 -278.615876)
			(xy 348.200019 -278.585655) (xy 348.163663 -278.549299) (xy 348.133442 -278.507703) (xy 348.110099 -278.461891)
			(xy 348.094211 -278.412992) (xy 348.086168 -278.36221) (xy 347.828644 -278.36221) (xy 347.828626 -278.363151)
			(xy 347.820683 -278.415855) (xy 347.804973 -278.466785) (xy 347.781847 -278.514806) (xy 347.751823 -278.558843)
			(xy 347.715571 -278.597914) (xy 347.6739 -278.631145) (xy 347.627742 -278.657794) (xy 347.578128 -278.677266)
			(xy 347.526166 -278.689126) (xy 347.473016 -278.69311) (xy 347.419866 -278.689126) (xy 347.367904 -278.677266)
			(xy 347.31829 -278.657794) (xy 347.272132 -278.631145) (xy 347.230461 -278.597914) (xy 347.194209 -278.558843)
			(xy 347.164185 -278.514806) (xy 347.141059 -278.466785) (xy 347.125349 -278.415855) (xy 347.117406 -278.363151)
			(xy 346.859715 -278.363151) (xy 346.851821 -278.412992) (xy 346.835933 -278.461891) (xy 346.81259 -278.507703)
			(xy 346.782369 -278.549299) (xy 346.746013 -278.585655) (xy 346.704417 -278.615876) (xy 346.658605 -278.639219)
			(xy 346.609706 -278.655107) (xy 346.558924 -278.66315) (xy 346.507508 -278.66315) (xy 346.456726 -278.655107)
			(xy 346.407827 -278.639219) (xy 346.362015 -278.615876) (xy 346.320419 -278.585655) (xy 346.284063 -278.549299)
			(xy 346.253842 -278.507703) (xy 346.230499 -278.461891) (xy 346.214611 -278.412992) (xy 346.206568 -278.36221)
			(xy 345.949044 -278.36221) (xy 345.949026 -278.363151) (xy 345.941083 -278.415855) (xy 345.925373 -278.466785)
			(xy 345.902247 -278.514806) (xy 345.872223 -278.558843) (xy 345.835971 -278.597914) (xy 345.7943 -278.631145)
			(xy 345.748142 -278.657794) (xy 345.698528 -278.677266) (xy 345.646566 -278.689126) (xy 345.593416 -278.69311)
			(xy 345.540266 -278.689126) (xy 345.488304 -278.677266) (xy 345.43869 -278.657794) (xy 345.392532 -278.631145)
			(xy 345.350861 -278.597914) (xy 345.314609 -278.558843) (xy 345.284585 -278.514806) (xy 345.261459 -278.466785)
			(xy 345.245749 -278.415855) (xy 345.237806 -278.363151) (xy 343.129626 -278.363151) (xy 343.121683 -278.415855)
			(xy 343.105973 -278.466785) (xy 343.082847 -278.514806) (xy 343.052823 -278.558843) (xy 343.016571 -278.597914)
			(xy 342.9749 -278.631145) (xy 342.928742 -278.657794) (xy 342.879128 -278.677266) (xy 342.827166 -278.689126)
			(xy 342.774016 -278.69311) (xy 342.720866 -278.689126) (xy 342.668904 -278.677266) (xy 342.61929 -278.657794)
			(xy 342.573132 -278.631145) (xy 342.531461 -278.597914) (xy 342.495209 -278.558843) (xy 342.465185 -278.514806)
			(xy 342.442059 -278.466785) (xy 342.426349 -278.415855) (xy 342.418406 -278.363151) (xy 342.160715 -278.363151)
			(xy 342.152821 -278.412992) (xy 342.136933 -278.461891) (xy 342.11359 -278.507703) (xy 342.083369 -278.549299)
			(xy 342.047013 -278.585655) (xy 342.005417 -278.615876) (xy 341.959605 -278.639219) (xy 341.910706 -278.655107)
			(xy 341.859924 -278.66315) (xy 341.808508 -278.66315) (xy 341.757726 -278.655107) (xy 341.708827 -278.639219)
			(xy 341.663015 -278.615876) (xy 341.621419 -278.585655) (xy 341.585063 -278.549299) (xy 341.554842 -278.507703)
			(xy 341.531499 -278.461891) (xy 341.515611 -278.412992) (xy 341.507568 -278.36221) (xy 341.250044 -278.36221)
			(xy 341.250026 -278.363151) (xy 341.242083 -278.415855) (xy 341.226373 -278.466785) (xy 341.203247 -278.514806)
			(xy 341.173223 -278.558843) (xy 341.136971 -278.597914) (xy 341.0953 -278.631145) (xy 341.049142 -278.657794)
			(xy 340.999528 -278.677266) (xy 340.947566 -278.689126) (xy 340.894416 -278.69311) (xy 340.841266 -278.689126)
			(xy 340.789304 -278.677266) (xy 340.73969 -278.657794) (xy 340.693532 -278.631145) (xy 340.651861 -278.597914)
			(xy 340.615609 -278.558843) (xy 340.585585 -278.514806) (xy 340.562459 -278.466785) (xy 340.546749 -278.415855)
			(xy 340.538806 -278.363151) (xy 340.281115 -278.363151) (xy 340.273221 -278.412992) (xy 340.257333 -278.461891)
			(xy 340.23399 -278.507703) (xy 340.203769 -278.549299) (xy 340.167413 -278.585655) (xy 340.125817 -278.615876)
			(xy 340.080005 -278.639219) (xy 340.031106 -278.655107) (xy 339.980324 -278.66315) (xy 339.928908 -278.66315)
			(xy 339.878126 -278.655107) (xy 339.829227 -278.639219) (xy 339.783415 -278.615876) (xy 339.741819 -278.585655)
			(xy 339.705463 -278.549299) (xy 339.675242 -278.507703) (xy 339.651899 -278.461891) (xy 339.636011 -278.412992)
			(xy 339.627968 -278.36221) (xy 339.37019 -278.36221) (xy 339.370172 -278.363151) (xy 339.362229 -278.415855)
			(xy 339.346519 -278.466785) (xy 339.323393 -278.514806) (xy 339.293369 -278.558843) (xy 339.257117 -278.597914)
			(xy 339.215446 -278.631145) (xy 339.169288 -278.657794) (xy 339.119674 -278.677266) (xy 339.067712 -278.689126)
			(xy 339.014562 -278.69311) (xy 338.961412 -278.689126) (xy 338.90945 -278.677266) (xy 338.859836 -278.657794)
			(xy 338.813678 -278.631145) (xy 338.772007 -278.597914) (xy 338.735755 -278.558843) (xy 338.705731 -278.514806)
			(xy 338.682605 -278.466785) (xy 338.666895 -278.415855) (xy 338.658952 -278.363151) (xy 334.658416 -278.363151)
			(xy 334.650429 -278.414864) (xy 334.634543 -278.465063) (xy 334.61118 -278.512248) (xy 334.580888 -278.555314)
			(xy 334.544376 -278.593252) (xy 334.502502 -278.625171) (xy 334.456246 -278.650324) (xy 334.406693 -278.668122)
			(xy 334.355003 -278.678146) (xy 334.302389 -278.680163) (xy 334.250084 -278.674125) (xy 334.199313 -278.660173)
			(xy 334.151268 -278.638634) (xy 334.107073 -278.610014) (xy 334.067765 -278.574983) (xy 334.034265 -278.534362)
			(xy 334.007359 -278.489103) (xy 333.987676 -278.440268) (xy 333.975679 -278.389) (xy 333.971649 -278.336502)
			(xy 332.677008 -278.336502) (xy 332.275455 -278.738055) (xy 332.761834 -278.738055) (xy 332.761834 -278.684757)
			(xy 332.769777 -278.632053) (xy 332.785487 -278.581123) (xy 332.808613 -278.533102) (xy 332.838637 -278.489065)
			(xy 332.874889 -278.449994) (xy 332.91656 -278.416763) (xy 332.962718 -278.390114) (xy 333.012332 -278.370642)
			(xy 333.064294 -278.358782) (xy 333.117444 -278.354799) (xy 333.170594 -278.358782) (xy 333.222556 -278.370642)
			(xy 333.27217 -278.390114) (xy 333.318328 -278.416763) (xy 333.359999 -278.449994) (xy 333.396251 -278.489065)
			(xy 333.426275 -278.533102) (xy 333.449401 -278.581123) (xy 333.465111 -278.632053) (xy 333.473054 -278.684757)
			(xy 333.473552 -278.711406) (xy 333.473054 -278.738055) (xy 333.465111 -278.790759) (xy 333.449401 -278.841689)
			(xy 333.426275 -278.88971) (xy 333.396251 -278.933747) (xy 333.359999 -278.972818) (xy 333.318328 -279.006049)
			(xy 333.27217 -279.032698) (xy 333.222556 -279.05217) (xy 333.170594 -279.06403) (xy 333.117444 -279.068014)
			(xy 333.064294 -279.06403) (xy 333.012332 -279.05217) (xy 332.962718 -279.032698) (xy 332.91656 -279.006049)
			(xy 332.874889 -278.972818) (xy 332.838637 -278.933747) (xy 332.808613 -278.88971) (xy 332.785487 -278.841689)
			(xy 332.769777 -278.790759) (xy 332.761834 -278.738055) (xy 332.275455 -278.738055) (xy 331.903324 -279.110186)
			(xy 331.903324 -279.176967) (xy 336.309452 -279.176967) (xy 336.309452 -279.123669) (xy 336.317395 -279.070965)
			(xy 336.333105 -279.020035) (xy 336.356231 -278.972014) (xy 336.386255 -278.927977) (xy 336.422507 -278.888906)
			(xy 336.464178 -278.855675) (xy 336.510336 -278.829026) (xy 336.55995 -278.809554) (xy 336.611912 -278.797694)
			(xy 336.665062 -278.793711) (xy 336.718212 -278.797694) (xy 336.770174 -278.809554) (xy 336.819788 -278.829026)
			(xy 336.865946 -278.855675) (xy 336.907617 -278.888906) (xy 336.943869 -278.927977) (xy 336.973893 -278.972014)
			(xy 336.997019 -279.020035) (xy 337.012729 -279.070965) (xy 337.020672 -279.123669) (xy 337.02117 -279.150318)
			(xy 337.020672 -279.176967) (xy 337.249252 -279.176967) (xy 337.249252 -279.123669) (xy 337.257195 -279.070965)
			(xy 337.272905 -279.020035) (xy 337.296031 -278.972014) (xy 337.326055 -278.927977) (xy 337.362307 -278.888906)
			(xy 337.403978 -278.855675) (xy 337.450136 -278.829026) (xy 337.49975 -278.809554) (xy 337.551712 -278.797694)
			(xy 337.604862 -278.793711) (xy 337.658012 -278.797694) (xy 337.709974 -278.809554) (xy 337.759588 -278.829026)
			(xy 337.805746 -278.855675) (xy 337.847417 -278.888906) (xy 337.883669 -278.927977) (xy 337.913693 -278.972014)
			(xy 337.936819 -279.020035) (xy 337.952529 -279.070965) (xy 337.960472 -279.123669) (xy 337.96097 -279.150318)
			(xy 337.960472 -279.176967) (xy 338.189052 -279.176967) (xy 338.189052 -279.123669) (xy 338.196995 -279.070965)
			(xy 338.212705 -279.020035) (xy 338.235831 -278.972014) (xy 338.265855 -278.927977) (xy 338.302107 -278.888906)
			(xy 338.343778 -278.855675) (xy 338.389936 -278.829026) (xy 338.43955 -278.809554) (xy 338.491512 -278.797694)
			(xy 338.544662 -278.793711) (xy 338.597812 -278.797694) (xy 338.649774 -278.809554) (xy 338.699388 -278.829026)
			(xy 338.745546 -278.855675) (xy 338.787217 -278.888906) (xy 338.823469 -278.927977) (xy 338.853493 -278.972014)
			(xy 338.876619 -279.020035) (xy 338.892329 -279.070965) (xy 338.900272 -279.123669) (xy 338.90077 -279.150318)
			(xy 338.900272 -279.176967) (xy 339.128852 -279.176967) (xy 339.128852 -279.123669) (xy 339.136795 -279.070965)
			(xy 339.152505 -279.020035) (xy 339.175631 -278.972014) (xy 339.205655 -278.927977) (xy 339.241907 -278.888906)
			(xy 339.283578 -278.855675) (xy 339.329736 -278.829026) (xy 339.37935 -278.809554) (xy 339.431312 -278.797694)
			(xy 339.484462 -278.793711) (xy 339.537612 -278.797694) (xy 339.589574 -278.809554) (xy 339.639188 -278.829026)
			(xy 339.685346 -278.855675) (xy 339.727017 -278.888906) (xy 339.763269 -278.927977) (xy 339.793293 -278.972014)
			(xy 339.816419 -279.020035) (xy 339.832129 -279.070965) (xy 339.840072 -279.123669) (xy 339.84057 -279.150318)
			(xy 339.84009 -279.176026) (xy 340.097614 -279.176026) (xy 340.097614 -279.12461) (xy 340.105657 -279.073828)
			(xy 340.121545 -279.024929) (xy 340.144888 -278.979117) (xy 340.175109 -278.937521) (xy 340.211465 -278.901165)
			(xy 340.253061 -278.870944) (xy 340.298873 -278.847601) (xy 340.347772 -278.831713) (xy 340.398554 -278.82367)
			(xy 340.44997 -278.82367) (xy 340.500752 -278.831713) (xy 340.549651 -278.847601) (xy 340.595463 -278.870944)
			(xy 340.637059 -278.901165) (xy 340.673415 -278.937521) (xy 340.703636 -278.979117) (xy 340.726979 -279.024929)
			(xy 340.742867 -279.073828) (xy 340.75091 -279.12461) (xy 340.751414 -279.150318) (xy 340.75091 -279.176026)
			(xy 341.037414 -279.176026) (xy 341.037414 -279.12461) (xy 341.045457 -279.073828) (xy 341.061345 -279.024929)
			(xy 341.084688 -278.979117) (xy 341.114909 -278.937521) (xy 341.151265 -278.901165) (xy 341.192861 -278.870944)
			(xy 341.238673 -278.847601) (xy 341.287572 -278.831713) (xy 341.338354 -278.82367) (xy 341.38977 -278.82367)
			(xy 341.440552 -278.831713) (xy 341.489451 -278.847601) (xy 341.535263 -278.870944) (xy 341.576859 -278.901165)
			(xy 341.613215 -278.937521) (xy 341.643436 -278.979117) (xy 341.666779 -279.024929) (xy 341.682667 -279.073828)
			(xy 341.69071 -279.12461) (xy 341.691214 -279.150318) (xy 341.69071 -279.176026) (xy 341.690561 -279.176967)
			(xy 341.948506 -279.176967) (xy 341.948506 -279.123669) (xy 341.956449 -279.070965) (xy 341.972159 -279.020035)
			(xy 341.995285 -278.972014) (xy 342.025309 -278.927977) (xy 342.061561 -278.888906) (xy 342.103232 -278.855675)
			(xy 342.14939 -278.829026) (xy 342.199004 -278.809554) (xy 342.250966 -278.797694) (xy 342.304116 -278.793711)
			(xy 342.357266 -278.797694) (xy 342.409228 -278.809554) (xy 342.458842 -278.829026) (xy 342.505 -278.855675)
			(xy 342.546671 -278.888906) (xy 342.582923 -278.927977) (xy 342.612947 -278.972014) (xy 342.636073 -279.020035)
			(xy 342.651783 -279.070965) (xy 342.659726 -279.123669) (xy 342.660224 -279.150318) (xy 342.659726 -279.176967)
			(xy 342.888306 -279.176967) (xy 342.888306 -279.123669) (xy 342.896249 -279.070965) (xy 342.911959 -279.020035)
			(xy 342.935085 -278.972014) (xy 342.965109 -278.927977) (xy 343.001361 -278.888906) (xy 343.043032 -278.855675)
			(xy 343.08919 -278.829026) (xy 343.138804 -278.809554) (xy 343.190766 -278.797694) (xy 343.243916 -278.793711)
			(xy 343.297066 -278.797694) (xy 343.349028 -278.809554) (xy 343.398642 -278.829026) (xy 343.4448 -278.855675)
			(xy 343.486471 -278.888906) (xy 343.522723 -278.927977) (xy 343.552747 -278.972014) (xy 343.575873 -279.020035)
			(xy 343.591583 -279.070965) (xy 343.599526 -279.123669) (xy 343.600024 -279.150318) (xy 343.599526 -279.176967)
			(xy 343.827852 -279.176967) (xy 343.827852 -279.123669) (xy 343.835795 -279.070965) (xy 343.851505 -279.020035)
			(xy 343.874631 -278.972014) (xy 343.904655 -278.927977) (xy 343.940907 -278.888906) (xy 343.982578 -278.855675)
			(xy 344.028736 -278.829026) (xy 344.07835 -278.809554) (xy 344.130312 -278.797694) (xy 344.183462 -278.793711)
			(xy 344.236612 -278.797694) (xy 344.288574 -278.809554) (xy 344.338188 -278.829026) (xy 344.384346 -278.855675)
			(xy 344.426017 -278.888906) (xy 344.462269 -278.927977) (xy 344.492293 -278.972014) (xy 344.515419 -279.020035)
			(xy 344.531129 -279.070965) (xy 344.539072 -279.123669) (xy 344.53957 -279.150318) (xy 344.539072 -279.176967)
			(xy 345.707706 -279.176967) (xy 345.707706 -279.123669) (xy 345.715649 -279.070965) (xy 345.731359 -279.020035)
			(xy 345.754485 -278.972014) (xy 345.784509 -278.927977) (xy 345.820761 -278.888906) (xy 345.862432 -278.855675)
			(xy 345.90859 -278.829026) (xy 345.958204 -278.809554) (xy 346.010166 -278.797694) (xy 346.063316 -278.793711)
			(xy 346.116466 -278.797694) (xy 346.168428 -278.809554) (xy 346.218042 -278.829026) (xy 346.2642 -278.855675)
			(xy 346.305871 -278.888906) (xy 346.342123 -278.927977) (xy 346.372147 -278.972014) (xy 346.395273 -279.020035)
			(xy 346.410983 -279.070965) (xy 346.418926 -279.123669) (xy 346.419424 -279.150318) (xy 346.418944 -279.176026)
			(xy 346.676214 -279.176026) (xy 346.676214 -279.12461) (xy 346.684257 -279.073828) (xy 346.700145 -279.024929)
			(xy 346.723488 -278.979117) (xy 346.753709 -278.937521) (xy 346.790065 -278.901165) (xy 346.831661 -278.870944)
			(xy 346.877473 -278.847601) (xy 346.926372 -278.831713) (xy 346.977154 -278.82367) (xy 347.02857 -278.82367)
			(xy 347.079352 -278.831713) (xy 347.128251 -278.847601) (xy 347.174063 -278.870944) (xy 347.215659 -278.901165)
			(xy 347.252015 -278.937521) (xy 347.282236 -278.979117) (xy 347.305579 -279.024929) (xy 347.321467 -279.073828)
			(xy 347.32951 -279.12461) (xy 347.330014 -279.150318) (xy 347.32951 -279.176026) (xy 347.616014 -279.176026)
			(xy 347.616014 -279.12461) (xy 347.624057 -279.073828) (xy 347.639945 -279.024929) (xy 347.663288 -278.979117)
			(xy 347.693509 -278.937521) (xy 347.729865 -278.901165) (xy 347.771461 -278.870944) (xy 347.817273 -278.847601)
			(xy 347.866172 -278.831713) (xy 347.916954 -278.82367) (xy 347.96837 -278.82367) (xy 348.019152 -278.831713)
			(xy 348.068051 -278.847601) (xy 348.113863 -278.870944) (xy 348.155459 -278.901165) (xy 348.191815 -278.937521)
			(xy 348.222036 -278.979117) (xy 348.245379 -279.024929) (xy 348.261267 -279.073828) (xy 348.26931 -279.12461)
			(xy 348.269814 -279.150318) (xy 348.26931 -279.176026) (xy 348.269161 -279.176967) (xy 348.527106 -279.176967)
			(xy 348.527106 -279.123669) (xy 348.535049 -279.070965) (xy 348.550759 -279.020035) (xy 348.573885 -278.972014)
			(xy 348.603909 -278.927977) (xy 348.640161 -278.888906) (xy 348.681832 -278.855675) (xy 348.72799 -278.829026)
			(xy 348.777604 -278.809554) (xy 348.829566 -278.797694) (xy 348.882716 -278.793711) (xy 348.935866 -278.797694)
			(xy 348.987828 -278.809554) (xy 349.037442 -278.829026) (xy 349.0836 -278.855675) (xy 349.125271 -278.888906)
			(xy 349.161523 -278.927977) (xy 349.191547 -278.972014) (xy 349.214673 -279.020035) (xy 349.230383 -279.070965)
			(xy 349.238326 -279.123669) (xy 349.238824 -279.150318) (xy 349.492824 -279.150318) (xy 349.493332 -279.124431)
			(xy 349.501431 -279.073293) (xy 349.51743 -279.024053) (xy 349.540936 -278.977921) (xy 349.571368 -278.936034)
			(xy 349.607978 -278.899424) (xy 349.649865 -278.868992) (xy 349.695997 -278.845486) (xy 349.745237 -278.829487)
			(xy 349.796375 -278.821388) (xy 349.848149 -278.821388) (xy 349.899287 -278.829487) (xy 349.948527 -278.845486)
			(xy 349.994659 -278.868992) (xy 350.036546 -278.899424) (xy 350.073156 -278.936034) (xy 350.103588 -278.977921)
			(xy 350.127094 -279.024053) (xy 350.143093 -279.073293) (xy 350.151192 -279.124431) (xy 350.1517 -279.150318)
			(xy 350.151146 -279.177962) (xy 350.141956 -279.23248) (xy 350.133412 -279.258776) (xy 350.125792 -279.28062)
			(xy 350.331024 -279.635966) (xy 350.353884 -279.640284) (xy 350.378708 -279.645438) (xy 350.426486 -279.662396)
			(xy 350.471104 -279.68647) (xy 350.511509 -279.717093) (xy 350.546749 -279.753542) (xy 350.575992 -279.794956)
			(xy 350.598549 -279.84036) (xy 350.613887 -279.888683) (xy 350.621645 -279.938785) (xy 350.622108 -279.964134)
			(xy 350.6216 -279.990041) (xy 350.621482 -279.990783) (xy 350.876352 -279.990783) (xy 350.876352 -279.937485)
			(xy 350.884295 -279.884781) (xy 350.900005 -279.833851) (xy 350.923131 -279.78583) (xy 350.953155 -279.741793)
			(xy 350.989407 -279.702722) (xy 351.031078 -279.669491) (xy 351.077236 -279.642842) (xy 351.12685 -279.62337)
			(xy 351.178812 -279.61151) (xy 351.231962 -279.607527) (xy 351.285112 -279.61151) (xy 351.337074 -279.62337)
			(xy 351.386688 -279.642842) (xy 351.432846 -279.669491) (xy 351.474517 -279.702722) (xy 351.510769 -279.741793)
			(xy 351.540793 -279.78583) (xy 351.563919 -279.833851) (xy 351.579629 -279.884781) (xy 351.587572 -279.937485)
			(xy 351.58807 -279.964134) (xy 351.587572 -279.990783) (xy 351.579629 -280.043487) (xy 351.563919 -280.094417)
			(xy 351.540793 -280.142438) (xy 351.510769 -280.186475) (xy 351.474517 -280.225546) (xy 351.432846 -280.258777)
			(xy 351.386688 -280.285426) (xy 351.337074 -280.304898) (xy 351.285112 -280.316758) (xy 351.231962 -280.320742)
			(xy 351.178812 -280.316758) (xy 351.12685 -280.304898) (xy 351.077236 -280.285426) (xy 351.031078 -280.258777)
			(xy 350.989407 -280.225546) (xy 350.953155 -280.186475) (xy 350.923131 -280.142438) (xy 350.900005 -280.094417)
			(xy 350.884295 -280.043487) (xy 350.876352 -279.990783) (xy 350.621482 -279.990783) (xy 350.613494 -280.041218)
			(xy 350.597482 -280.090497) (xy 350.573959 -280.136664) (xy 350.543503 -280.178583) (xy 350.506865 -280.215221)
			(xy 350.464946 -280.245677) (xy 350.418779 -280.2692) (xy 350.3695 -280.285212) (xy 350.318323 -280.293318)
			(xy 350.266509 -280.293318) (xy 350.215332 -280.285212) (xy 350.166053 -280.2692) (xy 350.119886 -280.245677)
			(xy 350.077967 -280.215221) (xy 350.041329 -280.178583) (xy 350.010873 -280.136664) (xy 349.98735 -280.090497)
			(xy 349.971338 -280.041218) (xy 349.963232 -279.990041) (xy 349.962724 -279.964134) (xy 349.963325 -279.936417)
			(xy 349.972644 -279.88177) (xy 349.981266 -279.855422) (xy 349.98914 -279.833324) (xy 349.784162 -279.478486)
			(xy 349.761302 -279.474168) (xy 349.736475 -279.468982) (xy 349.688671 -279.452048) (xy 349.644023 -279.427992)
			(xy 349.603586 -279.397383) (xy 349.568314 -279.360942) (xy 349.539039 -279.319529) (xy 349.516451 -279.274121)
			(xy 349.501083 -279.22579) (xy 349.493299 -279.175676) (xy 349.492824 -279.150318) (xy 349.238824 -279.150318)
			(xy 349.238326 -279.176967) (xy 349.230383 -279.229671) (xy 349.214673 -279.280601) (xy 349.191547 -279.328622)
			(xy 349.161523 -279.372659) (xy 349.125271 -279.41173) (xy 349.0836 -279.444961) (xy 349.037442 -279.47161)
			(xy 348.987828 -279.491082) (xy 348.935866 -279.502942) (xy 348.882716 -279.506926) (xy 348.829566 -279.502942)
			(xy 348.777604 -279.491082) (xy 348.72799 -279.47161) (xy 348.681832 -279.444961) (xy 348.640161 -279.41173)
			(xy 348.603909 -279.372659) (xy 348.573885 -279.328622) (xy 348.550759 -279.280601) (xy 348.535049 -279.229671)
			(xy 348.527106 -279.176967) (xy 348.269161 -279.176967) (xy 348.261267 -279.226808) (xy 348.245379 -279.275707)
			(xy 348.222036 -279.321519) (xy 348.191815 -279.363115) (xy 348.155459 -279.399471) (xy 348.113863 -279.429692)
			(xy 348.068051 -279.453035) (xy 348.019152 -279.468923) (xy 347.96837 -279.476966) (xy 347.916954 -279.476966)
			(xy 347.866172 -279.468923) (xy 347.817273 -279.453035) (xy 347.771461 -279.429692) (xy 347.729865 -279.399471)
			(xy 347.693509 -279.363115) (xy 347.663288 -279.321519) (xy 347.639945 -279.275707) (xy 347.624057 -279.226808)
			(xy 347.616014 -279.176026) (xy 347.32951 -279.176026) (xy 347.321467 -279.226808) (xy 347.305579 -279.275707)
			(xy 347.282236 -279.321519) (xy 347.252015 -279.363115) (xy 347.215659 -279.399471) (xy 347.174063 -279.429692)
			(xy 347.128251 -279.453035) (xy 347.079352 -279.468923) (xy 347.02857 -279.476966) (xy 346.977154 -279.476966)
			(xy 346.926372 -279.468923) (xy 346.877473 -279.453035) (xy 346.831661 -279.429692) (xy 346.790065 -279.399471)
			(xy 346.753709 -279.363115) (xy 346.723488 -279.321519) (xy 346.700145 -279.275707) (xy 346.684257 -279.226808)
			(xy 346.676214 -279.176026) (xy 346.418944 -279.176026) (xy 346.418926 -279.176967) (xy 346.410983 -279.229671)
			(xy 346.395273 -279.280601) (xy 346.372147 -279.328622) (xy 346.342123 -279.372659) (xy 346.305871 -279.41173)
			(xy 346.2642 -279.444961) (xy 346.218042 -279.47161) (xy 346.168428 -279.491082) (xy 346.116466 -279.502942)
			(xy 346.063316 -279.506926) (xy 346.010166 -279.502942) (xy 345.958204 -279.491082) (xy 345.90859 -279.47161)
			(xy 345.862432 -279.444961) (xy 345.820761 -279.41173) (xy 345.784509 -279.372659) (xy 345.754485 -279.328622)
			(xy 345.731359 -279.280601) (xy 345.715649 -279.229671) (xy 345.707706 -279.176967) (xy 344.539072 -279.176967)
			(xy 344.531129 -279.229671) (xy 344.515419 -279.280601) (xy 344.492293 -279.328622) (xy 344.462269 -279.372659)
			(xy 344.426017 -279.41173) (xy 344.384346 -279.444961) (xy 344.338188 -279.47161) (xy 344.288574 -279.491082)
			(xy 344.236612 -279.502942) (xy 344.183462 -279.506926) (xy 344.130312 -279.502942) (xy 344.07835 -279.491082)
			(xy 344.028736 -279.47161) (xy 343.982578 -279.444961) (xy 343.940907 -279.41173) (xy 343.904655 -279.372659)
			(xy 343.874631 -279.328622) (xy 343.851505 -279.280601) (xy 343.835795 -279.229671) (xy 343.827852 -279.176967)
			(xy 343.599526 -279.176967) (xy 343.591583 -279.229671) (xy 343.575873 -279.280601) (xy 343.552747 -279.328622)
			(xy 343.522723 -279.372659) (xy 343.486471 -279.41173) (xy 343.4448 -279.444961) (xy 343.398642 -279.47161)
			(xy 343.349028 -279.491082) (xy 343.297066 -279.502942) (xy 343.243916 -279.506926) (xy 343.190766 -279.502942)
			(xy 343.138804 -279.491082) (xy 343.08919 -279.47161) (xy 343.043032 -279.444961) (xy 343.001361 -279.41173)
			(xy 342.965109 -279.372659) (xy 342.935085 -279.328622) (xy 342.911959 -279.280601) (xy 342.896249 -279.229671)
			(xy 342.888306 -279.176967) (xy 342.659726 -279.176967) (xy 342.651783 -279.229671) (xy 342.636073 -279.280601)
			(xy 342.612947 -279.328622) (xy 342.582923 -279.372659) (xy 342.546671 -279.41173) (xy 342.505 -279.444961)
			(xy 342.458842 -279.47161) (xy 342.409228 -279.491082) (xy 342.357266 -279.502942) (xy 342.304116 -279.506926)
			(xy 342.250966 -279.502942) (xy 342.199004 -279.491082) (xy 342.14939 -279.47161) (xy 342.103232 -279.444961)
			(xy 342.061561 -279.41173) (xy 342.025309 -279.372659) (xy 341.995285 -279.328622) (xy 341.972159 -279.280601)
			(xy 341.956449 -279.229671) (xy 341.948506 -279.176967) (xy 341.690561 -279.176967) (xy 341.682667 -279.226808)
			(xy 341.666779 -279.275707) (xy 341.643436 -279.321519) (xy 341.613215 -279.363115) (xy 341.576859 -279.399471)
			(xy 341.535263 -279.429692) (xy 341.489451 -279.453035) (xy 341.440552 -279.468923) (xy 341.38977 -279.476966)
			(xy 341.338354 -279.476966) (xy 341.287572 -279.468923) (xy 341.238673 -279.453035) (xy 341.192861 -279.429692)
			(xy 341.151265 -279.399471) (xy 341.114909 -279.363115) (xy 341.084688 -279.321519) (xy 341.061345 -279.275707)
			(xy 341.045457 -279.226808) (xy 341.037414 -279.176026) (xy 340.75091 -279.176026) (xy 340.742867 -279.226808)
			(xy 340.726979 -279.275707) (xy 340.703636 -279.321519) (xy 340.673415 -279.363115) (xy 340.637059 -279.399471)
			(xy 340.595463 -279.429692) (xy 340.549651 -279.453035) (xy 340.500752 -279.468923) (xy 340.44997 -279.476966)
			(xy 340.398554 -279.476966) (xy 340.347772 -279.468923) (xy 340.298873 -279.453035) (xy 340.253061 -279.429692)
			(xy 340.211465 -279.399471) (xy 340.175109 -279.363115) (xy 340.144888 -279.321519) (xy 340.121545 -279.275707)
			(xy 340.105657 -279.226808) (xy 340.097614 -279.176026) (xy 339.84009 -279.176026) (xy 339.840072 -279.176967)
			(xy 339.832129 -279.229671) (xy 339.816419 -279.280601) (xy 339.793293 -279.328622) (xy 339.763269 -279.372659)
			(xy 339.727017 -279.41173) (xy 339.685346 -279.444961) (xy 339.639188 -279.47161) (xy 339.589574 -279.491082)
			(xy 339.537612 -279.502942) (xy 339.484462 -279.506926) (xy 339.431312 -279.502942) (xy 339.37935 -279.491082)
			(xy 339.329736 -279.47161) (xy 339.283578 -279.444961) (xy 339.241907 -279.41173) (xy 339.205655 -279.372659)
			(xy 339.175631 -279.328622) (xy 339.152505 -279.280601) (xy 339.136795 -279.229671) (xy 339.128852 -279.176967)
			(xy 338.900272 -279.176967) (xy 338.892329 -279.229671) (xy 338.876619 -279.280601) (xy 338.853493 -279.328622)
			(xy 338.823469 -279.372659) (xy 338.787217 -279.41173) (xy 338.745546 -279.444961) (xy 338.699388 -279.47161)
			(xy 338.649774 -279.491082) (xy 338.597812 -279.502942) (xy 338.544662 -279.506926) (xy 338.491512 -279.502942)
			(xy 338.43955 -279.491082) (xy 338.389936 -279.47161) (xy 338.343778 -279.444961) (xy 338.302107 -279.41173)
			(xy 338.265855 -279.372659) (xy 338.235831 -279.328622) (xy 338.212705 -279.280601) (xy 338.196995 -279.229671)
			(xy 338.189052 -279.176967) (xy 337.960472 -279.176967) (xy 337.952529 -279.229671) (xy 337.936819 -279.280601)
			(xy 337.913693 -279.328622) (xy 337.883669 -279.372659) (xy 337.847417 -279.41173) (xy 337.805746 -279.444961)
			(xy 337.759588 -279.47161) (xy 337.709974 -279.491082) (xy 337.658012 -279.502942) (xy 337.604862 -279.506926)
			(xy 337.551712 -279.502942) (xy 337.49975 -279.491082) (xy 337.450136 -279.47161) (xy 337.403978 -279.444961)
			(xy 337.362307 -279.41173) (xy 337.326055 -279.372659) (xy 337.296031 -279.328622) (xy 337.272905 -279.280601)
			(xy 337.257195 -279.229671) (xy 337.249252 -279.176967) (xy 337.020672 -279.176967) (xy 337.012729 -279.229671)
			(xy 336.997019 -279.280601) (xy 336.973893 -279.328622) (xy 336.943869 -279.372659) (xy 336.907617 -279.41173)
			(xy 336.865946 -279.444961) (xy 336.819788 -279.47161) (xy 336.770174 -279.491082) (xy 336.718212 -279.502942)
			(xy 336.665062 -279.506926) (xy 336.611912 -279.502942) (xy 336.55995 -279.491082) (xy 336.510336 -279.47161)
			(xy 336.464178 -279.444961) (xy 336.422507 -279.41173) (xy 336.386255 -279.372659) (xy 336.356231 -279.328622)
			(xy 336.333105 -279.280601) (xy 336.317395 -279.229671) (xy 336.309452 -279.176967) (xy 331.903324 -279.176967)
			(xy 331.903324 -279.990783) (xy 333.959952 -279.990783) (xy 333.959952 -279.937485) (xy 333.967895 -279.884781)
			(xy 333.983605 -279.833851) (xy 334.006731 -279.78583) (xy 334.036755 -279.741793) (xy 334.073007 -279.702722)
			(xy 334.114678 -279.669491) (xy 334.160836 -279.642842) (xy 334.21045 -279.62337) (xy 334.262412 -279.61151)
			(xy 334.315562 -279.607527) (xy 334.368712 -279.61151) (xy 334.420674 -279.62337) (xy 334.470288 -279.642842)
			(xy 334.516446 -279.669491) (xy 334.558117 -279.702722) (xy 334.594369 -279.741793) (xy 334.624393 -279.78583)
			(xy 334.647519 -279.833851) (xy 334.663229 -279.884781) (xy 334.671172 -279.937485) (xy 334.67167 -279.964134)
			(xy 334.671172 -279.990783) (xy 334.899752 -279.990783) (xy 334.899752 -279.937485) (xy 334.907695 -279.884781)
			(xy 334.923405 -279.833851) (xy 334.946531 -279.78583) (xy 334.976555 -279.741793) (xy 335.012807 -279.702722)
			(xy 335.054478 -279.669491) (xy 335.100636 -279.642842) (xy 335.15025 -279.62337) (xy 335.202212 -279.61151)
			(xy 335.255362 -279.607527) (xy 335.308512 -279.61151) (xy 335.360474 -279.62337) (xy 335.410088 -279.642842)
			(xy 335.456246 -279.669491) (xy 335.497917 -279.702722) (xy 335.534169 -279.741793) (xy 335.564193 -279.78583)
			(xy 335.587319 -279.833851) (xy 335.603029 -279.884781) (xy 335.610972 -279.937485) (xy 335.61147 -279.964134)
			(xy 335.610972 -279.990783) (xy 335.839552 -279.990783) (xy 335.839552 -279.937485) (xy 335.847495 -279.884781)
			(xy 335.863205 -279.833851) (xy 335.886331 -279.78583) (xy 335.916355 -279.741793) (xy 335.952607 -279.702722)
			(xy 335.994278 -279.669491) (xy 336.040436 -279.642842) (xy 336.09005 -279.62337) (xy 336.142012 -279.61151)
			(xy 336.195162 -279.607527) (xy 336.248312 -279.61151) (xy 336.300274 -279.62337) (xy 336.349888 -279.642842)
			(xy 336.396046 -279.669491) (xy 336.437717 -279.702722) (xy 336.473969 -279.741793) (xy 336.503993 -279.78583)
			(xy 336.527119 -279.833851) (xy 336.542829 -279.884781) (xy 336.550772 -279.937485) (xy 336.55127 -279.964134)
			(xy 336.550787 -279.989983) (xy 336.806103 -279.989983) (xy 336.806103 -279.938217) (xy 336.814201 -279.887089)
			(xy 336.830196 -279.837856) (xy 336.853696 -279.791732) (xy 336.884121 -279.749851) (xy 336.920722 -279.713245)
			(xy 336.9626 -279.682815) (xy 337.008721 -279.659311) (xy 337.057952 -279.64331) (xy 337.109079 -279.635206)
			(xy 337.134962 -279.634696) (xy 337.160473 -279.635206) (xy 337.210886 -279.64306) (xy 337.259487 -279.658588)
			(xy 337.305115 -279.681418) (xy 337.346681 -279.711006) (xy 337.383193 -279.746643) (xy 337.398868 -279.766776)
			(xy 337.810856 -279.766776) (xy 337.826548 -279.746656) (xy 337.863055 -279.711012) (xy 337.904617 -279.681418)
			(xy 337.950241 -279.658579) (xy 337.998839 -279.643041) (xy 338.049251 -279.635176) (xy 338.074762 -279.634696)
			(xy 338.100656 -279.635106) (xy 338.151807 -279.643203) (xy 338.201062 -279.659201) (xy 338.247208 -279.682709)
			(xy 338.289107 -279.713146) (xy 338.325729 -279.749764) (xy 338.356171 -279.79166) (xy 338.379684 -279.837803)
			(xy 338.395689 -279.887056) (xy 338.403791 -279.938206) (xy 338.403791 -279.989994) (xy 338.403666 -279.990783)
			(xy 339.599006 -279.990783) (xy 339.599006 -279.937485) (xy 339.606949 -279.884781) (xy 339.622659 -279.833851)
			(xy 339.645785 -279.78583) (xy 339.675809 -279.741793) (xy 339.712061 -279.702722) (xy 339.753732 -279.669491)
			(xy 339.79989 -279.642842) (xy 339.849504 -279.62337) (xy 339.901466 -279.61151) (xy 339.954616 -279.607527)
			(xy 340.007766 -279.61151) (xy 340.059728 -279.62337) (xy 340.109342 -279.642842) (xy 340.1555 -279.669491)
			(xy 340.197171 -279.702722) (xy 340.233423 -279.741793) (xy 340.263447 -279.78583) (xy 340.286573 -279.833851)
			(xy 340.302283 -279.884781) (xy 340.310226 -279.937485) (xy 340.310724 -279.964134) (xy 340.310226 -279.990783)
			(xy 340.538806 -279.990783) (xy 340.538806 -279.937485) (xy 340.546749 -279.884781) (xy 340.562459 -279.833851)
			(xy 340.585585 -279.78583) (xy 340.615609 -279.741793) (xy 340.651861 -279.702722) (xy 340.693532 -279.669491)
			(xy 340.73969 -279.642842) (xy 340.789304 -279.62337) (xy 340.841266 -279.61151) (xy 340.894416 -279.607527)
			(xy 340.947566 -279.61151) (xy 340.999528 -279.62337) (xy 341.049142 -279.642842) (xy 341.0953 -279.669491)
			(xy 341.136971 -279.702722) (xy 341.173223 -279.741793) (xy 341.203247 -279.78583) (xy 341.226373 -279.833851)
			(xy 341.242083 -279.884781) (xy 341.250026 -279.937485) (xy 341.250524 -279.964134) (xy 341.250026 -279.990783)
			(xy 342.418152 -279.990783) (xy 342.418152 -279.937485) (xy 342.426095 -279.884781) (xy 342.441805 -279.833851)
			(xy 342.464931 -279.78583) (xy 342.494955 -279.741793) (xy 342.531207 -279.702722) (xy 342.572878 -279.669491)
			(xy 342.619036 -279.642842) (xy 342.66865 -279.62337) (xy 342.720612 -279.61151) (xy 342.773762 -279.607527)
			(xy 342.826912 -279.61151) (xy 342.878874 -279.62337) (xy 342.928488 -279.642842) (xy 342.974646 -279.669491)
			(xy 343.016317 -279.702722) (xy 343.052569 -279.741793) (xy 343.082593 -279.78583) (xy 343.105719 -279.833851)
			(xy 343.121429 -279.884781) (xy 343.129372 -279.937485) (xy 343.12987 -279.964134) (xy 343.129372 -279.990783)
			(xy 343.358206 -279.990783) (xy 343.358206 -279.937485) (xy 343.366149 -279.884781) (xy 343.381859 -279.833851)
			(xy 343.404985 -279.78583) (xy 343.435009 -279.741793) (xy 343.471261 -279.702722) (xy 343.512932 -279.669491)
			(xy 343.55909 -279.642842) (xy 343.608704 -279.62337) (xy 343.660666 -279.61151) (xy 343.713816 -279.607527)
			(xy 343.766966 -279.61151) (xy 343.818928 -279.62337) (xy 343.868542 -279.642842) (xy 343.9147 -279.669491)
			(xy 343.956371 -279.702722) (xy 343.992623 -279.741793) (xy 344.022647 -279.78583) (xy 344.045773 -279.833851)
			(xy 344.061483 -279.884781) (xy 344.069426 -279.937485) (xy 344.069924 -279.964134) (xy 344.323924 -279.964134)
			(xy 344.324432 -279.938227) (xy 344.332538 -279.88705) (xy 344.34855 -279.837771) (xy 344.372073 -279.791604)
			(xy 344.402529 -279.749685) (xy 344.439167 -279.713047) (xy 344.481086 -279.682591) (xy 344.527253 -279.659068)
			(xy 344.576532 -279.643056) (xy 344.627709 -279.63495) (xy 344.679523 -279.63495) (xy 344.7307 -279.643056)
			(xy 344.779979 -279.659068) (xy 344.826146 -279.682591) (xy 344.868065 -279.713047) (xy 344.904703 -279.749685)
			(xy 344.935159 -279.791604) (xy 344.958682 -279.837771) (xy 344.974694 -279.88705) (xy 344.9828 -279.938227)
			(xy 344.983308 -279.964134) (xy 344.982697 -279.990783) (xy 345.237806 -279.990783) (xy 345.237806 -279.937485)
			(xy 345.245749 -279.884781) (xy 345.261459 -279.833851) (xy 345.284585 -279.78583) (xy 345.314609 -279.741793)
			(xy 345.350861 -279.702722) (xy 345.392532 -279.669491) (xy 345.43869 -279.642842) (xy 345.488304 -279.62337)
			(xy 345.540266 -279.61151) (xy 345.593416 -279.607527) (xy 345.646566 -279.61151) (xy 345.698528 -279.62337)
			(xy 345.748142 -279.642842) (xy 345.7943 -279.669491) (xy 345.835971 -279.702722) (xy 345.872223 -279.741793)
			(xy 345.902247 -279.78583) (xy 345.925373 -279.833851) (xy 345.941083 -279.884781) (xy 345.949026 -279.937485)
			(xy 345.949524 -279.964134) (xy 345.949026 -279.990783) (xy 346.177606 -279.990783) (xy 346.177606 -279.937485)
			(xy 346.185549 -279.884781) (xy 346.201259 -279.833851) (xy 346.224385 -279.78583) (xy 346.254409 -279.741793)
			(xy 346.290661 -279.702722) (xy 346.332332 -279.669491) (xy 346.37849 -279.642842) (xy 346.428104 -279.62337)
			(xy 346.480066 -279.61151) (xy 346.533216 -279.607527) (xy 346.586366 -279.61151) (xy 346.638328 -279.62337)
			(xy 346.687942 -279.642842) (xy 346.7341 -279.669491) (xy 346.775771 -279.702722) (xy 346.812023 -279.741793)
			(xy 346.842047 -279.78583) (xy 346.865173 -279.833851) (xy 346.880883 -279.884781) (xy 346.888826 -279.937485)
			(xy 346.889324 -279.964134) (xy 346.888826 -279.990783) (xy 348.057206 -279.990783) (xy 348.057206 -279.937485)
			(xy 348.065149 -279.884781) (xy 348.080859 -279.833851) (xy 348.103985 -279.78583) (xy 348.134009 -279.741793)
			(xy 348.170261 -279.702722) (xy 348.211932 -279.669491) (xy 348.25809 -279.642842) (xy 348.307704 -279.62337)
			(xy 348.359666 -279.61151) (xy 348.412816 -279.607527) (xy 348.465966 -279.61151) (xy 348.517928 -279.62337)
			(xy 348.567542 -279.642842) (xy 348.6137 -279.669491) (xy 348.655371 -279.702722) (xy 348.691623 -279.741793)
			(xy 348.721647 -279.78583) (xy 348.744773 -279.833851) (xy 348.760483 -279.884781) (xy 348.768426 -279.937485)
			(xy 348.768924 -279.964134) (xy 348.768426 -279.990783) (xy 348.997006 -279.990783) (xy 348.997006 -279.937485)
			(xy 349.004949 -279.884781) (xy 349.020659 -279.833851) (xy 349.043785 -279.78583) (xy 349.073809 -279.741793)
			(xy 349.110061 -279.702722) (xy 349.151732 -279.669491) (xy 349.19789 -279.642842) (xy 349.247504 -279.62337)
			(xy 349.299466 -279.61151) (xy 349.352616 -279.607527) (xy 349.405766 -279.61151) (xy 349.457728 -279.62337)
			(xy 349.507342 -279.642842) (xy 349.5535 -279.669491) (xy 349.595171 -279.702722) (xy 349.631423 -279.741793)
			(xy 349.661447 -279.78583) (xy 349.684573 -279.833851) (xy 349.700283 -279.884781) (xy 349.708226 -279.937485)
			(xy 349.708724 -279.964134) (xy 349.708226 -279.990783) (xy 349.700283 -280.043487) (xy 349.684573 -280.094417)
			(xy 349.661447 -280.142438) (xy 349.631423 -280.186475) (xy 349.595171 -280.225546) (xy 349.5535 -280.258777)
			(xy 349.507342 -280.285426) (xy 349.457728 -280.304898) (xy 349.405766 -280.316758) (xy 349.352616 -280.320742)
			(xy 349.299466 -280.316758) (xy 349.247504 -280.304898) (xy 349.19789 -280.285426) (xy 349.151732 -280.258777)
			(xy 349.110061 -280.225546) (xy 349.073809 -280.186475) (xy 349.043785 -280.142438) (xy 349.020659 -280.094417)
			(xy 349.004949 -280.043487) (xy 348.997006 -279.990783) (xy 348.768426 -279.990783) (xy 348.760483 -280.043487)
			(xy 348.744773 -280.094417) (xy 348.721647 -280.142438) (xy 348.691623 -280.186475) (xy 348.655371 -280.225546)
			(xy 348.6137 -280.258777) (xy 348.567542 -280.285426) (xy 348.517928 -280.304898) (xy 348.465966 -280.316758)
			(xy 348.412816 -280.320742) (xy 348.359666 -280.316758) (xy 348.307704 -280.304898) (xy 348.25809 -280.285426)
			(xy 348.211932 -280.258777) (xy 348.170261 -280.225546) (xy 348.134009 -280.186475) (xy 348.103985 -280.142438)
			(xy 348.080859 -280.094417) (xy 348.065149 -280.043487) (xy 348.057206 -279.990783) (xy 346.888826 -279.990783)
			(xy 346.880883 -280.043487) (xy 346.865173 -280.094417) (xy 346.842047 -280.142438) (xy 346.812023 -280.186475)
			(xy 346.775771 -280.225546) (xy 346.7341 -280.258777) (xy 346.687942 -280.285426) (xy 346.638328 -280.304898)
			(xy 346.586366 -280.316758) (xy 346.533216 -280.320742) (xy 346.480066 -280.316758) (xy 346.428104 -280.304898)
			(xy 346.37849 -280.285426) (xy 346.332332 -280.258777) (xy 346.290661 -280.225546) (xy 346.254409 -280.186475)
			(xy 346.224385 -280.142438) (xy 346.201259 -280.094417) (xy 346.185549 -280.043487) (xy 346.177606 -279.990783)
			(xy 345.949026 -279.990783) (xy 345.941083 -280.043487) (xy 345.925373 -280.094417) (xy 345.902247 -280.142438)
			(xy 345.872223 -280.186475) (xy 345.835971 -280.225546) (xy 345.7943 -280.258777) (xy 345.748142 -280.285426)
			(xy 345.698528 -280.304898) (xy 345.646566 -280.316758) (xy 345.593416 -280.320742) (xy 345.540266 -280.316758)
			(xy 345.488304 -280.304898) (xy 345.43869 -280.285426) (xy 345.392532 -280.258777) (xy 345.350861 -280.225546)
			(xy 345.314609 -280.186475) (xy 345.284585 -280.142438) (xy 345.261459 -280.094417) (xy 345.245749 -280.043487)
			(xy 345.237806 -279.990783) (xy 344.982697 -279.990783) (xy 344.982671 -279.991925) (xy 344.973225 -280.046702)
			(xy 344.964512 -280.0731) (xy 344.956892 -280.095198) (xy 345.16187 -280.450036) (xy 345.18473 -280.454354)
			(xy 345.209535 -280.459531) (xy 345.257274 -280.476523) (xy 345.30185 -280.500619) (xy 345.342215 -280.531252)
			(xy 345.377417 -280.5677) (xy 345.406629 -280.609105) (xy 345.429161 -280.654492) (xy 345.444484 -280.702792)
			(xy 345.452236 -280.752868) (xy 345.4527 -280.778204) (xy 345.452192 -280.804091) (xy 345.444093 -280.855229)
			(xy 345.428094 -280.904469) (xy 345.404588 -280.950601) (xy 345.374156 -280.992488) (xy 345.337546 -281.029098)
			(xy 345.295659 -281.05953) (xy 345.249527 -281.083036) (xy 345.200287 -281.099035) (xy 345.149149 -281.107134)
			(xy 345.097375 -281.107134) (xy 345.046237 -281.099035) (xy 344.996997 -281.083036) (xy 344.950865 -281.05953)
			(xy 344.908978 -281.029098) (xy 344.872368 -280.992488) (xy 344.841936 -280.950601) (xy 344.81843 -280.904469)
			(xy 344.802431 -280.855229) (xy 344.794332 -280.804091) (xy 344.793824 -280.778204) (xy 344.794353 -280.750496)
			(xy 344.803549 -280.695849) (xy 344.812112 -280.669492) (xy 344.819986 -280.647394) (xy 344.614754 -280.292302)
			(xy 344.591894 -280.287984) (xy 344.567101 -280.282754) (xy 344.519365 -280.265768) (xy 344.47479 -280.241678)
			(xy 344.434426 -280.211052) (xy 344.399223 -280.174611) (xy 344.37001 -280.133213) (xy 344.347475 -280.087832)
			(xy 344.332148 -280.039538) (xy 344.32439 -279.989468) (xy 344.323924 -279.964134) (xy 344.069924 -279.964134)
			(xy 344.069426 -279.990783) (xy 344.061483 -280.043487) (xy 344.045773 -280.094417) (xy 344.022647 -280.142438)
			(xy 343.992623 -280.186475) (xy 343.956371 -280.225546) (xy 343.9147 -280.258777) (xy 343.868542 -280.285426)
			(xy 343.818928 -280.304898) (xy 343.766966 -280.316758) (xy 343.713816 -280.320742) (xy 343.660666 -280.316758)
			(xy 343.608704 -280.304898) (xy 343.55909 -280.285426) (xy 343.512932 -280.258777) (xy 343.471261 -280.225546)
			(xy 343.435009 -280.186475) (xy 343.404985 -280.142438) (xy 343.381859 -280.094417) (xy 343.366149 -280.043487)
			(xy 343.358206 -279.990783) (xy 343.129372 -279.990783) (xy 343.121429 -280.043487) (xy 343.105719 -280.094417)
			(xy 343.082593 -280.142438) (xy 343.052569 -280.186475) (xy 343.016317 -280.225546) (xy 342.974646 -280.258777)
			(xy 342.928488 -280.285426) (xy 342.878874 -280.304898) (xy 342.826912 -280.316758) (xy 342.773762 -280.320742)
			(xy 342.720612 -280.316758) (xy 342.66865 -280.304898) (xy 342.619036 -280.285426) (xy 342.572878 -280.258777)
			(xy 342.531207 -280.225546) (xy 342.494955 -280.186475) (xy 342.464931 -280.142438) (xy 342.441805 -280.094417)
			(xy 342.426095 -280.043487) (xy 342.418152 -279.990783) (xy 341.250026 -279.990783) (xy 341.242083 -280.043487)
			(xy 341.226373 -280.094417) (xy 341.203247 -280.142438) (xy 341.173223 -280.186475) (xy 341.136971 -280.225546)
			(xy 341.0953 -280.258777) (xy 341.049142 -280.285426) (xy 340.999528 -280.304898) (xy 340.947566 -280.316758)
			(xy 340.894416 -280.320742) (xy 340.841266 -280.316758) (xy 340.789304 -280.304898) (xy 340.73969 -280.285426)
			(xy 340.693532 -280.258777) (xy 340.651861 -280.225546) (xy 340.615609 -280.186475) (xy 340.585585 -280.142438)
			(xy 340.562459 -280.094417) (xy 340.546749 -280.043487) (xy 340.538806 -279.990783) (xy 340.310226 -279.990783)
			(xy 340.302283 -280.043487) (xy 340.286573 -280.094417) (xy 340.263447 -280.142438) (xy 340.233423 -280.186475)
			(xy 340.197171 -280.225546) (xy 340.1555 -280.258777) (xy 340.109342 -280.285426) (xy 340.059728 -280.304898)
			(xy 340.007766 -280.316758) (xy 339.954616 -280.320742) (xy 339.901466 -280.316758) (xy 339.849504 -280.304898)
			(xy 339.79989 -280.285426) (xy 339.753732 -280.258777) (xy 339.712061 -280.225546) (xy 339.675809 -280.186475)
			(xy 339.645785 -280.142438) (xy 339.622659 -280.094417) (xy 339.606949 -280.043487) (xy 339.599006 -279.990783)
			(xy 338.403666 -279.990783) (xy 338.395689 -280.041144) (xy 338.379684 -280.090397) (xy 338.356171 -280.13654)
			(xy 338.325729 -280.178436) (xy 338.289107 -280.215054) (xy 338.247208 -280.245491) (xy 338.201062 -280.268999)
			(xy 338.151807 -280.284997) (xy 338.100656 -280.293094) (xy 338.074762 -280.293572) (xy 338.049249 -280.293131)
			(xy 337.998832 -280.285263) (xy 337.950229 -280.269723) (xy 337.9046 -280.24688) (xy 337.863036 -280.21728)
			(xy 337.826528 -280.18163) (xy 337.810856 -280.161492) (xy 337.398868 -280.161492) (xy 337.383211 -280.181641)
			(xy 337.346698 -280.217284) (xy 337.305129 -280.246877) (xy 337.259498 -280.269711) (xy 337.210893 -280.285241)
			(xy 337.160475 -280.293097) (xy 337.134962 -280.293572) (xy 337.109079 -280.292994) (xy 337.057952 -280.28489)
			(xy 337.008721 -280.268889) (xy 336.9626 -280.245385) (xy 336.920722 -280.214955) (xy 336.884121 -280.178349)
			(xy 336.853696 -280.136468) (xy 336.830196 -280.090344) (xy 336.814201 -280.041111) (xy 336.806103 -279.989983)
			(xy 336.550787 -279.989983) (xy 336.550772 -279.990783) (xy 336.542829 -280.043487) (xy 336.527119 -280.094417)
			(xy 336.503993 -280.142438) (xy 336.473969 -280.186475) (xy 336.437717 -280.225546) (xy 336.396046 -280.258777)
			(xy 336.349888 -280.285426) (xy 336.300274 -280.304898) (xy 336.248312 -280.316758) (xy 336.195162 -280.320742)
			(xy 336.142012 -280.316758) (xy 336.09005 -280.304898) (xy 336.040436 -280.285426) (xy 335.994278 -280.258777)
			(xy 335.952607 -280.225546) (xy 335.916355 -280.186475) (xy 335.886331 -280.142438) (xy 335.863205 -280.094417)
			(xy 335.847495 -280.043487) (xy 335.839552 -279.990783) (xy 335.610972 -279.990783) (xy 335.603029 -280.043487)
			(xy 335.587319 -280.094417) (xy 335.564193 -280.142438) (xy 335.534169 -280.186475) (xy 335.497917 -280.225546)
			(xy 335.456246 -280.258777) (xy 335.410088 -280.285426) (xy 335.360474 -280.304898) (xy 335.308512 -280.316758)
			(xy 335.255362 -280.320742) (xy 335.202212 -280.316758) (xy 335.15025 -280.304898) (xy 335.100636 -280.285426)
			(xy 335.054478 -280.258777) (xy 335.012807 -280.225546) (xy 334.976555 -280.186475) (xy 334.946531 -280.142438)
			(xy 334.923405 -280.094417) (xy 334.907695 -280.043487) (xy 334.899752 -279.990783) (xy 334.671172 -279.990783)
			(xy 334.663229 -280.043487) (xy 334.647519 -280.094417) (xy 334.624393 -280.142438) (xy 334.594369 -280.186475)
			(xy 334.558117 -280.225546) (xy 334.516446 -280.258777) (xy 334.470288 -280.285426) (xy 334.420674 -280.304898)
			(xy 334.368712 -280.316758) (xy 334.315562 -280.320742) (xy 334.262412 -280.316758) (xy 334.21045 -280.304898)
			(xy 334.160836 -280.285426) (xy 334.114678 -280.258777) (xy 334.073007 -280.225546) (xy 334.036755 -280.186475)
			(xy 334.006731 -280.142438) (xy 333.983605 -280.094417) (xy 333.967895 -280.043487) (xy 333.959952 -279.990783)
			(xy 331.903324 -279.990783) (xy 331.903324 -280.778204) (xy 333.501749 -280.778204) (xy 333.505779 -280.725706)
			(xy 333.517776 -280.674438) (xy 333.537459 -280.625603) (xy 333.564365 -280.580344) (xy 333.597865 -280.539723)
			(xy 333.637173 -280.504692) (xy 333.681368 -280.476072) (xy 333.729413 -280.454533) (xy 333.780184 -280.440581)
			(xy 333.832489 -280.434543) (xy 333.885103 -280.43656) (xy 333.936793 -280.446584) (xy 333.986346 -280.464382)
			(xy 334.032602 -280.489535) (xy 334.074476 -280.521454) (xy 334.110988 -280.559392) (xy 334.14128 -280.602458)
			(xy 334.164643 -280.649643) (xy 334.180529 -280.699842) (xy 334.188566 -280.751878) (xy 334.18907 -280.778204)
			(xy 334.188574 -280.804105) (xy 334.45632 -280.804105) (xy 334.45632 -280.752295) (xy 334.464425 -280.701122)
			(xy 334.480434 -280.651848) (xy 334.503953 -280.605684) (xy 334.534405 -280.563767) (xy 334.571038 -280.527129)
			(xy 334.612951 -280.496673) (xy 334.659113 -280.473148) (xy 334.708385 -280.457133) (xy 334.759557 -280.449023)
			(xy 334.785462 -280.448512) (xy 334.810955 -280.449019) (xy 334.861331 -280.456875) (xy 334.909894 -280.472404)
			(xy 334.955481 -280.495237) (xy 334.997003 -280.524825) (xy 335.033465 -280.560462) (xy 335.049114 -280.580592)
			(xy 335.46161 -280.580592) (xy 335.477279 -280.560477) (xy 335.513736 -280.524835) (xy 335.555252 -280.495239)
			(xy 335.600835 -280.472399) (xy 335.649395 -280.45686) (xy 335.699769 -280.448993) (xy 335.725262 -280.448512)
			(xy 335.751174 -280.448983) (xy 335.80236 -280.457084) (xy 335.851648 -280.473094) (xy 335.897825 -280.496618)
			(xy 335.939753 -280.527076) (xy 335.9764 -280.563718) (xy 336.006863 -280.605643) (xy 336.030391 -280.651817)
			(xy 336.046407 -280.701103) (xy 336.054514 -280.752288) (xy 336.054514 -280.804112) (xy 336.046407 -280.855297)
			(xy 336.030391 -280.904583) (xy 336.006863 -280.950757) (xy 335.9764 -280.992682) (xy 335.939753 -281.029324)
			(xy 335.897825 -281.059782) (xy 335.851648 -281.083306) (xy 335.80236 -281.099316) (xy 335.751174 -281.107417)
			(xy 335.725262 -281.107896) (xy 335.699767 -281.107441) (xy 335.649389 -281.099574) (xy 335.600825 -281.084033)
			(xy 335.555238 -281.061192) (xy 335.513718 -281.031594) (xy 335.477257 -280.99595) (xy 335.46161 -280.975816)
			(xy 335.049114 -280.975816) (xy 335.033491 -280.995969) (xy 334.997025 -281.031609) (xy 334.955498 -281.061199)
			(xy 334.909906 -281.084033) (xy 334.861339 -281.099564) (xy 334.810957 -281.107421) (xy 334.785462 -281.107896)
			(xy 334.759557 -281.107377) (xy 334.708385 -281.099267) (xy 334.659113 -281.083252) (xy 334.612951 -281.059727)
			(xy 334.571038 -281.029271) (xy 334.534405 -280.992633) (xy 334.503953 -280.950716) (xy 334.480434 -280.904552)
			(xy 334.464425 -280.855278) (xy 334.45632 -280.804105) (xy 334.188574 -280.804105) (xy 334.188566 -280.80453)
			(xy 334.180529 -280.856566) (xy 334.164643 -280.906765) (xy 334.14128 -280.95395) (xy 334.110988 -280.997016)
			(xy 334.074476 -281.034954) (xy 334.032602 -281.066873) (xy 333.986346 -281.092026) (xy 333.936793 -281.109824)
			(xy 333.885103 -281.119848) (xy 333.832489 -281.121865) (xy 333.780184 -281.115827) (xy 333.729413 -281.101875)
			(xy 333.681368 -281.080336) (xy 333.637173 -281.051716) (xy 333.597865 -281.016685) (xy 333.564365 -280.976064)
			(xy 333.537459 -280.930805) (xy 333.517776 -280.88197) (xy 333.505779 -280.830702) (xy 333.501749 -280.778204)
			(xy 331.903324 -280.778204) (xy 331.903324 -281.618669) (xy 333.959952 -281.618669) (xy 333.959952 -281.565371)
			(xy 333.967895 -281.512667) (xy 333.983605 -281.461737) (xy 334.006731 -281.413716) (xy 334.036755 -281.369679)
			(xy 334.073007 -281.330608) (xy 334.114678 -281.297377) (xy 334.160836 -281.270728) (xy 334.21045 -281.251256)
			(xy 334.262412 -281.239396) (xy 334.315562 -281.235413) (xy 334.368712 -281.239396) (xy 334.420674 -281.251256)
			(xy 334.470288 -281.270728) (xy 334.516446 -281.297377) (xy 334.558117 -281.330608) (xy 334.594369 -281.369679)
			(xy 334.624393 -281.413716) (xy 334.647519 -281.461737) (xy 334.663229 -281.512667) (xy 334.671172 -281.565371)
			(xy 334.67167 -281.59202) (xy 334.671172 -281.618669) (xy 334.663229 -281.671373) (xy 334.647519 -281.722303)
			(xy 334.624393 -281.770324) (xy 334.594369 -281.814361) (xy 334.558117 -281.853432) (xy 334.516446 -281.886663)
			(xy 334.470288 -281.913312) (xy 334.420674 -281.932784) (xy 334.368712 -281.944644) (xy 334.315562 -281.948628)
			(xy 334.262412 -281.944644) (xy 334.21045 -281.932784) (xy 334.160836 -281.913312) (xy 334.114678 -281.886663)
			(xy 334.073007 -281.853432) (xy 334.036755 -281.814361) (xy 334.006731 -281.770324) (xy 333.983605 -281.722303)
			(xy 333.967895 -281.671373) (xy 333.959952 -281.618669) (xy 331.903324 -281.618669) (xy 331.903324 -282.432485)
			(xy 333.490052 -282.432485) (xy 333.490052 -282.379187) (xy 333.497995 -282.326483) (xy 333.513705 -282.275553)
			(xy 333.536831 -282.227532) (xy 333.566855 -282.183495) (xy 333.603107 -282.144424) (xy 333.644778 -282.111193)
			(xy 333.690936 -282.084544) (xy 333.74055 -282.065072) (xy 333.792512 -282.053212) (xy 333.845662 -282.049229)
			(xy 333.898812 -282.053212) (xy 333.950774 -282.065072) (xy 334.000388 -282.084544) (xy 334.046546 -282.111193)
			(xy 334.088217 -282.144424) (xy 334.124469 -282.183495) (xy 334.154493 -282.227532) (xy 334.177619 -282.275553)
			(xy 334.193329 -282.326483) (xy 334.201272 -282.379187) (xy 334.20177 -282.405836) (xy 334.456024 -282.405836)
			(xy 334.456468 -282.38049) (xy 334.46425 -282.330397) (xy 334.479605 -282.282085) (xy 334.502171 -282.236692)
			(xy 334.531418 -282.195286) (xy 334.566656 -282.158843) (xy 334.607056 -282.128222) (xy 334.651665 -282.104142)
			(xy 334.699433 -282.087172) (xy 334.724248 -282.081986) (xy 334.747108 -282.077668) (xy 334.952086 -281.722576)
			(xy 334.944466 -281.700732) (xy 334.93582 -281.67439) (xy 334.926507 -281.619739) (xy 334.925924 -281.59202)
			(xy 334.926432 -281.566113) (xy 334.934538 -281.514936) (xy 334.95055 -281.465657) (xy 334.974073 -281.41949)
			(xy 335.004529 -281.377571) (xy 335.041167 -281.340933) (xy 335.083086 -281.310477) (xy 335.129253 -281.286954)
			(xy 335.178532 -281.270942) (xy 335.229709 -281.262836) (xy 335.281523 -281.262836) (xy 335.3327 -281.270942)
			(xy 335.381979 -281.286954) (xy 335.428146 -281.310477) (xy 335.470065 -281.340933) (xy 335.506703 -281.377571)
			(xy 335.537159 -281.41949) (xy 335.560682 -281.465657) (xy 335.576694 -281.514936) (xy 335.5848 -281.566113)
			(xy 335.585308 -281.59202) (xy 335.584798 -281.617364) (xy 335.584595 -281.618669) (xy 335.839552 -281.618669)
			(xy 335.839552 -281.565371) (xy 335.847495 -281.512667) (xy 335.863205 -281.461737) (xy 335.886331 -281.413716)
			(xy 335.916355 -281.369679) (xy 335.952607 -281.330608) (xy 335.994278 -281.297377) (xy 336.040436 -281.270728)
			(xy 336.09005 -281.251256) (xy 336.142012 -281.239396) (xy 336.195162 -281.235413) (xy 336.248312 -281.239396)
			(xy 336.300274 -281.251256) (xy 336.349888 -281.270728) (xy 336.396046 -281.297377) (xy 336.437717 -281.330608)
			(xy 336.473969 -281.369679) (xy 336.503993 -281.413716) (xy 336.527119 -281.461737) (xy 336.542829 -281.512667)
			(xy 336.550772 -281.565371) (xy 336.55127 -281.59202) (xy 336.805524 -281.59202) (xy 336.806044 -281.566676)
			(xy 336.813813 -281.516587) (xy 336.829157 -281.468277) (xy 336.851713 -281.422884) (xy 336.88095 -281.381477)
			(xy 336.916179 -281.345033) (xy 336.956571 -281.31441) (xy 337.001174 -281.290329) (xy 337.048936 -281.273357)
			(xy 337.073748 -281.26817) (xy 337.096608 -281.263852) (xy 337.301586 -280.909014) (xy 337.293966 -280.88717)
			(xy 337.285321 -280.860761) (xy 337.276 -280.805986) (xy 337.275424 -280.778204) (xy 337.275919 -280.752309)
			(xy 337.284017 -280.701155) (xy 337.300013 -280.651897) (xy 337.323515 -280.605746) (xy 337.353945 -280.563837)
			(xy 337.390553 -280.527202) (xy 337.432439 -280.496742) (xy 337.478573 -280.473206) (xy 337.527819 -280.457173)
			(xy 337.578967 -280.449038) (xy 337.604862 -280.448512) (xy 337.630766 -280.448979) (xy 337.681935 -280.457083)
			(xy 337.731205 -280.473097) (xy 337.777361 -280.496626) (xy 337.819265 -280.52709) (xy 337.855883 -280.563738)
			(xy 337.886313 -280.605666) (xy 337.909805 -280.651841) (xy 337.925779 -280.701124) (xy 337.933841 -280.7523)
			(xy 337.9343 -280.778204) (xy 337.933779 -280.803526) (xy 337.933574 -280.804853) (xy 338.189052 -280.804853)
			(xy 338.189052 -280.751555) (xy 338.196995 -280.698851) (xy 338.212705 -280.647921) (xy 338.235831 -280.5999)
			(xy 338.265855 -280.555863) (xy 338.302107 -280.516792) (xy 338.343778 -280.483561) (xy 338.389936 -280.456912)
			(xy 338.43955 -280.43744) (xy 338.491512 -280.42558) (xy 338.544662 -280.421597) (xy 338.597812 -280.42558)
			(xy 338.649774 -280.43744) (xy 338.699388 -280.456912) (xy 338.745546 -280.483561) (xy 338.787217 -280.516792)
			(xy 338.823469 -280.555863) (xy 338.853493 -280.5999) (xy 338.876619 -280.647921) (xy 338.892329 -280.698851)
			(xy 338.900272 -280.751555) (xy 338.90077 -280.778204) (xy 340.094824 -280.778204) (xy 340.095293 -280.752294)
			(xy 340.103399 -280.701112) (xy 340.119413 -280.651828) (xy 340.142939 -280.605656) (xy 340.173399 -280.563733)
			(xy 340.210042 -280.527091) (xy 340.251966 -280.496633) (xy 340.298139 -280.473108) (xy 340.347423 -280.457097)
			(xy 340.398606 -280.448992) (xy 340.424516 -280.448512) (xy 340.450421 -280.448929) (xy 340.501592 -280.457041)
			(xy 340.550863 -280.473063) (xy 340.597019 -280.496598) (xy 340.638922 -280.527068) (xy 340.67554 -280.563721)
			(xy 340.705969 -280.605654) (xy 340.72946 -280.651833) (xy 340.745433 -280.701119) (xy 340.753496 -280.752298)
			(xy 340.753954 -280.778204) (xy 340.753402 -280.804853) (xy 341.948506 -280.804853) (xy 341.948506 -280.751555)
			(xy 341.956449 -280.698851) (xy 341.972159 -280.647921) (xy 341.995285 -280.5999) (xy 342.025309 -280.555863)
			(xy 342.061561 -280.516792) (xy 342.103232 -280.483561) (xy 342.14939 -280.456912) (xy 342.199004 -280.43744)
			(xy 342.250966 -280.42558) (xy 342.304116 -280.421597) (xy 342.357266 -280.42558) (xy 342.409228 -280.43744)
			(xy 342.458842 -280.456912) (xy 342.505 -280.483561) (xy 342.546671 -280.516792) (xy 342.582923 -280.555863)
			(xy 342.612947 -280.5999) (xy 342.636073 -280.647921) (xy 342.651783 -280.698851) (xy 342.659726 -280.751555)
			(xy 342.660224 -280.778204) (xy 342.65974 -280.804105) (xy 342.91452 -280.804105) (xy 342.91452 -280.752295)
			(xy 342.922625 -280.701122) (xy 342.938634 -280.651848) (xy 342.962153 -280.605684) (xy 342.992605 -280.563767)
			(xy 343.029238 -280.527129) (xy 343.071151 -280.496673) (xy 343.117313 -280.473148) (xy 343.166585 -280.457133)
			(xy 343.217757 -280.449023) (xy 343.243662 -280.448512) (xy 343.269173 -280.449015) (xy 343.319587 -280.45687)
			(xy 343.368188 -280.472399) (xy 343.413817 -280.49523) (xy 343.455383 -280.524819) (xy 343.491894 -280.560459)
			(xy 343.507568 -280.580592) (xy 343.91981 -280.580592) (xy 343.935476 -280.56045) (xy 343.971987 -280.524807)
			(xy 344.013554 -280.495214) (xy 344.059184 -280.472379) (xy 344.107788 -280.456847) (xy 344.158204 -280.448988)
			(xy 344.183716 -280.448512) (xy 344.209623 -280.449014) (xy 344.260798 -280.457121) (xy 344.310075 -280.473134)
			(xy 344.356241 -280.496659) (xy 344.398158 -280.527115) (xy 344.434795 -280.563754) (xy 344.465249 -280.605673)
			(xy 344.488772 -280.65184) (xy 344.504782 -280.701117) (xy 344.512888 -280.752293) (xy 344.512888 -280.804107)
			(xy 344.504782 -280.855283) (xy 344.488772 -280.90456) (xy 344.465249 -280.950727) (xy 344.434795 -280.992646)
			(xy 344.398158 -281.029285) (xy 344.356241 -281.059741) (xy 344.310075 -281.083266) (xy 344.260798 -281.099279)
			(xy 344.209623 -281.107386) (xy 344.183716 -281.107896) (xy 344.158205 -281.107405) (xy 344.107791 -281.099547)
			(xy 344.059189 -281.084016) (xy 344.013561 -281.061182) (xy 343.971995 -281.031591) (xy 343.935484 -280.99595)
			(xy 343.91981 -280.975816) (xy 343.507568 -280.975816) (xy 343.491917 -280.99597) (xy 343.455403 -281.031612)
			(xy 343.413832 -281.061203) (xy 343.368199 -281.084036) (xy 343.319593 -281.099566) (xy 343.269175 -281.107421)
			(xy 343.243662 -281.107896) (xy 343.217757 -281.107377) (xy 343.166585 -281.099267) (xy 343.117313 -281.083252)
			(xy 343.071151 -281.059727) (xy 343.029238 -281.029271) (xy 342.992605 -280.992633) (xy 342.962153 -280.950716)
			(xy 342.938634 -280.904552) (xy 342.922625 -280.855278) (xy 342.91452 -280.804105) (xy 342.65974 -280.804105)
			(xy 342.659726 -280.804853) (xy 342.651783 -280.857557) (xy 342.636073 -280.908487) (xy 342.612947 -280.956508)
			(xy 342.582923 -281.000545) (xy 342.546671 -281.039616) (xy 342.505 -281.072847) (xy 342.458842 -281.099496)
			(xy 342.409228 -281.118968) (xy 342.357266 -281.130828) (xy 342.304116 -281.134812) (xy 342.250966 -281.130828)
			(xy 342.199004 -281.118968) (xy 342.14939 -281.099496) (xy 342.103232 -281.072847) (xy 342.061561 -281.039616)
			(xy 342.025309 -281.000545) (xy 341.995285 -280.956508) (xy 341.972159 -280.908487) (xy 341.956449 -280.857557)
			(xy 341.948506 -280.804853) (xy 340.753402 -280.804853) (xy 340.753379 -280.805986) (xy 340.744058 -280.860762)
			(xy 340.735412 -280.88717) (xy 340.727792 -280.909014) (xy 340.93277 -281.263852) (xy 340.95563 -281.26817)
			(xy 340.980439 -281.273332) (xy 341.028178 -281.290325) (xy 341.072756 -281.314423) (xy 341.113121 -281.345058)
			(xy 341.148323 -281.381508) (xy 341.177534 -281.422915) (xy 341.200066 -281.468304) (xy 341.215387 -281.516606)
			(xy 341.223138 -281.566683) (xy 341.2236 -281.59202) (xy 341.223092 -281.617907) (xy 341.214993 -281.669045)
			(xy 341.198994 -281.718285) (xy 341.175488 -281.764417) (xy 341.145056 -281.806304) (xy 341.108446 -281.842914)
			(xy 341.066559 -281.873346) (xy 341.020427 -281.896852) (xy 340.971187 -281.912851) (xy 340.920049 -281.92095)
			(xy 340.868275 -281.92095) (xy 340.817137 -281.912851) (xy 340.767897 -281.896852) (xy 340.721765 -281.873346)
			(xy 340.679878 -281.842914) (xy 340.643268 -281.806304) (xy 340.612836 -281.764417) (xy 340.58933 -281.718285)
			(xy 340.573331 -281.669045) (xy 340.565232 -281.617907) (xy 340.564724 -281.59202) (xy 340.565273 -281.564313)
			(xy 340.574459 -281.509667) (xy 340.583012 -281.483308) (xy 340.590632 -281.461464) (xy 340.385654 -281.106372)
			(xy 340.362794 -281.102054) (xy 340.337994 -281.096852) (xy 340.290256 -281.079864) (xy 340.24568 -281.055771)
			(xy 340.205315 -281.025142) (xy 340.170112 -280.988697) (xy 340.140899 -280.947295) (xy 340.118366 -280.901911)
			(xy 340.103042 -280.853613) (xy 340.095288 -280.803539) (xy 340.094824 -280.778204) (xy 338.90077 -280.778204)
			(xy 338.900272 -280.804853) (xy 338.892329 -280.857557) (xy 338.876619 -280.908487) (xy 338.853493 -280.956508)
			(xy 338.823469 -281.000545) (xy 338.787217 -281.039616) (xy 338.745546 -281.072847) (xy 338.699388 -281.099496)
			(xy 338.649774 -281.118968) (xy 338.597812 -281.130828) (xy 338.544662 -281.134812) (xy 338.491512 -281.130828)
			(xy 338.43955 -281.118968) (xy 338.389936 -281.099496) (xy 338.343778 -281.072847) (xy 338.302107 -281.039616)
			(xy 338.265855 -281.000545) (xy 338.235831 -280.956508) (xy 338.212705 -280.908487) (xy 338.196995 -280.857557)
			(xy 338.189052 -280.804853) (xy 337.933574 -280.804853) (xy 337.926048 -280.853575) (xy 337.910753 -280.901853)
			(xy 337.888254 -280.947223) (xy 337.859081 -280.988619) (xy 337.82392 -281.025066) (xy 337.783598 -281.055707)
			(xy 337.739064 -281.07982) (xy 337.691367 -281.096838) (xy 337.666584 -281.102054) (xy 337.643724 -281.106372)
			(xy 337.438746 -281.46121) (xy 337.446366 -281.483054) (xy 337.454977 -281.50934) (xy 337.464301 -281.563858)
			(xy 337.464908 -281.591512) (xy 337.464908 -281.59202) (xy 337.4644 -281.617927) (xy 337.464282 -281.618669)
			(xy 337.719152 -281.618669) (xy 337.719152 -281.565371) (xy 337.727095 -281.512667) (xy 337.742805 -281.461737)
			(xy 337.765931 -281.413716) (xy 337.795955 -281.369679) (xy 337.832207 -281.330608) (xy 337.873878 -281.297377)
			(xy 337.920036 -281.270728) (xy 337.96965 -281.251256) (xy 338.021612 -281.239396) (xy 338.074762 -281.235413)
			(xy 338.127912 -281.239396) (xy 338.179874 -281.251256) (xy 338.229488 -281.270728) (xy 338.275646 -281.297377)
			(xy 338.317317 -281.330608) (xy 338.353569 -281.369679) (xy 338.383593 -281.413716) (xy 338.406719 -281.461737)
			(xy 338.422429 -281.512667) (xy 338.430372 -281.565371) (xy 338.43087 -281.59202) (xy 338.430386 -281.617904)
			(xy 338.685436 -281.617904) (xy 338.685436 -281.566096) (xy 338.69354 -281.514926) (xy 338.709548 -281.465654)
			(xy 338.733067 -281.419492) (xy 338.763517 -281.377577) (xy 338.800148 -281.340942) (xy 338.84206 -281.310487)
			(xy 338.888219 -281.286963) (xy 338.937489 -281.270949) (xy 338.988658 -281.262839) (xy 339.014562 -281.262328)
			(xy 339.040073 -281.262825) (xy 339.090487 -281.270681) (xy 339.139089 -281.28621) (xy 339.184718 -281.309042)
			(xy 339.226284 -281.338633) (xy 339.262794 -281.374274) (xy 339.278468 -281.394408) (xy 339.690456 -281.394408)
			(xy 339.706157 -281.374295) (xy 339.742661 -281.33865) (xy 339.784221 -281.309053) (xy 339.829844 -281.286213)
			(xy 339.878441 -281.270675) (xy 339.928852 -281.262808) (xy 339.954362 -281.262328) (xy 339.980275 -281.262767)
			(xy 340.031464 -281.270869) (xy 340.080754 -281.286879) (xy 340.126933 -281.310404) (xy 340.168863 -281.340863)
			(xy 340.205512 -281.377508) (xy 340.235976 -281.419434) (xy 340.259506 -281.465611) (xy 340.275522 -281.514899)
			(xy 340.28363 -281.566087) (xy 340.28363 -281.617913) (xy 340.275522 -281.669101) (xy 340.259506 -281.718389)
			(xy 340.235976 -281.764566) (xy 340.205512 -281.806492) (xy 340.168863 -281.843137) (xy 340.126933 -281.873596)
			(xy 340.080754 -281.897121) (xy 340.031464 -281.913131) (xy 339.980275 -281.921233) (xy 339.954362 -281.921712)
			(xy 339.928849 -281.921255) (xy 339.878434 -281.913389) (xy 339.829832 -281.89785) (xy 339.784204 -281.87501)
			(xy 339.742639 -281.845414) (xy 339.706129 -281.809768) (xy 339.690456 -281.789632) (xy 339.278468 -281.789632)
			(xy 339.262822 -281.80979) (xy 339.226306 -281.845431) (xy 339.184734 -281.875021) (xy 339.139101 -281.897853)
			(xy 339.090494 -281.913382) (xy 339.040076 -281.921238) (xy 339.014562 -281.921712) (xy 338.988658 -281.921161)
			(xy 338.937489 -281.913051) (xy 338.888219 -281.897037) (xy 338.84206 -281.873513) (xy 338.800148 -281.843058)
			(xy 338.763517 -281.806423) (xy 338.733067 -281.764508) (xy 338.709548 -281.718346) (xy 338.69354 -281.669074)
			(xy 338.685436 -281.617904) (xy 338.430386 -281.617904) (xy 338.430372 -281.618669) (xy 338.422429 -281.671373)
			(xy 338.406719 -281.722303) (xy 338.383593 -281.770324) (xy 338.353569 -281.814361) (xy 338.317317 -281.853432)
			(xy 338.275646 -281.886663) (xy 338.229488 -281.913312) (xy 338.179874 -281.932784) (xy 338.127912 -281.944644)
			(xy 338.074762 -281.948628) (xy 338.021612 -281.944644) (xy 337.96965 -281.932784) (xy 337.920036 -281.913312)
			(xy 337.873878 -281.886663) (xy 337.832207 -281.853432) (xy 337.795955 -281.814361) (xy 337.765931 -281.770324)
			(xy 337.742805 -281.722303) (xy 337.727095 -281.671373) (xy 337.719152 -281.618669) (xy 337.464282 -281.618669)
			(xy 337.456294 -281.669104) (xy 337.440282 -281.718383) (xy 337.416759 -281.76455) (xy 337.386303 -281.806469)
			(xy 337.349665 -281.843107) (xy 337.307746 -281.873563) (xy 337.261579 -281.897086) (xy 337.2123 -281.913098)
			(xy 337.161123 -281.921204) (xy 337.109309 -281.921204) (xy 337.058132 -281.913098) (xy 337.008853 -281.897086)
			(xy 336.962686 -281.873563) (xy 336.920767 -281.843107) (xy 336.884129 -281.806469) (xy 336.853673 -281.76455)
			(xy 336.83015 -281.718383) (xy 336.814138 -281.669104) (xy 336.806032 -281.617927) (xy 336.805524 -281.59202)
			(xy 336.55127 -281.59202) (xy 336.550772 -281.618669) (xy 336.542829 -281.671373) (xy 336.527119 -281.722303)
			(xy 336.503993 -281.770324) (xy 336.473969 -281.814361) (xy 336.437717 -281.853432) (xy 336.396046 -281.886663)
			(xy 336.349888 -281.913312) (xy 336.300274 -281.932784) (xy 336.248312 -281.944644) (xy 336.195162 -281.948628)
			(xy 336.142012 -281.944644) (xy 336.09005 -281.932784) (xy 336.040436 -281.913312) (xy 335.994278 -281.886663)
			(xy 335.952607 -281.853432) (xy 335.916355 -281.814361) (xy 335.886331 -281.770324) (xy 335.863205 -281.722303)
			(xy 335.847495 -281.671373) (xy 335.839552 -281.618669) (xy 335.584595 -281.618669) (xy 335.577024 -281.667452)
			(xy 335.561677 -281.715761) (xy 335.539118 -281.761152) (xy 335.50988 -281.802558) (xy 335.47465 -281.839001)
			(xy 335.434259 -281.869625) (xy 335.389657 -281.893707) (xy 335.341896 -281.910681) (xy 335.317084 -281.91587)
			(xy 335.294224 -281.920188) (xy 335.089246 -282.27528) (xy 335.096866 -282.297124) (xy 335.1055 -282.32347)
			(xy 335.114821 -282.378118) (xy 335.115408 -282.405836) (xy 335.395824 -282.405836) (xy 335.396332 -282.379949)
			(xy 335.404431 -282.328811) (xy 335.42043 -282.279571) (xy 335.443936 -282.233439) (xy 335.474368 -282.191552)
			(xy 335.510978 -282.154942) (xy 335.552865 -282.12451) (xy 335.598997 -282.101004) (xy 335.648237 -282.085005)
			(xy 335.699375 -282.076906) (xy 335.751149 -282.076906) (xy 335.802287 -282.085005) (xy 335.851527 -282.101004)
			(xy 335.897659 -282.12451) (xy 335.939546 -282.154942) (xy 335.976156 -282.191552) (xy 336.006588 -282.233439)
			(xy 336.030094 -282.279571) (xy 336.046093 -282.328811) (xy 336.054192 -282.379949) (xy 336.0547 -282.405836)
			(xy 336.054214 -282.431707) (xy 336.336126 -282.431707) (xy 336.336126 -282.379893) (xy 336.344232 -282.328716)
			(xy 336.360244 -282.279437) (xy 336.383768 -282.23327) (xy 336.414225 -282.191352) (xy 336.450864 -282.154714)
			(xy 336.492784 -282.12426) (xy 336.538952 -282.100738) (xy 336.588231 -282.084728) (xy 336.639409 -282.076625)
			(xy 336.665316 -282.076144) (xy 336.690811 -282.076599) (xy 336.74119 -282.084464) (xy 336.789755 -282.100003)
			(xy 336.835342 -282.122845) (xy 336.876862 -282.152443) (xy 336.913321 -282.188089) (xy 336.928968 -282.208224)
			(xy 337.341464 -282.208224) (xy 337.35711 -282.18809) (xy 337.393571 -282.152447) (xy 337.435092 -282.122853)
			(xy 337.480679 -282.100016) (xy 337.529243 -282.084481) (xy 337.579622 -282.076621) (xy 337.605116 -282.076144)
			(xy 337.631025 -282.076581) (xy 337.682206 -282.08469) (xy 337.731488 -282.100704) (xy 337.777658 -282.124231)
			(xy 337.819579 -282.154691) (xy 337.85622 -282.191333) (xy 337.886677 -282.233256) (xy 337.910202 -282.279427)
			(xy 337.926214 -282.32871) (xy 337.93432 -282.379891) (xy 337.93432 -282.431709) (xy 337.934197 -282.432485)
			(xy 338.189306 -282.432485) (xy 338.189306 -282.379187) (xy 338.197249 -282.326483) (xy 338.212959 -282.275553)
			(xy 338.236085 -282.227532) (xy 338.266109 -282.183495) (xy 338.302361 -282.144424) (xy 338.344032 -282.111193)
			(xy 338.39019 -282.084544) (xy 338.439804 -282.065072) (xy 338.491766 -282.053212) (xy 338.544916 -282.049229)
			(xy 338.598066 -282.053212) (xy 338.650028 -282.065072) (xy 338.699642 -282.084544) (xy 338.7458 -282.111193)
			(xy 338.787471 -282.144424) (xy 338.823723 -282.183495) (xy 338.853747 -282.227532) (xy 338.876873 -282.275553)
			(xy 338.892583 -282.326483) (xy 338.900526 -282.379187) (xy 338.901024 -282.405836) (xy 338.900526 -282.432485)
			(xy 338.892583 -282.485189) (xy 338.876873 -282.536119) (xy 338.853747 -282.58414) (xy 338.823723 -282.628177)
			(xy 338.787471 -282.667248) (xy 338.7458 -282.700479) (xy 338.699642 -282.727128) (xy 338.650028 -282.7466)
			(xy 338.598066 -282.75846) (xy 338.544916 -282.762444) (xy 338.491766 -282.75846) (xy 338.439804 -282.7466)
			(xy 338.39019 -282.727128) (xy 338.344032 -282.700479) (xy 338.302361 -282.667248) (xy 338.266109 -282.628177)
			(xy 338.236085 -282.58414) (xy 338.212959 -282.536119) (xy 338.197249 -282.485189) (xy 338.189306 -282.432485)
			(xy 337.934197 -282.432485) (xy 337.926214 -282.48289) (xy 337.910202 -282.532173) (xy 337.886677 -282.578344)
			(xy 337.85622 -282.620267) (xy 337.819579 -282.656909) (xy 337.777658 -282.687369) (xy 337.731488 -282.710896)
			(xy 337.682206 -282.72691) (xy 337.631025 -282.735019) (xy 337.605116 -282.735528) (xy 337.579623 -282.735021)
			(xy 337.529248 -282.727163) (xy 337.480686 -282.711632) (xy 337.435099 -282.6888) (xy 337.393577 -282.659213)
			(xy 337.357114 -282.623577) (xy 337.341464 -282.603448) (xy 336.928968 -282.603448) (xy 336.913322 -282.623582)
			(xy 336.876859 -282.659221) (xy 336.835338 -282.688813) (xy 336.78975 -282.71165) (xy 336.741187 -282.727186)
			(xy 336.69081 -282.735049) (xy 336.665316 -282.735528) (xy 336.639409 -282.734975) (xy 336.588231 -282.726872)
			(xy 336.538952 -282.710862) (xy 336.492784 -282.68734) (xy 336.450864 -282.656886) (xy 336.414225 -282.620248)
			(xy 336.383768 -282.57833) (xy 336.360244 -282.532163) (xy 336.344232 -282.482884) (xy 336.336126 -282.431707)
			(xy 336.054214 -282.431707) (xy 336.054179 -282.433545) (xy 336.044978 -282.488191) (xy 336.036412 -282.514548)
			(xy 336.028538 -282.536646) (xy 336.23377 -282.891738) (xy 336.25663 -282.896056) (xy 336.281436 -282.901231)
			(xy 336.329174 -282.918223) (xy 336.373751 -282.94232) (xy 336.414116 -282.972953) (xy 336.449318 -283.009401)
			(xy 336.478529 -283.050806) (xy 336.501062 -283.096194) (xy 336.516384 -283.144494) (xy 336.524137 -283.19457)
			(xy 336.5246 -283.219906) (xy 336.524092 -283.245793) (xy 336.523971 -283.246555) (xy 336.779352 -283.246555)
			(xy 336.779352 -283.193257) (xy 336.787295 -283.140553) (xy 336.803005 -283.089623) (xy 336.826131 -283.041602)
			(xy 336.856155 -282.997565) (xy 336.892407 -282.958494) (xy 336.934078 -282.925263) (xy 336.980236 -282.898614)
			(xy 337.02985 -282.879142) (xy 337.081812 -282.867282) (xy 337.134962 -282.863299) (xy 337.188112 -282.867282)
			(xy 337.240074 -282.879142) (xy 337.289688 -282.898614) (xy 337.335846 -282.925263) (xy 337.377517 -282.958494)
			(xy 337.413769 -282.997565) (xy 337.443793 -283.041602) (xy 337.466919 -283.089623) (xy 337.482629 -283.140553)
			(xy 337.490572 -283.193257) (xy 337.49107 -283.219906) (xy 337.490572 -283.246555) (xy 337.719152 -283.246555)
			(xy 337.719152 -283.193257) (xy 337.727095 -283.140553) (xy 337.742805 -283.089623) (xy 337.765931 -283.041602)
			(xy 337.795955 -282.997565) (xy 337.832207 -282.958494) (xy 337.873878 -282.925263) (xy 337.920036 -282.898614)
			(xy 337.96965 -282.879142) (xy 338.021612 -282.867282) (xy 338.074762 -282.863299) (xy 338.127912 -282.867282)
			(xy 338.179874 -282.879142) (xy 338.229488 -282.898614) (xy 338.275646 -282.925263) (xy 338.317317 -282.958494)
			(xy 338.353569 -282.997565) (xy 338.383593 -283.041602) (xy 338.406719 -283.089623) (xy 338.422429 -283.140553)
			(xy 338.430372 -283.193257) (xy 338.43087 -283.219906) (xy 338.685124 -283.219906) (xy 338.685593 -283.194571)
			(xy 338.693345 -283.144497) (xy 338.708668 -283.096199) (xy 338.731201 -283.050814) (xy 338.760412 -283.009411)
			(xy 338.795615 -282.972966) (xy 338.83598 -282.942336) (xy 338.880556 -282.918243) (xy 338.928293 -282.901254)
			(xy 338.953094 -282.896056) (xy 338.975954 -282.891738) (xy 339.181186 -282.536392) (xy 339.173566 -282.514548)
			(xy 339.164924 -282.488205) (xy 339.155609 -282.433555) (xy 339.155024 -282.405836) (xy 339.155532 -282.379929)
			(xy 339.163638 -282.328752) (xy 339.17965 -282.279473) (xy 339.203173 -282.233306) (xy 339.233629 -282.191387)
			(xy 339.270267 -282.154749) (xy 339.312186 -282.124293) (xy 339.358353 -282.10077) (xy 339.407632 -282.084758)
			(xy 339.458809 -282.076652) (xy 339.510623 -282.076652) (xy 339.5618 -282.084758) (xy 339.611079 -282.10077)
			(xy 339.657246 -282.124293) (xy 339.699165 -282.154749) (xy 339.735803 -282.191387) (xy 339.766259 -282.233306)
			(xy 339.789782 -282.279473) (xy 339.805794 -282.328752) (xy 339.8139 -282.379929) (xy 339.814408 -282.405836)
			(xy 339.813997 -282.431202) (xy 339.813799 -282.432485) (xy 340.068906 -282.432485) (xy 340.068906 -282.379187)
			(xy 340.076849 -282.326483) (xy 340.092559 -282.275553) (xy 340.115685 -282.227532) (xy 340.145709 -282.183495)
			(xy 340.181961 -282.144424) (xy 340.223632 -282.111193) (xy 340.26979 -282.084544) (xy 340.319404 -282.065072)
			(xy 340.371366 -282.053212) (xy 340.424516 -282.049229) (xy 340.477666 -282.053212) (xy 340.529628 -282.065072)
			(xy 340.579242 -282.084544) (xy 340.6254 -282.111193) (xy 340.667071 -282.144424) (xy 340.703323 -282.183495)
			(xy 340.733347 -282.227532) (xy 340.756473 -282.275553) (xy 340.772183 -282.326483) (xy 340.780126 -282.379187)
			(xy 340.780624 -282.405836) (xy 341.034624 -282.405836) (xy 341.035068 -282.38049) (xy 341.04285 -282.330397)
			(xy 341.058205 -282.282085) (xy 341.080771 -282.236692) (xy 341.110018 -282.195286) (xy 341.145256 -282.158843)
			(xy 341.185656 -282.128222) (xy 341.230265 -282.104142) (xy 341.278033 -282.087172) (xy 341.302848 -282.081986)
			(xy 341.325708 -282.077668) (xy 341.530686 -281.72283) (xy 341.522812 -281.700986) (xy 341.514229 -281.674568)
			(xy 341.505035 -281.619792) (xy 341.504524 -281.59202) (xy 341.505032 -281.566133) (xy 341.513131 -281.514995)
			(xy 341.52913 -281.465755) (xy 341.552636 -281.419623) (xy 341.583068 -281.377736) (xy 341.619678 -281.341126)
			(xy 341.661565 -281.310694) (xy 341.707697 -281.287188) (xy 341.756937 -281.271189) (xy 341.808075 -281.26309)
			(xy 341.859849 -281.26309) (xy 341.910987 -281.271189) (xy 341.960227 -281.287188) (xy 342.006359 -281.310694)
			(xy 342.048246 -281.341126) (xy 342.084856 -281.377736) (xy 342.115288 -281.419623) (xy 342.138794 -281.465755)
			(xy 342.154793 -281.514995) (xy 342.162892 -281.566133) (xy 342.1634 -281.59202) (xy 342.162935 -281.617355)
			(xy 342.162731 -281.618669) (xy 342.418152 -281.618669) (xy 342.418152 -281.565371) (xy 342.426095 -281.512667)
			(xy 342.441805 -281.461737) (xy 342.464931 -281.413716) (xy 342.494955 -281.369679) (xy 342.531207 -281.330608)
			(xy 342.572878 -281.297377) (xy 342.619036 -281.270728) (xy 342.66865 -281.251256) (xy 342.720612 -281.239396)
			(xy 342.773762 -281.235413) (xy 342.826912 -281.239396) (xy 342.878874 -281.251256) (xy 342.928488 -281.270728)
			(xy 342.974646 -281.297377) (xy 343.016317 -281.330608) (xy 343.052569 -281.369679) (xy 343.082593 -281.413716)
			(xy 343.105719 -281.461737) (xy 343.121429 -281.512667) (xy 343.129372 -281.565371) (xy 343.12987 -281.59202)
			(xy 343.129372 -281.618669) (xy 343.121429 -281.671373) (xy 343.105719 -281.722303) (xy 343.082593 -281.770324)
			(xy 343.052569 -281.814361) (xy 343.016317 -281.853432) (xy 342.974646 -281.886663) (xy 342.928488 -281.913312)
			(xy 342.878874 -281.932784) (xy 342.826912 -281.944644) (xy 342.773762 -281.948628) (xy 342.720612 -281.944644)
			(xy 342.66865 -281.932784) (xy 342.619036 -281.913312) (xy 342.572878 -281.886663) (xy 342.531207 -281.853432)
			(xy 342.494955 -281.814361) (xy 342.464931 -281.770324) (xy 342.441805 -281.722303) (xy 342.426095 -281.671373)
			(xy 342.418152 -281.618669) (xy 342.162731 -281.618669) (xy 342.15518 -281.667428) (xy 342.139855 -281.715725)
			(xy 342.117321 -281.761109) (xy 342.088109 -281.802511) (xy 342.052906 -281.838956) (xy 342.012542 -281.869586)
			(xy 341.967967 -281.89368) (xy 341.92023 -281.910671) (xy 341.89543 -281.91587) (xy 341.87257 -281.920188)
			(xy 341.667592 -282.275026) (xy 341.675466 -282.297124) (xy 341.684085 -282.323474) (xy 341.693414 -282.378119)
			(xy 341.694008 -282.405836) (xy 341.6935 -282.431743) (xy 341.693382 -282.432485) (xy 341.948506 -282.432485)
			(xy 341.948506 -282.379187) (xy 341.956449 -282.326483) (xy 341.972159 -282.275553) (xy 341.995285 -282.227532)
			(xy 342.025309 -282.183495) (xy 342.061561 -282.144424) (xy 342.103232 -282.111193) (xy 342.14939 -282.084544)
			(xy 342.199004 -282.065072) (xy 342.250966 -282.053212) (xy 342.304116 -282.049229) (xy 342.357266 -282.053212)
			(xy 342.409228 -282.065072) (xy 342.458842 -282.084544) (xy 342.505 -282.111193) (xy 342.546671 -282.144424)
			(xy 342.582923 -282.183495) (xy 342.612947 -282.227532) (xy 342.636073 -282.275553) (xy 342.651783 -282.326483)
			(xy 342.659726 -282.379187) (xy 342.660224 -282.405836) (xy 342.914224 -282.405836) (xy 342.914629 -282.380499)
			(xy 342.922392 -282.330422) (xy 342.937724 -282.282122) (xy 342.960266 -282.236737) (xy 342.989485 -282.195335)
			(xy 343.024695 -282.15889) (xy 343.065066 -282.128262) (xy 343.109648 -282.10417) (xy 343.157391 -282.087183)
			(xy 343.182194 -282.081986) (xy 343.205054 -282.077668) (xy 343.410286 -281.722322) (xy 343.402666 -281.700478)
			(xy 343.39404 -281.674196) (xy 343.384726 -281.619675) (xy 343.384124 -281.59202) (xy 343.384632 -281.566113)
			(xy 343.392738 -281.514936) (xy 343.40875 -281.465657) (xy 343.432273 -281.41949) (xy 343.462729 -281.377571)
			(xy 343.499367 -281.340933) (xy 343.541286 -281.310477) (xy 343.587453 -281.286954) (xy 343.636732 -281.270942)
			(xy 343.687909 -281.262836) (xy 343.739723 -281.262836) (xy 343.7909 -281.270942) (xy 343.840179 -281.286954)
			(xy 343.886346 -281.310477) (xy 343.928265 -281.340933) (xy 343.964903 -281.377571) (xy 343.995359 -281.41949)
			(xy 344.018882 -281.465657) (xy 344.034894 -281.514936) (xy 344.043 -281.566113) (xy 344.043508 -281.59202)
			(xy 344.043045 -281.617395) (xy 344.042848 -281.618669) (xy 344.298006 -281.618669) (xy 344.298006 -281.565371)
			(xy 344.305949 -281.512667) (xy 344.321659 -281.461737) (xy 344.344785 -281.413716) (xy 344.374809 -281.369679)
			(xy 344.411061 -281.330608) (xy 344.452732 -281.297377) (xy 344.49889 -281.270728) (xy 344.548504 -281.251256)
			(xy 344.600466 -281.239396) (xy 344.653616 -281.235413) (xy 344.706766 -281.239396) (xy 344.758728 -281.251256)
			(xy 344.808342 -281.270728) (xy 344.8545 -281.297377) (xy 344.896171 -281.330608) (xy 344.932423 -281.369679)
			(xy 344.962447 -281.413716) (xy 344.985573 -281.461737) (xy 345.001283 -281.512667) (xy 345.009226 -281.565371)
			(xy 345.009724 -281.59202) (xy 345.263724 -281.59202) (xy 345.264244 -281.566676) (xy 345.272013 -281.516587)
			(xy 345.287357 -281.468277) (xy 345.309913 -281.422884) (xy 345.33915 -281.381477) (xy 345.374379 -281.345033)
			(xy 345.414771 -281.31441) (xy 345.459374 -281.290329) (xy 345.507136 -281.273357) (xy 345.531948 -281.26817)
			(xy 345.554808 -281.263852) (xy 345.759786 -280.909014) (xy 345.751912 -280.88717) (xy 345.743326 -280.860753)
			(xy 345.734134 -280.805977) (xy 345.733624 -280.778204) (xy 345.734132 -280.752317) (xy 345.742231 -280.701179)
			(xy 345.75823 -280.651939) (xy 345.781736 -280.605807) (xy 345.812168 -280.56392) (xy 345.848778 -280.52731)
			(xy 345.890665 -280.496878) (xy 345.936797 -280.473372) (xy 345.986037 -280.457373) (xy 346.037175 -280.449274)
			(xy 346.088949 -280.449274) (xy 346.140087 -280.457373) (xy 346.189327 -280.473372) (xy 346.235459 -280.496878)
			(xy 346.277346 -280.52731) (xy 346.313956 -280.56392) (xy 346.344388 -280.605807) (xy 346.367894 -280.651939)
			(xy 346.383893 -280.701179) (xy 346.391992 -280.752317) (xy 346.3925 -280.778204) (xy 346.392021 -280.803539)
			(xy 346.391818 -280.804853) (xy 346.647252 -280.804853) (xy 346.647252 -280.751555) (xy 346.655195 -280.698851)
			(xy 346.670905 -280.647921) (xy 346.694031 -280.5999) (xy 346.724055 -280.555863) (xy 346.760307 -280.516792)
			(xy 346.801978 -280.483561) (xy 346.848136 -280.456912) (xy 346.89775 -280.43744) (xy 346.949712 -280.42558)
			(xy 347.002862 -280.421597) (xy 347.056012 -280.42558) (xy 347.107974 -280.43744) (xy 347.157588 -280.456912)
			(xy 347.203746 -280.483561) (xy 347.245417 -280.516792) (xy 347.281669 -280.555863) (xy 347.311693 -280.5999)
			(xy 347.334819 -280.647921) (xy 347.350529 -280.698851) (xy 347.358472 -280.751555) (xy 347.35897 -280.778204)
			(xy 348.553024 -280.778204) (xy 348.553532 -280.752317) (xy 348.561631 -280.701179) (xy 348.57763 -280.651939)
			(xy 348.601136 -280.605807) (xy 348.631568 -280.56392) (xy 348.668178 -280.52731) (xy 348.710065 -280.496878)
			(xy 348.756197 -280.473372) (xy 348.805437 -280.457373) (xy 348.856575 -280.449274) (xy 348.908349 -280.449274)
			(xy 348.959487 -280.457373) (xy 349.008727 -280.473372) (xy 349.054859 -280.496878) (xy 349.096746 -280.52731)
			(xy 349.133356 -280.56392) (xy 349.163788 -280.605807) (xy 349.187294 -280.651939) (xy 349.203293 -280.701179)
			(xy 349.211392 -280.752317) (xy 349.2119 -280.778204) (xy 349.211362 -280.804853) (xy 349.466652 -280.804853)
			(xy 349.466652 -280.751555) (xy 349.474595 -280.698851) (xy 349.490305 -280.647921) (xy 349.513431 -280.5999)
			(xy 349.543455 -280.555863) (xy 349.579707 -280.516792) (xy 349.621378 -280.483561) (xy 349.667536 -280.456912)
			(xy 349.71715 -280.43744) (xy 349.769112 -280.42558) (xy 349.822262 -280.421597) (xy 349.875412 -280.42558)
			(xy 349.927374 -280.43744) (xy 349.976988 -280.456912) (xy 350.023146 -280.483561) (xy 350.064817 -280.516792)
			(xy 350.101069 -280.555863) (xy 350.131093 -280.5999) (xy 350.154219 -280.647921) (xy 350.169929 -280.698851)
			(xy 350.177872 -280.751555) (xy 350.17837 -280.778204) (xy 350.177872 -280.804853) (xy 350.406706 -280.804853)
			(xy 350.406706 -280.751555) (xy 350.414649 -280.698851) (xy 350.430359 -280.647921) (xy 350.453485 -280.5999)
			(xy 350.483509 -280.555863) (xy 350.519761 -280.516792) (xy 350.561432 -280.483561) (xy 350.60759 -280.456912)
			(xy 350.657204 -280.43744) (xy 350.709166 -280.42558) (xy 350.762316 -280.421597) (xy 350.815466 -280.42558)
			(xy 350.867428 -280.43744) (xy 350.917042 -280.456912) (xy 350.9632 -280.483561) (xy 351.004871 -280.516792)
			(xy 351.041123 -280.555863) (xy 351.071147 -280.5999) (xy 351.094273 -280.647921) (xy 351.109983 -280.698851)
			(xy 351.117926 -280.751555) (xy 351.118424 -280.778204) (xy 351.117926 -280.804853) (xy 351.109983 -280.857557)
			(xy 351.094273 -280.908487) (xy 351.071147 -280.956508) (xy 351.041123 -281.000545) (xy 351.004871 -281.039616)
			(xy 350.9632 -281.072847) (xy 350.917042 -281.099496) (xy 350.867428 -281.118968) (xy 350.815466 -281.130828)
			(xy 350.762316 -281.134812) (xy 350.709166 -281.130828) (xy 350.657204 -281.118968) (xy 350.60759 -281.099496)
			(xy 350.561432 -281.072847) (xy 350.519761 -281.039616) (xy 350.483509 -281.000545) (xy 350.453485 -280.956508)
			(xy 350.430359 -280.908487) (xy 350.414649 -280.857557) (xy 350.406706 -280.804853) (xy 350.177872 -280.804853)
			(xy 350.169929 -280.857557) (xy 350.154219 -280.908487) (xy 350.131093 -280.956508) (xy 350.101069 -281.000545)
			(xy 350.064817 -281.039616) (xy 350.023146 -281.072847) (xy 349.976988 -281.099496) (xy 349.927374 -281.118968)
			(xy 349.875412 -281.130828) (xy 349.822262 -281.134812) (xy 349.769112 -281.130828) (xy 349.71715 -281.118968)
			(xy 349.667536 -281.099496) (xy 349.621378 -281.072847) (xy 349.579707 -281.039616) (xy 349.543455 -281.000545)
			(xy 349.513431 -280.956508) (xy 349.490305 -280.908487) (xy 349.474595 -280.857557) (xy 349.466652 -280.804853)
			(xy 349.211362 -280.804853) (xy 349.211342 -280.805848) (xy 349.202155 -280.860366) (xy 349.193612 -280.886662)
			(xy 349.185992 -280.908506) (xy 349.391224 -281.263852) (xy 349.414084 -281.26817) (xy 349.438905 -281.273337)
			(xy 349.486682 -281.290294) (xy 349.531299 -281.314367) (xy 349.571704 -281.344988) (xy 349.606944 -281.381435)
			(xy 349.636188 -281.422848) (xy 349.658745 -281.46825) (xy 349.674085 -281.516571) (xy 349.681844 -281.566671)
			(xy 349.682308 -281.59202) (xy 349.6818 -281.617927) (xy 349.673694 -281.669104) (xy 349.657682 -281.718383)
			(xy 349.634159 -281.76455) (xy 349.603703 -281.806469) (xy 349.567065 -281.843107) (xy 349.525146 -281.873563)
			(xy 349.478979 -281.897086) (xy 349.4297 -281.913098) (xy 349.378523 -281.921204) (xy 349.326709 -281.921204)
			(xy 349.275532 -281.913098) (xy 349.226253 -281.897086) (xy 349.180086 -281.873563) (xy 349.138167 -281.843107)
			(xy 349.101529 -281.806469) (xy 349.071073 -281.76455) (xy 349.04755 -281.718383) (xy 349.031538 -281.669104)
			(xy 349.023432 -281.617927) (xy 349.022924 -281.59202) (xy 349.023522 -281.564303) (xy 349.032842 -281.509656)
			(xy 349.041466 -281.483308) (xy 349.04934 -281.46121) (xy 348.844362 -281.106372) (xy 348.821502 -281.102054)
			(xy 348.796672 -281.096882) (xy 348.748866 -281.079946) (xy 348.704218 -281.055889) (xy 348.663781 -281.025278)
			(xy 348.628509 -280.988835) (xy 348.599234 -280.947421) (xy 348.576647 -280.902011) (xy 348.561281 -280.853678)
			(xy 348.553498 -280.803562) (xy 348.553024 -280.778204) (xy 347.35897 -280.778204) (xy 347.358472 -280.804853)
			(xy 347.350529 -280.857557) (xy 347.334819 -280.908487) (xy 347.311693 -280.956508) (xy 347.281669 -281.000545)
			(xy 347.245417 -281.039616) (xy 347.203746 -281.072847) (xy 347.157588 -281.099496) (xy 347.107974 -281.118968)
			(xy 347.056012 -281.130828) (xy 347.002862 -281.134812) (xy 346.949712 -281.130828) (xy 346.89775 -281.118968)
			(xy 346.848136 -281.099496) (xy 346.801978 -281.072847) (xy 346.760307 -281.039616) (xy 346.724055 -281.000545)
			(xy 346.694031 -280.956508) (xy 346.670905 -280.908487) (xy 346.655195 -280.857557) (xy 346.647252 -280.804853)
			(xy 346.391818 -280.804853) (xy 346.384268 -280.853611) (xy 346.368945 -280.901908) (xy 346.346413 -280.947292)
			(xy 346.317203 -280.988694) (xy 346.282002 -281.025139) (xy 346.241639 -281.055769) (xy 346.197065 -281.079864)
			(xy 346.14933 -281.096855) (xy 346.12453 -281.102054) (xy 346.10167 -281.106372) (xy 345.896692 -281.46121)
			(xy 345.904566 -281.483308) (xy 345.913205 -281.509652) (xy 345.922521 -281.564301) (xy 345.923108 -281.59202)
			(xy 345.9226 -281.617927) (xy 345.922482 -281.618669) (xy 346.177606 -281.618669) (xy 346.177606 -281.565371)
			(xy 346.185549 -281.512667) (xy 346.201259 -281.461737) (xy 346.224385 -281.413716) (xy 346.254409 -281.369679)
			(xy 346.290661 -281.330608) (xy 346.332332 -281.297377) (xy 346.37849 -281.270728) (xy 346.428104 -281.251256)
			(xy 346.480066 -281.239396) (xy 346.533216 -281.235413) (xy 346.586366 -281.239396) (xy 346.638328 -281.251256)
			(xy 346.687942 -281.270728) (xy 346.7341 -281.297377) (xy 346.775771 -281.330608) (xy 346.812023 -281.369679)
			(xy 346.842047 -281.413716) (xy 346.865173 -281.461737) (xy 346.880883 -281.512667) (xy 346.888826 -281.565371)
			(xy 346.889324 -281.59202) (xy 346.88884 -281.617909) (xy 347.143809 -281.617909) (xy 347.143809 -281.566091)
			(xy 347.151916 -281.514912) (xy 347.167929 -281.465631) (xy 347.191454 -281.419462) (xy 347.221912 -281.377541)
			(xy 347.258553 -281.340902) (xy 347.300475 -281.310446) (xy 347.346646 -281.286923) (xy 347.395928 -281.270912)
			(xy 347.447107 -281.262808) (xy 347.473016 -281.262328) (xy 347.498529 -281.262786) (xy 347.548945 -281.27065)
			(xy 347.597547 -281.286187) (xy 347.643176 -281.309027) (xy 347.684741 -281.338624) (xy 347.721249 -281.374271)
			(xy 347.736922 -281.394408) (xy 348.14891 -281.394408) (xy 348.16458 -281.37427) (xy 348.20109 -281.338625)
			(xy 348.242656 -281.309032) (xy 348.288285 -281.286196) (xy 348.336888 -281.270663) (xy 348.387304 -281.262804)
			(xy 348.412816 -281.262328) (xy 348.438724 -281.262797) (xy 348.489902 -281.270905) (xy 348.539182 -281.286919)
			(xy 348.585349 -281.310445) (xy 348.627269 -281.340903) (xy 348.663907 -281.377543) (xy 348.694363 -281.419464)
			(xy 348.717887 -281.465633) (xy 348.733899 -281.514914) (xy 348.742004 -281.566092) (xy 348.742004 -281.617908)
			(xy 348.733899 -281.669086) (xy 348.717887 -281.718367) (xy 348.694363 -281.764536) (xy 348.663907 -281.806457)
			(xy 348.627269 -281.843097) (xy 348.585349 -281.873555) (xy 348.539182 -281.897081) (xy 348.489902 -281.913095)
			(xy 348.438724 -281.921203) (xy 348.412816 -281.921712) (xy 348.387305 -281.921215) (xy 348.336891 -281.913357)
			(xy 348.28829 -281.897827) (xy 348.242662 -281.874994) (xy 348.201096 -281.845405) (xy 348.164585 -281.809765)
			(xy 348.14891 -281.789632) (xy 347.736922 -281.789632) (xy 347.721245 -281.809764) (xy 347.684735 -281.845407)
			(xy 347.64317 -281.875) (xy 347.597542 -281.897836) (xy 347.548942 -281.913371) (xy 347.498528 -281.921234)
			(xy 347.473016 -281.921712) (xy 347.447107 -281.921192) (xy 347.395928 -281.913088) (xy 347.346646 -281.897077)
			(xy 347.300475 -281.873554) (xy 347.258553 -281.843098) (xy 347.221912 -281.806459) (xy 347.191454 -281.764538)
			(xy 347.167929 -281.718369) (xy 347.151916 -281.669088) (xy 347.143809 -281.617909) (xy 346.88884 -281.617909)
			(xy 346.888826 -281.618669) (xy 346.880883 -281.671373) (xy 346.865173 -281.722303) (xy 346.842047 -281.770324)
			(xy 346.812023 -281.814361) (xy 346.775771 -281.853432) (xy 346.7341 -281.886663) (xy 346.687942 -281.913312)
			(xy 346.638328 -281.932784) (xy 346.586366 -281.944644) (xy 346.533216 -281.948628) (xy 346.480066 -281.944644)
			(xy 346.428104 -281.932784) (xy 346.37849 -281.913312) (xy 346.332332 -281.886663) (xy 346.290661 -281.853432)
			(xy 346.254409 -281.814361) (xy 346.224385 -281.770324) (xy 346.201259 -281.722303) (xy 346.185549 -281.671373)
			(xy 346.177606 -281.618669) (xy 345.922482 -281.618669) (xy 345.914494 -281.669104) (xy 345.898482 -281.718383)
			(xy 345.874959 -281.76455) (xy 345.844503 -281.806469) (xy 345.807865 -281.843107) (xy 345.765946 -281.873563)
			(xy 345.719779 -281.897086) (xy 345.6705 -281.913098) (xy 345.619323 -281.921204) (xy 345.567509 -281.921204)
			(xy 345.516332 -281.913098) (xy 345.467053 -281.897086) (xy 345.420886 -281.873563) (xy 345.378967 -281.843107)
			(xy 345.342329 -281.806469) (xy 345.311873 -281.76455) (xy 345.28835 -281.718383) (xy 345.272338 -281.669104)
			(xy 345.264232 -281.617927) (xy 345.263724 -281.59202) (xy 345.009724 -281.59202) (xy 345.009226 -281.618669)
			(xy 345.001283 -281.671373) (xy 344.985573 -281.722303) (xy 344.962447 -281.770324) (xy 344.932423 -281.814361)
			(xy 344.896171 -281.853432) (xy 344.8545 -281.886663) (xy 344.808342 -281.913312) (xy 344.758728 -281.932784)
			(xy 344.706766 -281.944644) (xy 344.653616 -281.948628) (xy 344.600466 -281.944644) (xy 344.548504 -281.932784)
			(xy 344.49889 -281.913312) (xy 344.452732 -281.886663) (xy 344.411061 -281.853432) (xy 344.374809 -281.814361)
			(xy 344.344785 -281.770324) (xy 344.321659 -281.722303) (xy 344.305949 -281.671373) (xy 344.298006 -281.618669)
			(xy 344.042848 -281.618669) (xy 344.035274 -281.667545) (xy 344.019903 -281.71591) (xy 343.997297 -281.761346)
			(xy 343.967989 -281.802777) (xy 343.932674 -281.839223) (xy 343.892188 -281.869822) (xy 343.847487 -281.893849)
			(xy 343.79963 -281.910736) (xy 343.774776 -281.91587) (xy 343.751916 -281.920188) (xy 343.546938 -282.275026)
			(xy 343.554812 -282.297124) (xy 343.563378 -282.32348) (xy 343.572573 -282.378127) (xy 343.5731 -282.405836)
			(xy 343.854024 -282.405836) (xy 343.854532 -282.379949) (xy 343.862631 -282.328811) (xy 343.87863 -282.279571)
			(xy 343.902136 -282.233439) (xy 343.932568 -282.191552) (xy 343.969178 -282.154942) (xy 344.011065 -282.12451)
			(xy 344.057197 -282.101004) (xy 344.106437 -282.085005) (xy 344.157575 -282.076906) (xy 344.209349 -282.076906)
			(xy 344.260487 -282.085005) (xy 344.309727 -282.101004) (xy 344.355859 -282.12451) (xy 344.397746 -282.154942)
			(xy 344.434356 -282.191552) (xy 344.464788 -282.233439) (xy 344.488294 -282.279571) (xy 344.504293 -282.328811)
			(xy 344.512392 -282.379949) (xy 344.5129 -282.405836) (xy 344.512385 -282.431703) (xy 344.794152 -282.431703)
			(xy 344.794152 -282.379897) (xy 344.802256 -282.32873) (xy 344.818263 -282.27946) (xy 344.841781 -282.2333)
			(xy 344.872229 -282.191388) (xy 344.908859 -282.154754) (xy 344.950768 -282.124301) (xy 344.996925 -282.100778)
			(xy 345.046193 -282.084765) (xy 345.097359 -282.076655) (xy 345.123262 -282.076144) (xy 345.148774 -282.076635)
			(xy 345.199188 -282.084491) (xy 345.247791 -282.100021) (xy 345.293419 -282.122855) (xy 345.334985 -282.152446)
			(xy 345.371495 -282.188089) (xy 345.387168 -282.208224) (xy 345.799156 -282.208224) (xy 345.814861 -282.188115)
			(xy 345.851364 -282.152468) (xy 345.892922 -282.122871) (xy 345.938545 -282.10003) (xy 345.987141 -282.084491)
			(xy 346.037552 -282.076624) (xy 346.063062 -282.076144) (xy 346.088976 -282.076551) (xy 346.140167 -282.084653)
			(xy 346.18946 -282.100664) (xy 346.235642 -282.12419) (xy 346.277574 -282.154651) (xy 346.314224 -282.191297)
			(xy 346.34469 -282.233226) (xy 346.368221 -282.279404) (xy 346.384238 -282.328696) (xy 346.392346 -282.379886)
			(xy 346.392346 -282.431714) (xy 346.392224 -282.432485) (xy 346.647252 -282.432485) (xy 346.647252 -282.379187)
			(xy 346.655195 -282.326483) (xy 346.670905 -282.275553) (xy 346.694031 -282.227532) (xy 346.724055 -282.183495)
			(xy 346.760307 -282.144424) (xy 346.801978 -282.111193) (xy 346.848136 -282.084544) (xy 346.89775 -282.065072)
			(xy 346.949712 -282.053212) (xy 347.002862 -282.049229) (xy 347.056012 -282.053212) (xy 347.107974 -282.065072)
			(xy 347.157588 -282.084544) (xy 347.203746 -282.111193) (xy 347.245417 -282.144424) (xy 347.281669 -282.183495)
			(xy 347.311693 -282.227532) (xy 347.334819 -282.275553) (xy 347.350529 -282.326483) (xy 347.358472 -282.379187)
			(xy 347.35897 -282.405836) (xy 347.358472 -282.432485) (xy 347.350529 -282.485189) (xy 347.334819 -282.536119)
			(xy 347.311693 -282.58414) (xy 347.281669 -282.628177) (xy 347.245417 -282.667248) (xy 347.203746 -282.700479)
			(xy 347.157588 -282.727128) (xy 347.107974 -282.7466) (xy 347.056012 -282.75846) (xy 347.002862 -282.762444)
			(xy 346.949712 -282.75846) (xy 346.89775 -282.7466) (xy 346.848136 -282.727128) (xy 346.801978 -282.700479)
			(xy 346.760307 -282.667248) (xy 346.724055 -282.628177) (xy 346.694031 -282.58414) (xy 346.670905 -282.536119)
			(xy 346.655195 -282.485189) (xy 346.647252 -282.432485) (xy 346.392224 -282.432485) (xy 346.384238 -282.482904)
			(xy 346.368221 -282.532196) (xy 346.34469 -282.578374) (xy 346.314224 -282.620303) (xy 346.277574 -282.656949)
			(xy 346.235642 -282.68741) (xy 346.18946 -282.710936) (xy 346.140167 -282.726947) (xy 346.088976 -282.735049)
			(xy 346.063062 -282.735528) (xy 346.03755 -282.735064) (xy 345.987135 -282.727199) (xy 345.938534 -282.711661)
			(xy 345.892906 -282.688822) (xy 345.85134 -282.659228) (xy 345.81483 -282.623584) (xy 345.799156 -282.603448)
			(xy 345.387168 -282.603448) (xy 345.371526 -282.623609) (xy 345.335009 -282.659249) (xy 345.293436 -282.688839)
			(xy 345.247802 -282.71167) (xy 345.199195 -282.727199) (xy 345.148776 -282.735054) (xy 345.123262 -282.735528)
			(xy 345.097359 -282.734945) (xy 345.046193 -282.726835) (xy 344.996925 -282.710822) (xy 344.950768 -282.687299)
			(xy 344.908859 -282.656846) (xy 344.872229 -282.620212) (xy 344.841781 -282.5783) (xy 344.818263 -282.53214)
			(xy 344.802256 -282.48287) (xy 344.794152 -282.431703) (xy 344.512385 -282.431703) (xy 344.51235 -282.43348)
			(xy 344.503158 -282.487998) (xy 344.494612 -282.514294) (xy 344.486992 -282.536392) (xy 344.692224 -282.891738)
			(xy 344.715084 -282.896056) (xy 344.739902 -282.901236) (xy 344.787678 -282.918192) (xy 344.832294 -282.942264)
			(xy 344.872699 -282.972884) (xy 344.907939 -283.009329) (xy 344.937183 -283.05074) (xy 344.959741 -283.09614)
			(xy 344.975082 -283.14446) (xy 344.982843 -283.194558) (xy 344.983308 -283.219906) (xy 344.9828 -283.245813)
			(xy 344.982682 -283.246555) (xy 345.237552 -283.246555) (xy 345.237552 -283.193257) (xy 345.245495 -283.140553)
			(xy 345.261205 -283.089623) (xy 345.284331 -283.041602) (xy 345.314355 -282.997565) (xy 345.350607 -282.958494)
			(xy 345.392278 -282.925263) (xy 345.438436 -282.898614) (xy 345.48805 -282.879142) (xy 345.540012 -282.867282)
			(xy 345.593162 -282.863299) (xy 345.646312 -282.867282) (xy 345.698274 -282.879142) (xy 345.747888 -282.898614)
			(xy 345.794046 -282.925263) (xy 345.835717 -282.958494) (xy 345.871969 -282.997565) (xy 345.901993 -283.041602)
			(xy 345.925119 -283.089623) (xy 345.940829 -283.140553) (xy 345.948772 -283.193257) (xy 345.94927 -283.219906)
			(xy 345.948772 -283.246555) (xy 346.177352 -283.246555) (xy 346.177352 -283.193257) (xy 346.185295 -283.140553)
			(xy 346.201005 -283.089623) (xy 346.224131 -283.041602) (xy 346.254155 -282.997565) (xy 346.290407 -282.958494)
			(xy 346.332078 -282.925263) (xy 346.378236 -282.898614) (xy 346.42785 -282.879142) (xy 346.479812 -282.867282)
			(xy 346.532962 -282.863299) (xy 346.586112 -282.867282) (xy 346.638074 -282.879142) (xy 346.687688 -282.898614)
			(xy 346.733846 -282.925263) (xy 346.775517 -282.958494) (xy 346.811769 -282.997565) (xy 346.841793 -283.041602)
			(xy 346.864919 -283.089623) (xy 346.880629 -283.140553) (xy 346.888572 -283.193257) (xy 346.88907 -283.219906)
			(xy 347.143324 -283.219906) (xy 347.143831 -283.194562) (xy 347.151603 -283.144472) (xy 347.166948 -283.096161)
			(xy 347.189506 -283.050768) (xy 347.218745 -283.009362) (xy 347.253975 -282.972918) (xy 347.294368 -282.942295)
			(xy 347.338972 -282.918214) (xy 347.386736 -282.901243) (xy 347.411548 -282.896056) (xy 347.434408 -282.891738)
			(xy 347.639386 -282.5369) (xy 347.631766 -282.514802) (xy 347.623129 -282.488391) (xy 347.613803 -282.433617)
			(xy 347.613224 -282.405836) (xy 347.613732 -282.379949) (xy 347.621831 -282.328811) (xy 347.63783 -282.279571)
			(xy 347.661336 -282.233439) (xy 347.691768 -282.191552) (xy 347.728378 -282.154942) (xy 347.770265 -282.12451)
			(xy 347.816397 -282.101004) (xy 347.865637 -282.085005) (xy 347.916775 -282.076906) (xy 347.968549 -282.076906)
			(xy 348.019687 -282.085005) (xy 348.068927 -282.101004) (xy 348.115059 -282.12451) (xy 348.156946 -282.154942)
			(xy 348.193556 -282.191552) (xy 348.223988 -282.233439) (xy 348.247494 -282.279571) (xy 348.263493 -282.328811)
			(xy 348.271592 -282.379949) (xy 348.2721 -282.405836) (xy 348.271608 -282.431158) (xy 348.271403 -282.432485)
			(xy 348.526852 -282.432485) (xy 348.526852 -282.379187) (xy 348.534795 -282.326483) (xy 348.550505 -282.275553)
			(xy 348.573631 -282.227532) (xy 348.603655 -282.183495) (xy 348.639907 -282.144424) (xy 348.681578 -282.111193)
			(xy 348.727736 -282.084544) (xy 348.77735 -282.065072) (xy 348.829312 -282.053212) (xy 348.882462 -282.049229)
			(xy 348.935612 -282.053212) (xy 348.987574 -282.065072) (xy 349.037188 -282.084544) (xy 349.083346 -282.111193)
			(xy 349.125017 -282.144424) (xy 349.161269 -282.183495) (xy 349.191293 -282.227532) (xy 349.214419 -282.275553)
			(xy 349.230129 -282.326483) (xy 349.238072 -282.379187) (xy 349.23857 -282.405836) (xy 349.492824 -282.405836)
			(xy 349.493229 -282.380499) (xy 349.500992 -282.330422) (xy 349.516324 -282.282122) (xy 349.538866 -282.236737)
			(xy 349.568085 -282.195335) (xy 349.603295 -282.15889) (xy 349.643666 -282.128262) (xy 349.688248 -282.10417)
			(xy 349.735991 -282.087183) (xy 349.760794 -282.081986) (xy 349.783654 -282.077668) (xy 349.988886 -281.722322)
			(xy 349.981266 -281.700478) (xy 349.97264 -281.674196) (xy 349.963326 -281.619675) (xy 349.962724 -281.59202)
			(xy 349.963232 -281.566113) (xy 349.971338 -281.514936) (xy 349.98735 -281.465657) (xy 350.010873 -281.41949)
			(xy 350.041329 -281.377571) (xy 350.077967 -281.340933) (xy 350.119886 -281.310477) (xy 350.166053 -281.286954)
			(xy 350.215332 -281.270942) (xy 350.266509 -281.262836) (xy 350.318323 -281.262836) (xy 350.3695 -281.270942)
			(xy 350.418779 -281.286954) (xy 350.464946 -281.310477) (xy 350.506865 -281.340933) (xy 350.543503 -281.377571)
			(xy 350.573959 -281.41949) (xy 350.597482 -281.465657) (xy 350.613494 -281.514936) (xy 350.6216 -281.566113)
			(xy 350.622108 -281.59202) (xy 350.621645 -281.617395) (xy 350.621448 -281.618669) (xy 350.876352 -281.618669)
			(xy 350.876352 -281.565371) (xy 350.884295 -281.512667) (xy 350.900005 -281.461737) (xy 350.923131 -281.413716)
			(xy 350.953155 -281.369679) (xy 350.989407 -281.330608) (xy 351.031078 -281.297377) (xy 351.077236 -281.270728)
			(xy 351.12685 -281.251256) (xy 351.178812 -281.239396) (xy 351.231962 -281.235413) (xy 351.285112 -281.239396)
			(xy 351.337074 -281.251256) (xy 351.386688 -281.270728) (xy 351.432846 -281.297377) (xy 351.474517 -281.330608)
			(xy 351.510769 -281.369679) (xy 351.540793 -281.413716) (xy 351.563919 -281.461737) (xy 351.579629 -281.512667)
			(xy 351.587572 -281.565371) (xy 351.58807 -281.59202) (xy 351.587572 -281.618669) (xy 351.579629 -281.671373)
			(xy 351.563919 -281.722303) (xy 351.540793 -281.770324) (xy 351.510769 -281.814361) (xy 351.474517 -281.853432)
			(xy 351.432846 -281.886663) (xy 351.386688 -281.913312) (xy 351.337074 -281.932784) (xy 351.285112 -281.944644)
			(xy 351.231962 -281.948628) (xy 351.178812 -281.944644) (xy 351.12685 -281.932784) (xy 351.077236 -281.913312)
			(xy 351.031078 -281.886663) (xy 350.989407 -281.853432) (xy 350.953155 -281.814361) (xy 350.923131 -281.770324)
			(xy 350.900005 -281.722303) (xy 350.884295 -281.671373) (xy 350.876352 -281.618669) (xy 350.621448 -281.618669)
			(xy 350.613874 -281.667545) (xy 350.598503 -281.71591) (xy 350.575897 -281.761346) (xy 350.546589 -281.802777)
			(xy 350.511274 -281.839223) (xy 350.470788 -281.869822) (xy 350.426087 -281.893849) (xy 350.37823 -281.910736)
			(xy 350.353376 -281.91587) (xy 350.330516 -281.920188) (xy 350.125538 -282.275026) (xy 350.133412 -282.297124)
			(xy 350.141978 -282.32348) (xy 350.151173 -282.378127) (xy 350.1517 -282.405836) (xy 350.151192 -282.431723)
			(xy 350.151071 -282.432485) (xy 350.406706 -282.432485) (xy 350.406706 -282.379187) (xy 350.414649 -282.326483)
			(xy 350.430359 -282.275553) (xy 350.453485 -282.227532) (xy 350.483509 -282.183495) (xy 350.519761 -282.144424)
			(xy 350.561432 -282.111193) (xy 350.60759 -282.084544) (xy 350.657204 -282.065072) (xy 350.709166 -282.053212)
			(xy 350.762316 -282.049229) (xy 350.815466 -282.053212) (xy 350.867428 -282.065072) (xy 350.917042 -282.084544)
			(xy 350.9632 -282.111193) (xy 351.004871 -282.144424) (xy 351.041123 -282.183495) (xy 351.071147 -282.227532)
			(xy 351.094273 -282.275553) (xy 351.109983 -282.326483) (xy 351.117926 -282.379187) (xy 351.118424 -282.405836)
			(xy 351.117926 -282.432485) (xy 351.109983 -282.485189) (xy 351.094273 -282.536119) (xy 351.071147 -282.58414)
			(xy 351.041123 -282.628177) (xy 351.004871 -282.667248) (xy 350.9632 -282.700479) (xy 350.917042 -282.727128)
			(xy 350.867428 -282.7466) (xy 350.815466 -282.75846) (xy 350.762316 -282.762444) (xy 350.709166 -282.75846)
			(xy 350.657204 -282.7466) (xy 350.60759 -282.727128) (xy 350.561432 -282.700479) (xy 350.519761 -282.667248)
			(xy 350.483509 -282.628177) (xy 350.453485 -282.58414) (xy 350.430359 -282.536119) (xy 350.414649 -282.485189)
			(xy 350.406706 -282.432485) (xy 350.151071 -282.432485) (xy 350.143093 -282.482861) (xy 350.127094 -282.532101)
			(xy 350.103588 -282.578233) (xy 350.073156 -282.62012) (xy 350.036546 -282.65673) (xy 349.994659 -282.687162)
			(xy 349.948527 -282.710668) (xy 349.899287 -282.726667) (xy 349.848149 -282.734766) (xy 349.796375 -282.734766)
			(xy 349.745237 -282.726667) (xy 349.695997 -282.710668) (xy 349.649865 -282.687162) (xy 349.607978 -282.65673)
			(xy 349.571368 -282.62012) (xy 349.540936 -282.578233) (xy 349.51743 -282.532101) (xy 349.501431 -282.482861)
			(xy 349.493332 -282.431723) (xy 349.492824 -282.405836) (xy 349.23857 -282.405836) (xy 349.238072 -282.432485)
			(xy 349.230129 -282.485189) (xy 349.214419 -282.536119) (xy 349.191293 -282.58414) (xy 349.161269 -282.628177)
			(xy 349.125017 -282.667248) (xy 349.083346 -282.700479) (xy 349.037188 -282.727128) (xy 348.987574 -282.7466)
			(xy 348.935612 -282.75846) (xy 348.882462 -282.762444) (xy 348.829312 -282.75846) (xy 348.77735 -282.7466)
			(xy 348.727736 -282.727128) (xy 348.681578 -282.700479) (xy 348.639907 -282.667248) (xy 348.603655 -282.628177)
			(xy 348.573631 -282.58414) (xy 348.550505 -282.536119) (xy 348.534795 -282.485189) (xy 348.526852 -282.432485)
			(xy 348.271403 -282.432485) (xy 348.263872 -282.481209) (xy 348.248573 -282.529487) (xy 348.22607 -282.574858)
			(xy 348.196893 -282.616254) (xy 348.161729 -282.6527) (xy 348.121404 -282.68334) (xy 348.076868 -282.707453)
			(xy 348.029168 -282.72447) (xy 348.004384 -282.729686) (xy 347.981524 -282.734004) (xy 347.776292 -283.089096)
			(xy 347.784166 -283.111194) (xy 347.792802 -283.137539) (xy 347.80212 -283.192188) (xy 347.802708 -283.219906)
			(xy 347.8022 -283.245813) (xy 347.802082 -283.246555) (xy 348.056952 -283.246555) (xy 348.056952 -283.193257)
			(xy 348.064895 -283.140553) (xy 348.080605 -283.089623) (xy 348.103731 -283.041602) (xy 348.133755 -282.997565)
			(xy 348.170007 -282.958494) (xy 348.211678 -282.925263) (xy 348.257836 -282.898614) (xy 348.30745 -282.879142)
			(xy 348.359412 -282.867282) (xy 348.412562 -282.863299) (xy 348.465712 -282.867282) (xy 348.517674 -282.879142)
			(xy 348.567288 -282.898614) (xy 348.613446 -282.925263) (xy 348.655117 -282.958494) (xy 348.691369 -282.997565)
			(xy 348.721393 -283.041602) (xy 348.744519 -283.089623) (xy 348.760229 -283.140553) (xy 348.768172 -283.193257)
			(xy 348.76867 -283.219906) (xy 348.768172 -283.246555) (xy 348.760229 -283.299259) (xy 348.744519 -283.350189)
			(xy 348.721393 -283.39821) (xy 348.691369 -283.442247) (xy 348.655117 -283.481318) (xy 348.613446 -283.514549)
			(xy 348.567288 -283.541198) (xy 348.517674 -283.56067) (xy 348.465712 -283.57253) (xy 348.412562 -283.576514)
			(xy 348.359412 -283.57253) (xy 348.30745 -283.56067) (xy 348.257836 -283.541198) (xy 348.211678 -283.514549)
			(xy 348.170007 -283.481318) (xy 348.133755 -283.442247) (xy 348.103731 -283.39821) (xy 348.080605 -283.350189)
			(xy 348.064895 -283.299259) (xy 348.056952 -283.246555) (xy 347.802082 -283.246555) (xy 347.794094 -283.29699)
			(xy 347.778082 -283.346269) (xy 347.754559 -283.392436) (xy 347.724103 -283.434355) (xy 347.687465 -283.470993)
			(xy 347.645546 -283.501449) (xy 347.599379 -283.524972) (xy 347.5501 -283.540984) (xy 347.498923 -283.54909)
			(xy 347.447109 -283.54909) (xy 347.395932 -283.540984) (xy 347.346653 -283.524972) (xy 347.300486 -283.501449)
			(xy 347.258567 -283.470993) (xy 347.221929 -283.434355) (xy 347.191473 -283.392436) (xy 347.16795 -283.346269)
			(xy 347.151938 -283.29699) (xy 347.143832 -283.245813) (xy 347.143324 -283.219906) (xy 346.88907 -283.219906)
			(xy 346.888572 -283.246555) (xy 346.880629 -283.299259) (xy 346.864919 -283.350189) (xy 346.841793 -283.39821)
			(xy 346.811769 -283.442247) (xy 346.775517 -283.481318) (xy 346.733846 -283.514549) (xy 346.687688 -283.541198)
			(xy 346.638074 -283.56067) (xy 346.586112 -283.57253) (xy 346.532962 -283.576514) (xy 346.479812 -283.57253)
			(xy 346.42785 -283.56067) (xy 346.378236 -283.541198) (xy 346.332078 -283.514549) (xy 346.290407 -283.481318)
			(xy 346.254155 -283.442247) (xy 346.224131 -283.39821) (xy 346.201005 -283.350189) (xy 346.185295 -283.299259)
			(xy 346.177352 -283.246555) (xy 345.948772 -283.246555) (xy 345.940829 -283.299259) (xy 345.925119 -283.350189)
			(xy 345.901993 -283.39821) (xy 345.871969 -283.442247) (xy 345.835717 -283.481318) (xy 345.794046 -283.514549)
			(xy 345.747888 -283.541198) (xy 345.698274 -283.56067) (xy 345.646312 -283.57253) (xy 345.593162 -283.576514)
			(xy 345.540012 -283.57253) (xy 345.48805 -283.56067) (xy 345.438436 -283.541198) (xy 345.392278 -283.514549)
			(xy 345.350607 -283.481318) (xy 345.314355 -283.442247) (xy 345.284331 -283.39821) (xy 345.261205 -283.350189)
			(xy 345.245495 -283.299259) (xy 345.237552 -283.246555) (xy 344.982682 -283.246555) (xy 344.974694 -283.29699)
			(xy 344.958682 -283.346269) (xy 344.935159 -283.392436) (xy 344.904703 -283.434355) (xy 344.868065 -283.470993)
			(xy 344.826146 -283.501449) (xy 344.779979 -283.524972) (xy 344.7307 -283.540984) (xy 344.679523 -283.54909)
			(xy 344.627709 -283.54909) (xy 344.576532 -283.540984) (xy 344.527253 -283.524972) (xy 344.481086 -283.501449)
			(xy 344.439167 -283.470993) (xy 344.402529 -283.434355) (xy 344.372073 -283.392436) (xy 344.34855 -283.346269)
			(xy 344.332538 -283.29699) (xy 344.324432 -283.245813) (xy 344.323924 -283.219906) (xy 344.324518 -283.192189)
			(xy 344.333841 -283.137542) (xy 344.342466 -283.111194) (xy 344.35034 -283.089096) (xy 344.145362 -282.734004)
			(xy 344.122248 -282.729686) (xy 344.097423 -282.724538) (xy 344.049642 -282.707582) (xy 344.005022 -282.683508)
			(xy 343.964615 -282.652886) (xy 343.929374 -282.616436) (xy 343.900131 -282.57502) (xy 343.877575 -282.529614)
			(xy 343.862239 -282.481289) (xy 343.854484 -282.431186) (xy 343.854024 -282.405836) (xy 343.5731 -282.405836)
			(xy 343.572592 -282.431723) (xy 343.564493 -282.482861) (xy 343.548494 -282.532101) (xy 343.524988 -282.578233)
			(xy 343.494556 -282.62012) (xy 343.457946 -282.65673) (xy 343.416059 -282.687162) (xy 343.369927 -282.710668)
			(xy 343.320687 -282.726667) (xy 343.269549 -282.734766) (xy 343.217775 -282.734766) (xy 343.166637 -282.726667)
			(xy 343.117397 -282.710668) (xy 343.071265 -282.687162) (xy 343.029378 -282.65673) (xy 342.992768 -282.62012)
			(xy 342.962336 -282.578233) (xy 342.93883 -282.532101) (xy 342.922831 -282.482861) (xy 342.914732 -282.431723)
			(xy 342.914224 -282.405836) (xy 342.660224 -282.405836) (xy 342.659726 -282.432485) (xy 342.651783 -282.485189)
			(xy 342.636073 -282.536119) (xy 342.612947 -282.58414) (xy 342.582923 -282.628177) (xy 342.546671 -282.667248)
			(xy 342.505 -282.700479) (xy 342.458842 -282.727128) (xy 342.409228 -282.7466) (xy 342.357266 -282.75846)
			(xy 342.304116 -282.762444) (xy 342.250966 -282.75846) (xy 342.199004 -282.7466) (xy 342.14939 -282.727128)
			(xy 342.103232 -282.700479) (xy 342.061561 -282.667248) (xy 342.025309 -282.628177) (xy 341.995285 -282.58414)
			(xy 341.972159 -282.536119) (xy 341.956449 -282.485189) (xy 341.948506 -282.432485) (xy 341.693382 -282.432485)
			(xy 341.685394 -282.48292) (xy 341.669382 -282.532199) (xy 341.645859 -282.578366) (xy 341.615403 -282.620285)
			(xy 341.578765 -282.656923) (xy 341.536846 -282.687379) (xy 341.490679 -282.710902) (xy 341.4414 -282.726914)
			(xy 341.390223 -282.73502) (xy 341.338409 -282.73502) (xy 341.287232 -282.726914) (xy 341.237953 -282.710902)
			(xy 341.191786 -282.687379) (xy 341.149867 -282.656923) (xy 341.113229 -282.620285) (xy 341.082773 -282.578366)
			(xy 341.05925 -282.532199) (xy 341.043238 -282.48292) (xy 341.035132 -282.431743) (xy 341.034624 -282.405836)
			(xy 340.780624 -282.405836) (xy 340.780126 -282.432485) (xy 340.772183 -282.485189) (xy 340.756473 -282.536119)
			(xy 340.733347 -282.58414) (xy 340.703323 -282.628177) (xy 340.667071 -282.667248) (xy 340.6254 -282.700479)
			(xy 340.579242 -282.727128) (xy 340.529628 -282.7466) (xy 340.477666 -282.75846) (xy 340.424516 -282.762444)
			(xy 340.371366 -282.75846) (xy 340.319404 -282.7466) (xy 340.26979 -282.727128) (xy 340.223632 -282.700479)
			(xy 340.181961 -282.667248) (xy 340.145709 -282.628177) (xy 340.115685 -282.58414) (xy 340.092559 -282.536119)
			(xy 340.076849 -282.485189) (xy 340.068906 -282.432485) (xy 339.813799 -282.432485) (xy 339.806243 -282.481337)
			(xy 339.790893 -282.52969) (xy 339.768309 -282.575118) (xy 339.739027 -282.616545) (xy 339.703739 -282.652993)
			(xy 339.663279 -282.683598) (xy 339.618605 -282.707637) (xy 339.570773 -282.724541) (xy 339.54593 -282.729686)
			(xy 339.52307 -282.734004) (xy 339.318092 -283.089096) (xy 339.325712 -283.11094) (xy 339.33426 -283.137236)
			(xy 339.343458 -283.191753) (xy 339.344 -283.219398) (xy 339.344 -283.219906) (xy 339.343492 -283.245793)
			(xy 339.343371 -283.246555) (xy 339.598752 -283.246555) (xy 339.598752 -283.193257) (xy 339.606695 -283.140553)
			(xy 339.622405 -283.089623) (xy 339.645531 -283.041602) (xy 339.675555 -282.997565) (xy 339.711807 -282.958494)
			(xy 339.753478 -282.925263) (xy 339.799636 -282.898614) (xy 339.84925 -282.879142) (xy 339.901212 -282.867282)
			(xy 339.954362 -282.863299) (xy 340.007512 -282.867282) (xy 340.059474 -282.879142) (xy 340.109088 -282.898614)
			(xy 340.155246 -282.925263) (xy 340.196917 -282.958494) (xy 340.233169 -282.997565) (xy 340.263193 -283.041602)
			(xy 340.286319 -283.089623) (xy 340.302029 -283.140553) (xy 340.309972 -283.193257) (xy 340.31047 -283.219906)
			(xy 340.309986 -283.245785) (xy 340.565275 -283.245785) (xy 340.565275 -283.194015) (xy 340.573373 -283.142882)
			(xy 340.58937 -283.093646) (xy 340.612872 -283.047517) (xy 340.643299 -283.005633) (xy 340.679904 -282.969024)
			(xy 340.721785 -282.938592) (xy 340.76791 -282.915085) (xy 340.817145 -282.899082) (xy 340.868277 -282.890978)
			(xy 340.894162 -282.890468) (xy 340.919672 -282.890989) (xy 340.970084 -282.898843) (xy 341.018684 -282.914369)
			(xy 341.064312 -282.937197) (xy 341.105879 -282.966782) (xy 341.142392 -283.002417) (xy 341.158068 -283.022548)
			(xy 341.570056 -283.022548) (xy 341.585741 -283.002422) (xy 341.62225 -282.96678) (xy 341.663813 -282.937187)
			(xy 341.709439 -282.91435) (xy 341.758039 -282.898813) (xy 341.808451 -282.890948) (xy 341.833962 -282.890468)
			(xy 341.859854 -282.890934) (xy 341.911001 -282.89903) (xy 341.960252 -282.915027) (xy 342.006393 -282.938533)
			(xy 342.048289 -282.968968) (xy 342.084908 -283.005582) (xy 342.115347 -283.047475) (xy 342.138858 -283.093613)
			(xy 342.154861 -283.142862) (xy 342.162963 -283.194008) (xy 342.162963 -283.245792) (xy 342.162842 -283.246555)
			(xy 342.418152 -283.246555) (xy 342.418152 -283.193257) (xy 342.426095 -283.140553) (xy 342.441805 -283.089623)
			(xy 342.464931 -283.041602) (xy 342.494955 -282.997565) (xy 342.531207 -282.958494) (xy 342.572878 -282.925263)
			(xy 342.619036 -282.898614) (xy 342.66865 -282.879142) (xy 342.720612 -282.867282) (xy 342.773762 -282.863299)
			(xy 342.826912 -282.867282) (xy 342.878874 -282.879142) (xy 342.928488 -282.898614) (xy 342.974646 -282.925263)
			(xy 343.016317 -282.958494) (xy 343.052569 -282.997565) (xy 343.082593 -283.041602) (xy 343.105719 -283.089623)
			(xy 343.121429 -283.140553) (xy 343.129372 -283.193257) (xy 343.12987 -283.219906) (xy 343.129372 -283.246555)
			(xy 343.357952 -283.246555) (xy 343.357952 -283.193257) (xy 343.365895 -283.140553) (xy 343.381605 -283.089623)
			(xy 343.404731 -283.041602) (xy 343.434755 -282.997565) (xy 343.471007 -282.958494) (xy 343.512678 -282.925263)
			(xy 343.558836 -282.898614) (xy 343.60845 -282.879142) (xy 343.660412 -282.867282) (xy 343.713562 -282.863299)
			(xy 343.766712 -282.867282) (xy 343.818674 -282.879142) (xy 343.868288 -282.898614) (xy 343.914446 -282.925263)
			(xy 343.956117 -282.958494) (xy 343.992369 -282.997565) (xy 344.022393 -283.041602) (xy 344.045519 -283.089623)
			(xy 344.061229 -283.140553) (xy 344.069172 -283.193257) (xy 344.06967 -283.219906) (xy 344.069172 -283.246555)
			(xy 344.061229 -283.299259) (xy 344.045519 -283.350189) (xy 344.022393 -283.39821) (xy 343.992369 -283.442247)
			(xy 343.956117 -283.481318) (xy 343.914446 -283.514549) (xy 343.868288 -283.541198) (xy 343.818674 -283.56067)
			(xy 343.766712 -283.57253) (xy 343.713562 -283.576514) (xy 343.660412 -283.57253) (xy 343.60845 -283.56067)
			(xy 343.558836 -283.541198) (xy 343.512678 -283.514549) (xy 343.471007 -283.481318) (xy 343.434755 -283.442247)
			(xy 343.404731 -283.39821) (xy 343.381605 -283.350189) (xy 343.365895 -283.299259) (xy 343.357952 -283.246555)
			(xy 343.129372 -283.246555) (xy 343.121429 -283.299259) (xy 343.105719 -283.350189) (xy 343.082593 -283.39821)
			(xy 343.052569 -283.442247) (xy 343.016317 -283.481318) (xy 342.974646 -283.514549) (xy 342.928488 -283.541198)
			(xy 342.878874 -283.56067) (xy 342.826912 -283.57253) (xy 342.773762 -283.576514) (xy 342.720612 -283.57253)
			(xy 342.66865 -283.56067) (xy 342.619036 -283.541198) (xy 342.572878 -283.514549) (xy 342.531207 -283.481318)
			(xy 342.494955 -283.442247) (xy 342.464931 -283.39821) (xy 342.441805 -283.350189) (xy 342.426095 -283.299259)
			(xy 342.418152 -283.246555) (xy 342.162842 -283.246555) (xy 342.154861 -283.296938) (xy 342.138858 -283.346187)
			(xy 342.115347 -283.392325) (xy 342.084908 -283.434218) (xy 342.048289 -283.470832) (xy 342.006393 -283.501267)
			(xy 341.960252 -283.524773) (xy 341.911001 -283.54077) (xy 341.859854 -283.548866) (xy 341.833962 -283.549344)
			(xy 341.808448 -283.548913) (xy 341.75803 -283.541045) (xy 341.709427 -283.525503) (xy 341.663798 -283.502658)
			(xy 341.622234 -283.473056) (xy 341.585727 -283.437404) (xy 341.570056 -283.417264) (xy 341.158068 -283.417264)
			(xy 341.142404 -283.437407) (xy 341.105893 -283.473052) (xy 341.064326 -283.502646) (xy 341.018696 -283.525481)
			(xy 340.970092 -283.541013) (xy 340.919675 -283.548869) (xy 340.894162 -283.549344) (xy 340.868277 -283.548822)
			(xy 340.817145 -283.540718) (xy 340.76791 -283.524715) (xy 340.721785 -283.501208) (xy 340.679904 -283.470776)
			(xy 340.643299 -283.434167) (xy 340.612872 -283.392283) (xy 340.58937 -283.346154) (xy 340.573373 -283.296918)
			(xy 340.565275 -283.245785) (xy 340.309986 -283.245785) (xy 340.309972 -283.246555) (xy 340.302029 -283.299259)
			(xy 340.286319 -283.350189) (xy 340.263193 -283.39821) (xy 340.233169 -283.442247) (xy 340.196917 -283.481318)
			(xy 340.155246 -283.514549) (xy 340.109088 -283.541198) (xy 340.059474 -283.56067) (xy 340.007512 -283.57253)
			(xy 339.954362 -283.576514) (xy 339.901212 -283.57253) (xy 339.84925 -283.56067) (xy 339.799636 -283.541198)
			(xy 339.753478 -283.514549) (xy 339.711807 -283.481318) (xy 339.675555 -283.442247) (xy 339.645531 -283.39821)
			(xy 339.622405 -283.350189) (xy 339.606695 -283.299259) (xy 339.598752 -283.246555) (xy 339.343371 -283.246555)
			(xy 339.335393 -283.296931) (xy 339.319394 -283.346171) (xy 339.295888 -283.392303) (xy 339.265456 -283.43419)
			(xy 339.228846 -283.4708) (xy 339.186959 -283.501232) (xy 339.140827 -283.524738) (xy 339.091587 -283.540737)
			(xy 339.040449 -283.548836) (xy 338.988675 -283.548836) (xy 338.937537 -283.540737) (xy 338.888297 -283.524738)
			(xy 338.842165 -283.501232) (xy 338.800278 -283.4708) (xy 338.763668 -283.43419) (xy 338.733236 -283.392303)
			(xy 338.70973 -283.346171) (xy 338.693731 -283.296931) (xy 338.685632 -283.245793) (xy 338.685124 -283.219906)
			(xy 338.43087 -283.219906) (xy 338.430372 -283.246555) (xy 338.422429 -283.299259) (xy 338.406719 -283.350189)
			(xy 338.383593 -283.39821) (xy 338.353569 -283.442247) (xy 338.317317 -283.481318) (xy 338.275646 -283.514549)
			(xy 338.229488 -283.541198) (xy 338.179874 -283.56067) (xy 338.127912 -283.57253) (xy 338.074762 -283.576514)
			(xy 338.021612 -283.57253) (xy 337.96965 -283.56067) (xy 337.920036 -283.541198) (xy 337.873878 -283.514549)
			(xy 337.832207 -283.481318) (xy 337.795955 -283.442247) (xy 337.765931 -283.39821) (xy 337.742805 -283.350189)
			(xy 337.727095 -283.299259) (xy 337.719152 -283.246555) (xy 337.490572 -283.246555) (xy 337.482629 -283.299259)
			(xy 337.466919 -283.350189) (xy 337.443793 -283.39821) (xy 337.413769 -283.442247) (xy 337.377517 -283.481318)
			(xy 337.335846 -283.514549) (xy 337.289688 -283.541198) (xy 337.240074 -283.56067) (xy 337.188112 -283.57253)
			(xy 337.134962 -283.576514) (xy 337.081812 -283.57253) (xy 337.02985 -283.56067) (xy 336.980236 -283.541198)
			(xy 336.934078 -283.514549) (xy 336.892407 -283.481318) (xy 336.856155 -283.442247) (xy 336.826131 -283.39821)
			(xy 336.803005 -283.350189) (xy 336.787295 -283.299259) (xy 336.779352 -283.246555) (xy 336.523971 -283.246555)
			(xy 336.515993 -283.296931) (xy 336.499994 -283.346171) (xy 336.476488 -283.392303) (xy 336.446056 -283.43419)
			(xy 336.409446 -283.4708) (xy 336.367559 -283.501232) (xy 336.321427 -283.524738) (xy 336.272187 -283.540737)
			(xy 336.221049 -283.548836) (xy 336.169275 -283.548836) (xy 336.118137 -283.540737) (xy 336.068897 -283.524738)
			(xy 336.022765 -283.501232) (xy 335.980878 -283.4708) (xy 335.944268 -283.43419) (xy 335.913836 -283.392303)
			(xy 335.89033 -283.346171) (xy 335.874331 -283.296931) (xy 335.866232 -283.245793) (xy 335.865724 -283.219906)
			(xy 335.866254 -283.192198) (xy 335.875449 -283.137551) (xy 335.884012 -283.111194) (xy 335.891886 -283.089096)
			(xy 335.686654 -282.734004) (xy 335.663794 -282.729686) (xy 335.639001 -282.724454) (xy 335.591266 -282.707468)
			(xy 335.546691 -282.683379) (xy 335.506327 -282.652753) (xy 335.471124 -282.616312) (xy 335.441911 -282.574914)
			(xy 335.419375 -282.529534) (xy 335.404048 -282.48124) (xy 335.396291 -282.43117) (xy 335.395824 -282.405836)
			(xy 335.115408 -282.405836) (xy 335.1149 -282.431743) (xy 335.106794 -282.48292) (xy 335.090782 -282.532199)
			(xy 335.067259 -282.578366) (xy 335.036803 -282.620285) (xy 335.000165 -282.656923) (xy 334.958246 -282.687379)
			(xy 334.912079 -282.710902) (xy 334.8628 -282.726914) (xy 334.811623 -282.73502) (xy 334.759809 -282.73502)
			(xy 334.708632 -282.726914) (xy 334.659353 -282.710902) (xy 334.613186 -282.687379) (xy 334.571267 -282.656923)
			(xy 334.534629 -282.620285) (xy 334.504173 -282.578366) (xy 334.48065 -282.532199) (xy 334.464638 -282.48292)
			(xy 334.456532 -282.431743) (xy 334.456024 -282.405836) (xy 334.20177 -282.405836) (xy 334.201272 -282.432485)
			(xy 334.193329 -282.485189) (xy 334.177619 -282.536119) (xy 334.154493 -282.58414) (xy 334.124469 -282.628177)
			(xy 334.088217 -282.667248) (xy 334.046546 -282.700479) (xy 334.000388 -282.727128) (xy 333.950774 -282.7466)
			(xy 333.898812 -282.75846) (xy 333.845662 -282.762444) (xy 333.792512 -282.75846) (xy 333.74055 -282.7466)
			(xy 333.690936 -282.727128) (xy 333.644778 -282.700479) (xy 333.603107 -282.667248) (xy 333.566855 -282.628177)
			(xy 333.536831 -282.58414) (xy 333.513705 -282.536119) (xy 333.497995 -282.485189) (xy 333.490052 -282.432485)
			(xy 331.903324 -282.432485) (xy 331.903324 -283.246555) (xy 333.020152 -283.246555) (xy 333.020152 -283.193257)
			(xy 333.028095 -283.140553) (xy 333.043805 -283.089623) (xy 333.066931 -283.041602) (xy 333.096955 -282.997565)
			(xy 333.133207 -282.958494) (xy 333.174878 -282.925263) (xy 333.221036 -282.898614) (xy 333.27065 -282.879142)
			(xy 333.322612 -282.867282) (xy 333.375762 -282.863299) (xy 333.428912 -282.867282) (xy 333.480874 -282.879142)
			(xy 333.530488 -282.898614) (xy 333.576646 -282.925263) (xy 333.618317 -282.958494) (xy 333.654569 -282.997565)
			(xy 333.684593 -283.041602) (xy 333.707719 -283.089623) (xy 333.723429 -283.140553) (xy 333.731372 -283.193257)
			(xy 333.73187 -283.219906) (xy 333.731372 -283.246555) (xy 333.959952 -283.246555) (xy 333.959952 -283.193257)
			(xy 333.967895 -283.140553) (xy 333.983605 -283.089623) (xy 334.006731 -283.041602) (xy 334.036755 -282.997565)
			(xy 334.073007 -282.958494) (xy 334.114678 -282.925263) (xy 334.160836 -282.898614) (xy 334.21045 -282.879142)
			(xy 334.262412 -282.867282) (xy 334.315562 -282.863299) (xy 334.368712 -282.867282) (xy 334.420674 -282.879142)
			(xy 334.470288 -282.898614) (xy 334.516446 -282.925263) (xy 334.558117 -282.958494) (xy 334.594369 -282.997565)
			(xy 334.624393 -283.041602) (xy 334.647519 -283.089623) (xy 334.663229 -283.140553) (xy 334.671172 -283.193257)
			(xy 334.67167 -283.219906) (xy 334.671172 -283.246555) (xy 334.899752 -283.246555) (xy 334.899752 -283.193257)
			(xy 334.907695 -283.140553) (xy 334.923405 -283.089623) (xy 334.946531 -283.041602) (xy 334.976555 -282.997565)
			(xy 335.012807 -282.958494) (xy 335.054478 -282.925263) (xy 335.100636 -282.898614) (xy 335.15025 -282.879142)
			(xy 335.202212 -282.867282) (xy 335.255362 -282.863299) (xy 335.308512 -282.867282) (xy 335.360474 -282.879142)
			(xy 335.410088 -282.898614) (xy 335.456246 -282.925263) (xy 335.497917 -282.958494) (xy 335.534169 -282.997565)
			(xy 335.564193 -283.041602) (xy 335.587319 -283.089623) (xy 335.603029 -283.140553) (xy 335.610972 -283.193257)
			(xy 335.61147 -283.219906) (xy 335.610972 -283.246555) (xy 335.603029 -283.299259) (xy 335.587319 -283.350189)
			(xy 335.564193 -283.39821) (xy 335.534169 -283.442247) (xy 335.497917 -283.481318) (xy 335.456246 -283.514549)
			(xy 335.410088 -283.541198) (xy 335.360474 -283.56067) (xy 335.308512 -283.57253) (xy 335.255362 -283.576514)
			(xy 335.202212 -283.57253) (xy 335.15025 -283.56067) (xy 335.100636 -283.541198) (xy 335.054478 -283.514549)
			(xy 335.012807 -283.481318) (xy 334.976555 -283.442247) (xy 334.946531 -283.39821) (xy 334.923405 -283.350189)
			(xy 334.907695 -283.299259) (xy 334.899752 -283.246555) (xy 334.671172 -283.246555) (xy 334.663229 -283.299259)
			(xy 334.647519 -283.350189) (xy 334.624393 -283.39821) (xy 334.594369 -283.442247) (xy 334.558117 -283.481318)
			(xy 334.516446 -283.514549) (xy 334.470288 -283.541198) (xy 334.420674 -283.56067) (xy 334.368712 -283.57253)
			(xy 334.315562 -283.576514) (xy 334.262412 -283.57253) (xy 334.21045 -283.56067) (xy 334.160836 -283.541198)
			(xy 334.114678 -283.514549) (xy 334.073007 -283.481318) (xy 334.036755 -283.442247) (xy 334.006731 -283.39821)
			(xy 333.983605 -283.350189) (xy 333.967895 -283.299259) (xy 333.959952 -283.246555) (xy 333.731372 -283.246555)
			(xy 333.723429 -283.299259) (xy 333.707719 -283.350189) (xy 333.684593 -283.39821) (xy 333.654569 -283.442247)
			(xy 333.618317 -283.481318) (xy 333.576646 -283.514549) (xy 333.530488 -283.541198) (xy 333.480874 -283.56067)
			(xy 333.428912 -283.57253) (xy 333.375762 -283.576514) (xy 333.322612 -283.57253) (xy 333.27065 -283.56067)
			(xy 333.221036 -283.541198) (xy 333.174878 -283.514549) (xy 333.133207 -283.481318) (xy 333.096955 -283.442247)
			(xy 333.066931 -283.39821) (xy 333.043805 -283.350189) (xy 333.028095 -283.299259) (xy 333.020152 -283.246555)
			(xy 331.903324 -283.246555) (xy 331.903324 -284.033722) (xy 334.456024 -284.033722) (xy 334.456532 -284.007815)
			(xy 334.464638 -283.956638) (xy 334.48065 -283.907359) (xy 334.504173 -283.861192) (xy 334.534629 -283.819273)
			(xy 334.571267 -283.782635) (xy 334.613186 -283.752179) (xy 334.659353 -283.728656) (xy 334.708632 -283.712644)
			(xy 334.759809 -283.704538) (xy 334.811623 -283.704538) (xy 334.8628 -283.712644) (xy 334.912079 -283.728656)
			(xy 334.958246 -283.752179) (xy 335.000165 -283.782635) (xy 335.036803 -283.819273) (xy 335.067259 -283.861192)
			(xy 335.090782 -283.907359) (xy 335.106794 -283.956638) (xy 335.1149 -284.007815) (xy 335.115408 -284.033722)
			(xy 335.114842 -284.060371) (xy 335.369652 -284.060371) (xy 335.369652 -284.007073) (xy 335.377595 -283.954369)
			(xy 335.393305 -283.903439) (xy 335.416431 -283.855418) (xy 335.446455 -283.811381) (xy 335.482707 -283.77231)
			(xy 335.524378 -283.739079) (xy 335.570536 -283.71243) (xy 335.62015 -283.692958) (xy 335.672112 -283.681098)
			(xy 335.725262 -283.677115) (xy 335.778412 -283.681098) (xy 335.830374 -283.692958) (xy 335.879988 -283.71243)
			(xy 335.926146 -283.739079) (xy 335.967817 -283.77231) (xy 336.004069 -283.811381) (xy 336.034093 -283.855418)
			(xy 336.057219 -283.903439) (xy 336.072929 -283.954369) (xy 336.080872 -284.007073) (xy 336.08137 -284.033722)
			(xy 336.080872 -284.060371) (xy 336.309706 -284.060371) (xy 336.309706 -284.007073) (xy 336.317649 -283.954369)
			(xy 336.333359 -283.903439) (xy 336.356485 -283.855418) (xy 336.386509 -283.811381) (xy 336.422761 -283.77231)
			(xy 336.464432 -283.739079) (xy 336.51059 -283.71243) (xy 336.560204 -283.692958) (xy 336.612166 -283.681098)
			(xy 336.665316 -283.677115) (xy 336.718466 -283.681098) (xy 336.770428 -283.692958) (xy 336.820042 -283.71243)
			(xy 336.8662 -283.739079) (xy 336.907871 -283.77231) (xy 336.944123 -283.811381) (xy 336.974147 -283.855418)
			(xy 336.997273 -283.903439) (xy 337.012983 -283.954369) (xy 337.020926 -284.007073) (xy 337.021424 -284.033722)
			(xy 337.020926 -284.060371) (xy 338.189052 -284.060371) (xy 338.189052 -284.007073) (xy 338.196995 -283.954369)
			(xy 338.212705 -283.903439) (xy 338.235831 -283.855418) (xy 338.265855 -283.811381) (xy 338.302107 -283.77231)
			(xy 338.343778 -283.739079) (xy 338.389936 -283.71243) (xy 338.43955 -283.692958) (xy 338.491512 -283.681098)
			(xy 338.544662 -283.677115) (xy 338.597812 -283.681098) (xy 338.649774 -283.692958) (xy 338.699388 -283.71243)
			(xy 338.745546 -283.739079) (xy 338.787217 -283.77231) (xy 338.823469 -283.811381) (xy 338.853493 -283.855418)
			(xy 338.876619 -283.903439) (xy 338.892329 -283.954369) (xy 338.900272 -284.007073) (xy 338.90077 -284.033722)
			(xy 338.900272 -284.060371) (xy 339.128852 -284.060371) (xy 339.128852 -284.007073) (xy 339.136795 -283.954369)
			(xy 339.152505 -283.903439) (xy 339.175631 -283.855418) (xy 339.205655 -283.811381) (xy 339.241907 -283.77231)
			(xy 339.283578 -283.739079) (xy 339.329736 -283.71243) (xy 339.37935 -283.692958) (xy 339.431312 -283.681098)
			(xy 339.484462 -283.677115) (xy 339.537612 -283.681098) (xy 339.589574 -283.692958) (xy 339.639188 -283.71243)
			(xy 339.685346 -283.739079) (xy 339.727017 -283.77231) (xy 339.763269 -283.811381) (xy 339.793293 -283.855418)
			(xy 339.816419 -283.903439) (xy 339.832129 -283.954369) (xy 339.840072 -284.007073) (xy 339.84057 -284.033722)
			(xy 339.840072 -284.060371) (xy 340.068652 -284.060371) (xy 340.068652 -284.007073) (xy 340.076595 -283.954369)
			(xy 340.092305 -283.903439) (xy 340.115431 -283.855418) (xy 340.145455 -283.811381) (xy 340.181707 -283.77231)
			(xy 340.223378 -283.739079) (xy 340.269536 -283.71243) (xy 340.31915 -283.692958) (xy 340.371112 -283.681098)
			(xy 340.424262 -283.677115) (xy 340.477412 -283.681098) (xy 340.529374 -283.692958) (xy 340.578988 -283.71243)
			(xy 340.625146 -283.739079) (xy 340.666817 -283.77231) (xy 340.703069 -283.811381) (xy 340.733093 -283.855418)
			(xy 340.756219 -283.903439) (xy 340.771929 -283.954369) (xy 340.779872 -284.007073) (xy 340.78037 -284.033722)
			(xy 340.779872 -284.060371) (xy 341.008452 -284.060371) (xy 341.008452 -284.007073) (xy 341.016395 -283.954369)
			(xy 341.032105 -283.903439) (xy 341.055231 -283.855418) (xy 341.085255 -283.811381) (xy 341.121507 -283.77231)
			(xy 341.163178 -283.739079) (xy 341.209336 -283.71243) (xy 341.25895 -283.692958) (xy 341.310912 -283.681098)
			(xy 341.364062 -283.677115) (xy 341.417212 -283.681098) (xy 341.469174 -283.692958) (xy 341.518788 -283.71243)
			(xy 341.564946 -283.739079) (xy 341.606617 -283.77231) (xy 341.642869 -283.811381) (xy 341.672893 -283.855418)
			(xy 341.696019 -283.903439) (xy 341.711729 -283.954369) (xy 341.719672 -284.007073) (xy 341.72017 -284.033722)
			(xy 341.719672 -284.060371) (xy 341.948252 -284.060371) (xy 341.948252 -284.007073) (xy 341.956195 -283.954369)
			(xy 341.971905 -283.903439) (xy 341.995031 -283.855418) (xy 342.025055 -283.811381) (xy 342.061307 -283.77231)
			(xy 342.102978 -283.739079) (xy 342.149136 -283.71243) (xy 342.19875 -283.692958) (xy 342.250712 -283.681098)
			(xy 342.303862 -283.677115) (xy 342.357012 -283.681098) (xy 342.408974 -283.692958) (xy 342.458588 -283.71243)
			(xy 342.504746 -283.739079) (xy 342.546417 -283.77231) (xy 342.582669 -283.811381) (xy 342.612693 -283.855418)
			(xy 342.635819 -283.903439) (xy 342.651529 -283.954369) (xy 342.659472 -284.007073) (xy 342.65997 -284.033722)
			(xy 342.659472 -284.060371) (xy 342.888052 -284.060371) (xy 342.888052 -284.007073) (xy 342.895995 -283.954369)
			(xy 342.911705 -283.903439) (xy 342.934831 -283.855418) (xy 342.964855 -283.811381) (xy 343.001107 -283.77231)
			(xy 343.042778 -283.739079) (xy 343.088936 -283.71243) (xy 343.13855 -283.692958) (xy 343.190512 -283.681098)
			(xy 343.243662 -283.677115) (xy 343.296812 -283.681098) (xy 343.348774 -283.692958) (xy 343.398388 -283.71243)
			(xy 343.444546 -283.739079) (xy 343.486217 -283.77231) (xy 343.522469 -283.811381) (xy 343.552493 -283.855418)
			(xy 343.575619 -283.903439) (xy 343.591329 -283.954369) (xy 343.599272 -284.007073) (xy 343.59977 -284.033722)
			(xy 343.599272 -284.060371) (xy 343.827852 -284.060371) (xy 343.827852 -284.007073) (xy 343.835795 -283.954369)
			(xy 343.851505 -283.903439) (xy 343.874631 -283.855418) (xy 343.904655 -283.811381) (xy 343.940907 -283.77231)
			(xy 343.982578 -283.739079) (xy 344.028736 -283.71243) (xy 344.07835 -283.692958) (xy 344.130312 -283.681098)
			(xy 344.183462 -283.677115) (xy 344.236612 -283.681098) (xy 344.288574 -283.692958) (xy 344.338188 -283.71243)
			(xy 344.384346 -283.739079) (xy 344.426017 -283.77231) (xy 344.462269 -283.811381) (xy 344.492293 -283.855418)
			(xy 344.515419 -283.903439) (xy 344.531129 -283.954369) (xy 344.539072 -284.007073) (xy 344.53957 -284.033722)
			(xy 344.539072 -284.060371) (xy 344.767652 -284.060371) (xy 344.767652 -284.007073) (xy 344.775595 -283.954369)
			(xy 344.791305 -283.903439) (xy 344.814431 -283.855418) (xy 344.844455 -283.811381) (xy 344.880707 -283.77231)
			(xy 344.922378 -283.739079) (xy 344.968536 -283.71243) (xy 345.01815 -283.692958) (xy 345.070112 -283.681098)
			(xy 345.123262 -283.677115) (xy 345.176412 -283.681098) (xy 345.228374 -283.692958) (xy 345.277988 -283.71243)
			(xy 345.324146 -283.739079) (xy 345.365817 -283.77231) (xy 345.402069 -283.811381) (xy 345.432093 -283.855418)
			(xy 345.455219 -283.903439) (xy 345.470929 -283.954369) (xy 345.478872 -284.007073) (xy 345.47937 -284.033722)
			(xy 345.478872 -284.060371) (xy 345.707452 -284.060371) (xy 345.707452 -284.007073) (xy 345.715395 -283.954369)
			(xy 345.731105 -283.903439) (xy 345.754231 -283.855418) (xy 345.784255 -283.811381) (xy 345.820507 -283.77231)
			(xy 345.862178 -283.739079) (xy 345.908336 -283.71243) (xy 345.95795 -283.692958) (xy 346.009912 -283.681098)
			(xy 346.063062 -283.677115) (xy 346.116212 -283.681098) (xy 346.168174 -283.692958) (xy 346.217788 -283.71243)
			(xy 346.263946 -283.739079) (xy 346.305617 -283.77231) (xy 346.341869 -283.811381) (xy 346.371893 -283.855418)
			(xy 346.395019 -283.903439) (xy 346.410729 -283.954369) (xy 346.418672 -284.007073) (xy 346.41917 -284.033722)
			(xy 346.418672 -284.060371) (xy 346.647252 -284.060371) (xy 346.647252 -284.007073) (xy 346.655195 -283.954369)
			(xy 346.670905 -283.903439) (xy 346.694031 -283.855418) (xy 346.724055 -283.811381) (xy 346.760307 -283.77231)
			(xy 346.801978 -283.739079) (xy 346.848136 -283.71243) (xy 346.89775 -283.692958) (xy 346.949712 -283.681098)
			(xy 347.002862 -283.677115) (xy 347.056012 -283.681098) (xy 347.107974 -283.692958) (xy 347.157588 -283.71243)
			(xy 347.203746 -283.739079) (xy 347.245417 -283.77231) (xy 347.281669 -283.811381) (xy 347.311693 -283.855418)
			(xy 347.334819 -283.903439) (xy 347.350529 -283.954369) (xy 347.358472 -284.007073) (xy 347.35897 -284.033722)
			(xy 347.358472 -284.060371) (xy 347.587052 -284.060371) (xy 347.587052 -284.007073) (xy 347.594995 -283.954369)
			(xy 347.610705 -283.903439) (xy 347.633831 -283.855418) (xy 347.663855 -283.811381) (xy 347.700107 -283.77231)
			(xy 347.741778 -283.739079) (xy 347.787936 -283.71243) (xy 347.83755 -283.692958) (xy 347.889512 -283.681098)
			(xy 347.942662 -283.677115) (xy 347.995812 -283.681098) (xy 348.047774 -283.692958) (xy 348.097388 -283.71243)
			(xy 348.143546 -283.739079) (xy 348.185217 -283.77231) (xy 348.221469 -283.811381) (xy 348.251493 -283.855418)
			(xy 348.274619 -283.903439) (xy 348.290329 -283.954369) (xy 348.298272 -284.007073) (xy 348.29877 -284.033722)
			(xy 348.298272 -284.060371) (xy 348.290329 -284.113075) (xy 348.274619 -284.164005) (xy 348.251493 -284.212026)
			(xy 348.221469 -284.256063) (xy 348.185217 -284.295134) (xy 348.143546 -284.328365) (xy 348.097388 -284.355014)
			(xy 348.047774 -284.374486) (xy 347.995812 -284.386346) (xy 347.942662 -284.39033) (xy 347.889512 -284.386346)
			(xy 347.83755 -284.374486) (xy 347.787936 -284.355014) (xy 347.741778 -284.328365) (xy 347.700107 -284.295134)
			(xy 347.663855 -284.256063) (xy 347.633831 -284.212026) (xy 347.610705 -284.164005) (xy 347.594995 -284.113075)
			(xy 347.587052 -284.060371) (xy 347.358472 -284.060371) (xy 347.350529 -284.113075) (xy 347.334819 -284.164005)
			(xy 347.311693 -284.212026) (xy 347.281669 -284.256063) (xy 347.245417 -284.295134) (xy 347.203746 -284.328365)
			(xy 347.157588 -284.355014) (xy 347.107974 -284.374486) (xy 347.056012 -284.386346) (xy 347.002862 -284.39033)
			(xy 346.949712 -284.386346) (xy 346.89775 -284.374486) (xy 346.848136 -284.355014) (xy 346.801978 -284.328365)
			(xy 346.760307 -284.295134) (xy 346.724055 -284.256063) (xy 346.694031 -284.212026) (xy 346.670905 -284.164005)
			(xy 346.655195 -284.113075) (xy 346.647252 -284.060371) (xy 346.418672 -284.060371) (xy 346.410729 -284.113075)
			(xy 346.395019 -284.164005) (xy 346.371893 -284.212026) (xy 346.341869 -284.256063) (xy 346.305617 -284.295134)
			(xy 346.263946 -284.328365) (xy 346.217788 -284.355014) (xy 346.168174 -284.374486) (xy 346.116212 -284.386346)
			(xy 346.063062 -284.39033) (xy 346.009912 -284.386346) (xy 345.95795 -284.374486) (xy 345.908336 -284.355014)
			(xy 345.862178 -284.328365) (xy 345.820507 -284.295134) (xy 345.784255 -284.256063) (xy 345.754231 -284.212026)
			(xy 345.731105 -284.164005) (xy 345.715395 -284.113075) (xy 345.707452 -284.060371) (xy 345.478872 -284.060371)
			(xy 345.470929 -284.113075) (xy 345.455219 -284.164005) (xy 345.432093 -284.212026) (xy 345.402069 -284.256063)
			(xy 345.365817 -284.295134) (xy 345.324146 -284.328365) (xy 345.277988 -284.355014) (xy 345.228374 -284.374486)
			(xy 345.176412 -284.386346) (xy 345.123262 -284.39033) (xy 345.070112 -284.386346) (xy 345.01815 -284.374486)
			(xy 344.968536 -284.355014) (xy 344.922378 -284.328365) (xy 344.880707 -284.295134) (xy 344.844455 -284.256063)
			(xy 344.814431 -284.212026) (xy 344.791305 -284.164005) (xy 344.775595 -284.113075) (xy 344.767652 -284.060371)
			(xy 344.539072 -284.060371) (xy 344.531129 -284.113075) (xy 344.515419 -284.164005) (xy 344.492293 -284.212026)
			(xy 344.462269 -284.256063) (xy 344.426017 -284.295134) (xy 344.384346 -284.328365) (xy 344.338188 -284.355014)
			(xy 344.288574 -284.374486) (xy 344.236612 -284.386346) (xy 344.183462 -284.39033) (xy 344.130312 -284.386346)
			(xy 344.07835 -284.374486) (xy 344.028736 -284.355014) (xy 343.982578 -284.328365) (xy 343.940907 -284.295134)
			(xy 343.904655 -284.256063) (xy 343.874631 -284.212026) (xy 343.851505 -284.164005) (xy 343.835795 -284.113075)
			(xy 343.827852 -284.060371) (xy 343.599272 -284.060371) (xy 343.591329 -284.113075) (xy 343.575619 -284.164005)
			(xy 343.552493 -284.212026) (xy 343.522469 -284.256063) (xy 343.486217 -284.295134) (xy 343.444546 -284.328365)
			(xy 343.398388 -284.355014) (xy 343.348774 -284.374486) (xy 343.296812 -284.386346) (xy 343.243662 -284.39033)
			(xy 343.190512 -284.386346) (xy 343.13855 -284.374486) (xy 343.088936 -284.355014) (xy 343.042778 -284.328365)
			(xy 343.001107 -284.295134) (xy 342.964855 -284.256063) (xy 342.934831 -284.212026) (xy 342.911705 -284.164005)
			(xy 342.895995 -284.113075) (xy 342.888052 -284.060371) (xy 342.659472 -284.060371) (xy 342.651529 -284.113075)
			(xy 342.635819 -284.164005) (xy 342.612693 -284.212026) (xy 342.582669 -284.256063) (xy 342.546417 -284.295134)
			(xy 342.504746 -284.328365) (xy 342.458588 -284.355014) (xy 342.408974 -284.374486) (xy 342.357012 -284.386346)
			(xy 342.303862 -284.39033) (xy 342.250712 -284.386346) (xy 342.19875 -284.374486) (xy 342.149136 -284.355014)
			(xy 342.102978 -284.328365) (xy 342.061307 -284.295134) (xy 342.025055 -284.256063) (xy 341.995031 -284.212026)
			(xy 341.971905 -284.164005) (xy 341.956195 -284.113075) (xy 341.948252 -284.060371) (xy 341.719672 -284.060371)
			(xy 341.711729 -284.113075) (xy 341.696019 -284.164005) (xy 341.672893 -284.212026) (xy 341.642869 -284.256063)
			(xy 341.606617 -284.295134) (xy 341.564946 -284.328365) (xy 341.518788 -284.355014) (xy 341.469174 -284.374486)
			(xy 341.417212 -284.386346) (xy 341.364062 -284.39033) (xy 341.310912 -284.386346) (xy 341.25895 -284.374486)
			(xy 341.209336 -284.355014) (xy 341.163178 -284.328365) (xy 341.121507 -284.295134) (xy 341.085255 -284.256063)
			(xy 341.055231 -284.212026) (xy 341.032105 -284.164005) (xy 341.016395 -284.113075) (xy 341.008452 -284.060371)
			(xy 340.779872 -284.060371) (xy 340.771929 -284.113075) (xy 340.756219 -284.164005) (xy 340.733093 -284.212026)
			(xy 340.703069 -284.256063) (xy 340.666817 -284.295134) (xy 340.625146 -284.328365) (xy 340.578988 -284.355014)
			(xy 340.529374 -284.374486) (xy 340.477412 -284.386346) (xy 340.424262 -284.39033) (xy 340.371112 -284.386346)
			(xy 340.31915 -284.374486) (xy 340.269536 -284.355014) (xy 340.223378 -284.328365) (xy 340.181707 -284.295134)
			(xy 340.145455 -284.256063) (xy 340.115431 -284.212026) (xy 340.092305 -284.164005) (xy 340.076595 -284.113075)
			(xy 340.068652 -284.060371) (xy 339.840072 -284.060371) (xy 339.832129 -284.113075) (xy 339.816419 -284.164005)
			(xy 339.793293 -284.212026) (xy 339.763269 -284.256063) (xy 339.727017 -284.295134) (xy 339.685346 -284.328365)
			(xy 339.639188 -284.355014) (xy 339.589574 -284.374486) (xy 339.537612 -284.386346) (xy 339.484462 -284.39033)
			(xy 339.431312 -284.386346) (xy 339.37935 -284.374486) (xy 339.329736 -284.355014) (xy 339.283578 -284.328365)
			(xy 339.241907 -284.295134) (xy 339.205655 -284.256063) (xy 339.175631 -284.212026) (xy 339.152505 -284.164005)
			(xy 339.136795 -284.113075) (xy 339.128852 -284.060371) (xy 338.900272 -284.060371) (xy 338.892329 -284.113075)
			(xy 338.876619 -284.164005) (xy 338.853493 -284.212026) (xy 338.823469 -284.256063) (xy 338.787217 -284.295134)
			(xy 338.745546 -284.328365) (xy 338.699388 -284.355014) (xy 338.649774 -284.374486) (xy 338.597812 -284.386346)
			(xy 338.544662 -284.39033) (xy 338.491512 -284.386346) (xy 338.43955 -284.374486) (xy 338.389936 -284.355014)
			(xy 338.343778 -284.328365) (xy 338.302107 -284.295134) (xy 338.265855 -284.256063) (xy 338.235831 -284.212026)
			(xy 338.212705 -284.164005) (xy 338.196995 -284.113075) (xy 338.189052 -284.060371) (xy 337.020926 -284.060371)
			(xy 337.012983 -284.113075) (xy 336.997273 -284.164005) (xy 336.974147 -284.212026) (xy 336.944123 -284.256063)
			(xy 336.907871 -284.295134) (xy 336.8662 -284.328365) (xy 336.820042 -284.355014) (xy 336.770428 -284.374486)
			(xy 336.718466 -284.386346) (xy 336.665316 -284.39033) (xy 336.612166 -284.386346) (xy 336.560204 -284.374486)
			(xy 336.51059 -284.355014) (xy 336.464432 -284.328365) (xy 336.422761 -284.295134) (xy 336.386509 -284.256063)
			(xy 336.356485 -284.212026) (xy 336.333359 -284.164005) (xy 336.317649 -284.113075) (xy 336.309706 -284.060371)
			(xy 336.080872 -284.060371) (xy 336.072929 -284.113075) (xy 336.057219 -284.164005) (xy 336.034093 -284.212026)
			(xy 336.004069 -284.256063) (xy 335.967817 -284.295134) (xy 335.926146 -284.328365) (xy 335.879988 -284.355014)
			(xy 335.830374 -284.374486) (xy 335.778412 -284.386346) (xy 335.725262 -284.39033) (xy 335.672112 -284.386346)
			(xy 335.62015 -284.374486) (xy 335.570536 -284.355014) (xy 335.524378 -284.328365) (xy 335.482707 -284.295134)
			(xy 335.446455 -284.256063) (xy 335.416431 -284.212026) (xy 335.393305 -284.164005) (xy 335.377595 -284.113075)
			(xy 335.369652 -284.060371) (xy 335.114842 -284.060371) (xy 335.114819 -284.06144) (xy 335.105492 -284.116086)
			(xy 335.096866 -284.142434) (xy 335.088992 -284.164532) (xy 335.29397 -284.51937) (xy 335.31683 -284.523688)
			(xy 335.341643 -284.528833) (xy 335.389384 -284.545828) (xy 335.433962 -284.569927) (xy 335.474328 -284.600564)
			(xy 335.50953 -284.637016) (xy 335.538741 -284.678425) (xy 335.561271 -284.723817) (xy 335.576591 -284.772121)
			(xy 335.584339 -284.8222) (xy 335.5848 -284.847538) (xy 335.584292 -284.873425) (xy 335.576193 -284.924563)
			(xy 335.560194 -284.973803) (xy 335.536688 -285.019935) (xy 335.506256 -285.061822) (xy 335.469646 -285.098432)
			(xy 335.427759 -285.128864) (xy 335.381627 -285.15237) (xy 335.332387 -285.168369) (xy 335.281249 -285.176468)
			(xy 335.229475 -285.176468) (xy 335.178337 -285.168369) (xy 335.129097 -285.15237) (xy 335.082965 -285.128864)
			(xy 335.041078 -285.098432) (xy 335.004468 -285.061822) (xy 334.974036 -285.019935) (xy 334.95053 -284.973803)
			(xy 334.934531 -284.924563) (xy 334.926432 -284.873425) (xy 334.925924 -284.847538) (xy 334.926462 -284.81983)
			(xy 334.935651 -284.765183) (xy 334.944212 -284.738826) (xy 334.952086 -284.716728) (xy 334.747108 -284.36189)
			(xy 334.724248 -284.357572) (xy 334.699419 -284.352437) (xy 334.651638 -284.33548) (xy 334.607017 -284.311405)
			(xy 334.56661 -284.280781) (xy 334.531369 -284.24433) (xy 334.502126 -284.202912) (xy 334.479571 -284.157504)
			(xy 334.464236 -284.109178) (xy 334.456483 -284.059073) (xy 334.456024 -284.033722) (xy 331.903324 -284.033722)
			(xy 331.903324 -284.873383) (xy 333.046907 -284.873383) (xy 333.046907 -284.821618) (xy 333.055005 -284.77049)
			(xy 333.071 -284.721258) (xy 333.094499 -284.675134) (xy 333.124924 -284.633254) (xy 333.161525 -284.596648)
			(xy 333.203402 -284.566219) (xy 333.249523 -284.542714) (xy 333.298753 -284.526713) (xy 333.34988 -284.51861)
			(xy 333.375762 -284.5181) (xy 333.401254 -284.518612) (xy 333.451631 -284.526467) (xy 333.500193 -284.541996)
			(xy 333.54578 -284.564827) (xy 333.587302 -284.594415) (xy 333.623765 -284.63005) (xy 333.639414 -284.65018)
			(xy 334.05191 -284.65018) (xy 334.067576 -284.630063) (xy 334.104034 -284.594421) (xy 334.145551 -284.564826)
			(xy 334.191135 -284.541986) (xy 334.239694 -284.526447) (xy 334.290069 -284.518581) (xy 334.315562 -284.5181)
			(xy 334.341456 -284.518502) (xy 334.392608 -284.526599) (xy 334.441864 -284.542598) (xy 334.48801 -284.566106)
			(xy 334.52991 -284.596543) (xy 334.566532 -284.633161) (xy 334.596975 -284.675058) (xy 334.620488 -284.721201)
			(xy 334.636492 -284.770455) (xy 334.644595 -284.821606) (xy 334.644595 -284.873394) (xy 334.636492 -284.924545)
			(xy 334.620488 -284.973799) (xy 334.596975 -285.019942) (xy 334.566532 -285.061839) (xy 334.52991 -285.098457)
			(xy 334.48801 -285.128894) (xy 334.441864 -285.152402) (xy 334.392608 -285.168401) (xy 334.341456 -285.176498)
			(xy 334.315562 -285.176976) (xy 334.290067 -285.176529) (xy 334.239687 -285.168661) (xy 334.191123 -285.15312)
			(xy 334.145536 -285.130277) (xy 334.104016 -285.100678) (xy 334.067557 -285.065031) (xy 334.05191 -285.044896)
			(xy 333.639414 -285.044896) (xy 333.623786 -285.065045) (xy 333.587321 -285.100686) (xy 333.545796 -285.130277)
			(xy 333.500205 -285.153112) (xy 333.451638 -285.168644) (xy 333.401257 -285.176501) (xy 333.375762 -285.176976)
			(xy 333.34988 -285.17639) (xy 333.298753 -285.168287) (xy 333.249523 -285.152286) (xy 333.203402 -285.128781)
			(xy 333.161525 -285.098352) (xy 333.124924 -285.061746) (xy 333.094499 -285.019866) (xy 333.071 -284.973742)
			(xy 333.055005 -284.92451) (xy 333.046907 -284.873383) (xy 331.903324 -284.873383) (xy 331.903324 -285.688003)
			(xy 333.490052 -285.688003) (xy 333.490052 -285.634705) (xy 333.497995 -285.582001) (xy 333.513705 -285.531071)
			(xy 333.536831 -285.48305) (xy 333.566855 -285.439013) (xy 333.603107 -285.399942) (xy 333.644778 -285.366711)
			(xy 333.690936 -285.340062) (xy 333.74055 -285.32059) (xy 333.792512 -285.30873) (xy 333.845662 -285.304747)
			(xy 333.898812 -285.30873) (xy 333.950774 -285.32059) (xy 334.000388 -285.340062) (xy 334.046546 -285.366711)
			(xy 334.088217 -285.399942) (xy 334.124469 -285.439013) (xy 334.154493 -285.48305) (xy 334.177619 -285.531071)
			(xy 334.193329 -285.582001) (xy 334.201272 -285.634705) (xy 334.20177 -285.661354) (xy 334.201272 -285.688003)
			(xy 334.429852 -285.688003) (xy 334.429852 -285.634705) (xy 334.437795 -285.582001) (xy 334.453505 -285.531071)
			(xy 334.476631 -285.48305) (xy 334.506655 -285.439013) (xy 334.542907 -285.399942) (xy 334.584578 -285.366711)
			(xy 334.630736 -285.340062) (xy 334.68035 -285.32059) (xy 334.732312 -285.30873) (xy 334.785462 -285.304747)
			(xy 334.838612 -285.30873) (xy 334.890574 -285.32059) (xy 334.940188 -285.340062) (xy 334.986346 -285.366711)
			(xy 335.028017 -285.399942) (xy 335.064269 -285.439013) (xy 335.094293 -285.48305) (xy 335.117419 -285.531071)
			(xy 335.133129 -285.582001) (xy 335.141072 -285.634705) (xy 335.14157 -285.661354) (xy 335.395824 -285.661354)
			(xy 335.396245 -285.636017) (xy 335.404005 -285.585941) (xy 335.419335 -285.537642) (xy 335.441875 -285.492257)
			(xy 335.471092 -285.450854) (xy 335.5063 -285.41441) (xy 335.54667 -285.383781) (xy 335.59125 -285.359689)
			(xy 335.638992 -285.342701) (xy 335.663794 -285.337504) (xy 335.686654 -285.333186) (xy 335.891632 -284.978094)
			(xy 335.884012 -284.95625) (xy 335.875447 -284.929893) (xy 335.86625 -284.875247) (xy 335.865724 -284.847538)
			(xy 335.866232 -284.821651) (xy 335.874331 -284.770513) (xy 335.89033 -284.721273) (xy 335.913836 -284.675141)
			(xy 335.944268 -284.633254) (xy 335.980878 -284.596644) (xy 336.022765 -284.566212) (xy 336.068897 -284.542706)
			(xy 336.118137 -284.526707) (xy 336.169275 -284.518608) (xy 336.221049 -284.518608) (xy 336.272187 -284.526707)
			(xy 336.321427 -284.542706) (xy 336.367559 -284.566212) (xy 336.409446 -284.596644) (xy 336.446056 -284.633254)
			(xy 336.476488 -284.675141) (xy 336.499994 -284.721273) (xy 336.515993 -284.770513) (xy 336.524092 -284.821651)
			(xy 336.5246 -284.847538) (xy 336.524152 -284.872874) (xy 336.523949 -284.874187) (xy 336.779352 -284.874187)
			(xy 336.779352 -284.820889) (xy 336.787295 -284.768185) (xy 336.803005 -284.717255) (xy 336.826131 -284.669234)
			(xy 336.856155 -284.625197) (xy 336.892407 -284.586126) (xy 336.934078 -284.552895) (xy 336.980236 -284.526246)
			(xy 337.02985 -284.506774) (xy 337.081812 -284.494914) (xy 337.134962 -284.490931) (xy 337.188112 -284.494914)
			(xy 337.240074 -284.506774) (xy 337.289688 -284.526246) (xy 337.335846 -284.552895) (xy 337.377517 -284.586126)
			(xy 337.413769 -284.625197) (xy 337.443793 -284.669234) (xy 337.466919 -284.717255) (xy 337.482629 -284.768185)
			(xy 337.490572 -284.820889) (xy 337.49107 -284.847538) (xy 337.490572 -284.874187) (xy 337.482629 -284.926891)
			(xy 337.466919 -284.977821) (xy 337.443793 -285.025842) (xy 337.413769 -285.069879) (xy 337.377517 -285.10895)
			(xy 337.335846 -285.142181) (xy 337.289688 -285.16883) (xy 337.240074 -285.188302) (xy 337.188112 -285.200162)
			(xy 337.134962 -285.204146) (xy 337.081812 -285.200162) (xy 337.02985 -285.188302) (xy 336.980236 -285.16883)
			(xy 336.934078 -285.142181) (xy 336.892407 -285.10895) (xy 336.856155 -285.069879) (xy 336.826131 -285.025842)
			(xy 336.803005 -284.977821) (xy 336.787295 -284.926891) (xy 336.779352 -284.874187) (xy 336.523949 -284.874187)
			(xy 336.516394 -284.922948) (xy 336.501066 -284.971245) (xy 336.47853 -285.016629) (xy 336.449316 -285.058031)
			(xy 336.414111 -285.094476) (xy 336.373746 -285.125106) (xy 336.329169 -285.149199) (xy 336.281431 -285.16619)
			(xy 336.25663 -285.171388) (xy 336.23377 -285.175706) (xy 336.028792 -285.530798) (xy 336.036412 -285.552642)
			(xy 336.044976 -285.578999) (xy 336.054174 -285.633646) (xy 336.0547 -285.661354) (xy 336.054192 -285.687241)
			(xy 336.054071 -285.688003) (xy 336.309452 -285.688003) (xy 336.309452 -285.634705) (xy 336.317395 -285.582001)
			(xy 336.333105 -285.531071) (xy 336.356231 -285.48305) (xy 336.386255 -285.439013) (xy 336.422507 -285.399942)
			(xy 336.464178 -285.366711) (xy 336.510336 -285.340062) (xy 336.55995 -285.32059) (xy 336.611912 -285.30873)
			(xy 336.665062 -285.304747) (xy 336.718212 -285.30873) (xy 336.770174 -285.32059) (xy 336.819788 -285.340062)
			(xy 336.865946 -285.366711) (xy 336.907617 -285.399942) (xy 336.943869 -285.439013) (xy 336.973893 -285.48305)
			(xy 336.997019 -285.531071) (xy 337.012729 -285.582001) (xy 337.020672 -285.634705) (xy 337.02117 -285.661354)
			(xy 337.275424 -285.661354) (xy 337.275932 -285.635467) (xy 337.284031 -285.584329) (xy 337.30003 -285.535089)
			(xy 337.323536 -285.488957) (xy 337.353968 -285.44707) (xy 337.390578 -285.41046) (xy 337.432465 -285.380028)
			(xy 337.478597 -285.356522) (xy 337.527837 -285.340523) (xy 337.578975 -285.332424) (xy 337.630749 -285.332424)
			(xy 337.681887 -285.340523) (xy 337.731127 -285.356522) (xy 337.777259 -285.380028) (xy 337.819146 -285.41046)
			(xy 337.855756 -285.44707) (xy 337.886188 -285.488957) (xy 337.909694 -285.535089) (xy 337.925693 -285.584329)
			(xy 337.933792 -285.635467) (xy 337.9343 -285.661354) (xy 338.215224 -285.661354) (xy 338.215684 -285.636008)
			(xy 338.223463 -285.585916) (xy 338.238816 -285.537605) (xy 338.26138 -285.492212) (xy 338.290625 -285.450806)
			(xy 338.325861 -285.414363) (xy 338.366259 -285.383741) (xy 338.410867 -285.359661) (xy 338.458634 -285.34269)
			(xy 338.483448 -285.337504) (xy 338.506308 -285.333186) (xy 338.711286 -284.978348) (xy 338.703412 -284.956504)
			(xy 338.694834 -284.930085) (xy 338.685636 -284.87531) (xy 338.685124 -284.847538) (xy 338.685632 -284.821651)
			(xy 338.693731 -284.770513) (xy 338.70973 -284.721273) (xy 338.733236 -284.675141) (xy 338.763668 -284.633254)
			(xy 338.800278 -284.596644) (xy 338.842165 -284.566212) (xy 338.888297 -284.542706) (xy 338.937537 -284.526707)
			(xy 338.988675 -284.518608) (xy 339.040449 -284.518608) (xy 339.091587 -284.526707) (xy 339.140827 -284.542706)
			(xy 339.186959 -284.566212) (xy 339.228846 -284.596644) (xy 339.265456 -284.633254) (xy 339.295888 -284.675141)
			(xy 339.319394 -284.721273) (xy 339.335393 -284.770513) (xy 339.343492 -284.821651) (xy 339.344 -284.847538)
			(xy 339.343552 -284.872874) (xy 339.335794 -284.922948) (xy 339.320466 -284.971245) (xy 339.29793 -285.016629)
			(xy 339.268716 -285.058031) (xy 339.233511 -285.094476) (xy 339.193146 -285.125106) (xy 339.148569 -285.149199)
			(xy 339.100831 -285.16619) (xy 339.07603 -285.171388) (xy 339.05317 -285.175706) (xy 338.848192 -285.530544)
			(xy 338.856066 -285.552642) (xy 338.86469 -285.578991) (xy 338.874015 -285.633637) (xy 338.874608 -285.661354)
			(xy 339.155024 -285.661354) (xy 339.155532 -285.635447) (xy 339.163638 -285.58427) (xy 339.17965 -285.534991)
			(xy 339.203173 -285.488824) (xy 339.233629 -285.446905) (xy 339.270267 -285.410267) (xy 339.312186 -285.379811)
			(xy 339.358353 -285.356288) (xy 339.407632 -285.340276) (xy 339.458809 -285.33217) (xy 339.510623 -285.33217)
			(xy 339.5618 -285.340276) (xy 339.611079 -285.356288) (xy 339.657246 -285.379811) (xy 339.699165 -285.410267)
			(xy 339.735803 -285.446905) (xy 339.766259 -285.488824) (xy 339.789782 -285.534991) (xy 339.805794 -285.58427)
			(xy 339.8139 -285.635447) (xy 339.814408 -285.661354) (xy 340.094824 -285.661354) (xy 340.095245 -285.636017)
			(xy 340.103005 -285.585941) (xy 340.118335 -285.537642) (xy 340.140875 -285.492257) (xy 340.170092 -285.450854)
			(xy 340.2053 -285.41441) (xy 340.24567 -285.383781) (xy 340.29025 -285.359689) (xy 340.337992 -285.342701)
			(xy 340.362794 -285.337504) (xy 340.385654 -285.333186) (xy 340.590886 -284.97784) (xy 340.583266 -284.955996)
			(xy 340.574644 -284.929713) (xy 340.565327 -284.875193) (xy 340.564724 -284.847538) (xy 340.565232 -284.821631)
			(xy 340.573338 -284.770454) (xy 340.58935 -284.721175) (xy 340.612873 -284.675008) (xy 340.643329 -284.633089)
			(xy 340.679967 -284.596451) (xy 340.721886 -284.565995) (xy 340.768053 -284.542472) (xy 340.817332 -284.52646)
			(xy 340.868509 -284.518354) (xy 340.920323 -284.518354) (xy 340.9715 -284.52646) (xy 341.020779 -284.542472)
			(xy 341.066946 -284.565995) (xy 341.108865 -284.596451) (xy 341.145503 -284.633089) (xy 341.175959 -284.675008)
			(xy 341.199482 -284.721175) (xy 341.215494 -284.770454) (xy 341.2236 -284.821631) (xy 341.224108 -284.847538)
			(xy 341.223661 -284.872913) (xy 341.215887 -284.923064) (xy 341.200514 -284.97143) (xy 341.177905 -285.016866)
			(xy 341.148596 -285.058297) (xy 341.113279 -285.094742) (xy 341.072791 -285.125341) (xy 341.028089 -285.149367)
			(xy 340.980231 -285.166254) (xy 340.955376 -285.171388) (xy 340.932516 -285.175706) (xy 340.727538 -285.530544)
			(xy 340.735412 -285.552642) (xy 340.743983 -285.578997) (xy 340.753175 -285.633645) (xy 340.7537 -285.661354)
			(xy 341.034624 -285.661354) (xy 341.035132 -285.635467) (xy 341.043231 -285.584329) (xy 341.05923 -285.535089)
			(xy 341.082736 -285.488957) (xy 341.113168 -285.44707) (xy 341.149778 -285.41046) (xy 341.191665 -285.380028)
			(xy 341.237797 -285.356522) (xy 341.287037 -285.340523) (xy 341.338175 -285.332424) (xy 341.389949 -285.332424)
			(xy 341.441087 -285.340523) (xy 341.490327 -285.356522) (xy 341.536459 -285.380028) (xy 341.578346 -285.41046)
			(xy 341.614956 -285.44707) (xy 341.645388 -285.488957) (xy 341.668894 -285.535089) (xy 341.684893 -285.584329)
			(xy 341.692992 -285.635467) (xy 341.6935 -285.661354) (xy 341.974424 -285.661354) (xy 341.974845 -285.636017)
			(xy 341.982605 -285.585941) (xy 341.997935 -285.537642) (xy 342.020475 -285.492257) (xy 342.049692 -285.450854)
			(xy 342.0849 -285.41441) (xy 342.12527 -285.383781) (xy 342.16985 -285.359689) (xy 342.217592 -285.342701)
			(xy 342.242394 -285.337504) (xy 342.265254 -285.333186) (xy 342.470486 -284.97784) (xy 342.462866 -284.955996)
			(xy 342.454244 -284.929713) (xy 342.444927 -284.875193) (xy 342.444324 -284.847538) (xy 342.444832 -284.821631)
			(xy 342.452938 -284.770454) (xy 342.46895 -284.721175) (xy 342.492473 -284.675008) (xy 342.522929 -284.633089)
			(xy 342.559567 -284.596451) (xy 342.601486 -284.565995) (xy 342.647653 -284.542472) (xy 342.696932 -284.52646)
			(xy 342.748109 -284.518354) (xy 342.799923 -284.518354) (xy 342.8511 -284.52646) (xy 342.900379 -284.542472)
			(xy 342.946546 -284.565995) (xy 342.988465 -284.596451) (xy 343.025103 -284.633089) (xy 343.055559 -284.675008)
			(xy 343.079082 -284.721175) (xy 343.095094 -284.770454) (xy 343.1032 -284.821631) (xy 343.103708 -284.847538)
			(xy 343.103261 -284.872913) (xy 343.095487 -284.923064) (xy 343.080114 -284.97143) (xy 343.057505 -285.016866)
			(xy 343.028196 -285.058297) (xy 342.992879 -285.094742) (xy 342.952391 -285.125341) (xy 342.907689 -285.149367)
			(xy 342.859831 -285.166254) (xy 342.834976 -285.171388) (xy 342.812116 -285.175706) (xy 342.607138 -285.530544)
			(xy 342.615012 -285.552642) (xy 342.623583 -285.578997) (xy 342.632775 -285.633645) (xy 342.6333 -285.661354)
			(xy 342.914224 -285.661354) (xy 342.914732 -285.635467) (xy 342.922831 -285.584329) (xy 342.93883 -285.535089)
			(xy 342.962336 -285.488957) (xy 342.992768 -285.44707) (xy 343.029378 -285.41046) (xy 343.071265 -285.380028)
			(xy 343.117397 -285.356522) (xy 343.166637 -285.340523) (xy 343.217775 -285.332424) (xy 343.269549 -285.332424)
			(xy 343.320687 -285.340523) (xy 343.369927 -285.356522) (xy 343.416059 -285.380028) (xy 343.457946 -285.41046)
			(xy 343.494556 -285.44707) (xy 343.524988 -285.488957) (xy 343.548494 -285.535089) (xy 343.564493 -285.584329)
			(xy 343.572592 -285.635467) (xy 343.5731 -285.661354) (xy 343.854024 -285.661354) (xy 343.854445 -285.636017)
			(xy 343.862205 -285.585941) (xy 343.877535 -285.537642) (xy 343.900075 -285.492257) (xy 343.929292 -285.450854)
			(xy 343.9645 -285.41441) (xy 344.00487 -285.383781) (xy 344.04945 -285.359689) (xy 344.097192 -285.342701)
			(xy 344.121994 -285.337504) (xy 344.144854 -285.333186) (xy 344.350086 -284.97784) (xy 344.342466 -284.955996)
			(xy 344.333844 -284.929713) (xy 344.324527 -284.875193) (xy 344.323924 -284.847538) (xy 344.324432 -284.821631)
			(xy 344.332538 -284.770454) (xy 344.34855 -284.721175) (xy 344.372073 -284.675008) (xy 344.402529 -284.633089)
			(xy 344.439167 -284.596451) (xy 344.481086 -284.565995) (xy 344.527253 -284.542472) (xy 344.576532 -284.52646)
			(xy 344.627709 -284.518354) (xy 344.679523 -284.518354) (xy 344.7307 -284.52646) (xy 344.779979 -284.542472)
			(xy 344.826146 -284.565995) (xy 344.868065 -284.596451) (xy 344.904703 -284.633089) (xy 344.935159 -284.675008)
			(xy 344.958682 -284.721175) (xy 344.974694 -284.770454) (xy 344.9828 -284.821631) (xy 344.983308 -284.847538)
			(xy 344.982861 -284.872913) (xy 344.975087 -284.923064) (xy 344.959714 -284.97143) (xy 344.937105 -285.016866)
			(xy 344.907796 -285.058297) (xy 344.872479 -285.094742) (xy 344.831991 -285.125341) (xy 344.787289 -285.149367)
			(xy 344.739431 -285.166254) (xy 344.714576 -285.171388) (xy 344.691716 -285.175706) (xy 344.486738 -285.530544)
			(xy 344.494612 -285.552642) (xy 344.503183 -285.578997) (xy 344.512375 -285.633645) (xy 344.5129 -285.661354)
			(xy 344.793824 -285.661354) (xy 344.794332 -285.635467) (xy 344.802431 -285.584329) (xy 344.81843 -285.535089)
			(xy 344.841936 -285.488957) (xy 344.872368 -285.44707) (xy 344.908978 -285.41046) (xy 344.950865 -285.380028)
			(xy 344.996997 -285.356522) (xy 345.046237 -285.340523) (xy 345.097375 -285.332424) (xy 345.149149 -285.332424)
			(xy 345.200287 -285.340523) (xy 345.249527 -285.356522) (xy 345.295659 -285.380028) (xy 345.337546 -285.41046)
			(xy 345.374156 -285.44707) (xy 345.404588 -285.488957) (xy 345.428094 -285.535089) (xy 345.444093 -285.584329)
			(xy 345.452192 -285.635467) (xy 345.4527 -285.661354) (xy 345.733624 -285.661354) (xy 345.734045 -285.636017)
			(xy 345.741805 -285.585941) (xy 345.757135 -285.537642) (xy 345.779675 -285.492257) (xy 345.808892 -285.450854)
			(xy 345.8441 -285.41441) (xy 345.88447 -285.383781) (xy 345.92905 -285.359689) (xy 345.976792 -285.342701)
			(xy 346.001594 -285.337504) (xy 346.024454 -285.333186) (xy 346.229686 -284.97784) (xy 346.222066 -284.955996)
			(xy 346.213444 -284.929713) (xy 346.204127 -284.875193) (xy 346.203524 -284.847538) (xy 346.204032 -284.821631)
			(xy 346.212138 -284.770454) (xy 346.22815 -284.721175) (xy 346.251673 -284.675008) (xy 346.282129 -284.633089)
			(xy 346.318767 -284.596451) (xy 346.360686 -284.565995) (xy 346.406853 -284.542472) (xy 346.456132 -284.52646)
			(xy 346.507309 -284.518354) (xy 346.559123 -284.518354) (xy 346.6103 -284.52646) (xy 346.659579 -284.542472)
			(xy 346.705746 -284.565995) (xy 346.747665 -284.596451) (xy 346.784303 -284.633089) (xy 346.814759 -284.675008)
			(xy 346.838282 -284.721175) (xy 346.854294 -284.770454) (xy 346.8624 -284.821631) (xy 346.862908 -284.847538)
			(xy 346.862461 -284.872913) (xy 346.854687 -284.923064) (xy 346.839314 -284.97143) (xy 346.816705 -285.016866)
			(xy 346.787396 -285.058297) (xy 346.752079 -285.094742) (xy 346.711591 -285.125341) (xy 346.666889 -285.149367)
			(xy 346.619031 -285.166254) (xy 346.594176 -285.171388) (xy 346.571316 -285.175706) (xy 346.366338 -285.530544)
			(xy 346.374212 -285.552642) (xy 346.382783 -285.578997) (xy 346.391975 -285.633645) (xy 346.3925 -285.661354)
			(xy 346.673424 -285.661354) (xy 346.673932 -285.635467) (xy 346.682031 -285.584329) (xy 346.69803 -285.535089)
			(xy 346.721536 -285.488957) (xy 346.751968 -285.44707) (xy 346.788578 -285.41046) (xy 346.830465 -285.380028)
			(xy 346.876597 -285.356522) (xy 346.925837 -285.340523) (xy 346.976975 -285.332424) (xy 347.028749 -285.332424)
			(xy 347.079887 -285.340523) (xy 347.129127 -285.356522) (xy 347.175259 -285.380028) (xy 347.217146 -285.41046)
			(xy 347.253756 -285.44707) (xy 347.284188 -285.488957) (xy 347.307694 -285.535089) (xy 347.323693 -285.584329)
			(xy 347.331792 -285.635467) (xy 347.3323 -285.661354) (xy 347.331755 -285.688998) (xy 347.322559 -285.743516)
			(xy 347.314012 -285.769812) (xy 347.306392 -285.79191) (xy 347.511624 -286.147256) (xy 347.534484 -286.151574)
			(xy 347.559306 -286.156737) (xy 347.607083 -286.173695) (xy 347.651701 -286.197768) (xy 347.692106 -286.22839)
			(xy 347.727346 -286.264837) (xy 347.756589 -286.30625) (xy 347.779146 -286.351653) (xy 347.794485 -286.399975)
			(xy 347.802245 -286.450075) (xy 347.802708 -286.475424) (xy 347.8022 -286.501331) (xy 347.802082 -286.502073)
			(xy 348.056952 -286.502073) (xy 348.056952 -286.448775) (xy 348.064895 -286.396071) (xy 348.080605 -286.345141)
			(xy 348.103731 -286.29712) (xy 348.133755 -286.253083) (xy 348.170007 -286.214012) (xy 348.211678 -286.180781)
			(xy 348.257836 -286.154132) (xy 348.30745 -286.13466) (xy 348.359412 -286.1228) (xy 348.412562 -286.118817)
			(xy 348.465712 -286.1228) (xy 348.517674 -286.13466) (xy 348.567288 -286.154132) (xy 348.613446 -286.180781)
			(xy 348.655117 -286.214012) (xy 348.691369 -286.253083) (xy 348.721393 -286.29712) (xy 348.744519 -286.345141)
			(xy 348.760229 -286.396071) (xy 348.768172 -286.448775) (xy 348.76867 -286.475424) (xy 348.768172 -286.502073)
			(xy 348.760229 -286.554777) (xy 348.744519 -286.605707) (xy 348.721393 -286.653728) (xy 348.691369 -286.697765)
			(xy 348.655117 -286.736836) (xy 348.613446 -286.770067) (xy 348.567288 -286.796716) (xy 348.517674 -286.816188)
			(xy 348.465712 -286.828048) (xy 348.412562 -286.832032) (xy 348.359412 -286.828048) (xy 348.30745 -286.816188)
			(xy 348.257836 -286.796716) (xy 348.211678 -286.770067) (xy 348.170007 -286.736836) (xy 348.133755 -286.697765)
			(xy 348.103731 -286.653728) (xy 348.080605 -286.605707) (xy 348.064895 -286.554777) (xy 348.056952 -286.502073)
			(xy 347.802082 -286.502073) (xy 347.794094 -286.552508) (xy 347.778082 -286.601787) (xy 347.754559 -286.647954)
			(xy 347.724103 -286.689873) (xy 347.687465 -286.726511) (xy 347.645546 -286.756967) (xy 347.599379 -286.78049)
			(xy 347.5501 -286.796502) (xy 347.498923 -286.804608) (xy 347.447109 -286.804608) (xy 347.395932 -286.796502)
			(xy 347.346653 -286.78049) (xy 347.300486 -286.756967) (xy 347.258567 -286.726511) (xy 347.221929 -286.689873)
			(xy 347.191473 -286.647954) (xy 347.16795 -286.601787) (xy 347.151938 -286.552508) (xy 347.143832 -286.501331)
			(xy 347.143324 -286.475424) (xy 347.143923 -286.447707) (xy 347.153243 -286.39306) (xy 347.161866 -286.366712)
			(xy 347.16974 -286.344614) (xy 346.964762 -285.989522) (xy 346.941648 -285.985204) (xy 346.916827 -285.980039)
			(xy 346.869047 -285.963084) (xy 346.824428 -285.939012) (xy 346.784022 -285.908392) (xy 346.748781 -285.871945)
			(xy 346.719537 -285.830531) (xy 346.69698 -285.785127) (xy 346.681643 -285.736804) (xy 346.673886 -285.686703)
			(xy 346.673424 -285.661354) (xy 346.3925 -285.661354) (xy 346.391992 -285.687241) (xy 346.383893 -285.738379)
			(xy 346.367894 -285.787619) (xy 346.344388 -285.833751) (xy 346.313956 -285.875638) (xy 346.277346 -285.912248)
			(xy 346.235459 -285.94268) (xy 346.189327 -285.966186) (xy 346.140087 -285.982185) (xy 346.088949 -285.990284)
			(xy 346.037175 -285.990284) (xy 345.986037 -285.982185) (xy 345.936797 -285.966186) (xy 345.890665 -285.94268)
			(xy 345.848778 -285.912248) (xy 345.812168 -285.875638) (xy 345.781736 -285.833751) (xy 345.75823 -285.787619)
			(xy 345.742231 -285.738379) (xy 345.734132 -285.687241) (xy 345.733624 -285.661354) (xy 345.4527 -285.661354)
			(xy 345.452155 -285.688998) (xy 345.442959 -285.743516) (xy 345.434412 -285.769812) (xy 345.426792 -285.79191)
			(xy 345.632024 -286.147256) (xy 345.654884 -286.151574) (xy 345.679706 -286.156737) (xy 345.727483 -286.173695)
			(xy 345.772101 -286.197768) (xy 345.812506 -286.22839) (xy 345.847746 -286.264837) (xy 345.876989 -286.30625)
			(xy 345.899546 -286.351653) (xy 345.914885 -286.399975) (xy 345.922645 -286.450075) (xy 345.923108 -286.475424)
			(xy 345.9226 -286.501331) (xy 345.922482 -286.502073) (xy 346.177352 -286.502073) (xy 346.177352 -286.448775)
			(xy 346.185295 -286.396071) (xy 346.201005 -286.345141) (xy 346.224131 -286.29712) (xy 346.254155 -286.253083)
			(xy 346.290407 -286.214012) (xy 346.332078 -286.180781) (xy 346.378236 -286.154132) (xy 346.42785 -286.13466)
			(xy 346.479812 -286.1228) (xy 346.532962 -286.118817) (xy 346.586112 -286.1228) (xy 346.638074 -286.13466)
			(xy 346.687688 -286.154132) (xy 346.733846 -286.180781) (xy 346.775517 -286.214012) (xy 346.811769 -286.253083)
			(xy 346.841793 -286.29712) (xy 346.864919 -286.345141) (xy 346.880629 -286.396071) (xy 346.888572 -286.448775)
			(xy 346.88907 -286.475424) (xy 346.888572 -286.502073) (xy 346.880629 -286.554777) (xy 346.864919 -286.605707)
			(xy 346.841793 -286.653728) (xy 346.811769 -286.697765) (xy 346.775517 -286.736836) (xy 346.733846 -286.770067)
			(xy 346.687688 -286.796716) (xy 346.638074 -286.816188) (xy 346.586112 -286.828048) (xy 346.532962 -286.832032)
			(xy 346.479812 -286.828048) (xy 346.42785 -286.816188) (xy 346.378236 -286.796716) (xy 346.332078 -286.770067)
			(xy 346.290407 -286.736836) (xy 346.254155 -286.697765) (xy 346.224131 -286.653728) (xy 346.201005 -286.605707)
			(xy 346.185295 -286.554777) (xy 346.177352 -286.502073) (xy 345.922482 -286.502073) (xy 345.914494 -286.552508)
			(xy 345.898482 -286.601787) (xy 345.874959 -286.647954) (xy 345.844503 -286.689873) (xy 345.807865 -286.726511)
			(xy 345.765946 -286.756967) (xy 345.719779 -286.78049) (xy 345.6705 -286.796502) (xy 345.619323 -286.804608)
			(xy 345.567509 -286.804608) (xy 345.516332 -286.796502) (xy 345.467053 -286.78049) (xy 345.420886 -286.756967)
			(xy 345.378967 -286.726511) (xy 345.342329 -286.689873) (xy 345.311873 -286.647954) (xy 345.28835 -286.601787)
			(xy 345.272338 -286.552508) (xy 345.264232 -286.501331) (xy 345.263724 -286.475424) (xy 345.264323 -286.447707)
			(xy 345.273643 -286.39306) (xy 345.282266 -286.366712) (xy 345.29014 -286.344614) (xy 345.085162 -285.989522)
			(xy 345.062048 -285.985204) (xy 345.037227 -285.980039) (xy 344.989447 -285.963084) (xy 344.944828 -285.939012)
			(xy 344.904422 -285.908392) (xy 344.869181 -285.871945) (xy 344.839937 -285.830531) (xy 344.81738 -285.785127)
			(xy 344.802043 -285.736804) (xy 344.794286 -285.686703) (xy 344.793824 -285.661354) (xy 344.5129 -285.661354)
			(xy 344.512392 -285.687241) (xy 344.504293 -285.738379) (xy 344.488294 -285.787619) (xy 344.464788 -285.833751)
			(xy 344.434356 -285.875638) (xy 344.397746 -285.912248) (xy 344.355859 -285.94268) (xy 344.309727 -285.966186)
			(xy 344.260487 -285.982185) (xy 344.209349 -285.990284) (xy 344.157575 -285.990284) (xy 344.106437 -285.982185)
			(xy 344.057197 -285.966186) (xy 344.011065 -285.94268) (xy 343.969178 -285.912248) (xy 343.932568 -285.875638)
			(xy 343.902136 -285.833751) (xy 343.87863 -285.787619) (xy 343.862631 -285.738379) (xy 343.854532 -285.687241)
			(xy 343.854024 -285.661354) (xy 343.5731 -285.661354) (xy 343.572555 -285.688998) (xy 343.563359 -285.743516)
			(xy 343.554812 -285.769812) (xy 343.547192 -285.79191) (xy 343.752424 -286.147256) (xy 343.775284 -286.151574)
			(xy 343.800106 -286.156737) (xy 343.847883 -286.173695) (xy 343.892501 -286.197768) (xy 343.932906 -286.22839)
			(xy 343.968146 -286.264837) (xy 343.997389 -286.30625) (xy 344.019946 -286.351653) (xy 344.035285 -286.399975)
			(xy 344.043045 -286.450075) (xy 344.043508 -286.475424) (xy 344.043 -286.501331) (xy 344.042882 -286.502073)
			(xy 344.297752 -286.502073) (xy 344.297752 -286.448775) (xy 344.305695 -286.396071) (xy 344.321405 -286.345141)
			(xy 344.344531 -286.29712) (xy 344.374555 -286.253083) (xy 344.410807 -286.214012) (xy 344.452478 -286.180781)
			(xy 344.498636 -286.154132) (xy 344.54825 -286.13466) (xy 344.600212 -286.1228) (xy 344.653362 -286.118817)
			(xy 344.706512 -286.1228) (xy 344.758474 -286.13466) (xy 344.808088 -286.154132) (xy 344.854246 -286.180781)
			(xy 344.895917 -286.214012) (xy 344.932169 -286.253083) (xy 344.962193 -286.29712) (xy 344.985319 -286.345141)
			(xy 345.001029 -286.396071) (xy 345.008972 -286.448775) (xy 345.00947 -286.475424) (xy 345.008972 -286.502073)
			(xy 345.001029 -286.554777) (xy 344.985319 -286.605707) (xy 344.962193 -286.653728) (xy 344.932169 -286.697765)
			(xy 344.895917 -286.736836) (xy 344.854246 -286.770067) (xy 344.808088 -286.796716) (xy 344.758474 -286.816188)
			(xy 344.706512 -286.828048) (xy 344.653362 -286.832032) (xy 344.600212 -286.828048) (xy 344.54825 -286.816188)
			(xy 344.498636 -286.796716) (xy 344.452478 -286.770067) (xy 344.410807 -286.736836) (xy 344.374555 -286.697765)
			(xy 344.344531 -286.653728) (xy 344.321405 -286.605707) (xy 344.305695 -286.554777) (xy 344.297752 -286.502073)
			(xy 344.042882 -286.502073) (xy 344.034894 -286.552508) (xy 344.018882 -286.601787) (xy 343.995359 -286.647954)
			(xy 343.964903 -286.689873) (xy 343.928265 -286.726511) (xy 343.886346 -286.756967) (xy 343.840179 -286.78049)
			(xy 343.7909 -286.796502) (xy 343.739723 -286.804608) (xy 343.687909 -286.804608) (xy 343.636732 -286.796502)
			(xy 343.587453 -286.78049) (xy 343.541286 -286.756967) (xy 343.499367 -286.726511) (xy 343.462729 -286.689873)
			(xy 343.432273 -286.647954) (xy 343.40875 -286.601787) (xy 343.392738 -286.552508) (xy 343.384632 -286.501331)
			(xy 343.384124 -286.475424) (xy 343.384723 -286.447707) (xy 343.394043 -286.39306) (xy 343.402666 -286.366712)
			(xy 343.41054 -286.344614) (xy 343.205562 -285.989522) (xy 343.182448 -285.985204) (xy 343.157627 -285.980039)
			(xy 343.109847 -285.963084) (xy 343.065228 -285.939012) (xy 343.024822 -285.908392) (xy 342.989581 -285.871945)
			(xy 342.960337 -285.830531) (xy 342.93778 -285.785127) (xy 342.922443 -285.736804) (xy 342.914686 -285.686703)
			(xy 342.914224 -285.661354) (xy 342.6333 -285.661354) (xy 342.632792 -285.687241) (xy 342.624693 -285.738379)
			(xy 342.608694 -285.787619) (xy 342.585188 -285.833751) (xy 342.554756 -285.875638) (xy 342.518146 -285.912248)
			(xy 342.476259 -285.94268) (xy 342.430127 -285.966186) (xy 342.380887 -285.982185) (xy 342.329749 -285.990284)
			(xy 342.277975 -285.990284) (xy 342.226837 -285.982185) (xy 342.177597 -285.966186) (xy 342.131465 -285.94268)
			(xy 342.089578 -285.912248) (xy 342.052968 -285.875638) (xy 342.022536 -285.833751) (xy 341.99903 -285.787619)
			(xy 341.983031 -285.738379) (xy 341.974932 -285.687241) (xy 341.974424 -285.661354) (xy 341.6935 -285.661354)
			(xy 341.692955 -285.688998) (xy 341.683759 -285.743516) (xy 341.675212 -285.769812) (xy 341.667592 -285.79191)
			(xy 341.872824 -286.147256) (xy 341.895684 -286.151574) (xy 341.920506 -286.156737) (xy 341.968283 -286.173695)
			(xy 342.012901 -286.197768) (xy 342.053306 -286.22839) (xy 342.088546 -286.264837) (xy 342.117789 -286.30625)
			(xy 342.140346 -286.351653) (xy 342.155685 -286.399975) (xy 342.163445 -286.450075) (xy 342.163908 -286.475424)
			(xy 342.1634 -286.501331) (xy 342.163282 -286.502073) (xy 342.418152 -286.502073) (xy 342.418152 -286.448775)
			(xy 342.426095 -286.396071) (xy 342.441805 -286.345141) (xy 342.464931 -286.29712) (xy 342.494955 -286.253083)
			(xy 342.531207 -286.214012) (xy 342.572878 -286.180781) (xy 342.619036 -286.154132) (xy 342.66865 -286.13466)
			(xy 342.720612 -286.1228) (xy 342.773762 -286.118817) (xy 342.826912 -286.1228) (xy 342.878874 -286.13466)
			(xy 342.928488 -286.154132) (xy 342.974646 -286.180781) (xy 343.016317 -286.214012) (xy 343.052569 -286.253083)
			(xy 343.082593 -286.29712) (xy 343.105719 -286.345141) (xy 343.121429 -286.396071) (xy 343.129372 -286.448775)
			(xy 343.12987 -286.475424) (xy 343.129372 -286.502073) (xy 343.121429 -286.554777) (xy 343.105719 -286.605707)
			(xy 343.082593 -286.653728) (xy 343.052569 -286.697765) (xy 343.016317 -286.736836) (xy 342.974646 -286.770067)
			(xy 342.928488 -286.796716) (xy 342.878874 -286.816188) (xy 342.826912 -286.828048) (xy 342.773762 -286.832032)
			(xy 342.720612 -286.828048) (xy 342.66865 -286.816188) (xy 342.619036 -286.796716) (xy 342.572878 -286.770067)
			(xy 342.531207 -286.736836) (xy 342.494955 -286.697765) (xy 342.464931 -286.653728) (xy 342.441805 -286.605707)
			(xy 342.426095 -286.554777) (xy 342.418152 -286.502073) (xy 342.163282 -286.502073) (xy 342.155294 -286.552508)
			(xy 342.139282 -286.601787) (xy 342.115759 -286.647954) (xy 342.085303 -286.689873) (xy 342.048665 -286.726511)
			(xy 342.006746 -286.756967) (xy 341.960579 -286.78049) (xy 341.9113 -286.796502) (xy 341.860123 -286.804608)
			(xy 341.808309 -286.804608) (xy 341.757132 -286.796502) (xy 341.707853 -286.78049) (xy 341.661686 -286.756967)
			(xy 341.619767 -286.726511) (xy 341.583129 -286.689873) (xy 341.552673 -286.647954) (xy 341.52915 -286.601787)
			(xy 341.513138 -286.552508) (xy 341.505032 -286.501331) (xy 341.504524 -286.475424) (xy 341.505123 -286.447707)
			(xy 341.514443 -286.39306) (xy 341.523066 -286.366712) (xy 341.53094 -286.344614) (xy 341.325962 -285.989522)
			(xy 341.302848 -285.985204) (xy 341.278027 -285.980039) (xy 341.230247 -285.963084) (xy 341.185628 -285.939012)
			(xy 341.145222 -285.908392) (xy 341.109981 -285.871945) (xy 341.080737 -285.830531) (xy 341.05818 -285.785127)
			(xy 341.042843 -285.736804) (xy 341.035086 -285.686703) (xy 341.034624 -285.661354) (xy 340.7537 -285.661354)
			(xy 340.753192 -285.687241) (xy 340.745093 -285.738379) (xy 340.729094 -285.787619) (xy 340.705588 -285.833751)
			(xy 340.675156 -285.875638) (xy 340.638546 -285.912248) (xy 340.596659 -285.94268) (xy 340.550527 -285.966186)
			(xy 340.501287 -285.982185) (xy 340.450149 -285.990284) (xy 340.398375 -285.990284) (xy 340.347237 -285.982185)
			(xy 340.297997 -285.966186) (xy 340.251865 -285.94268) (xy 340.209978 -285.912248) (xy 340.173368 -285.875638)
			(xy 340.142936 -285.833751) (xy 340.11943 -285.787619) (xy 340.103431 -285.738379) (xy 340.095332 -285.687241)
			(xy 340.094824 -285.661354) (xy 339.814408 -285.661354) (xy 339.813802 -285.689071) (xy 339.804487 -285.743717)
			(xy 339.795866 -285.770066) (xy 339.787992 -285.792164) (xy 339.993224 -286.147256) (xy 340.016084 -286.151574)
			(xy 340.040906 -286.156737) (xy 340.088683 -286.173695) (xy 340.133301 -286.197768) (xy 340.173706 -286.22839)
			(xy 340.208946 -286.264837) (xy 340.238189 -286.30625) (xy 340.260746 -286.351653) (xy 340.276085 -286.399975)
			(xy 340.283845 -286.450075) (xy 340.284308 -286.475424) (xy 340.2838 -286.501331) (xy 340.283682 -286.502073)
			(xy 340.538806 -286.502073) (xy 340.538806 -286.448775) (xy 340.546749 -286.396071) (xy 340.562459 -286.345141)
			(xy 340.585585 -286.29712) (xy 340.615609 -286.253083) (xy 340.651861 -286.214012) (xy 340.693532 -286.180781)
			(xy 340.73969 -286.154132) (xy 340.789304 -286.13466) (xy 340.841266 -286.1228) (xy 340.894416 -286.118817)
			(xy 340.947566 -286.1228) (xy 340.999528 -286.13466) (xy 341.049142 -286.154132) (xy 341.0953 -286.180781)
			(xy 341.136971 -286.214012) (xy 341.173223 -286.253083) (xy 341.203247 -286.29712) (xy 341.226373 -286.345141)
			(xy 341.242083 -286.396071) (xy 341.250026 -286.448775) (xy 341.250524 -286.475424) (xy 341.250026 -286.502073)
			(xy 341.242083 -286.554777) (xy 341.226373 -286.605707) (xy 341.203247 -286.653728) (xy 341.173223 -286.697765)
			(xy 341.136971 -286.736836) (xy 341.0953 -286.770067) (xy 341.049142 -286.796716) (xy 340.999528 -286.816188)
			(xy 340.947566 -286.828048) (xy 340.894416 -286.832032) (xy 340.841266 -286.828048) (xy 340.789304 -286.816188)
			(xy 340.73969 -286.796716) (xy 340.693532 -286.770067) (xy 340.651861 -286.736836) (xy 340.615609 -286.697765)
			(xy 340.585585 -286.653728) (xy 340.562459 -286.605707) (xy 340.546749 -286.554777) (xy 340.538806 -286.502073)
			(xy 340.283682 -286.502073) (xy 340.275694 -286.552508) (xy 340.259682 -286.601787) (xy 340.236159 -286.647954)
			(xy 340.205703 -286.689873) (xy 340.169065 -286.726511) (xy 340.127146 -286.756967) (xy 340.080979 -286.78049)
			(xy 340.0317 -286.796502) (xy 339.980523 -286.804608) (xy 339.928709 -286.804608) (xy 339.877532 -286.796502)
			(xy 339.828253 -286.78049) (xy 339.782086 -286.756967) (xy 339.740167 -286.726511) (xy 339.703529 -286.689873)
			(xy 339.673073 -286.647954) (xy 339.64955 -286.601787) (xy 339.633538 -286.552508) (xy 339.625432 -286.501331)
			(xy 339.624924 -286.475424) (xy 339.625523 -286.447707) (xy 339.634843 -286.39306) (xy 339.643466 -286.366712)
			(xy 339.65134 -286.344614) (xy 339.446108 -285.989522) (xy 339.423248 -285.985204) (xy 339.398427 -285.980039)
			(xy 339.350647 -285.963084) (xy 339.306028 -285.939012) (xy 339.265622 -285.908392) (xy 339.230381 -285.871945)
			(xy 339.201137 -285.830531) (xy 339.17858 -285.785127) (xy 339.163243 -285.736804) (xy 339.155486 -285.686703)
			(xy 339.155024 -285.661354) (xy 338.874608 -285.661354) (xy 338.8741 -285.687261) (xy 338.865994 -285.738438)
			(xy 338.849982 -285.787717) (xy 338.826459 -285.833884) (xy 338.796003 -285.875803) (xy 338.759365 -285.912441)
			(xy 338.717446 -285.942897) (xy 338.671279 -285.96642) (xy 338.622 -285.982432) (xy 338.570823 -285.990538)
			(xy 338.519009 -285.990538) (xy 338.467832 -285.982432) (xy 338.418553 -285.96642) (xy 338.372386 -285.942897)
			(xy 338.330467 -285.912441) (xy 338.293829 -285.875803) (xy 338.263373 -285.833884) (xy 338.23985 -285.787717)
			(xy 338.223838 -285.738438) (xy 338.215732 -285.687261) (xy 338.215224 -285.661354) (xy 337.9343 -285.661354)
			(xy 337.933759 -285.689062) (xy 337.924571 -285.743708) (xy 337.916012 -285.770066) (xy 337.908138 -285.792164)
			(xy 338.11337 -286.147256) (xy 338.13623 -286.151574) (xy 338.16104 -286.156732) (xy 338.20878 -286.173726)
			(xy 338.253357 -286.197824) (xy 338.293722 -286.228459) (xy 338.328925 -286.264909) (xy 338.358136 -286.306317)
			(xy 338.380667 -286.351707) (xy 338.395988 -286.400009) (xy 338.403738 -286.450087) (xy 338.4042 -286.475424)
			(xy 338.403692 -286.501311) (xy 338.403571 -286.502073) (xy 338.658952 -286.502073) (xy 338.658952 -286.448775)
			(xy 338.666895 -286.396071) (xy 338.682605 -286.345141) (xy 338.705731 -286.29712) (xy 338.735755 -286.253083)
			(xy 338.772007 -286.214012) (xy 338.813678 -286.180781) (xy 338.859836 -286.154132) (xy 338.90945 -286.13466)
			(xy 338.961412 -286.1228) (xy 339.014562 -286.118817) (xy 339.067712 -286.1228) (xy 339.119674 -286.13466)
			(xy 339.169288 -286.154132) (xy 339.215446 -286.180781) (xy 339.257117 -286.214012) (xy 339.293369 -286.253083)
			(xy 339.323393 -286.29712) (xy 339.346519 -286.345141) (xy 339.362229 -286.396071) (xy 339.370172 -286.448775)
			(xy 339.37067 -286.475424) (xy 339.370172 -286.502073) (xy 339.362229 -286.554777) (xy 339.346519 -286.605707)
			(xy 339.323393 -286.653728) (xy 339.293369 -286.697765) (xy 339.257117 -286.736836) (xy 339.215446 -286.770067)
			(xy 339.169288 -286.796716) (xy 339.119674 -286.816188) (xy 339.067712 -286.828048) (xy 339.014562 -286.832032)
			(xy 338.961412 -286.828048) (xy 338.90945 -286.816188) (xy 338.859836 -286.796716) (xy 338.813678 -286.770067)
			(xy 338.772007 -286.736836) (xy 338.735755 -286.697765) (xy 338.705731 -286.653728) (xy 338.682605 -286.605707)
			(xy 338.666895 -286.554777) (xy 338.658952 -286.502073) (xy 338.403571 -286.502073) (xy 338.395593 -286.552449)
			(xy 338.379594 -286.601689) (xy 338.356088 -286.647821) (xy 338.325656 -286.689708) (xy 338.289046 -286.726318)
			(xy 338.247159 -286.75675) (xy 338.201027 -286.780256) (xy 338.151787 -286.796255) (xy 338.100649 -286.804354)
			(xy 338.048875 -286.804354) (xy 337.997737 -286.796255) (xy 337.948497 -286.780256) (xy 337.902365 -286.75675)
			(xy 337.860478 -286.726318) (xy 337.823868 -286.689708) (xy 337.793436 -286.647821) (xy 337.76993 -286.601689)
			(xy 337.753931 -286.552449) (xy 337.745832 -286.501311) (xy 337.745324 -286.475424) (xy 337.745858 -286.447716)
			(xy 337.75505 -286.393069) (xy 337.763612 -286.366712) (xy 337.771486 -286.344614) (xy 337.566254 -285.989522)
			(xy 337.543394 -285.985204) (xy 337.518583 -285.980049) (xy 337.470842 -285.963057) (xy 337.426263 -285.93896)
			(xy 337.385896 -285.908325) (xy 337.350693 -285.871874) (xy 337.321482 -285.830466) (xy 337.298951 -285.785075)
			(xy 337.283632 -285.736771) (xy 337.275885 -285.686692) (xy 337.275424 -285.661354) (xy 337.02117 -285.661354)
			(xy 337.020672 -285.688003) (xy 337.012729 -285.740707) (xy 336.997019 -285.791637) (xy 336.973893 -285.839658)
			(xy 336.943869 -285.883695) (xy 336.907617 -285.922766) (xy 336.865946 -285.955997) (xy 336.819788 -285.982646)
			(xy 336.770174 -286.002118) (xy 336.718212 -286.013978) (xy 336.665062 -286.017962) (xy 336.611912 -286.013978)
			(xy 336.55995 -286.002118) (xy 336.510336 -285.982646) (xy 336.464178 -285.955997) (xy 336.422507 -285.922766)
			(xy 336.386255 -285.883695) (xy 336.356231 -285.839658) (xy 336.333105 -285.791637) (xy 336.317395 -285.740707)
			(xy 336.309452 -285.688003) (xy 336.054071 -285.688003) (xy 336.046093 -285.738379) (xy 336.030094 -285.787619)
			(xy 336.006588 -285.833751) (xy 335.976156 -285.875638) (xy 335.939546 -285.912248) (xy 335.897659 -285.94268)
			(xy 335.851527 -285.966186) (xy 335.802287 -285.982185) (xy 335.751149 -285.990284) (xy 335.699375 -285.990284)
			(xy 335.648237 -285.982185) (xy 335.598997 -285.966186) (xy 335.552865 -285.94268) (xy 335.510978 -285.912248)
			(xy 335.474368 -285.875638) (xy 335.443936 -285.833751) (xy 335.42043 -285.787619) (xy 335.404431 -285.738379)
			(xy 335.396332 -285.687241) (xy 335.395824 -285.661354) (xy 335.14157 -285.661354) (xy 335.141072 -285.688003)
			(xy 335.133129 -285.740707) (xy 335.117419 -285.791637) (xy 335.094293 -285.839658) (xy 335.064269 -285.883695)
			(xy 335.028017 -285.922766) (xy 334.986346 -285.955997) (xy 334.940188 -285.982646) (xy 334.890574 -286.002118)
			(xy 334.838612 -286.013978) (xy 334.785462 -286.017962) (xy 334.732312 -286.013978) (xy 334.68035 -286.002118)
			(xy 334.630736 -285.982646) (xy 334.584578 -285.955997) (xy 334.542907 -285.922766) (xy 334.506655 -285.883695)
			(xy 334.476631 -285.839658) (xy 334.453505 -285.791637) (xy 334.437795 -285.740707) (xy 334.429852 -285.688003)
			(xy 334.201272 -285.688003) (xy 334.193329 -285.740707) (xy 334.177619 -285.791637) (xy 334.154493 -285.839658)
			(xy 334.124469 -285.883695) (xy 334.088217 -285.922766) (xy 334.046546 -285.955997) (xy 334.000388 -285.982646)
			(xy 333.950774 -286.002118) (xy 333.898812 -286.013978) (xy 333.845662 -286.017962) (xy 333.792512 -286.013978)
			(xy 333.74055 -286.002118) (xy 333.690936 -285.982646) (xy 333.644778 -285.955997) (xy 333.603107 -285.922766)
			(xy 333.566855 -285.883695) (xy 333.536831 -285.839658) (xy 333.513705 -285.791637) (xy 333.497995 -285.740707)
			(xy 333.490052 -285.688003) (xy 331.903324 -285.688003) (xy 331.903324 -286.502073) (xy 333.020152 -286.502073)
			(xy 333.020152 -286.448775) (xy 333.028095 -286.396071) (xy 333.043805 -286.345141) (xy 333.066931 -286.29712)
			(xy 333.096955 -286.253083) (xy 333.133207 -286.214012) (xy 333.174878 -286.180781) (xy 333.221036 -286.154132)
			(xy 333.27065 -286.13466) (xy 333.322612 -286.1228) (xy 333.375762 -286.118817) (xy 333.428912 -286.1228)
			(xy 333.480874 -286.13466) (xy 333.530488 -286.154132) (xy 333.576646 -286.180781) (xy 333.618317 -286.214012)
			(xy 333.654569 -286.253083) (xy 333.684593 -286.29712) (xy 333.707719 -286.345141) (xy 333.723429 -286.396071)
			(xy 333.731372 -286.448775) (xy 333.73187 -286.475424) (xy 333.986124 -286.475424) (xy 333.986632 -286.449537)
			(xy 333.994731 -286.398399) (xy 334.01073 -286.349159) (xy 334.034236 -286.303027) (xy 334.064668 -286.26114)
			(xy 334.101278 -286.22453) (xy 334.143165 -286.194098) (xy 334.189297 -286.170592) (xy 334.238537 -286.154593)
			(xy 334.289675 -286.146494) (xy 334.341449 -286.146494) (xy 334.392587 -286.154593) (xy 334.441827 -286.170592)
			(xy 334.487959 -286.194098) (xy 334.529846 -286.22453) (xy 334.566456 -286.26114) (xy 334.596888 -286.303027)
			(xy 334.620394 -286.349159) (xy 334.636393 -286.398399) (xy 334.644492 -286.449537) (xy 334.645 -286.475424)
			(xy 334.644511 -286.501304) (xy 334.92624 -286.501304) (xy 334.92624 -286.449496) (xy 334.934344 -286.398327)
			(xy 334.950352 -286.349055) (xy 334.97387 -286.302894) (xy 335.00432 -286.26098) (xy 335.040951 -286.224345)
			(xy 335.082862 -286.19389) (xy 335.12902 -286.170367) (xy 335.17829 -286.154353) (xy 335.229459 -286.146243)
			(xy 335.255362 -286.145732) (xy 335.280855 -286.146231) (xy 335.331232 -286.154087) (xy 335.379796 -286.169618)
			(xy 335.425383 -286.192452) (xy 335.466904 -286.222042) (xy 335.503366 -286.257681) (xy 335.519014 -286.277812)
			(xy 335.93151 -286.277812) (xy 335.947185 -286.257701) (xy 335.98364 -286.222058) (xy 336.025155 -286.192461)
			(xy 336.070737 -286.16962) (xy 336.119296 -286.15408) (xy 336.16967 -286.146213) (xy 336.195162 -286.145732)
			(xy 336.221075 -286.146163) (xy 336.272264 -286.154265) (xy 336.321556 -286.170276) (xy 336.367735 -286.193801)
			(xy 336.409666 -286.22426) (xy 336.446315 -286.260905) (xy 336.47678 -286.302832) (xy 336.50031 -286.349009)
			(xy 336.516326 -286.398299) (xy 336.524434 -286.449487) (xy 336.524434 -286.501313) (xy 336.516326 -286.552501)
			(xy 336.50031 -286.601791) (xy 336.47678 -286.647968) (xy 336.446315 -286.689895) (xy 336.409666 -286.72654)
			(xy 336.367735 -286.756999) (xy 336.321556 -286.780524) (xy 336.272264 -286.796535) (xy 336.221075 -286.804637)
			(xy 336.195162 -286.805116) (xy 336.169668 -286.804653) (xy 336.11929 -286.796786) (xy 336.070727 -286.781247)
			(xy 336.02514 -286.758407) (xy 335.98362 -286.728811) (xy 335.947158 -286.693169) (xy 335.93151 -286.673036)
			(xy 335.519014 -286.673036) (xy 335.503397 -286.693193) (xy 335.466928 -286.728832) (xy 335.425401 -286.758421)
			(xy 335.379808 -286.781254) (xy 335.33124 -286.796785) (xy 335.280857 -286.804641) (xy 335.255362 -286.805116)
			(xy 335.229459 -286.804557) (xy 335.17829 -286.796447) (xy 335.12902 -286.780433) (xy 335.082862 -286.75691)
			(xy 335.040951 -286.726455) (xy 335.00432 -286.68982) (xy 334.97387 -286.647906) (xy 334.950352 -286.601745)
			(xy 334.934344 -286.552473) (xy 334.92624 -286.501304) (xy 334.644511 -286.501304) (xy 334.644476 -286.503132)
			(xy 334.635277 -286.557779) (xy 334.626712 -286.584136) (xy 334.619092 -286.60598) (xy 334.82407 -286.961072)
			(xy 334.84693 -286.96539) (xy 334.871744 -286.970533) (xy 334.919484 -286.987528) (xy 334.964063 -287.011628)
			(xy 335.004428 -287.042264) (xy 335.039631 -287.078717) (xy 335.068841 -287.120126) (xy 335.091372 -287.165518)
			(xy 335.106691 -287.213822) (xy 335.114439 -287.263902) (xy 335.1149 -287.28924) (xy 335.114392 -287.315127)
			(xy 335.114271 -287.315889) (xy 335.369652 -287.315889) (xy 335.369652 -287.262591) (xy 335.377595 -287.209887)
			(xy 335.393305 -287.158957) (xy 335.416431 -287.110936) (xy 335.446455 -287.066899) (xy 335.482707 -287.027828)
			(xy 335.524378 -286.994597) (xy 335.570536 -286.967948) (xy 335.62015 -286.948476) (xy 335.672112 -286.936616)
			(xy 335.725262 -286.932633) (xy 335.778412 -286.936616) (xy 335.830374 -286.948476) (xy 335.879988 -286.967948)
			(xy 335.926146 -286.994597) (xy 335.967817 -287.027828) (xy 336.004069 -287.066899) (xy 336.034093 -287.110936)
			(xy 336.057219 -287.158957) (xy 336.072929 -287.209887) (xy 336.080872 -287.262591) (xy 336.08137 -287.28924)
			(xy 336.080872 -287.315889) (xy 336.309452 -287.315889) (xy 336.309452 -287.262591) (xy 336.317395 -287.209887)
			(xy 336.333105 -287.158957) (xy 336.356231 -287.110936) (xy 336.386255 -287.066899) (xy 336.422507 -287.027828)
			(xy 336.464178 -286.994597) (xy 336.510336 -286.967948) (xy 336.55995 -286.948476) (xy 336.611912 -286.936616)
			(xy 336.665062 -286.932633) (xy 336.718212 -286.936616) (xy 336.770174 -286.948476) (xy 336.819788 -286.967948)
			(xy 336.865946 -286.994597) (xy 336.907617 -287.027828) (xy 336.943869 -287.066899) (xy 336.973893 -287.110936)
			(xy 336.997019 -287.158957) (xy 337.012729 -287.209887) (xy 337.020672 -287.262591) (xy 337.02117 -287.28924)
			(xy 337.020672 -287.315889) (xy 337.249252 -287.315889) (xy 337.249252 -287.262591) (xy 337.257195 -287.209887)
			(xy 337.272905 -287.158957) (xy 337.296031 -287.110936) (xy 337.326055 -287.066899) (xy 337.362307 -287.027828)
			(xy 337.403978 -286.994597) (xy 337.450136 -286.967948) (xy 337.49975 -286.948476) (xy 337.551712 -286.936616)
			(xy 337.604862 -286.932633) (xy 337.658012 -286.936616) (xy 337.709974 -286.948476) (xy 337.759588 -286.967948)
			(xy 337.805746 -286.994597) (xy 337.847417 -287.027828) (xy 337.883669 -287.066899) (xy 337.913693 -287.110936)
			(xy 337.936819 -287.158957) (xy 337.952529 -287.209887) (xy 337.960472 -287.262591) (xy 337.96097 -287.28924)
			(xy 337.960472 -287.315889) (xy 338.189306 -287.315889) (xy 338.189306 -287.262591) (xy 338.197249 -287.209887)
			(xy 338.212959 -287.158957) (xy 338.236085 -287.110936) (xy 338.266109 -287.066899) (xy 338.302361 -287.027828)
			(xy 338.344032 -286.994597) (xy 338.39019 -286.967948) (xy 338.439804 -286.948476) (xy 338.491766 -286.936616)
			(xy 338.544916 -286.932633) (xy 338.598066 -286.936616) (xy 338.650028 -286.948476) (xy 338.699642 -286.967948)
			(xy 338.7458 -286.994597) (xy 338.787471 -287.027828) (xy 338.823723 -287.066899) (xy 338.853747 -287.110936)
			(xy 338.876873 -287.158957) (xy 338.892583 -287.209887) (xy 338.900526 -287.262591) (xy 338.901024 -287.28924)
			(xy 338.900526 -287.315889) (xy 339.129106 -287.315889) (xy 339.129106 -287.262591) (xy 339.137049 -287.209887)
			(xy 339.152759 -287.158957) (xy 339.175885 -287.110936) (xy 339.205909 -287.066899) (xy 339.242161 -287.027828)
			(xy 339.283832 -286.994597) (xy 339.32999 -286.967948) (xy 339.379604 -286.948476) (xy 339.431566 -286.936616)
			(xy 339.484716 -286.932633) (xy 339.537866 -286.936616) (xy 339.589828 -286.948476) (xy 339.639442 -286.967948)
			(xy 339.6856 -286.994597) (xy 339.727271 -287.027828) (xy 339.763523 -287.066899) (xy 339.793547 -287.110936)
			(xy 339.816673 -287.158957) (xy 339.832383 -287.209887) (xy 339.840326 -287.262591) (xy 339.840824 -287.28924)
			(xy 339.840326 -287.315889) (xy 340.068906 -287.315889) (xy 340.068906 -287.262591) (xy 340.076849 -287.209887)
			(xy 340.092559 -287.158957) (xy 340.115685 -287.110936) (xy 340.145709 -287.066899) (xy 340.181961 -287.027828)
			(xy 340.223632 -286.994597) (xy 340.26979 -286.967948) (xy 340.319404 -286.948476) (xy 340.371366 -286.936616)
			(xy 340.424516 -286.932633) (xy 340.477666 -286.936616) (xy 340.529628 -286.948476) (xy 340.579242 -286.967948)
			(xy 340.6254 -286.994597) (xy 340.667071 -287.027828) (xy 340.703323 -287.066899) (xy 340.733347 -287.110936)
			(xy 340.756473 -287.158957) (xy 340.772183 -287.209887) (xy 340.780126 -287.262591) (xy 340.780624 -287.28924)
			(xy 340.780126 -287.315889) (xy 341.008452 -287.315889) (xy 341.008452 -287.262591) (xy 341.016395 -287.209887)
			(xy 341.032105 -287.158957) (xy 341.055231 -287.110936) (xy 341.085255 -287.066899) (xy 341.121507 -287.027828)
			(xy 341.163178 -286.994597) (xy 341.209336 -286.967948) (xy 341.25895 -286.948476) (xy 341.310912 -286.936616)
			(xy 341.364062 -286.932633) (xy 341.417212 -286.936616) (xy 341.469174 -286.948476) (xy 341.518788 -286.967948)
			(xy 341.564946 -286.994597) (xy 341.606617 -287.027828) (xy 341.642869 -287.066899) (xy 341.672893 -287.110936)
			(xy 341.696019 -287.158957) (xy 341.711729 -287.209887) (xy 341.719672 -287.262591) (xy 341.72017 -287.28924)
			(xy 341.719672 -287.315889) (xy 341.948252 -287.315889) (xy 341.948252 -287.262591) (xy 341.956195 -287.209887)
			(xy 341.971905 -287.158957) (xy 341.995031 -287.110936) (xy 342.025055 -287.066899) (xy 342.061307 -287.027828)
			(xy 342.102978 -286.994597) (xy 342.149136 -286.967948) (xy 342.19875 -286.948476) (xy 342.250712 -286.936616)
			(xy 342.303862 -286.932633) (xy 342.357012 -286.936616) (xy 342.408974 -286.948476) (xy 342.458588 -286.967948)
			(xy 342.504746 -286.994597) (xy 342.546417 -287.027828) (xy 342.582669 -287.066899) (xy 342.612693 -287.110936)
			(xy 342.635819 -287.158957) (xy 342.651529 -287.209887) (xy 342.659472 -287.262591) (xy 342.65997 -287.28924)
			(xy 342.659472 -287.315889) (xy 342.888052 -287.315889) (xy 342.888052 -287.262591) (xy 342.895995 -287.209887)
			(xy 342.911705 -287.158957) (xy 342.934831 -287.110936) (xy 342.964855 -287.066899) (xy 343.001107 -287.027828)
			(xy 343.042778 -286.994597) (xy 343.088936 -286.967948) (xy 343.13855 -286.948476) (xy 343.190512 -286.936616)
			(xy 343.243662 -286.932633) (xy 343.296812 -286.936616) (xy 343.348774 -286.948476) (xy 343.398388 -286.967948)
			(xy 343.444546 -286.994597) (xy 343.486217 -287.027828) (xy 343.522469 -287.066899) (xy 343.552493 -287.110936)
			(xy 343.575619 -287.158957) (xy 343.591329 -287.209887) (xy 343.599272 -287.262591) (xy 343.59977 -287.28924)
			(xy 343.599272 -287.315889) (xy 343.827852 -287.315889) (xy 343.827852 -287.262591) (xy 343.835795 -287.209887)
			(xy 343.851505 -287.158957) (xy 343.874631 -287.110936) (xy 343.904655 -287.066899) (xy 343.940907 -287.027828)
			(xy 343.982578 -286.994597) (xy 344.028736 -286.967948) (xy 344.07835 -286.948476) (xy 344.130312 -286.936616)
			(xy 344.183462 -286.932633) (xy 344.236612 -286.936616) (xy 344.288574 -286.948476) (xy 344.338188 -286.967948)
			(xy 344.384346 -286.994597) (xy 344.426017 -287.027828) (xy 344.462269 -287.066899) (xy 344.492293 -287.110936)
			(xy 344.515419 -287.158957) (xy 344.531129 -287.209887) (xy 344.539072 -287.262591) (xy 344.53957 -287.28924)
			(xy 344.539072 -287.315889) (xy 344.767652 -287.315889) (xy 344.767652 -287.262591) (xy 344.775595 -287.209887)
			(xy 344.791305 -287.158957) (xy 344.814431 -287.110936) (xy 344.844455 -287.066899) (xy 344.880707 -287.027828)
			(xy 344.922378 -286.994597) (xy 344.968536 -286.967948) (xy 345.01815 -286.948476) (xy 345.070112 -286.936616)
			(xy 345.123262 -286.932633) (xy 345.176412 -286.936616) (xy 345.228374 -286.948476) (xy 345.277988 -286.967948)
			(xy 345.324146 -286.994597) (xy 345.365817 -287.027828) (xy 345.402069 -287.066899) (xy 345.432093 -287.110936)
			(xy 345.455219 -287.158957) (xy 345.470929 -287.209887) (xy 345.478872 -287.262591) (xy 345.47937 -287.28924)
			(xy 345.478872 -287.315889) (xy 345.707452 -287.315889) (xy 345.707452 -287.262591) (xy 345.715395 -287.209887)
			(xy 345.731105 -287.158957) (xy 345.754231 -287.110936) (xy 345.784255 -287.066899) (xy 345.820507 -287.027828)
			(xy 345.862178 -286.994597) (xy 345.908336 -286.967948) (xy 345.95795 -286.948476) (xy 346.009912 -286.936616)
			(xy 346.063062 -286.932633) (xy 346.116212 -286.936616) (xy 346.168174 -286.948476) (xy 346.217788 -286.967948)
			(xy 346.263946 -286.994597) (xy 346.305617 -287.027828) (xy 346.341869 -287.066899) (xy 346.371893 -287.110936)
			(xy 346.395019 -287.158957) (xy 346.410729 -287.209887) (xy 346.418672 -287.262591) (xy 346.41917 -287.28924)
			(xy 346.418672 -287.315889) (xy 346.647252 -287.315889) (xy 346.647252 -287.262591) (xy 346.655195 -287.209887)
			(xy 346.670905 -287.158957) (xy 346.694031 -287.110936) (xy 346.724055 -287.066899) (xy 346.760307 -287.027828)
			(xy 346.801978 -286.994597) (xy 346.848136 -286.967948) (xy 346.89775 -286.948476) (xy 346.949712 -286.936616)
			(xy 347.002862 -286.932633) (xy 347.056012 -286.936616) (xy 347.107974 -286.948476) (xy 347.157588 -286.967948)
			(xy 347.203746 -286.994597) (xy 347.245417 -287.027828) (xy 347.281669 -287.066899) (xy 347.311693 -287.110936)
			(xy 347.334819 -287.158957) (xy 347.350529 -287.209887) (xy 347.358472 -287.262591) (xy 347.35897 -287.28924)
			(xy 347.358472 -287.315889) (xy 347.587052 -287.315889) (xy 347.587052 -287.262591) (xy 347.594995 -287.209887)
			(xy 347.610705 -287.158957) (xy 347.633831 -287.110936) (xy 347.663855 -287.066899) (xy 347.700107 -287.027828)
			(xy 347.741778 -286.994597) (xy 347.787936 -286.967948) (xy 347.83755 -286.948476) (xy 347.889512 -286.936616)
			(xy 347.942662 -286.932633) (xy 347.995812 -286.936616) (xy 348.047774 -286.948476) (xy 348.097388 -286.967948)
			(xy 348.143546 -286.994597) (xy 348.185217 -287.027828) (xy 348.221469 -287.066899) (xy 348.251493 -287.110936)
			(xy 348.274619 -287.158957) (xy 348.290329 -287.209887) (xy 348.298272 -287.262591) (xy 348.29877 -287.28924)
			(xy 348.298272 -287.315889) (xy 348.526852 -287.315889) (xy 348.526852 -287.262591) (xy 348.534795 -287.209887)
			(xy 348.550505 -287.158957) (xy 348.573631 -287.110936) (xy 348.603655 -287.066899) (xy 348.639907 -287.027828)
			(xy 348.681578 -286.994597) (xy 348.727736 -286.967948) (xy 348.77735 -286.948476) (xy 348.829312 -286.936616)
			(xy 348.882462 -286.932633) (xy 348.935612 -286.936616) (xy 348.987574 -286.948476) (xy 349.037188 -286.967948)
			(xy 349.083346 -286.994597) (xy 349.125017 -287.027828) (xy 349.161269 -287.066899) (xy 349.191293 -287.110936)
			(xy 349.214419 -287.158957) (xy 349.230129 -287.209887) (xy 349.238072 -287.262591) (xy 349.23857 -287.28924)
			(xy 349.238072 -287.315889) (xy 349.230129 -287.368593) (xy 349.214419 -287.419523) (xy 349.191293 -287.467544)
			(xy 349.161269 -287.511581) (xy 349.125017 -287.550652) (xy 349.083346 -287.583883) (xy 349.037188 -287.610532)
			(xy 348.987574 -287.630004) (xy 348.935612 -287.641864) (xy 348.882462 -287.645848) (xy 348.829312 -287.641864)
			(xy 348.77735 -287.630004) (xy 348.727736 -287.610532) (xy 348.681578 -287.583883) (xy 348.639907 -287.550652)
			(xy 348.603655 -287.511581) (xy 348.573631 -287.467544) (xy 348.550505 -287.419523) (xy 348.534795 -287.368593)
			(xy 348.526852 -287.315889) (xy 348.298272 -287.315889) (xy 348.290329 -287.368593) (xy 348.274619 -287.419523)
			(xy 348.251493 -287.467544) (xy 348.221469 -287.511581) (xy 348.185217 -287.550652) (xy 348.143546 -287.583883)
			(xy 348.097388 -287.610532) (xy 348.047774 -287.630004) (xy 347.995812 -287.641864) (xy 347.942662 -287.645848)
			(xy 347.889512 -287.641864) (xy 347.83755 -287.630004) (xy 347.787936 -287.610532) (xy 347.741778 -287.583883)
			(xy 347.700107 -287.550652) (xy 347.663855 -287.511581) (xy 347.633831 -287.467544) (xy 347.610705 -287.419523)
			(xy 347.594995 -287.368593) (xy 347.587052 -287.315889) (xy 347.358472 -287.315889) (xy 347.350529 -287.368593)
			(xy 347.334819 -287.419523) (xy 347.311693 -287.467544) (xy 347.281669 -287.511581) (xy 347.245417 -287.550652)
			(xy 347.203746 -287.583883) (xy 347.157588 -287.610532) (xy 347.107974 -287.630004) (xy 347.056012 -287.641864)
			(xy 347.002862 -287.645848) (xy 346.949712 -287.641864) (xy 346.89775 -287.630004) (xy 346.848136 -287.610532)
			(xy 346.801978 -287.583883) (xy 346.760307 -287.550652) (xy 346.724055 -287.511581) (xy 346.694031 -287.467544)
			(xy 346.670905 -287.419523) (xy 346.655195 -287.368593) (xy 346.647252 -287.315889) (xy 346.418672 -287.315889)
			(xy 346.410729 -287.368593) (xy 346.395019 -287.419523) (xy 346.371893 -287.467544) (xy 346.341869 -287.511581)
			(xy 346.305617 -287.550652) (xy 346.263946 -287.583883) (xy 346.217788 -287.610532) (xy 346.168174 -287.630004)
			(xy 346.116212 -287.641864) (xy 346.063062 -287.645848) (xy 346.009912 -287.641864) (xy 345.95795 -287.630004)
			(xy 345.908336 -287.610532) (xy 345.862178 -287.583883) (xy 345.820507 -287.550652) (xy 345.784255 -287.511581)
			(xy 345.754231 -287.467544) (xy 345.731105 -287.419523) (xy 345.715395 -287.368593) (xy 345.707452 -287.315889)
			(xy 345.478872 -287.315889) (xy 345.470929 -287.368593) (xy 345.455219 -287.419523) (xy 345.432093 -287.467544)
			(xy 345.402069 -287.511581) (xy 345.365817 -287.550652) (xy 345.324146 -287.583883) (xy 345.277988 -287.610532)
			(xy 345.228374 -287.630004) (xy 345.176412 -287.641864) (xy 345.123262 -287.645848) (xy 345.070112 -287.641864)
			(xy 345.01815 -287.630004) (xy 344.968536 -287.610532) (xy 344.922378 -287.583883) (xy 344.880707 -287.550652)
			(xy 344.844455 -287.511581) (xy 344.814431 -287.467544) (xy 344.791305 -287.419523) (xy 344.775595 -287.368593)
			(xy 344.767652 -287.315889) (xy 344.539072 -287.315889) (xy 344.531129 -287.368593) (xy 344.515419 -287.419523)
			(xy 344.492293 -287.467544) (xy 344.462269 -287.511581) (xy 344.426017 -287.550652) (xy 344.384346 -287.583883)
			(xy 344.338188 -287.610532) (xy 344.288574 -287.630004) (xy 344.236612 -287.641864) (xy 344.183462 -287.645848)
			(xy 344.130312 -287.641864) (xy 344.07835 -287.630004) (xy 344.028736 -287.610532) (xy 343.982578 -287.583883)
			(xy 343.940907 -287.550652) (xy 343.904655 -287.511581) (xy 343.874631 -287.467544) (xy 343.851505 -287.419523)
			(xy 343.835795 -287.368593) (xy 343.827852 -287.315889) (xy 343.599272 -287.315889) (xy 343.591329 -287.368593)
			(xy 343.575619 -287.419523) (xy 343.552493 -287.467544) (xy 343.522469 -287.511581) (xy 343.486217 -287.550652)
			(xy 343.444546 -287.583883) (xy 343.398388 -287.610532) (xy 343.348774 -287.630004) (xy 343.296812 -287.641864)
			(xy 343.243662 -287.645848) (xy 343.190512 -287.641864) (xy 343.13855 -287.630004) (xy 343.088936 -287.610532)
			(xy 343.042778 -287.583883) (xy 343.001107 -287.550652) (xy 342.964855 -287.511581) (xy 342.934831 -287.467544)
			(xy 342.911705 -287.419523) (xy 342.895995 -287.368593) (xy 342.888052 -287.315889) (xy 342.659472 -287.315889)
			(xy 342.651529 -287.368593) (xy 342.635819 -287.419523) (xy 342.612693 -287.467544) (xy 342.582669 -287.511581)
			(xy 342.546417 -287.550652) (xy 342.504746 -287.583883) (xy 342.458588 -287.610532) (xy 342.408974 -287.630004)
			(xy 342.357012 -287.641864) (xy 342.303862 -287.645848) (xy 342.250712 -287.641864) (xy 342.19875 -287.630004)
			(xy 342.149136 -287.610532) (xy 342.102978 -287.583883) (xy 342.061307 -287.550652) (xy 342.025055 -287.511581)
			(xy 341.995031 -287.467544) (xy 341.971905 -287.419523) (xy 341.956195 -287.368593) (xy 341.948252 -287.315889)
			(xy 341.719672 -287.315889) (xy 341.711729 -287.368593) (xy 341.696019 -287.419523) (xy 341.672893 -287.467544)
			(xy 341.642869 -287.511581) (xy 341.606617 -287.550652) (xy 341.564946 -287.583883) (xy 341.518788 -287.610532)
			(xy 341.469174 -287.630004) (xy 341.417212 -287.641864) (xy 341.364062 -287.645848) (xy 341.310912 -287.641864)
			(xy 341.25895 -287.630004) (xy 341.209336 -287.610532) (xy 341.163178 -287.583883) (xy 341.121507 -287.550652)
			(xy 341.085255 -287.511581) (xy 341.055231 -287.467544) (xy 341.032105 -287.419523) (xy 341.016395 -287.368593)
			(xy 341.008452 -287.315889) (xy 340.780126 -287.315889) (xy 340.772183 -287.368593) (xy 340.756473 -287.419523)
			(xy 340.733347 -287.467544) (xy 340.703323 -287.511581) (xy 340.667071 -287.550652) (xy 340.6254 -287.583883)
			(xy 340.579242 -287.610532) (xy 340.529628 -287.630004) (xy 340.477666 -287.641864) (xy 340.424516 -287.645848)
			(xy 340.371366 -287.641864) (xy 340.319404 -287.630004) (xy 340.26979 -287.610532) (xy 340.223632 -287.583883)
			(xy 340.181961 -287.550652) (xy 340.145709 -287.511581) (xy 340.115685 -287.467544) (xy 340.092559 -287.419523)
			(xy 340.076849 -287.368593) (xy 340.068906 -287.315889) (xy 339.840326 -287.315889) (xy 339.832383 -287.368593)
			(xy 339.816673 -287.419523) (xy 339.793547 -287.467544) (xy 339.763523 -287.511581) (xy 339.727271 -287.550652)
			(xy 339.6856 -287.583883) (xy 339.639442 -287.610532) (xy 339.589828 -287.630004) (xy 339.537866 -287.641864)
			(xy 339.484716 -287.645848) (xy 339.431566 -287.641864) (xy 339.379604 -287.630004) (xy 339.32999 -287.610532)
			(xy 339.283832 -287.583883) (xy 339.242161 -287.550652) (xy 339.205909 -287.511581) (xy 339.175885 -287.467544)
			(xy 339.152759 -287.419523) (xy 339.137049 -287.368593) (xy 339.129106 -287.315889) (xy 338.900526 -287.315889)
			(xy 338.892583 -287.368593) (xy 338.876873 -287.419523) (xy 338.853747 -287.467544) (xy 338.823723 -287.511581)
			(xy 338.787471 -287.550652) (xy 338.7458 -287.583883) (xy 338.699642 -287.610532) (xy 338.650028 -287.630004)
			(xy 338.598066 -287.641864) (xy 338.544916 -287.645848) (xy 338.491766 -287.641864) (xy 338.439804 -287.630004)
			(xy 338.39019 -287.610532) (xy 338.344032 -287.583883) (xy 338.302361 -287.550652) (xy 338.266109 -287.511581)
			(xy 338.236085 -287.467544) (xy 338.212959 -287.419523) (xy 338.197249 -287.368593) (xy 338.189306 -287.315889)
			(xy 337.960472 -287.315889) (xy 337.952529 -287.368593) (xy 337.936819 -287.419523) (xy 337.913693 -287.467544)
			(xy 337.883669 -287.511581) (xy 337.847417 -287.550652) (xy 337.805746 -287.583883) (xy 337.759588 -287.610532)
			(xy 337.709974 -287.630004) (xy 337.658012 -287.641864) (xy 337.604862 -287.645848) (xy 337.551712 -287.641864)
			(xy 337.49975 -287.630004) (xy 337.450136 -287.610532) (xy 337.403978 -287.583883) (xy 337.362307 -287.550652)
			(xy 337.326055 -287.511581) (xy 337.296031 -287.467544) (xy 337.272905 -287.419523) (xy 337.257195 -287.368593)
			(xy 337.249252 -287.315889) (xy 337.020672 -287.315889) (xy 337.012729 -287.368593) (xy 336.997019 -287.419523)
			(xy 336.973893 -287.467544) (xy 336.943869 -287.511581) (xy 336.907617 -287.550652) (xy 336.865946 -287.583883)
			(xy 336.819788 -287.610532) (xy 336.770174 -287.630004) (xy 336.718212 -287.641864) (xy 336.665062 -287.645848)
			(xy 336.611912 -287.641864) (xy 336.55995 -287.630004) (xy 336.510336 -287.610532) (xy 336.464178 -287.583883)
			(xy 336.422507 -287.550652) (xy 336.386255 -287.511581) (xy 336.356231 -287.467544) (xy 336.333105 -287.419523)
			(xy 336.317395 -287.368593) (xy 336.309452 -287.315889) (xy 336.080872 -287.315889) (xy 336.072929 -287.368593)
			(xy 336.057219 -287.419523) (xy 336.034093 -287.467544) (xy 336.004069 -287.511581) (xy 335.967817 -287.550652)
			(xy 335.926146 -287.583883) (xy 335.879988 -287.610532) (xy 335.830374 -287.630004) (xy 335.778412 -287.641864)
			(xy 335.725262 -287.645848) (xy 335.672112 -287.641864) (xy 335.62015 -287.630004) (xy 335.570536 -287.610532)
			(xy 335.524378 -287.583883) (xy 335.482707 -287.550652) (xy 335.446455 -287.511581) (xy 335.416431 -287.467544)
			(xy 335.393305 -287.419523) (xy 335.377595 -287.368593) (xy 335.369652 -287.315889) (xy 335.114271 -287.315889)
			(xy 335.106293 -287.366265) (xy 335.090294 -287.415505) (xy 335.066788 -287.461637) (xy 335.036356 -287.503524)
			(xy 334.999746 -287.540134) (xy 334.957859 -287.570566) (xy 334.911727 -287.594072) (xy 334.862487 -287.610071)
			(xy 334.811349 -287.61817) (xy 334.759575 -287.61817) (xy 334.708437 -287.610071) (xy 334.659197 -287.594072)
			(xy 334.613065 -287.570566) (xy 334.571178 -287.540134) (xy 334.534568 -287.503524) (xy 334.504136 -287.461637)
			(xy 334.48063 -287.415505) (xy 334.464631 -287.366265) (xy 334.456532 -287.315127) (xy 334.456024 -287.28924)
			(xy 334.456562 -287.261532) (xy 334.465751 -287.206885) (xy 334.474312 -287.180528) (xy 334.481932 -287.158684)
			(xy 334.276954 -286.803592) (xy 334.254094 -286.799274) (xy 334.229299 -286.794053) (xy 334.181562 -286.777067)
			(xy 334.136987 -286.752976) (xy 334.096622 -286.722349) (xy 334.061419 -286.685906) (xy 334.032206 -286.644507)
			(xy 334.009672 -286.599125) (xy 333.994346 -286.55083) (xy 333.98659 -286.500758) (xy 333.986124 -286.475424)
			(xy 333.73187 -286.475424) (xy 333.731372 -286.502073) (xy 333.723429 -286.554777) (xy 333.707719 -286.605707)
			(xy 333.684593 -286.653728) (xy 333.654569 -286.697765) (xy 333.618317 -286.736836) (xy 333.576646 -286.770067)
			(xy 333.530488 -286.796716) (xy 333.480874 -286.816188) (xy 333.428912 -286.828048) (xy 333.375762 -286.832032)
			(xy 333.322612 -286.828048) (xy 333.27065 -286.816188) (xy 333.221036 -286.796716) (xy 333.174878 -286.770067)
			(xy 333.133207 -286.736836) (xy 333.096955 -286.697765) (xy 333.066931 -286.653728) (xy 333.043805 -286.605707)
			(xy 333.028095 -286.554777) (xy 333.020152 -286.502073) (xy 331.903324 -286.502073) (xy 331.903324 -287.906206)
			(xy 332.126823 -288.129705) (xy 334.899752 -288.129705) (xy 334.899752 -288.076407) (xy 334.907695 -288.023703)
			(xy 334.923405 -287.972773) (xy 334.946531 -287.924752) (xy 334.976555 -287.880715) (xy 335.012807 -287.841644)
			(xy 335.054478 -287.808413) (xy 335.100636 -287.781764) (xy 335.15025 -287.762292) (xy 335.202212 -287.750432)
			(xy 335.255362 -287.746449) (xy 335.308512 -287.750432) (xy 335.360474 -287.762292) (xy 335.410088 -287.781764)
			(xy 335.456246 -287.808413) (xy 335.497917 -287.841644) (xy 335.534169 -287.880715) (xy 335.564193 -287.924752)
			(xy 335.587319 -287.972773) (xy 335.603029 -288.023703) (xy 335.610972 -288.076407) (xy 335.61147 -288.103056)
			(xy 335.610972 -288.129705) (xy 335.603029 -288.182409) (xy 335.587319 -288.233339) (xy 335.564193 -288.28136)
			(xy 335.534169 -288.325397) (xy 335.497917 -288.364468) (xy 335.456246 -288.397699) (xy 335.410088 -288.424348)
			(xy 335.360474 -288.44382) (xy 335.308512 -288.45568) (xy 335.255362 -288.459664) (xy 335.202212 -288.45568)
			(xy 335.15025 -288.44382) (xy 335.100636 -288.424348) (xy 335.054478 -288.397699) (xy 335.012807 -288.364468)
			(xy 334.976555 -288.325397) (xy 334.946531 -288.28136) (xy 334.923405 -288.233339) (xy 334.907695 -288.182409)
			(xy 334.899752 -288.129705) (xy 332.126823 -288.129705) (xy 333.107284 -289.110166)
		)
		(stroke
			(width 0)
			(type solid)
		)
		(fill yes)
		(layer "B.Cu")
		(net "PVCCFA_EHV_FIVRA_CPU0")
	)
	(gr_poly
		(pts
			(xy 332.287626 -333.243428) (xy 332.287626 -328.60107) (xy 332.515464 -328.373232) (xy 341.253064 -328.373232)
			(xy 342.048084 -327.578212) (xy 342.048084 -325.402702) (xy 342.478614 -324.972172) (xy 373.111268 -324.972172)
			(xy 373.330978 -325.191882) (xy 373.330978 -328.27595) (xy 373.45874 -328.403712) (xy 381.824738 -328.403712)
			(xy 382.170178 -328.749152) (xy 382.170178 -331.317346) (xy 382.350264 -331.497432) (xy 389.886444 -331.497432)
			(xy 390.803384 -330.580492) (xy 390.803384 -282.493466) (xy 386.998972 -278.689308) (xy 386.97535 -278.69134)
			(xy 386.944362 -278.69261) (xy 386.916381 -278.692058) (xy 386.861108 -278.683298) (xy 386.807886 -278.666001)
			(xy 386.758025 -278.640591) (xy 386.712752 -278.607694) (xy 386.673183 -278.56812) (xy 386.640291 -278.522844)
			(xy 386.614886 -278.472981) (xy 386.597593 -278.419757) (xy 386.588839 -278.364483) (xy 386.588254 -278.336502)
			(xy 386.589524 -278.30526) (xy 386.59181 -278.281892) (xy 386.53212 -278.222202) (xy 386.522003 -278.212741)
			(xy 386.497885 -278.199144) (xy 386.470998 -278.192532) (xy 386.443324 -278.193391) (xy 386.416901 -278.201659)
			(xy 386.393673 -278.216727) (xy 386.375351 -278.237485) (xy 386.363284 -278.262405) (xy 386.358362 -278.289651)
			(xy 386.359146 -278.303482) (xy 386.36067 -278.336248) (xy 386.36067 -278.336502) (xy 386.360164 -278.363579)
			(xy 386.351964 -278.417107) (xy 386.335753 -278.468777) (xy 386.311904 -278.517396) (xy 386.280968 -278.561844)
			(xy 386.243659 -278.601094) (xy 386.200836 -278.634242) (xy 386.153488 -278.660524) (xy 386.102706 -278.679333)
			(xy 386.049662 -278.690235) (xy 385.995578 -278.69298) (xy 385.941702 -278.687503) (xy 385.889277 -278.673931)
			(xy 385.839512 -278.652578) (xy 385.793554 -278.623935) (xy 385.752463 -278.588663) (xy 385.717187 -278.547575)
			(xy 385.688539 -278.50162) (xy 385.66718 -278.451857) (xy 385.653603 -278.399433) (xy 385.648121 -278.345558)
			(xy 385.65086 -278.291474) (xy 385.661757 -278.238428) (xy 385.680561 -278.187645) (xy 385.706838 -278.140294)
			(xy 385.739982 -278.097468) (xy 385.779228 -278.060154) (xy 385.823672 -278.029214) (xy 385.872289 -278.005361)
			(xy 385.923957 -277.989144) (xy 385.977485 -277.980938) (xy 386.004562 -277.980394) (xy 386.004816 -277.980394)
			(xy 386.037582 -277.981918) (xy 386.051404 -277.982725) (xy 386.078633 -277.977769) (xy 386.103531 -277.965684)
			(xy 386.12427 -277.947357) (xy 386.139327 -277.924135) (xy 386.147595 -277.897723) (xy 386.148468 -277.870061)
			(xy 386.141882 -277.84318) (xy 386.12832 -277.819055) (xy 386.118862 -277.808944) (xy 385.47548 -277.165562)
			(xy 385.367784 -277.05812) (xy 384.58267 -277.05812) (xy 384.57378 -277.057866) (xy 384.194558 -277.057866)
			(xy 384.189986 -277.058628) (xy 384.173878 -277.061456) (xy 384.141315 -277.064511) (xy 384.124962 -277.064724)
			(xy 384.108609 -277.064516) (xy 384.076045 -277.061462) (xy 384.059938 -277.058628) (xy 384.055366 -277.057866)
			(xy 383.676144 -277.057866) (xy 383.667254 -277.05812) (xy 383.613914 -277.05812) (xy 383.605024 -277.057866)
			(xy 382.765808 -277.057866) (xy 382.756918 -277.05812) (xy 382.703324 -277.05812) (xy 382.694434 -277.057866)
			(xy 382.315212 -277.057866) (xy 382.31064 -277.058628) (xy 382.294532 -277.061454) (xy 382.261969 -277.064504)
			(xy 382.245616 -277.064724) (xy 382.229263 -277.064518) (xy 382.196698 -277.06147) (xy 382.180592 -277.058628)
			(xy 382.17602 -277.057866) (xy 381.796798 -277.057866) (xy 381.787908 -277.05812) (xy 381.734314 -277.05812)
			(xy 381.725424 -277.057866) (xy 380.886208 -277.057866) (xy 380.877318 -277.05812) (xy 380.82347 -277.05812)
			(xy 380.81458 -277.057866) (xy 380.435358 -277.057866) (xy 380.430786 -277.058628) (xy 380.414678 -277.061456)
			(xy 380.382115 -277.064511) (xy 380.365762 -277.064724) (xy 380.349409 -277.064516) (xy 380.316845 -277.061462)
			(xy 380.300738 -277.058628) (xy 380.296166 -277.057866) (xy 379.916944 -277.057866) (xy 379.908054 -277.05812)
			(xy 379.854714 -277.05812) (xy 379.845824 -277.057866) (xy 379.006608 -277.057866) (xy 378.997718 -277.05812)
			(xy 378.914914 -277.05812) (xy 378.906024 -277.057866) (xy 378.066808 -277.057866) (xy 378.057918 -277.05812)
			(xy 378.004324 -277.05812) (xy 377.995434 -277.057866) (xy 377.616212 -277.057866) (xy 377.61164 -277.058628)
			(xy 377.595532 -277.061454) (xy 377.562969 -277.064504) (xy 377.546616 -277.064724) (xy 377.530263 -277.064518)
			(xy 377.497698 -277.06147) (xy 377.481592 -277.058628) (xy 377.47702 -277.057866) (xy 377.097798 -277.057866)
			(xy 377.088908 -277.05812) (xy 377.035314 -277.05812) (xy 377.026424 -277.057866) (xy 376.187208 -277.057866)
			(xy 376.178318 -277.05812) (xy 376.124724 -277.05812) (xy 376.115834 -277.057866) (xy 375.736612 -277.057866)
			(xy 375.73204 -277.058628) (xy 375.715932 -277.061454) (xy 375.683369 -277.064504) (xy 375.667016 -277.064724)
			(xy 375.650663 -277.064518) (xy 375.618098 -277.06147) (xy 375.601992 -277.058628) (xy 375.59742 -277.057866)
			(xy 375.218198 -277.057866) (xy 375.209308 -277.05812) (xy 375.155714 -277.05812) (xy 375.146824 -277.057866)
			(xy 374.307608 -277.057866) (xy 374.298718 -277.05812) (xy 374.24487 -277.05812) (xy 374.23598 -277.057866)
			(xy 373.856758 -277.057866) (xy 373.852186 -277.058628) (xy 373.836078 -277.061456) (xy 373.803515 -277.064511)
			(xy 373.787162 -277.064724) (xy 373.770809 -277.064516) (xy 373.738245 -277.061462) (xy 373.722138 -277.058628)
			(xy 373.717566 -277.057866) (xy 373.338344 -277.057866) (xy 373.329454 -277.05812) (xy 373.276114 -277.05812)
			(xy 373.267224 -277.057866) (xy 372.428008 -277.057866) (xy 372.419118 -277.05812) (xy 372.336314 -277.05812)
			(xy 372.327424 -277.057866) (xy 371.488208 -277.057866) (xy 371.479318 -277.05812) (xy 371.425724 -277.05812)
			(xy 371.416834 -277.057866) (xy 371.037612 -277.057866) (xy 371.03304 -277.058628) (xy 371.016932 -277.061454)
			(xy 370.984369 -277.064504) (xy 370.968016 -277.064724) (xy 370.951663 -277.064518) (xy 370.919098 -277.06147)
			(xy 370.902992 -277.058628) (xy 370.89842 -277.057866) (xy 370.519198 -277.057866) (xy 370.510308 -277.05812)
			(xy 370.485924 -277.05812) (xy 370.477034 -277.057866) (xy 370.097812 -277.057866) (xy 370.09324 -277.058628)
			(xy 370.077132 -277.061454) (xy 370.044569 -277.064504) (xy 370.028216 -277.064724) (xy 370.011863 -277.064518)
			(xy 369.979298 -277.06147) (xy 369.963192 -277.058628) (xy 369.95862 -277.057866) (xy 369.579398 -277.057866)
			(xy 369.570508 -277.05812) (xy 369.546124 -277.05812) (xy 369.537234 -277.057866) (xy 369.158012 -277.057866)
			(xy 369.15344 -277.058628) (xy 369.137332 -277.061454) (xy 369.104769 -277.064504) (xy 369.088416 -277.064724)
			(xy 369.072063 -277.064518) (xy 369.039498 -277.06147) (xy 369.023392 -277.058628) (xy 369.01882 -277.057866)
			(xy 368.639598 -277.057866) (xy 368.630708 -277.05812) (xy 368.60607 -277.05812) (xy 368.59718 -277.057866)
			(xy 368.216688 -277.057866) (xy 368.21237 -277.058628) (xy 368.196509 -277.061355) (xy 368.164455 -277.064278)
			(xy 368.148362 -277.06447) (xy 368.132269 -277.064281) (xy 368.100215 -277.061359) (xy 368.084354 -277.058628)
			(xy 368.080036 -277.057866) (xy 367.699544 -277.057866) (xy 367.690654 -277.05812) (xy 367.66627 -277.05812)
			(xy 367.65738 -277.057866) (xy 367.278158 -277.057866) (xy 367.273586 -277.058628) (xy 367.257478 -277.061456)
			(xy 367.224915 -277.064511) (xy 367.208562 -277.064724) (xy 367.192209 -277.064516) (xy 367.159645 -277.061462)
			(xy 367.143538 -277.058628) (xy 367.138966 -277.057866) (xy 366.759744 -277.057866) (xy 366.750854 -277.05812)
			(xy 366.72647 -277.05812) (xy 366.71758 -277.057866) (xy 366.337088 -277.057866) (xy 366.33277 -277.058628)
			(xy 366.316909 -277.061355) (xy 366.284855 -277.064278) (xy 366.268762 -277.06447) (xy 366.252669 -277.064281)
			(xy 366.220615 -277.061359) (xy 366.204754 -277.058628) (xy 366.200436 -277.057866) (xy 365.397288 -277.057866)
			(xy 365.39297 -277.058628) (xy 365.377109 -277.061355) (xy 365.345055 -277.064278) (xy 365.328962 -277.06447)
			(xy 365.312869 -277.064281) (xy 365.280815 -277.061359) (xy 365.264954 -277.058628) (xy 365.260636 -277.057866)
			(xy 365.054134 -277.057866) (xy 364.858808 -276.86254) (xy 364.849059 -276.853391) (xy 364.825879 -276.840087)
			(xy 364.80004 -276.833257) (xy 364.773313 -276.833369) (xy 364.747532 -276.840415) (xy 364.724464 -276.853913)
			(xy 364.705691 -276.872936) (xy 364.698788 -276.884384) (xy 364.685111 -276.907465) (xy 364.651906 -276.949601)
			(xy 364.612753 -276.986277) (xy 364.56854 -277.016663) (xy 364.520268 -277.04007) (xy 364.46903 -277.055969)
			(xy 364.415986 -277.063999) (xy 364.389162 -277.06447) (xy 364.361182 -277.063918) (xy 364.305912 -277.055158)
			(xy 364.252692 -277.03786) (xy 364.202834 -277.012449) (xy 364.157565 -276.979552) (xy 364.117999 -276.939978)
			(xy 364.085111 -276.894701) (xy 364.059711 -276.844838) (xy 364.042424 -276.791614) (xy 364.033676 -276.736342)
			(xy 364.033054 -276.708362) (xy 364.033542 -276.68154) (xy 364.041588 -276.628502) (xy 364.057494 -276.57727)
			(xy 364.0809 -276.529001) (xy 364.111276 -276.484785) (xy 364.147936 -276.445623) (xy 364.190053 -276.412398)
			(xy 364.21314 -276.398736) (xy 364.224578 -276.391806) (xy 364.243631 -276.37305) (xy 364.257153 -276.349986)
			(xy 364.264214 -276.3242) (xy 364.264328 -276.297465) (xy 364.257488 -276.271619) (xy 364.244164 -276.24844)
			(xy 364.234984 -276.238716) (xy 364.158276 -276.162008) (xy 364.123478 -276.186646) (xy 364.100918 -276.20178)
			(xy 364.052179 -276.22577) (xy 364.000366 -276.242089) (xy 363.946677 -276.250361) (xy 363.919516 -276.250908)
			(xy 363.919262 -276.250908) (xy 363.891281 -276.250356) (xy 363.836008 -276.241596) (xy 363.782786 -276.224299)
			(xy 363.732925 -276.198888) (xy 363.687653 -276.165992) (xy 363.648084 -276.126418) (xy 363.615192 -276.081142)
			(xy 363.589787 -276.031279) (xy 363.572495 -275.978055) (xy 363.563741 -275.922781) (xy 363.563154 -275.8948)
			(xy 363.563154 -275.894546) (xy 363.563665 -275.867382) (xy 363.571923 -275.813686) (xy 363.588254 -275.761871)
			(xy 363.612277 -275.713144) (xy 363.627416 -275.690584) (xy 363.652054 -275.655786) (xy 363.433106 -275.436838)
			(xy 363.415072 -275.435314) (xy 363.387519 -275.432146) (xy 363.333799 -275.41836) (xy 363.282873 -275.396401)
			(xy 363.235973 -275.366799) (xy 363.194239 -275.330274) (xy 363.176058 -275.30933) (xy 362.782358 -275.30933)
			(xy 362.765346 -275.32892) (xy 362.72662 -275.363448) (xy 362.683293 -275.391991) (xy 362.636282 -275.413944)
			(xy 362.586584 -275.428842) (xy 362.53525 -275.436372) (xy 362.483366 -275.436372) (xy 362.432032 -275.428842)
			(xy 362.382334 -275.413944) (xy 362.335323 -275.391991) (xy 362.291996 -275.363448) (xy 362.25327 -275.32892)
			(xy 362.236258 -275.30933) (xy 361.842812 -275.30933) (xy 361.825798 -275.328917) (xy 361.78707 -275.363438)
			(xy 361.743742 -275.391973) (xy 361.696732 -275.413919) (xy 361.647034 -275.428812) (xy 361.595702 -275.436334)
			(xy 361.569762 -275.436838) (xy 361.54178 -275.436286) (xy 361.486506 -275.427527) (xy 361.433282 -275.410229)
			(xy 361.383419 -275.38482) (xy 361.338144 -275.351923) (xy 361.298572 -275.31235) (xy 361.265676 -275.267075)
			(xy 361.240268 -275.217211) (xy 361.222971 -275.163987) (xy 361.214213 -275.108712) (xy 361.213654 -275.08073)
			(xy 361.213654 -275.080222) (xy 361.214064 -275.056469) (xy 361.220407 -275.009386) (xy 361.232942 -274.963562)
			(xy 361.241848 -274.941538) (xy 361.25531 -274.910042) (xy 361.116118 -274.77085) (xy 361.116118 -269.99311)
			(xy 361.685586 -269.423642) (xy 361.68457 -269.401036) (xy 361.684062 -269.38351) (xy 361.684516 -269.358168)
			(xy 361.691716 -269.307998) (xy 361.705959 -269.259357) (xy 361.726955 -269.213226) (xy 361.754281 -269.17054)
			(xy 361.787385 -269.13216) (xy 361.825597 -269.098863) (xy 361.868145 -269.071321) (xy 361.914168 -269.050091)
			(xy 361.938316 -269.042388) (xy 361.974638 -269.031466) (xy 361.974638 -268.91234) (xy 361.974128 -268.897753)
			(xy 361.965813 -268.869786) (xy 361.949936 -268.845308) (xy 361.927789 -268.826313) (xy 361.901178 -268.814348)
			(xy 361.872271 -268.81039) (xy 361.843423 -268.81476) (xy 361.816986 -268.827103) (xy 361.805728 -268.836394)
			(xy 361.786097 -268.85315) (xy 361.74291 -268.881411) (xy 361.696097 -268.903144) (xy 361.646638 -268.917894)
			(xy 361.595568 -268.925351) (xy 361.569762 -268.925802) (xy 361.543115 -268.925302) (xy 361.490417 -268.917353)
			(xy 361.439492 -268.90164) (xy 361.391477 -268.878513) (xy 361.347446 -268.848489) (xy 361.30838 -268.812237)
			(xy 361.275154 -268.770569) (xy 361.248508 -268.724414) (xy 361.229039 -268.674803) (xy 361.217181 -268.622845)
			(xy 361.213198 -268.5697) (xy 361.217181 -268.516555) (xy 361.229039 -268.464597) (xy 361.248508 -268.414986)
			(xy 361.275154 -268.368831) (xy 361.30838 -268.327163) (xy 361.347446 -268.290911) (xy 361.391477 -268.260887)
			(xy 361.439492 -268.23776) (xy 361.490417 -268.222047) (xy 361.543115 -268.214098) (xy 361.569762 -268.213586)
			(xy 361.595568 -268.214043) (xy 361.646641 -268.22149) (xy 361.696103 -268.236234) (xy 361.742917 -268.257966)
			(xy 361.786103 -268.28623) (xy 361.805728 -268.302994) (xy 361.816972 -268.312302) (xy 361.843406 -268.324659)
			(xy 361.872255 -268.329038) (xy 361.901165 -268.32508) (xy 361.927776 -268.31311) (xy 361.949917 -268.294104)
			(xy 361.96578 -268.269614) (xy 361.974072 -268.241637) (xy 361.974638 -268.227048) (xy 361.974638 -268.107922)
			(xy 361.938316 -268.097254) (xy 361.912698 -268.089134) (xy 361.864066 -268.066267) (xy 361.819423 -268.036351)
			(xy 361.779782 -268.000067) (xy 361.746044 -267.958238) (xy 361.718974 -267.911815) (xy 361.699187 -267.861851)
			(xy 361.687132 -267.809481) (xy 361.683084 -267.755894) (xy 361.687134 -267.702307) (xy 361.699191 -267.649937)
			(xy 361.718979 -267.599974) (xy 361.746051 -267.553551) (xy 361.779791 -267.511724) (xy 361.819433 -267.475441)
			(xy 361.864077 -267.445527) (xy 361.912709 -267.422661) (xy 361.938316 -267.414502) (xy 361.974638 -267.403834)
			(xy 361.974638 -267.284454) (xy 361.97413 -267.269865) (xy 361.965817 -267.241895) (xy 361.94994 -267.217413)
			(xy 361.927792 -267.198415) (xy 361.901179 -267.186449) (xy 361.872269 -267.18249) (xy 361.843419 -267.186862)
			(xy 361.816979 -267.199207) (xy 361.805728 -267.208508) (xy 361.786098 -267.225267) (xy 361.742914 -267.253535)
			(xy 361.696101 -267.275274) (xy 361.646641 -267.290027) (xy 361.595569 -267.297486) (xy 361.569762 -267.297916)
			(xy 361.543114 -267.297416) (xy 361.490414 -267.289467) (xy 361.439487 -267.273753) (xy 361.39147 -267.250625)
			(xy 361.347437 -267.2206) (xy 361.30837 -267.184347) (xy 361.275142 -267.142677) (xy 361.248496 -267.09652)
			(xy 361.229026 -267.046907) (xy 361.217167 -266.994947) (xy 361.213184 -266.9418) (xy 361.217167 -266.888653)
			(xy 361.229026 -266.836693) (xy 361.248496 -266.78708) (xy 361.275142 -266.740923) (xy 361.30837 -266.699253)
			(xy 361.347437 -266.663) (xy 361.39147 -266.632975) (xy 361.439487 -266.609847) (xy 361.490414 -266.594133)
			(xy 361.543114 -266.586184) (xy 361.569762 -266.5857) (xy 361.595569 -266.586156) (xy 361.646643 -266.593602)
			(xy 361.696107 -266.608343) (xy 361.742924 -266.630071) (xy 361.786114 -266.658331) (xy 361.805728 -266.675108)
			(xy 361.816973 -266.684415) (xy 361.843408 -266.696771) (xy 361.872257 -266.701148) (xy 361.901167 -266.697191)
			(xy 361.927779 -266.685221) (xy 361.949921 -266.666216) (xy 361.965786 -266.641727) (xy 361.97408 -266.613751)
			(xy 361.974638 -266.599162) (xy 361.974638 -266.48029) (xy 361.938316 -266.469622) (xy 361.914116 -266.461967)
			(xy 361.868005 -266.440759) (xy 361.825372 -266.413218) (xy 361.78708 -266.379904) (xy 361.753905 -266.341492)
			(xy 361.72652 -266.298759) (xy 361.705479 -266.252571) (xy 361.691207 -266.203863) (xy 361.683996 -266.153623)
			(xy 361.683554 -266.128246) (xy 361.684071 -266.100257) (xy 361.69282 -266.044968) (xy 361.710112 -265.991728)
			(xy 361.735519 -265.941848) (xy 361.768416 -265.896558) (xy 361.807994 -265.856971) (xy 361.853277 -265.824063)
			(xy 361.90315 -265.798644) (xy 361.956386 -265.78134) (xy 362.011673 -265.772577) (xy 362.039662 -265.772138)
			(xy 362.067919 -265.772676) (xy 362.123724 -265.781592) (xy 362.177423 -265.799207) (xy 362.227667 -265.825078)
			(xy 362.273196 -265.858557) (xy 362.293408 -265.87831) (xy 362.293408 -265.878564) (xy 362.329476 -265.914632)
			(xy 362.427266 -265.816842) (xy 362.437287 -265.806164) (xy 362.45129 -265.780459) (xy 362.457419 -265.751836)
			(xy 362.455171 -265.72265) (xy 362.44473 -265.695304) (xy 362.426956 -265.672046) (xy 362.40331 -265.654791)
			(xy 362.389674 -265.649456) (xy 362.364107 -265.639784) (xy 362.316053 -265.613729) (xy 362.272544 -265.580639)
			(xy 362.234603 -265.541289) (xy 362.203119 -265.496604) (xy 362.178832 -265.447633) (xy 362.162313 -265.395526)
			(xy 362.15395 -265.341507) (xy 362.153454 -265.314176) (xy 362.153952 -265.287527) (xy 362.161895 -265.234823)
			(xy 362.177605 -265.183893) (xy 362.200731 -265.135872) (xy 362.230755 -265.091835) (xy 362.267007 -265.052764)
			(xy 362.308678 -265.019533) (xy 362.354836 -264.992884) (xy 362.40445 -264.973412) (xy 362.456412 -264.961552)
			(xy 362.509562 -264.957569) (xy 362.562712 -264.961552) (xy 362.614674 -264.973412) (xy 362.664288 -264.992884)
			(xy 362.710446 -265.019533) (xy 362.752117 -265.052764) (xy 362.788369 -265.091835) (xy 362.818393 -265.135872)
			(xy 362.841519 -265.183893) (xy 362.857229 -265.234823) (xy 362.865172 -265.287527) (xy 362.86567 -265.314176)
			(xy 362.865304 -265.337192) (xy 362.859367 -265.38284) (xy 362.847602 -265.427344) (xy 362.839254 -265.448796)
			(xy 362.834331 -265.462149) (xy 362.831292 -265.490435) (xy 362.83617 -265.518461) (xy 362.848588 -265.544056)
			(xy 362.867581 -265.565235) (xy 362.891679 -265.580355) (xy 362.919011 -265.588244) (xy 362.933234 -265.58875)
			(xy 363.001814 -265.58875) (xy 363.125512 -265.465052) (xy 363.11459 -265.434826) (xy 363.104761 -265.405636)
			(xy 363.094153 -265.344969) (xy 363.093508 -265.314176) (xy 363.093943 -265.288626) (xy 363.101239 -265.23805)
			(xy 363.115691 -265.189037) (xy 363.137002 -265.142594) (xy 363.164735 -265.099674) (xy 363.19832 -265.061162)
			(xy 363.237066 -265.027847) (xy 363.280177 -265.000414) (xy 363.303312 -264.989564) (xy 363.303312 -264.90041)
			(xy 363.302709 -264.885308) (xy 363.293783 -264.856449) (xy 363.276825 -264.83145) (xy 363.25331 -264.812488)
			(xy 363.225285 -264.801213) (xy 363.19519 -264.798607) (xy 363.165644 -264.804896) (xy 363.152182 -264.811764)
			(xy 363.125579 -264.825802) (xy 363.068827 -264.845725) (xy 363.009536 -264.855836) (xy 362.979462 -264.856468)
			(xy 362.952818 -264.855967) (xy 362.900125 -264.84802) (xy 362.849204 -264.832308) (xy 362.801195 -264.809183)
			(xy 362.757167 -264.779162) (xy 362.718106 -264.742914) (xy 362.684882 -264.701249) (xy 362.65824 -264.655099)
			(xy 362.638772 -264.605493) (xy 362.626915 -264.55354) (xy 362.622933 -264.5004) (xy 362.626915 -264.44726)
			(xy 362.638772 -264.395307) (xy 362.65824 -264.345701) (xy 362.684882 -264.299551) (xy 362.718106 -264.257886)
			(xy 362.757167 -264.221638) (xy 362.801195 -264.191617) (xy 362.849204 -264.168492) (xy 362.900125 -264.15278)
			(xy 362.952818 -264.144833) (xy 362.979462 -264.144252) (xy 363.002966 -264.144623) (xy 363.049566 -264.150805)
			(xy 363.094943 -264.163078) (xy 363.138305 -264.181229) (xy 363.158786 -264.192766) (xy 363.172228 -264.200038)
			(xy 363.201976 -264.206989) (xy 363.232449 -264.204839) (xy 363.260926 -264.19378) (xy 363.284863 -264.174799)
			(xy 363.302121 -264.149592) (xy 363.31116 -264.12041) (xy 363.311694 -264.105136) (xy 363.311694 -264.016236)
			(xy 363.284516 -264.002012) (xy 363.261821 -263.989615) (xy 363.21995 -263.959265) (xy 363.18291 -263.923178)
			(xy 363.15148 -263.882112) (xy 363.12632 -263.836933) (xy 363.10796 -263.788588) (xy 363.096786 -263.738097)
			(xy 363.093033 -263.68652) (xy 363.09678 -263.634943) (xy 363.107949 -263.584451) (xy 363.126303 -263.536105)
			(xy 363.151458 -263.490922) (xy 363.182883 -263.449853) (xy 363.219919 -263.413761) (xy 363.261786 -263.383407)
			(xy 363.284516 -263.371076) (xy 363.311694 -263.356852) (xy 363.311694 -260.343396) (xy 362.895896 -259.927598)
			(xy 362.895896 -258.198874) (xy 363.222032 -257.872738) (xy 365.149384 -257.872738) (xy 365.201454 -257.820668)
			(xy 365.201454 -257.552698) (xy 365.164624 -257.515868) (xy 363.546136 -257.515868) (xy 363.311694 -257.281426)
			(xy 363.311694 -256.976626) (xy 362.947204 -256.612136) (xy 362.947204 -255.511046) (xy 363.12348 -255.33477)
			(xy 363.438694 -255.33477) (xy 363.565694 -255.46177) (xy 368.45748 -255.46177) (xy 368.514376 -255.404874)
			(xy 368.514376 -253.997714) (xy 368.442494 -253.925578) (xy 368.355626 -253.83871) (xy 366.952784 -253.83871)
			(xy 366.857026 -253.934468) (xy 366.857026 -254.211328) (xy 366.825276 -254.243078) (xy 366.745774 -254.322326)
			(xy 366.667034 -254.401066) (xy 366.665764 -254.401066) (xy 366.635284 -254.431546) (xy 365.365284 -254.431546)
			(xy 365.192564 -254.258826) (xy 365.192564 -253.923546) (xy 365.10595 -253.836932) (xy 363.67339 -253.836932)
			(xy 362.916724 -253.080266) (xy 362.916724 -251.922026) (xy 363.037628 -251.801122) (xy 368.445288 -251.801122)
			(xy 368.553238 -251.693172) (xy 368.553238 -250.453398) (xy 368.273584 -250.173744) (xy 366.925606 -250.173744)
			(xy 366.818672 -250.280678) (xy 366.818672 -250.539758) (xy 366.604804 -250.753626) (xy 365.317024 -250.753626)
			(xy 365.202724 -250.639326) (xy 365.202724 -250.276106) (xy 365.08055 -250.153932) (xy 363.430058 -250.153932)
			(xy 362.883704 -249.607578) (xy 362.883704 -248.315226) (xy 363.048804 -248.150126) (xy 366.787176 -248.150126)
			(xy 366.821212 -248.11609) (xy 366.821212 -247.139714) (xy 366.774984 -247.093486) (xy 365.527844 -247.093486)
			(xy 365.314484 -246.880126) (xy 365.314484 -246.565166) (xy 365.218726 -246.469408) (xy 363.494066 -246.469408)
			(xy 362.914184 -245.889526) (xy 362.914184 -244.497098) (xy 363.079284 -244.331998) (xy 363.542072 -244.331998)
			(xy 363.599222 -244.389148) (xy 368.511582 -244.389148) (xy 368.511582 -242.88877) (xy 368.408204 -242.785392)
			(xy 366.914684 -242.785392) (xy 366.851692 -242.848638) (xy 366.851692 -243.122958) (xy 366.604804 -243.369846)
			(xy 365.365284 -243.369846) (xy 365.197644 -243.202206) (xy 365.197644 -242.917726) (xy 365.07166 -242.791742)
			(xy 363.17682 -242.791742) (xy 362.904024 -242.518946) (xy 362.904024 -240.782094) (xy 363.061504 -240.624614)
			(xy 363.575092 -240.624614) (xy 363.696504 -240.746026) (xy 366.73028 -240.746026) (xy 366.80648 -240.669826)
			(xy 366.80648 -239.920526) (xy 366.73028 -239.844326) (xy 365.131604 -239.844326) (xy 364.956344 -239.669066)
			(xy 364.956344 -238.211614) (xy 364.852204 -238.107474) (xy 362.796836 -238.107474) (xy 362.18749 -238.71682)
			(xy 361.860592 -238.71682) (xy 361.845506 -238.717354) (xy 361.816645 -238.72615) (xy 361.791618 -238.743)
			(xy 361.772611 -238.766432) (xy 361.761286 -238.794397) (xy 361.758633 -238.824452) (xy 361.764883 -238.853968)
			(xy 361.771692 -238.867442) (xy 361.785588 -238.893906) (xy 361.805291 -238.950333) (xy 361.815271 -239.009262)
			(xy 361.815888 -239.039146) (xy 361.815888 -239.0394) (xy 361.81539 -239.066049) (xy 361.807447 -239.118753)
			(xy 361.791737 -239.169683) (xy 361.768611 -239.217704) (xy 361.738587 -239.261741) (xy 361.702335 -239.300812)
			(xy 361.660664 -239.334043) (xy 361.614506 -239.360692) (xy 361.564892 -239.380164) (xy 361.51293 -239.392024)
			(xy 361.45978 -239.396008) (xy 361.40663 -239.392024) (xy 361.354668 -239.380164) (xy 361.305054 -239.360692)
			(xy 361.258896 -239.334043) (xy 361.217225 -239.300812) (xy 361.180973 -239.261741) (xy 361.150949 -239.217704)
			(xy 361.127823 -239.169683) (xy 361.112113 -239.118753) (xy 361.10417 -239.066049) (xy 361.103672 -239.0394)
			(xy 361.103672 -239.039146) (xy 361.104306 -239.009265) (xy 361.114313 -238.950344) (xy 361.133988 -238.893912)
			(xy 361.147868 -238.867442) (xy 361.15467 -238.853973) (xy 361.160883 -238.824463) (xy 361.15821 -238.794424)
			(xy 361.146883 -238.766474) (xy 361.127889 -238.743049) (xy 361.102884 -238.72619) (xy 361.074046 -238.717366)
			(xy 361.058968 -238.71682) (xy 357.083106 -238.71682) (xy 357.081328 -238.715042) (xy 356.668324 -238.715042)
			(xy 356.402894 -238.980472) (xy 356.402894 -239.879865) (xy 357.815124 -239.879865) (xy 357.815124 -239.826567)
			(xy 357.823067 -239.773863) (xy 357.838777 -239.722933) (xy 357.861903 -239.674912) (xy 357.891927 -239.630875)
			(xy 357.928179 -239.591804) (xy 357.96985 -239.558573) (xy 358.016008 -239.531924) (xy 358.065622 -239.512452)
			(xy 358.117584 -239.500592) (xy 358.170734 -239.496609) (xy 358.223884 -239.500592) (xy 358.275846 -239.512452)
			(xy 358.32546 -239.531924) (xy 358.371618 -239.558573) (xy 358.413289 -239.591804) (xy 358.449541 -239.630875)
			(xy 358.479565 -239.674912) (xy 358.502691 -239.722933) (xy 358.518401 -239.773863) (xy 358.526344 -239.826567)
			(xy 358.526842 -239.853216) (xy 358.526344 -239.879865) (xy 358.518401 -239.932569) (xy 358.502691 -239.983499)
			(xy 358.479565 -240.03152) (xy 358.449541 -240.075557) (xy 358.413289 -240.114628) (xy 358.371618 -240.147859)
			(xy 358.32546 -240.174508) (xy 358.275846 -240.19398) (xy 358.223884 -240.20584) (xy 358.170734 -240.209824)
			(xy 358.117584 -240.20584) (xy 358.065622 -240.19398) (xy 358.016008 -240.174508) (xy 357.96985 -240.147859)
			(xy 357.928179 -240.114628) (xy 357.891927 -240.075557) (xy 357.861903 -240.03152) (xy 357.838777 -239.983499)
			(xy 357.823067 -239.932569) (xy 357.815124 -239.879865) (xy 356.402894 -239.879865) (xy 356.402894 -239.938306)
			(xy 356.871524 -240.406936) (xy 356.871524 -240.693935) (xy 361.104424 -240.693935) (xy 361.104424 -240.640637)
			(xy 361.112367 -240.587933) (xy 361.128077 -240.537003) (xy 361.151203 -240.488982) (xy 361.181227 -240.444945)
			(xy 361.217479 -240.405874) (xy 361.25915 -240.372643) (xy 361.305308 -240.345994) (xy 361.354922 -240.326522)
			(xy 361.406884 -240.314662) (xy 361.460034 -240.310679) (xy 361.513184 -240.314662) (xy 361.565146 -240.326522)
			(xy 361.61476 -240.345994) (xy 361.660918 -240.372643) (xy 361.702589 -240.405874) (xy 361.738841 -240.444945)
			(xy 361.768865 -240.488982) (xy 361.791991 -240.537003) (xy 361.807701 -240.587933) (xy 361.815644 -240.640637)
			(xy 361.816142 -240.667286) (xy 361.815644 -240.693935) (xy 361.807701 -240.746639) (xy 361.791991 -240.797569)
			(xy 361.768865 -240.84559) (xy 361.738841 -240.889627) (xy 361.702589 -240.928698) (xy 361.660918 -240.961929)
			(xy 361.61476 -240.988578) (xy 361.565146 -241.00805) (xy 361.513184 -241.01991) (xy 361.460034 -241.023894)
			(xy 361.406884 -241.01991) (xy 361.354922 -241.00805) (xy 361.305308 -240.988578) (xy 361.25915 -240.961929)
			(xy 361.217479 -240.928698) (xy 361.181227 -240.889627) (xy 361.151203 -240.84559) (xy 361.128077 -240.797569)
			(xy 361.112367 -240.746639) (xy 361.104424 -240.693935) (xy 356.871524 -240.693935) (xy 356.871524 -241.403886)
			(xy 356.767659 -241.507751) (xy 357.815124 -241.507751) (xy 357.815124 -241.454453) (xy 357.823067 -241.401749)
			(xy 357.838777 -241.350819) (xy 357.861903 -241.302798) (xy 357.891927 -241.258761) (xy 357.928179 -241.21969)
			(xy 357.96985 -241.186459) (xy 358.016008 -241.15981) (xy 358.065622 -241.140338) (xy 358.117584 -241.128478)
			(xy 358.170734 -241.124495) (xy 358.223884 -241.128478) (xy 358.275846 -241.140338) (xy 358.32546 -241.15981)
			(xy 358.371618 -241.186459) (xy 358.413289 -241.21969) (xy 358.449541 -241.258761) (xy 358.479565 -241.302798)
			(xy 358.502691 -241.350819) (xy 358.518401 -241.401749) (xy 358.526344 -241.454453) (xy 358.526842 -241.481102)
			(xy 358.526344 -241.507751) (xy 358.518401 -241.560455) (xy 358.502691 -241.611385) (xy 358.479565 -241.659406)
			(xy 358.449541 -241.703443) (xy 358.413289 -241.742514) (xy 358.371618 -241.775745) (xy 358.32546 -241.802394)
			(xy 358.275846 -241.821866) (xy 358.223884 -241.833726) (xy 358.170734 -241.83771) (xy 358.117584 -241.833726)
			(xy 358.065622 -241.821866) (xy 358.016008 -241.802394) (xy 357.96985 -241.775745) (xy 357.928179 -241.742514)
			(xy 357.891927 -241.703443) (xy 357.861903 -241.659406) (xy 357.838777 -241.611385) (xy 357.823067 -241.560455)
			(xy 357.815124 -241.507751) (xy 356.767659 -241.507751) (xy 356.691184 -241.584226) (xy 354.904294 -241.584226)
			(xy 354.624894 -241.304826) (xy 352.516694 -241.304826) (xy 352.454718 -241.366802) (xy 352.448022 -241.374239)
			(xy 352.440432 -241.392733) (xy 352.440483 -241.412723) (xy 352.448167 -241.431178) (xy 352.462319 -241.445298)
			(xy 352.480791 -241.45294) (xy 352.490786 -241.453416) (xy 352.563938 -241.453416) (xy 352.580618 -241.453965)
			(xy 352.612839 -241.462606) (xy 352.641728 -241.479289) (xy 352.665316 -241.502879) (xy 352.681997 -241.531768)
			(xy 352.690636 -241.56399) (xy 352.691192 -241.58067) (xy 352.691192 -242.321567) (xy 361.104424 -242.321567)
			(xy 361.104424 -242.268269) (xy 361.112367 -242.215565) (xy 361.128077 -242.164635) (xy 361.151203 -242.116614)
			(xy 361.181227 -242.072577) (xy 361.217479 -242.033506) (xy 361.25915 -242.000275) (xy 361.305308 -241.973626)
			(xy 361.354922 -241.954154) (xy 361.406884 -241.942294) (xy 361.460034 -241.938311) (xy 361.513184 -241.942294)
			(xy 361.565146 -241.954154) (xy 361.61476 -241.973626) (xy 361.660918 -242.000275) (xy 361.702589 -242.033506)
			(xy 361.738841 -242.072577) (xy 361.768865 -242.116614) (xy 361.791991 -242.164635) (xy 361.807701 -242.215565)
			(xy 361.815644 -242.268269) (xy 361.816142 -242.294918) (xy 361.815644 -242.321567) (xy 361.807701 -242.374271)
			(xy 361.791991 -242.425201) (xy 361.768865 -242.473222) (xy 361.738841 -242.517259) (xy 361.702589 -242.55633)
			(xy 361.660918 -242.589561) (xy 361.61476 -242.61621) (xy 361.565146 -242.635682) (xy 361.513184 -242.647542)
			(xy 361.460034 -242.651526) (xy 361.406884 -242.647542) (xy 361.354922 -242.635682) (xy 361.305308 -242.61621)
			(xy 361.25915 -242.589561) (xy 361.217479 -242.55633) (xy 361.181227 -242.517259) (xy 361.151203 -242.473222)
			(xy 361.128077 -242.425201) (xy 361.112367 -242.374271) (xy 361.104424 -242.321567) (xy 352.691192 -242.321567)
			(xy 352.691192 -242.59667) (xy 352.690651 -242.613356) (xy 352.682022 -242.645593) (xy 352.665343 -242.674498)
			(xy 352.641752 -242.698102) (xy 352.612856 -242.714796) (xy 352.580624 -242.723442) (xy 352.563938 -242.723924)
			(xy 351.999296 -242.723924) (xy 351.927414 -242.795806) (xy 351.268284 -242.795806) (xy 351.143824 -242.920266)
			(xy 351.143824 -243.135637) (xy 357.815124 -243.135637) (xy 357.815124 -243.082339) (xy 357.823067 -243.029635)
			(xy 357.838777 -242.978705) (xy 357.861903 -242.930684) (xy 357.891927 -242.886647) (xy 357.928179 -242.847576)
			(xy 357.96985 -242.814345) (xy 358.016008 -242.787696) (xy 358.065622 -242.768224) (xy 358.117584 -242.756364)
			(xy 358.170734 -242.752381) (xy 358.223884 -242.756364) (xy 358.275846 -242.768224) (xy 358.32546 -242.787696)
			(xy 358.371618 -242.814345) (xy 358.413289 -242.847576) (xy 358.449541 -242.886647) (xy 358.479565 -242.930684)
			(xy 358.502691 -242.978705) (xy 358.518401 -243.029635) (xy 358.526344 -243.082339) (xy 358.526842 -243.108988)
			(xy 358.526344 -243.135637) (xy 358.518401 -243.188341) (xy 358.502691 -243.239271) (xy 358.479565 -243.287292)
			(xy 358.449541 -243.331329) (xy 358.413289 -243.3704) (xy 358.371618 -243.403631) (xy 358.32546 -243.43028)
			(xy 358.275846 -243.449752) (xy 358.223884 -243.461612) (xy 358.170734 -243.465596) (xy 358.117584 -243.461612)
			(xy 358.065622 -243.449752) (xy 358.016008 -243.43028) (xy 357.96985 -243.403631) (xy 357.928179 -243.3704)
			(xy 357.891927 -243.331329) (xy 357.861903 -243.287292) (xy 357.838777 -243.239271) (xy 357.823067 -243.188341)
			(xy 357.815124 -243.135637) (xy 351.143824 -243.135637) (xy 351.143824 -243.949453) (xy 361.104424 -243.949453)
			(xy 361.104424 -243.896155) (xy 361.112367 -243.843451) (xy 361.128077 -243.792521) (xy 361.151203 -243.7445)
			(xy 361.181227 -243.700463) (xy 361.217479 -243.661392) (xy 361.25915 -243.628161) (xy 361.305308 -243.601512)
			(xy 361.354922 -243.58204) (xy 361.406884 -243.57018) (xy 361.460034 -243.566197) (xy 361.513184 -243.57018)
			(xy 361.565146 -243.58204) (xy 361.61476 -243.601512) (xy 361.660918 -243.628161) (xy 361.702589 -243.661392)
			(xy 361.738841 -243.700463) (xy 361.768865 -243.7445) (xy 361.791991 -243.792521) (xy 361.807701 -243.843451)
			(xy 361.815644 -243.896155) (xy 361.816142 -243.922804) (xy 361.815644 -243.949453) (xy 361.807701 -244.002157)
			(xy 361.791991 -244.053087) (xy 361.768865 -244.101108) (xy 361.738841 -244.145145) (xy 361.702589 -244.184216)
			(xy 361.660918 -244.217447) (xy 361.61476 -244.244096) (xy 361.565146 -244.263568) (xy 361.513184 -244.275428)
			(xy 361.460034 -244.279412) (xy 361.406884 -244.275428) (xy 361.354922 -244.263568) (xy 361.305308 -244.244096)
			(xy 361.25915 -244.217447) (xy 361.217479 -244.184216) (xy 361.181227 -244.145145) (xy 361.151203 -244.101108)
			(xy 361.128077 -244.053087) (xy 361.112367 -244.002157) (xy 361.104424 -243.949453) (xy 351.143824 -243.949453)
			(xy 351.143824 -244.375686) (xy 351.247964 -244.479826) (xy 356.01148 -244.479826) (xy 356.152958 -244.338348)
			(xy 356.650544 -244.338348) (xy 356.825296 -244.513354) (xy 356.818184 -244.520466) (xy 356.818184 -244.763269)
			(xy 357.815124 -244.763269) (xy 357.815124 -244.709971) (xy 357.823067 -244.657267) (xy 357.838777 -244.606337)
			(xy 357.861903 -244.558316) (xy 357.891927 -244.514279) (xy 357.928179 -244.475208) (xy 357.96985 -244.441977)
			(xy 358.016008 -244.415328) (xy 358.065622 -244.395856) (xy 358.117584 -244.383996) (xy 358.170734 -244.380013)
			(xy 358.223884 -244.383996) (xy 358.275846 -244.395856) (xy 358.32546 -244.415328) (xy 358.371618 -244.441977)
			(xy 358.413289 -244.475208) (xy 358.449541 -244.514279) (xy 358.479565 -244.558316) (xy 358.502691 -244.606337)
			(xy 358.518401 -244.657267) (xy 358.526344 -244.709971) (xy 358.526842 -244.73662) (xy 358.526344 -244.763269)
			(xy 358.518401 -244.815973) (xy 358.502691 -244.866903) (xy 358.479565 -244.914924) (xy 358.449541 -244.958961)
			(xy 358.413289 -244.998032) (xy 358.371618 -245.031263) (xy 358.32546 -245.057912) (xy 358.275846 -245.077384)
			(xy 358.223884 -245.089244) (xy 358.170734 -245.093228) (xy 358.117584 -245.089244) (xy 358.065622 -245.077384)
			(xy 358.016008 -245.057912) (xy 357.96985 -245.031263) (xy 357.928179 -244.998032) (xy 357.891927 -244.958961)
			(xy 357.861903 -244.914924) (xy 357.838777 -244.866903) (xy 357.823067 -244.815973) (xy 357.815124 -244.763269)
			(xy 356.818184 -244.763269) (xy 356.818184 -245.577339) (xy 361.104424 -245.577339) (xy 361.104424 -245.524041)
			(xy 361.112367 -245.471337) (xy 361.128077 -245.420407) (xy 361.151203 -245.372386) (xy 361.181227 -245.328349)
			(xy 361.217479 -245.289278) (xy 361.25915 -245.256047) (xy 361.305308 -245.229398) (xy 361.354922 -245.209926)
			(xy 361.406884 -245.198066) (xy 361.460034 -245.194083) (xy 361.513184 -245.198066) (xy 361.565146 -245.209926)
			(xy 361.61476 -245.229398) (xy 361.660918 -245.256047) (xy 361.702589 -245.289278) (xy 361.738841 -245.328349)
			(xy 361.768865 -245.372386) (xy 361.791991 -245.420407) (xy 361.807701 -245.471337) (xy 361.815644 -245.524041)
			(xy 361.816142 -245.55069) (xy 361.815644 -245.577339) (xy 361.807701 -245.630043) (xy 361.791991 -245.680973)
			(xy 361.768865 -245.728994) (xy 361.738841 -245.773031) (xy 361.702589 -245.812102) (xy 361.660918 -245.845333)
			(xy 361.61476 -245.871982) (xy 361.565146 -245.891454) (xy 361.513184 -245.903314) (xy 361.460034 -245.907298)
			(xy 361.406884 -245.903314) (xy 361.354922 -245.891454) (xy 361.305308 -245.871982) (xy 361.25915 -245.845333)
			(xy 361.217479 -245.812102) (xy 361.181227 -245.773031) (xy 361.151203 -245.728994) (xy 361.128077 -245.680973)
			(xy 361.112367 -245.630043) (xy 361.104424 -245.577339) (xy 356.818184 -245.577339) (xy 356.818184 -245.709186)
			(xy 356.136215 -246.391155) (xy 357.815124 -246.391155) (xy 357.815124 -246.337857) (xy 357.823067 -246.285153)
			(xy 357.838777 -246.234223) (xy 357.861903 -246.186202) (xy 357.891927 -246.142165) (xy 357.928179 -246.103094)
			(xy 357.96985 -246.069863) (xy 358.016008 -246.043214) (xy 358.065622 -246.023742) (xy 358.117584 -246.011882)
			(xy 358.170734 -246.007899) (xy 358.223884 -246.011882) (xy 358.275846 -246.023742) (xy 358.32546 -246.043214)
			(xy 358.371618 -246.069863) (xy 358.413289 -246.103094) (xy 358.449541 -246.142165) (xy 358.479565 -246.186202)
			(xy 358.502691 -246.234223) (xy 358.518401 -246.285153) (xy 358.526344 -246.337857) (xy 358.526842 -246.364506)
			(xy 358.526344 -246.391155) (xy 358.518401 -246.443859) (xy 358.502691 -246.494789) (xy 358.479565 -246.54281)
			(xy 358.449541 -246.586847) (xy 358.413289 -246.625918) (xy 358.371618 -246.659149) (xy 358.32546 -246.685798)
			(xy 358.275846 -246.70527) (xy 358.223884 -246.71713) (xy 358.170734 -246.721114) (xy 358.117584 -246.71713)
			(xy 358.065622 -246.70527) (xy 358.016008 -246.685798) (xy 357.96985 -246.659149) (xy 357.928179 -246.625918)
			(xy 357.891927 -246.586847) (xy 357.861903 -246.54281) (xy 357.838777 -246.494789) (xy 357.823067 -246.443859)
			(xy 357.815124 -246.391155) (xy 356.136215 -246.391155) (xy 356.038404 -246.488966) (xy 354.549964 -246.488966)
			(xy 354.45446 -246.58447) (xy 354.45446 -246.879618) (xy 354.243132 -247.090946) (xy 352.987864 -247.090946)
			(xy 352.967544 -247.111266) (xy 352.967544 -247.204971) (xy 361.104424 -247.204971) (xy 361.104424 -247.151673)
			(xy 361.112367 -247.098969) (xy 361.128077 -247.048039) (xy 361.151203 -247.000018) (xy 361.181227 -246.955981)
			(xy 361.217479 -246.91691) (xy 361.25915 -246.883679) (xy 361.305308 -246.85703) (xy 361.354922 -246.837558)
			(xy 361.406884 -246.825698) (xy 361.460034 -246.821715) (xy 361.513184 -246.825698) (xy 361.565146 -246.837558)
			(xy 361.61476 -246.85703) (xy 361.660918 -246.883679) (xy 361.702589 -246.91691) (xy 361.738841 -246.955981)
			(xy 361.768865 -247.000018) (xy 361.791991 -247.048039) (xy 361.807701 -247.098969) (xy 361.815644 -247.151673)
			(xy 361.816142 -247.178322) (xy 361.815644 -247.204971) (xy 361.807701 -247.257675) (xy 361.791991 -247.308605)
			(xy 361.768865 -247.356626) (xy 361.738841 -247.400663) (xy 361.702589 -247.439734) (xy 361.660918 -247.472965)
			(xy 361.61476 -247.499614) (xy 361.565146 -247.519086) (xy 361.513184 -247.530946) (xy 361.460034 -247.53493)
			(xy 361.406884 -247.530946) (xy 361.354922 -247.519086) (xy 361.305308 -247.499614) (xy 361.25915 -247.472965)
			(xy 361.217479 -247.439734) (xy 361.181227 -247.400663) (xy 361.151203 -247.356626) (xy 361.128077 -247.308605)
			(xy 361.112367 -247.257675) (xy 361.104424 -247.204971) (xy 352.967544 -247.204971) (xy 352.967544 -248.104914)
			(xy 353.003104 -248.140474) (xy 355.978968 -248.140474) (xy 356.1461 -247.973342) (xy 356.622604 -247.973342)
			(xy 356.668049 -248.018787) (xy 357.815124 -248.018787) (xy 357.815124 -247.965489) (xy 357.823067 -247.912785)
			(xy 357.838777 -247.861855) (xy 357.861903 -247.813834) (xy 357.891927 -247.769797) (xy 357.928179 -247.730726)
			(xy 357.96985 -247.697495) (xy 358.016008 -247.670846) (xy 358.065622 -247.651374) (xy 358.117584 -247.639514)
			(xy 358.170734 -247.635531) (xy 358.223884 -247.639514) (xy 358.275846 -247.651374) (xy 358.32546 -247.670846)
			(xy 358.371618 -247.697495) (xy 358.413289 -247.730726) (xy 358.449541 -247.769797) (xy 358.479565 -247.813834)
			(xy 358.502691 -247.861855) (xy 358.518401 -247.912785) (xy 358.526344 -247.965489) (xy 358.526842 -247.992138)
			(xy 358.526344 -248.018787) (xy 358.518401 -248.071491) (xy 358.502691 -248.122421) (xy 358.479565 -248.170442)
			(xy 358.449541 -248.214479) (xy 358.413289 -248.25355) (xy 358.371618 -248.286781) (xy 358.32546 -248.31343)
			(xy 358.275846 -248.332902) (xy 358.223884 -248.344762) (xy 358.170734 -248.348746) (xy 358.117584 -248.344762)
			(xy 358.065622 -248.332902) (xy 358.016008 -248.31343) (xy 357.96985 -248.286781) (xy 357.928179 -248.25355)
			(xy 357.891927 -248.214479) (xy 357.861903 -248.170442) (xy 357.838777 -248.122421) (xy 357.823067 -248.071491)
			(xy 357.815124 -248.018787) (xy 356.668049 -248.018787) (xy 356.797864 -248.148602) (xy 356.797864 -248.832857)
			(xy 361.104424 -248.832857) (xy 361.104424 -248.779559) (xy 361.112367 -248.726855) (xy 361.128077 -248.675925)
			(xy 361.151203 -248.627904) (xy 361.181227 -248.583867) (xy 361.217479 -248.544796) (xy 361.25915 -248.511565)
			(xy 361.305308 -248.484916) (xy 361.354922 -248.465444) (xy 361.406884 -248.453584) (xy 361.460034 -248.449601)
			(xy 361.513184 -248.453584) (xy 361.565146 -248.465444) (xy 361.61476 -248.484916) (xy 361.660918 -248.511565)
			(xy 361.702589 -248.544796) (xy 361.738841 -248.583867) (xy 361.768865 -248.627904) (xy 361.791991 -248.675925)
			(xy 361.807701 -248.726855) (xy 361.815644 -248.779559) (xy 361.816142 -248.806208) (xy 361.815644 -248.832857)
			(xy 361.807701 -248.885561) (xy 361.791991 -248.936491) (xy 361.768865 -248.984512) (xy 361.738841 -249.028549)
			(xy 361.702589 -249.06762) (xy 361.660918 -249.100851) (xy 361.61476 -249.1275) (xy 361.565146 -249.146972)
			(xy 361.513184 -249.158832) (xy 361.460034 -249.162816) (xy 361.406884 -249.158832) (xy 361.354922 -249.146972)
			(xy 361.305308 -249.1275) (xy 361.25915 -249.100851) (xy 361.217479 -249.06762) (xy 361.181227 -249.028549)
			(xy 361.151203 -248.984512) (xy 361.128077 -248.936491) (xy 361.112367 -248.885561) (xy 361.104424 -248.832857)
			(xy 356.797864 -248.832857) (xy 356.797864 -249.257058) (xy 356.77856 -249.276362) (xy 356.510844 -249.544332)
			(xy 356.408503 -249.646673) (xy 357.815124 -249.646673) (xy 357.815124 -249.593375) (xy 357.823067 -249.540671)
			(xy 357.838777 -249.489741) (xy 357.861903 -249.44172) (xy 357.891927 -249.397683) (xy 357.928179 -249.358612)
			(xy 357.96985 -249.325381) (xy 358.016008 -249.298732) (xy 358.065622 -249.27926) (xy 358.117584 -249.2674)
			(xy 358.170734 -249.263417) (xy 358.223884 -249.2674) (xy 358.275846 -249.27926) (xy 358.32546 -249.298732)
			(xy 358.371618 -249.325381) (xy 358.413289 -249.358612) (xy 358.449541 -249.397683) (xy 358.479565 -249.44172)
			(xy 358.502691 -249.489741) (xy 358.518401 -249.540671) (xy 358.526344 -249.593375) (xy 358.526842 -249.620024)
			(xy 358.526344 -249.646673) (xy 358.518401 -249.699377) (xy 358.502691 -249.750307) (xy 358.479565 -249.798328)
			(xy 358.449541 -249.842365) (xy 358.413289 -249.881436) (xy 358.371618 -249.914667) (xy 358.32546 -249.941316)
			(xy 358.275846 -249.960788) (xy 358.223884 -249.972648) (xy 358.170734 -249.976632) (xy 358.117584 -249.972648)
			(xy 358.065622 -249.960788) (xy 358.016008 -249.941316) (xy 357.96985 -249.914667) (xy 357.928179 -249.881436)
			(xy 357.891927 -249.842365) (xy 357.861903 -249.798328) (xy 357.838777 -249.750307) (xy 357.823067 -249.699377)
			(xy 357.815124 -249.646673) (xy 356.408503 -249.646673) (xy 356.387146 -249.66803) (xy 356.387146 -250.011946)
			(xy 356.21087 -250.188222) (xy 354.522024 -250.188222) (xy 354.478082 -250.232164) (xy 354.478082 -250.586748)
			(xy 354.328984 -250.735846) (xy 353.135184 -250.735846) (xy 352.924364 -250.525026) (xy 352.924364 -250.263406)
			(xy 352.84918 -250.188222) (xy 351.295208 -250.188222) (xy 351.210372 -250.273058) (xy 351.210372 -251.751338)
			(xy 351.259902 -251.801122) (xy 356.00513 -251.801122) (xy 356.161086 -251.645166) (xy 356.650544 -251.645166)
			(xy 356.833424 -251.828046) (xy 356.833424 -252.84176) (xy 356.391972 -253.283212) (xy 356.391972 -253.568708)
			(xy 356.10927 -253.85141) (xy 354.562664 -253.85141) (xy 354.488496 -253.925578) (xy 354.488496 -253.946385)
			(xy 361.214152 -253.946385) (xy 361.214152 -253.893087) (xy 361.222095 -253.840383) (xy 361.237805 -253.789453)
			(xy 361.260931 -253.741432) (xy 361.290955 -253.697395) (xy 361.327207 -253.658324) (xy 361.368878 -253.625093)
			(xy 361.415036 -253.598444) (xy 361.46465 -253.578972) (xy 361.516612 -253.567112) (xy 361.569762 -253.563129)
			(xy 361.622912 -253.567112) (xy 361.674874 -253.578972) (xy 361.724488 -253.598444) (xy 361.770646 -253.625093)
			(xy 361.812317 -253.658324) (xy 361.848569 -253.697395) (xy 361.878593 -253.741432) (xy 361.901719 -253.789453)
			(xy 361.917429 -253.840383) (xy 361.925372 -253.893087) (xy 361.92587 -253.919736) (xy 361.925372 -253.946385)
			(xy 361.917429 -253.999089) (xy 361.901719 -254.050019) (xy 361.878593 -254.09804) (xy 361.848569 -254.142077)
			(xy 361.812317 -254.181148) (xy 361.770646 -254.214379) (xy 361.724488 -254.241028) (xy 361.674874 -254.2605)
			(xy 361.622912 -254.27236) (xy 361.569762 -254.276344) (xy 361.516612 -254.27236) (xy 361.46465 -254.2605)
			(xy 361.415036 -254.241028) (xy 361.368878 -254.214379) (xy 361.327207 -254.181148) (xy 361.290955 -254.142077)
			(xy 361.260931 -254.09804) (xy 361.237805 -254.050019) (xy 361.222095 -253.999089) (xy 361.214152 -253.946385)
			(xy 354.488496 -253.946385) (xy 354.488496 -254.274574) (xy 354.328984 -254.434086) (xy 353.142804 -254.434086)
			(xy 352.921824 -254.213106) (xy 352.921824 -253.882906) (xy 352.860864 -253.821946) (xy 351.931224 -253.821946)
			(xy 351.890584 -253.862586) (xy 351.890584 -254.149606) (xy 351.931224 -254.190246) (xy 352.545904 -254.190246)
			(xy 352.738944 -254.383286) (xy 352.738944 -254.760201) (xy 357.924852 -254.760201) (xy 357.924852 -254.706903)
			(xy 357.932795 -254.654199) (xy 357.948505 -254.603269) (xy 357.971631 -254.555248) (xy 358.001655 -254.511211)
			(xy 358.037907 -254.47214) (xy 358.079578 -254.438909) (xy 358.125736 -254.41226) (xy 358.17535 -254.392788)
			(xy 358.227312 -254.380928) (xy 358.280462 -254.376945) (xy 358.333612 -254.380928) (xy 358.385574 -254.392788)
			(xy 358.435188 -254.41226) (xy 358.481346 -254.438909) (xy 358.523017 -254.47214) (xy 358.559269 -254.511211)
			(xy 358.589293 -254.555248) (xy 358.612419 -254.603269) (xy 358.628129 -254.654199) (xy 358.636072 -254.706903)
			(xy 358.63657 -254.733552) (xy 358.636072 -254.760201) (xy 358.628129 -254.812905) (xy 358.612419 -254.863835)
			(xy 358.589293 -254.911856) (xy 358.559269 -254.955893) (xy 358.523017 -254.994964) (xy 358.481346 -255.028195)
			(xy 358.435188 -255.054844) (xy 358.385574 -255.074316) (xy 358.333612 -255.086176) (xy 358.280462 -255.09016)
			(xy 358.227312 -255.086176) (xy 358.17535 -255.074316) (xy 358.125736 -255.054844) (xy 358.079578 -255.028195)
			(xy 358.037907 -254.994964) (xy 358.001655 -254.955893) (xy 357.971631 -254.911856) (xy 357.948505 -254.863835)
			(xy 357.932795 -254.812905) (xy 357.924852 -254.760201) (xy 352.738944 -254.760201) (xy 352.738944 -255.404366)
			(xy 352.801682 -255.467104) (xy 353.155504 -255.467104) (xy 353.160838 -255.46177) (xy 356.053136 -255.46177)
			(xy 356.256082 -255.258824) (xy 356.627684 -255.258824) (xy 356.863904 -255.495044) (xy 356.863904 -255.574271)
			(xy 361.214152 -255.574271) (xy 361.214152 -255.520973) (xy 361.222095 -255.468269) (xy 361.237805 -255.417339)
			(xy 361.260931 -255.369318) (xy 361.290955 -255.325281) (xy 361.327207 -255.28621) (xy 361.368878 -255.252979)
			(xy 361.415036 -255.22633) (xy 361.46465 -255.206858) (xy 361.516612 -255.194998) (xy 361.569762 -255.191015)
			(xy 361.622912 -255.194998) (xy 361.674874 -255.206858) (xy 361.724488 -255.22633) (xy 361.770646 -255.252979)
			(xy 361.812317 -255.28621) (xy 361.848569 -255.325281) (xy 361.878593 -255.369318) (xy 361.901719 -255.417339)
			(xy 361.917429 -255.468269) (xy 361.925372 -255.520973) (xy 361.92587 -255.547622) (xy 361.925372 -255.574271)
			(xy 361.917429 -255.626975) (xy 361.901719 -255.677905) (xy 361.878593 -255.725926) (xy 361.848569 -255.769963)
			(xy 361.812317 -255.809034) (xy 361.770646 -255.842265) (xy 361.724488 -255.868914) (xy 361.674874 -255.888386)
			(xy 361.622912 -255.900246) (xy 361.569762 -255.90423) (xy 361.516612 -255.900246) (xy 361.46465 -255.888386)
			(xy 361.415036 -255.868914) (xy 361.368878 -255.842265) (xy 361.327207 -255.809034) (xy 361.290955 -255.769963)
			(xy 361.260931 -255.725926) (xy 361.237805 -255.677905) (xy 361.222095 -255.626975) (xy 361.214152 -255.574271)
			(xy 356.863904 -255.574271) (xy 356.863904 -256.388087) (xy 357.924852 -256.388087) (xy 357.924852 -256.334789)
			(xy 357.932795 -256.282085) (xy 357.948505 -256.231155) (xy 357.971631 -256.183134) (xy 358.001655 -256.139097)
			(xy 358.037907 -256.100026) (xy 358.079578 -256.066795) (xy 358.125736 -256.040146) (xy 358.17535 -256.020674)
			(xy 358.227312 -256.008814) (xy 358.280462 -256.004831) (xy 358.333612 -256.008814) (xy 358.385574 -256.020674)
			(xy 358.435188 -256.040146) (xy 358.481346 -256.066795) (xy 358.523017 -256.100026) (xy 358.559269 -256.139097)
			(xy 358.589293 -256.183134) (xy 358.612419 -256.231155) (xy 358.628129 -256.282085) (xy 358.636072 -256.334789)
			(xy 358.63657 -256.361438) (xy 358.636072 -256.388087) (xy 358.628129 -256.440791) (xy 358.612419 -256.491721)
			(xy 358.589293 -256.539742) (xy 358.559269 -256.583779) (xy 358.523017 -256.62285) (xy 358.481346 -256.656081)
			(xy 358.435188 -256.68273) (xy 358.385574 -256.702202) (xy 358.333612 -256.714062) (xy 358.280462 -256.718046)
			(xy 358.227312 -256.714062) (xy 358.17535 -256.702202) (xy 358.125736 -256.68273) (xy 358.079578 -256.656081)
			(xy 358.037907 -256.62285) (xy 358.001655 -256.583779) (xy 357.971631 -256.539742) (xy 357.948505 -256.491721)
			(xy 357.932795 -256.440791) (xy 357.924852 -256.388087) (xy 356.863904 -256.388087) (xy 356.863904 -256.591816)
			(xy 356.428294 -257.027426) (xy 356.428294 -257.201903) (xy 361.214152 -257.201903) (xy 361.214152 -257.148605)
			(xy 361.222095 -257.095901) (xy 361.237805 -257.044971) (xy 361.260931 -256.99695) (xy 361.290955 -256.952913)
			(xy 361.327207 -256.913842) (xy 361.368878 -256.880611) (xy 361.415036 -256.853962) (xy 361.46465 -256.83449)
			(xy 361.516612 -256.82263) (xy 361.569762 -256.818647) (xy 361.622912 -256.82263) (xy 361.674874 -256.83449)
			(xy 361.724488 -256.853962) (xy 361.770646 -256.880611) (xy 361.812317 -256.913842) (xy 361.848569 -256.952913)
			(xy 361.878593 -256.99695) (xy 361.901719 -257.044971) (xy 361.917429 -257.095901) (xy 361.925372 -257.148605)
			(xy 361.92587 -257.175254) (xy 361.925372 -257.201903) (xy 361.917429 -257.254607) (xy 361.901719 -257.305537)
			(xy 361.878593 -257.353558) (xy 361.848569 -257.397595) (xy 361.812317 -257.436666) (xy 361.770646 -257.469897)
			(xy 361.724488 -257.496546) (xy 361.674874 -257.516018) (xy 361.622912 -257.527878) (xy 361.569762 -257.531862)
			(xy 361.516612 -257.527878) (xy 361.46465 -257.516018) (xy 361.415036 -257.496546) (xy 361.368878 -257.469897)
			(xy 361.327207 -257.436666) (xy 361.290955 -257.397595) (xy 361.260931 -257.353558) (xy 361.237805 -257.305537)
			(xy 361.222095 -257.254607) (xy 361.214152 -257.201903) (xy 356.428294 -257.201903) (xy 356.428294 -257.256026)
			(xy 356.189026 -257.495294) (xy 354.640896 -257.495294) (xy 354.549964 -257.586226) (xy 354.549964 -257.764788)
			(xy 354.674424 -257.889248) (xy 356.12832 -257.889248) (xy 356.254791 -258.015719) (xy 357.924852 -258.015719)
			(xy 357.924852 -257.962421) (xy 357.932795 -257.909717) (xy 357.948505 -257.858787) (xy 357.971631 -257.810766)
			(xy 358.001655 -257.766729) (xy 358.037907 -257.727658) (xy 358.079578 -257.694427) (xy 358.125736 -257.667778)
			(xy 358.17535 -257.648306) (xy 358.227312 -257.636446) (xy 358.280462 -257.632463) (xy 358.333612 -257.636446)
			(xy 358.385574 -257.648306) (xy 358.435188 -257.667778) (xy 358.481346 -257.694427) (xy 358.523017 -257.727658)
			(xy 358.559269 -257.766729) (xy 358.589293 -257.810766) (xy 358.612419 -257.858787) (xy 358.628129 -257.909717)
			(xy 358.636072 -257.962421) (xy 358.63657 -257.98907) (xy 358.636072 -258.015719) (xy 358.628129 -258.068423)
			(xy 358.612419 -258.119353) (xy 358.589293 -258.167374) (xy 358.559269 -258.211411) (xy 358.523017 -258.250482)
			(xy 358.481346 -258.283713) (xy 358.435188 -258.310362) (xy 358.385574 -258.329834) (xy 358.333612 -258.341694)
			(xy 358.280462 -258.345678) (xy 358.227312 -258.341694) (xy 358.17535 -258.329834) (xy 358.125736 -258.310362)
			(xy 358.079578 -258.283713) (xy 358.037907 -258.250482) (xy 358.001655 -258.211411) (xy 357.971631 -258.167374)
			(xy 357.948505 -258.119353) (xy 357.932795 -258.068423) (xy 357.924852 -258.015719) (xy 356.254791 -258.015719)
			(xy 356.813104 -258.574032) (xy 356.813104 -258.829789) (xy 361.214152 -258.829789) (xy 361.214152 -258.776491)
			(xy 361.222095 -258.723787) (xy 361.237805 -258.672857) (xy 361.260931 -258.624836) (xy 361.290955 -258.580799)
			(xy 361.327207 -258.541728) (xy 361.368878 -258.508497) (xy 361.415036 -258.481848) (xy 361.46465 -258.462376)
			(xy 361.516612 -258.450516) (xy 361.569762 -258.446533) (xy 361.622912 -258.450516) (xy 361.674874 -258.462376)
			(xy 361.724488 -258.481848) (xy 361.770646 -258.508497) (xy 361.812317 -258.541728) (xy 361.848569 -258.580799)
			(xy 361.878593 -258.624836) (xy 361.901719 -258.672857) (xy 361.917429 -258.723787) (xy 361.925372 -258.776491)
			(xy 361.92587 -258.80314) (xy 361.925372 -258.829789) (xy 361.917429 -258.882493) (xy 361.901719 -258.933423)
			(xy 361.878593 -258.981444) (xy 361.848569 -259.025481) (xy 361.812317 -259.064552) (xy 361.770646 -259.097783)
			(xy 361.724488 -259.124432) (xy 361.674874 -259.143904) (xy 361.622912 -259.155764) (xy 361.569762 -259.159748)
			(xy 361.516612 -259.155764) (xy 361.46465 -259.143904) (xy 361.415036 -259.124432) (xy 361.368878 -259.097783)
			(xy 361.327207 -259.064552) (xy 361.290955 -259.025481) (xy 361.260931 -258.981444) (xy 361.237805 -258.933423)
			(xy 361.222095 -258.882493) (xy 361.214152 -258.829789) (xy 356.813104 -258.829789) (xy 356.813104 -259.643605)
			(xy 357.924852 -259.643605) (xy 357.924852 -259.590307) (xy 357.932795 -259.537603) (xy 357.948505 -259.486673)
			(xy 357.971631 -259.438652) (xy 358.001655 -259.394615) (xy 358.037907 -259.355544) (xy 358.079578 -259.322313)
			(xy 358.125736 -259.295664) (xy 358.17535 -259.276192) (xy 358.227312 -259.264332) (xy 358.280462 -259.260349)
			(xy 358.333612 -259.264332) (xy 358.385574 -259.276192) (xy 358.435188 -259.295664) (xy 358.481346 -259.322313)
			(xy 358.523017 -259.355544) (xy 358.559269 -259.394615) (xy 358.589293 -259.438652) (xy 358.612419 -259.486673)
			(xy 358.628129 -259.537603) (xy 358.636072 -259.590307) (xy 358.63657 -259.616956) (xy 358.636072 -259.643605)
			(xy 358.628129 -259.696309) (xy 358.612419 -259.747239) (xy 358.589293 -259.79526) (xy 358.559269 -259.839297)
			(xy 358.523017 -259.878368) (xy 358.481346 -259.911599) (xy 358.435188 -259.938248) (xy 358.385574 -259.95772)
			(xy 358.333612 -259.96958) (xy 358.280462 -259.973564) (xy 358.227312 -259.96958) (xy 358.17535 -259.95772)
			(xy 358.125736 -259.938248) (xy 358.079578 -259.911599) (xy 358.037907 -259.878368) (xy 358.001655 -259.839297)
			(xy 357.971631 -259.79526) (xy 357.948505 -259.747239) (xy 357.932795 -259.696309) (xy 357.924852 -259.643605)
			(xy 356.813104 -259.643605) (xy 356.813104 -259.862066) (xy 356.352094 -260.323076) (xy 356.352094 -260.457421)
			(xy 361.214152 -260.457421) (xy 361.214152 -260.404123) (xy 361.222095 -260.351419) (xy 361.237805 -260.300489)
			(xy 361.260931 -260.252468) (xy 361.290955 -260.208431) (xy 361.327207 -260.16936) (xy 361.368878 -260.136129)
			(xy 361.415036 -260.10948) (xy 361.46465 -260.090008) (xy 361.516612 -260.078148) (xy 361.569762 -260.074165)
			(xy 361.622912 -260.078148) (xy 361.674874 -260.090008) (xy 361.724488 -260.10948) (xy 361.770646 -260.136129)
			(xy 361.812317 -260.16936) (xy 361.848569 -260.208431) (xy 361.878593 -260.252468) (xy 361.901719 -260.300489)
			(xy 361.917429 -260.351419) (xy 361.925372 -260.404123) (xy 361.92587 -260.430772) (xy 361.925372 -260.457421)
			(xy 361.917429 -260.510125) (xy 361.901719 -260.561055) (xy 361.878593 -260.609076) (xy 361.848569 -260.653113)
			(xy 361.812317 -260.692184) (xy 361.770646 -260.725415) (xy 361.724488 -260.752064) (xy 361.674874 -260.771536)
			(xy 361.622912 -260.783396) (xy 361.569762 -260.78738) (xy 361.516612 -260.783396) (xy 361.46465 -260.771536)
			(xy 361.415036 -260.752064) (xy 361.368878 -260.725415) (xy 361.327207 -260.692184) (xy 361.290955 -260.653113)
			(xy 361.260931 -260.609076) (xy 361.237805 -260.561055) (xy 361.222095 -260.510125) (xy 361.214152 -260.457421)
			(xy 356.352094 -260.457421) (xy 356.352094 -261.271491) (xy 357.924852 -261.271491) (xy 357.924852 -261.218193)
			(xy 357.932795 -261.165489) (xy 357.948505 -261.114559) (xy 357.971631 -261.066538) (xy 358.001655 -261.022501)
			(xy 358.037907 -260.98343) (xy 358.079578 -260.950199) (xy 358.125736 -260.92355) (xy 358.17535 -260.904078)
			(xy 358.227312 -260.892218) (xy 358.280462 -260.888235) (xy 358.333612 -260.892218) (xy 358.385574 -260.904078)
			(xy 358.435188 -260.92355) (xy 358.481346 -260.950199) (xy 358.523017 -260.98343) (xy 358.559269 -261.022501)
			(xy 358.589293 -261.066538) (xy 358.612419 -261.114559) (xy 358.628129 -261.165489) (xy 358.636072 -261.218193)
			(xy 358.63657 -261.244842) (xy 358.636072 -261.271491) (xy 358.628129 -261.324195) (xy 358.612419 -261.375125)
			(xy 358.589293 -261.423146) (xy 358.559269 -261.467183) (xy 358.523017 -261.506254) (xy 358.481346 -261.539485)
			(xy 358.435188 -261.566134) (xy 358.385574 -261.585606) (xy 358.333612 -261.597466) (xy 358.280462 -261.60145)
			(xy 358.227312 -261.597466) (xy 358.17535 -261.585606) (xy 358.125736 -261.566134) (xy 358.079578 -261.539485)
			(xy 358.037907 -261.506254) (xy 358.001655 -261.467183) (xy 357.971631 -261.423146) (xy 357.948505 -261.375125)
			(xy 357.932795 -261.324195) (xy 357.924852 -261.271491) (xy 356.352094 -261.271491) (xy 356.352094 -261.548626)
			(xy 356.110794 -261.789926) (xy 354.091494 -261.789926) (xy 353.913694 -261.967726) (xy 353.913694 -262.085307)
			(xy 361.214152 -262.085307) (xy 361.214152 -262.032009) (xy 361.222095 -261.979305) (xy 361.237805 -261.928375)
			(xy 361.260931 -261.880354) (xy 361.290955 -261.836317) (xy 361.327207 -261.797246) (xy 361.368878 -261.764015)
			(xy 361.415036 -261.737366) (xy 361.46465 -261.717894) (xy 361.516612 -261.706034) (xy 361.569762 -261.702051)
			(xy 361.622912 -261.706034) (xy 361.674874 -261.717894) (xy 361.724488 -261.737366) (xy 361.770646 -261.764015)
			(xy 361.812317 -261.797246) (xy 361.848569 -261.836317) (xy 361.878593 -261.880354) (xy 361.901719 -261.928375)
			(xy 361.917429 -261.979305) (xy 361.925372 -262.032009) (xy 361.92587 -262.058658) (xy 361.925372 -262.085307)
			(xy 361.917429 -262.138011) (xy 361.901719 -262.188941) (xy 361.878593 -262.236962) (xy 361.848569 -262.280999)
			(xy 361.812317 -262.32007) (xy 361.770646 -262.353301) (xy 361.724488 -262.37995) (xy 361.674874 -262.399422)
			(xy 361.622912 -262.411282) (xy 361.569762 -262.415266) (xy 361.516612 -262.411282) (xy 361.46465 -262.399422)
			(xy 361.415036 -262.37995) (xy 361.368878 -262.353301) (xy 361.327207 -262.32007) (xy 361.290955 -262.280999)
			(xy 361.260931 -262.236962) (xy 361.237805 -262.188941) (xy 361.222095 -262.138011) (xy 361.214152 -262.085307)
			(xy 353.913694 -262.085307) (xy 353.913694 -262.899123) (xy 357.924852 -262.899123) (xy 357.924852 -262.845825)
			(xy 357.932795 -262.793121) (xy 357.948505 -262.742191) (xy 357.971631 -262.69417) (xy 358.001655 -262.650133)
			(xy 358.037907 -262.611062) (xy 358.079578 -262.577831) (xy 358.125736 -262.551182) (xy 358.17535 -262.53171)
			(xy 358.227312 -262.51985) (xy 358.280462 -262.515867) (xy 358.333612 -262.51985) (xy 358.385574 -262.53171)
			(xy 358.435188 -262.551182) (xy 358.481346 -262.577831) (xy 358.523017 -262.611062) (xy 358.559269 -262.650133)
			(xy 358.589293 -262.69417) (xy 358.612419 -262.742191) (xy 358.628129 -262.793121) (xy 358.636072 -262.845825)
			(xy 358.63657 -262.872474) (xy 358.636072 -262.899123) (xy 358.628129 -262.951827) (xy 358.612419 -263.002757)
			(xy 358.589293 -263.050778) (xy 358.559269 -263.094815) (xy 358.523017 -263.133886) (xy 358.481346 -263.167117)
			(xy 358.435188 -263.193766) (xy 358.385574 -263.213238) (xy 358.333612 -263.225098) (xy 358.280462 -263.229082)
			(xy 358.227312 -263.225098) (xy 358.17535 -263.213238) (xy 358.125736 -263.193766) (xy 358.079578 -263.167117)
			(xy 358.037907 -263.133886) (xy 358.001655 -263.094815) (xy 357.971631 -263.050778) (xy 357.948505 -263.002757)
			(xy 357.932795 -262.951827) (xy 357.924852 -262.899123) (xy 353.913694 -262.899123) (xy 353.913694 -263.326626)
			(xy 354.193094 -263.606026) (xy 354.231448 -263.62152) (xy 354.737162 -263.62152) (xy 354.762667 -263.622017)
			(xy 354.813029 -263.630127) (xy 354.86146 -263.646146) (xy 354.906724 -263.669666) (xy 354.94767 -263.700089)
			(xy 354.960428 -263.713193) (xy 361.214152 -263.713193) (xy 361.214152 -263.659895) (xy 361.222095 -263.607191)
			(xy 361.237805 -263.556261) (xy 361.260931 -263.50824) (xy 361.290955 -263.464203) (xy 361.327207 -263.425132)
			(xy 361.368878 -263.391901) (xy 361.415036 -263.365252) (xy 361.46465 -263.34578) (xy 361.516612 -263.33392)
			(xy 361.569762 -263.329937) (xy 361.622912 -263.33392) (xy 361.674874 -263.34578) (xy 361.724488 -263.365252)
			(xy 361.770646 -263.391901) (xy 361.812317 -263.425132) (xy 361.848569 -263.464203) (xy 361.878593 -263.50824)
			(xy 361.901719 -263.556261) (xy 361.917429 -263.607191) (xy 361.925372 -263.659895) (xy 361.92587 -263.686544)
			(xy 361.925372 -263.713193) (xy 361.917429 -263.765897) (xy 361.901719 -263.816827) (xy 361.878593 -263.864848)
			(xy 361.848569 -263.908885) (xy 361.812317 -263.947956) (xy 361.770646 -263.981187) (xy 361.724488 -264.007836)
			(xy 361.674874 -264.027308) (xy 361.622912 -264.039168) (xy 361.569762 -264.043152) (xy 361.516612 -264.039168)
			(xy 361.46465 -264.027308) (xy 361.415036 -264.007836) (xy 361.368878 -263.981187) (xy 361.327207 -263.947956)
			(xy 361.290955 -263.908885) (xy 361.260931 -263.864848) (xy 361.237805 -263.816827) (xy 361.222095 -263.765897)
			(xy 361.214152 -263.713193) (xy 354.960428 -263.713193) (xy 354.983255 -263.736638) (xy 355.012571 -263.778383)
			(xy 355.024182 -263.801098) (xy 355.027992 -263.808718) (xy 355.271832 -264.052558) (xy 355.28728 -264.068594)
			(xy 355.313749 -264.104397) (xy 355.334636 -264.14372) (xy 355.342444 -264.164572) (xy 355.371119 -264.155119)
			(xy 355.430622 -264.14491) (xy 355.460808 -264.144252) (xy 355.461316 -264.144252) (xy 355.489299 -264.144802)
			(xy 355.544577 -264.153559) (xy 355.597804 -264.170854) (xy 355.647671 -264.196263) (xy 355.69295 -264.229158)
			(xy 355.732526 -264.268732) (xy 355.765425 -264.314008) (xy 355.790836 -264.363873) (xy 355.808136 -264.4171)
			(xy 355.816896 -264.472377) (xy 355.817424 -264.50036) (xy 355.816928 -264.527009) (xy 356.045506 -264.527009)
			(xy 356.045506 -264.473711) (xy 356.053449 -264.421007) (xy 356.069159 -264.370077) (xy 356.092285 -264.322056)
			(xy 356.122309 -264.278019) (xy 356.158561 -264.238948) (xy 356.200232 -264.205717) (xy 356.24639 -264.179068)
			(xy 356.296004 -264.159596) (xy 356.347966 -264.147736) (xy 356.401116 -264.143753) (xy 356.454266 -264.147736)
			(xy 356.506228 -264.159596) (xy 356.555842 -264.179068) (xy 356.602 -264.205717) (xy 356.643671 -264.238948)
			(xy 356.679923 -264.278019) (xy 356.709947 -264.322056) (xy 356.733073 -264.370077) (xy 356.748783 -264.421007)
			(xy 356.756726 -264.473711) (xy 356.757224 -264.50036) (xy 356.756726 -264.527009) (xy 356.748783 -264.579713)
			(xy 356.733073 -264.630643) (xy 356.709947 -264.678664) (xy 356.679923 -264.722701) (xy 356.643671 -264.761772)
			(xy 356.602 -264.795003) (xy 356.555842 -264.821652) (xy 356.506228 -264.841124) (xy 356.454266 -264.852984)
			(xy 356.401116 -264.856968) (xy 356.347966 -264.852984) (xy 356.296004 -264.841124) (xy 356.24639 -264.821652)
			(xy 356.200232 -264.795003) (xy 356.158561 -264.761772) (xy 356.122309 -264.722701) (xy 356.092285 -264.678664)
			(xy 356.069159 -264.630643) (xy 356.053449 -264.579713) (xy 356.045506 -264.527009) (xy 355.816928 -264.527009)
			(xy 355.816911 -264.527934) (xy 355.808421 -264.582423) (xy 355.791637 -264.634954) (xy 355.766961 -264.684272)
			(xy 355.734981 -264.729199) (xy 355.716078 -264.74928) (xy 355.687376 -264.77849) (xy 355.816154 -264.97534)
			(xy 355.850698 -264.967212) (xy 355.870361 -264.962947) (xy 355.910336 -264.958365) (xy 355.930454 -264.958068)
			(xy 355.931216 -264.958068) (xy 355.959199 -264.958618) (xy 356.014476 -264.967375) (xy 356.067702 -264.984671)
			(xy 356.117568 -265.010079) (xy 356.162845 -265.042975) (xy 356.20242 -265.082549) (xy 356.235317 -265.127825)
			(xy 356.260726 -265.177691) (xy 356.278023 -265.230917) (xy 356.286781 -265.286193) (xy 356.287324 -265.314176)
			(xy 356.286815 -265.340825) (xy 356.515406 -265.340825) (xy 356.515406 -265.287527) (xy 356.523349 -265.234823)
			(xy 356.539059 -265.183893) (xy 356.562185 -265.135872) (xy 356.592209 -265.091835) (xy 356.628461 -265.052764)
			(xy 356.670132 -265.019533) (xy 356.71629 -264.992884) (xy 356.765904 -264.973412) (xy 356.817866 -264.961552)
			(xy 356.871016 -264.957569) (xy 356.924166 -264.961552) (xy 356.976128 -264.973412) (xy 357.025742 -264.992884)
			(xy 357.0719 -265.019533) (xy 357.113571 -265.052764) (xy 357.149823 -265.091835) (xy 357.179847 -265.135872)
			(xy 357.202973 -265.183893) (xy 357.218683 -265.234823) (xy 357.226626 -265.287527) (xy 357.227124 -265.314176)
			(xy 357.226626 -265.340825) (xy 357.218683 -265.393529) (xy 357.202973 -265.444459) (xy 357.179847 -265.49248)
			(xy 357.149823 -265.536517) (xy 357.113571 -265.575588) (xy 357.0719 -265.608819) (xy 357.025742 -265.635468)
			(xy 356.976128 -265.65494) (xy 356.924166 -265.6668) (xy 356.871016 -265.670784) (xy 356.817866 -265.6668)
			(xy 356.765904 -265.65494) (xy 356.71629 -265.635468) (xy 356.670132 -265.608819) (xy 356.628461 -265.575588)
			(xy 356.592209 -265.536517) (xy 356.562185 -265.49248) (xy 356.539059 -265.444459) (xy 356.523349 -265.393529)
			(xy 356.515406 -265.340825) (xy 356.286815 -265.340825) (xy 356.286775 -265.342914) (xy 356.277541 -265.399643)
			(xy 356.259309 -265.45415) (xy 356.232554 -265.505018) (xy 356.215696 -265.528298) (xy 356.205536 -265.54176)
			(xy 356.205536 -265.612118) (xy 356.418388 -265.772392) (xy 356.432612 -265.773662) (xy 356.458849 -265.776495)
			(xy 356.510138 -265.788912) (xy 356.559033 -265.808761) (xy 356.604465 -265.835607) (xy 356.645438 -265.868863)
			(xy 356.681055 -265.9078) (xy 356.710537 -265.951567) (xy 356.733239 -265.999205) (xy 356.748663 -266.049671)
			(xy 356.756472 -266.101861) (xy 356.75697 -266.128246) (xy 356.756444 -266.154895) (xy 356.985306 -266.154895)
			(xy 356.985306 -266.101597) (xy 356.993249 -266.048893) (xy 357.008959 -265.997963) (xy 357.032085 -265.949942)
			(xy 357.062109 -265.905905) (xy 357.098361 -265.866834) (xy 357.140032 -265.833603) (xy 357.18619 -265.806954)
			(xy 357.235804 -265.787482) (xy 357.287766 -265.775622) (xy 357.340916 -265.771639) (xy 357.394066 -265.775622)
			(xy 357.446028 -265.787482) (xy 357.495642 -265.806954) (xy 357.5418 -265.833603) (xy 357.583471 -265.866834)
			(xy 357.619723 -265.905905) (xy 357.649747 -265.949942) (xy 357.672873 -265.997963) (xy 357.688583 -266.048893)
			(xy 357.696526 -266.101597) (xy 357.697024 -266.128246) (xy 357.696526 -266.154895) (xy 357.688583 -266.207599)
			(xy 357.672873 -266.258529) (xy 357.649747 -266.30655) (xy 357.619723 -266.350587) (xy 357.583471 -266.389658)
			(xy 357.5418 -266.422889) (xy 357.495642 -266.449538) (xy 357.446028 -266.46901) (xy 357.394066 -266.48087)
			(xy 357.340916 -266.484854) (xy 357.287766 -266.48087) (xy 357.235804 -266.46901) (xy 357.18619 -266.449538)
			(xy 357.140032 -266.422889) (xy 357.098361 -266.389658) (xy 357.062109 -266.350587) (xy 357.032085 -266.30655)
			(xy 357.008959 -266.258529) (xy 356.993249 -266.207599) (xy 356.985306 -266.154895) (xy 356.756444 -266.154895)
			(xy 356.756418 -266.156226) (xy 356.747657 -266.211495) (xy 356.730358 -266.264713) (xy 356.704946 -266.314571)
			(xy 356.672049 -266.359839) (xy 356.632475 -266.399403) (xy 356.587199 -266.43229) (xy 356.537336 -266.45769)
			(xy 356.484113 -266.474976) (xy 356.428842 -266.483724) (xy 356.400862 -266.484354) (xy 356.382501 -266.484113)
			(xy 356.345978 -266.480294) (xy 356.327964 -266.476734) (xy 356.313107 -266.474171) (xy 356.283092 -266.476856)
			(xy 356.255169 -266.488186) (xy 356.231769 -266.507173) (xy 356.21493 -266.532164) (xy 356.206119 -266.560981)
			(xy 356.205536 -266.576048) (xy 356.205536 -266.714732) (xy 356.222604 -266.736139) (xy 356.250646 -266.78316)
			(xy 356.271162 -266.833919) (xy 356.283668 -266.88722) (xy 356.287869 -266.941806) (xy 356.285817 -266.968457)
			(xy 356.515406 -266.968457) (xy 356.515406 -266.915159) (xy 356.523349 -266.862455) (xy 356.539059 -266.811525)
			(xy 356.562185 -266.763504) (xy 356.592209 -266.719467) (xy 356.628461 -266.680396) (xy 356.670132 -266.647165)
			(xy 356.71629 -266.620516) (xy 356.765904 -266.601044) (xy 356.817866 -266.589184) (xy 356.871016 -266.585201)
			(xy 356.924166 -266.589184) (xy 356.976128 -266.601044) (xy 357.025742 -266.620516) (xy 357.0719 -266.647165)
			(xy 357.113571 -266.680396) (xy 357.149823 -266.719467) (xy 357.179847 -266.763504) (xy 357.202973 -266.811525)
			(xy 357.218683 -266.862455) (xy 357.226626 -266.915159) (xy 357.227124 -266.941808) (xy 357.226626 -266.968457)
			(xy 357.454952 -266.968457) (xy 357.454952 -266.915159) (xy 357.462895 -266.862455) (xy 357.478605 -266.811525)
			(xy 357.501731 -266.763504) (xy 357.531755 -266.719467) (xy 357.568007 -266.680396) (xy 357.609678 -266.647165)
			(xy 357.655836 -266.620516) (xy 357.70545 -266.601044) (xy 357.757412 -266.589184) (xy 357.810562 -266.585201)
			(xy 357.863712 -266.589184) (xy 357.915674 -266.601044) (xy 357.965288 -266.620516) (xy 358.011446 -266.647165)
			(xy 358.053117 -266.680396) (xy 358.089369 -266.719467) (xy 358.119393 -266.763504) (xy 358.142519 -266.811525)
			(xy 358.158229 -266.862455) (xy 358.166172 -266.915159) (xy 358.16667 -266.941808) (xy 358.166172 -266.968457)
			(xy 358.158229 -267.021161) (xy 358.142519 -267.072091) (xy 358.119393 -267.120112) (xy 358.089369 -267.164149)
			(xy 358.053117 -267.20322) (xy 358.011446 -267.236451) (xy 357.965288 -267.2631) (xy 357.915674 -267.282572)
			(xy 357.863712 -267.294432) (xy 357.810562 -267.298416) (xy 357.757412 -267.294432) (xy 357.70545 -267.282572)
			(xy 357.655836 -267.2631) (xy 357.609678 -267.236451) (xy 357.568007 -267.20322) (xy 357.531755 -267.164149)
			(xy 357.501731 -267.120112) (xy 357.478605 -267.072091) (xy 357.462895 -267.021161) (xy 357.454952 -266.968457)
			(xy 357.226626 -266.968457) (xy 357.218683 -267.021161) (xy 357.202973 -267.072091) (xy 357.179847 -267.120112)
			(xy 357.149823 -267.164149) (xy 357.113571 -267.20322) (xy 357.0719 -267.236451) (xy 357.025742 -267.2631)
			(xy 356.976128 -267.282572) (xy 356.924166 -267.294432) (xy 356.871016 -267.298416) (xy 356.817866 -267.294432)
			(xy 356.765904 -267.282572) (xy 356.71629 -267.2631) (xy 356.670132 -267.236451) (xy 356.628461 -267.20322)
			(xy 356.592209 -267.164149) (xy 356.562185 -267.120112) (xy 356.539059 -267.072091) (xy 356.523349 -267.021161)
			(xy 356.515406 -266.968457) (xy 356.285817 -266.968457) (xy 356.283666 -266.996393) (xy 356.271158 -267.049693)
			(xy 356.250641 -267.100451) (xy 356.222597 -267.147471) (xy 356.205536 -267.168884) (xy 356.205536 -267.308076)
			(xy 356.20613 -267.323127) (xy 356.214997 -267.351897) (xy 356.231851 -267.376843) (xy 356.255235 -267.395805)
			(xy 356.283124 -267.407143) (xy 356.313106 -267.409874) (xy 356.327964 -267.40739) (xy 356.345981 -267.403851)
			(xy 356.382502 -267.400031) (xy 356.400862 -267.39977) (xy 356.426445 -267.400211) (xy 356.477085 -267.407532)
			(xy 356.526155 -267.422029) (xy 356.572643 -267.443403) (xy 356.615591 -267.471213) (xy 356.654115 -267.504886)
			(xy 356.68742 -267.543729) (xy 356.71482 -267.586941) (xy 356.73575 -267.63363) (xy 356.749778 -267.682836)
			(xy 356.753668 -267.708126) (xy 356.759764 -267.752068) (xy 356.921816 -267.752068) (xy 356.99192 -267.681964)
			(xy 356.995476 -267.668248) (xy 357.002361 -267.642992) (xy 357.022523 -267.594683) (xy 357.049542 -267.549846)
			(xy 357.082835 -267.50945) (xy 357.121683 -267.474363) (xy 357.16525 -267.445342) (xy 357.212597 -267.423014)
			(xy 357.262703 -267.407858) (xy 357.314488 -267.400202) (xy 357.340662 -267.39977) (xy 357.36865 -267.400287)
			(xy 357.423938 -267.409038) (xy 357.477175 -267.42633) (xy 357.527053 -267.451738) (xy 357.572341 -267.484636)
			(xy 357.611925 -267.524213) (xy 357.64483 -267.569496) (xy 357.670247 -267.619369) (xy 357.687548 -267.672604)
			(xy 357.696308 -267.72789) (xy 357.69677 -267.755878) (xy 357.69631 -267.782051) (xy 357.69624 -267.782527)
			(xy 357.924852 -267.782527) (xy 357.924852 -267.729229) (xy 357.932795 -267.676525) (xy 357.948505 -267.625595)
			(xy 357.971631 -267.577574) (xy 358.001655 -267.533537) (xy 358.037907 -267.494466) (xy 358.079578 -267.461235)
			(xy 358.125736 -267.434586) (xy 358.17535 -267.415114) (xy 358.227312 -267.403254) (xy 358.280462 -267.399271)
			(xy 358.333612 -267.403254) (xy 358.385574 -267.415114) (xy 358.435188 -267.434586) (xy 358.481346 -267.461235)
			(xy 358.523017 -267.494466) (xy 358.559269 -267.533537) (xy 358.589293 -267.577574) (xy 358.612419 -267.625595)
			(xy 358.628129 -267.676525) (xy 358.636072 -267.729229) (xy 358.63657 -267.755878) (xy 358.636072 -267.782527)
			(xy 358.628129 -267.835231) (xy 358.612419 -267.886161) (xy 358.589293 -267.934182) (xy 358.559269 -267.978219)
			(xy 358.523017 -268.01729) (xy 358.481346 -268.050521) (xy 358.435188 -268.07717) (xy 358.385574 -268.096642)
			(xy 358.333612 -268.108502) (xy 358.280462 -268.112486) (xy 358.227312 -268.108502) (xy 358.17535 -268.096642)
			(xy 358.125736 -268.07717) (xy 358.079578 -268.050521) (xy 358.037907 -268.01729) (xy 358.001655 -267.978219)
			(xy 357.971631 -267.934182) (xy 357.948505 -267.886161) (xy 357.932795 -267.835231) (xy 357.924852 -267.782527)
			(xy 357.69624 -267.782527) (xy 357.688651 -267.833834) (xy 357.673495 -267.883938) (xy 357.651169 -267.931285)
			(xy 357.622154 -267.974853) (xy 357.587074 -268.013706) (xy 357.546685 -268.047005) (xy 357.501857 -268.074034)
			(xy 357.453555 -268.094211) (xy 357.428292 -268.101064) (xy 357.414576 -268.10462) (xy 357.256842 -268.262354)
			(xy 357.248931 -268.270063) (xy 357.232149 -268.284427) (xy 357.223314 -268.291056) (xy 357.212331 -268.299797)
			(xy 357.195242 -268.322051) (xy 357.184846 -268.348113) (xy 357.181927 -268.37602) (xy 357.186705 -268.403669)
			(xy 357.192326 -268.416532) (xy 357.203211 -268.440539) (xy 357.218585 -268.490956) (xy 357.226376 -268.543086)
			(xy 357.22687 -268.56944) (xy 357.22687 -268.569694) (xy 357.226375 -268.596343) (xy 357.454952 -268.596343)
			(xy 357.454952 -268.543045) (xy 357.462895 -268.490341) (xy 357.478605 -268.439411) (xy 357.501731 -268.39139)
			(xy 357.531755 -268.347353) (xy 357.568007 -268.308282) (xy 357.609678 -268.275051) (xy 357.655836 -268.248402)
			(xy 357.70545 -268.22893) (xy 357.757412 -268.21707) (xy 357.810562 -268.213087) (xy 357.863712 -268.21707)
			(xy 357.915674 -268.22893) (xy 357.965288 -268.248402) (xy 358.011446 -268.275051) (xy 358.053117 -268.308282)
			(xy 358.089369 -268.347353) (xy 358.119393 -268.39139) (xy 358.142519 -268.439411) (xy 358.158229 -268.490341)
			(xy 358.166172 -268.543045) (xy 358.16667 -268.569694) (xy 358.166172 -268.596343) (xy 358.158229 -268.649047)
			(xy 358.142519 -268.699977) (xy 358.119393 -268.747998) (xy 358.089369 -268.792035) (xy 358.053117 -268.831106)
			(xy 358.011446 -268.864337) (xy 357.965288 -268.890986) (xy 357.915674 -268.910458) (xy 357.863712 -268.922318)
			(xy 357.810562 -268.926302) (xy 357.757412 -268.922318) (xy 357.70545 -268.910458) (xy 357.655836 -268.890986)
			(xy 357.609678 -268.864337) (xy 357.568007 -268.831106) (xy 357.531755 -268.792035) (xy 357.501731 -268.747998)
			(xy 357.478605 -268.699977) (xy 357.462895 -268.649047) (xy 357.454952 -268.596343) (xy 357.226375 -268.596343)
			(xy 357.22635 -268.597679) (xy 357.217595 -268.652959) (xy 357.200299 -268.706188) (xy 357.174888 -268.756057)
			(xy 357.141989 -268.801336) (xy 357.102411 -268.84091) (xy 357.057129 -268.873805) (xy 357.007259 -268.899211)
			(xy 356.954027 -268.916502) (xy 356.898747 -268.925252) (xy 356.870762 -268.925802) (xy 356.850581 -268.925505)
			(xy 356.81048 -268.920921) (xy 356.790752 -268.916658) (xy 356.775398 -268.913694) (xy 356.744243 -268.916197)
			(xy 356.715306 -268.928009) (xy 356.6913 -268.948023) (xy 356.674474 -268.974362) (xy 356.669848 -268.989302)
			(xy 356.664195 -269.008712) (xy 356.648386 -269.04592) (xy 356.638352 -269.06347) (xy 356.63307 -269.073638)
			(xy 356.631085 -269.096434) (xy 356.639154 -269.117846) (xy 356.646988 -269.126208) (xy 356.667414 -269.146487)
			(xy 356.702088 -269.192426) (xy 356.728912 -269.243348) (xy 356.747188 -269.297925) (xy 356.756437 -269.354732)
			(xy 356.75697 -269.38351) (xy 356.756474 -269.410159) (xy 356.985052 -269.410159) (xy 356.985052 -269.356861)
			(xy 356.992995 -269.304157) (xy 357.008705 -269.253227) (xy 357.031831 -269.205206) (xy 357.061855 -269.161169)
			(xy 357.098107 -269.122098) (xy 357.139778 -269.088867) (xy 357.185936 -269.062218) (xy 357.23555 -269.042746)
			(xy 357.287512 -269.030886) (xy 357.340662 -269.026903) (xy 357.393812 -269.030886) (xy 357.445774 -269.042746)
			(xy 357.495388 -269.062218) (xy 357.541546 -269.088867) (xy 357.583217 -269.122098) (xy 357.619469 -269.161169)
			(xy 357.649493 -269.205206) (xy 357.672619 -269.253227) (xy 357.688329 -269.304157) (xy 357.696272 -269.356861)
			(xy 357.69677 -269.38351) (xy 357.696272 -269.410159) (xy 357.924852 -269.410159) (xy 357.924852 -269.356861)
			(xy 357.932795 -269.304157) (xy 357.948505 -269.253227) (xy 357.971631 -269.205206) (xy 358.001655 -269.161169)
			(xy 358.037907 -269.122098) (xy 358.079578 -269.088867) (xy 358.125736 -269.062218) (xy 358.17535 -269.042746)
			(xy 358.227312 -269.030886) (xy 358.280462 -269.026903) (xy 358.333612 -269.030886) (xy 358.385574 -269.042746)
			(xy 358.435188 -269.062218) (xy 358.481346 -269.088867) (xy 358.523017 -269.122098) (xy 358.559269 -269.161169)
			(xy 358.589293 -269.205206) (xy 358.612419 -269.253227) (xy 358.628129 -269.304157) (xy 358.636072 -269.356861)
			(xy 358.63657 -269.38351) (xy 358.636072 -269.410159) (xy 358.628129 -269.462863) (xy 358.612419 -269.513793)
			(xy 358.589293 -269.561814) (xy 358.559269 -269.605851) (xy 358.523017 -269.644922) (xy 358.481346 -269.678153)
			(xy 358.435188 -269.704802) (xy 358.385574 -269.724274) (xy 358.333612 -269.736134) (xy 358.280462 -269.740118)
			(xy 358.227312 -269.736134) (xy 358.17535 -269.724274) (xy 358.125736 -269.704802) (xy 358.079578 -269.678153)
			(xy 358.037907 -269.644922) (xy 358.001655 -269.605851) (xy 357.971631 -269.561814) (xy 357.948505 -269.513793)
			(xy 357.932795 -269.462863) (xy 357.924852 -269.410159) (xy 357.696272 -269.410159) (xy 357.688329 -269.462863)
			(xy 357.672619 -269.513793) (xy 357.649493 -269.561814) (xy 357.619469 -269.605851) (xy 357.583217 -269.644922)
			(xy 357.541546 -269.678153) (xy 357.495388 -269.704802) (xy 357.445774 -269.724274) (xy 357.393812 -269.736134)
			(xy 357.340662 -269.740118) (xy 357.287512 -269.736134) (xy 357.23555 -269.724274) (xy 357.185936 -269.704802)
			(xy 357.139778 -269.678153) (xy 357.098107 -269.644922) (xy 357.061855 -269.605851) (xy 357.031831 -269.561814)
			(xy 357.008705 -269.513793) (xy 356.992995 -269.462863) (xy 356.985052 -269.410159) (xy 356.756474 -269.410159)
			(xy 356.756449 -269.411494) (xy 356.747691 -269.466772) (xy 356.730394 -269.519999) (xy 356.704983 -269.569865)
			(xy 356.672083 -269.615142) (xy 356.632506 -269.654715) (xy 356.587225 -269.687608) (xy 356.537355 -269.713013)
			(xy 356.484125 -269.730303) (xy 356.428846 -269.739052) (xy 356.400862 -269.739618) (xy 356.376878 -269.739227)
			(xy 356.329346 -269.732777) (xy 356.283115 -269.719985) (xy 356.260908 -269.710916) (xy 356.250145 -269.736669)
			(xy 356.225743 -269.786874) (xy 356.21214 -269.811246) (xy 356.205536 -269.82293) (xy 356.205536 -269.970504)
			(xy 356.222606 -269.991911) (xy 356.250653 -270.038933) (xy 356.271173 -270.089693) (xy 356.283682 -270.142995)
			(xy 356.287886 -270.197585) (xy 356.285837 -270.224229) (xy 356.515152 -270.224229) (xy 356.515152 -270.170931)
			(xy 356.523095 -270.118227) (xy 356.538805 -270.067297) (xy 356.561931 -270.019276) (xy 356.591955 -269.975239)
			(xy 356.628207 -269.936168) (xy 356.669878 -269.902937) (xy 356.716036 -269.876288) (xy 356.76565 -269.856816)
			(xy 356.817612 -269.844956) (xy 356.870762 -269.840973) (xy 356.923912 -269.844956) (xy 356.975874 -269.856816)
			(xy 357.025488 -269.876288) (xy 357.071646 -269.902937) (xy 357.113317 -269.936168) (xy 357.149569 -269.975239)
			(xy 357.179593 -270.019276) (xy 357.202719 -270.067297) (xy 357.218429 -270.118227) (xy 357.226372 -270.170931)
			(xy 357.22687 -270.19758) (xy 357.226372 -270.224229) (xy 357.454952 -270.224229) (xy 357.454952 -270.170931)
			(xy 357.462895 -270.118227) (xy 357.478605 -270.067297) (xy 357.501731 -270.019276) (xy 357.531755 -269.975239)
			(xy 357.568007 -269.936168) (xy 357.609678 -269.902937) (xy 357.655836 -269.876288) (xy 357.70545 -269.856816)
			(xy 357.757412 -269.844956) (xy 357.810562 -269.840973) (xy 357.863712 -269.844956) (xy 357.915674 -269.856816)
			(xy 357.965288 -269.876288) (xy 358.011446 -269.902937) (xy 358.053117 -269.936168) (xy 358.089369 -269.975239)
			(xy 358.119393 -270.019276) (xy 358.142519 -270.067297) (xy 358.158229 -270.118227) (xy 358.166172 -270.170931)
			(xy 358.16667 -270.19758) (xy 358.166172 -270.224229) (xy 358.158229 -270.276933) (xy 358.142519 -270.327863)
			(xy 358.119393 -270.375884) (xy 358.089369 -270.419921) (xy 358.053117 -270.458992) (xy 358.011446 -270.492223)
			(xy 357.965288 -270.518872) (xy 357.915674 -270.538344) (xy 357.863712 -270.550204) (xy 357.810562 -270.554188)
			(xy 357.757412 -270.550204) (xy 357.70545 -270.538344) (xy 357.655836 -270.518872) (xy 357.609678 -270.492223)
			(xy 357.568007 -270.458992) (xy 357.531755 -270.419921) (xy 357.501731 -270.375884) (xy 357.478605 -270.327863)
			(xy 357.462895 -270.276933) (xy 357.454952 -270.224229) (xy 357.226372 -270.224229) (xy 357.218429 -270.276933)
			(xy 357.202719 -270.327863) (xy 357.179593 -270.375884) (xy 357.149569 -270.419921) (xy 357.113317 -270.458992)
			(xy 357.071646 -270.492223) (xy 357.025488 -270.518872) (xy 356.975874 -270.538344) (xy 356.923912 -270.550204)
			(xy 356.870762 -270.554188) (xy 356.817612 -270.550204) (xy 356.76565 -270.538344) (xy 356.716036 -270.518872)
			(xy 356.669878 -270.492223) (xy 356.628207 -270.458992) (xy 356.591955 -270.419921) (xy 356.561931 -270.375884)
			(xy 356.538805 -270.327863) (xy 356.523095 -270.276933) (xy 356.515152 -270.224229) (xy 356.285837 -270.224229)
			(xy 356.283687 -270.252174) (xy 356.271182 -270.305478) (xy 356.250666 -270.356239) (xy 356.222624 -270.403263)
			(xy 356.205536 -270.424656) (xy 356.205536 -270.563594) (xy 356.206119 -270.578653) (xy 356.214972 -270.607445)
			(xy 356.231824 -270.632413) (xy 356.255214 -270.651393) (xy 356.283117 -270.662741) (xy 356.313115 -270.665474)
			(xy 356.327964 -270.662908) (xy 356.345981 -270.659369) (xy 356.382502 -270.655551) (xy 356.400862 -270.655288)
			(xy 356.427515 -270.655759) (xy 356.480227 -270.663698) (xy 356.531167 -270.679406) (xy 356.579196 -270.702531)
			(xy 356.623242 -270.732557) (xy 356.66232 -270.768813) (xy 356.695558 -270.810488) (xy 356.722213 -270.856652)
			(xy 356.74169 -270.906273) (xy 356.753552 -270.958243) (xy 356.757536 -271.0114) (xy 356.755539 -271.038045)
			(xy 356.985052 -271.038045) (xy 356.985052 -270.984747) (xy 356.992995 -270.932043) (xy 357.008705 -270.881113)
			(xy 357.031831 -270.833092) (xy 357.061855 -270.789055) (xy 357.098107 -270.749984) (xy 357.139778 -270.716753)
			(xy 357.185936 -270.690104) (xy 357.23555 -270.670632) (xy 357.287512 -270.658772) (xy 357.340662 -270.654789)
			(xy 357.393812 -270.658772) (xy 357.445774 -270.670632) (xy 357.495388 -270.690104) (xy 357.541546 -270.716753)
			(xy 357.583217 -270.749984) (xy 357.619469 -270.789055) (xy 357.649493 -270.833092) (xy 357.672619 -270.881113)
			(xy 357.688329 -270.932043) (xy 357.696272 -270.984747) (xy 357.69677 -271.011396) (xy 357.696272 -271.038045)
			(xy 357.924852 -271.038045) (xy 357.924852 -270.984747) (xy 357.932795 -270.932043) (xy 357.948505 -270.881113)
			(xy 357.971631 -270.833092) (xy 358.001655 -270.789055) (xy 358.037907 -270.749984) (xy 358.079578 -270.716753)
			(xy 358.125736 -270.690104) (xy 358.17535 -270.670632) (xy 358.227312 -270.658772) (xy 358.280462 -270.654789)
			(xy 358.333612 -270.658772) (xy 358.385574 -270.670632) (xy 358.435188 -270.690104) (xy 358.481346 -270.716753)
			(xy 358.523017 -270.749984) (xy 358.559269 -270.789055) (xy 358.589293 -270.833092) (xy 358.612419 -270.881113)
			(xy 358.628129 -270.932043) (xy 358.636072 -270.984747) (xy 358.63657 -271.011396) (xy 358.636072 -271.038045)
			(xy 358.628129 -271.090749) (xy 358.612419 -271.141679) (xy 358.589293 -271.1897) (xy 358.559269 -271.233737)
			(xy 358.523017 -271.272808) (xy 358.481346 -271.306039) (xy 358.435188 -271.332688) (xy 358.385574 -271.35216)
			(xy 358.333612 -271.36402) (xy 358.280462 -271.368004) (xy 358.227312 -271.36402) (xy 358.17535 -271.35216)
			(xy 358.125736 -271.332688) (xy 358.079578 -271.306039) (xy 358.037907 -271.272808) (xy 358.001655 -271.233737)
			(xy 357.971631 -271.1897) (xy 357.948505 -271.141679) (xy 357.932795 -271.090749) (xy 357.924852 -271.038045)
			(xy 357.696272 -271.038045) (xy 357.688329 -271.090749) (xy 357.672619 -271.141679) (xy 357.649493 -271.1897)
			(xy 357.619469 -271.233737) (xy 357.583217 -271.272808) (xy 357.541546 -271.306039) (xy 357.495388 -271.332688)
			(xy 357.445774 -271.35216) (xy 357.393812 -271.36402) (xy 357.340662 -271.368004) (xy 357.287512 -271.36402)
			(xy 357.23555 -271.35216) (xy 357.185936 -271.332688) (xy 357.139778 -271.306039) (xy 357.098107 -271.272808)
			(xy 357.061855 -271.233737) (xy 357.031831 -271.1897) (xy 357.008705 -271.141679) (xy 356.992995 -271.090749)
			(xy 356.985052 -271.038045) (xy 356.755539 -271.038045) (xy 356.753552 -271.064557) (xy 356.74169 -271.116527)
			(xy 356.722213 -271.166148) (xy 356.695558 -271.212312) (xy 356.66232 -271.253987) (xy 356.623242 -271.290243)
			(xy 356.579196 -271.320269) (xy 356.531167 -271.343394) (xy 356.480227 -271.359102) (xy 356.427515 -271.367041)
			(xy 356.400862 -271.367504) (xy 356.382501 -271.367263) (xy 356.345978 -271.363444) (xy 356.327964 -271.359884)
			(xy 356.313104 -271.357321) (xy 356.283085 -271.360008) (xy 356.255157 -271.371336) (xy 356.23175 -271.390322)
			(xy 356.214901 -271.415311) (xy 356.206078 -271.444129) (xy 356.205536 -271.459198) (xy 356.205536 -271.598136)
			(xy 356.222604 -271.619543) (xy 356.250645 -271.666564) (xy 356.271161 -271.717323) (xy 356.283666 -271.770623)
			(xy 356.287866 -271.825209) (xy 356.285814 -271.851861) (xy 356.515406 -271.851861) (xy 356.515406 -271.798563)
			(xy 356.523349 -271.745859) (xy 356.539059 -271.694929) (xy 356.562185 -271.646908) (xy 356.592209 -271.602871)
			(xy 356.628461 -271.5638) (xy 356.670132 -271.530569) (xy 356.71629 -271.50392) (xy 356.765904 -271.484448)
			(xy 356.817866 -271.472588) (xy 356.871016 -271.468605) (xy 356.924166 -271.472588) (xy 356.976128 -271.484448)
			(xy 357.025742 -271.50392) (xy 357.0719 -271.530569) (xy 357.113571 -271.5638) (xy 357.149823 -271.602871)
			(xy 357.179847 -271.646908) (xy 357.202973 -271.694929) (xy 357.218683 -271.745859) (xy 357.226626 -271.798563)
			(xy 357.227124 -271.825212) (xy 357.226626 -271.851861) (xy 357.454698 -271.851861) (xy 357.454698 -271.798563)
			(xy 357.462641 -271.745859) (xy 357.478351 -271.694929) (xy 357.501477 -271.646908) (xy 357.531501 -271.602871)
			(xy 357.567753 -271.5638) (xy 357.609424 -271.530569) (xy 357.655582 -271.50392) (xy 357.705196 -271.484448)
			(xy 357.757158 -271.472588) (xy 357.810308 -271.468605) (xy 357.863458 -271.472588) (xy 357.91542 -271.484448)
			(xy 357.965034 -271.50392) (xy 358.011192 -271.530569) (xy 358.052863 -271.5638) (xy 358.089115 -271.602871)
			(xy 358.119139 -271.646908) (xy 358.142265 -271.694929) (xy 358.157975 -271.745859) (xy 358.165918 -271.798563)
			(xy 358.166416 -271.825212) (xy 358.165918 -271.851861) (xy 358.157975 -271.904565) (xy 358.142265 -271.955495)
			(xy 358.119139 -272.003516) (xy 358.089115 -272.047553) (xy 358.052863 -272.086624) (xy 358.011192 -272.119855)
			(xy 357.965034 -272.146504) (xy 357.91542 -272.165976) (xy 357.863458 -272.177836) (xy 357.810308 -272.18182)
			(xy 357.757158 -272.177836) (xy 357.705196 -272.165976) (xy 357.655582 -272.146504) (xy 357.609424 -272.119855)
			(xy 357.567753 -272.086624) (xy 357.531501 -272.047553) (xy 357.501477 -272.003516) (xy 357.478351 -271.955495)
			(xy 357.462641 -271.904565) (xy 357.454698 -271.851861) (xy 357.226626 -271.851861) (xy 357.218683 -271.904565)
			(xy 357.202973 -271.955495) (xy 357.179847 -272.003516) (xy 357.149823 -272.047553) (xy 357.113571 -272.086624)
			(xy 357.0719 -272.119855) (xy 357.025742 -272.146504) (xy 356.976128 -272.165976) (xy 356.924166 -272.177836)
			(xy 356.871016 -272.18182) (xy 356.817866 -272.177836) (xy 356.765904 -272.165976) (xy 356.71629 -272.146504)
			(xy 356.670132 -272.119855) (xy 356.628461 -272.086624) (xy 356.592209 -272.047553) (xy 356.562185 -272.003516)
			(xy 356.539059 -271.955495) (xy 356.523349 -271.904565) (xy 356.515406 -271.851861) (xy 356.285814 -271.851861)
			(xy 356.283663 -271.879795) (xy 356.271155 -271.933095) (xy 356.250637 -271.983852) (xy 356.222593 -272.030872)
			(xy 356.205536 -272.052288) (xy 356.205536 -272.199862) (xy 356.21214 -272.211546) (xy 356.225741 -272.235919)
			(xy 356.250143 -272.286124) (xy 356.260908 -272.311876) (xy 356.283115 -272.302811) (xy 356.329351 -272.290043)
			(xy 356.376879 -272.283577) (xy 356.400862 -272.283174) (xy 356.427516 -272.283645) (xy 356.48023 -272.291585)
			(xy 356.531172 -272.307293) (xy 356.579203 -272.330419) (xy 356.623251 -272.360446) (xy 356.662331 -272.396703)
			(xy 356.69557 -272.43838) (xy 356.722226 -272.484546) (xy 356.741703 -272.534169) (xy 356.753566 -272.58614)
			(xy 356.75755 -272.6393) (xy 356.755554 -272.665931) (xy 356.985052 -272.665931) (xy 356.985052 -272.612633)
			(xy 356.992995 -272.559929) (xy 357.008705 -272.508999) (xy 357.031831 -272.460978) (xy 357.061855 -272.416941)
			(xy 357.098107 -272.37787) (xy 357.139778 -272.344639) (xy 357.185936 -272.31799) (xy 357.23555 -272.298518)
			(xy 357.287512 -272.286658) (xy 357.340662 -272.282675) (xy 357.393812 -272.286658) (xy 357.445774 -272.298518)
			(xy 357.495388 -272.31799) (xy 357.541546 -272.344639) (xy 357.583217 -272.37787) (xy 357.619469 -272.416941)
			(xy 357.649493 -272.460978) (xy 357.672619 -272.508999) (xy 357.688329 -272.559929) (xy 357.696272 -272.612633)
			(xy 357.69677 -272.639282) (xy 357.696272 -272.665931) (xy 357.924852 -272.665931) (xy 357.924852 -272.612633)
			(xy 357.932795 -272.559929) (xy 357.948505 -272.508999) (xy 357.971631 -272.460978) (xy 358.001655 -272.416941)
			(xy 358.037907 -272.37787) (xy 358.079578 -272.344639) (xy 358.125736 -272.31799) (xy 358.17535 -272.298518)
			(xy 358.227312 -272.286658) (xy 358.280462 -272.282675) (xy 358.333612 -272.286658) (xy 358.385574 -272.298518)
			(xy 358.435188 -272.31799) (xy 358.481346 -272.344639) (xy 358.523017 -272.37787) (xy 358.559269 -272.416941)
			(xy 358.589293 -272.460978) (xy 358.612419 -272.508999) (xy 358.628129 -272.559929) (xy 358.636072 -272.612633)
			(xy 358.63657 -272.639282) (xy 358.636072 -272.665931) (xy 358.628129 -272.718635) (xy 358.612419 -272.769565)
			(xy 358.589293 -272.817586) (xy 358.559269 -272.861623) (xy 358.523017 -272.900694) (xy 358.481346 -272.933925)
			(xy 358.435188 -272.960574) (xy 358.385574 -272.980046) (xy 358.333612 -272.991906) (xy 358.280462 -272.99589)
			(xy 358.227312 -272.991906) (xy 358.17535 -272.980046) (xy 358.125736 -272.960574) (xy 358.079578 -272.933925)
			(xy 358.037907 -272.900694) (xy 358.001655 -272.861623) (xy 357.971631 -272.817586) (xy 357.948505 -272.769565)
			(xy 357.932795 -272.718635) (xy 357.924852 -272.665931) (xy 357.696272 -272.665931) (xy 357.688329 -272.718635)
			(xy 357.672619 -272.769565) (xy 357.649493 -272.817586) (xy 357.619469 -272.861623) (xy 357.583217 -272.900694)
			(xy 357.541546 -272.933925) (xy 357.495388 -272.960574) (xy 357.445774 -272.980046) (xy 357.393812 -272.991906)
			(xy 357.340662 -272.99589) (xy 357.287512 -272.991906) (xy 357.23555 -272.980046) (xy 357.185936 -272.960574)
			(xy 357.139778 -272.933925) (xy 357.098107 -272.900694) (xy 357.061855 -272.861623) (xy 357.031831 -272.817586)
			(xy 357.008705 -272.769565) (xy 356.992995 -272.718635) (xy 356.985052 -272.665931) (xy 356.755554 -272.665931)
			(xy 356.753566 -272.69246) (xy 356.741703 -272.744431) (xy 356.722226 -272.794054) (xy 356.69557 -272.84022)
			(xy 356.662331 -272.881897) (xy 356.623251 -272.918154) (xy 356.579203 -272.948181) (xy 356.531172 -272.971307)
			(xy 356.48023 -272.987015) (xy 356.427516 -272.994955) (xy 356.400862 -272.99539) (xy 356.376878 -272.994999)
			(xy 356.329346 -272.988548) (xy 356.283116 -272.975755) (xy 356.260908 -272.966688) (xy 356.25014 -272.992377)
			(xy 356.225736 -273.042453) (xy 356.21214 -273.066764) (xy 356.205536 -273.078448) (xy 356.205536 -273.226022)
			(xy 356.220922 -273.245264) (xy 356.246805 -273.287184) (xy 356.266663 -273.332273) (xy 356.280116 -273.379667)
			(xy 356.286907 -273.428464) (xy 356.287324 -273.453098) (xy 356.541324 -273.453098) (xy 356.541832 -273.427211)
			(xy 356.549931 -273.376073) (xy 356.56593 -273.326833) (xy 356.589436 -273.280701) (xy 356.619868 -273.238814)
			(xy 356.656478 -273.202204) (xy 356.698365 -273.171772) (xy 356.744497 -273.148266) (xy 356.793737 -273.132267)
			(xy 356.844875 -273.124168) (xy 356.896649 -273.124168) (xy 356.947787 -273.132267) (xy 356.997027 -273.148266)
			(xy 357.043159 -273.171772) (xy 357.085046 -273.202204) (xy 357.121656 -273.238814) (xy 357.152088 -273.280701)
			(xy 357.175594 -273.326833) (xy 357.191593 -273.376073) (xy 357.199692 -273.427211) (xy 357.2002 -273.453098)
			(xy 357.19969 -273.479747) (xy 357.454952 -273.479747) (xy 357.454952 -273.426449) (xy 357.462895 -273.373745)
			(xy 357.478605 -273.322815) (xy 357.501731 -273.274794) (xy 357.531755 -273.230757) (xy 357.568007 -273.191686)
			(xy 357.609678 -273.158455) (xy 357.655836 -273.131806) (xy 357.70545 -273.112334) (xy 357.757412 -273.100474)
			(xy 357.810562 -273.096491) (xy 357.863712 -273.100474) (xy 357.915674 -273.112334) (xy 357.965288 -273.131806)
			(xy 358.011446 -273.158455) (xy 358.053117 -273.191686) (xy 358.089369 -273.230757) (xy 358.119393 -273.274794)
			(xy 358.142519 -273.322815) (xy 358.158229 -273.373745) (xy 358.166172 -273.426449) (xy 358.16667 -273.453098)
			(xy 358.166172 -273.479747) (xy 358.158229 -273.532451) (xy 358.142519 -273.583381) (xy 358.119393 -273.631402)
			(xy 358.089369 -273.675439) (xy 358.053117 -273.71451) (xy 358.011446 -273.747741) (xy 357.965288 -273.77439)
			(xy 357.915674 -273.793862) (xy 357.863712 -273.805722) (xy 357.810562 -273.809706) (xy 357.757412 -273.805722)
			(xy 357.70545 -273.793862) (xy 357.655836 -273.77439) (xy 357.609678 -273.747741) (xy 357.568007 -273.71451)
			(xy 357.531755 -273.675439) (xy 357.501731 -273.631402) (xy 357.478605 -273.583381) (xy 357.462895 -273.532451)
			(xy 357.454952 -273.479747) (xy 357.19969 -273.479747) (xy 357.19967 -273.480806) (xy 357.190475 -273.535453)
			(xy 357.181912 -273.56181) (xy 357.174292 -273.583654) (xy 357.37927 -273.938746) (xy 357.40213 -273.943064)
			(xy 357.426938 -273.948232) (xy 357.474677 -273.965225) (xy 357.519254 -273.989322) (xy 357.559619 -274.019956)
			(xy 357.594821 -274.056405) (xy 357.624032 -274.097811) (xy 357.646564 -274.143199) (xy 357.661886 -274.191501)
			(xy 357.669637 -274.241577) (xy 357.6701 -274.266914) (xy 357.669592 -274.292801) (xy 357.669471 -274.293563)
			(xy 357.924852 -274.293563) (xy 357.924852 -274.240265) (xy 357.932795 -274.187561) (xy 357.948505 -274.136631)
			(xy 357.971631 -274.08861) (xy 358.001655 -274.044573) (xy 358.037907 -274.005502) (xy 358.079578 -273.972271)
			(xy 358.125736 -273.945622) (xy 358.17535 -273.92615) (xy 358.227312 -273.91429) (xy 358.280462 -273.910307)
			(xy 358.333612 -273.91429) (xy 358.385574 -273.92615) (xy 358.435188 -273.945622) (xy 358.481346 -273.972271)
			(xy 358.523017 -274.005502) (xy 358.559269 -274.044573) (xy 358.589293 -274.08861) (xy 358.612419 -274.136631)
			(xy 358.628129 -274.187561) (xy 358.636072 -274.240265) (xy 358.63657 -274.266914) (xy 358.636072 -274.293563)
			(xy 358.628129 -274.346267) (xy 358.612419 -274.397197) (xy 358.589293 -274.445218) (xy 358.559269 -274.489255)
			(xy 358.523017 -274.528326) (xy 358.481346 -274.561557) (xy 358.435188 -274.588206) (xy 358.385574 -274.607678)
			(xy 358.333612 -274.619538) (xy 358.280462 -274.623522) (xy 358.227312 -274.619538) (xy 358.17535 -274.607678)
			(xy 358.125736 -274.588206) (xy 358.079578 -274.561557) (xy 358.037907 -274.528326) (xy 358.001655 -274.489255)
			(xy 357.971631 -274.445218) (xy 357.948505 -274.397197) (xy 357.932795 -274.346267) (xy 357.924852 -274.293563)
			(xy 357.669471 -274.293563) (xy 357.661493 -274.343939) (xy 357.645494 -274.393179) (xy 357.621988 -274.439311)
			(xy 357.591556 -274.481198) (xy 357.554946 -274.517808) (xy 357.513059 -274.54824) (xy 357.466927 -274.571746)
			(xy 357.417687 -274.587745) (xy 357.366549 -274.595844) (xy 357.314775 -274.595844) (xy 357.263637 -274.587745)
			(xy 357.214397 -274.571746) (xy 357.168265 -274.54824) (xy 357.126378 -274.517808) (xy 357.089768 -274.481198)
			(xy 357.059336 -274.439311) (xy 357.03583 -274.393179) (xy 357.019831 -274.343939) (xy 357.011732 -274.292801)
			(xy 357.011224 -274.266914) (xy 357.011756 -274.239206) (xy 357.020949 -274.184559) (xy 357.029512 -274.158202)
			(xy 357.037386 -274.136104) (xy 356.832408 -273.781266) (xy 356.809548 -273.776948) (xy 356.784736 -273.771741)
			(xy 356.73696 -273.75479) (xy 356.692344 -273.730722) (xy 356.651938 -273.700106) (xy 356.616698 -273.663665)
			(xy 356.587453 -273.622257) (xy 356.564893 -273.576859) (xy 356.549551 -273.528542) (xy 356.541789 -273.478445)
			(xy 356.541324 -273.453098) (xy 356.287324 -273.453098) (xy 356.286858 -273.479311) (xy 356.27917 -273.531171)
			(xy 356.26396 -273.581342) (xy 356.241556 -273.628741) (xy 356.212444 -273.672341) (xy 356.177252 -273.711201)
			(xy 356.157276 -273.72818) (xy 356.155498 -273.729704) (xy 355.780086 -274.105116) (xy 355.792278 -274.136104)
			(xy 355.800157 -274.157002) (xy 355.811239 -274.200269) (xy 355.816823 -274.244582) (xy 355.81717 -274.266914)
			(xy 355.816673 -274.293563) (xy 356.045506 -274.293563) (xy 356.045506 -274.240265) (xy 356.053449 -274.187561)
			(xy 356.069159 -274.136631) (xy 356.092285 -274.08861) (xy 356.122309 -274.044573) (xy 356.158561 -274.005502)
			(xy 356.200232 -273.972271) (xy 356.24639 -273.945622) (xy 356.296004 -273.92615) (xy 356.347966 -273.91429)
			(xy 356.401116 -273.910307) (xy 356.454266 -273.91429) (xy 356.506228 -273.92615) (xy 356.555842 -273.945622)
			(xy 356.602 -273.972271) (xy 356.643671 -274.005502) (xy 356.679923 -274.044573) (xy 356.709947 -274.08861)
			(xy 356.733073 -274.136631) (xy 356.748783 -274.187561) (xy 356.756726 -274.240265) (xy 356.757224 -274.266914)
			(xy 356.756726 -274.293563) (xy 356.748783 -274.346267) (xy 356.733073 -274.397197) (xy 356.709947 -274.445218)
			(xy 356.679923 -274.489255) (xy 356.643671 -274.528326) (xy 356.602 -274.561557) (xy 356.555842 -274.588206)
			(xy 356.506228 -274.607678) (xy 356.454266 -274.619538) (xy 356.401116 -274.623522) (xy 356.347966 -274.619538)
			(xy 356.296004 -274.607678) (xy 356.24639 -274.588206) (xy 356.200232 -274.561557) (xy 356.158561 -274.528326)
			(xy 356.122309 -274.489255) (xy 356.092285 -274.445218) (xy 356.069159 -274.397197) (xy 356.053449 -274.346267)
			(xy 356.045506 -274.293563) (xy 355.816673 -274.293563) (xy 355.816648 -274.294898) (xy 355.807891 -274.350175)
			(xy 355.790593 -274.403402) (xy 355.765182 -274.453268) (xy 355.732282 -274.498544) (xy 355.692704 -274.538116)
			(xy 355.647423 -274.571009) (xy 355.597554 -274.596413) (xy 355.544325 -274.613703) (xy 355.489046 -274.622452)
			(xy 355.461062 -274.623022) (xy 355.437078 -274.622631) (xy 355.389546 -274.616181) (xy 355.343315 -274.603389)
			(xy 355.321108 -274.59432) (xy 355.305971 -274.630148) (xy 355.270138 -274.699187) (xy 355.228247 -274.764728)
			(xy 355.204776 -274.795742) (xy 355.226535 -274.812658) (xy 355.265055 -274.852071) (xy 355.297038 -274.896953)
			(xy 355.321718 -274.946229) (xy 355.338505 -274.998721) (xy 355.346998 -275.053174) (xy 355.347524 -275.08073)
			(xy 355.601524 -275.08073) (xy 355.602032 -275.054823) (xy 355.610138 -275.003646) (xy 355.62615 -274.954367)
			(xy 355.649673 -274.9082) (xy 355.680129 -274.866281) (xy 355.716767 -274.829643) (xy 355.758686 -274.799187)
			(xy 355.804853 -274.775664) (xy 355.854132 -274.759652) (xy 355.905309 -274.751546) (xy 355.957123 -274.751546)
			(xy 356.0083 -274.759652) (xy 356.057579 -274.775664) (xy 356.103746 -274.799187) (xy 356.145665 -274.829643)
			(xy 356.182303 -274.866281) (xy 356.212759 -274.9082) (xy 356.236282 -274.954367) (xy 356.252294 -275.003646)
			(xy 356.2604 -275.054823) (xy 356.260908 -275.08073) (xy 356.26032 -275.107379) (xy 356.515152 -275.107379)
			(xy 356.515152 -275.054081) (xy 356.523095 -275.001377) (xy 356.538805 -274.950447) (xy 356.561931 -274.902426)
			(xy 356.591955 -274.858389) (xy 356.628207 -274.819318) (xy 356.669878 -274.786087) (xy 356.716036 -274.759438)
			(xy 356.76565 -274.739966) (xy 356.817612 -274.728106) (xy 356.870762 -274.724123) (xy 356.923912 -274.728106)
			(xy 356.975874 -274.739966) (xy 357.025488 -274.759438) (xy 357.071646 -274.786087) (xy 357.113317 -274.819318)
			(xy 357.149569 -274.858389) (xy 357.179593 -274.902426) (xy 357.202719 -274.950447) (xy 357.218429 -275.001377)
			(xy 357.226372 -275.054081) (xy 357.22687 -275.08073) (xy 357.226372 -275.107379) (xy 357.454952 -275.107379)
			(xy 357.454952 -275.054081) (xy 357.462895 -275.001377) (xy 357.478605 -274.950447) (xy 357.501731 -274.902426)
			(xy 357.531755 -274.858389) (xy 357.568007 -274.819318) (xy 357.609678 -274.786087) (xy 357.655836 -274.759438)
			(xy 357.70545 -274.739966) (xy 357.757412 -274.728106) (xy 357.810562 -274.724123) (xy 357.863712 -274.728106)
			(xy 357.915674 -274.739966) (xy 357.965288 -274.759438) (xy 358.011446 -274.786087) (xy 358.053117 -274.819318)
			(xy 358.089369 -274.858389) (xy 358.119393 -274.902426) (xy 358.142519 -274.950447) (xy 358.158229 -275.001377)
			(xy 358.166172 -275.054081) (xy 358.16667 -275.08073) (xy 358.166172 -275.107379) (xy 358.158229 -275.160083)
			(xy 358.142519 -275.211013) (xy 358.119393 -275.259034) (xy 358.089369 -275.303071) (xy 358.053117 -275.342142)
			(xy 358.011446 -275.375373) (xy 357.965288 -275.402022) (xy 357.915674 -275.421494) (xy 357.863712 -275.433354)
			(xy 357.810562 -275.437338) (xy 357.757412 -275.433354) (xy 357.70545 -275.421494) (xy 357.655836 -275.402022)
			(xy 357.609678 -275.375373) (xy 357.568007 -275.342142) (xy 357.531755 -275.303071) (xy 357.501731 -275.259034)
			(xy 357.478605 -275.211013) (xy 357.462895 -275.160083) (xy 357.454952 -275.107379) (xy 357.226372 -275.107379)
			(xy 357.218429 -275.160083) (xy 357.202719 -275.211013) (xy 357.179593 -275.259034) (xy 357.149569 -275.303071)
			(xy 357.113317 -275.342142) (xy 357.071646 -275.375373) (xy 357.025488 -275.402022) (xy 356.975874 -275.421494)
			(xy 356.923912 -275.433354) (xy 356.870762 -275.437338) (xy 356.817612 -275.433354) (xy 356.76565 -275.421494)
			(xy 356.716036 -275.402022) (xy 356.669878 -275.375373) (xy 356.628207 -275.342142) (xy 356.591955 -275.303071)
			(xy 356.561931 -275.259034) (xy 356.538805 -275.211013) (xy 356.523095 -275.160083) (xy 356.515152 -275.107379)
			(xy 356.26032 -275.107379) (xy 356.260296 -275.108446) (xy 356.250985 -275.163093) (xy 356.242366 -275.189442)
			(xy 356.234492 -275.21154) (xy 356.439724 -275.566632) (xy 356.462584 -275.57095) (xy 356.4874 -275.576135)
			(xy 356.535176 -275.593092) (xy 356.579792 -275.617163) (xy 356.620197 -275.647782) (xy 356.655436 -275.684226)
			(xy 356.684681 -275.725636) (xy 356.707239 -275.771036) (xy 356.722581 -275.819355) (xy 356.730343 -275.869452)
			(xy 356.730808 -275.8948) (xy 356.7303 -275.920707) (xy 356.722194 -275.971884) (xy 356.706182 -276.021163)
			(xy 356.682659 -276.06733) (xy 356.652203 -276.109249) (xy 356.615565 -276.145887) (xy 356.573646 -276.176343)
			(xy 356.527479 -276.199866) (xy 356.4782 -276.215878) (xy 356.427023 -276.223984) (xy 356.375209 -276.223984)
			(xy 356.324032 -276.215878) (xy 356.274753 -276.199866) (xy 356.228586 -276.176343) (xy 356.186667 -276.145887)
			(xy 356.150029 -276.109249) (xy 356.119573 -276.06733) (xy 356.09605 -276.021163) (xy 356.080038 -275.971884)
			(xy 356.071932 -275.920707) (xy 356.071424 -275.8948) (xy 356.072017 -275.867083) (xy 356.081341 -275.812436)
			(xy 356.089966 -275.786088) (xy 356.09784 -275.76399) (xy 355.892608 -275.408898) (xy 355.869748 -275.40458)
			(xy 355.844921 -275.399437) (xy 355.79714 -275.382481) (xy 355.75252 -275.358407) (xy 355.712113 -275.327784)
			(xy 355.676872 -275.291334) (xy 355.647629 -275.249917) (xy 355.625073 -275.20451) (xy 355.609738 -275.156184)
			(xy 355.601984 -275.10608) (xy 355.601524 -275.08073) (xy 355.347524 -275.08073) (xy 355.346973 -275.108712)
			(xy 355.338214 -275.163987) (xy 355.320917 -275.217211) (xy 355.295508 -275.267074) (xy 355.262611 -275.312349)
			(xy 355.223038 -275.35192) (xy 355.177762 -275.384815) (xy 355.127898 -275.410223) (xy 355.074673 -275.427517)
			(xy 355.019398 -275.436274) (xy 354.991416 -275.436838) (xy 354.96612 -275.436395) (xy 354.916038 -275.429236)
			(xy 354.867474 -275.415059) (xy 354.821406 -275.394151) (xy 354.778761 -275.366932) (xy 354.740399 -275.333951)
			(xy 354.723446 -275.315172) (xy 354.713947 -275.305036) (xy 354.690709 -275.28984) (xy 354.664238 -275.281458)
			(xy 354.636488 -275.280508) (xy 354.609507 -275.287061) (xy 354.585284 -275.300634) (xy 354.57511 -275.310092)
			(xy 354.49129 -275.393912) (xy 354.481468 -275.404422) (xy 354.467595 -275.429608) (xy 354.461292 -275.457662)
			(xy 354.463059 -275.486361) (xy 354.472754 -275.513431) (xy 354.489611 -275.536725) (xy 354.512292 -275.554398)
			(xy 354.539 -275.565048) (xy 354.553266 -275.566886) (xy 354.580486 -275.570062) (xy 354.633406 -275.584286)
			(xy 354.683241 -275.607073) (xy 354.728618 -275.637794) (xy 354.768284 -275.675602) (xy 354.785168 -275.697188)
			(xy 355.197156 -275.697188) (xy 355.212829 -275.677051) (xy 355.249337 -275.641403) (xy 355.290902 -275.611805)
			(xy 355.336531 -275.588964) (xy 355.385133 -275.573424) (xy 355.435549 -275.565557) (xy 355.461062 -275.565108)
			(xy 355.486973 -275.565587) (xy 355.538159 -275.573688) (xy 355.587447 -275.589698) (xy 355.633623 -275.613221)
			(xy 355.67555 -275.643679) (xy 355.712197 -275.680321) (xy 355.742659 -275.722245) (xy 355.766188 -275.768418)
			(xy 355.782203 -275.817704) (xy 355.79031 -275.868889) (xy 355.79031 -275.920711) (xy 355.782203 -275.971896)
			(xy 355.766188 -276.021182) (xy 355.742659 -276.067355) (xy 355.712197 -276.109279) (xy 355.67555 -276.145921)
			(xy 355.633623 -276.176379) (xy 355.587447 -276.199902) (xy 355.538159 -276.215912) (xy 355.486973 -276.224013)
			(xy 355.461062 -276.224492) (xy 355.435551 -276.224012) (xy 355.38514 -276.216146) (xy 355.336542 -276.200608)
			(xy 355.290918 -276.177769) (xy 355.249357 -276.148173) (xy 355.212852 -276.112529) (xy 355.197156 -276.092412)
			(xy 354.785168 -276.092412) (xy 354.769494 -276.112545) (xy 354.732982 -276.148184) (xy 354.691416 -276.177773)
			(xy 354.645788 -276.200604) (xy 354.597186 -276.216132) (xy 354.546773 -276.223987) (xy 354.521262 -276.224492)
			(xy 354.494264 -276.223947) (xy 354.440992 -276.215137) (xy 354.389869 -276.197759) (xy 354.342264 -276.172278)
			(xy 354.29945 -276.139377) (xy 354.262574 -276.099935) (xy 354.232622 -276.055008) (xy 354.210396 -276.005798)
			(xy 354.196492 -275.953624) (xy 354.193348 -275.926804) (xy 354.191446 -275.91256) (xy 354.180776 -275.885893)
			(xy 354.163105 -275.863249) (xy 354.139829 -275.846419) (xy 354.112788 -275.836733) (xy 354.08412 -275.834957)
			(xy 354.05609 -275.841231) (xy 354.030915 -275.85506) (xy 354.020374 -275.864828) (xy 353.933506 -275.951696)
			(xy 353.930458 -275.966428) (xy 353.924777 -275.991752) (xy 353.907066 -276.040535) (xy 353.88246 -276.08623)
			(xy 353.85148 -276.127868) (xy 353.814783 -276.164567) (xy 353.773146 -276.195549) (xy 353.727453 -276.220158)
			(xy 353.678671 -276.237872) (xy 353.653344 -276.243542) (xy 353.638612 -276.24659) (xy 353.376738 -276.508464)
			(xy 353.396296 -276.5425) (xy 353.410461 -276.567872) (xy 353.430603 -276.622374) (xy 353.440868 -276.679565)
			(xy 353.441508 -276.708616) (xy 353.441049 -276.733967) (xy 353.440848 -276.735265) (xy 353.695752 -276.735265)
			(xy 353.695752 -276.681967) (xy 353.703695 -276.629263) (xy 353.719405 -276.578333) (xy 353.742531 -276.530312)
			(xy 353.772555 -276.486275) (xy 353.808807 -276.447204) (xy 353.850478 -276.413973) (xy 353.896636 -276.387324)
			(xy 353.94625 -276.367852) (xy 353.998212 -276.355992) (xy 354.051362 -276.352009) (xy 354.104512 -276.355992)
			(xy 354.156474 -276.367852) (xy 354.206088 -276.387324) (xy 354.252246 -276.413973) (xy 354.293917 -276.447204)
			(xy 354.330169 -276.486275) (xy 354.360193 -276.530312) (xy 354.383319 -276.578333) (xy 354.399029 -276.629263)
			(xy 354.406972 -276.681967) (xy 354.40747 -276.708616) (xy 354.406972 -276.735265) (xy 354.399029 -276.787969)
			(xy 354.383319 -276.838899) (xy 354.360193 -276.88692) (xy 354.330169 -276.930957) (xy 354.293917 -276.970028)
			(xy 354.252246 -277.003259) (xy 354.206088 -277.029908) (xy 354.156474 -277.04938) (xy 354.104512 -277.06124)
			(xy 354.051362 -277.065224) (xy 353.998212 -277.06124) (xy 353.94625 -277.04938) (xy 353.896636 -277.029908)
			(xy 353.850478 -277.003259) (xy 353.808807 -276.970028) (xy 353.772555 -276.930957) (xy 353.742531 -276.88692)
			(xy 353.719405 -276.838899) (xy 353.703695 -276.787969) (xy 353.695752 -276.735265) (xy 353.440848 -276.735265)
			(xy 353.433298 -276.784073) (xy 353.417965 -276.832401) (xy 353.395412 -276.877811) (xy 353.366172 -276.919231)
			(xy 353.330933 -276.955686) (xy 353.290528 -276.986314) (xy 353.245909 -277.010394) (xy 353.198129 -277.027357)
			(xy 353.148315 -277.036803) (xy 353.122992 -277.038054) (xy 353.107375 -277.039134) (xy 353.077876 -277.049563)
			(xy 353.052913 -277.068425) (xy 353.034824 -277.093953) (xy 353.025302 -277.123757) (xy 353.024694 -277.1394)
			(xy 353.024694 -277.549081) (xy 353.225852 -277.549081) (xy 353.225852 -277.495783) (xy 353.233795 -277.443079)
			(xy 353.249505 -277.392149) (xy 353.272631 -277.344128) (xy 353.302655 -277.300091) (xy 353.338907 -277.26102)
			(xy 353.380578 -277.227789) (xy 353.426736 -277.20114) (xy 353.47635 -277.181668) (xy 353.528312 -277.169808)
			(xy 353.581462 -277.165825) (xy 353.634612 -277.169808) (xy 353.686574 -277.181668) (xy 353.736188 -277.20114)
			(xy 353.782346 -277.227789) (xy 353.824017 -277.26102) (xy 353.860269 -277.300091) (xy 353.890293 -277.344128)
			(xy 353.913419 -277.392149) (xy 353.929129 -277.443079) (xy 353.937072 -277.495783) (xy 353.93757 -277.522432)
			(xy 354.191824 -277.522432) (xy 354.192226 -277.497095) (xy 354.199989 -277.447018) (xy 354.215322 -277.398718)
			(xy 354.237864 -277.353333) (xy 354.267084 -277.31193) (xy 354.302294 -277.275486) (xy 354.342666 -277.244857)
			(xy 354.387248 -277.220766) (xy 354.434991 -277.203779) (xy 354.459794 -277.198582) (xy 354.482654 -277.194264)
			(xy 354.687886 -276.838918) (xy 354.680266 -276.817074) (xy 354.671663 -276.790785) (xy 354.662334 -276.736269)
			(xy 354.661724 -276.708616) (xy 354.662232 -276.682709) (xy 354.670338 -276.631532) (xy 354.68635 -276.582253)
			(xy 354.709873 -276.536086) (xy 354.740329 -276.494167) (xy 354.776967 -276.457529) (xy 354.818886 -276.427073)
			(xy 354.865053 -276.40355) (xy 354.914332 -276.387538) (xy 354.965509 -276.379432) (xy 355.017323 -276.379432)
			(xy 355.0685 -276.387538) (xy 355.117779 -276.40355) (xy 355.163946 -276.427073) (xy 355.205865 -276.457529)
			(xy 355.242503 -276.494167) (xy 355.272959 -276.536086) (xy 355.296482 -276.582253) (xy 355.312494 -276.631532)
			(xy 355.3206 -276.682709) (xy 355.321108 -276.708616) (xy 355.320641 -276.73399) (xy 355.320443 -276.735265)
			(xy 355.575606 -276.735265) (xy 355.575606 -276.681967) (xy 355.583549 -276.629263) (xy 355.599259 -276.578333)
			(xy 355.622385 -276.530312) (xy 355.652409 -276.486275) (xy 355.688661 -276.447204) (xy 355.730332 -276.413973)
			(xy 355.77649 -276.387324) (xy 355.826104 -276.367852) (xy 355.878066 -276.355992) (xy 355.931216 -276.352009)
			(xy 355.984366 -276.355992) (xy 356.036328 -276.367852) (xy 356.085942 -276.387324) (xy 356.1321 -276.413973)
			(xy 356.173771 -276.447204) (xy 356.210023 -276.486275) (xy 356.240047 -276.530312) (xy 356.263173 -276.578333)
			(xy 356.278883 -276.629263) (xy 356.286826 -276.681967) (xy 356.287324 -276.708616) (xy 356.541324 -276.708616)
			(xy 356.541802 -276.683281) (xy 356.549553 -276.633207) (xy 356.564874 -276.584909) (xy 356.587406 -276.539525)
			(xy 356.616616 -276.498122) (xy 356.651818 -276.461676) (xy 356.692181 -276.431046) (xy 356.736757 -276.406953)
			(xy 356.784494 -276.389964) (xy 356.809294 -276.384766) (xy 356.832154 -276.380448) (xy 357.037132 -276.02561)
			(xy 357.029258 -276.003766) (xy 357.020612 -275.977358) (xy 357.011292 -275.922582) (xy 357.010716 -275.8948)
			(xy 357.011224 -275.868893) (xy 357.01933 -275.817716) (xy 357.035342 -275.768437) (xy 357.058865 -275.72227)
			(xy 357.089321 -275.680351) (xy 357.125959 -275.643713) (xy 357.167878 -275.613257) (xy 357.214045 -275.589734)
			(xy 357.263324 -275.573722) (xy 357.314501 -275.565616) (xy 357.366315 -275.565616) (xy 357.417492 -275.573722)
			(xy 357.466771 -275.589734) (xy 357.512938 -275.613257) (xy 357.554857 -275.643713) (xy 357.591495 -275.680351)
			(xy 357.621951 -275.72227) (xy 357.645474 -275.768437) (xy 357.661486 -275.817716) (xy 357.669592 -275.868893)
			(xy 357.6701 -275.8948) (xy 357.669579 -275.920144) (xy 357.669377 -275.921449) (xy 357.924852 -275.921449)
			(xy 357.924852 -275.868151) (xy 357.932795 -275.815447) (xy 357.948505 -275.764517) (xy 357.971631 -275.716496)
			(xy 358.001655 -275.672459) (xy 358.037907 -275.633388) (xy 358.079578 -275.600157) (xy 358.125736 -275.573508)
			(xy 358.17535 -275.554036) (xy 358.227312 -275.542176) (xy 358.280462 -275.538193) (xy 358.333612 -275.542176)
			(xy 358.385574 -275.554036) (xy 358.435188 -275.573508) (xy 358.481346 -275.600157) (xy 358.523017 -275.633388)
			(xy 358.559269 -275.672459) (xy 358.589293 -275.716496) (xy 358.612419 -275.764517) (xy 358.628129 -275.815447)
			(xy 358.636072 -275.868151) (xy 358.63657 -275.8948) (xy 358.636072 -275.921449) (xy 361.684306 -275.921449)
			(xy 361.684306 -275.868151) (xy 361.692249 -275.815447) (xy 361.707959 -275.764517) (xy 361.731085 -275.716496)
			(xy 361.761109 -275.672459) (xy 361.797361 -275.633388) (xy 361.839032 -275.600157) (xy 361.88519 -275.573508)
			(xy 361.934804 -275.554036) (xy 361.986766 -275.542176) (xy 362.039916 -275.538193) (xy 362.093066 -275.542176)
			(xy 362.145028 -275.554036) (xy 362.194642 -275.573508) (xy 362.2408 -275.600157) (xy 362.282471 -275.633388)
			(xy 362.318723 -275.672459) (xy 362.348747 -275.716496) (xy 362.371873 -275.764517) (xy 362.387583 -275.815447)
			(xy 362.395526 -275.868151) (xy 362.396024 -275.8948) (xy 362.395526 -275.921449) (xy 362.623852 -275.921449)
			(xy 362.623852 -275.868151) (xy 362.631795 -275.815447) (xy 362.647505 -275.764517) (xy 362.670631 -275.716496)
			(xy 362.700655 -275.672459) (xy 362.736907 -275.633388) (xy 362.778578 -275.600157) (xy 362.824736 -275.573508)
			(xy 362.87435 -275.554036) (xy 362.926312 -275.542176) (xy 362.979462 -275.538193) (xy 363.032612 -275.542176)
			(xy 363.084574 -275.554036) (xy 363.134188 -275.573508) (xy 363.180346 -275.600157) (xy 363.222017 -275.633388)
			(xy 363.258269 -275.672459) (xy 363.288293 -275.716496) (xy 363.311419 -275.764517) (xy 363.327129 -275.815447)
			(xy 363.335072 -275.868151) (xy 363.33557 -275.8948) (xy 363.335072 -275.921449) (xy 363.327129 -275.974153)
			(xy 363.311419 -276.025083) (xy 363.288293 -276.073104) (xy 363.258269 -276.117141) (xy 363.222017 -276.156212)
			(xy 363.180346 -276.189443) (xy 363.134188 -276.216092) (xy 363.084574 -276.235564) (xy 363.032612 -276.247424)
			(xy 362.979462 -276.251408) (xy 362.926312 -276.247424) (xy 362.87435 -276.235564) (xy 362.824736 -276.216092)
			(xy 362.778578 -276.189443) (xy 362.736907 -276.156212) (xy 362.700655 -276.117141) (xy 362.670631 -276.073104)
			(xy 362.647505 -276.025083) (xy 362.631795 -275.974153) (xy 362.623852 -275.921449) (xy 362.395526 -275.921449)
			(xy 362.387583 -275.974153) (xy 362.371873 -276.025083) (xy 362.348747 -276.073104) (xy 362.318723 -276.117141)
			(xy 362.282471 -276.156212) (xy 362.2408 -276.189443) (xy 362.194642 -276.216092) (xy 362.145028 -276.235564)
			(xy 362.093066 -276.247424) (xy 362.039916 -276.251408) (xy 361.986766 -276.247424) (xy 361.934804 -276.235564)
			(xy 361.88519 -276.216092) (xy 361.839032 -276.189443) (xy 361.797361 -276.156212) (xy 361.761109 -276.117141)
			(xy 361.731085 -276.073104) (xy 361.707959 -276.025083) (xy 361.692249 -275.974153) (xy 361.684306 -275.921449)
			(xy 358.636072 -275.921449) (xy 358.628129 -275.974153) (xy 358.612419 -276.025083) (xy 358.589293 -276.073104)
			(xy 358.559269 -276.117141) (xy 358.523017 -276.156212) (xy 358.481346 -276.189443) (xy 358.435188 -276.216092)
			(xy 358.385574 -276.235564) (xy 358.333612 -276.247424) (xy 358.280462 -276.251408) (xy 358.227312 -276.247424)
			(xy 358.17535 -276.235564) (xy 358.125736 -276.216092) (xy 358.079578 -276.189443) (xy 358.037907 -276.156212)
			(xy 358.001655 -276.117141) (xy 357.971631 -276.073104) (xy 357.948505 -276.025083) (xy 357.932795 -275.974153)
			(xy 357.924852 -275.921449) (xy 357.669377 -275.921449) (xy 357.661807 -275.970232) (xy 357.646462 -276.018541)
			(xy 357.623906 -276.063932) (xy 357.594669 -276.105338) (xy 357.55944 -276.141782) (xy 357.519049 -276.172406)
			(xy 357.474448 -276.196488) (xy 357.426687 -276.213462) (xy 357.401876 -276.21865) (xy 357.379016 -276.222968)
			(xy 357.174038 -276.577806) (xy 357.181912 -276.599904) (xy 357.190474 -276.626262) (xy 357.199672 -276.680908)
			(xy 357.2002 -276.708616) (xy 357.199692 -276.734503) (xy 357.199571 -276.735265) (xy 357.454952 -276.735265)
			(xy 357.454952 -276.681967) (xy 357.462895 -276.629263) (xy 357.478605 -276.578333) (xy 357.501731 -276.530312)
			(xy 357.531755 -276.486275) (xy 357.568007 -276.447204) (xy 357.609678 -276.413973) (xy 357.655836 -276.387324)
			(xy 357.70545 -276.367852) (xy 357.757412 -276.355992) (xy 357.810562 -276.352009) (xy 357.863712 -276.355992)
			(xy 357.915674 -276.367852) (xy 357.965288 -276.387324) (xy 358.011446 -276.413973) (xy 358.053117 -276.447204)
			(xy 358.089369 -276.486275) (xy 358.119393 -276.530312) (xy 358.142519 -276.578333) (xy 358.158229 -276.629263)
			(xy 358.166172 -276.681967) (xy 358.16667 -276.708616) (xy 358.166172 -276.735265) (xy 362.154206 -276.735265)
			(xy 362.154206 -276.681967) (xy 362.162149 -276.629263) (xy 362.177859 -276.578333) (xy 362.200985 -276.530312)
			(xy 362.231009 -276.486275) (xy 362.267261 -276.447204) (xy 362.308932 -276.413973) (xy 362.35509 -276.387324)
			(xy 362.404704 -276.367852) (xy 362.456666 -276.355992) (xy 362.509816 -276.352009) (xy 362.562966 -276.355992)
			(xy 362.614928 -276.367852) (xy 362.664542 -276.387324) (xy 362.7107 -276.413973) (xy 362.752371 -276.447204)
			(xy 362.788623 -276.486275) (xy 362.818647 -276.530312) (xy 362.841773 -276.578333) (xy 362.857483 -276.629263)
			(xy 362.865426 -276.681967) (xy 362.865924 -276.708616) (xy 362.865431 -276.735011) (xy 363.093752 -276.735011)
			(xy 363.093752 -276.681713) (xy 363.101695 -276.629009) (xy 363.117405 -276.578079) (xy 363.140531 -276.530058)
			(xy 363.170555 -276.486021) (xy 363.206807 -276.44695) (xy 363.248478 -276.413719) (xy 363.294636 -276.38707)
			(xy 363.34425 -276.367598) (xy 363.396212 -276.355738) (xy 363.449362 -276.351755) (xy 363.502512 -276.355738)
			(xy 363.554474 -276.367598) (xy 363.604088 -276.38707) (xy 363.650246 -276.413719) (xy 363.691917 -276.44695)
			(xy 363.728169 -276.486021) (xy 363.758193 -276.530058) (xy 363.781319 -276.578079) (xy 363.797029 -276.629009)
			(xy 363.804972 -276.681713) (xy 363.80547 -276.708362) (xy 363.804972 -276.735011) (xy 363.797029 -276.787715)
			(xy 363.781319 -276.838645) (xy 363.758193 -276.886666) (xy 363.728169 -276.930703) (xy 363.691917 -276.969774)
			(xy 363.650246 -277.003005) (xy 363.604088 -277.029654) (xy 363.554474 -277.049126) (xy 363.502512 -277.060986)
			(xy 363.449362 -277.06497) (xy 363.396212 -277.060986) (xy 363.34425 -277.049126) (xy 363.294636 -277.029654)
			(xy 363.248478 -277.003005) (xy 363.206807 -276.969774) (xy 363.170555 -276.930703) (xy 363.140531 -276.886666)
			(xy 363.117405 -276.838645) (xy 363.101695 -276.787715) (xy 363.093752 -276.735011) (xy 362.865431 -276.735011)
			(xy 362.865426 -276.735265) (xy 362.857483 -276.787969) (xy 362.841773 -276.838899) (xy 362.818647 -276.88692)
			(xy 362.788623 -276.930957) (xy 362.752371 -276.970028) (xy 362.7107 -277.003259) (xy 362.664542 -277.029908)
			(xy 362.614928 -277.04938) (xy 362.562966 -277.06124) (xy 362.509816 -277.065224) (xy 362.456666 -277.06124)
			(xy 362.404704 -277.04938) (xy 362.35509 -277.029908) (xy 362.308932 -277.003259) (xy 362.267261 -276.970028)
			(xy 362.231009 -276.930957) (xy 362.200985 -276.88692) (xy 362.177859 -276.838899) (xy 362.162149 -276.787969)
			(xy 362.154206 -276.735265) (xy 358.166172 -276.735265) (xy 358.158229 -276.787969) (xy 358.142519 -276.838899)
			(xy 358.119393 -276.88692) (xy 358.089369 -276.930957) (xy 358.053117 -276.970028) (xy 358.011446 -277.003259)
			(xy 357.965288 -277.029908) (xy 357.915674 -277.04938) (xy 357.863712 -277.06124) (xy 357.810562 -277.065224)
			(xy 357.757412 -277.06124) (xy 357.70545 -277.04938) (xy 357.655836 -277.029908) (xy 357.609678 -277.003259)
			(xy 357.568007 -276.970028) (xy 357.531755 -276.930957) (xy 357.501731 -276.88692) (xy 357.478605 -276.838899)
			(xy 357.462895 -276.787969) (xy 357.454952 -276.735265) (xy 357.199571 -276.735265) (xy 357.191593 -276.785641)
			(xy 357.175594 -276.834881) (xy 357.152088 -276.881013) (xy 357.121656 -276.9229) (xy 357.085046 -276.95951)
			(xy 357.043159 -276.989942) (xy 356.997027 -277.013448) (xy 356.947787 -277.029447) (xy 356.896649 -277.037546)
			(xy 356.844875 -277.037546) (xy 356.793737 -277.029447) (xy 356.744497 -277.013448) (xy 356.698365 -276.989942)
			(xy 356.656478 -276.95951) (xy 356.619868 -276.9229) (xy 356.589436 -276.881013) (xy 356.56593 -276.834881)
			(xy 356.549931 -276.785641) (xy 356.541832 -276.734503) (xy 356.541324 -276.708616) (xy 356.287324 -276.708616)
			(xy 356.286826 -276.735265) (xy 356.278883 -276.787969) (xy 356.263173 -276.838899) (xy 356.240047 -276.88692)
			(xy 356.210023 -276.930957) (xy 356.173771 -276.970028) (xy 356.1321 -277.003259) (xy 356.085942 -277.029908)
			(xy 356.036328 -277.04938) (xy 355.984366 -277.06124) (xy 355.931216 -277.065224) (xy 355.878066 -277.06124)
			(xy 355.826104 -277.04938) (xy 355.77649 -277.029908) (xy 355.730332 -277.003259) (xy 355.688661 -276.970028)
			(xy 355.652409 -276.930957) (xy 355.622385 -276.88692) (xy 355.599259 -276.838899) (xy 355.583549 -276.787969)
			(xy 355.575606 -276.735265) (xy 355.320443 -276.735265) (xy 355.312871 -276.784141) (xy 355.297501 -276.832506)
			(xy 355.274895 -276.877942) (xy 355.245588 -276.919373) (xy 355.210273 -276.955819) (xy 355.169787 -276.986418)
			(xy 355.125087 -277.010445) (xy 355.07723 -277.027332) (xy 355.052376 -277.032466) (xy 355.029516 -277.036784)
			(xy 354.824538 -277.391622) (xy 354.832412 -277.41372) (xy 354.840977 -277.440077) (xy 354.850173 -277.494724)
			(xy 354.8507 -277.522432) (xy 355.131624 -277.522432) (xy 355.132132 -277.496545) (xy 355.140231 -277.445407)
			(xy 355.15623 -277.396167) (xy 355.179736 -277.350035) (xy 355.210168 -277.308148) (xy 355.246778 -277.271538)
			(xy 355.288665 -277.241106) (xy 355.334797 -277.2176) (xy 355.384037 -277.201601) (xy 355.435175 -277.193502)
			(xy 355.486949 -277.193502) (xy 355.538087 -277.201601) (xy 355.587327 -277.2176) (xy 355.633459 -277.241106)
			(xy 355.675346 -277.271538) (xy 355.711956 -277.308148) (xy 355.742388 -277.350035) (xy 355.765894 -277.396167)
			(xy 355.781893 -277.445407) (xy 355.789992 -277.496545) (xy 355.7905 -277.522432) (xy 355.7905 -277.52294)
			(xy 355.789963 -277.548303) (xy 356.071748 -277.548303) (xy 356.071748 -277.496497) (xy 356.079852 -277.445329)
			(xy 356.09586 -277.396058) (xy 356.119377 -277.349898) (xy 356.149826 -277.307985) (xy 356.186456 -277.271351)
			(xy 356.228366 -277.240897) (xy 356.274523 -277.217374) (xy 356.323792 -277.201361) (xy 356.374959 -277.193251)
			(xy 356.400862 -277.19274) (xy 356.426374 -277.193232) (xy 356.476788 -277.201088) (xy 356.52539 -277.216618)
			(xy 356.571019 -277.239452) (xy 356.612585 -277.269043) (xy 356.649095 -277.304685) (xy 356.664768 -277.32482)
			(xy 357.076756 -277.32482) (xy 357.09246 -277.30471) (xy 357.128963 -277.269063) (xy 357.170522 -277.239467)
			(xy 357.216144 -277.216626) (xy 357.264741 -277.201087) (xy 357.315152 -277.19322) (xy 357.340662 -277.19274)
			(xy 357.366576 -277.193155) (xy 357.417766 -277.201257) (xy 357.467059 -277.217268) (xy 357.51324 -277.240794)
			(xy 357.555171 -277.271254) (xy 357.591821 -277.3079) (xy 357.622286 -277.349828) (xy 357.645817 -277.396006)
			(xy 357.661834 -277.445297) (xy 357.669942 -277.496486) (xy 357.669942 -277.548314) (xy 357.669821 -277.549081)
			(xy 357.924852 -277.549081) (xy 357.924852 -277.495783) (xy 357.932795 -277.443079) (xy 357.948505 -277.392149)
			(xy 357.971631 -277.344128) (xy 358.001655 -277.300091) (xy 358.037907 -277.26102) (xy 358.079578 -277.227789)
			(xy 358.125736 -277.20114) (xy 358.17535 -277.181668) (xy 358.227312 -277.169808) (xy 358.280462 -277.165825)
			(xy 358.333612 -277.169808) (xy 358.385574 -277.181668) (xy 358.435188 -277.20114) (xy 358.481346 -277.227789)
			(xy 358.523017 -277.26102) (xy 358.559269 -277.300091) (xy 358.589293 -277.344128) (xy 358.612419 -277.392149)
			(xy 358.628129 -277.443079) (xy 358.636072 -277.495783) (xy 358.63657 -277.522432) (xy 358.636072 -277.549081)
			(xy 362.623852 -277.549081) (xy 362.623852 -277.495783) (xy 362.631795 -277.443079) (xy 362.647505 -277.392149)
			(xy 362.670631 -277.344128) (xy 362.700655 -277.300091) (xy 362.736907 -277.26102) (xy 362.778578 -277.227789)
			(xy 362.824736 -277.20114) (xy 362.87435 -277.181668) (xy 362.926312 -277.169808) (xy 362.979462 -277.165825)
			(xy 363.032612 -277.169808) (xy 363.084574 -277.181668) (xy 363.134188 -277.20114) (xy 363.180346 -277.227789)
			(xy 363.222017 -277.26102) (xy 363.258269 -277.300091) (xy 363.288293 -277.344128) (xy 363.311419 -277.392149)
			(xy 363.327129 -277.443079) (xy 363.335072 -277.495783) (xy 363.33557 -277.522432) (xy 363.335077 -277.548827)
			(xy 363.563906 -277.548827) (xy 363.563906 -277.495529) (xy 363.571849 -277.442825) (xy 363.587559 -277.391895)
			(xy 363.610685 -277.343874) (xy 363.640709 -277.299837) (xy 363.676961 -277.260766) (xy 363.718632 -277.227535)
			(xy 363.76479 -277.200886) (xy 363.814404 -277.181414) (xy 363.866366 -277.169554) (xy 363.919516 -277.165571)
			(xy 363.972666 -277.169554) (xy 364.024628 -277.181414) (xy 364.074242 -277.200886) (xy 364.1204 -277.227535)
			(xy 364.162071 -277.260766) (xy 364.198323 -277.299837) (xy 364.228347 -277.343874) (xy 364.251473 -277.391895)
			(xy 364.267183 -277.442825) (xy 364.275126 -277.495529) (xy 364.275624 -277.522178) (xy 364.275126 -277.548827)
			(xy 364.275088 -277.549081) (xy 364.503452 -277.549081) (xy 364.503452 -277.495783) (xy 364.511395 -277.443079)
			(xy 364.527105 -277.392149) (xy 364.550231 -277.344128) (xy 364.580255 -277.300091) (xy 364.616507 -277.26102)
			(xy 364.658178 -277.227789) (xy 364.704336 -277.20114) (xy 364.75395 -277.181668) (xy 364.805912 -277.169808)
			(xy 364.859062 -277.165825) (xy 364.912212 -277.169808) (xy 364.964174 -277.181668) (xy 365.013788 -277.20114)
			(xy 365.059946 -277.227789) (xy 365.101617 -277.26102) (xy 365.137869 -277.300091) (xy 365.167893 -277.344128)
			(xy 365.191019 -277.392149) (xy 365.206729 -277.443079) (xy 365.214672 -277.495783) (xy 365.21517 -277.522432)
			(xy 365.214677 -277.548827) (xy 365.443506 -277.548827) (xy 365.443506 -277.495529) (xy 365.451449 -277.442825)
			(xy 365.467159 -277.391895) (xy 365.490285 -277.343874) (xy 365.520309 -277.299837) (xy 365.556561 -277.260766)
			(xy 365.598232 -277.227535) (xy 365.64439 -277.200886) (xy 365.694004 -277.181414) (xy 365.745966 -277.169554)
			(xy 365.799116 -277.165571) (xy 365.852266 -277.169554) (xy 365.904228 -277.181414) (xy 365.953842 -277.200886)
			(xy 366 -277.227535) (xy 366.041671 -277.260766) (xy 366.077923 -277.299837) (xy 366.107947 -277.343874)
			(xy 366.131073 -277.391895) (xy 366.146783 -277.442825) (xy 366.154726 -277.495529) (xy 366.155224 -277.522178)
			(xy 366.154726 -277.548827) (xy 366.154688 -277.549081) (xy 366.383306 -277.549081) (xy 366.383306 -277.495783)
			(xy 366.391249 -277.443079) (xy 366.406959 -277.392149) (xy 366.430085 -277.344128) (xy 366.460109 -277.300091)
			(xy 366.496361 -277.26102) (xy 366.538032 -277.227789) (xy 366.58419 -277.20114) (xy 366.633804 -277.181668)
			(xy 366.685766 -277.169808) (xy 366.738916 -277.165825) (xy 366.792066 -277.169808) (xy 366.844028 -277.181668)
			(xy 366.893642 -277.20114) (xy 366.9398 -277.227789) (xy 366.981471 -277.26102) (xy 367.017723 -277.300091)
			(xy 367.047747 -277.344128) (xy 367.070873 -277.392149) (xy 367.086583 -277.443079) (xy 367.094526 -277.495783)
			(xy 367.095024 -277.522432) (xy 367.094531 -277.548827) (xy 367.323106 -277.548827) (xy 367.323106 -277.495529)
			(xy 367.331049 -277.442825) (xy 367.346759 -277.391895) (xy 367.369885 -277.343874) (xy 367.399909 -277.299837)
			(xy 367.436161 -277.260766) (xy 367.477832 -277.227535) (xy 367.52399 -277.200886) (xy 367.573604 -277.181414)
			(xy 367.625566 -277.169554) (xy 367.678716 -277.165571) (xy 367.731866 -277.169554) (xy 367.783828 -277.181414)
			(xy 367.833442 -277.200886) (xy 367.8796 -277.227535) (xy 367.921271 -277.260766) (xy 367.957523 -277.299837)
			(xy 367.987547 -277.343874) (xy 368.010673 -277.391895) (xy 368.026383 -277.442825) (xy 368.034326 -277.495529)
			(xy 368.034824 -277.522178) (xy 368.034326 -277.548827) (xy 368.262906 -277.548827) (xy 368.262906 -277.495529)
			(xy 368.270849 -277.442825) (xy 368.286559 -277.391895) (xy 368.309685 -277.343874) (xy 368.339709 -277.299837)
			(xy 368.375961 -277.260766) (xy 368.417632 -277.227535) (xy 368.46379 -277.200886) (xy 368.513404 -277.181414)
			(xy 368.565366 -277.169554) (xy 368.618516 -277.165571) (xy 368.671666 -277.169554) (xy 368.723628 -277.181414)
			(xy 368.773242 -277.200886) (xy 368.8194 -277.227535) (xy 368.861071 -277.260766) (xy 368.897323 -277.299837)
			(xy 368.927347 -277.343874) (xy 368.950473 -277.391895) (xy 368.966183 -277.442825) (xy 368.974126 -277.495529)
			(xy 368.974624 -277.522178) (xy 368.974126 -277.548827) (xy 369.202706 -277.548827) (xy 369.202706 -277.495529)
			(xy 369.210649 -277.442825) (xy 369.226359 -277.391895) (xy 369.249485 -277.343874) (xy 369.279509 -277.299837)
			(xy 369.315761 -277.260766) (xy 369.357432 -277.227535) (xy 369.40359 -277.200886) (xy 369.453204 -277.181414)
			(xy 369.505166 -277.169554) (xy 369.558316 -277.165571) (xy 369.611466 -277.169554) (xy 369.663428 -277.181414)
			(xy 369.713042 -277.200886) (xy 369.7592 -277.227535) (xy 369.800871 -277.260766) (xy 369.837123 -277.299837)
			(xy 369.867147 -277.343874) (xy 369.890273 -277.391895) (xy 369.905983 -277.442825) (xy 369.913926 -277.495529)
			(xy 369.914424 -277.522178) (xy 369.913926 -277.548827) (xy 370.142506 -277.548827) (xy 370.142506 -277.495529)
			(xy 370.150449 -277.442825) (xy 370.166159 -277.391895) (xy 370.189285 -277.343874) (xy 370.219309 -277.299837)
			(xy 370.255561 -277.260766) (xy 370.297232 -277.227535) (xy 370.34339 -277.200886) (xy 370.393004 -277.181414)
			(xy 370.444966 -277.169554) (xy 370.498116 -277.165571) (xy 370.551266 -277.169554) (xy 370.603228 -277.181414)
			(xy 370.652842 -277.200886) (xy 370.699 -277.227535) (xy 370.740671 -277.260766) (xy 370.776923 -277.299837)
			(xy 370.806947 -277.343874) (xy 370.830073 -277.391895) (xy 370.845783 -277.442825) (xy 370.853726 -277.495529)
			(xy 370.854224 -277.522178) (xy 370.853726 -277.548827) (xy 370.853688 -277.549081) (xy 371.082052 -277.549081)
			(xy 371.082052 -277.495783) (xy 371.089995 -277.443079) (xy 371.105705 -277.392149) (xy 371.128831 -277.344128)
			(xy 371.158855 -277.300091) (xy 371.195107 -277.26102) (xy 371.236778 -277.227789) (xy 371.282936 -277.20114)
			(xy 371.33255 -277.181668) (xy 371.384512 -277.169808) (xy 371.437662 -277.165825) (xy 371.490812 -277.169808)
			(xy 371.542774 -277.181668) (xy 371.592388 -277.20114) (xy 371.638546 -277.227789) (xy 371.680217 -277.26102)
			(xy 371.716469 -277.300091) (xy 371.746493 -277.344128) (xy 371.769619 -277.392149) (xy 371.785329 -277.443079)
			(xy 371.793272 -277.495783) (xy 371.79377 -277.522432) (xy 371.793272 -277.549081) (xy 372.021852 -277.549081)
			(xy 372.021852 -277.495783) (xy 372.029795 -277.443079) (xy 372.045505 -277.392149) (xy 372.068631 -277.344128)
			(xy 372.098655 -277.300091) (xy 372.134907 -277.26102) (xy 372.176578 -277.227789) (xy 372.222736 -277.20114)
			(xy 372.27235 -277.181668) (xy 372.324312 -277.169808) (xy 372.377462 -277.165825) (xy 372.430612 -277.169808)
			(xy 372.482574 -277.181668) (xy 372.532188 -277.20114) (xy 372.578346 -277.227789) (xy 372.620017 -277.26102)
			(xy 372.656269 -277.300091) (xy 372.686293 -277.344128) (xy 372.709419 -277.392149) (xy 372.725129 -277.443079)
			(xy 372.733072 -277.495783) (xy 372.73357 -277.522432) (xy 372.733072 -277.549081) (xy 372.961906 -277.549081)
			(xy 372.961906 -277.495783) (xy 372.969849 -277.443079) (xy 372.985559 -277.392149) (xy 373.008685 -277.344128)
			(xy 373.038709 -277.300091) (xy 373.074961 -277.26102) (xy 373.116632 -277.227789) (xy 373.16279 -277.20114)
			(xy 373.212404 -277.181668) (xy 373.264366 -277.169808) (xy 373.317516 -277.165825) (xy 373.370666 -277.169808)
			(xy 373.422628 -277.181668) (xy 373.472242 -277.20114) (xy 373.5184 -277.227789) (xy 373.560071 -277.26102)
			(xy 373.596323 -277.300091) (xy 373.626347 -277.344128) (xy 373.649473 -277.392149) (xy 373.665183 -277.443079)
			(xy 373.673126 -277.495783) (xy 373.673624 -277.522432) (xy 373.673144 -277.54814) (xy 373.930414 -277.54814)
			(xy 373.930414 -277.496724) (xy 373.938457 -277.445942) (xy 373.954345 -277.397043) (xy 373.977688 -277.351231)
			(xy 374.007909 -277.309635) (xy 374.044265 -277.273279) (xy 374.085861 -277.243058) (xy 374.131673 -277.219715)
			(xy 374.180572 -277.203827) (xy 374.231354 -277.195784) (xy 374.28277 -277.195784) (xy 374.333552 -277.203827)
			(xy 374.382451 -277.219715) (xy 374.428263 -277.243058) (xy 374.469859 -277.273279) (xy 374.506215 -277.309635)
			(xy 374.536436 -277.351231) (xy 374.559779 -277.397043) (xy 374.575667 -277.445942) (xy 374.58371 -277.496724)
			(xy 374.584214 -277.522432) (xy 374.58371 -277.54814) (xy 374.870214 -277.54814) (xy 374.870214 -277.496724)
			(xy 374.878257 -277.445942) (xy 374.894145 -277.397043) (xy 374.917488 -277.351231) (xy 374.947709 -277.309635)
			(xy 374.984065 -277.273279) (xy 375.025661 -277.243058) (xy 375.071473 -277.219715) (xy 375.120372 -277.203827)
			(xy 375.171154 -277.195784) (xy 375.22257 -277.195784) (xy 375.273352 -277.203827) (xy 375.322251 -277.219715)
			(xy 375.368063 -277.243058) (xy 375.409659 -277.273279) (xy 375.446015 -277.309635) (xy 375.476236 -277.351231)
			(xy 375.499579 -277.397043) (xy 375.515467 -277.445942) (xy 375.52351 -277.496724) (xy 375.524014 -277.522432)
			(xy 375.52351 -277.54814) (xy 375.810014 -277.54814) (xy 375.810014 -277.496724) (xy 375.818057 -277.445942)
			(xy 375.833945 -277.397043) (xy 375.857288 -277.351231) (xy 375.887509 -277.309635) (xy 375.923865 -277.273279)
			(xy 375.965461 -277.243058) (xy 376.011273 -277.219715) (xy 376.060172 -277.203827) (xy 376.110954 -277.195784)
			(xy 376.16237 -277.195784) (xy 376.213152 -277.203827) (xy 376.262051 -277.219715) (xy 376.307863 -277.243058)
			(xy 376.349459 -277.273279) (xy 376.385815 -277.309635) (xy 376.416036 -277.351231) (xy 376.439379 -277.397043)
			(xy 376.455267 -277.445942) (xy 376.46331 -277.496724) (xy 376.463814 -277.522432) (xy 376.46331 -277.54814)
			(xy 376.749814 -277.54814) (xy 376.749814 -277.496724) (xy 376.757857 -277.445942) (xy 376.773745 -277.397043)
			(xy 376.797088 -277.351231) (xy 376.827309 -277.309635) (xy 376.863665 -277.273279) (xy 376.905261 -277.243058)
			(xy 376.951073 -277.219715) (xy 376.999972 -277.203827) (xy 377.050754 -277.195784) (xy 377.10217 -277.195784)
			(xy 377.152952 -277.203827) (xy 377.201851 -277.219715) (xy 377.247663 -277.243058) (xy 377.289259 -277.273279)
			(xy 377.325615 -277.309635) (xy 377.355836 -277.351231) (xy 377.379179 -277.397043) (xy 377.395067 -277.445942)
			(xy 377.40311 -277.496724) (xy 377.403614 -277.522432) (xy 377.40311 -277.54814) (xy 377.402961 -277.549081)
			(xy 377.660906 -277.549081) (xy 377.660906 -277.495783) (xy 377.668849 -277.443079) (xy 377.684559 -277.392149)
			(xy 377.707685 -277.344128) (xy 377.737709 -277.300091) (xy 377.773961 -277.26102) (xy 377.815632 -277.227789)
			(xy 377.86179 -277.20114) (xy 377.911404 -277.181668) (xy 377.963366 -277.169808) (xy 378.016516 -277.165825)
			(xy 378.069666 -277.169808) (xy 378.121628 -277.181668) (xy 378.171242 -277.20114) (xy 378.2174 -277.227789)
			(xy 378.259071 -277.26102) (xy 378.295323 -277.300091) (xy 378.325347 -277.344128) (xy 378.348473 -277.392149)
			(xy 378.364183 -277.443079) (xy 378.372126 -277.495783) (xy 378.372624 -277.522432) (xy 378.372126 -277.549081)
			(xy 378.600706 -277.549081) (xy 378.600706 -277.495783) (xy 378.608649 -277.443079) (xy 378.624359 -277.392149)
			(xy 378.647485 -277.344128) (xy 378.677509 -277.300091) (xy 378.713761 -277.26102) (xy 378.755432 -277.227789)
			(xy 378.80159 -277.20114) (xy 378.851204 -277.181668) (xy 378.903166 -277.169808) (xy 378.956316 -277.165825)
			(xy 379.009466 -277.169808) (xy 379.061428 -277.181668) (xy 379.111042 -277.20114) (xy 379.1572 -277.227789)
			(xy 379.198871 -277.26102) (xy 379.235123 -277.300091) (xy 379.265147 -277.344128) (xy 379.288273 -277.392149)
			(xy 379.303983 -277.443079) (xy 379.311926 -277.495783) (xy 379.312424 -277.522432) (xy 379.311926 -277.549081)
			(xy 379.540252 -277.549081) (xy 379.540252 -277.495783) (xy 379.548195 -277.443079) (xy 379.563905 -277.392149)
			(xy 379.587031 -277.344128) (xy 379.617055 -277.300091) (xy 379.653307 -277.26102) (xy 379.694978 -277.227789)
			(xy 379.741136 -277.20114) (xy 379.79075 -277.181668) (xy 379.842712 -277.169808) (xy 379.895862 -277.165825)
			(xy 379.949012 -277.169808) (xy 380.000974 -277.181668) (xy 380.050588 -277.20114) (xy 380.096746 -277.227789)
			(xy 380.138417 -277.26102) (xy 380.174669 -277.300091) (xy 380.204693 -277.344128) (xy 380.227819 -277.392149)
			(xy 380.243529 -277.443079) (xy 380.251472 -277.495783) (xy 380.25197 -277.522432) (xy 380.25149 -277.54814)
			(xy 380.509014 -277.54814) (xy 380.509014 -277.496724) (xy 380.517057 -277.445942) (xy 380.532945 -277.397043)
			(xy 380.556288 -277.351231) (xy 380.586509 -277.309635) (xy 380.622865 -277.273279) (xy 380.664461 -277.243058)
			(xy 380.710273 -277.219715) (xy 380.759172 -277.203827) (xy 380.809954 -277.195784) (xy 380.86137 -277.195784)
			(xy 380.912152 -277.203827) (xy 380.961051 -277.219715) (xy 381.006863 -277.243058) (xy 381.048459 -277.273279)
			(xy 381.084815 -277.309635) (xy 381.115036 -277.351231) (xy 381.138379 -277.397043) (xy 381.154267 -277.445942)
			(xy 381.16231 -277.496724) (xy 381.162814 -277.522432) (xy 381.16231 -277.54814) (xy 381.448814 -277.54814)
			(xy 381.448814 -277.496724) (xy 381.456857 -277.445942) (xy 381.472745 -277.397043) (xy 381.496088 -277.351231)
			(xy 381.526309 -277.309635) (xy 381.562665 -277.273279) (xy 381.604261 -277.243058) (xy 381.650073 -277.219715)
			(xy 381.698972 -277.203827) (xy 381.749754 -277.195784) (xy 381.80117 -277.195784) (xy 381.851952 -277.203827)
			(xy 381.900851 -277.219715) (xy 381.946663 -277.243058) (xy 381.988259 -277.273279) (xy 382.024615 -277.309635)
			(xy 382.054836 -277.351231) (xy 382.078179 -277.397043) (xy 382.094067 -277.445942) (xy 382.10211 -277.496724)
			(xy 382.102614 -277.522432) (xy 382.10211 -277.54814) (xy 382.388614 -277.54814) (xy 382.388614 -277.496724)
			(xy 382.396657 -277.445942) (xy 382.412545 -277.397043) (xy 382.435888 -277.351231) (xy 382.466109 -277.309635)
			(xy 382.502465 -277.273279) (xy 382.544061 -277.243058) (xy 382.589873 -277.219715) (xy 382.638772 -277.203827)
			(xy 382.689554 -277.195784) (xy 382.74097 -277.195784) (xy 382.791752 -277.203827) (xy 382.840651 -277.219715)
			(xy 382.886463 -277.243058) (xy 382.928059 -277.273279) (xy 382.964415 -277.309635) (xy 382.994636 -277.351231)
			(xy 383.017979 -277.397043) (xy 383.033867 -277.445942) (xy 383.04191 -277.496724) (xy 383.042414 -277.522432)
			(xy 383.04191 -277.54814) (xy 383.32816 -277.54814) (xy 383.32816 -277.496724) (xy 383.336203 -277.445942)
			(xy 383.352091 -277.397043) (xy 383.375434 -277.351231) (xy 383.405655 -277.309635) (xy 383.442011 -277.273279)
			(xy 383.483607 -277.243058) (xy 383.529419 -277.219715) (xy 383.578318 -277.203827) (xy 383.6291 -277.195784)
			(xy 383.680516 -277.195784) (xy 383.731298 -277.203827) (xy 383.780197 -277.219715) (xy 383.826009 -277.243058)
			(xy 383.867605 -277.273279) (xy 383.903961 -277.309635) (xy 383.934182 -277.351231) (xy 383.957525 -277.397043)
			(xy 383.973413 -277.445942) (xy 383.981456 -277.496724) (xy 383.98196 -277.522432) (xy 383.981456 -277.54814)
			(xy 383.981307 -277.549081) (xy 384.239252 -277.549081) (xy 384.239252 -277.495783) (xy 384.247195 -277.443079)
			(xy 384.262905 -277.392149) (xy 384.286031 -277.344128) (xy 384.316055 -277.300091) (xy 384.352307 -277.26102)
			(xy 384.393978 -277.227789) (xy 384.440136 -277.20114) (xy 384.48975 -277.181668) (xy 384.541712 -277.169808)
			(xy 384.594862 -277.165825) (xy 384.648012 -277.169808) (xy 384.699974 -277.181668) (xy 384.749588 -277.20114)
			(xy 384.795746 -277.227789) (xy 384.837417 -277.26102) (xy 384.873669 -277.300091) (xy 384.903693 -277.344128)
			(xy 384.926819 -277.392149) (xy 384.942529 -277.443079) (xy 384.950472 -277.495783) (xy 384.95097 -277.522432)
			(xy 384.950472 -277.549081) (xy 384.942529 -277.601785) (xy 384.926819 -277.652715) (xy 384.903693 -277.700736)
			(xy 384.873669 -277.744773) (xy 384.837417 -277.783844) (xy 384.795746 -277.817075) (xy 384.749588 -277.843724)
			(xy 384.699974 -277.863196) (xy 384.648012 -277.875056) (xy 384.594862 -277.87904) (xy 384.541712 -277.875056)
			(xy 384.48975 -277.863196) (xy 384.440136 -277.843724) (xy 384.393978 -277.817075) (xy 384.352307 -277.783844)
			(xy 384.316055 -277.744773) (xy 384.286031 -277.700736) (xy 384.262905 -277.652715) (xy 384.247195 -277.601785)
			(xy 384.239252 -277.549081) (xy 383.981307 -277.549081) (xy 383.973413 -277.598922) (xy 383.957525 -277.647821)
			(xy 383.934182 -277.693633) (xy 383.903961 -277.735229) (xy 383.867605 -277.771585) (xy 383.826009 -277.801806)
			(xy 383.780197 -277.825149) (xy 383.731298 -277.841037) (xy 383.680516 -277.84908) (xy 383.6291 -277.84908)
			(xy 383.578318 -277.841037) (xy 383.529419 -277.825149) (xy 383.483607 -277.801806) (xy 383.442011 -277.771585)
			(xy 383.405655 -277.735229) (xy 383.375434 -277.693633) (xy 383.352091 -277.647821) (xy 383.336203 -277.598922)
			(xy 383.32816 -277.54814) (xy 383.04191 -277.54814) (xy 383.033867 -277.598922) (xy 383.017979 -277.647821)
			(xy 382.994636 -277.693633) (xy 382.964415 -277.735229) (xy 382.928059 -277.771585) (xy 382.886463 -277.801806)
			(xy 382.840651 -277.825149) (xy 382.791752 -277.841037) (xy 382.74097 -277.84908) (xy 382.689554 -277.84908)
			(xy 382.638772 -277.841037) (xy 382.589873 -277.825149) (xy 382.544061 -277.801806) (xy 382.502465 -277.771585)
			(xy 382.466109 -277.735229) (xy 382.435888 -277.693633) (xy 382.412545 -277.647821) (xy 382.396657 -277.598922)
			(xy 382.388614 -277.54814) (xy 382.10211 -277.54814) (xy 382.094067 -277.598922) (xy 382.078179 -277.647821)
			(xy 382.054836 -277.693633) (xy 382.024615 -277.735229) (xy 381.988259 -277.771585) (xy 381.946663 -277.801806)
			(xy 381.900851 -277.825149) (xy 381.851952 -277.841037) (xy 381.80117 -277.84908) (xy 381.749754 -277.84908)
			(xy 381.698972 -277.841037) (xy 381.650073 -277.825149) (xy 381.604261 -277.801806) (xy 381.562665 -277.771585)
			(xy 381.526309 -277.735229) (xy 381.496088 -277.693633) (xy 381.472745 -277.647821) (xy 381.456857 -277.598922)
			(xy 381.448814 -277.54814) (xy 381.16231 -277.54814) (xy 381.154267 -277.598922) (xy 381.138379 -277.647821)
			(xy 381.115036 -277.693633) (xy 381.084815 -277.735229) (xy 381.048459 -277.771585) (xy 381.006863 -277.801806)
			(xy 380.961051 -277.825149) (xy 380.912152 -277.841037) (xy 380.86137 -277.84908) (xy 380.809954 -277.84908)
			(xy 380.759172 -277.841037) (xy 380.710273 -277.825149) (xy 380.664461 -277.801806) (xy 380.622865 -277.771585)
			(xy 380.586509 -277.735229) (xy 380.556288 -277.693633) (xy 380.532945 -277.647821) (xy 380.517057 -277.598922)
			(xy 380.509014 -277.54814) (xy 380.25149 -277.54814) (xy 380.251472 -277.549081) (xy 380.243529 -277.601785)
			(xy 380.227819 -277.652715) (xy 380.204693 -277.700736) (xy 380.174669 -277.744773) (xy 380.138417 -277.783844)
			(xy 380.096746 -277.817075) (xy 380.050588 -277.843724) (xy 380.000974 -277.863196) (xy 379.949012 -277.875056)
			(xy 379.895862 -277.87904) (xy 379.842712 -277.875056) (xy 379.79075 -277.863196) (xy 379.741136 -277.843724)
			(xy 379.694978 -277.817075) (xy 379.653307 -277.783844) (xy 379.617055 -277.744773) (xy 379.587031 -277.700736)
			(xy 379.563905 -277.652715) (xy 379.548195 -277.601785) (xy 379.540252 -277.549081) (xy 379.311926 -277.549081)
			(xy 379.303983 -277.601785) (xy 379.288273 -277.652715) (xy 379.265147 -277.700736) (xy 379.235123 -277.744773)
			(xy 379.198871 -277.783844) (xy 379.1572 -277.817075) (xy 379.111042 -277.843724) (xy 379.061428 -277.863196)
			(xy 379.009466 -277.875056) (xy 378.956316 -277.87904) (xy 378.903166 -277.875056) (xy 378.851204 -277.863196)
			(xy 378.80159 -277.843724) (xy 378.755432 -277.817075) (xy 378.713761 -277.783844) (xy 378.677509 -277.744773)
			(xy 378.647485 -277.700736) (xy 378.624359 -277.652715) (xy 378.608649 -277.601785) (xy 378.600706 -277.549081)
			(xy 378.372126 -277.549081) (xy 378.364183 -277.601785) (xy 378.348473 -277.652715) (xy 378.325347 -277.700736)
			(xy 378.295323 -277.744773) (xy 378.259071 -277.783844) (xy 378.2174 -277.817075) (xy 378.171242 -277.843724)
			(xy 378.121628 -277.863196) (xy 378.069666 -277.875056) (xy 378.016516 -277.87904) (xy 377.963366 -277.875056)
			(xy 377.911404 -277.863196) (xy 377.86179 -277.843724) (xy 377.815632 -277.817075) (xy 377.773961 -277.783844)
			(xy 377.737709 -277.744773) (xy 377.707685 -277.700736) (xy 377.684559 -277.652715) (xy 377.668849 -277.601785)
			(xy 377.660906 -277.549081) (xy 377.402961 -277.549081) (xy 377.395067 -277.598922) (xy 377.379179 -277.647821)
			(xy 377.355836 -277.693633) (xy 377.325615 -277.735229) (xy 377.289259 -277.771585) (xy 377.247663 -277.801806)
			(xy 377.201851 -277.825149) (xy 377.152952 -277.841037) (xy 377.10217 -277.84908) (xy 377.050754 -277.84908)
			(xy 376.999972 -277.841037) (xy 376.951073 -277.825149) (xy 376.905261 -277.801806) (xy 376.863665 -277.771585)
			(xy 376.827309 -277.735229) (xy 376.797088 -277.693633) (xy 376.773745 -277.647821) (xy 376.757857 -277.598922)
			(xy 376.749814 -277.54814) (xy 376.46331 -277.54814) (xy 376.455267 -277.598922) (xy 376.439379 -277.647821)
			(xy 376.416036 -277.693633) (xy 376.385815 -277.735229) (xy 376.349459 -277.771585) (xy 376.307863 -277.801806)
			(xy 376.262051 -277.825149) (xy 376.213152 -277.841037) (xy 376.16237 -277.84908) (xy 376.110954 -277.84908)
			(xy 376.060172 -277.841037) (xy 376.011273 -277.825149) (xy 375.965461 -277.801806) (xy 375.923865 -277.771585)
			(xy 375.887509 -277.735229) (xy 375.857288 -277.693633) (xy 375.833945 -277.647821) (xy 375.818057 -277.598922)
			(xy 375.810014 -277.54814) (xy 375.52351 -277.54814) (xy 375.515467 -277.598922) (xy 375.499579 -277.647821)
			(xy 375.476236 -277.693633) (xy 375.446015 -277.735229) (xy 375.409659 -277.771585) (xy 375.368063 -277.801806)
			(xy 375.322251 -277.825149) (xy 375.273352 -277.841037) (xy 375.22257 -277.84908) (xy 375.171154 -277.84908)
			(xy 375.120372 -277.841037) (xy 375.071473 -277.825149) (xy 375.025661 -277.801806) (xy 374.984065 -277.771585)
			(xy 374.947709 -277.735229) (xy 374.917488 -277.693633) (xy 374.894145 -277.647821) (xy 374.878257 -277.598922)
			(xy 374.870214 -277.54814) (xy 374.58371 -277.54814) (xy 374.575667 -277.598922) (xy 374.559779 -277.647821)
			(xy 374.536436 -277.693633) (xy 374.506215 -277.735229) (xy 374.469859 -277.771585) (xy 374.428263 -277.801806)
			(xy 374.382451 -277.825149) (xy 374.333552 -277.841037) (xy 374.28277 -277.84908) (xy 374.231354 -277.84908)
			(xy 374.180572 -277.841037) (xy 374.131673 -277.825149) (xy 374.085861 -277.801806) (xy 374.044265 -277.771585)
			(xy 374.007909 -277.735229) (xy 373.977688 -277.693633) (xy 373.954345 -277.647821) (xy 373.938457 -277.598922)
			(xy 373.930414 -277.54814) (xy 373.673144 -277.54814) (xy 373.673126 -277.549081) (xy 373.665183 -277.601785)
			(xy 373.649473 -277.652715) (xy 373.626347 -277.700736) (xy 373.596323 -277.744773) (xy 373.560071 -277.783844)
			(xy 373.5184 -277.817075) (xy 373.472242 -277.843724) (xy 373.422628 -277.863196) (xy 373.370666 -277.875056)
			(xy 373.317516 -277.87904) (xy 373.264366 -277.875056) (xy 373.212404 -277.863196) (xy 373.16279 -277.843724)
			(xy 373.116632 -277.817075) (xy 373.074961 -277.783844) (xy 373.038709 -277.744773) (xy 373.008685 -277.700736)
			(xy 372.985559 -277.652715) (xy 372.969849 -277.601785) (xy 372.961906 -277.549081) (xy 372.733072 -277.549081)
			(xy 372.725129 -277.601785) (xy 372.709419 -277.652715) (xy 372.686293 -277.700736) (xy 372.656269 -277.744773)
			(xy 372.620017 -277.783844) (xy 372.578346 -277.817075) (xy 372.532188 -277.843724) (xy 372.482574 -277.863196)
			(xy 372.430612 -277.875056) (xy 372.377462 -277.87904) (xy 372.324312 -277.875056) (xy 372.27235 -277.863196)
			(xy 372.222736 -277.843724) (xy 372.176578 -277.817075) (xy 372.134907 -277.783844) (xy 372.098655 -277.744773)
			(xy 372.068631 -277.700736) (xy 372.045505 -277.652715) (xy 372.029795 -277.601785) (xy 372.021852 -277.549081)
			(xy 371.793272 -277.549081) (xy 371.785329 -277.601785) (xy 371.769619 -277.652715) (xy 371.746493 -277.700736)
			(xy 371.716469 -277.744773) (xy 371.680217 -277.783844) (xy 371.638546 -277.817075) (xy 371.592388 -277.843724)
			(xy 371.542774 -277.863196) (xy 371.490812 -277.875056) (xy 371.437662 -277.87904) (xy 371.384512 -277.875056)
			(xy 371.33255 -277.863196) (xy 371.282936 -277.843724) (xy 371.236778 -277.817075) (xy 371.195107 -277.783844)
			(xy 371.158855 -277.744773) (xy 371.128831 -277.700736) (xy 371.105705 -277.652715) (xy 371.089995 -277.601785)
			(xy 371.082052 -277.549081) (xy 370.853688 -277.549081) (xy 370.845783 -277.601531) (xy 370.830073 -277.652461)
			(xy 370.806947 -277.700482) (xy 370.776923 -277.744519) (xy 370.740671 -277.78359) (xy 370.699 -277.816821)
			(xy 370.652842 -277.84347) (xy 370.603228 -277.862942) (xy 370.551266 -277.874802) (xy 370.498116 -277.878786)
			(xy 370.444966 -277.874802) (xy 370.393004 -277.862942) (xy 370.34339 -277.84347) (xy 370.297232 -277.816821)
			(xy 370.255561 -277.78359) (xy 370.219309 -277.744519) (xy 370.189285 -277.700482) (xy 370.166159 -277.652461)
			(xy 370.150449 -277.601531) (xy 370.142506 -277.548827) (xy 369.913926 -277.548827) (xy 369.905983 -277.601531)
			(xy 369.890273 -277.652461) (xy 369.867147 -277.700482) (xy 369.837123 -277.744519) (xy 369.800871 -277.78359)
			(xy 369.7592 -277.816821) (xy 369.713042 -277.84347) (xy 369.663428 -277.862942) (xy 369.611466 -277.874802)
			(xy 369.558316 -277.878786) (xy 369.505166 -277.874802) (xy 369.453204 -277.862942) (xy 369.40359 -277.84347)
			(xy 369.357432 -277.816821) (xy 369.315761 -277.78359) (xy 369.279509 -277.744519) (xy 369.249485 -277.700482)
			(xy 369.226359 -277.652461) (xy 369.210649 -277.601531) (xy 369.202706 -277.548827) (xy 368.974126 -277.548827)
			(xy 368.966183 -277.601531) (xy 368.950473 -277.652461) (xy 368.927347 -277.700482) (xy 368.897323 -277.744519)
			(xy 368.861071 -277.78359) (xy 368.8194 -277.816821) (xy 368.773242 -277.84347) (xy 368.723628 -277.862942)
			(xy 368.671666 -277.874802) (xy 368.618516 -277.878786) (xy 368.565366 -277.874802) (xy 368.513404 -277.862942)
			(xy 368.46379 -277.84347) (xy 368.417632 -277.816821) (xy 368.375961 -277.78359) (xy 368.339709 -277.744519)
			(xy 368.309685 -277.700482) (xy 368.286559 -277.652461) (xy 368.270849 -277.601531) (xy 368.262906 -277.548827)
			(xy 368.034326 -277.548827) (xy 368.026383 -277.601531) (xy 368.010673 -277.652461) (xy 367.987547 -277.700482)
			(xy 367.957523 -277.744519) (xy 367.921271 -277.78359) (xy 367.8796 -277.816821) (xy 367.833442 -277.84347)
			(xy 367.783828 -277.862942) (xy 367.731866 -277.874802) (xy 367.678716 -277.878786) (xy 367.625566 -277.874802)
			(xy 367.573604 -277.862942) (xy 367.52399 -277.84347) (xy 367.477832 -277.816821) (xy 367.436161 -277.78359)
			(xy 367.399909 -277.744519) (xy 367.369885 -277.700482) (xy 367.346759 -277.652461) (xy 367.331049 -277.601531)
			(xy 367.323106 -277.548827) (xy 367.094531 -277.548827) (xy 367.094526 -277.549081) (xy 367.086583 -277.601785)
			(xy 367.070873 -277.652715) (xy 367.047747 -277.700736) (xy 367.017723 -277.744773) (xy 366.981471 -277.783844)
			(xy 366.9398 -277.817075) (xy 366.893642 -277.843724) (xy 366.844028 -277.863196) (xy 366.792066 -277.875056)
			(xy 366.738916 -277.87904) (xy 366.685766 -277.875056) (xy 366.633804 -277.863196) (xy 366.58419 -277.843724)
			(xy 366.538032 -277.817075) (xy 366.496361 -277.783844) (xy 366.460109 -277.744773) (xy 366.430085 -277.700736)
			(xy 366.406959 -277.652715) (xy 366.391249 -277.601785) (xy 366.383306 -277.549081) (xy 366.154688 -277.549081)
			(xy 366.146783 -277.601531) (xy 366.131073 -277.652461) (xy 366.107947 -277.700482) (xy 366.077923 -277.744519)
			(xy 366.041671 -277.78359) (xy 366 -277.816821) (xy 365.953842 -277.84347) (xy 365.904228 -277.862942)
			(xy 365.852266 -277.874802) (xy 365.799116 -277.878786) (xy 365.745966 -277.874802) (xy 365.694004 -277.862942)
			(xy 365.64439 -277.84347) (xy 365.598232 -277.816821) (xy 365.556561 -277.78359) (xy 365.520309 -277.744519)
			(xy 365.490285 -277.700482) (xy 365.467159 -277.652461) (xy 365.451449 -277.601531) (xy 365.443506 -277.548827)
			(xy 365.214677 -277.548827) (xy 365.214672 -277.549081) (xy 365.206729 -277.601785) (xy 365.191019 -277.652715)
			(xy 365.167893 -277.700736) (xy 365.137869 -277.744773) (xy 365.101617 -277.783844) (xy 365.059946 -277.817075)
			(xy 365.013788 -277.843724) (xy 364.964174 -277.863196) (xy 364.912212 -277.875056) (xy 364.859062 -277.87904)
			(xy 364.805912 -277.875056) (xy 364.75395 -277.863196) (xy 364.704336 -277.843724) (xy 364.658178 -277.817075)
			(xy 364.616507 -277.783844) (xy 364.580255 -277.744773) (xy 364.550231 -277.700736) (xy 364.527105 -277.652715)
			(xy 364.511395 -277.601785) (xy 364.503452 -277.549081) (xy 364.275088 -277.549081) (xy 364.267183 -277.601531)
			(xy 364.251473 -277.652461) (xy 364.228347 -277.700482) (xy 364.198323 -277.744519) (xy 364.162071 -277.78359)
			(xy 364.1204 -277.816821) (xy 364.074242 -277.84347) (xy 364.024628 -277.862942) (xy 363.972666 -277.874802)
			(xy 363.919516 -277.878786) (xy 363.866366 -277.874802) (xy 363.814404 -277.862942) (xy 363.76479 -277.84347)
			(xy 363.718632 -277.816821) (xy 363.676961 -277.78359) (xy 363.640709 -277.744519) (xy 363.610685 -277.700482)
			(xy 363.587559 -277.652461) (xy 363.571849 -277.601531) (xy 363.563906 -277.548827) (xy 363.335077 -277.548827)
			(xy 363.335072 -277.549081) (xy 363.327129 -277.601785) (xy 363.311419 -277.652715) (xy 363.288293 -277.700736)
			(xy 363.258269 -277.744773) (xy 363.222017 -277.783844) (xy 363.180346 -277.817075) (xy 363.134188 -277.843724)
			(xy 363.084574 -277.863196) (xy 363.032612 -277.875056) (xy 362.979462 -277.87904) (xy 362.926312 -277.875056)
			(xy 362.87435 -277.863196) (xy 362.824736 -277.843724) (xy 362.778578 -277.817075) (xy 362.736907 -277.783844)
			(xy 362.700655 -277.744773) (xy 362.670631 -277.700736) (xy 362.647505 -277.652715) (xy 362.631795 -277.601785)
			(xy 362.623852 -277.549081) (xy 358.636072 -277.549081) (xy 358.628129 -277.601785) (xy 358.612419 -277.652715)
			(xy 358.589293 -277.700736) (xy 358.559269 -277.744773) (xy 358.523017 -277.783844) (xy 358.481346 -277.817075)
			(xy 358.435188 -277.843724) (xy 358.385574 -277.863196) (xy 358.333612 -277.875056) (xy 358.280462 -277.87904)
			(xy 358.227312 -277.875056) (xy 358.17535 -277.863196) (xy 358.125736 -277.843724) (xy 358.079578 -277.817075)
			(xy 358.037907 -277.783844) (xy 358.001655 -277.744773) (xy 357.971631 -277.700736) (xy 357.948505 -277.652715)
			(xy 357.932795 -277.601785) (xy 357.924852 -277.549081) (xy 357.669821 -277.549081) (xy 357.661834 -277.599503)
			(xy 357.645817 -277.648794) (xy 357.622286 -277.694972) (xy 357.591821 -277.7369) (xy 357.555171 -277.773546)
			(xy 357.51324 -277.804006) (xy 357.467059 -277.827532) (xy 357.417766 -277.843543) (xy 357.366576 -277.851645)
			(xy 357.340662 -277.852124) (xy 357.31515 -277.851662) (xy 357.264735 -277.843796) (xy 357.216133 -277.828258)
			(xy 357.170505 -277.805419) (xy 357.12894 -277.775824) (xy 357.09243 -277.74018) (xy 357.076756 -277.720044)
			(xy 356.664768 -277.720044) (xy 356.649125 -277.740204) (xy 356.612608 -277.775845) (xy 356.571036 -277.805434)
			(xy 356.525401 -277.828266) (xy 356.476795 -277.843795) (xy 356.426376 -277.85165) (xy 356.400862 -277.852124)
			(xy 356.374959 -277.851549) (xy 356.323792 -277.843439) (xy 356.274523 -277.827426) (xy 356.228366 -277.803903)
			(xy 356.186456 -277.773449) (xy 356.149826 -277.736815) (xy 356.119377 -277.694902) (xy 356.09586 -277.648742)
			(xy 356.079852 -277.599471) (xy 356.071748 -277.548303) (xy 355.789963 -277.548303) (xy 355.789917 -277.550456)
			(xy 355.780726 -277.604717) (xy 355.772212 -277.63089) (xy 355.764592 -277.652988) (xy 355.969824 -278.008334)
			(xy 355.992684 -278.012652) (xy 356.017501 -278.017836) (xy 356.065277 -278.034792) (xy 356.109893 -278.058863)
			(xy 356.150297 -278.089482) (xy 356.185537 -278.125927) (xy 356.214781 -278.167338) (xy 356.23734 -278.212738)
			(xy 356.252681 -278.261056) (xy 356.260443 -278.311154) (xy 356.260908 -278.336502) (xy 356.2604 -278.362409)
			(xy 356.260282 -278.363151) (xy 356.515152 -278.363151) (xy 356.515152 -278.309853) (xy 356.523095 -278.257149)
			(xy 356.538805 -278.206219) (xy 356.561931 -278.158198) (xy 356.591955 -278.114161) (xy 356.628207 -278.07509)
			(xy 356.669878 -278.041859) (xy 356.716036 -278.01521) (xy 356.76565 -277.995738) (xy 356.817612 -277.983878)
			(xy 356.870762 -277.979895) (xy 356.923912 -277.983878) (xy 356.975874 -277.995738) (xy 357.025488 -278.01521)
			(xy 357.071646 -278.041859) (xy 357.113317 -278.07509) (xy 357.149569 -278.114161) (xy 357.179593 -278.158198)
			(xy 357.202719 -278.206219) (xy 357.218429 -278.257149) (xy 357.226372 -278.309853) (xy 357.22687 -278.336502)
			(xy 357.226372 -278.363151) (xy 357.454952 -278.363151) (xy 357.454952 -278.309853) (xy 357.462895 -278.257149)
			(xy 357.478605 -278.206219) (xy 357.501731 -278.158198) (xy 357.531755 -278.114161) (xy 357.568007 -278.07509)
			(xy 357.609678 -278.041859) (xy 357.655836 -278.01521) (xy 357.70545 -277.995738) (xy 357.757412 -277.983878)
			(xy 357.810562 -277.979895) (xy 357.863712 -277.983878) (xy 357.915674 -277.995738) (xy 357.965288 -278.01521)
			(xy 358.011446 -278.041859) (xy 358.053117 -278.07509) (xy 358.089369 -278.114161) (xy 358.119393 -278.158198)
			(xy 358.142519 -278.206219) (xy 358.158229 -278.257149) (xy 358.166172 -278.309853) (xy 358.16667 -278.336502)
			(xy 358.166177 -278.362897) (xy 362.153952 -278.362897) (xy 362.153952 -278.309599) (xy 362.161895 -278.256895)
			(xy 362.177605 -278.205965) (xy 362.200731 -278.157944) (xy 362.230755 -278.113907) (xy 362.267007 -278.074836)
			(xy 362.308678 -278.041605) (xy 362.354836 -278.014956) (xy 362.40445 -277.995484) (xy 362.456412 -277.983624)
			(xy 362.509562 -277.979641) (xy 362.562712 -277.983624) (xy 362.614674 -277.995484) (xy 362.664288 -278.014956)
			(xy 362.710446 -278.041605) (xy 362.752117 -278.074836) (xy 362.788369 -278.113907) (xy 362.818393 -278.157944)
			(xy 362.841519 -278.205965) (xy 362.857229 -278.256895) (xy 362.865172 -278.309599) (xy 362.86567 -278.336248)
			(xy 362.865172 -278.362897) (xy 363.093752 -278.362897) (xy 363.093752 -278.309599) (xy 363.101695 -278.256895)
			(xy 363.117405 -278.205965) (xy 363.140531 -278.157944) (xy 363.170555 -278.113907) (xy 363.206807 -278.074836)
			(xy 363.248478 -278.041605) (xy 363.294636 -278.014956) (xy 363.34425 -277.995484) (xy 363.396212 -277.983624)
			(xy 363.449362 -277.979641) (xy 363.502512 -277.983624) (xy 363.554474 -277.995484) (xy 363.604088 -278.014956)
			(xy 363.650246 -278.041605) (xy 363.691917 -278.074836) (xy 363.728169 -278.113907) (xy 363.758193 -278.157944)
			(xy 363.781319 -278.205965) (xy 363.797029 -278.256895) (xy 363.804972 -278.309599) (xy 363.80547 -278.336248)
			(xy 363.804972 -278.362897) (xy 364.033552 -278.362897) (xy 364.033552 -278.309599) (xy 364.041495 -278.256895)
			(xy 364.057205 -278.205965) (xy 364.080331 -278.157944) (xy 364.110355 -278.113907) (xy 364.146607 -278.074836)
			(xy 364.188278 -278.041605) (xy 364.234436 -278.014956) (xy 364.28405 -277.995484) (xy 364.336012 -277.983624)
			(xy 364.389162 -277.979641) (xy 364.442312 -277.983624) (xy 364.494274 -277.995484) (xy 364.543888 -278.014956)
			(xy 364.590046 -278.041605) (xy 364.631717 -278.074836) (xy 364.667969 -278.113907) (xy 364.697993 -278.157944)
			(xy 364.721119 -278.205965) (xy 364.736829 -278.256895) (xy 364.744772 -278.309599) (xy 364.74527 -278.336248)
			(xy 364.744772 -278.362897) (xy 364.973352 -278.362897) (xy 364.973352 -278.309599) (xy 364.981295 -278.256895)
			(xy 364.997005 -278.205965) (xy 365.020131 -278.157944) (xy 365.050155 -278.113907) (xy 365.086407 -278.074836)
			(xy 365.128078 -278.041605) (xy 365.174236 -278.014956) (xy 365.22385 -277.995484) (xy 365.275812 -277.983624)
			(xy 365.328962 -277.979641) (xy 365.382112 -277.983624) (xy 365.434074 -277.995484) (xy 365.483688 -278.014956)
			(xy 365.529846 -278.041605) (xy 365.571517 -278.074836) (xy 365.607769 -278.113907) (xy 365.637793 -278.157944)
			(xy 365.660919 -278.205965) (xy 365.676629 -278.256895) (xy 365.684572 -278.309599) (xy 365.68507 -278.336248)
			(xy 365.684572 -278.362897) (xy 365.913152 -278.362897) (xy 365.913152 -278.309599) (xy 365.921095 -278.256895)
			(xy 365.936805 -278.205965) (xy 365.959931 -278.157944) (xy 365.989955 -278.113907) (xy 366.026207 -278.074836)
			(xy 366.067878 -278.041605) (xy 366.114036 -278.014956) (xy 366.16365 -277.995484) (xy 366.215612 -277.983624)
			(xy 366.268762 -277.979641) (xy 366.321912 -277.983624) (xy 366.373874 -277.995484) (xy 366.423488 -278.014956)
			(xy 366.469646 -278.041605) (xy 366.511317 -278.074836) (xy 366.547569 -278.113907) (xy 366.577593 -278.157944)
			(xy 366.600719 -278.205965) (xy 366.616429 -278.256895) (xy 366.624372 -278.309599) (xy 366.62487 -278.336248)
			(xy 366.624372 -278.362897) (xy 366.624334 -278.363151) (xy 366.853206 -278.363151) (xy 366.853206 -278.309853)
			(xy 366.861149 -278.257149) (xy 366.876859 -278.206219) (xy 366.899985 -278.158198) (xy 366.930009 -278.114161)
			(xy 366.966261 -278.07509) (xy 367.007932 -278.041859) (xy 367.05409 -278.01521) (xy 367.103704 -277.995738)
			(xy 367.155666 -277.983878) (xy 367.208816 -277.979895) (xy 367.261966 -277.983878) (xy 367.313928 -277.995738)
			(xy 367.363542 -278.01521) (xy 367.4097 -278.041859) (xy 367.451371 -278.07509) (xy 367.487623 -278.114161)
			(xy 367.517647 -278.158198) (xy 367.540773 -278.206219) (xy 367.556483 -278.257149) (xy 367.564426 -278.309853)
			(xy 367.564924 -278.336502) (xy 367.564426 -278.363151) (xy 367.793006 -278.363151) (xy 367.793006 -278.309853)
			(xy 367.800949 -278.257149) (xy 367.816659 -278.206219) (xy 367.839785 -278.158198) (xy 367.869809 -278.114161)
			(xy 367.906061 -278.07509) (xy 367.947732 -278.041859) (xy 367.99389 -278.01521) (xy 368.043504 -277.995738)
			(xy 368.095466 -277.983878) (xy 368.148616 -277.979895) (xy 368.201766 -277.983878) (xy 368.253728 -277.995738)
			(xy 368.303342 -278.01521) (xy 368.3495 -278.041859) (xy 368.391171 -278.07509) (xy 368.427423 -278.114161)
			(xy 368.457447 -278.158198) (xy 368.480573 -278.206219) (xy 368.496283 -278.257149) (xy 368.504226 -278.309853)
			(xy 368.504724 -278.336502) (xy 368.504231 -278.362897) (xy 368.732552 -278.362897) (xy 368.732552 -278.309599)
			(xy 368.740495 -278.256895) (xy 368.756205 -278.205965) (xy 368.779331 -278.157944) (xy 368.809355 -278.113907)
			(xy 368.845607 -278.074836) (xy 368.887278 -278.041605) (xy 368.933436 -278.014956) (xy 368.98305 -277.995484)
			(xy 369.035012 -277.983624) (xy 369.088162 -277.979641) (xy 369.141312 -277.983624) (xy 369.193274 -277.995484)
			(xy 369.242888 -278.014956) (xy 369.289046 -278.041605) (xy 369.330717 -278.074836) (xy 369.366969 -278.113907)
			(xy 369.396993 -278.157944) (xy 369.420119 -278.205965) (xy 369.435829 -278.256895) (xy 369.443772 -278.309599)
			(xy 369.44427 -278.336248) (xy 369.443772 -278.362897) (xy 369.443734 -278.363151) (xy 369.672352 -278.363151)
			(xy 369.672352 -278.309853) (xy 369.680295 -278.257149) (xy 369.696005 -278.206219) (xy 369.719131 -278.158198)
			(xy 369.749155 -278.114161) (xy 369.785407 -278.07509) (xy 369.827078 -278.041859) (xy 369.873236 -278.01521)
			(xy 369.92285 -277.995738) (xy 369.974812 -277.983878) (xy 370.027962 -277.979895) (xy 370.081112 -277.983878)
			(xy 370.133074 -277.995738) (xy 370.182688 -278.01521) (xy 370.228846 -278.041859) (xy 370.270517 -278.07509)
			(xy 370.306769 -278.114161) (xy 370.336793 -278.158198) (xy 370.359919 -278.206219) (xy 370.375629 -278.257149)
			(xy 370.383572 -278.309853) (xy 370.38407 -278.336502) (xy 370.383572 -278.363151) (xy 370.612406 -278.363151)
			(xy 370.612406 -278.309853) (xy 370.620349 -278.257149) (xy 370.636059 -278.206219) (xy 370.659185 -278.158198)
			(xy 370.689209 -278.114161) (xy 370.725461 -278.07509) (xy 370.767132 -278.041859) (xy 370.81329 -278.01521)
			(xy 370.862904 -277.995738) (xy 370.914866 -277.983878) (xy 370.968016 -277.979895) (xy 371.021166 -277.983878)
			(xy 371.073128 -277.995738) (xy 371.122742 -278.01521) (xy 371.1689 -278.041859) (xy 371.210571 -278.07509)
			(xy 371.246823 -278.114161) (xy 371.276847 -278.158198) (xy 371.299973 -278.206219) (xy 371.315683 -278.257149)
			(xy 371.323626 -278.309853) (xy 371.324124 -278.336502) (xy 371.323626 -278.363151) (xy 371.552206 -278.363151)
			(xy 371.552206 -278.309853) (xy 371.560149 -278.257149) (xy 371.575859 -278.206219) (xy 371.598985 -278.158198)
			(xy 371.629009 -278.114161) (xy 371.665261 -278.07509) (xy 371.706932 -278.041859) (xy 371.75309 -278.01521)
			(xy 371.802704 -277.995738) (xy 371.854666 -277.983878) (xy 371.907816 -277.979895) (xy 371.960966 -277.983878)
			(xy 372.012928 -277.995738) (xy 372.062542 -278.01521) (xy 372.1087 -278.041859) (xy 372.150371 -278.07509)
			(xy 372.186623 -278.114161) (xy 372.216647 -278.158198) (xy 372.239773 -278.206219) (xy 372.255483 -278.257149)
			(xy 372.263426 -278.309853) (xy 372.263924 -278.336502) (xy 372.263426 -278.363151) (xy 372.492006 -278.363151)
			(xy 372.492006 -278.309853) (xy 372.499949 -278.257149) (xy 372.515659 -278.206219) (xy 372.538785 -278.158198)
			(xy 372.568809 -278.114161) (xy 372.605061 -278.07509) (xy 372.646732 -278.041859) (xy 372.69289 -278.01521)
			(xy 372.742504 -277.995738) (xy 372.794466 -277.983878) (xy 372.847616 -277.979895) (xy 372.900766 -277.983878)
			(xy 372.952728 -277.995738) (xy 373.002342 -278.01521) (xy 373.0485 -278.041859) (xy 373.090171 -278.07509)
			(xy 373.126423 -278.114161) (xy 373.156447 -278.158198) (xy 373.179573 -278.206219) (xy 373.195283 -278.257149)
			(xy 373.203226 -278.309853) (xy 373.203724 -278.336502) (xy 373.203226 -278.363151) (xy 373.431806 -278.363151)
			(xy 373.431806 -278.309853) (xy 373.439749 -278.257149) (xy 373.455459 -278.206219) (xy 373.478585 -278.158198)
			(xy 373.508609 -278.114161) (xy 373.544861 -278.07509) (xy 373.586532 -278.041859) (xy 373.63269 -278.01521)
			(xy 373.682304 -277.995738) (xy 373.734266 -277.983878) (xy 373.787416 -277.979895) (xy 373.840566 -277.983878)
			(xy 373.892528 -277.995738) (xy 373.942142 -278.01521) (xy 373.9883 -278.041859) (xy 374.029971 -278.07509)
			(xy 374.066223 -278.114161) (xy 374.096247 -278.158198) (xy 374.119373 -278.206219) (xy 374.135083 -278.257149)
			(xy 374.143026 -278.309853) (xy 374.143524 -278.336502) (xy 374.143026 -278.363151) (xy 374.371606 -278.363151)
			(xy 374.371606 -278.309853) (xy 374.379549 -278.257149) (xy 374.395259 -278.206219) (xy 374.418385 -278.158198)
			(xy 374.448409 -278.114161) (xy 374.484661 -278.07509) (xy 374.526332 -278.041859) (xy 374.57249 -278.01521)
			(xy 374.622104 -277.995738) (xy 374.674066 -277.983878) (xy 374.727216 -277.979895) (xy 374.780366 -277.983878)
			(xy 374.832328 -277.995738) (xy 374.881942 -278.01521) (xy 374.9281 -278.041859) (xy 374.969771 -278.07509)
			(xy 375.006023 -278.114161) (xy 375.036047 -278.158198) (xy 375.059173 -278.206219) (xy 375.074883 -278.257149)
			(xy 375.082826 -278.309853) (xy 375.083324 -278.336502) (xy 375.082826 -278.363151) (xy 375.311406 -278.363151)
			(xy 375.311406 -278.309853) (xy 375.319349 -278.257149) (xy 375.335059 -278.206219) (xy 375.358185 -278.158198)
			(xy 375.388209 -278.114161) (xy 375.424461 -278.07509) (xy 375.466132 -278.041859) (xy 375.51229 -278.01521)
			(xy 375.561904 -277.995738) (xy 375.613866 -277.983878) (xy 375.667016 -277.979895) (xy 375.720166 -277.983878)
			(xy 375.772128 -277.995738) (xy 375.821742 -278.01521) (xy 375.8679 -278.041859) (xy 375.909571 -278.07509)
			(xy 375.945823 -278.114161) (xy 375.975847 -278.158198) (xy 375.998973 -278.206219) (xy 376.014683 -278.257149)
			(xy 376.022626 -278.309853) (xy 376.023124 -278.336502) (xy 376.022644 -278.36221) (xy 376.279914 -278.36221)
			(xy 376.279914 -278.310794) (xy 376.287957 -278.260012) (xy 376.303845 -278.211113) (xy 376.327188 -278.165301)
			(xy 376.357409 -278.123705) (xy 376.393765 -278.087349) (xy 376.435361 -278.057128) (xy 376.481173 -278.033785)
			(xy 376.530072 -278.017897) (xy 376.580854 -278.009854) (xy 376.63227 -278.009854) (xy 376.683052 -278.017897)
			(xy 376.731951 -278.033785) (xy 376.777763 -278.057128) (xy 376.819359 -278.087349) (xy 376.855715 -278.123705)
			(xy 376.885936 -278.165301) (xy 376.909279 -278.211113) (xy 376.925167 -278.260012) (xy 376.93321 -278.310794)
			(xy 376.933714 -278.336502) (xy 376.93321 -278.36221) (xy 377.219968 -278.36221) (xy 377.219968 -278.310794)
			(xy 377.228011 -278.260012) (xy 377.243899 -278.211113) (xy 377.267242 -278.165301) (xy 377.297463 -278.123705)
			(xy 377.333819 -278.087349) (xy 377.375415 -278.057128) (xy 377.421227 -278.033785) (xy 377.470126 -278.017897)
			(xy 377.520908 -278.009854) (xy 377.572324 -278.009854) (xy 377.623106 -278.017897) (xy 377.672005 -278.033785)
			(xy 377.717817 -278.057128) (xy 377.759413 -278.087349) (xy 377.795769 -278.123705) (xy 377.82599 -278.165301)
			(xy 377.849333 -278.211113) (xy 377.865221 -278.260012) (xy 377.873264 -278.310794) (xy 377.873768 -278.336502)
			(xy 377.873264 -278.36221) (xy 377.873115 -278.363151) (xy 378.130552 -278.363151) (xy 378.130552 -278.309853)
			(xy 378.138495 -278.257149) (xy 378.154205 -278.206219) (xy 378.177331 -278.158198) (xy 378.207355 -278.114161)
			(xy 378.243607 -278.07509) (xy 378.285278 -278.041859) (xy 378.331436 -278.01521) (xy 378.38105 -277.995738)
			(xy 378.433012 -277.983878) (xy 378.486162 -277.979895) (xy 378.539312 -277.983878) (xy 378.591274 -277.995738)
			(xy 378.640888 -278.01521) (xy 378.687046 -278.041859) (xy 378.728717 -278.07509) (xy 378.764969 -278.114161)
			(xy 378.794993 -278.158198) (xy 378.818119 -278.206219) (xy 378.833829 -278.257149) (xy 378.841772 -278.309853)
			(xy 378.84227 -278.336502) (xy 378.841772 -278.363151) (xy 379.070606 -278.363151) (xy 379.070606 -278.309853)
			(xy 379.078549 -278.257149) (xy 379.094259 -278.206219) (xy 379.117385 -278.158198) (xy 379.147409 -278.114161)
			(xy 379.183661 -278.07509) (xy 379.225332 -278.041859) (xy 379.27149 -278.01521) (xy 379.321104 -277.995738)
			(xy 379.373066 -277.983878) (xy 379.426216 -277.979895) (xy 379.479366 -277.983878) (xy 379.531328 -277.995738)
			(xy 379.580942 -278.01521) (xy 379.6271 -278.041859) (xy 379.668771 -278.07509) (xy 379.705023 -278.114161)
			(xy 379.735047 -278.158198) (xy 379.758173 -278.206219) (xy 379.773883 -278.257149) (xy 379.781826 -278.309853)
			(xy 379.782324 -278.336502) (xy 379.781844 -278.36221) (xy 380.039368 -278.36221) (xy 380.039368 -278.310794)
			(xy 380.047411 -278.260012) (xy 380.063299 -278.211113) (xy 380.086642 -278.165301) (xy 380.116863 -278.123705)
			(xy 380.153219 -278.087349) (xy 380.194815 -278.057128) (xy 380.240627 -278.033785) (xy 380.289526 -278.017897)
			(xy 380.340308 -278.009854) (xy 380.391724 -278.009854) (xy 380.442506 -278.017897) (xy 380.491405 -278.033785)
			(xy 380.537217 -278.057128) (xy 380.578813 -278.087349) (xy 380.615169 -278.123705) (xy 380.64539 -278.165301)
			(xy 380.668733 -278.211113) (xy 380.684621 -278.260012) (xy 380.692664 -278.310794) (xy 380.693168 -278.336502)
			(xy 380.692664 -278.36221) (xy 380.979168 -278.36221) (xy 380.979168 -278.310794) (xy 380.987211 -278.260012)
			(xy 381.003099 -278.211113) (xy 381.026442 -278.165301) (xy 381.056663 -278.123705) (xy 381.093019 -278.087349)
			(xy 381.134615 -278.057128) (xy 381.180427 -278.033785) (xy 381.229326 -278.017897) (xy 381.280108 -278.009854)
			(xy 381.331524 -278.009854) (xy 381.382306 -278.017897) (xy 381.431205 -278.033785) (xy 381.477017 -278.057128)
			(xy 381.518613 -278.087349) (xy 381.554969 -278.123705) (xy 381.58519 -278.165301) (xy 381.608533 -278.211113)
			(xy 381.624421 -278.260012) (xy 381.632464 -278.310794) (xy 381.632968 -278.336502) (xy 381.632464 -278.36221)
			(xy 381.632315 -278.363151) (xy 381.889752 -278.363151) (xy 381.889752 -278.309853) (xy 381.897695 -278.257149)
			(xy 381.913405 -278.206219) (xy 381.936531 -278.158198) (xy 381.966555 -278.114161) (xy 382.002807 -278.07509)
			(xy 382.044478 -278.041859) (xy 382.090636 -278.01521) (xy 382.14025 -277.995738) (xy 382.192212 -277.983878)
			(xy 382.245362 -277.979895) (xy 382.298512 -277.983878) (xy 382.350474 -277.995738) (xy 382.400088 -278.01521)
			(xy 382.446246 -278.041859) (xy 382.487917 -278.07509) (xy 382.524169 -278.114161) (xy 382.554193 -278.158198)
			(xy 382.577319 -278.206219) (xy 382.593029 -278.257149) (xy 382.600972 -278.309853) (xy 382.60147 -278.336502)
			(xy 382.60099 -278.36221) (xy 382.858514 -278.36221) (xy 382.858514 -278.310794) (xy 382.866557 -278.260012)
			(xy 382.882445 -278.211113) (xy 382.905788 -278.165301) (xy 382.936009 -278.123705) (xy 382.972365 -278.087349)
			(xy 383.013961 -278.057128) (xy 383.059773 -278.033785) (xy 383.108672 -278.017897) (xy 383.159454 -278.009854)
			(xy 383.21087 -278.009854) (xy 383.261652 -278.017897) (xy 383.310551 -278.033785) (xy 383.356363 -278.057128)
			(xy 383.397959 -278.087349) (xy 383.434315 -278.123705) (xy 383.464536 -278.165301) (xy 383.487879 -278.211113)
			(xy 383.503767 -278.260012) (xy 383.51181 -278.310794) (xy 383.512314 -278.336502) (xy 383.51181 -278.36221)
			(xy 383.511661 -278.363151) (xy 383.769352 -278.363151) (xy 383.769352 -278.309853) (xy 383.777295 -278.257149)
			(xy 383.793005 -278.206219) (xy 383.816131 -278.158198) (xy 383.846155 -278.114161) (xy 383.882407 -278.07509)
			(xy 383.924078 -278.041859) (xy 383.970236 -278.01521) (xy 384.01985 -277.995738) (xy 384.071812 -277.983878)
			(xy 384.124962 -277.979895) (xy 384.178112 -277.983878) (xy 384.230074 -277.995738) (xy 384.279688 -278.01521)
			(xy 384.325846 -278.041859) (xy 384.367517 -278.07509) (xy 384.403769 -278.114161) (xy 384.433793 -278.158198)
			(xy 384.456919 -278.206219) (xy 384.472629 -278.257149) (xy 384.480572 -278.309853) (xy 384.48107 -278.336502)
			(xy 384.480572 -278.363151) (xy 384.472629 -278.415855) (xy 384.456919 -278.466785) (xy 384.433793 -278.514806)
			(xy 384.403769 -278.558843) (xy 384.367517 -278.597914) (xy 384.325846 -278.631145) (xy 384.279688 -278.657794)
			(xy 384.230074 -278.677266) (xy 384.178112 -278.689126) (xy 384.124962 -278.69311) (xy 384.071812 -278.689126)
			(xy 384.01985 -278.677266) (xy 383.970236 -278.657794) (xy 383.924078 -278.631145) (xy 383.882407 -278.597914)
			(xy 383.846155 -278.558843) (xy 383.816131 -278.514806) (xy 383.793005 -278.466785) (xy 383.777295 -278.415855)
			(xy 383.769352 -278.363151) (xy 383.511661 -278.363151) (xy 383.503767 -278.412992) (xy 383.487879 -278.461891)
			(xy 383.464536 -278.507703) (xy 383.434315 -278.549299) (xy 383.397959 -278.585655) (xy 383.356363 -278.615876)
			(xy 383.310551 -278.639219) (xy 383.261652 -278.655107) (xy 383.21087 -278.66315) (xy 383.159454 -278.66315)
			(xy 383.108672 -278.655107) (xy 383.059773 -278.639219) (xy 383.013961 -278.615876) (xy 382.972365 -278.585655)
			(xy 382.936009 -278.549299) (xy 382.905788 -278.507703) (xy 382.882445 -278.461891) (xy 382.866557 -278.412992)
			(xy 382.858514 -278.36221) (xy 382.60099 -278.36221) (xy 382.600972 -278.363151) (xy 382.593029 -278.415855)
			(xy 382.577319 -278.466785) (xy 382.554193 -278.514806) (xy 382.524169 -278.558843) (xy 382.487917 -278.597914)
			(xy 382.446246 -278.631145) (xy 382.400088 -278.657794) (xy 382.350474 -278.677266) (xy 382.298512 -278.689126)
			(xy 382.245362 -278.69311) (xy 382.192212 -278.689126) (xy 382.14025 -278.677266) (xy 382.090636 -278.657794)
			(xy 382.044478 -278.631145) (xy 382.002807 -278.597914) (xy 381.966555 -278.558843) (xy 381.936531 -278.514806)
			(xy 381.913405 -278.466785) (xy 381.897695 -278.415855) (xy 381.889752 -278.363151) (xy 381.632315 -278.363151)
			(xy 381.624421 -278.412992) (xy 381.608533 -278.461891) (xy 381.58519 -278.507703) (xy 381.554969 -278.549299)
			(xy 381.518613 -278.585655) (xy 381.477017 -278.615876) (xy 381.431205 -278.639219) (xy 381.382306 -278.655107)
			(xy 381.331524 -278.66315) (xy 381.280108 -278.66315) (xy 381.229326 -278.655107) (xy 381.180427 -278.639219)
			(xy 381.134615 -278.615876) (xy 381.093019 -278.585655) (xy 381.056663 -278.549299) (xy 381.026442 -278.507703)
			(xy 381.003099 -278.461891) (xy 380.987211 -278.412992) (xy 380.979168 -278.36221) (xy 380.692664 -278.36221)
			(xy 380.684621 -278.412992) (xy 380.668733 -278.461891) (xy 380.64539 -278.507703) (xy 380.615169 -278.549299)
			(xy 380.578813 -278.585655) (xy 380.537217 -278.615876) (xy 380.491405 -278.639219) (xy 380.442506 -278.655107)
			(xy 380.391724 -278.66315) (xy 380.340308 -278.66315) (xy 380.289526 -278.655107) (xy 380.240627 -278.639219)
			(xy 380.194815 -278.615876) (xy 380.153219 -278.585655) (xy 380.116863 -278.549299) (xy 380.086642 -278.507703)
			(xy 380.063299 -278.461891) (xy 380.047411 -278.412992) (xy 380.039368 -278.36221) (xy 379.781844 -278.36221)
			(xy 379.781826 -278.363151) (xy 379.773883 -278.415855) (xy 379.758173 -278.466785) (xy 379.735047 -278.514806)
			(xy 379.705023 -278.558843) (xy 379.668771 -278.597914) (xy 379.6271 -278.631145) (xy 379.580942 -278.657794)
			(xy 379.531328 -278.677266) (xy 379.479366 -278.689126) (xy 379.426216 -278.69311) (xy 379.373066 -278.689126)
			(xy 379.321104 -278.677266) (xy 379.27149 -278.657794) (xy 379.225332 -278.631145) (xy 379.183661 -278.597914)
			(xy 379.147409 -278.558843) (xy 379.117385 -278.514806) (xy 379.094259 -278.466785) (xy 379.078549 -278.415855)
			(xy 379.070606 -278.363151) (xy 378.841772 -278.363151) (xy 378.833829 -278.415855) (xy 378.818119 -278.466785)
			(xy 378.794993 -278.514806) (xy 378.764969 -278.558843) (xy 378.728717 -278.597914) (xy 378.687046 -278.631145)
			(xy 378.640888 -278.657794) (xy 378.591274 -278.677266) (xy 378.539312 -278.689126) (xy 378.486162 -278.69311)
			(xy 378.433012 -278.689126) (xy 378.38105 -278.677266) (xy 378.331436 -278.657794) (xy 378.285278 -278.631145)
			(xy 378.243607 -278.597914) (xy 378.207355 -278.558843) (xy 378.177331 -278.514806) (xy 378.154205 -278.466785)
			(xy 378.138495 -278.415855) (xy 378.130552 -278.363151) (xy 377.873115 -278.363151) (xy 377.865221 -278.412992)
			(xy 377.849333 -278.461891) (xy 377.82599 -278.507703) (xy 377.795769 -278.549299) (xy 377.759413 -278.585655)
			(xy 377.717817 -278.615876) (xy 377.672005 -278.639219) (xy 377.623106 -278.655107) (xy 377.572324 -278.66315)
			(xy 377.520908 -278.66315) (xy 377.470126 -278.655107) (xy 377.421227 -278.639219) (xy 377.375415 -278.615876)
			(xy 377.333819 -278.585655) (xy 377.297463 -278.549299) (xy 377.267242 -278.507703) (xy 377.243899 -278.461891)
			(xy 377.228011 -278.412992) (xy 377.219968 -278.36221) (xy 376.93321 -278.36221) (xy 376.925167 -278.412992)
			(xy 376.909279 -278.461891) (xy 376.885936 -278.507703) (xy 376.855715 -278.549299) (xy 376.819359 -278.585655)
			(xy 376.777763 -278.615876) (xy 376.731951 -278.639219) (xy 376.683052 -278.655107) (xy 376.63227 -278.66315)
			(xy 376.580854 -278.66315) (xy 376.530072 -278.655107) (xy 376.481173 -278.639219) (xy 376.435361 -278.615876)
			(xy 376.393765 -278.585655) (xy 376.357409 -278.549299) (xy 376.327188 -278.507703) (xy 376.303845 -278.461891)
			(xy 376.287957 -278.412992) (xy 376.279914 -278.36221) (xy 376.022644 -278.36221) (xy 376.022626 -278.363151)
			(xy 376.014683 -278.415855) (xy 375.998973 -278.466785) (xy 375.975847 -278.514806) (xy 375.945823 -278.558843)
			(xy 375.909571 -278.597914) (xy 375.8679 -278.631145) (xy 375.821742 -278.657794) (xy 375.772128 -278.677266)
			(xy 375.720166 -278.689126) (xy 375.667016 -278.69311) (xy 375.613866 -278.689126) (xy 375.561904 -278.677266)
			(xy 375.51229 -278.657794) (xy 375.466132 -278.631145) (xy 375.424461 -278.597914) (xy 375.388209 -278.558843)
			(xy 375.358185 -278.514806) (xy 375.335059 -278.466785) (xy 375.319349 -278.415855) (xy 375.311406 -278.363151)
			(xy 375.082826 -278.363151) (xy 375.074883 -278.415855) (xy 375.059173 -278.466785) (xy 375.036047 -278.514806)
			(xy 375.006023 -278.558843) (xy 374.969771 -278.597914) (xy 374.9281 -278.631145) (xy 374.881942 -278.657794)
			(xy 374.832328 -278.677266) (xy 374.780366 -278.689126) (xy 374.727216 -278.69311) (xy 374.674066 -278.689126)
			(xy 374.622104 -278.677266) (xy 374.57249 -278.657794) (xy 374.526332 -278.631145) (xy 374.484661 -278.597914)
			(xy 374.448409 -278.558843) (xy 374.418385 -278.514806) (xy 374.395259 -278.466785) (xy 374.379549 -278.415855)
			(xy 374.371606 -278.363151) (xy 374.143026 -278.363151) (xy 374.135083 -278.415855) (xy 374.119373 -278.466785)
			(xy 374.096247 -278.514806) (xy 374.066223 -278.558843) (xy 374.029971 -278.597914) (xy 373.9883 -278.631145)
			(xy 373.942142 -278.657794) (xy 373.892528 -278.677266) (xy 373.840566 -278.689126) (xy 373.787416 -278.69311)
			(xy 373.734266 -278.689126) (xy 373.682304 -278.677266) (xy 373.63269 -278.657794) (xy 373.586532 -278.631145)
			(xy 373.544861 -278.597914) (xy 373.508609 -278.558843) (xy 373.478585 -278.514806) (xy 373.455459 -278.466785)
			(xy 373.439749 -278.415855) (xy 373.431806 -278.363151) (xy 373.203226 -278.363151) (xy 373.195283 -278.415855)
			(xy 373.179573 -278.466785) (xy 373.156447 -278.514806) (xy 373.126423 -278.558843) (xy 373.090171 -278.597914)
			(xy 373.0485 -278.631145) (xy 373.002342 -278.657794) (xy 372.952728 -278.677266) (xy 372.900766 -278.689126)
			(xy 372.847616 -278.69311) (xy 372.794466 -278.689126) (xy 372.742504 -278.677266) (xy 372.69289 -278.657794)
			(xy 372.646732 -278.631145) (xy 372.605061 -278.597914) (xy 372.568809 -278.558843) (xy 372.538785 -278.514806)
			(xy 372.515659 -278.466785) (xy 372.499949 -278.415855) (xy 372.492006 -278.363151) (xy 372.263426 -278.363151)
			(xy 372.255483 -278.415855) (xy 372.239773 -278.466785) (xy 372.216647 -278.514806) (xy 372.186623 -278.558843)
			(xy 372.150371 -278.597914) (xy 372.1087 -278.631145) (xy 372.062542 -278.657794) (xy 372.012928 -278.677266)
			(xy 371.960966 -278.689126) (xy 371.907816 -278.69311) (xy 371.854666 -278.689126) (xy 371.802704 -278.677266)
			(xy 371.75309 -278.657794) (xy 371.706932 -278.631145) (xy 371.665261 -278.597914) (xy 371.629009 -278.558843)
			(xy 371.598985 -278.514806) (xy 371.575859 -278.466785) (xy 371.560149 -278.415855) (xy 371.552206 -278.363151)
			(xy 371.323626 -278.363151) (xy 371.315683 -278.415855) (xy 371.299973 -278.466785) (xy 371.276847 -278.514806)
			(xy 371.246823 -278.558843) (xy 371.210571 -278.597914) (xy 371.1689 -278.631145) (xy 371.122742 -278.657794)
			(xy 371.073128 -278.677266) (xy 371.021166 -278.689126) (xy 370.968016 -278.69311) (xy 370.914866 -278.689126)
			(xy 370.862904 -278.677266) (xy 370.81329 -278.657794) (xy 370.767132 -278.631145) (xy 370.725461 -278.597914)
			(xy 370.689209 -278.558843) (xy 370.659185 -278.514806) (xy 370.636059 -278.466785) (xy 370.620349 -278.415855)
			(xy 370.612406 -278.363151) (xy 370.383572 -278.363151) (xy 370.375629 -278.415855) (xy 370.359919 -278.466785)
			(xy 370.336793 -278.514806) (xy 370.306769 -278.558843) (xy 370.270517 -278.597914) (xy 370.228846 -278.631145)
			(xy 370.182688 -278.657794) (xy 370.133074 -278.677266) (xy 370.081112 -278.689126) (xy 370.027962 -278.69311)
			(xy 369.974812 -278.689126) (xy 369.92285 -278.677266) (xy 369.873236 -278.657794) (xy 369.827078 -278.631145)
			(xy 369.785407 -278.597914) (xy 369.749155 -278.558843) (xy 369.719131 -278.514806) (xy 369.696005 -278.466785)
			(xy 369.680295 -278.415855) (xy 369.672352 -278.363151) (xy 369.443734 -278.363151) (xy 369.435829 -278.415601)
			(xy 369.420119 -278.466531) (xy 369.396993 -278.514552) (xy 369.366969 -278.558589) (xy 369.330717 -278.59766)
			(xy 369.289046 -278.630891) (xy 369.242888 -278.65754) (xy 369.193274 -278.677012) (xy 369.141312 -278.688872)
			(xy 369.088162 -278.692856) (xy 369.035012 -278.688872) (xy 368.98305 -278.677012) (xy 368.933436 -278.65754)
			(xy 368.887278 -278.630891) (xy 368.845607 -278.59766) (xy 368.809355 -278.558589) (xy 368.779331 -278.514552)
			(xy 368.756205 -278.466531) (xy 368.740495 -278.415601) (xy 368.732552 -278.362897) (xy 368.504231 -278.362897)
			(xy 368.504226 -278.363151) (xy 368.496283 -278.415855) (xy 368.480573 -278.466785) (xy 368.457447 -278.514806)
			(xy 368.427423 -278.558843) (xy 368.391171 -278.597914) (xy 368.3495 -278.631145) (xy 368.303342 -278.657794)
			(xy 368.253728 -278.677266) (xy 368.201766 -278.689126) (xy 368.148616 -278.69311) (xy 368.095466 -278.689126)
			(xy 368.043504 -278.677266) (xy 367.99389 -278.657794) (xy 367.947732 -278.631145) (xy 367.906061 -278.597914)
			(xy 367.869809 -278.558843) (xy 367.839785 -278.514806) (xy 367.816659 -278.466785) (xy 367.800949 -278.415855)
			(xy 367.793006 -278.363151) (xy 367.564426 -278.363151) (xy 367.556483 -278.415855) (xy 367.540773 -278.466785)
			(xy 367.517647 -278.514806) (xy 367.487623 -278.558843) (xy 367.451371 -278.597914) (xy 367.4097 -278.631145)
			(xy 367.363542 -278.657794) (xy 367.313928 -278.677266) (xy 367.261966 -278.689126) (xy 367.208816 -278.69311)
			(xy 367.155666 -278.689126) (xy 367.103704 -278.677266) (xy 367.05409 -278.657794) (xy 367.007932 -278.631145)
			(xy 366.966261 -278.597914) (xy 366.930009 -278.558843) (xy 366.899985 -278.514806) (xy 366.876859 -278.466785)
			(xy 366.861149 -278.415855) (xy 366.853206 -278.363151) (xy 366.624334 -278.363151) (xy 366.616429 -278.415601)
			(xy 366.600719 -278.466531) (xy 366.577593 -278.514552) (xy 366.547569 -278.558589) (xy 366.511317 -278.59766)
			(xy 366.469646 -278.630891) (xy 366.423488 -278.65754) (xy 366.373874 -278.677012) (xy 366.321912 -278.688872)
			(xy 366.268762 -278.692856) (xy 366.215612 -278.688872) (xy 366.16365 -278.677012) (xy 366.114036 -278.65754)
			(xy 366.067878 -278.630891) (xy 366.026207 -278.59766) (xy 365.989955 -278.558589) (xy 365.959931 -278.514552)
			(xy 365.936805 -278.466531) (xy 365.921095 -278.415601) (xy 365.913152 -278.362897) (xy 365.684572 -278.362897)
			(xy 365.676629 -278.415601) (xy 365.660919 -278.466531) (xy 365.637793 -278.514552) (xy 365.607769 -278.558589)
			(xy 365.571517 -278.59766) (xy 365.529846 -278.630891) (xy 365.483688 -278.65754) (xy 365.434074 -278.677012)
			(xy 365.382112 -278.688872) (xy 365.328962 -278.692856) (xy 365.275812 -278.688872) (xy 365.22385 -278.677012)
			(xy 365.174236 -278.65754) (xy 365.128078 -278.630891) (xy 365.086407 -278.59766) (xy 365.050155 -278.558589)
			(xy 365.020131 -278.514552) (xy 364.997005 -278.466531) (xy 364.981295 -278.415601) (xy 364.973352 -278.362897)
			(xy 364.744772 -278.362897) (xy 364.736829 -278.415601) (xy 364.721119 -278.466531) (xy 364.697993 -278.514552)
			(xy 364.667969 -278.558589) (xy 364.631717 -278.59766) (xy 364.590046 -278.630891) (xy 364.543888 -278.65754)
			(xy 364.494274 -278.677012) (xy 364.442312 -278.688872) (xy 364.389162 -278.692856) (xy 364.336012 -278.688872)
			(xy 364.28405 -278.677012) (xy 364.234436 -278.65754) (xy 364.188278 -278.630891) (xy 364.146607 -278.59766)
			(xy 364.110355 -278.558589) (xy 364.080331 -278.514552) (xy 364.057205 -278.466531) (xy 364.041495 -278.415601)
			(xy 364.033552 -278.362897) (xy 363.804972 -278.362897) (xy 363.797029 -278.415601) (xy 363.781319 -278.466531)
			(xy 363.758193 -278.514552) (xy 363.728169 -278.558589) (xy 363.691917 -278.59766) (xy 363.650246 -278.630891)
			(xy 363.604088 -278.65754) (xy 363.554474 -278.677012) (xy 363.502512 -278.688872) (xy 363.449362 -278.692856)
			(xy 363.396212 -278.688872) (xy 363.34425 -278.677012) (xy 363.294636 -278.65754) (xy 363.248478 -278.630891)
			(xy 363.206807 -278.59766) (xy 363.170555 -278.558589) (xy 363.140531 -278.514552) (xy 363.117405 -278.466531)
			(xy 363.101695 -278.415601) (xy 363.093752 -278.362897) (xy 362.865172 -278.362897) (xy 362.857229 -278.415601)
			(xy 362.841519 -278.466531) (xy 362.818393 -278.514552) (xy 362.788369 -278.558589) (xy 362.752117 -278.59766)
			(xy 362.710446 -278.630891) (xy 362.664288 -278.65754) (xy 362.614674 -278.677012) (xy 362.562712 -278.688872)
			(xy 362.509562 -278.692856) (xy 362.456412 -278.688872) (xy 362.40445 -278.677012) (xy 362.354836 -278.65754)
			(xy 362.308678 -278.630891) (xy 362.267007 -278.59766) (xy 362.230755 -278.558589) (xy 362.200731 -278.514552)
			(xy 362.177605 -278.466531) (xy 362.161895 -278.415601) (xy 362.153952 -278.362897) (xy 358.166177 -278.362897)
			(xy 358.166172 -278.363151) (xy 358.158229 -278.415855) (xy 358.142519 -278.466785) (xy 358.119393 -278.514806)
			(xy 358.089369 -278.558843) (xy 358.053117 -278.597914) (xy 358.011446 -278.631145) (xy 357.965288 -278.657794)
			(xy 357.915674 -278.677266) (xy 357.863712 -278.689126) (xy 357.810562 -278.69311) (xy 357.757412 -278.689126)
			(xy 357.70545 -278.677266) (xy 357.655836 -278.657794) (xy 357.609678 -278.631145) (xy 357.568007 -278.597914)
			(xy 357.531755 -278.558843) (xy 357.501731 -278.514806) (xy 357.478605 -278.466785) (xy 357.462895 -278.415855)
			(xy 357.454952 -278.363151) (xy 357.226372 -278.363151) (xy 357.218429 -278.415855) (xy 357.202719 -278.466785)
			(xy 357.179593 -278.514806) (xy 357.149569 -278.558843) (xy 357.113317 -278.597914) (xy 357.071646 -278.631145)
			(xy 357.025488 -278.657794) (xy 356.975874 -278.677266) (xy 356.923912 -278.689126) (xy 356.870762 -278.69311)
			(xy 356.817612 -278.689126) (xy 356.76565 -278.677266) (xy 356.716036 -278.657794) (xy 356.669878 -278.631145)
			(xy 356.628207 -278.597914) (xy 356.591955 -278.558843) (xy 356.561931 -278.514806) (xy 356.538805 -278.466785)
			(xy 356.523095 -278.415855) (xy 356.515152 -278.363151) (xy 356.260282 -278.363151) (xy 356.252294 -278.413586)
			(xy 356.236282 -278.462865) (xy 356.212759 -278.509032) (xy 356.182303 -278.550951) (xy 356.145665 -278.587589)
			(xy 356.103746 -278.618045) (xy 356.057579 -278.641568) (xy 356.0083 -278.65758) (xy 355.957123 -278.665686)
			(xy 355.905309 -278.665686) (xy 355.854132 -278.65758) (xy 355.804853 -278.641568) (xy 355.758686 -278.618045)
			(xy 355.716767 -278.587589) (xy 355.680129 -278.550951) (xy 355.649673 -278.509032) (xy 355.62615 -278.462865)
			(xy 355.610138 -278.413586) (xy 355.602032 -278.362409) (xy 355.601524 -278.336502) (xy 355.602117 -278.308785)
			(xy 355.611441 -278.254138) (xy 355.620066 -278.22779) (xy 355.62794 -278.205692) (xy 355.422962 -277.8506)
			(xy 355.399848 -277.846282) (xy 355.375022 -277.841137) (xy 355.327241 -277.824181) (xy 355.282621 -277.800107)
			(xy 355.242213 -277.769484) (xy 355.206972 -277.733035) (xy 355.177729 -277.691618) (xy 355.155174 -277.646211)
			(xy 355.139838 -277.597886) (xy 355.132084 -277.547782) (xy 355.131624 -277.522432) (xy 354.8507 -277.522432)
			(xy 354.850192 -277.548319) (xy 354.842093 -277.599457) (xy 354.826094 -277.648697) (xy 354.802588 -277.694829)
			(xy 354.772156 -277.736716) (xy 354.735546 -277.773326) (xy 354.693659 -277.803758) (xy 354.647527 -277.827264)
			(xy 354.598287 -277.843263) (xy 354.547149 -277.851362) (xy 354.495375 -277.851362) (xy 354.444237 -277.843263)
			(xy 354.394997 -277.827264) (xy 354.348865 -277.803758) (xy 354.306978 -277.773326) (xy 354.270368 -277.736716)
			(xy 354.239936 -277.694829) (xy 354.21643 -277.648697) (xy 354.200431 -277.599457) (xy 354.192332 -277.548319)
			(xy 354.191824 -277.522432) (xy 353.93757 -277.522432) (xy 353.937072 -277.549081) (xy 353.929129 -277.601785)
			(xy 353.913419 -277.652715) (xy 353.890293 -277.700736) (xy 353.860269 -277.744773) (xy 353.824017 -277.783844)
			(xy 353.782346 -277.817075) (xy 353.736188 -277.843724) (xy 353.686574 -277.863196) (xy 353.634612 -277.875056)
			(xy 353.581462 -277.87904) (xy 353.528312 -277.875056) (xy 353.47635 -277.863196) (xy 353.426736 -277.843724)
			(xy 353.380578 -277.817075) (xy 353.338907 -277.783844) (xy 353.302655 -277.744773) (xy 353.272631 -277.700736)
			(xy 353.249505 -277.652715) (xy 353.233795 -277.601785) (xy 353.225852 -277.549081) (xy 353.024694 -277.549081)
			(xy 353.024694 -277.879048) (xy 353.025274 -277.894714) (xy 353.034767 -277.924573) (xy 353.052849 -277.95016)
			(xy 353.077825 -277.969077) (xy 353.107354 -277.979552) (xy 353.122992 -277.980648) (xy 353.149066 -277.981941)
			(xy 353.20044 -277.991212) (xy 353.249909 -278.007887) (xy 353.296413 -278.031606) (xy 353.338955 -278.061863)
			(xy 353.376623 -278.098007) (xy 353.408608 -278.139264) (xy 353.434226 -278.18475) (xy 353.452928 -278.233489)
			(xy 353.464311 -278.284436) (xy 353.468133 -278.3365) (xy 353.466177 -278.363151) (xy 353.696006 -278.363151)
			(xy 353.696006 -278.309853) (xy 353.703949 -278.257149) (xy 353.719659 -278.206219) (xy 353.742785 -278.158198)
			(xy 353.772809 -278.114161) (xy 353.809061 -278.07509) (xy 353.850732 -278.041859) (xy 353.89689 -278.01521)
			(xy 353.946504 -277.995738) (xy 353.998466 -277.983878) (xy 354.051616 -277.979895) (xy 354.104766 -277.983878)
			(xy 354.156728 -277.995738) (xy 354.206342 -278.01521) (xy 354.2525 -278.041859) (xy 354.294171 -278.07509)
			(xy 354.330423 -278.114161) (xy 354.360447 -278.158198) (xy 354.383573 -278.206219) (xy 354.399283 -278.257149)
			(xy 354.407226 -278.309853) (xy 354.407724 -278.336502) (xy 354.407226 -278.363151) (xy 354.635806 -278.363151)
			(xy 354.635806 -278.309853) (xy 354.643749 -278.257149) (xy 354.659459 -278.206219) (xy 354.682585 -278.158198)
			(xy 354.712609 -278.114161) (xy 354.748861 -278.07509) (xy 354.790532 -278.041859) (xy 354.83669 -278.01521)
			(xy 354.886304 -277.995738) (xy 354.938266 -277.983878) (xy 354.991416 -277.979895) (xy 355.044566 -277.983878)
			(xy 355.096528 -277.995738) (xy 355.146142 -278.01521) (xy 355.1923 -278.041859) (xy 355.233971 -278.07509)
			(xy 355.270223 -278.114161) (xy 355.300247 -278.158198) (xy 355.323373 -278.206219) (xy 355.339083 -278.257149)
			(xy 355.347026 -278.309853) (xy 355.347524 -278.336502) (xy 355.347026 -278.363151) (xy 355.339083 -278.415855)
			(xy 355.323373 -278.466785) (xy 355.300247 -278.514806) (xy 355.270223 -278.558843) (xy 355.233971 -278.597914)
			(xy 355.1923 -278.631145) (xy 355.146142 -278.657794) (xy 355.096528 -278.677266) (xy 355.044566 -278.689126)
			(xy 354.991416 -278.69311) (xy 354.938266 -278.689126) (xy 354.886304 -278.677266) (xy 354.83669 -278.657794)
			(xy 354.790532 -278.631145) (xy 354.748861 -278.597914) (xy 354.712609 -278.558843) (xy 354.682585 -278.514806)
			(xy 354.659459 -278.466785) (xy 354.643749 -278.415855) (xy 354.635806 -278.363151) (xy 354.407226 -278.363151)
			(xy 354.399283 -278.415855) (xy 354.383573 -278.466785) (xy 354.360447 -278.514806) (xy 354.330423 -278.558843)
			(xy 354.294171 -278.597914) (xy 354.2525 -278.631145) (xy 354.206342 -278.657794) (xy 354.156728 -278.677266)
			(xy 354.104766 -278.689126) (xy 354.051616 -278.69311) (xy 353.998466 -278.689126) (xy 353.946504 -278.677266)
			(xy 353.89689 -278.657794) (xy 353.850732 -278.631145) (xy 353.809061 -278.597914) (xy 353.772809 -278.558843)
			(xy 353.742785 -278.514806) (xy 353.719659 -278.466785) (xy 353.703949 -278.415855) (xy 353.696006 -278.363151)
			(xy 353.466177 -278.363151) (xy 353.464311 -278.388564) (xy 353.452928 -278.439511) (xy 353.434226 -278.488251)
			(xy 353.408608 -278.533736) (xy 353.376622 -278.574993) (xy 353.338955 -278.611138) (xy 353.296413 -278.641394)
			(xy 353.249909 -278.665113) (xy 353.20044 -278.681788) (xy 353.149066 -278.691059) (xy 353.122992 -278.692356)
			(xy 353.10735 -278.693441) (xy 353.077809 -278.703901) (xy 353.052825 -278.722819) (xy 353.034745 -278.748416)
			(xy 353.025268 -278.778287) (xy 353.024694 -278.793956) (xy 353.024694 -279.176967) (xy 353.226106 -279.176967)
			(xy 353.226106 -279.123669) (xy 353.234049 -279.070965) (xy 353.249759 -279.020035) (xy 353.272885 -278.972014)
			(xy 353.302909 -278.927977) (xy 353.339161 -278.888906) (xy 353.380832 -278.855675) (xy 353.42699 -278.829026)
			(xy 353.476604 -278.809554) (xy 353.528566 -278.797694) (xy 353.581716 -278.793711) (xy 353.634866 -278.797694)
			(xy 353.686828 -278.809554) (xy 353.736442 -278.829026) (xy 353.7826 -278.855675) (xy 353.824271 -278.888906)
			(xy 353.860523 -278.927977) (xy 353.890547 -278.972014) (xy 353.913673 -279.020035) (xy 353.929383 -279.070965)
			(xy 353.937326 -279.123669) (xy 353.937824 -279.150318) (xy 353.937326 -279.176967) (xy 354.165906 -279.176967)
			(xy 354.165906 -279.123669) (xy 354.173849 -279.070965) (xy 354.189559 -279.020035) (xy 354.212685 -278.972014)
			(xy 354.242709 -278.927977) (xy 354.278961 -278.888906) (xy 354.320632 -278.855675) (xy 354.36679 -278.829026)
			(xy 354.416404 -278.809554) (xy 354.468366 -278.797694) (xy 354.521516 -278.793711) (xy 354.574666 -278.797694)
			(xy 354.626628 -278.809554) (xy 354.676242 -278.829026) (xy 354.7224 -278.855675) (xy 354.764071 -278.888906)
			(xy 354.800323 -278.927977) (xy 354.830347 -278.972014) (xy 354.853473 -279.020035) (xy 354.869183 -279.070965)
			(xy 354.877126 -279.123669) (xy 354.877624 -279.150318) (xy 354.877126 -279.176967) (xy 355.105452 -279.176967)
			(xy 355.105452 -279.123669) (xy 355.113395 -279.070965) (xy 355.129105 -279.020035) (xy 355.152231 -278.972014)
			(xy 355.182255 -278.927977) (xy 355.218507 -278.888906) (xy 355.260178 -278.855675) (xy 355.306336 -278.829026)
			(xy 355.35595 -278.809554) (xy 355.407912 -278.797694) (xy 355.461062 -278.793711) (xy 355.514212 -278.797694)
			(xy 355.566174 -278.809554) (xy 355.615788 -278.829026) (xy 355.661946 -278.855675) (xy 355.703617 -278.888906)
			(xy 355.739869 -278.927977) (xy 355.769893 -278.972014) (xy 355.793019 -279.020035) (xy 355.808729 -279.070965)
			(xy 355.816672 -279.123669) (xy 355.81717 -279.150318) (xy 355.816672 -279.176967) (xy 356.045252 -279.176967)
			(xy 356.045252 -279.123669) (xy 356.053195 -279.070965) (xy 356.068905 -279.020035) (xy 356.092031 -278.972014)
			(xy 356.122055 -278.927977) (xy 356.158307 -278.888906) (xy 356.199978 -278.855675) (xy 356.246136 -278.829026)
			(xy 356.29575 -278.809554) (xy 356.347712 -278.797694) (xy 356.400862 -278.793711) (xy 356.454012 -278.797694)
			(xy 356.505974 -278.809554) (xy 356.555588 -278.829026) (xy 356.601746 -278.855675) (xy 356.643417 -278.888906)
			(xy 356.679669 -278.927977) (xy 356.709693 -278.972014) (xy 356.732819 -279.020035) (xy 356.748529 -279.070965)
			(xy 356.756472 -279.123669) (xy 356.75697 -279.150318) (xy 356.756472 -279.176967) (xy 362.623852 -279.176967)
			(xy 362.623852 -279.123669) (xy 362.631795 -279.070965) (xy 362.647505 -279.020035) (xy 362.670631 -278.972014)
			(xy 362.700655 -278.927977) (xy 362.736907 -278.888906) (xy 362.778578 -278.855675) (xy 362.824736 -278.829026)
			(xy 362.87435 -278.809554) (xy 362.926312 -278.797694) (xy 362.979462 -278.793711) (xy 363.032612 -278.797694)
			(xy 363.084574 -278.809554) (xy 363.134188 -278.829026) (xy 363.180346 -278.855675) (xy 363.222017 -278.888906)
			(xy 363.258269 -278.927977) (xy 363.288293 -278.972014) (xy 363.311419 -279.020035) (xy 363.327129 -279.070965)
			(xy 363.335072 -279.123669) (xy 363.33557 -279.150318) (xy 363.335072 -279.176967) (xy 363.563652 -279.176967)
			(xy 363.563652 -279.123669) (xy 363.571595 -279.070965) (xy 363.587305 -279.020035) (xy 363.610431 -278.972014)
			(xy 363.640455 -278.927977) (xy 363.676707 -278.888906) (xy 363.718378 -278.855675) (xy 363.764536 -278.829026)
			(xy 363.81415 -278.809554) (xy 363.866112 -278.797694) (xy 363.919262 -278.793711) (xy 363.972412 -278.797694)
			(xy 364.024374 -278.809554) (xy 364.073988 -278.829026) (xy 364.120146 -278.855675) (xy 364.161817 -278.888906)
			(xy 364.198069 -278.927977) (xy 364.228093 -278.972014) (xy 364.251219 -279.020035) (xy 364.266929 -279.070965)
			(xy 364.274872 -279.123669) (xy 364.27537 -279.150318) (xy 364.274877 -279.176713) (xy 364.503706 -279.176713)
			(xy 364.503706 -279.123415) (xy 364.511649 -279.070711) (xy 364.527359 -279.019781) (xy 364.550485 -278.97176)
			(xy 364.580509 -278.927723) (xy 364.616761 -278.888652) (xy 364.658432 -278.855421) (xy 364.70459 -278.828772)
			(xy 364.754204 -278.8093) (xy 364.806166 -278.79744) (xy 364.859316 -278.793457) (xy 364.912466 -278.79744)
			(xy 364.964428 -278.8093) (xy 365.014042 -278.828772) (xy 365.0602 -278.855421) (xy 365.101871 -278.888652)
			(xy 365.138123 -278.927723) (xy 365.168147 -278.97176) (xy 365.191273 -279.019781) (xy 365.206983 -279.070711)
			(xy 365.214926 -279.123415) (xy 365.215424 -279.150064) (xy 365.214926 -279.176713) (xy 365.214888 -279.176967)
			(xy 365.443506 -279.176967) (xy 365.443506 -279.123669) (xy 365.451449 -279.070965) (xy 365.467159 -279.020035)
			(xy 365.490285 -278.972014) (xy 365.520309 -278.927977) (xy 365.556561 -278.888906) (xy 365.598232 -278.855675)
			(xy 365.64439 -278.829026) (xy 365.694004 -278.809554) (xy 365.745966 -278.797694) (xy 365.799116 -278.793711)
			(xy 365.852266 -278.797694) (xy 365.904228 -278.809554) (xy 365.953842 -278.829026) (xy 366 -278.855675)
			(xy 366.041671 -278.888906) (xy 366.077923 -278.927977) (xy 366.107947 -278.972014) (xy 366.131073 -279.020035)
			(xy 366.146783 -279.070965) (xy 366.154726 -279.123669) (xy 366.155224 -279.150318) (xy 366.154726 -279.176967)
			(xy 366.383052 -279.176967) (xy 366.383052 -279.123669) (xy 366.390995 -279.070965) (xy 366.406705 -279.020035)
			(xy 366.429831 -278.972014) (xy 366.459855 -278.927977) (xy 366.496107 -278.888906) (xy 366.537778 -278.855675)
			(xy 366.583936 -278.829026) (xy 366.63355 -278.809554) (xy 366.685512 -278.797694) (xy 366.738662 -278.793711)
			(xy 366.791812 -278.797694) (xy 366.843774 -278.809554) (xy 366.893388 -278.829026) (xy 366.939546 -278.855675)
			(xy 366.981217 -278.888906) (xy 367.017469 -278.927977) (xy 367.047493 -278.972014) (xy 367.070619 -279.020035)
			(xy 367.086329 -279.070965) (xy 367.094272 -279.123669) (xy 367.09477 -279.150318) (xy 367.094272 -279.176967)
			(xy 367.322852 -279.176967) (xy 367.322852 -279.123669) (xy 367.330795 -279.070965) (xy 367.346505 -279.020035)
			(xy 367.369631 -278.972014) (xy 367.399655 -278.927977) (xy 367.435907 -278.888906) (xy 367.477578 -278.855675)
			(xy 367.523736 -278.829026) (xy 367.57335 -278.809554) (xy 367.625312 -278.797694) (xy 367.678462 -278.793711)
			(xy 367.731612 -278.797694) (xy 367.783574 -278.809554) (xy 367.833188 -278.829026) (xy 367.879346 -278.855675)
			(xy 367.921017 -278.888906) (xy 367.957269 -278.927977) (xy 367.987293 -278.972014) (xy 368.010419 -279.020035)
			(xy 368.026129 -279.070965) (xy 368.034072 -279.123669) (xy 368.03457 -279.150318) (xy 368.034072 -279.176967)
			(xy 368.262906 -279.176967) (xy 368.262906 -279.123669) (xy 368.270849 -279.070965) (xy 368.286559 -279.020035)
			(xy 368.309685 -278.972014) (xy 368.339709 -278.927977) (xy 368.375961 -278.888906) (xy 368.417632 -278.855675)
			(xy 368.46379 -278.829026) (xy 368.513404 -278.809554) (xy 368.565366 -278.797694) (xy 368.618516 -278.793711)
			(xy 368.671666 -278.797694) (xy 368.723628 -278.809554) (xy 368.773242 -278.829026) (xy 368.8194 -278.855675)
			(xy 368.861071 -278.888906) (xy 368.897323 -278.927977) (xy 368.927347 -278.972014) (xy 368.950473 -279.020035)
			(xy 368.966183 -279.070965) (xy 368.974126 -279.123669) (xy 368.974624 -279.150318) (xy 368.974126 -279.176967)
			(xy 369.202452 -279.176967) (xy 369.202452 -279.123669) (xy 369.210395 -279.070965) (xy 369.226105 -279.020035)
			(xy 369.249231 -278.972014) (xy 369.279255 -278.927977) (xy 369.315507 -278.888906) (xy 369.357178 -278.855675)
			(xy 369.403336 -278.829026) (xy 369.45295 -278.809554) (xy 369.504912 -278.797694) (xy 369.558062 -278.793711)
			(xy 369.611212 -278.797694) (xy 369.663174 -278.809554) (xy 369.712788 -278.829026) (xy 369.758946 -278.855675)
			(xy 369.800617 -278.888906) (xy 369.836869 -278.927977) (xy 369.866893 -278.972014) (xy 369.890019 -279.020035)
			(xy 369.905729 -279.070965) (xy 369.913672 -279.123669) (xy 369.91417 -279.150318) (xy 369.913672 -279.176967)
			(xy 370.142252 -279.176967) (xy 370.142252 -279.123669) (xy 370.150195 -279.070965) (xy 370.165905 -279.020035)
			(xy 370.189031 -278.972014) (xy 370.219055 -278.927977) (xy 370.255307 -278.888906) (xy 370.296978 -278.855675)
			(xy 370.343136 -278.829026) (xy 370.39275 -278.809554) (xy 370.444712 -278.797694) (xy 370.497862 -278.793711)
			(xy 370.551012 -278.797694) (xy 370.602974 -278.809554) (xy 370.652588 -278.829026) (xy 370.698746 -278.855675)
			(xy 370.740417 -278.888906) (xy 370.776669 -278.927977) (xy 370.806693 -278.972014) (xy 370.829819 -279.020035)
			(xy 370.845529 -279.070965) (xy 370.853472 -279.123669) (xy 370.85397 -279.150318) (xy 370.853472 -279.176967)
			(xy 371.082306 -279.176967) (xy 371.082306 -279.123669) (xy 371.090249 -279.070965) (xy 371.105959 -279.020035)
			(xy 371.129085 -278.972014) (xy 371.159109 -278.927977) (xy 371.195361 -278.888906) (xy 371.237032 -278.855675)
			(xy 371.28319 -278.829026) (xy 371.332804 -278.809554) (xy 371.384766 -278.797694) (xy 371.437916 -278.793711)
			(xy 371.491066 -278.797694) (xy 371.543028 -278.809554) (xy 371.592642 -278.829026) (xy 371.6388 -278.855675)
			(xy 371.680471 -278.888906) (xy 371.716723 -278.927977) (xy 371.746747 -278.972014) (xy 371.769873 -279.020035)
			(xy 371.785583 -279.070965) (xy 371.793526 -279.123669) (xy 371.794024 -279.150318) (xy 371.793526 -279.176967)
			(xy 372.021852 -279.176967) (xy 372.021852 -279.123669) (xy 372.029795 -279.070965) (xy 372.045505 -279.020035)
			(xy 372.068631 -278.972014) (xy 372.098655 -278.927977) (xy 372.134907 -278.888906) (xy 372.176578 -278.855675)
			(xy 372.222736 -278.829026) (xy 372.27235 -278.809554) (xy 372.324312 -278.797694) (xy 372.377462 -278.793711)
			(xy 372.430612 -278.797694) (xy 372.482574 -278.809554) (xy 372.532188 -278.829026) (xy 372.578346 -278.855675)
			(xy 372.620017 -278.888906) (xy 372.656269 -278.927977) (xy 372.686293 -278.972014) (xy 372.709419 -279.020035)
			(xy 372.725129 -279.070965) (xy 372.733072 -279.123669) (xy 372.73357 -279.150318) (xy 372.733072 -279.176967)
			(xy 372.961652 -279.176967) (xy 372.961652 -279.123669) (xy 372.969595 -279.070965) (xy 372.985305 -279.020035)
			(xy 373.008431 -278.972014) (xy 373.038455 -278.927977) (xy 373.074707 -278.888906) (xy 373.116378 -278.855675)
			(xy 373.162536 -278.829026) (xy 373.21215 -278.809554) (xy 373.264112 -278.797694) (xy 373.317262 -278.793711)
			(xy 373.370412 -278.797694) (xy 373.422374 -278.809554) (xy 373.471988 -278.829026) (xy 373.518146 -278.855675)
			(xy 373.559817 -278.888906) (xy 373.596069 -278.927977) (xy 373.626093 -278.972014) (xy 373.649219 -279.020035)
			(xy 373.664929 -279.070965) (xy 373.672872 -279.123669) (xy 373.67337 -279.150318) (xy 373.672872 -279.176967)
			(xy 373.901452 -279.176967) (xy 373.901452 -279.123669) (xy 373.909395 -279.070965) (xy 373.925105 -279.020035)
			(xy 373.948231 -278.972014) (xy 373.978255 -278.927977) (xy 374.014507 -278.888906) (xy 374.056178 -278.855675)
			(xy 374.102336 -278.829026) (xy 374.15195 -278.809554) (xy 374.203912 -278.797694) (xy 374.257062 -278.793711)
			(xy 374.310212 -278.797694) (xy 374.362174 -278.809554) (xy 374.411788 -278.829026) (xy 374.457946 -278.855675)
			(xy 374.499617 -278.888906) (xy 374.535869 -278.927977) (xy 374.565893 -278.972014) (xy 374.589019 -279.020035)
			(xy 374.604729 -279.070965) (xy 374.612672 -279.123669) (xy 374.61317 -279.150318) (xy 374.612672 -279.176967)
			(xy 374.841252 -279.176967) (xy 374.841252 -279.123669) (xy 374.849195 -279.070965) (xy 374.864905 -279.020035)
			(xy 374.888031 -278.972014) (xy 374.918055 -278.927977) (xy 374.954307 -278.888906) (xy 374.995978 -278.855675)
			(xy 375.042136 -278.829026) (xy 375.09175 -278.809554) (xy 375.143712 -278.797694) (xy 375.196862 -278.793711)
			(xy 375.250012 -278.797694) (xy 375.301974 -278.809554) (xy 375.351588 -278.829026) (xy 375.397746 -278.855675)
			(xy 375.439417 -278.888906) (xy 375.475669 -278.927977) (xy 375.505693 -278.972014) (xy 375.528819 -279.020035)
			(xy 375.544529 -279.070965) (xy 375.552472 -279.123669) (xy 375.55297 -279.150318) (xy 375.552472 -279.176967)
			(xy 375.781052 -279.176967) (xy 375.781052 -279.123669) (xy 375.788995 -279.070965) (xy 375.804705 -279.020035)
			(xy 375.827831 -278.972014) (xy 375.857855 -278.927977) (xy 375.894107 -278.888906) (xy 375.935778 -278.855675)
			(xy 375.981936 -278.829026) (xy 376.03155 -278.809554) (xy 376.083512 -278.797694) (xy 376.136662 -278.793711)
			(xy 376.189812 -278.797694) (xy 376.241774 -278.809554) (xy 376.291388 -278.829026) (xy 376.337546 -278.855675)
			(xy 376.379217 -278.888906) (xy 376.415469 -278.927977) (xy 376.445493 -278.972014) (xy 376.468619 -279.020035)
			(xy 376.484329 -279.070965) (xy 376.492272 -279.123669) (xy 376.49277 -279.150318) (xy 376.492272 -279.176967)
			(xy 376.720852 -279.176967) (xy 376.720852 -279.123669) (xy 376.728795 -279.070965) (xy 376.744505 -279.020035)
			(xy 376.767631 -278.972014) (xy 376.797655 -278.927977) (xy 376.833907 -278.888906) (xy 376.875578 -278.855675)
			(xy 376.921736 -278.829026) (xy 376.97135 -278.809554) (xy 377.023312 -278.797694) (xy 377.076462 -278.793711)
			(xy 377.129612 -278.797694) (xy 377.181574 -278.809554) (xy 377.231188 -278.829026) (xy 377.277346 -278.855675)
			(xy 377.319017 -278.888906) (xy 377.355269 -278.927977) (xy 377.385293 -278.972014) (xy 377.408419 -279.020035)
			(xy 377.424129 -279.070965) (xy 377.432072 -279.123669) (xy 377.43257 -279.150318) (xy 377.432072 -279.176967)
			(xy 377.660906 -279.176967) (xy 377.660906 -279.123669) (xy 377.668849 -279.070965) (xy 377.684559 -279.020035)
			(xy 377.707685 -278.972014) (xy 377.737709 -278.927977) (xy 377.773961 -278.888906) (xy 377.815632 -278.855675)
			(xy 377.86179 -278.829026) (xy 377.911404 -278.809554) (xy 377.963366 -278.797694) (xy 378.016516 -278.793711)
			(xy 378.069666 -278.797694) (xy 378.121628 -278.809554) (xy 378.171242 -278.829026) (xy 378.2174 -278.855675)
			(xy 378.259071 -278.888906) (xy 378.295323 -278.927977) (xy 378.325347 -278.972014) (xy 378.348473 -279.020035)
			(xy 378.364183 -279.070965) (xy 378.372126 -279.123669) (xy 378.372624 -279.150318) (xy 378.372144 -279.176026)
			(xy 378.629414 -279.176026) (xy 378.629414 -279.12461) (xy 378.637457 -279.073828) (xy 378.653345 -279.024929)
			(xy 378.676688 -278.979117) (xy 378.706909 -278.937521) (xy 378.743265 -278.901165) (xy 378.784861 -278.870944)
			(xy 378.830673 -278.847601) (xy 378.879572 -278.831713) (xy 378.930354 -278.82367) (xy 378.98177 -278.82367)
			(xy 379.032552 -278.831713) (xy 379.081451 -278.847601) (xy 379.127263 -278.870944) (xy 379.168859 -278.901165)
			(xy 379.205215 -278.937521) (xy 379.235436 -278.979117) (xy 379.258779 -279.024929) (xy 379.274667 -279.073828)
			(xy 379.28271 -279.12461) (xy 379.283214 -279.150318) (xy 379.28271 -279.176026) (xy 379.282561 -279.176967)
			(xy 379.540506 -279.176967) (xy 379.540506 -279.123669) (xy 379.548449 -279.070965) (xy 379.564159 -279.020035)
			(xy 379.587285 -278.972014) (xy 379.617309 -278.927977) (xy 379.653561 -278.888906) (xy 379.695232 -278.855675)
			(xy 379.74139 -278.829026) (xy 379.791004 -278.809554) (xy 379.842966 -278.797694) (xy 379.896116 -278.793711)
			(xy 379.949266 -278.797694) (xy 380.001228 -278.809554) (xy 380.050842 -278.829026) (xy 380.097 -278.855675)
			(xy 380.138671 -278.888906) (xy 380.174923 -278.927977) (xy 380.204947 -278.972014) (xy 380.228073 -279.020035)
			(xy 380.243783 -279.070965) (xy 380.251726 -279.123669) (xy 380.252224 -279.150318) (xy 380.251726 -279.176967)
			(xy 380.480306 -279.176967) (xy 380.480306 -279.123669) (xy 380.488249 -279.070965) (xy 380.503959 -279.020035)
			(xy 380.527085 -278.972014) (xy 380.557109 -278.927977) (xy 380.593361 -278.888906) (xy 380.635032 -278.855675)
			(xy 380.68119 -278.829026) (xy 380.730804 -278.809554) (xy 380.782766 -278.797694) (xy 380.835916 -278.793711)
			(xy 380.889066 -278.797694) (xy 380.941028 -278.809554) (xy 380.990642 -278.829026) (xy 381.0368 -278.855675)
			(xy 381.078471 -278.888906) (xy 381.114723 -278.927977) (xy 381.144747 -278.972014) (xy 381.167873 -279.020035)
			(xy 381.183583 -279.070965) (xy 381.191526 -279.123669) (xy 381.192024 -279.150318) (xy 381.191526 -279.176967)
			(xy 381.419852 -279.176967) (xy 381.419852 -279.123669) (xy 381.427795 -279.070965) (xy 381.443505 -279.020035)
			(xy 381.466631 -278.972014) (xy 381.496655 -278.927977) (xy 381.532907 -278.888906) (xy 381.574578 -278.855675)
			(xy 381.620736 -278.829026) (xy 381.67035 -278.809554) (xy 381.722312 -278.797694) (xy 381.775462 -278.793711)
			(xy 381.828612 -278.797694) (xy 381.880574 -278.809554) (xy 381.930188 -278.829026) (xy 381.976346 -278.855675)
			(xy 382.018017 -278.888906) (xy 382.054269 -278.927977) (xy 382.084293 -278.972014) (xy 382.107419 -279.020035)
			(xy 382.123129 -279.070965) (xy 382.131072 -279.123669) (xy 382.13157 -279.150318) (xy 382.13109 -279.176026)
			(xy 382.388614 -279.176026) (xy 382.388614 -279.12461) (xy 382.396657 -279.073828) (xy 382.412545 -279.024929)
			(xy 382.435888 -278.979117) (xy 382.466109 -278.937521) (xy 382.502465 -278.901165) (xy 382.544061 -278.870944)
			(xy 382.589873 -278.847601) (xy 382.638772 -278.831713) (xy 382.689554 -278.82367) (xy 382.74097 -278.82367)
			(xy 382.791752 -278.831713) (xy 382.840651 -278.847601) (xy 382.886463 -278.870944) (xy 382.928059 -278.901165)
			(xy 382.964415 -278.937521) (xy 382.994636 -278.979117) (xy 383.017979 -279.024929) (xy 383.033867 -279.073828)
			(xy 383.04191 -279.12461) (xy 383.042414 -279.150318) (xy 383.04191 -279.176026) (xy 383.041761 -279.176967)
			(xy 383.299452 -279.176967) (xy 383.299452 -279.123669) (xy 383.307395 -279.070965) (xy 383.323105 -279.020035)
			(xy 383.346231 -278.972014) (xy 383.376255 -278.927977) (xy 383.412507 -278.888906) (xy 383.454178 -278.855675)
			(xy 383.500336 -278.829026) (xy 383.54995 -278.809554) (xy 383.601912 -278.797694) (xy 383.655062 -278.793711)
			(xy 383.708212 -278.797694) (xy 383.760174 -278.809554) (xy 383.809788 -278.829026) (xy 383.855946 -278.855675)
			(xy 383.897617 -278.888906) (xy 383.933869 -278.927977) (xy 383.963893 -278.972014) (xy 383.987019 -279.020035)
			(xy 384.002729 -279.070965) (xy 384.010672 -279.123669) (xy 384.01117 -279.150318) (xy 384.010672 -279.176967)
			(xy 384.002729 -279.229671) (xy 383.987019 -279.280601) (xy 383.963893 -279.328622) (xy 383.933869 -279.372659)
			(xy 383.897617 -279.41173) (xy 383.855946 -279.444961) (xy 383.809788 -279.47161) (xy 383.760174 -279.491082)
			(xy 383.708212 -279.502942) (xy 383.655062 -279.506926) (xy 383.601912 -279.502942) (xy 383.54995 -279.491082)
			(xy 383.500336 -279.47161) (xy 383.454178 -279.444961) (xy 383.412507 -279.41173) (xy 383.376255 -279.372659)
			(xy 383.346231 -279.328622) (xy 383.323105 -279.280601) (xy 383.307395 -279.229671) (xy 383.299452 -279.176967)
			(xy 383.041761 -279.176967) (xy 383.033867 -279.226808) (xy 383.017979 -279.275707) (xy 382.994636 -279.321519)
			(xy 382.964415 -279.363115) (xy 382.928059 -279.399471) (xy 382.886463 -279.429692) (xy 382.840651 -279.453035)
			(xy 382.791752 -279.468923) (xy 382.74097 -279.476966) (xy 382.689554 -279.476966) (xy 382.638772 -279.468923)
			(xy 382.589873 -279.453035) (xy 382.544061 -279.429692) (xy 382.502465 -279.399471) (xy 382.466109 -279.363115)
			(xy 382.435888 -279.321519) (xy 382.412545 -279.275707) (xy 382.396657 -279.226808) (xy 382.388614 -279.176026)
			(xy 382.13109 -279.176026) (xy 382.131072 -279.176967) (xy 382.123129 -279.229671) (xy 382.107419 -279.280601)
			(xy 382.084293 -279.328622) (xy 382.054269 -279.372659) (xy 382.018017 -279.41173) (xy 381.976346 -279.444961)
			(xy 381.930188 -279.47161) (xy 381.880574 -279.491082) (xy 381.828612 -279.502942) (xy 381.775462 -279.506926)
			(xy 381.722312 -279.502942) (xy 381.67035 -279.491082) (xy 381.620736 -279.47161) (xy 381.574578 -279.444961)
			(xy 381.532907 -279.41173) (xy 381.496655 -279.372659) (xy 381.466631 -279.328622) (xy 381.443505 -279.280601)
			(xy 381.427795 -279.229671) (xy 381.419852 -279.176967) (xy 381.191526 -279.176967) (xy 381.183583 -279.229671)
			(xy 381.167873 -279.280601) (xy 381.144747 -279.328622) (xy 381.114723 -279.372659) (xy 381.078471 -279.41173)
			(xy 381.0368 -279.444961) (xy 380.990642 -279.47161) (xy 380.941028 -279.491082) (xy 380.889066 -279.502942)
			(xy 380.835916 -279.506926) (xy 380.782766 -279.502942) (xy 380.730804 -279.491082) (xy 380.68119 -279.47161)
			(xy 380.635032 -279.444961) (xy 380.593361 -279.41173) (xy 380.557109 -279.372659) (xy 380.527085 -279.328622)
			(xy 380.503959 -279.280601) (xy 380.488249 -279.229671) (xy 380.480306 -279.176967) (xy 380.251726 -279.176967)
			(xy 380.243783 -279.229671) (xy 380.228073 -279.280601) (xy 380.204947 -279.328622) (xy 380.174923 -279.372659)
			(xy 380.138671 -279.41173) (xy 380.097 -279.444961) (xy 380.050842 -279.47161) (xy 380.001228 -279.491082)
			(xy 379.949266 -279.502942) (xy 379.896116 -279.506926) (xy 379.842966 -279.502942) (xy 379.791004 -279.491082)
			(xy 379.74139 -279.47161) (xy 379.695232 -279.444961) (xy 379.653561 -279.41173) (xy 379.617309 -279.372659)
			(xy 379.587285 -279.328622) (xy 379.564159 -279.280601) (xy 379.548449 -279.229671) (xy 379.540506 -279.176967)
			(xy 379.282561 -279.176967) (xy 379.274667 -279.226808) (xy 379.258779 -279.275707) (xy 379.235436 -279.321519)
			(xy 379.205215 -279.363115) (xy 379.168859 -279.399471) (xy 379.127263 -279.429692) (xy 379.081451 -279.453035)
			(xy 379.032552 -279.468923) (xy 378.98177 -279.476966) (xy 378.930354 -279.476966) (xy 378.879572 -279.468923)
			(xy 378.830673 -279.453035) (xy 378.784861 -279.429692) (xy 378.743265 -279.399471) (xy 378.706909 -279.363115)
			(xy 378.676688 -279.321519) (xy 378.653345 -279.275707) (xy 378.637457 -279.226808) (xy 378.629414 -279.176026)
			(xy 378.372144 -279.176026) (xy 378.372126 -279.176967) (xy 378.364183 -279.229671) (xy 378.348473 -279.280601)
			(xy 378.325347 -279.328622) (xy 378.295323 -279.372659) (xy 378.259071 -279.41173) (xy 378.2174 -279.444961)
			(xy 378.171242 -279.47161) (xy 378.121628 -279.491082) (xy 378.069666 -279.502942) (xy 378.016516 -279.506926)
			(xy 377.963366 -279.502942) (xy 377.911404 -279.491082) (xy 377.86179 -279.47161) (xy 377.815632 -279.444961)
			(xy 377.773961 -279.41173) (xy 377.737709 -279.372659) (xy 377.707685 -279.328622) (xy 377.684559 -279.280601)
			(xy 377.668849 -279.229671) (xy 377.660906 -279.176967) (xy 377.432072 -279.176967) (xy 377.424129 -279.229671)
			(xy 377.408419 -279.280601) (xy 377.385293 -279.328622) (xy 377.355269 -279.372659) (xy 377.319017 -279.41173)
			(xy 377.277346 -279.444961) (xy 377.231188 -279.47161) (xy 377.181574 -279.491082) (xy 377.129612 -279.502942)
			(xy 377.076462 -279.506926) (xy 377.023312 -279.502942) (xy 376.97135 -279.491082) (xy 376.921736 -279.47161)
			(xy 376.875578 -279.444961) (xy 376.833907 -279.41173) (xy 376.797655 -279.372659) (xy 376.767631 -279.328622)
			(xy 376.744505 -279.280601) (xy 376.728795 -279.229671) (xy 376.720852 -279.176967) (xy 376.492272 -279.176967)
			(xy 376.484329 -279.229671) (xy 376.468619 -279.280601) (xy 376.445493 -279.328622) (xy 376.415469 -279.372659)
			(xy 376.379217 -279.41173) (xy 376.337546 -279.444961) (xy 376.291388 -279.47161) (xy 376.241774 -279.491082)
			(xy 376.189812 -279.502942) (xy 376.136662 -279.506926) (xy 376.083512 -279.502942) (xy 376.03155 -279.491082)
			(xy 375.981936 -279.47161) (xy 375.935778 -279.444961) (xy 375.894107 -279.41173) (xy 375.857855 -279.372659)
			(xy 375.827831 -279.328622) (xy 375.804705 -279.280601) (xy 375.788995 -279.229671) (xy 375.781052 -279.176967)
			(xy 375.552472 -279.176967) (xy 375.544529 -279.229671) (xy 375.528819 -279.280601) (xy 375.505693 -279.328622)
			(xy 375.475669 -279.372659) (xy 375.439417 -279.41173) (xy 375.397746 -279.444961) (xy 375.351588 -279.47161)
			(xy 375.301974 -279.491082) (xy 375.250012 -279.502942) (xy 375.196862 -279.506926) (xy 375.143712 -279.502942)
			(xy 375.09175 -279.491082) (xy 375.042136 -279.47161) (xy 374.995978 -279.444961) (xy 374.954307 -279.41173)
			(xy 374.918055 -279.372659) (xy 374.888031 -279.328622) (xy 374.864905 -279.280601) (xy 374.849195 -279.229671)
			(xy 374.841252 -279.176967) (xy 374.612672 -279.176967) (xy 374.604729 -279.229671) (xy 374.589019 -279.280601)
			(xy 374.565893 -279.328622) (xy 374.535869 -279.372659) (xy 374.499617 -279.41173) (xy 374.457946 -279.444961)
			(xy 374.411788 -279.47161) (xy 374.362174 -279.491082) (xy 374.310212 -279.502942) (xy 374.257062 -279.506926)
			(xy 374.203912 -279.502942) (xy 374.15195 -279.491082) (xy 374.102336 -279.47161) (xy 374.056178 -279.444961)
			(xy 374.014507 -279.41173) (xy 373.978255 -279.372659) (xy 373.948231 -279.328622) (xy 373.925105 -279.280601)
			(xy 373.909395 -279.229671) (xy 373.901452 -279.176967) (xy 373.672872 -279.176967) (xy 373.664929 -279.229671)
			(xy 373.649219 -279.280601) (xy 373.626093 -279.328622) (xy 373.596069 -279.372659) (xy 373.559817 -279.41173)
			(xy 373.518146 -279.444961) (xy 373.471988 -279.47161) (xy 373.422374 -279.491082) (xy 373.370412 -279.502942)
			(xy 373.317262 -279.506926) (xy 373.264112 -279.502942) (xy 373.21215 -279.491082) (xy 373.162536 -279.47161)
			(xy 373.116378 -279.444961) (xy 373.074707 -279.41173) (xy 373.038455 -279.372659) (xy 373.008431 -279.328622)
			(xy 372.985305 -279.280601) (xy 372.969595 -279.229671) (xy 372.961652 -279.176967) (xy 372.733072 -279.176967)
			(xy 372.725129 -279.229671) (xy 372.709419 -279.280601) (xy 372.686293 -279.328622) (xy 372.656269 -279.372659)
			(xy 372.620017 -279.41173) (xy 372.578346 -279.444961) (xy 372.532188 -279.47161) (xy 372.482574 -279.491082)
			(xy 372.430612 -279.502942) (xy 372.377462 -279.506926) (xy 372.324312 -279.502942) (xy 372.27235 -279.491082)
			(xy 372.222736 -279.47161) (xy 372.176578 -279.444961) (xy 372.134907 -279.41173) (xy 372.098655 -279.372659)
			(xy 372.068631 -279.328622) (xy 372.045505 -279.280601) (xy 372.029795 -279.229671) (xy 372.021852 -279.176967)
			(xy 371.793526 -279.176967) (xy 371.785583 -279.229671) (xy 371.769873 -279.280601) (xy 371.746747 -279.328622)
			(xy 371.716723 -279.372659) (xy 371.680471 -279.41173) (xy 371.6388 -279.444961) (xy 371.592642 -279.47161)
			(xy 371.543028 -279.491082) (xy 371.491066 -279.502942) (xy 371.437916 -279.506926) (xy 371.384766 -279.502942)
			(xy 371.332804 -279.491082) (xy 371.28319 -279.47161) (xy 371.237032 -279.444961) (xy 371.195361 -279.41173)
			(xy 371.159109 -279.372659) (xy 371.129085 -279.328622) (xy 371.105959 -279.280601) (xy 371.090249 -279.229671)
			(xy 371.082306 -279.176967) (xy 370.853472 -279.176967) (xy 370.845529 -279.229671) (xy 370.829819 -279.280601)
			(xy 370.806693 -279.328622) (xy 370.776669 -279.372659) (xy 370.740417 -279.41173) (xy 370.698746 -279.444961)
			(xy 370.652588 -279.47161) (xy 370.602974 -279.491082) (xy 370.551012 -279.502942) (xy 370.497862 -279.506926)
			(xy 370.444712 -279.502942) (xy 370.39275 -279.491082) (xy 370.343136 -279.47161) (xy 370.296978 -279.444961)
			(xy 370.255307 -279.41173) (xy 370.219055 -279.372659) (xy 370.189031 -279.328622) (xy 370.165905 -279.280601)
			(xy 370.150195 -279.229671) (xy 370.142252 -279.176967) (xy 369.913672 -279.176967) (xy 369.905729 -279.229671)
			(xy 369.890019 -279.280601) (xy 369.866893 -279.328622) (xy 369.836869 -279.372659) (xy 369.800617 -279.41173)
			(xy 369.758946 -279.444961) (xy 369.712788 -279.47161) (xy 369.663174 -279.491082) (xy 369.611212 -279.502942)
			(xy 369.558062 -279.506926) (xy 369.504912 -279.502942) (xy 369.45295 -279.491082) (xy 369.403336 -279.47161)
			(xy 369.357178 -279.444961) (xy 369.315507 -279.41173) (xy 369.279255 -279.372659) (xy 369.249231 -279.328622)
			(xy 369.226105 -279.280601) (xy 369.210395 -279.229671) (xy 369.202452 -279.176967) (xy 368.974126 -279.176967)
			(xy 368.966183 -279.229671) (xy 368.950473 -279.280601) (xy 368.927347 -279.328622) (xy 368.897323 -279.372659)
			(xy 368.861071 -279.41173) (xy 368.8194 -279.444961) (xy 368.773242 -279.47161) (xy 368.723628 -279.491082)
			(xy 368.671666 -279.502942) (xy 368.618516 -279.506926) (xy 368.565366 -279.502942) (xy 368.513404 -279.491082)
			(xy 368.46379 -279.47161) (xy 368.417632 -279.444961) (xy 368.375961 -279.41173) (xy 368.339709 -279.372659)
			(xy 368.309685 -279.328622) (xy 368.286559 -279.280601) (xy 368.270849 -279.229671) (xy 368.262906 -279.176967)
			(xy 368.034072 -279.176967) (xy 368.026129 -279.229671) (xy 368.010419 -279.280601) (xy 367.987293 -279.328622)
			(xy 367.957269 -279.372659) (xy 367.921017 -279.41173) (xy 367.879346 -279.444961) (xy 367.833188 -279.47161)
			(xy 367.783574 -279.491082) (xy 367.731612 -279.502942) (xy 367.678462 -279.506926) (xy 367.625312 -279.502942)
			(xy 367.57335 -279.491082) (xy 367.523736 -279.47161) (xy 367.477578 -279.444961) (xy 367.435907 -279.41173)
			(xy 367.399655 -279.372659) (xy 367.369631 -279.328622) (xy 367.346505 -279.280601) (xy 367.330795 -279.229671)
			(xy 367.322852 -279.176967) (xy 367.094272 -279.176967) (xy 367.086329 -279.229671) (xy 367.070619 -279.280601)
			(xy 367.047493 -279.328622) (xy 367.017469 -279.372659) (xy 366.981217 -279.41173) (xy 366.939546 -279.444961)
			(xy 366.893388 -279.47161) (xy 366.843774 -279.491082) (xy 366.791812 -279.502942) (xy 366.738662 -279.506926)
			(xy 366.685512 -279.502942) (xy 366.63355 -279.491082) (xy 366.583936 -279.47161) (xy 366.537778 -279.444961)
			(xy 366.496107 -279.41173) (xy 366.459855 -279.372659) (xy 366.429831 -279.328622) (xy 366.406705 -279.280601)
			(xy 366.390995 -279.229671) (xy 366.383052 -279.176967) (xy 366.154726 -279.176967) (xy 366.146783 -279.229671)
			(xy 366.131073 -279.280601) (xy 366.107947 -279.328622) (xy 366.077923 -279.372659) (xy 366.041671 -279.41173)
			(xy 366 -279.444961) (xy 365.953842 -279.47161) (xy 365.904228 -279.491082) (xy 365.852266 -279.502942)
			(xy 365.799116 -279.506926) (xy 365.745966 -279.502942) (xy 365.694004 -279.491082) (xy 365.64439 -279.47161)
			(xy 365.598232 -279.444961) (xy 365.556561 -279.41173) (xy 365.520309 -279.372659) (xy 365.490285 -279.328622)
			(xy 365.467159 -279.280601) (xy 365.451449 -279.229671) (xy 365.443506 -279.176967) (xy 365.214888 -279.176967)
			(xy 365.206983 -279.229417) (xy 365.191273 -279.280347) (xy 365.168147 -279.328368) (xy 365.138123 -279.372405)
			(xy 365.101871 -279.411476) (xy 365.0602 -279.444707) (xy 365.014042 -279.471356) (xy 364.964428 -279.490828)
			(xy 364.912466 -279.502688) (xy 364.859316 -279.506672) (xy 364.806166 -279.502688) (xy 364.754204 -279.490828)
			(xy 364.70459 -279.471356) (xy 364.658432 -279.444707) (xy 364.616761 -279.411476) (xy 364.580509 -279.372405)
			(xy 364.550485 -279.328368) (xy 364.527359 -279.280347) (xy 364.511649 -279.229417) (xy 364.503706 -279.176713)
			(xy 364.274877 -279.176713) (xy 364.274872 -279.176967) (xy 364.266929 -279.229671) (xy 364.251219 -279.280601)
			(xy 364.228093 -279.328622) (xy 364.198069 -279.372659) (xy 364.161817 -279.41173) (xy 364.120146 -279.444961)
			(xy 364.073988 -279.47161) (xy 364.024374 -279.491082) (xy 363.972412 -279.502942) (xy 363.919262 -279.506926)
			(xy 363.866112 -279.502942) (xy 363.81415 -279.491082) (xy 363.764536 -279.47161) (xy 363.718378 -279.444961)
			(xy 363.676707 -279.41173) (xy 363.640455 -279.372659) (xy 363.610431 -279.328622) (xy 363.587305 -279.280601)
			(xy 363.571595 -279.229671) (xy 363.563652 -279.176967) (xy 363.335072 -279.176967) (xy 363.327129 -279.229671)
			(xy 363.311419 -279.280601) (xy 363.288293 -279.328622) (xy 363.258269 -279.372659) (xy 363.222017 -279.41173)
			(xy 363.180346 -279.444961) (xy 363.134188 -279.47161) (xy 363.084574 -279.491082) (xy 363.032612 -279.502942)
			(xy 362.979462 -279.506926) (xy 362.926312 -279.502942) (xy 362.87435 -279.491082) (xy 362.824736 -279.47161)
			(xy 362.778578 -279.444961) (xy 362.736907 -279.41173) (xy 362.700655 -279.372659) (xy 362.670631 -279.328622)
			(xy 362.647505 -279.280601) (xy 362.631795 -279.229671) (xy 362.623852 -279.176967) (xy 356.756472 -279.176967)
			(xy 356.748529 -279.229671) (xy 356.732819 -279.280601) (xy 356.709693 -279.328622) (xy 356.679669 -279.372659)
			(xy 356.643417 -279.41173) (xy 356.601746 -279.444961) (xy 356.555588 -279.47161) (xy 356.505974 -279.491082)
			(xy 356.454012 -279.502942) (xy 356.400862 -279.506926) (xy 356.347712 -279.502942) (xy 356.29575 -279.491082)
			(xy 356.246136 -279.47161) (xy 356.199978 -279.444961) (xy 356.158307 -279.41173) (xy 356.122055 -279.372659)
			(xy 356.092031 -279.328622) (xy 356.068905 -279.280601) (xy 356.053195 -279.229671) (xy 356.045252 -279.176967)
			(xy 355.816672 -279.176967) (xy 355.808729 -279.229671) (xy 355.793019 -279.280601) (xy 355.769893 -279.328622)
			(xy 355.739869 -279.372659) (xy 355.703617 -279.41173) (xy 355.661946 -279.444961) (xy 355.615788 -279.47161)
			(xy 355.566174 -279.491082) (xy 355.514212 -279.502942) (xy 355.461062 -279.506926) (xy 355.407912 -279.502942)
			(xy 355.35595 -279.491082) (xy 355.306336 -279.47161) (xy 355.260178 -279.444961) (xy 355.218507 -279.41173)
			(xy 355.182255 -279.372659) (xy 355.152231 -279.328622) (xy 355.129105 -279.280601) (xy 355.113395 -279.229671)
			(xy 355.105452 -279.176967) (xy 354.877126 -279.176967) (xy 354.869183 -279.229671) (xy 354.853473 -279.280601)
			(xy 354.830347 -279.328622) (xy 354.800323 -279.372659) (xy 354.764071 -279.41173) (xy 354.7224 -279.444961)
			(xy 354.676242 -279.47161) (xy 354.626628 -279.491082) (xy 354.574666 -279.502942) (xy 354.521516 -279.506926)
			(xy 354.468366 -279.502942) (xy 354.416404 -279.491082) (xy 354.36679 -279.47161) (xy 354.320632 -279.444961)
			(xy 354.278961 -279.41173) (xy 354.242709 -279.372659) (xy 354.212685 -279.328622) (xy 354.189559 -279.280601)
			(xy 354.173849 -279.229671) (xy 354.165906 -279.176967) (xy 353.937326 -279.176967) (xy 353.929383 -279.229671)
			(xy 353.913673 -279.280601) (xy 353.890547 -279.328622) (xy 353.860523 -279.372659) (xy 353.824271 -279.41173)
			(xy 353.7826 -279.444961) (xy 353.736442 -279.47161) (xy 353.686828 -279.491082) (xy 353.634866 -279.502942)
			(xy 353.581716 -279.506926) (xy 353.528566 -279.502942) (xy 353.476604 -279.491082) (xy 353.42699 -279.47161)
			(xy 353.380832 -279.444961) (xy 353.339161 -279.41173) (xy 353.302909 -279.372659) (xy 353.272885 -279.328622)
			(xy 353.249759 -279.280601) (xy 353.234049 -279.229671) (xy 353.226106 -279.176967) (xy 353.024694 -279.176967)
			(xy 353.024694 -279.53335) (xy 353.025301 -279.548994) (xy 353.03483 -279.5788) (xy 353.052919 -279.604332)
			(xy 353.077878 -279.623206) (xy 353.107372 -279.633656) (xy 353.122992 -279.634696) (xy 353.148307 -279.636021)
			(xy 353.198108 -279.645476) (xy 353.245875 -279.662441) (xy 353.290482 -279.686519) (xy 353.330879 -279.71714)
			(xy 353.366113 -279.753583) (xy 353.395353 -279.79499) (xy 353.417911 -279.840385) (xy 353.433256 -279.888697)
			(xy 353.441024 -279.938789) (xy 353.441508 -279.964134) (xy 353.441039 -279.989494) (xy 353.440839 -279.990783)
			(xy 353.696006 -279.990783) (xy 353.696006 -279.937485) (xy 353.703949 -279.884781) (xy 353.719659 -279.833851)
			(xy 353.742785 -279.78583) (xy 353.772809 -279.741793) (xy 353.809061 -279.702722) (xy 353.850732 -279.669491)
			(xy 353.89689 -279.642842) (xy 353.946504 -279.62337) (xy 353.998466 -279.61151) (xy 354.051616 -279.607527)
			(xy 354.104766 -279.61151) (xy 354.156728 -279.62337) (xy 354.206342 -279.642842) (xy 354.2525 -279.669491)
			(xy 354.294171 -279.702722) (xy 354.330423 -279.741793) (xy 354.360447 -279.78583) (xy 354.383573 -279.833851)
			(xy 354.399283 -279.884781) (xy 354.407226 -279.937485) (xy 354.407724 -279.964134) (xy 354.407226 -279.990783)
			(xy 354.635806 -279.990783) (xy 354.635806 -279.937485) (xy 354.643749 -279.884781) (xy 354.659459 -279.833851)
			(xy 354.682585 -279.78583) (xy 354.712609 -279.741793) (xy 354.748861 -279.702722) (xy 354.790532 -279.669491)
			(xy 354.83669 -279.642842) (xy 354.886304 -279.62337) (xy 354.938266 -279.61151) (xy 354.991416 -279.607527)
			(xy 355.044566 -279.61151) (xy 355.096528 -279.62337) (xy 355.146142 -279.642842) (xy 355.1923 -279.669491)
			(xy 355.233971 -279.702722) (xy 355.270223 -279.741793) (xy 355.300247 -279.78583) (xy 355.323373 -279.833851)
			(xy 355.339083 -279.884781) (xy 355.347026 -279.937485) (xy 355.347524 -279.964134) (xy 355.347026 -279.990783)
			(xy 355.575352 -279.990783) (xy 355.575352 -279.937485) (xy 355.583295 -279.884781) (xy 355.599005 -279.833851)
			(xy 355.622131 -279.78583) (xy 355.652155 -279.741793) (xy 355.688407 -279.702722) (xy 355.730078 -279.669491)
			(xy 355.776236 -279.642842) (xy 355.82585 -279.62337) (xy 355.877812 -279.61151) (xy 355.930962 -279.607527)
			(xy 355.984112 -279.61151) (xy 356.036074 -279.62337) (xy 356.085688 -279.642842) (xy 356.131846 -279.669491)
			(xy 356.173517 -279.702722) (xy 356.209769 -279.741793) (xy 356.239793 -279.78583) (xy 356.262919 -279.833851)
			(xy 356.278629 -279.884781) (xy 356.286572 -279.937485) (xy 356.28707 -279.964134) (xy 356.286572 -279.990783)
			(xy 361.214152 -279.990783) (xy 361.214152 -279.937485) (xy 361.222095 -279.884781) (xy 361.237805 -279.833851)
			(xy 361.260931 -279.78583) (xy 361.290955 -279.741793) (xy 361.327207 -279.702722) (xy 361.368878 -279.669491)
			(xy 361.415036 -279.642842) (xy 361.46465 -279.62337) (xy 361.516612 -279.61151) (xy 361.569762 -279.607527)
			(xy 361.622912 -279.61151) (xy 361.674874 -279.62337) (xy 361.724488 -279.642842) (xy 361.770646 -279.669491)
			(xy 361.812317 -279.702722) (xy 361.848569 -279.741793) (xy 361.878593 -279.78583) (xy 361.901719 -279.833851)
			(xy 361.917429 -279.884781) (xy 361.925372 -279.937485) (xy 361.92587 -279.964134) (xy 361.925372 -279.990783)
			(xy 364.033806 -279.990783) (xy 364.033806 -279.937485) (xy 364.041749 -279.884781) (xy 364.057459 -279.833851)
			(xy 364.080585 -279.78583) (xy 364.110609 -279.741793) (xy 364.146861 -279.702722) (xy 364.188532 -279.669491)
			(xy 364.23469 -279.642842) (xy 364.284304 -279.62337) (xy 364.336266 -279.61151) (xy 364.389416 -279.607527)
			(xy 364.442566 -279.61151) (xy 364.494528 -279.62337) (xy 364.544142 -279.642842) (xy 364.5903 -279.669491)
			(xy 364.631971 -279.702722) (xy 364.668223 -279.741793) (xy 364.698247 -279.78583) (xy 364.721373 -279.833851)
			(xy 364.737083 -279.884781) (xy 364.745026 -279.937485) (xy 364.745524 -279.964134) (xy 364.745026 -279.990783)
			(xy 364.973606 -279.990783) (xy 364.973606 -279.937485) (xy 364.981549 -279.884781) (xy 364.997259 -279.833851)
			(xy 365.020385 -279.78583) (xy 365.050409 -279.741793) (xy 365.086661 -279.702722) (xy 365.128332 -279.669491)
			(xy 365.17449 -279.642842) (xy 365.224104 -279.62337) (xy 365.276066 -279.61151) (xy 365.329216 -279.607527)
			(xy 365.382366 -279.61151) (xy 365.434328 -279.62337) (xy 365.483942 -279.642842) (xy 365.5301 -279.669491)
			(xy 365.571771 -279.702722) (xy 365.608023 -279.741793) (xy 365.638047 -279.78583) (xy 365.661173 -279.833851)
			(xy 365.676883 -279.884781) (xy 365.684826 -279.937485) (xy 365.685324 -279.964134) (xy 365.684826 -279.990783)
			(xy 365.913152 -279.990783) (xy 365.913152 -279.937485) (xy 365.921095 -279.884781) (xy 365.936805 -279.833851)
			(xy 365.959931 -279.78583) (xy 365.989955 -279.741793) (xy 366.026207 -279.702722) (xy 366.067878 -279.669491)
			(xy 366.114036 -279.642842) (xy 366.16365 -279.62337) (xy 366.215612 -279.61151) (xy 366.268762 -279.607527)
			(xy 366.321912 -279.61151) (xy 366.373874 -279.62337) (xy 366.423488 -279.642842) (xy 366.469646 -279.669491)
			(xy 366.511317 -279.702722) (xy 366.547569 -279.741793) (xy 366.577593 -279.78583) (xy 366.600719 -279.833851)
			(xy 366.616429 -279.884781) (xy 366.624372 -279.937485) (xy 366.62487 -279.964134) (xy 366.624372 -279.990783)
			(xy 366.853206 -279.990783) (xy 366.853206 -279.937485) (xy 366.861149 -279.884781) (xy 366.876859 -279.833851)
			(xy 366.899985 -279.78583) (xy 366.930009 -279.741793) (xy 366.966261 -279.702722) (xy 367.007932 -279.669491)
			(xy 367.05409 -279.642842) (xy 367.103704 -279.62337) (xy 367.155666 -279.61151) (xy 367.208816 -279.607527)
			(xy 367.261966 -279.61151) (xy 367.313928 -279.62337) (xy 367.363542 -279.642842) (xy 367.4097 -279.669491)
			(xy 367.451371 -279.702722) (xy 367.487623 -279.741793) (xy 367.517647 -279.78583) (xy 367.540773 -279.833851)
			(xy 367.556483 -279.884781) (xy 367.564426 -279.937485) (xy 367.564924 -279.964134) (xy 367.564426 -279.990783)
			(xy 367.793006 -279.990783) (xy 367.793006 -279.937485) (xy 367.800949 -279.884781) (xy 367.816659 -279.833851)
			(xy 367.839785 -279.78583) (xy 367.869809 -279.741793) (xy 367.906061 -279.702722) (xy 367.947732 -279.669491)
			(xy 367.99389 -279.642842) (xy 368.043504 -279.62337) (xy 368.095466 -279.61151) (xy 368.148616 -279.607527)
			(xy 368.201766 -279.61151) (xy 368.253728 -279.62337) (xy 368.303342 -279.642842) (xy 368.3495 -279.669491)
			(xy 368.391171 -279.702722) (xy 368.427423 -279.741793) (xy 368.457447 -279.78583) (xy 368.480573 -279.833851)
			(xy 368.496283 -279.884781) (xy 368.504226 -279.937485) (xy 368.504724 -279.964134) (xy 368.504226 -279.990783)
			(xy 368.732806 -279.990783) (xy 368.732806 -279.937485) (xy 368.740749 -279.884781) (xy 368.756459 -279.833851)
			(xy 368.779585 -279.78583) (xy 368.809609 -279.741793) (xy 368.845861 -279.702722) (xy 368.887532 -279.669491)
			(xy 368.93369 -279.642842) (xy 368.983304 -279.62337) (xy 369.035266 -279.61151) (xy 369.088416 -279.607527)
			(xy 369.141566 -279.61151) (xy 369.193528 -279.62337) (xy 369.243142 -279.642842) (xy 369.2893 -279.669491)
			(xy 369.330971 -279.702722) (xy 369.367223 -279.741793) (xy 369.397247 -279.78583) (xy 369.420373 -279.833851)
			(xy 369.436083 -279.884781) (xy 369.444026 -279.937485) (xy 369.444524 -279.964134) (xy 369.444026 -279.990783)
			(xy 369.672606 -279.990783) (xy 369.672606 -279.937485) (xy 369.680549 -279.884781) (xy 369.696259 -279.833851)
			(xy 369.719385 -279.78583) (xy 369.749409 -279.741793) (xy 369.785661 -279.702722) (xy 369.827332 -279.669491)
			(xy 369.87349 -279.642842) (xy 369.923104 -279.62337) (xy 369.975066 -279.61151) (xy 370.028216 -279.607527)
			(xy 370.081366 -279.61151) (xy 370.133328 -279.62337) (xy 370.182942 -279.642842) (xy 370.2291 -279.669491)
			(xy 370.270771 -279.702722) (xy 370.307023 -279.741793) (xy 370.337047 -279.78583) (xy 370.360173 -279.833851)
			(xy 370.375883 -279.884781) (xy 370.383826 -279.937485) (xy 370.384324 -279.964134) (xy 370.383826 -279.990783)
			(xy 370.612406 -279.990783) (xy 370.612406 -279.937485) (xy 370.620349 -279.884781) (xy 370.636059 -279.833851)
			(xy 370.659185 -279.78583) (xy 370.689209 -279.741793) (xy 370.725461 -279.702722) (xy 370.767132 -279.669491)
			(xy 370.81329 -279.642842) (xy 370.862904 -279.62337) (xy 370.914866 -279.61151) (xy 370.968016 -279.607527)
			(xy 371.021166 -279.61151) (xy 371.073128 -279.62337) (xy 371.122742 -279.642842) (xy 371.1689 -279.669491)
			(xy 371.210571 -279.702722) (xy 371.246823 -279.741793) (xy 371.276847 -279.78583) (xy 371.299973 -279.833851)
			(xy 371.315683 -279.884781) (xy 371.323626 -279.937485) (xy 371.324124 -279.964134) (xy 371.323626 -279.990783)
			(xy 371.551952 -279.990783) (xy 371.551952 -279.937485) (xy 371.559895 -279.884781) (xy 371.575605 -279.833851)
			(xy 371.598731 -279.78583) (xy 371.628755 -279.741793) (xy 371.665007 -279.702722) (xy 371.706678 -279.669491)
			(xy 371.752836 -279.642842) (xy 371.80245 -279.62337) (xy 371.854412 -279.61151) (xy 371.907562 -279.607527)
			(xy 371.960712 -279.61151) (xy 372.012674 -279.62337) (xy 372.062288 -279.642842) (xy 372.108446 -279.669491)
			(xy 372.150117 -279.702722) (xy 372.186369 -279.741793) (xy 372.216393 -279.78583) (xy 372.239519 -279.833851)
			(xy 372.255229 -279.884781) (xy 372.263172 -279.937485) (xy 372.26367 -279.964134) (xy 372.263172 -279.990783)
			(xy 372.492006 -279.990783) (xy 372.492006 -279.937485) (xy 372.499949 -279.884781) (xy 372.515659 -279.833851)
			(xy 372.538785 -279.78583) (xy 372.568809 -279.741793) (xy 372.605061 -279.702722) (xy 372.646732 -279.669491)
			(xy 372.69289 -279.642842) (xy 372.742504 -279.62337) (xy 372.794466 -279.61151) (xy 372.847616 -279.607527)
			(xy 372.900766 -279.61151) (xy 372.952728 -279.62337) (xy 373.002342 -279.642842) (xy 373.0485 -279.669491)
			(xy 373.090171 -279.702722) (xy 373.126423 -279.741793) (xy 373.156447 -279.78583) (xy 373.179573 -279.833851)
			(xy 373.195283 -279.884781) (xy 373.203226 -279.937485) (xy 373.203724 -279.964134) (xy 373.203226 -279.990783)
			(xy 373.431806 -279.990783) (xy 373.431806 -279.937485) (xy 373.439749 -279.884781) (xy 373.455459 -279.833851)
			(xy 373.478585 -279.78583) (xy 373.508609 -279.741793) (xy 373.544861 -279.702722) (xy 373.586532 -279.669491)
			(xy 373.63269 -279.642842) (xy 373.682304 -279.62337) (xy 373.734266 -279.61151) (xy 373.787416 -279.607527)
			(xy 373.840566 -279.61151) (xy 373.892528 -279.62337) (xy 373.942142 -279.642842) (xy 373.9883 -279.669491)
			(xy 374.029971 -279.702722) (xy 374.066223 -279.741793) (xy 374.096247 -279.78583) (xy 374.119373 -279.833851)
			(xy 374.135083 -279.884781) (xy 374.143026 -279.937485) (xy 374.143524 -279.964134) (xy 374.143026 -279.990783)
			(xy 374.371352 -279.990783) (xy 374.371352 -279.937485) (xy 374.379295 -279.884781) (xy 374.395005 -279.833851)
			(xy 374.418131 -279.78583) (xy 374.448155 -279.741793) (xy 374.484407 -279.702722) (xy 374.526078 -279.669491)
			(xy 374.572236 -279.642842) (xy 374.62185 -279.62337) (xy 374.673812 -279.61151) (xy 374.726962 -279.607527)
			(xy 374.780112 -279.61151) (xy 374.832074 -279.62337) (xy 374.881688 -279.642842) (xy 374.927846 -279.669491)
			(xy 374.969517 -279.702722) (xy 375.005769 -279.741793) (xy 375.035793 -279.78583) (xy 375.058919 -279.833851)
			(xy 375.074629 -279.884781) (xy 375.082572 -279.937485) (xy 375.08307 -279.964134) (xy 375.082572 -279.990783)
			(xy 375.311406 -279.990783) (xy 375.311406 -279.937485) (xy 375.319349 -279.884781) (xy 375.335059 -279.833851)
			(xy 375.358185 -279.78583) (xy 375.388209 -279.741793) (xy 375.424461 -279.702722) (xy 375.466132 -279.669491)
			(xy 375.51229 -279.642842) (xy 375.561904 -279.62337) (xy 375.613866 -279.61151) (xy 375.667016 -279.607527)
			(xy 375.720166 -279.61151) (xy 375.772128 -279.62337) (xy 375.821742 -279.642842) (xy 375.8679 -279.669491)
			(xy 375.909571 -279.702722) (xy 375.945823 -279.741793) (xy 375.975847 -279.78583) (xy 375.998973 -279.833851)
			(xy 376.014683 -279.884781) (xy 376.022626 -279.937485) (xy 376.023124 -279.964134) (xy 376.022631 -279.990529)
			(xy 376.250952 -279.990529) (xy 376.250952 -279.937231) (xy 376.258895 -279.884527) (xy 376.274605 -279.833597)
			(xy 376.297731 -279.785576) (xy 376.327755 -279.741539) (xy 376.364007 -279.702468) (xy 376.405678 -279.669237)
			(xy 376.451836 -279.642588) (xy 376.50145 -279.623116) (xy 376.553412 -279.611256) (xy 376.606562 -279.607273)
			(xy 376.659712 -279.611256) (xy 376.711674 -279.623116) (xy 376.761288 -279.642588) (xy 376.807446 -279.669237)
			(xy 376.849117 -279.702468) (xy 376.885369 -279.741539) (xy 376.915393 -279.785576) (xy 376.938519 -279.833597)
			(xy 376.954229 -279.884527) (xy 376.962172 -279.937231) (xy 376.96267 -279.96388) (xy 376.962172 -279.990529)
			(xy 376.962134 -279.990783) (xy 377.191006 -279.990783) (xy 377.191006 -279.937485) (xy 377.198949 -279.884781)
			(xy 377.214659 -279.833851) (xy 377.237785 -279.78583) (xy 377.267809 -279.741793) (xy 377.304061 -279.702722)
			(xy 377.345732 -279.669491) (xy 377.39189 -279.642842) (xy 377.441504 -279.62337) (xy 377.493466 -279.61151)
			(xy 377.546616 -279.607527) (xy 377.599766 -279.61151) (xy 377.651728 -279.62337) (xy 377.701342 -279.642842)
			(xy 377.7475 -279.669491) (xy 377.789171 -279.702722) (xy 377.825423 -279.741793) (xy 377.855447 -279.78583)
			(xy 377.878573 -279.833851) (xy 377.894283 -279.884781) (xy 377.902226 -279.937485) (xy 377.902724 -279.964134)
			(xy 377.902226 -279.990783) (xy 378.130806 -279.990783) (xy 378.130806 -279.937485) (xy 378.138749 -279.884781)
			(xy 378.154459 -279.833851) (xy 378.177585 -279.78583) (xy 378.207609 -279.741793) (xy 378.243861 -279.702722)
			(xy 378.285532 -279.669491) (xy 378.33169 -279.642842) (xy 378.381304 -279.62337) (xy 378.433266 -279.61151)
			(xy 378.486416 -279.607527) (xy 378.539566 -279.61151) (xy 378.591528 -279.62337) (xy 378.641142 -279.642842)
			(xy 378.6873 -279.669491) (xy 378.728971 -279.702722) (xy 378.765223 -279.741793) (xy 378.795247 -279.78583)
			(xy 378.818373 -279.833851) (xy 378.834083 -279.884781) (xy 378.842026 -279.937485) (xy 378.842524 -279.964134)
			(xy 378.842044 -279.989842) (xy 379.099568 -279.989842) (xy 379.099568 -279.938426) (xy 379.107611 -279.887644)
			(xy 379.123499 -279.838745) (xy 379.146842 -279.792933) (xy 379.177063 -279.751337) (xy 379.213419 -279.714981)
			(xy 379.255015 -279.68476) (xy 379.300827 -279.661417) (xy 379.349726 -279.645529) (xy 379.400508 -279.637486)
			(xy 379.451924 -279.637486) (xy 379.502706 -279.645529) (xy 379.551605 -279.661417) (xy 379.597417 -279.68476)
			(xy 379.639013 -279.714981) (xy 379.675369 -279.751337) (xy 379.70559 -279.792933) (xy 379.728933 -279.838745)
			(xy 379.744821 -279.887644) (xy 379.752864 -279.938426) (xy 379.753368 -279.964134) (xy 379.752864 -279.989842)
			(xy 379.752715 -279.990783) (xy 380.010152 -279.990783) (xy 380.010152 -279.937485) (xy 380.018095 -279.884781)
			(xy 380.033805 -279.833851) (xy 380.056931 -279.78583) (xy 380.086955 -279.741793) (xy 380.123207 -279.702722)
			(xy 380.164878 -279.669491) (xy 380.211036 -279.642842) (xy 380.26065 -279.62337) (xy 380.312612 -279.61151)
			(xy 380.365762 -279.607527) (xy 380.418912 -279.61151) (xy 380.470874 -279.62337) (xy 380.520488 -279.642842)
			(xy 380.566646 -279.669491) (xy 380.608317 -279.702722) (xy 380.644569 -279.741793) (xy 380.674593 -279.78583)
			(xy 380.697719 -279.833851) (xy 380.713429 -279.884781) (xy 380.721372 -279.937485) (xy 380.72187 -279.964134)
			(xy 380.721372 -279.990783) (xy 380.950206 -279.990783) (xy 380.950206 -279.937485) (xy 380.958149 -279.884781)
			(xy 380.973859 -279.833851) (xy 380.996985 -279.78583) (xy 381.027009 -279.741793) (xy 381.063261 -279.702722)
			(xy 381.104932 -279.669491) (xy 381.15109 -279.642842) (xy 381.200704 -279.62337) (xy 381.252666 -279.61151)
			(xy 381.305816 -279.607527) (xy 381.358966 -279.61151) (xy 381.410928 -279.62337) (xy 381.460542 -279.642842)
			(xy 381.5067 -279.669491) (xy 381.548371 -279.702722) (xy 381.584623 -279.741793) (xy 381.614647 -279.78583)
			(xy 381.637773 -279.833851) (xy 381.653483 -279.884781) (xy 381.661426 -279.937485) (xy 381.661924 -279.964134)
			(xy 381.661426 -279.990783) (xy 381.890006 -279.990783) (xy 381.890006 -279.937485) (xy 381.897949 -279.884781)
			(xy 381.913659 -279.833851) (xy 381.936785 -279.78583) (xy 381.966809 -279.741793) (xy 382.003061 -279.702722)
			(xy 382.044732 -279.669491) (xy 382.09089 -279.642842) (xy 382.140504 -279.62337) (xy 382.192466 -279.61151)
			(xy 382.245616 -279.607527) (xy 382.298766 -279.61151) (xy 382.350728 -279.62337) (xy 382.400342 -279.642842)
			(xy 382.4465 -279.669491) (xy 382.488171 -279.702722) (xy 382.524423 -279.741793) (xy 382.554447 -279.78583)
			(xy 382.577573 -279.833851) (xy 382.593283 -279.884781) (xy 382.601226 -279.937485) (xy 382.601724 -279.964134)
			(xy 382.601226 -279.990783) (xy 382.829298 -279.990783) (xy 382.829298 -279.937485) (xy 382.837241 -279.884781)
			(xy 382.852951 -279.833851) (xy 382.876077 -279.78583) (xy 382.906101 -279.741793) (xy 382.942353 -279.702722)
			(xy 382.984024 -279.669491) (xy 383.030182 -279.642842) (xy 383.079796 -279.62337) (xy 383.131758 -279.61151)
			(xy 383.184908 -279.607527) (xy 383.238058 -279.61151) (xy 383.29002 -279.62337) (xy 383.339634 -279.642842)
			(xy 383.385792 -279.669491) (xy 383.427463 -279.702722) (xy 383.463715 -279.741793) (xy 383.493739 -279.78583)
			(xy 383.516865 -279.833851) (xy 383.532575 -279.884781) (xy 383.540518 -279.937485) (xy 383.541016 -279.964134)
			(xy 383.540518 -279.990783) (xy 383.769352 -279.990783) (xy 383.769352 -279.937485) (xy 383.777295 -279.884781)
			(xy 383.793005 -279.833851) (xy 383.816131 -279.78583) (xy 383.846155 -279.741793) (xy 383.882407 -279.702722)
			(xy 383.924078 -279.669491) (xy 383.970236 -279.642842) (xy 384.01985 -279.62337) (xy 384.071812 -279.61151)
			(xy 384.124962 -279.607527) (xy 384.178112 -279.61151) (xy 384.230074 -279.62337) (xy 384.279688 -279.642842)
			(xy 384.325846 -279.669491) (xy 384.367517 -279.702722) (xy 384.403769 -279.741793) (xy 384.433793 -279.78583)
			(xy 384.456919 -279.833851) (xy 384.472629 -279.884781) (xy 384.480572 -279.937485) (xy 384.48107 -279.964134)
			(xy 384.480572 -279.990783) (xy 384.709152 -279.990783) (xy 384.709152 -279.937485) (xy 384.717095 -279.884781)
			(xy 384.732805 -279.833851) (xy 384.755931 -279.78583) (xy 384.785955 -279.741793) (xy 384.822207 -279.702722)
			(xy 384.863878 -279.669491) (xy 384.910036 -279.642842) (xy 384.95965 -279.62337) (xy 385.011612 -279.61151)
			(xy 385.064762 -279.607527) (xy 385.117912 -279.61151) (xy 385.169874 -279.62337) (xy 385.219488 -279.642842)
			(xy 385.265646 -279.669491) (xy 385.307317 -279.702722) (xy 385.343569 -279.741793) (xy 385.373593 -279.78583)
			(xy 385.396719 -279.833851) (xy 385.412429 -279.884781) (xy 385.420372 -279.937485) (xy 385.42087 -279.964134)
			(xy 385.420372 -279.990783) (xy 385.412429 -280.043487) (xy 385.396719 -280.094417) (xy 385.373593 -280.142438)
			(xy 385.343569 -280.186475) (xy 385.307317 -280.225546) (xy 385.265646 -280.258777) (xy 385.219488 -280.285426)
			(xy 385.169874 -280.304898) (xy 385.117912 -280.316758) (xy 385.064762 -280.320742) (xy 385.011612 -280.316758)
			(xy 384.95965 -280.304898) (xy 384.910036 -280.285426) (xy 384.863878 -280.258777) (xy 384.822207 -280.225546)
			(xy 384.785955 -280.186475) (xy 384.755931 -280.142438) (xy 384.732805 -280.094417) (xy 384.717095 -280.043487)
			(xy 384.709152 -279.990783) (xy 384.480572 -279.990783) (xy 384.472629 -280.043487) (xy 384.456919 -280.094417)
			(xy 384.433793 -280.142438) (xy 384.403769 -280.186475) (xy 384.367517 -280.225546) (xy 384.325846 -280.258777)
			(xy 384.279688 -280.285426) (xy 384.230074 -280.304898) (xy 384.178112 -280.316758) (xy 384.124962 -280.320742)
			(xy 384.071812 -280.316758) (xy 384.01985 -280.304898) (xy 383.970236 -280.285426) (xy 383.924078 -280.258777)
			(xy 383.882407 -280.225546) (xy 383.846155 -280.186475) (xy 383.816131 -280.142438) (xy 383.793005 -280.094417)
			(xy 383.777295 -280.043487) (xy 383.769352 -279.990783) (xy 383.540518 -279.990783) (xy 383.532575 -280.043487)
			(xy 383.516865 -280.094417) (xy 383.493739 -280.142438) (xy 383.463715 -280.186475) (xy 383.427463 -280.225546)
			(xy 383.385792 -280.258777) (xy 383.339634 -280.285426) (xy 383.29002 -280.304898) (xy 383.238058 -280.316758)
			(xy 383.184908 -280.320742) (xy 383.131758 -280.316758) (xy 383.079796 -280.304898) (xy 383.030182 -280.285426)
			(xy 382.984024 -280.258777) (xy 382.942353 -280.225546) (xy 382.906101 -280.186475) (xy 382.876077 -280.142438)
			(xy 382.852951 -280.094417) (xy 382.837241 -280.043487) (xy 382.829298 -279.990783) (xy 382.601226 -279.990783)
			(xy 382.593283 -280.043487) (xy 382.577573 -280.094417) (xy 382.554447 -280.142438) (xy 382.524423 -280.186475)
			(xy 382.488171 -280.225546) (xy 382.4465 -280.258777) (xy 382.400342 -280.285426) (xy 382.350728 -280.304898)
			(xy 382.298766 -280.316758) (xy 382.245616 -280.320742) (xy 382.192466 -280.316758) (xy 382.140504 -280.304898)
			(xy 382.09089 -280.285426) (xy 382.044732 -280.258777) (xy 382.003061 -280.225546) (xy 381.966809 -280.186475)
			(xy 381.936785 -280.142438) (xy 381.913659 -280.094417) (xy 381.897949 -280.043487) (xy 381.890006 -279.990783)
			(xy 381.661426 -279.990783) (xy 381.653483 -280.043487) (xy 381.637773 -280.094417) (xy 381.614647 -280.142438)
			(xy 381.584623 -280.186475) (xy 381.548371 -280.225546) (xy 381.5067 -280.258777) (xy 381.460542 -280.285426)
			(xy 381.410928 -280.304898) (xy 381.358966 -280.316758) (xy 381.305816 -280.320742) (xy 381.252666 -280.316758)
			(xy 381.200704 -280.304898) (xy 381.15109 -280.285426) (xy 381.104932 -280.258777) (xy 381.063261 -280.225546)
			(xy 381.027009 -280.186475) (xy 380.996985 -280.142438) (xy 380.973859 -280.094417) (xy 380.958149 -280.043487)
			(xy 380.950206 -279.990783) (xy 380.721372 -279.990783) (xy 380.713429 -280.043487) (xy 380.697719 -280.094417)
			(xy 380.674593 -280.142438) (xy 380.644569 -280.186475) (xy 380.608317 -280.225546) (xy 380.566646 -280.258777)
			(xy 380.520488 -280.285426) (xy 380.470874 -280.304898) (xy 380.418912 -280.316758) (xy 380.365762 -280.320742)
			(xy 380.312612 -280.316758) (xy 380.26065 -280.304898) (xy 380.211036 -280.285426) (xy 380.164878 -280.258777)
			(xy 380.123207 -280.225546) (xy 380.086955 -280.186475) (xy 380.056931 -280.142438) (xy 380.033805 -280.094417)
			(xy 380.018095 -280.043487) (xy 380.010152 -279.990783) (xy 379.752715 -279.990783) (xy 379.744821 -280.040624)
			(xy 379.728933 -280.089523) (xy 379.70559 -280.135335) (xy 379.675369 -280.176931) (xy 379.639013 -280.213287)
			(xy 379.597417 -280.243508) (xy 379.551605 -280.266851) (xy 379.502706 -280.282739) (xy 379.451924 -280.290782)
			(xy 379.400508 -280.290782) (xy 379.349726 -280.282739) (xy 379.300827 -280.266851) (xy 379.255015 -280.243508)
			(xy 379.213419 -280.213287) (xy 379.177063 -280.176931) (xy 379.146842 -280.135335) (xy 379.123499 -280.089523)
			(xy 379.107611 -280.040624) (xy 379.099568 -279.989842) (xy 378.842044 -279.989842) (xy 378.842026 -279.990783)
			(xy 378.834083 -280.043487) (xy 378.818373 -280.094417) (xy 378.795247 -280.142438) (xy 378.765223 -280.186475)
			(xy 378.728971 -280.225546) (xy 378.6873 -280.258777) (xy 378.641142 -280.285426) (xy 378.591528 -280.304898)
			(xy 378.539566 -280.316758) (xy 378.486416 -280.320742) (xy 378.433266 -280.316758) (xy 378.381304 -280.304898)
			(xy 378.33169 -280.285426) (xy 378.285532 -280.258777) (xy 378.243861 -280.225546) (xy 378.207609 -280.186475)
			(xy 378.177585 -280.142438) (xy 378.154459 -280.094417) (xy 378.138749 -280.043487) (xy 378.130806 -279.990783)
			(xy 377.902226 -279.990783) (xy 377.894283 -280.043487) (xy 377.878573 -280.094417) (xy 377.855447 -280.142438)
			(xy 377.825423 -280.186475) (xy 377.789171 -280.225546) (xy 377.7475 -280.258777) (xy 377.701342 -280.285426)
			(xy 377.651728 -280.304898) (xy 377.599766 -280.316758) (xy 377.546616 -280.320742) (xy 377.493466 -280.316758)
			(xy 377.441504 -280.304898) (xy 377.39189 -280.285426) (xy 377.345732 -280.258777) (xy 377.304061 -280.225546)
			(xy 377.267809 -280.186475) (xy 377.237785 -280.142438) (xy 377.214659 -280.094417) (xy 377.198949 -280.043487)
			(xy 377.191006 -279.990783) (xy 376.962134 -279.990783) (xy 376.954229 -280.043233) (xy 376.938519 -280.094163)
			(xy 376.915393 -280.142184) (xy 376.885369 -280.186221) (xy 376.849117 -280.225292) (xy 376.807446 -280.258523)
			(xy 376.761288 -280.285172) (xy 376.711674 -280.304644) (xy 376.659712 -280.316504) (xy 376.606562 -280.320488)
			(xy 376.553412 -280.316504) (xy 376.50145 -280.304644) (xy 376.451836 -280.285172) (xy 376.405678 -280.258523)
			(xy 376.364007 -280.225292) (xy 376.327755 -280.186221) (xy 376.297731 -280.142184) (xy 376.274605 -280.094163)
			(xy 376.258895 -280.043233) (xy 376.250952 -279.990529) (xy 376.022631 -279.990529) (xy 376.022626 -279.990783)
			(xy 376.014683 -280.043487) (xy 375.998973 -280.094417) (xy 375.975847 -280.142438) (xy 375.945823 -280.186475)
			(xy 375.909571 -280.225546) (xy 375.8679 -280.258777) (xy 375.821742 -280.285426) (xy 375.772128 -280.304898)
			(xy 375.720166 -280.316758) (xy 375.667016 -280.320742) (xy 375.613866 -280.316758) (xy 375.561904 -280.304898)
			(xy 375.51229 -280.285426) (xy 375.466132 -280.258777) (xy 375.424461 -280.225546) (xy 375.388209 -280.186475)
			(xy 375.358185 -280.142438) (xy 375.335059 -280.094417) (xy 375.319349 -280.043487) (xy 375.311406 -279.990783)
			(xy 375.082572 -279.990783) (xy 375.074629 -280.043487) (xy 375.058919 -280.094417) (xy 375.035793 -280.142438)
			(xy 375.005769 -280.186475) (xy 374.969517 -280.225546) (xy 374.927846 -280.258777) (xy 374.881688 -280.285426)
			(xy 374.832074 -280.304898) (xy 374.780112 -280.316758) (xy 374.726962 -280.320742) (xy 374.673812 -280.316758)
			(xy 374.62185 -280.304898) (xy 374.572236 -280.285426) (xy 374.526078 -280.258777) (xy 374.484407 -280.225546)
			(xy 374.448155 -280.186475) (xy 374.418131 -280.142438) (xy 374.395005 -280.094417) (xy 374.379295 -280.043487)
			(xy 374.371352 -279.990783) (xy 374.143026 -279.990783) (xy 374.135083 -280.043487) (xy 374.119373 -280.094417)
			(xy 374.096247 -280.142438) (xy 374.066223 -280.186475) (xy 374.029971 -280.225546) (xy 373.9883 -280.258777)
			(xy 373.942142 -280.285426) (xy 373.892528 -280.304898) (xy 373.840566 -280.316758) (xy 373.787416 -280.320742)
			(xy 373.734266 -280.316758) (xy 373.682304 -280.304898) (xy 373.63269 -280.285426) (xy 373.586532 -280.258777)
			(xy 373.544861 -280.225546) (xy 373.508609 -280.186475) (xy 373.478585 -280.142438) (xy 373.455459 -280.094417)
			(xy 373.439749 -280.043487) (xy 373.431806 -279.990783) (xy 373.203226 -279.990783) (xy 373.195283 -280.043487)
			(xy 373.179573 -280.094417) (xy 373.156447 -280.142438) (xy 373.126423 -280.186475) (xy 373.090171 -280.225546)
			(xy 373.0485 -280.258777) (xy 373.002342 -280.285426) (xy 372.952728 -280.304898) (xy 372.900766 -280.316758)
			(xy 372.847616 -280.320742) (xy 372.794466 -280.316758) (xy 372.742504 -280.304898) (xy 372.69289 -280.285426)
			(xy 372.646732 -280.258777) (xy 372.605061 -280.225546) (xy 372.568809 -280.186475) (xy 372.538785 -280.142438)
			(xy 372.515659 -280.094417) (xy 372.499949 -280.043487) (xy 372.492006 -279.990783) (xy 372.263172 -279.990783)
			(xy 372.255229 -280.043487) (xy 372.239519 -280.094417) (xy 372.216393 -280.142438) (xy 372.186369 -280.186475)
			(xy 372.150117 -280.225546) (xy 372.108446 -280.258777) (xy 372.062288 -280.285426) (xy 372.012674 -280.304898)
			(xy 371.960712 -280.316758) (xy 371.907562 -280.320742) (xy 371.854412 -280.316758) (xy 371.80245 -280.304898)
			(xy 371.752836 -280.285426) (xy 371.706678 -280.258777) (xy 371.665007 -280.225546) (xy 371.628755 -280.186475)
			(xy 371.598731 -280.142438) (xy 371.575605 -280.094417) (xy 371.559895 -280.043487) (xy 371.551952 -279.990783)
			(xy 371.323626 -279.990783) (xy 371.315683 -280.043487) (xy 371.299973 -280.094417) (xy 371.276847 -280.142438)
			(xy 371.246823 -280.186475) (xy 371.210571 -280.225546) (xy 371.1689 -280.258777) (xy 371.122742 -280.285426)
			(xy 371.073128 -280.304898) (xy 371.021166 -280.316758) (xy 370.968016 -280.320742) (xy 370.914866 -280.316758)
			(xy 370.862904 -280.304898) (xy 370.81329 -280.285426) (xy 370.767132 -280.258777) (xy 370.725461 -280.225546)
			(xy 370.689209 -280.186475) (xy 370.659185 -280.142438) (xy 370.636059 -280.094417) (xy 370.620349 -280.043487)
			(xy 370.612406 -279.990783) (xy 370.383826 -279.990783) (xy 370.375883 -280.043487) (xy 370.360173 -280.094417)
			(xy 370.337047 -280.142438) (xy 370.307023 -280.186475) (xy 370.270771 -280.225546) (xy 370.2291 -280.258777)
			(xy 370.182942 -280.285426) (xy 370.133328 -280.304898) (xy 370.081366 -280.316758) (xy 370.028216 -280.320742)
			(xy 369.975066 -280.316758) (xy 369.923104 -280.304898) (xy 369.87349 -280.285426) (xy 369.827332 -280.258777)
			(xy 369.785661 -280.225546) (xy 369.749409 -280.186475) (xy 369.719385 -280.142438) (xy 369.696259 -280.094417)
			(xy 369.680549 -280.043487) (xy 369.672606 -279.990783) (xy 369.444026 -279.990783) (xy 369.436083 -280.043487)
			(xy 369.420373 -280.094417) (xy 369.397247 -280.142438) (xy 369.367223 -280.186475) (xy 369.330971 -280.225546)
			(xy 369.2893 -280.258777) (xy 369.243142 -280.285426) (xy 369.193528 -280.304898) (xy 369.141566 -280.316758)
			(xy 369.088416 -280.320742) (xy 369.035266 -280.316758) (xy 368.983304 -280.304898) (xy 368.93369 -280.285426)
			(xy 368.887532 -280.258777) (xy 368.845861 -280.225546) (xy 368.809609 -280.186475) (xy 368.779585 -280.142438)
			(xy 368.756459 -280.094417) (xy 368.740749 -280.043487) (xy 368.732806 -279.990783) (xy 368.504226 -279.990783)
			(xy 368.496283 -280.043487) (xy 368.480573 -280.094417) (xy 368.457447 -280.142438) (xy 368.427423 -280.186475)
			(xy 368.391171 -280.225546) (xy 368.3495 -280.258777) (xy 368.303342 -280.285426) (xy 368.253728 -280.304898)
			(xy 368.201766 -280.316758) (xy 368.148616 -280.320742) (xy 368.095466 -280.316758) (xy 368.043504 -280.304898)
			(xy 367.99389 -280.285426) (xy 367.947732 -280.258777) (xy 367.906061 -280.225546) (xy 367.869809 -280.186475)
			(xy 367.839785 -280.142438) (xy 367.816659 -280.094417) (xy 367.800949 -280.043487) (xy 367.793006 -279.990783)
			(xy 367.564426 -279.990783) (xy 367.556483 -280.043487) (xy 367.540773 -280.094417) (xy 367.517647 -280.142438)
			(xy 367.487623 -280.186475) (xy 367.451371 -280.225546) (xy 367.4097 -280.258777) (xy 367.363542 -280.285426)
			(xy 367.313928 -280.304898) (xy 367.261966 -280.316758) (xy 367.208816 -280.320742) (xy 367.155666 -280.316758)
			(xy 367.103704 -280.304898) (xy 367.05409 -280.285426) (xy 367.007932 -280.258777) (xy 366.966261 -280.225546)
			(xy 366.930009 -280.186475) (xy 366.899985 -280.142438) (xy 366.876859 -280.094417) (xy 366.861149 -280.043487)
			(xy 366.853206 -279.990783) (xy 366.624372 -279.990783) (xy 366.616429 -280.043487) (xy 366.600719 -280.094417)
			(xy 366.577593 -280.142438) (xy 366.547569 -280.186475) (xy 366.511317 -280.225546) (xy 366.469646 -280.258777)
			(xy 366.423488 -280.285426) (xy 366.373874 -280.304898) (xy 366.321912 -280.316758) (xy 366.268762 -280.320742)
			(xy 366.215612 -280.316758) (xy 366.16365 -280.304898) (xy 366.114036 -280.285426) (xy 366.067878 -280.258777)
			(xy 366.026207 -280.225546) (xy 365.989955 -280.186475) (xy 365.959931 -280.142438) (xy 365.936805 -280.094417)
			(xy 365.921095 -280.043487) (xy 365.913152 -279.990783) (xy 365.684826 -279.990783) (xy 365.676883 -280.043487)
			(xy 365.661173 -280.094417) (xy 365.638047 -280.142438) (xy 365.608023 -280.186475) (xy 365.571771 -280.225546)
			(xy 365.5301 -280.258777) (xy 365.483942 -280.285426) (xy 365.434328 -280.304898) (xy 365.382366 -280.316758)
			(xy 365.329216 -280.320742) (xy 365.276066 -280.316758) (xy 365.224104 -280.304898) (xy 365.17449 -280.285426)
			(xy 365.128332 -280.258777) (xy 365.086661 -280.225546) (xy 365.050409 -280.186475) (xy 365.020385 -280.142438)
			(xy 364.997259 -280.094417) (xy 364.981549 -280.043487) (xy 364.973606 -279.990783) (xy 364.745026 -279.990783)
			(xy 364.737083 -280.043487) (xy 364.721373 -280.094417) (xy 364.698247 -280.142438) (xy 364.668223 -280.186475)
			(xy 364.631971 -280.225546) (xy 364.5903 -280.258777) (xy 364.544142 -280.285426) (xy 364.494528 -280.304898)
			(xy 364.442566 -280.316758) (xy 364.389416 -280.320742) (xy 364.336266 -280.316758) (xy 364.284304 -280.304898)
			(xy 364.23469 -280.285426) (xy 364.188532 -280.258777) (xy 364.146861 -280.225546) (xy 364.110609 -280.186475)
			(xy 364.080585 -280.142438) (xy 364.057459 -280.094417) (xy 364.041749 -280.043487) (xy 364.033806 -279.990783)
			(xy 361.925372 -279.990783) (xy 361.917429 -280.043487) (xy 361.901719 -280.094417) (xy 361.878593 -280.142438)
			(xy 361.848569 -280.186475) (xy 361.812317 -280.225546) (xy 361.770646 -280.258777) (xy 361.724488 -280.285426)
			(xy 361.674874 -280.304898) (xy 361.622912 -280.316758) (xy 361.569762 -280.320742) (xy 361.516612 -280.316758)
			(xy 361.46465 -280.304898) (xy 361.415036 -280.285426) (xy 361.368878 -280.258777) (xy 361.327207 -280.225546)
			(xy 361.290955 -280.186475) (xy 361.260931 -280.142438) (xy 361.237805 -280.094417) (xy 361.222095 -280.043487)
			(xy 361.214152 -279.990783) (xy 356.286572 -279.990783) (xy 356.278629 -280.043487) (xy 356.262919 -280.094417)
			(xy 356.239793 -280.142438) (xy 356.209769 -280.186475) (xy 356.173517 -280.225546) (xy 356.131846 -280.258777)
			(xy 356.085688 -280.285426) (xy 356.036074 -280.304898) (xy 355.984112 -280.316758) (xy 355.930962 -280.320742)
			(xy 355.877812 -280.316758) (xy 355.82585 -280.304898) (xy 355.776236 -280.285426) (xy 355.730078 -280.258777)
			(xy 355.688407 -280.225546) (xy 355.652155 -280.186475) (xy 355.622131 -280.142438) (xy 355.599005 -280.094417)
			(xy 355.583295 -280.043487) (xy 355.575352 -279.990783) (xy 355.347026 -279.990783) (xy 355.339083 -280.043487)
			(xy 355.323373 -280.094417) (xy 355.300247 -280.142438) (xy 355.270223 -280.186475) (xy 355.233971 -280.225546)
			(xy 355.1923 -280.258777) (xy 355.146142 -280.285426) (xy 355.096528 -280.304898) (xy 355.044566 -280.316758)
			(xy 354.991416 -280.320742) (xy 354.938266 -280.316758) (xy 354.886304 -280.304898) (xy 354.83669 -280.285426)
			(xy 354.790532 -280.258777) (xy 354.748861 -280.225546) (xy 354.712609 -280.186475) (xy 354.682585 -280.142438)
			(xy 354.659459 -280.094417) (xy 354.643749 -280.043487) (xy 354.635806 -279.990783) (xy 354.407226 -279.990783)
			(xy 354.399283 -280.043487) (xy 354.383573 -280.094417) (xy 354.360447 -280.142438) (xy 354.330423 -280.186475)
			(xy 354.294171 -280.225546) (xy 354.2525 -280.258777) (xy 354.206342 -280.285426) (xy 354.156728 -280.304898)
			(xy 354.104766 -280.316758) (xy 354.051616 -280.320742) (xy 353.998466 -280.316758) (xy 353.946504 -280.304898)
			(xy 353.89689 -280.285426) (xy 353.850732 -280.258777) (xy 353.809061 -280.225546) (xy 353.772809 -280.186475)
			(xy 353.742785 -280.142438) (xy 353.719659 -280.094417) (xy 353.703949 -280.043487) (xy 353.696006 -279.990783)
			(xy 353.440839 -279.990783) (xy 353.433264 -280.039615) (xy 353.417903 -280.087953) (xy 353.395319 -280.133367)
			(xy 353.366044 -280.174786) (xy 353.330769 -280.211231) (xy 353.290329 -280.241842) (xy 353.245676 -280.265897)
			(xy 353.197865 -280.282828) (xy 353.17303 -280.287984) (xy 353.149916 -280.292302) (xy 353.024694 -280.509472)
			(xy 353.024694 -280.804105) (xy 353.25232 -280.804105) (xy 353.25232 -280.752295) (xy 353.260425 -280.701122)
			(xy 353.276434 -280.651848) (xy 353.299953 -280.605684) (xy 353.330405 -280.563767) (xy 353.367038 -280.527129)
			(xy 353.408951 -280.496673) (xy 353.455113 -280.473148) (xy 353.504385 -280.457133) (xy 353.555557 -280.449023)
			(xy 353.581462 -280.448512) (xy 353.606973 -280.449015) (xy 353.657387 -280.45687) (xy 353.705988 -280.472399)
			(xy 353.751617 -280.49523) (xy 353.793183 -280.524819) (xy 353.829694 -280.560459) (xy 353.845368 -280.580592)
			(xy 354.257356 -280.580592) (xy 354.273053 -280.560476) (xy 354.309558 -280.524831) (xy 354.351119 -280.495236)
			(xy 354.396742 -280.472396) (xy 354.44534 -280.456858) (xy 354.495751 -280.448992) (xy 354.521262 -280.448512)
			(xy 354.547174 -280.448983) (xy 354.59836 -280.457084) (xy 354.647648 -280.473094) (xy 354.693825 -280.496618)
			(xy 354.735753 -280.527076) (xy 354.7724 -280.563718) (xy 354.802863 -280.605643) (xy 354.826391 -280.651817)
			(xy 354.842407 -280.701103) (xy 354.850514 -280.752288) (xy 354.850514 -280.804112) (xy 354.850397 -280.804853)
			(xy 355.105452 -280.804853) (xy 355.105452 -280.751555) (xy 355.113395 -280.698851) (xy 355.129105 -280.647921)
			(xy 355.152231 -280.5999) (xy 355.182255 -280.555863) (xy 355.218507 -280.516792) (xy 355.260178 -280.483561)
			(xy 355.306336 -280.456912) (xy 355.35595 -280.43744) (xy 355.407912 -280.42558) (xy 355.461062 -280.421597)
			(xy 355.514212 -280.42558) (xy 355.566174 -280.43744) (xy 355.615788 -280.456912) (xy 355.661946 -280.483561)
			(xy 355.703617 -280.516792) (xy 355.739869 -280.555863) (xy 355.769893 -280.5999) (xy 355.793019 -280.647921)
			(xy 355.808729 -280.698851) (xy 355.816672 -280.751555) (xy 355.81717 -280.778204) (xy 355.816672 -280.804853)
			(xy 357.924852 -280.804853) (xy 357.924852 -280.751555) (xy 357.932795 -280.698851) (xy 357.948505 -280.647921)
			(xy 357.971631 -280.5999) (xy 358.001655 -280.555863) (xy 358.037907 -280.516792) (xy 358.079578 -280.483561)
			(xy 358.125736 -280.456912) (xy 358.17535 -280.43744) (xy 358.227312 -280.42558) (xy 358.280462 -280.421597)
			(xy 358.333612 -280.42558) (xy 358.385574 -280.43744) (xy 358.435188 -280.456912) (xy 358.481346 -280.483561)
			(xy 358.523017 -280.516792) (xy 358.559269 -280.555863) (xy 358.589293 -280.5999) (xy 358.612419 -280.647921)
			(xy 358.628129 -280.698851) (xy 358.636072 -280.751555) (xy 358.63657 -280.778204) (xy 358.636072 -280.804853)
			(xy 364.503706 -280.804853) (xy 364.503706 -280.751555) (xy 364.511649 -280.698851) (xy 364.527359 -280.647921)
			(xy 364.550485 -280.5999) (xy 364.580509 -280.555863) (xy 364.616761 -280.516792) (xy 364.658432 -280.483561)
			(xy 364.70459 -280.456912) (xy 364.754204 -280.43744) (xy 364.806166 -280.42558) (xy 364.859316 -280.421597)
			(xy 364.912466 -280.42558) (xy 364.964428 -280.43744) (xy 365.014042 -280.456912) (xy 365.0602 -280.483561)
			(xy 365.101871 -280.516792) (xy 365.138123 -280.555863) (xy 365.168147 -280.5999) (xy 365.191273 -280.647921)
			(xy 365.206983 -280.698851) (xy 365.214926 -280.751555) (xy 365.215424 -280.778204) (xy 365.214926 -280.804853)
			(xy 365.443506 -280.804853) (xy 365.443506 -280.751555) (xy 365.451449 -280.698851) (xy 365.467159 -280.647921)
			(xy 365.490285 -280.5999) (xy 365.520309 -280.555863) (xy 365.556561 -280.516792) (xy 365.598232 -280.483561)
			(xy 365.64439 -280.456912) (xy 365.694004 -280.43744) (xy 365.745966 -280.42558) (xy 365.799116 -280.421597)
			(xy 365.852266 -280.42558) (xy 365.904228 -280.43744) (xy 365.953842 -280.456912) (xy 366 -280.483561)
			(xy 366.041671 -280.516792) (xy 366.077923 -280.555863) (xy 366.107947 -280.5999) (xy 366.131073 -280.647921)
			(xy 366.146783 -280.698851) (xy 366.154726 -280.751555) (xy 366.155224 -280.778204) (xy 366.154726 -280.804853)
			(xy 366.383052 -280.804853) (xy 366.383052 -280.751555) (xy 366.390995 -280.698851) (xy 366.406705 -280.647921)
			(xy 366.429831 -280.5999) (xy 366.459855 -280.555863) (xy 366.496107 -280.516792) (xy 366.537778 -280.483561)
			(xy 366.583936 -280.456912) (xy 366.63355 -280.43744) (xy 366.685512 -280.42558) (xy 366.738662 -280.421597)
			(xy 366.791812 -280.42558) (xy 366.843774 -280.43744) (xy 366.893388 -280.456912) (xy 366.939546 -280.483561)
			(xy 366.981217 -280.516792) (xy 367.017469 -280.555863) (xy 367.047493 -280.5999) (xy 367.070619 -280.647921)
			(xy 367.086329 -280.698851) (xy 367.094272 -280.751555) (xy 367.09477 -280.778204) (xy 367.094272 -280.804853)
			(xy 367.322852 -280.804853) (xy 367.322852 -280.751555) (xy 367.330795 -280.698851) (xy 367.346505 -280.647921)
			(xy 367.369631 -280.5999) (xy 367.399655 -280.555863) (xy 367.435907 -280.516792) (xy 367.477578 -280.483561)
			(xy 367.523736 -280.456912) (xy 367.57335 -280.43744) (xy 367.625312 -280.42558) (xy 367.678462 -280.421597)
			(xy 367.731612 -280.42558) (xy 367.783574 -280.43744) (xy 367.833188 -280.456912) (xy 367.879346 -280.483561)
			(xy 367.921017 -280.516792) (xy 367.957269 -280.555863) (xy 367.987293 -280.5999) (xy 368.010419 -280.647921)
			(xy 368.026129 -280.698851) (xy 368.034072 -280.751555) (xy 368.03457 -280.778204) (xy 368.034072 -280.804853)
			(xy 368.262652 -280.804853) (xy 368.262652 -280.751555) (xy 368.270595 -280.698851) (xy 368.286305 -280.647921)
			(xy 368.309431 -280.5999) (xy 368.339455 -280.555863) (xy 368.375707 -280.516792) (xy 368.417378 -280.483561)
			(xy 368.463536 -280.456912) (xy 368.51315 -280.43744) (xy 368.565112 -280.42558) (xy 368.618262 -280.421597)
			(xy 368.671412 -280.42558) (xy 368.723374 -280.43744) (xy 368.772988 -280.456912) (xy 368.819146 -280.483561)
			(xy 368.860817 -280.516792) (xy 368.897069 -280.555863) (xy 368.927093 -280.5999) (xy 368.950219 -280.647921)
			(xy 368.965929 -280.698851) (xy 368.973872 -280.751555) (xy 368.97437 -280.778204) (xy 368.973872 -280.804853)
			(xy 369.202452 -280.804853) (xy 369.202452 -280.751555) (xy 369.210395 -280.698851) (xy 369.226105 -280.647921)
			(xy 369.249231 -280.5999) (xy 369.279255 -280.555863) (xy 369.315507 -280.516792) (xy 369.357178 -280.483561)
			(xy 369.403336 -280.456912) (xy 369.45295 -280.43744) (xy 369.504912 -280.42558) (xy 369.558062 -280.421597)
			(xy 369.611212 -280.42558) (xy 369.663174 -280.43744) (xy 369.712788 -280.456912) (xy 369.758946 -280.483561)
			(xy 369.800617 -280.516792) (xy 369.836869 -280.555863) (xy 369.866893 -280.5999) (xy 369.890019 -280.647921)
			(xy 369.905729 -280.698851) (xy 369.913672 -280.751555) (xy 369.91417 -280.778204) (xy 369.913672 -280.804853)
			(xy 370.142252 -280.804853) (xy 370.142252 -280.751555) (xy 370.150195 -280.698851) (xy 370.165905 -280.647921)
			(xy 370.189031 -280.5999) (xy 370.219055 -280.555863) (xy 370.255307 -280.516792) (xy 370.296978 -280.483561)
			(xy 370.343136 -280.456912) (xy 370.39275 -280.43744) (xy 370.444712 -280.42558) (xy 370.497862 -280.421597)
			(xy 370.551012 -280.42558) (xy 370.602974 -280.43744) (xy 370.652588 -280.456912) (xy 370.698746 -280.483561)
			(xy 370.740417 -280.516792) (xy 370.776669 -280.555863) (xy 370.806693 -280.5999) (xy 370.829819 -280.647921)
			(xy 370.845529 -280.698851) (xy 370.853472 -280.751555) (xy 370.85397 -280.778204) (xy 370.853472 -280.804853)
			(xy 371.082052 -280.804853) (xy 371.082052 -280.751555) (xy 371.089995 -280.698851) (xy 371.105705 -280.647921)
			(xy 371.128831 -280.5999) (xy 371.158855 -280.555863) (xy 371.195107 -280.516792) (xy 371.236778 -280.483561)
			(xy 371.282936 -280.456912) (xy 371.33255 -280.43744) (xy 371.384512 -280.42558) (xy 371.437662 -280.421597)
			(xy 371.490812 -280.42558) (xy 371.542774 -280.43744) (xy 371.592388 -280.456912) (xy 371.638546 -280.483561)
			(xy 371.680217 -280.516792) (xy 371.716469 -280.555863) (xy 371.746493 -280.5999) (xy 371.769619 -280.647921)
			(xy 371.785329 -280.698851) (xy 371.793272 -280.751555) (xy 371.79377 -280.778204) (xy 371.793272 -280.804853)
			(xy 372.021852 -280.804853) (xy 372.021852 -280.751555) (xy 372.029795 -280.698851) (xy 372.045505 -280.647921)
			(xy 372.068631 -280.5999) (xy 372.098655 -280.555863) (xy 372.134907 -280.516792) (xy 372.176578 -280.483561)
			(xy 372.222736 -280.456912) (xy 372.27235 -280.43744) (xy 372.324312 -280.42558) (xy 372.377462 -280.421597)
			(xy 372.430612 -280.42558) (xy 372.482574 -280.43744) (xy 372.532188 -280.456912) (xy 372.578346 -280.483561)
			(xy 372.620017 -280.516792) (xy 372.656269 -280.555863) (xy 372.686293 -280.5999) (xy 372.709419 -280.647921)
			(xy 372.725129 -280.698851) (xy 372.733072 -280.751555) (xy 372.73357 -280.778204) (xy 372.733072 -280.804853)
			(xy 372.961652 -280.804853) (xy 372.961652 -280.751555) (xy 372.969595 -280.698851) (xy 372.985305 -280.647921)
			(xy 373.008431 -280.5999) (xy 373.038455 -280.555863) (xy 373.074707 -280.516792) (xy 373.116378 -280.483561)
			(xy 373.162536 -280.456912) (xy 373.21215 -280.43744) (xy 373.264112 -280.42558) (xy 373.317262 -280.421597)
			(xy 373.370412 -280.42558) (xy 373.422374 -280.43744) (xy 373.471988 -280.456912) (xy 373.518146 -280.483561)
			(xy 373.559817 -280.516792) (xy 373.596069 -280.555863) (xy 373.626093 -280.5999) (xy 373.649219 -280.647921)
			(xy 373.664929 -280.698851) (xy 373.672872 -280.751555) (xy 373.67337 -280.778204) (xy 373.672872 -280.804853)
			(xy 373.901706 -280.804853) (xy 373.901706 -280.751555) (xy 373.909649 -280.698851) (xy 373.925359 -280.647921)
			(xy 373.948485 -280.5999) (xy 373.978509 -280.555863) (xy 374.014761 -280.516792) (xy 374.056432 -280.483561)
			(xy 374.10259 -280.456912) (xy 374.152204 -280.43744) (xy 374.204166 -280.42558) (xy 374.257316 -280.421597)
			(xy 374.310466 -280.42558) (xy 374.362428 -280.43744) (xy 374.412042 -280.456912) (xy 374.4582 -280.483561)
			(xy 374.499871 -280.516792) (xy 374.536123 -280.555863) (xy 374.566147 -280.5999) (xy 374.589273 -280.647921)
			(xy 374.604983 -280.698851) (xy 374.612926 -280.751555) (xy 374.613424 -280.778204) (xy 374.612926 -280.804853)
			(xy 374.841506 -280.804853) (xy 374.841506 -280.751555) (xy 374.849449 -280.698851) (xy 374.865159 -280.647921)
			(xy 374.888285 -280.5999) (xy 374.918309 -280.555863) (xy 374.954561 -280.516792) (xy 374.996232 -280.483561)
			(xy 375.04239 -280.456912) (xy 375.092004 -280.43744) (xy 375.143966 -280.42558) (xy 375.197116 -280.421597)
			(xy 375.250266 -280.42558) (xy 375.302228 -280.43744) (xy 375.351842 -280.456912) (xy 375.398 -280.483561)
			(xy 375.439671 -280.516792) (xy 375.475923 -280.555863) (xy 375.505947 -280.5999) (xy 375.529073 -280.647921)
			(xy 375.544783 -280.698851) (xy 375.552726 -280.751555) (xy 375.553224 -280.778204) (xy 375.552726 -280.804853)
			(xy 375.781306 -280.804853) (xy 375.781306 -280.751555) (xy 375.789249 -280.698851) (xy 375.804959 -280.647921)
			(xy 375.828085 -280.5999) (xy 375.858109 -280.555863) (xy 375.894361 -280.516792) (xy 375.936032 -280.483561)
			(xy 375.98219 -280.456912) (xy 376.031804 -280.43744) (xy 376.083766 -280.42558) (xy 376.136916 -280.421597)
			(xy 376.190066 -280.42558) (xy 376.242028 -280.43744) (xy 376.291642 -280.456912) (xy 376.3378 -280.483561)
			(xy 376.379471 -280.516792) (xy 376.415723 -280.555863) (xy 376.445747 -280.5999) (xy 376.468873 -280.647921)
			(xy 376.484583 -280.698851) (xy 376.492526 -280.751555) (xy 376.493024 -280.778204) (xy 376.492526 -280.804853)
			(xy 376.721106 -280.804853) (xy 376.721106 -280.751555) (xy 376.729049 -280.698851) (xy 376.744759 -280.647921)
			(xy 376.767885 -280.5999) (xy 376.797909 -280.555863) (xy 376.834161 -280.516792) (xy 376.875832 -280.483561)
			(xy 376.92199 -280.456912) (xy 376.971604 -280.43744) (xy 377.023566 -280.42558) (xy 377.076716 -280.421597)
			(xy 377.129866 -280.42558) (xy 377.181828 -280.43744) (xy 377.231442 -280.456912) (xy 377.2776 -280.483561)
			(xy 377.319271 -280.516792) (xy 377.355523 -280.555863) (xy 377.385547 -280.5999) (xy 377.408673 -280.647921)
			(xy 377.424383 -280.698851) (xy 377.432326 -280.751555) (xy 377.432824 -280.778204) (xy 377.432326 -280.804853)
			(xy 377.660906 -280.804853) (xy 377.660906 -280.751555) (xy 377.668849 -280.698851) (xy 377.684559 -280.647921)
			(xy 377.707685 -280.5999) (xy 377.737709 -280.555863) (xy 377.773961 -280.516792) (xy 377.815632 -280.483561)
			(xy 377.86179 -280.456912) (xy 377.911404 -280.43744) (xy 377.963366 -280.42558) (xy 378.016516 -280.421597)
			(xy 378.069666 -280.42558) (xy 378.121628 -280.43744) (xy 378.171242 -280.456912) (xy 378.2174 -280.483561)
			(xy 378.259071 -280.516792) (xy 378.295323 -280.555863) (xy 378.325347 -280.5999) (xy 378.348473 -280.647921)
			(xy 378.364183 -280.698851) (xy 378.372126 -280.751555) (xy 378.372624 -280.778204) (xy 378.372126 -280.804853)
			(xy 378.600452 -280.804853) (xy 378.600452 -280.751555) (xy 378.608395 -280.698851) (xy 378.624105 -280.647921)
			(xy 378.647231 -280.5999) (xy 378.677255 -280.555863) (xy 378.713507 -280.516792) (xy 378.755178 -280.483561)
			(xy 378.801336 -280.456912) (xy 378.85095 -280.43744) (xy 378.902912 -280.42558) (xy 378.956062 -280.421597)
			(xy 379.009212 -280.42558) (xy 379.061174 -280.43744) (xy 379.110788 -280.456912) (xy 379.156946 -280.483561)
			(xy 379.198617 -280.516792) (xy 379.234869 -280.555863) (xy 379.264893 -280.5999) (xy 379.288019 -280.647921)
			(xy 379.303729 -280.698851) (xy 379.311672 -280.751555) (xy 379.31217 -280.778204) (xy 379.311672 -280.804853)
			(xy 379.540252 -280.804853) (xy 379.540252 -280.751555) (xy 379.548195 -280.698851) (xy 379.563905 -280.647921)
			(xy 379.587031 -280.5999) (xy 379.617055 -280.555863) (xy 379.653307 -280.516792) (xy 379.694978 -280.483561)
			(xy 379.741136 -280.456912) (xy 379.79075 -280.43744) (xy 379.842712 -280.42558) (xy 379.895862 -280.421597)
			(xy 379.949012 -280.42558) (xy 380.000974 -280.43744) (xy 380.050588 -280.456912) (xy 380.096746 -280.483561)
			(xy 380.138417 -280.516792) (xy 380.174669 -280.555863) (xy 380.204693 -280.5999) (xy 380.227819 -280.647921)
			(xy 380.243529 -280.698851) (xy 380.251472 -280.751555) (xy 380.25197 -280.778204) (xy 380.251472 -280.804853)
			(xy 380.480052 -280.804853) (xy 380.480052 -280.751555) (xy 380.487995 -280.698851) (xy 380.503705 -280.647921)
			(xy 380.526831 -280.5999) (xy 380.556855 -280.555863) (xy 380.593107 -280.516792) (xy 380.634778 -280.483561)
			(xy 380.680936 -280.456912) (xy 380.73055 -280.43744) (xy 380.782512 -280.42558) (xy 380.835662 -280.421597)
			(xy 380.888812 -280.42558) (xy 380.940774 -280.43744) (xy 380.990388 -280.456912) (xy 381.036546 -280.483561)
			(xy 381.078217 -280.516792) (xy 381.114469 -280.555863) (xy 381.144493 -280.5999) (xy 381.167619 -280.647921)
			(xy 381.183329 -280.698851) (xy 381.191272 -280.751555) (xy 381.19177 -280.778204) (xy 381.191272 -280.804853)
			(xy 381.419852 -280.804853) (xy 381.419852 -280.751555) (xy 381.427795 -280.698851) (xy 381.443505 -280.647921)
			(xy 381.466631 -280.5999) (xy 381.496655 -280.555863) (xy 381.532907 -280.516792) (xy 381.574578 -280.483561)
			(xy 381.620736 -280.456912) (xy 381.67035 -280.43744) (xy 381.722312 -280.42558) (xy 381.775462 -280.421597)
			(xy 381.828612 -280.42558) (xy 381.880574 -280.43744) (xy 381.930188 -280.456912) (xy 381.976346 -280.483561)
			(xy 382.018017 -280.516792) (xy 382.054269 -280.555863) (xy 382.084293 -280.5999) (xy 382.107419 -280.647921)
			(xy 382.123129 -280.698851) (xy 382.131072 -280.751555) (xy 382.13157 -280.778204) (xy 382.131072 -280.804853)
			(xy 382.359652 -280.804853) (xy 382.359652 -280.751555) (xy 382.367595 -280.698851) (xy 382.383305 -280.647921)
			(xy 382.406431 -280.5999) (xy 382.436455 -280.555863) (xy 382.472707 -280.516792) (xy 382.514378 -280.483561)
			(xy 382.560536 -280.456912) (xy 382.61015 -280.43744) (xy 382.662112 -280.42558) (xy 382.715262 -280.421597)
			(xy 382.768412 -280.42558) (xy 382.820374 -280.43744) (xy 382.869988 -280.456912) (xy 382.916146 -280.483561)
			(xy 382.957817 -280.516792) (xy 382.994069 -280.555863) (xy 383.024093 -280.5999) (xy 383.047219 -280.647921)
			(xy 383.062929 -280.698851) (xy 383.070872 -280.751555) (xy 383.07137 -280.778204) (xy 383.070872 -280.804853)
			(xy 383.299452 -280.804853) (xy 383.299452 -280.751555) (xy 383.307395 -280.698851) (xy 383.323105 -280.647921)
			(xy 383.346231 -280.5999) (xy 383.376255 -280.555863) (xy 383.412507 -280.516792) (xy 383.454178 -280.483561)
			(xy 383.500336 -280.456912) (xy 383.54995 -280.43744) (xy 383.601912 -280.42558) (xy 383.655062 -280.421597)
			(xy 383.708212 -280.42558) (xy 383.760174 -280.43744) (xy 383.809788 -280.456912) (xy 383.855946 -280.483561)
			(xy 383.897617 -280.516792) (xy 383.933869 -280.555863) (xy 383.963893 -280.5999) (xy 383.987019 -280.647921)
			(xy 384.002729 -280.698851) (xy 384.010672 -280.751555) (xy 384.01117 -280.778204) (xy 384.010672 -280.804853)
			(xy 384.239252 -280.804853) (xy 384.239252 -280.751555) (xy 384.247195 -280.698851) (xy 384.262905 -280.647921)
			(xy 384.286031 -280.5999) (xy 384.316055 -280.555863) (xy 384.352307 -280.516792) (xy 384.393978 -280.483561)
			(xy 384.440136 -280.456912) (xy 384.48975 -280.43744) (xy 384.541712 -280.42558) (xy 384.594862 -280.421597)
			(xy 384.648012 -280.42558) (xy 384.699974 -280.43744) (xy 384.749588 -280.456912) (xy 384.795746 -280.483561)
			(xy 384.837417 -280.516792) (xy 384.873669 -280.555863) (xy 384.903693 -280.5999) (xy 384.926819 -280.647921)
			(xy 384.942529 -280.698851) (xy 384.950472 -280.751555) (xy 384.95097 -280.778204) (xy 384.950472 -280.804853)
			(xy 385.179052 -280.804853) (xy 385.179052 -280.751555) (xy 385.186995 -280.698851) (xy 385.202705 -280.647921)
			(xy 385.225831 -280.5999) (xy 385.255855 -280.555863) (xy 385.292107 -280.516792) (xy 385.333778 -280.483561)
			(xy 385.379936 -280.456912) (xy 385.42955 -280.43744) (xy 385.481512 -280.42558) (xy 385.534662 -280.421597)
			(xy 385.587812 -280.42558) (xy 385.639774 -280.43744) (xy 385.689388 -280.456912) (xy 385.735546 -280.483561)
			(xy 385.777217 -280.516792) (xy 385.813469 -280.555863) (xy 385.843493 -280.5999) (xy 385.866619 -280.647921)
			(xy 385.882329 -280.698851) (xy 385.890272 -280.751555) (xy 385.89077 -280.778204) (xy 385.890272 -280.804853)
			(xy 386.119106 -280.804853) (xy 386.119106 -280.751555) (xy 386.127049 -280.698851) (xy 386.142759 -280.647921)
			(xy 386.165885 -280.5999) (xy 386.195909 -280.555863) (xy 386.232161 -280.516792) (xy 386.273832 -280.483561)
			(xy 386.31999 -280.456912) (xy 386.369604 -280.43744) (xy 386.421566 -280.42558) (xy 386.474716 -280.421597)
			(xy 386.527866 -280.42558) (xy 386.579828 -280.43744) (xy 386.629442 -280.456912) (xy 386.6756 -280.483561)
			(xy 386.717271 -280.516792) (xy 386.753523 -280.555863) (xy 386.783547 -280.5999) (xy 386.806673 -280.647921)
			(xy 386.822383 -280.698851) (xy 386.830326 -280.751555) (xy 386.830824 -280.778204) (xy 386.830326 -280.804853)
			(xy 386.822383 -280.857557) (xy 386.806673 -280.908487) (xy 386.783547 -280.956508) (xy 386.753523 -281.000545)
			(xy 386.717271 -281.039616) (xy 386.6756 -281.072847) (xy 386.629442 -281.099496) (xy 386.579828 -281.118968)
			(xy 386.527866 -281.130828) (xy 386.474716 -281.134812) (xy 386.421566 -281.130828) (xy 386.369604 -281.118968)
			(xy 386.31999 -281.099496) (xy 386.273832 -281.072847) (xy 386.232161 -281.039616) (xy 386.195909 -281.000545)
			(xy 386.165885 -280.956508) (xy 386.142759 -280.908487) (xy 386.127049 -280.857557) (xy 386.119106 -280.804853)
			(xy 385.890272 -280.804853) (xy 385.882329 -280.857557) (xy 385.866619 -280.908487) (xy 385.843493 -280.956508)
			(xy 385.813469 -281.000545) (xy 385.777217 -281.039616) (xy 385.735546 -281.072847) (xy 385.689388 -281.099496)
			(xy 385.639774 -281.118968) (xy 385.587812 -281.130828) (xy 385.534662 -281.134812) (xy 385.481512 -281.130828)
			(xy 385.42955 -281.118968) (xy 385.379936 -281.099496) (xy 385.333778 -281.072847) (xy 385.292107 -281.039616)
			(xy 385.255855 -281.000545) (xy 385.225831 -280.956508) (xy 385.202705 -280.908487) (xy 385.186995 -280.857557)
			(xy 385.179052 -280.804853) (xy 384.950472 -280.804853) (xy 384.942529 -280.857557) (xy 384.926819 -280.908487)
			(xy 384.903693 -280.956508) (xy 384.873669 -281.000545) (xy 384.837417 -281.039616) (xy 384.795746 -281.072847)
			(xy 384.749588 -281.099496) (xy 384.699974 -281.118968) (xy 384.648012 -281.130828) (xy 384.594862 -281.134812)
			(xy 384.541712 -281.130828) (xy 384.48975 -281.118968) (xy 384.440136 -281.099496) (xy 384.393978 -281.072847)
			(xy 384.352307 -281.039616) (xy 384.316055 -281.000545) (xy 384.286031 -280.956508) (xy 384.262905 -280.908487)
			(xy 384.247195 -280.857557) (xy 384.239252 -280.804853) (xy 384.010672 -280.804853) (xy 384.002729 -280.857557)
			(xy 383.987019 -280.908487) (xy 383.963893 -280.956508) (xy 383.933869 -281.000545) (xy 383.897617 -281.039616)
			(xy 383.855946 -281.072847) (xy 383.809788 -281.099496) (xy 383.760174 -281.118968) (xy 383.708212 -281.130828)
			(xy 383.655062 -281.134812) (xy 383.601912 -281.130828) (xy 383.54995 -281.118968) (xy 383.500336 -281.099496)
			(xy 383.454178 -281.072847) (xy 383.412507 -281.039616) (xy 383.376255 -281.000545) (xy 383.346231 -280.956508)
			(xy 383.323105 -280.908487) (xy 383.307395 -280.857557) (xy 383.299452 -280.804853) (xy 383.070872 -280.804853)
			(xy 383.062929 -280.857557) (xy 383.047219 -280.908487) (xy 383.024093 -280.956508) (xy 382.994069 -281.000545)
			(xy 382.957817 -281.039616) (xy 382.916146 -281.072847) (xy 382.869988 -281.099496) (xy 382.820374 -281.118968)
			(xy 382.768412 -281.130828) (xy 382.715262 -281.134812) (xy 382.662112 -281.130828) (xy 382.61015 -281.118968)
			(xy 382.560536 -281.099496) (xy 382.514378 -281.072847) (xy 382.472707 -281.039616) (xy 382.436455 -281.000545)
			(xy 382.406431 -280.956508) (xy 382.383305 -280.908487) (xy 382.367595 -280.857557) (xy 382.359652 -280.804853)
			(xy 382.131072 -280.804853) (xy 382.123129 -280.857557) (xy 382.107419 -280.908487) (xy 382.084293 -280.956508)
			(xy 382.054269 -281.000545) (xy 382.018017 -281.039616) (xy 381.976346 -281.072847) (xy 381.930188 -281.099496)
			(xy 381.880574 -281.118968) (xy 381.828612 -281.130828) (xy 381.775462 -281.134812) (xy 381.722312 -281.130828)
			(xy 381.67035 -281.118968) (xy 381.620736 -281.099496) (xy 381.574578 -281.072847) (xy 381.532907 -281.039616)
			(xy 381.496655 -281.000545) (xy 381.466631 -280.956508) (xy 381.443505 -280.908487) (xy 381.427795 -280.857557)
			(xy 381.419852 -280.804853) (xy 381.191272 -280.804853) (xy 381.183329 -280.857557) (xy 381.167619 -280.908487)
			(xy 381.144493 -280.956508) (xy 381.114469 -281.000545) (xy 381.078217 -281.039616) (xy 381.036546 -281.072847)
			(xy 380.990388 -281.099496) (xy 380.940774 -281.118968) (xy 380.888812 -281.130828) (xy 380.835662 -281.134812)
			(xy 380.782512 -281.130828) (xy 380.73055 -281.118968) (xy 380.680936 -281.099496) (xy 380.634778 -281.072847)
			(xy 380.593107 -281.039616) (xy 380.556855 -281.000545) (xy 380.526831 -280.956508) (xy 380.503705 -280.908487)
			(xy 380.487995 -280.857557) (xy 380.480052 -280.804853) (xy 380.251472 -280.804853) (xy 380.243529 -280.857557)
			(xy 380.227819 -280.908487) (xy 380.204693 -280.956508) (xy 380.174669 -281.000545) (xy 380.138417 -281.039616)
			(xy 380.096746 -281.072847) (xy 380.050588 -281.099496) (xy 380.000974 -281.118968) (xy 379.949012 -281.130828)
			(xy 379.895862 -281.134812) (xy 379.842712 -281.130828) (xy 379.79075 -281.118968) (xy 379.741136 -281.099496)
			(xy 379.694978 -281.072847) (xy 379.653307 -281.039616) (xy 379.617055 -281.000545) (xy 379.587031 -280.956508)
			(xy 379.563905 -280.908487) (xy 379.548195 -280.857557) (xy 379.540252 -280.804853) (xy 379.311672 -280.804853)
			(xy 379.303729 -280.857557) (xy 379.288019 -280.908487) (xy 379.264893 -280.956508) (xy 379.234869 -281.000545)
			(xy 379.198617 -281.039616) (xy 379.156946 -281.072847) (xy 379.110788 -281.099496) (xy 379.061174 -281.118968)
			(xy 379.009212 -281.130828) (xy 378.956062 -281.134812) (xy 378.902912 -281.130828) (xy 378.85095 -281.118968)
			(xy 378.801336 -281.099496) (xy 378.755178 -281.072847) (xy 378.713507 -281.039616) (xy 378.677255 -281.000545)
			(xy 378.647231 -280.956508) (xy 378.624105 -280.908487) (xy 378.608395 -280.857557) (xy 378.600452 -280.804853)
			(xy 378.372126 -280.804853) (xy 378.364183 -280.857557) (xy 378.348473 -280.908487) (xy 378.325347 -280.956508)
			(xy 378.295323 -281.000545) (xy 378.259071 -281.039616) (xy 378.2174 -281.072847) (xy 378.171242 -281.099496)
			(xy 378.121628 -281.118968) (xy 378.069666 -281.130828) (xy 378.016516 -281.134812) (xy 377.963366 -281.130828)
			(xy 377.911404 -281.118968) (xy 377.86179 -281.099496) (xy 377.815632 -281.072847) (xy 377.773961 -281.039616)
			(xy 377.737709 -281.000545) (xy 377.707685 -280.956508) (xy 377.684559 -280.908487) (xy 377.668849 -280.857557)
			(xy 377.660906 -280.804853) (xy 377.432326 -280.804853) (xy 377.424383 -280.857557) (xy 377.408673 -280.908487)
			(xy 377.385547 -280.956508) (xy 377.355523 -281.000545) (xy 377.319271 -281.039616) (xy 377.2776 -281.072847)
			(xy 377.231442 -281.099496) (xy 377.181828 -281.118968) (xy 377.129866 -281.130828) (xy 377.076716 -281.134812)
			(xy 377.023566 -281.130828) (xy 376.971604 -281.118968) (xy 376.92199 -281.099496) (xy 376.875832 -281.072847)
			(xy 376.834161 -281.039616) (xy 376.797909 -281.000545) (xy 376.767885 -280.956508) (xy 376.744759 -280.908487)
			(xy 376.729049 -280.857557) (xy 376.721106 -280.804853) (xy 376.492526 -280.804853) (xy 376.484583 -280.857557)
			(xy 376.468873 -280.908487) (xy 376.445747 -280.956508) (xy 376.415723 -281.000545) (xy 376.379471 -281.039616)
			(xy 376.3378 -281.072847) (xy 376.291642 -281.099496) (xy 376.242028 -281.118968) (xy 376.190066 -281.130828)
			(xy 376.136916 -281.134812) (xy 376.083766 -281.130828) (xy 376.031804 -281.118968) (xy 375.98219 -281.099496)
			(xy 375.936032 -281.072847) (xy 375.894361 -281.039616) (xy 375.858109 -281.000545) (xy 375.828085 -280.956508)
			(xy 375.804959 -280.908487) (xy 375.789249 -280.857557) (xy 375.781306 -280.804853) (xy 375.552726 -280.804853)
			(xy 375.544783 -280.857557) (xy 375.529073 -280.908487) (xy 375.505947 -280.956508) (xy 375.475923 -281.000545)
			(xy 375.439671 -281.039616) (xy 375.398 -281.072847) (xy 375.351842 -281.099496) (xy 375.302228 -281.118968)
			(xy 375.250266 -281.130828) (xy 375.197116 -281.134812) (xy 375.143966 -281.130828) (xy 375.092004 -281.118968)
			(xy 375.04239 -281.099496) (xy 374.996232 -281.072847) (xy 374.954561 -281.039616) (xy 374.918309 -281.000545)
			(xy 374.888285 -280.956508) (xy 374.865159 -280.908487) (xy 374.849449 -280.857557) (xy 374.841506 -280.804853)
			(xy 374.612926 -280.804853) (xy 374.604983 -280.857557) (xy 374.589273 -280.908487) (xy 374.566147 -280.956508)
			(xy 374.536123 -281.000545) (xy 374.499871 -281.039616) (xy 374.4582 -281.072847) (xy 374.412042 -281.099496)
			(xy 374.362428 -281.118968) (xy 374.310466 -281.130828) (xy 374.257316 -281.134812) (xy 374.204166 -281.130828)
			(xy 374.152204 -281.118968) (xy 374.10259 -281.099496) (xy 374.056432 -281.072847) (xy 374.014761 -281.039616)
			(xy 373.978509 -281.000545) (xy 373.948485 -280.956508) (xy 373.925359 -280.908487) (xy 373.909649 -280.857557)
			(xy 373.901706 -280.804853) (xy 373.672872 -280.804853) (xy 373.664929 -280.857557) (xy 373.649219 -280.908487)
			(xy 373.626093 -280.956508) (xy 373.596069 -281.000545) (xy 373.559817 -281.039616) (xy 373.518146 -281.072847)
			(xy 373.471988 -281.099496) (xy 373.422374 -281.118968) (xy 373.370412 -281.130828) (xy 373.317262 -281.134812)
			(xy 373.264112 -281.130828) (xy 373.21215 -281.118968) (xy 373.162536 -281.099496) (xy 373.116378 -281.072847)
			(xy 373.074707 -281.039616) (xy 373.038455 -281.000545) (xy 373.008431 -280.956508) (xy 372.985305 -280.908487)
			(xy 372.969595 -280.857557) (xy 372.961652 -280.804853) (xy 372.733072 -280.804853) (xy 372.725129 -280.857557)
			(xy 372.709419 -280.908487) (xy 372.686293 -280.956508) (xy 372.656269 -281.000545) (xy 372.620017 -281.039616)
			(xy 372.578346 -281.072847) (xy 372.532188 -281.099496) (xy 372.482574 -281.118968) (xy 372.430612 -281.130828)
			(xy 372.377462 -281.134812) (xy 372.324312 -281.130828) (xy 372.27235 -281.118968) (xy 372.222736 -281.099496)
			(xy 372.176578 -281.072847) (xy 372.134907 -281.039616) (xy 372.098655 -281.000545) (xy 372.068631 -280.956508)
			(xy 372.045505 -280.908487) (xy 372.029795 -280.857557) (xy 372.021852 -280.804853) (xy 371.793272 -280.804853)
			(xy 371.785329 -280.857557) (xy 371.769619 -280.908487) (xy 371.746493 -280.956508) (xy 371.716469 -281.000545)
			(xy 371.680217 -281.039616) (xy 371.638546 -281.072847) (xy 371.592388 -281.099496) (xy 371.542774 -281.118968)
			(xy 371.490812 -281.130828) (xy 371.437662 -281.134812) (xy 371.384512 -281.130828) (xy 371.33255 -281.118968)
			(xy 371.282936 -281.099496) (xy 371.236778 -281.072847) (xy 371.195107 -281.039616) (xy 371.158855 -281.000545)
			(xy 371.128831 -280.956508) (xy 371.105705 -280.908487) (xy 371.089995 -280.857557) (xy 371.082052 -280.804853)
			(xy 370.853472 -280.804853) (xy 370.845529 -280.857557) (xy 370.829819 -280.908487) (xy 370.806693 -280.956508)
			(xy 370.776669 -281.000545) (xy 370.740417 -281.039616) (xy 370.698746 -281.072847) (xy 370.652588 -281.099496)
			(xy 370.602974 -281.118968) (xy 370.551012 -281.130828) (xy 370.497862 -281.134812) (xy 370.444712 -281.130828)
			(xy 370.39275 -281.118968) (xy 370.343136 -281.099496) (xy 370.296978 -281.072847) (xy 370.255307 -281.039616)
			(xy 370.219055 -281.000545) (xy 370.189031 -280.956508) (xy 370.165905 -280.908487) (xy 370.150195 -280.857557)
			(xy 370.142252 -280.804853) (xy 369.913672 -280.804853) (xy 369.905729 -280.857557) (xy 369.890019 -280.908487)
			(xy 369.866893 -280.956508) (xy 369.836869 -281.000545) (xy 369.800617 -281.039616) (xy 369.758946 -281.072847)
			(xy 369.712788 -281.099496) (xy 369.663174 -281.118968) (xy 369.611212 -281.130828) (xy 369.558062 -281.134812)
			(xy 369.504912 -281.130828) (xy 369.45295 -281.118968) (xy 369.403336 -281.099496) (xy 369.357178 -281.072847)
			(xy 369.315507 -281.039616) (xy 369.279255 -281.000545) (xy 369.249231 -280.956508) (xy 369.226105 -280.908487)
			(xy 369.210395 -280.857557) (xy 369.202452 -280.804853) (xy 368.973872 -280.804853) (xy 368.965929 -280.857557)
			(xy 368.950219 -280.908487) (xy 368.927093 -280.956508) (xy 368.897069 -281.000545) (xy 368.860817 -281.039616)
			(xy 368.819146 -281.072847) (xy 368.772988 -281.099496) (xy 368.723374 -281.118968) (xy 368.671412 -281.130828)
			(xy 368.618262 -281.134812) (xy 368.565112 -281.130828) (xy 368.51315 -281.118968) (xy 368.463536 -281.099496)
			(xy 368.417378 -281.072847) (xy 368.375707 -281.039616) (xy 368.339455 -281.000545) (xy 368.309431 -280.956508)
			(xy 368.286305 -280.908487) (xy 368.270595 -280.857557) (xy 368.262652 -280.804853) (xy 368.034072 -280.804853)
			(xy 368.026129 -280.857557) (xy 368.010419 -280.908487) (xy 367.987293 -280.956508) (xy 367.957269 -281.000545)
			(xy 367.921017 -281.039616) (xy 367.879346 -281.072847) (xy 367.833188 -281.099496) (xy 367.783574 -281.118968)
			(xy 367.731612 -281.130828) (xy 367.678462 -281.134812) (xy 367.625312 -281.130828) (xy 367.57335 -281.118968)
			(xy 367.523736 -281.099496) (xy 367.477578 -281.072847) (xy 367.435907 -281.039616) (xy 367.399655 -281.000545)
			(xy 367.369631 -280.956508) (xy 367.346505 -280.908487) (xy 367.330795 -280.857557) (xy 367.322852 -280.804853)
			(xy 367.094272 -280.804853) (xy 367.086329 -280.857557) (xy 367.070619 -280.908487) (xy 367.047493 -280.956508)
			(xy 367.017469 -281.000545) (xy 366.981217 -281.039616) (xy 366.939546 -281.072847) (xy 366.893388 -281.099496)
			(xy 366.843774 -281.118968) (xy 366.791812 -281.130828) (xy 366.738662 -281.134812) (xy 366.685512 -281.130828)
			(xy 366.63355 -281.118968) (xy 366.583936 -281.099496) (xy 366.537778 -281.072847) (xy 366.496107 -281.039616)
			(xy 366.459855 -281.000545) (xy 366.429831 -280.956508) (xy 366.406705 -280.908487) (xy 366.390995 -280.857557)
			(xy 366.383052 -280.804853) (xy 366.154726 -280.804853) (xy 366.146783 -280.857557) (xy 366.131073 -280.908487)
			(xy 366.107947 -280.956508) (xy 366.077923 -281.000545) (xy 366.041671 -281.039616) (xy 366 -281.072847)
			(xy 365.953842 -281.099496) (xy 365.904228 -281.118968) (xy 365.852266 -281.130828) (xy 365.799116 -281.134812)
			(xy 365.745966 -281.130828) (xy 365.694004 -281.118968) (xy 365.64439 -281.099496) (xy 365.598232 -281.072847)
			(xy 365.556561 -281.039616) (xy 365.520309 -281.000545) (xy 365.490285 -280.956508) (xy 365.467159 -280.908487)
			(xy 365.451449 -280.857557) (xy 365.443506 -280.804853) (xy 365.214926 -280.804853) (xy 365.206983 -280.857557)
			(xy 365.191273 -280.908487) (xy 365.168147 -280.956508) (xy 365.138123 -281.000545) (xy 365.101871 -281.039616)
			(xy 365.0602 -281.072847) (xy 365.014042 -281.099496) (xy 364.964428 -281.118968) (xy 364.912466 -281.130828)
			(xy 364.859316 -281.134812) (xy 364.806166 -281.130828) (xy 364.754204 -281.118968) (xy 364.70459 -281.099496)
			(xy 364.658432 -281.072847) (xy 364.616761 -281.039616) (xy 364.580509 -281.000545) (xy 364.550485 -280.956508)
			(xy 364.527359 -280.908487) (xy 364.511649 -280.857557) (xy 364.503706 -280.804853) (xy 358.636072 -280.804853)
			(xy 358.628129 -280.857557) (xy 358.612419 -280.908487) (xy 358.589293 -280.956508) (xy 358.559269 -281.000545)
			(xy 358.523017 -281.039616) (xy 358.481346 -281.072847) (xy 358.435188 -281.099496) (xy 358.385574 -281.118968)
			(xy 358.333612 -281.130828) (xy 358.280462 -281.134812) (xy 358.227312 -281.130828) (xy 358.17535 -281.118968)
			(xy 358.125736 -281.099496) (xy 358.079578 -281.072847) (xy 358.037907 -281.039616) (xy 358.001655 -281.000545)
			(xy 357.971631 -280.956508) (xy 357.948505 -280.908487) (xy 357.932795 -280.857557) (xy 357.924852 -280.804853)
			(xy 355.816672 -280.804853) (xy 355.808729 -280.857557) (xy 355.793019 -280.908487) (xy 355.769893 -280.956508)
			(xy 355.739869 -281.000545) (xy 355.703617 -281.039616) (xy 355.661946 -281.072847) (xy 355.615788 -281.099496)
			(xy 355.566174 -281.118968) (xy 355.514212 -281.130828) (xy 355.461062 -281.134812) (xy 355.407912 -281.130828)
			(xy 355.35595 -281.118968) (xy 355.306336 -281.099496) (xy 355.260178 -281.072847) (xy 355.218507 -281.039616)
			(xy 355.182255 -281.000545) (xy 355.152231 -280.956508) (xy 355.129105 -280.908487) (xy 355.113395 -280.857557)
			(xy 355.105452 -280.804853) (xy 354.850397 -280.804853) (xy 354.842407 -280.855297) (xy 354.826391 -280.904583)
			(xy 354.802863 -280.950757) (xy 354.7724 -280.992682) (xy 354.735753 -281.029324) (xy 354.693825 -281.059782)
			(xy 354.647648 -281.083306) (xy 354.59836 -281.099316) (xy 354.547174 -281.107417) (xy 354.521262 -281.107896)
			(xy 354.495749 -281.107445) (xy 354.445333 -281.099578) (xy 354.396731 -281.084039) (xy 354.351103 -281.061198)
			(xy 354.309538 -281.031601) (xy 354.273029 -280.995953) (xy 354.257356 -280.975816) (xy 353.845368 -280.975816)
			(xy 353.829717 -280.99597) (xy 353.793203 -281.031612) (xy 353.751632 -281.061203) (xy 353.705999 -281.084036)
			(xy 353.657393 -281.099566) (xy 353.606975 -281.107421) (xy 353.581462 -281.107896) (xy 353.555557 -281.107377)
			(xy 353.504385 -281.099267) (xy 353.455113 -281.083252) (xy 353.408951 -281.059727) (xy 353.367038 -281.029271)
			(xy 353.330405 -280.992633) (xy 353.299953 -280.950716) (xy 353.276434 -280.904552) (xy 353.260425 -280.855278)
			(xy 353.25232 -280.804105) (xy 353.024694 -280.804105) (xy 353.024694 -281.134566) (xy 353.025276 -281.15023)
			(xy 353.034773 -281.180084) (xy 353.052856 -281.205667) (xy 353.07783 -281.22458) (xy 353.107356 -281.235053)
			(xy 353.122992 -281.236166) (xy 353.149074 -281.237445) (xy 353.200468 -281.246693) (xy 353.24996 -281.26335)
			(xy 353.296487 -281.287058) (xy 353.339052 -281.317309) (xy 353.376741 -281.353453) (xy 353.408746 -281.394714)
			(xy 353.43438 -281.440209) (xy 353.453094 -281.48896) (xy 353.464485 -281.539922) (xy 353.468309 -281.592001)
			(xy 353.468308 -281.59202) (xy 353.721924 -281.59202) (xy 353.722432 -281.566113) (xy 353.730538 -281.514936)
			(xy 353.74655 -281.465657) (xy 353.770073 -281.41949) (xy 353.800529 -281.377571) (xy 353.837167 -281.340933)
			(xy 353.879086 -281.310477) (xy 353.925253 -281.286954) (xy 353.974532 -281.270942) (xy 354.025709 -281.262836)
			(xy 354.077523 -281.262836) (xy 354.1287 -281.270942) (xy 354.177979 -281.286954) (xy 354.224146 -281.310477)
			(xy 354.266065 -281.340933) (xy 354.302703 -281.377571) (xy 354.333159 -281.41949) (xy 354.356682 -281.465657)
			(xy 354.372694 -281.514936) (xy 354.3808 -281.566113) (xy 354.381308 -281.59202) (xy 354.380762 -281.618669)
			(xy 354.635806 -281.618669) (xy 354.635806 -281.565371) (xy 354.643749 -281.512667) (xy 354.659459 -281.461737)
			(xy 354.682585 -281.413716) (xy 354.712609 -281.369679) (xy 354.748861 -281.330608) (xy 354.790532 -281.297377)
			(xy 354.83669 -281.270728) (xy 354.886304 -281.251256) (xy 354.938266 -281.239396) (xy 354.991416 -281.235413)
			(xy 355.044566 -281.239396) (xy 355.096528 -281.251256) (xy 355.146142 -281.270728) (xy 355.1923 -281.297377)
			(xy 355.233971 -281.330608) (xy 355.270223 -281.369679) (xy 355.300247 -281.413716) (xy 355.323373 -281.461737)
			(xy 355.339083 -281.512667) (xy 355.347026 -281.565371) (xy 355.347524 -281.59202) (xy 355.347026 -281.618669)
			(xy 361.214152 -281.618669) (xy 361.214152 -281.565371) (xy 361.222095 -281.512667) (xy 361.237805 -281.461737)
			(xy 361.260931 -281.413716) (xy 361.290955 -281.369679) (xy 361.327207 -281.330608) (xy 361.368878 -281.297377)
			(xy 361.415036 -281.270728) (xy 361.46465 -281.251256) (xy 361.516612 -281.239396) (xy 361.569762 -281.235413)
			(xy 361.622912 -281.239396) (xy 361.674874 -281.251256) (xy 361.724488 -281.270728) (xy 361.770646 -281.297377)
			(xy 361.812317 -281.330608) (xy 361.848569 -281.369679) (xy 361.878593 -281.413716) (xy 361.901719 -281.461737)
			(xy 361.917429 -281.512667) (xy 361.925372 -281.565371) (xy 361.92587 -281.59202) (xy 361.925372 -281.618669)
			(xy 364.973606 -281.618669) (xy 364.973606 -281.565371) (xy 364.981549 -281.512667) (xy 364.997259 -281.461737)
			(xy 365.020385 -281.413716) (xy 365.050409 -281.369679) (xy 365.086661 -281.330608) (xy 365.128332 -281.297377)
			(xy 365.17449 -281.270728) (xy 365.224104 -281.251256) (xy 365.276066 -281.239396) (xy 365.329216 -281.235413)
			(xy 365.382366 -281.239396) (xy 365.434328 -281.251256) (xy 365.483942 -281.270728) (xy 365.5301 -281.297377)
			(xy 365.571771 -281.330608) (xy 365.608023 -281.369679) (xy 365.638047 -281.413716) (xy 365.661173 -281.461737)
			(xy 365.676883 -281.512667) (xy 365.684826 -281.565371) (xy 365.685324 -281.59202) (xy 365.684826 -281.618669)
			(xy 365.913152 -281.618669) (xy 365.913152 -281.565371) (xy 365.921095 -281.512667) (xy 365.936805 -281.461737)
			(xy 365.959931 -281.413716) (xy 365.989955 -281.369679) (xy 366.026207 -281.330608) (xy 366.067878 -281.297377)
			(xy 366.114036 -281.270728) (xy 366.16365 -281.251256) (xy 366.215612 -281.239396) (xy 366.268762 -281.235413)
			(xy 366.321912 -281.239396) (xy 366.373874 -281.251256) (xy 366.423488 -281.270728) (xy 366.469646 -281.297377)
			(xy 366.511317 -281.330608) (xy 366.547569 -281.369679) (xy 366.577593 -281.413716) (xy 366.600719 -281.461737)
			(xy 366.616429 -281.512667) (xy 366.624372 -281.565371) (xy 366.62487 -281.59202) (xy 366.624372 -281.618669)
			(xy 366.853206 -281.618669) (xy 366.853206 -281.565371) (xy 366.861149 -281.512667) (xy 366.876859 -281.461737)
			(xy 366.899985 -281.413716) (xy 366.930009 -281.369679) (xy 366.966261 -281.330608) (xy 367.007932 -281.297377)
			(xy 367.05409 -281.270728) (xy 367.103704 -281.251256) (xy 367.155666 -281.239396) (xy 367.208816 -281.235413)
			(xy 367.261966 -281.239396) (xy 367.313928 -281.251256) (xy 367.363542 -281.270728) (xy 367.4097 -281.297377)
			(xy 367.451371 -281.330608) (xy 367.487623 -281.369679) (xy 367.517647 -281.413716) (xy 367.540773 -281.461737)
			(xy 367.556483 -281.512667) (xy 367.564426 -281.565371) (xy 367.564924 -281.59202) (xy 367.564426 -281.618669)
			(xy 367.793006 -281.618669) (xy 367.793006 -281.565371) (xy 367.800949 -281.512667) (xy 367.816659 -281.461737)
			(xy 367.839785 -281.413716) (xy 367.869809 -281.369679) (xy 367.906061 -281.330608) (xy 367.947732 -281.297377)
			(xy 367.99389 -281.270728) (xy 368.043504 -281.251256) (xy 368.095466 -281.239396) (xy 368.148616 -281.235413)
			(xy 368.201766 -281.239396) (xy 368.253728 -281.251256) (xy 368.303342 -281.270728) (xy 368.3495 -281.297377)
			(xy 368.391171 -281.330608) (xy 368.427423 -281.369679) (xy 368.457447 -281.413716) (xy 368.480573 -281.461737)
			(xy 368.496283 -281.512667) (xy 368.504226 -281.565371) (xy 368.504724 -281.59202) (xy 368.504226 -281.618669)
			(xy 368.732806 -281.618669) (xy 368.732806 -281.565371) (xy 368.740749 -281.512667) (xy 368.756459 -281.461737)
			(xy 368.779585 -281.413716) (xy 368.809609 -281.369679) (xy 368.845861 -281.330608) (xy 368.887532 -281.297377)
			(xy 368.93369 -281.270728) (xy 368.983304 -281.251256) (xy 369.035266 -281.239396) (xy 369.088416 -281.235413)
			(xy 369.141566 -281.239396) (xy 369.193528 -281.251256) (xy 369.243142 -281.270728) (xy 369.2893 -281.297377)
			(xy 369.330971 -281.330608) (xy 369.367223 -281.369679) (xy 369.397247 -281.413716) (xy 369.420373 -281.461737)
			(xy 369.436083 -281.512667) (xy 369.444026 -281.565371) (xy 369.444524 -281.59202) (xy 369.444026 -281.618669)
			(xy 369.672606 -281.618669) (xy 369.672606 -281.565371) (xy 369.680549 -281.512667) (xy 369.696259 -281.461737)
			(xy 369.719385 -281.413716) (xy 369.749409 -281.369679) (xy 369.785661 -281.330608) (xy 369.827332 -281.297377)
			(xy 369.87349 -281.270728) (xy 369.923104 -281.251256) (xy 369.975066 -281.239396) (xy 370.028216 -281.235413)
			(xy 370.081366 -281.239396) (xy 370.133328 -281.251256) (xy 370.182942 -281.270728) (xy 370.2291 -281.297377)
			(xy 370.270771 -281.330608) (xy 370.307023 -281.369679) (xy 370.337047 -281.413716) (xy 370.360173 -281.461737)
			(xy 370.375883 -281.512667) (xy 370.383826 -281.565371) (xy 370.384324 -281.59202) (xy 370.383826 -281.618669)
			(xy 370.612406 -281.618669) (xy 370.612406 -281.565371) (xy 370.620349 -281.512667) (xy 370.636059 -281.461737)
			(xy 370.659185 -281.413716) (xy 370.689209 -281.369679) (xy 370.725461 -281.330608) (xy 370.767132 -281.297377)
			(xy 370.81329 -281.270728) (xy 370.862904 -281.251256) (xy 370.914866 -281.239396) (xy 370.968016 -281.235413)
			(xy 371.021166 -281.239396) (xy 371.073128 -281.251256) (xy 371.122742 -281.270728) (xy 371.1689 -281.297377)
			(xy 371.210571 -281.330608) (xy 371.246823 -281.369679) (xy 371.276847 -281.413716) (xy 371.299973 -281.461737)
			(xy 371.315683 -281.512667) (xy 371.323626 -281.565371) (xy 371.324124 -281.59202) (xy 371.323626 -281.618669)
			(xy 371.552206 -281.618669) (xy 371.552206 -281.565371) (xy 371.560149 -281.512667) (xy 371.575859 -281.461737)
			(xy 371.598985 -281.413716) (xy 371.629009 -281.369679) (xy 371.665261 -281.330608) (xy 371.706932 -281.297377)
			(xy 371.75309 -281.270728) (xy 371.802704 -281.251256) (xy 371.854666 -281.239396) (xy 371.907816 -281.235413)
			(xy 371.960966 -281.239396) (xy 372.012928 -281.251256) (xy 372.062542 -281.270728) (xy 372.1087 -281.297377)
			(xy 372.150371 -281.330608) (xy 372.186623 -281.369679) (xy 372.216647 -281.413716) (xy 372.239773 -281.461737)
			(xy 372.255483 -281.512667) (xy 372.263426 -281.565371) (xy 372.263924 -281.59202) (xy 372.263426 -281.618669)
			(xy 372.492006 -281.618669) (xy 372.492006 -281.565371) (xy 372.499949 -281.512667) (xy 372.515659 -281.461737)
			(xy 372.538785 -281.413716) (xy 372.568809 -281.369679) (xy 372.605061 -281.330608) (xy 372.646732 -281.297377)
			(xy 372.69289 -281.270728) (xy 372.742504 -281.251256) (xy 372.794466 -281.239396) (xy 372.847616 -281.235413)
			(xy 372.900766 -281.239396) (xy 372.952728 -281.251256) (xy 373.002342 -281.270728) (xy 373.0485 -281.297377)
			(xy 373.090171 -281.330608) (xy 373.126423 -281.369679) (xy 373.156447 -281.413716) (xy 373.179573 -281.461737)
			(xy 373.195283 -281.512667) (xy 373.203226 -281.565371) (xy 373.203724 -281.59202) (xy 373.203226 -281.618669)
			(xy 373.431806 -281.618669) (xy 373.431806 -281.565371) (xy 373.439749 -281.512667) (xy 373.455459 -281.461737)
			(xy 373.478585 -281.413716) (xy 373.508609 -281.369679) (xy 373.544861 -281.330608) (xy 373.586532 -281.297377)
			(xy 373.63269 -281.270728) (xy 373.682304 -281.251256) (xy 373.734266 -281.239396) (xy 373.787416 -281.235413)
			(xy 373.840566 -281.239396) (xy 373.892528 -281.251256) (xy 373.942142 -281.270728) (xy 373.9883 -281.297377)
			(xy 374.029971 -281.330608) (xy 374.066223 -281.369679) (xy 374.096247 -281.413716) (xy 374.119373 -281.461737)
			(xy 374.135083 -281.512667) (xy 374.143026 -281.565371) (xy 374.143524 -281.59202) (xy 374.143026 -281.618669)
			(xy 374.371352 -281.618669) (xy 374.371352 -281.565371) (xy 374.379295 -281.512667) (xy 374.395005 -281.461737)
			(xy 374.418131 -281.413716) (xy 374.448155 -281.369679) (xy 374.484407 -281.330608) (xy 374.526078 -281.297377)
			(xy 374.572236 -281.270728) (xy 374.62185 -281.251256) (xy 374.673812 -281.239396) (xy 374.726962 -281.235413)
			(xy 374.780112 -281.239396) (xy 374.832074 -281.251256) (xy 374.881688 -281.270728) (xy 374.927846 -281.297377)
			(xy 374.969517 -281.330608) (xy 375.005769 -281.369679) (xy 375.035793 -281.413716) (xy 375.058919 -281.461737)
			(xy 375.074629 -281.512667) (xy 375.082572 -281.565371) (xy 375.08307 -281.59202) (xy 375.082577 -281.618415)
			(xy 375.311152 -281.618415) (xy 375.311152 -281.565117) (xy 375.319095 -281.512413) (xy 375.334805 -281.461483)
			(xy 375.357931 -281.413462) (xy 375.387955 -281.369425) (xy 375.424207 -281.330354) (xy 375.465878 -281.297123)
			(xy 375.512036 -281.270474) (xy 375.56165 -281.251002) (xy 375.613612 -281.239142) (xy 375.666762 -281.235159)
			(xy 375.719912 -281.239142) (xy 375.771874 -281.251002) (xy 375.821488 -281.270474) (xy 375.867646 -281.297123)
			(xy 375.909317 -281.330354) (xy 375.945569 -281.369425) (xy 375.975593 -281.413462) (xy 375.998719 -281.461483)
			(xy 376.014429 -281.512413) (xy 376.022372 -281.565117) (xy 376.02287 -281.591766) (xy 376.022372 -281.618415)
			(xy 376.022334 -281.618669) (xy 376.251206 -281.618669) (xy 376.251206 -281.565371) (xy 376.259149 -281.512667)
			(xy 376.274859 -281.461737) (xy 376.297985 -281.413716) (xy 376.328009 -281.369679) (xy 376.364261 -281.330608)
			(xy 376.405932 -281.297377) (xy 376.45209 -281.270728) (xy 376.501704 -281.251256) (xy 376.553666 -281.239396)
			(xy 376.606816 -281.235413) (xy 376.659966 -281.239396) (xy 376.711928 -281.251256) (xy 376.761542 -281.270728)
			(xy 376.8077 -281.297377) (xy 376.849371 -281.330608) (xy 376.885623 -281.369679) (xy 376.915647 -281.413716)
			(xy 376.938773 -281.461737) (xy 376.954483 -281.512667) (xy 376.962426 -281.565371) (xy 376.962924 -281.59202)
			(xy 376.962426 -281.618669) (xy 377.190752 -281.618669) (xy 377.190752 -281.565371) (xy 377.198695 -281.512667)
			(xy 377.214405 -281.461737) (xy 377.237531 -281.413716) (xy 377.267555 -281.369679) (xy 377.303807 -281.330608)
			(xy 377.345478 -281.297377) (xy 377.391636 -281.270728) (xy 377.44125 -281.251256) (xy 377.493212 -281.239396)
			(xy 377.546362 -281.235413) (xy 377.599512 -281.239396) (xy 377.651474 -281.251256) (xy 377.701088 -281.270728)
			(xy 377.747246 -281.297377) (xy 377.788917 -281.330608) (xy 377.825169 -281.369679) (xy 377.855193 -281.413716)
			(xy 377.878319 -281.461737) (xy 377.894029 -281.512667) (xy 377.901972 -281.565371) (xy 377.90247 -281.59202)
			(xy 377.901972 -281.618669) (xy 378.130806 -281.618669) (xy 378.130806 -281.565371) (xy 378.138749 -281.512667)
			(xy 378.154459 -281.461737) (xy 378.177585 -281.413716) (xy 378.207609 -281.369679) (xy 378.243861 -281.330608)
			(xy 378.285532 -281.297377) (xy 378.33169 -281.270728) (xy 378.381304 -281.251256) (xy 378.433266 -281.239396)
			(xy 378.486416 -281.235413) (xy 378.539566 -281.239396) (xy 378.591528 -281.251256) (xy 378.641142 -281.270728)
			(xy 378.6873 -281.297377) (xy 378.728971 -281.330608) (xy 378.765223 -281.369679) (xy 378.795247 -281.413716)
			(xy 378.818373 -281.461737) (xy 378.834083 -281.512667) (xy 378.842026 -281.565371) (xy 378.842524 -281.59202)
			(xy 378.842026 -281.618669) (xy 379.070606 -281.618669) (xy 379.070606 -281.565371) (xy 379.078549 -281.512667)
			(xy 379.094259 -281.461737) (xy 379.117385 -281.413716) (xy 379.147409 -281.369679) (xy 379.183661 -281.330608)
			(xy 379.225332 -281.297377) (xy 379.27149 -281.270728) (xy 379.321104 -281.251256) (xy 379.373066 -281.239396)
			(xy 379.426216 -281.235413) (xy 379.479366 -281.239396) (xy 379.531328 -281.251256) (xy 379.580942 -281.270728)
			(xy 379.6271 -281.297377) (xy 379.668771 -281.330608) (xy 379.705023 -281.369679) (xy 379.735047 -281.413716)
			(xy 379.758173 -281.461737) (xy 379.773883 -281.512667) (xy 379.781826 -281.565371) (xy 379.782324 -281.59202)
			(xy 379.781826 -281.618669) (xy 380.010406 -281.618669) (xy 380.010406 -281.565371) (xy 380.018349 -281.512667)
			(xy 380.034059 -281.461737) (xy 380.057185 -281.413716) (xy 380.087209 -281.369679) (xy 380.123461 -281.330608)
			(xy 380.165132 -281.297377) (xy 380.21129 -281.270728) (xy 380.260904 -281.251256) (xy 380.312866 -281.239396)
			(xy 380.366016 -281.235413) (xy 380.419166 -281.239396) (xy 380.471128 -281.251256) (xy 380.520742 -281.270728)
			(xy 380.5669 -281.297377) (xy 380.608571 -281.330608) (xy 380.644823 -281.369679) (xy 380.674847 -281.413716)
			(xy 380.697973 -281.461737) (xy 380.713683 -281.512667) (xy 380.721626 -281.565371) (xy 380.722124 -281.59202)
			(xy 380.721626 -281.618669) (xy 380.950206 -281.618669) (xy 380.950206 -281.565371) (xy 380.958149 -281.512667)
			(xy 380.973859 -281.461737) (xy 380.996985 -281.413716) (xy 381.027009 -281.369679) (xy 381.063261 -281.330608)
			(xy 381.104932 -281.297377) (xy 381.15109 -281.270728) (xy 381.200704 -281.251256) (xy 381.252666 -281.239396)
			(xy 381.305816 -281.235413) (xy 381.358966 -281.239396) (xy 381.410928 -281.251256) (xy 381.460542 -281.270728)
			(xy 381.5067 -281.297377) (xy 381.548371 -281.330608) (xy 381.584623 -281.369679) (xy 381.614647 -281.413716)
			(xy 381.637773 -281.461737) (xy 381.653483 -281.512667) (xy 381.661426 -281.565371) (xy 381.661924 -281.59202)
			(xy 381.661426 -281.618669) (xy 381.890006 -281.618669) (xy 381.890006 -281.565371) (xy 381.897949 -281.512667)
			(xy 381.913659 -281.461737) (xy 381.936785 -281.413716) (xy 381.966809 -281.369679) (xy 382.003061 -281.330608)
			(xy 382.044732 -281.297377) (xy 382.09089 -281.270728) (xy 382.140504 -281.251256) (xy 382.192466 -281.239396)
			(xy 382.245616 -281.235413) (xy 382.298766 -281.239396) (xy 382.350728 -281.251256) (xy 382.400342 -281.270728)
			(xy 382.4465 -281.297377) (xy 382.488171 -281.330608) (xy 382.524423 -281.369679) (xy 382.554447 -281.413716)
			(xy 382.577573 -281.461737) (xy 382.593283 -281.512667) (xy 382.601226 -281.565371) (xy 382.601724 -281.59202)
			(xy 382.601226 -281.618669) (xy 382.829552 -281.618669) (xy 382.829552 -281.565371) (xy 382.837495 -281.512667)
			(xy 382.853205 -281.461737) (xy 382.876331 -281.413716) (xy 382.906355 -281.369679) (xy 382.942607 -281.330608)
			(xy 382.984278 -281.297377) (xy 383.030436 -281.270728) (xy 383.08005 -281.251256) (xy 383.132012 -281.239396)
			(xy 383.185162 -281.235413) (xy 383.238312 -281.239396) (xy 383.290274 -281.251256) (xy 383.339888 -281.270728)
			(xy 383.386046 -281.297377) (xy 383.427717 -281.330608) (xy 383.463969 -281.369679) (xy 383.493993 -281.413716)
			(xy 383.517119 -281.461737) (xy 383.532829 -281.512667) (xy 383.540772 -281.565371) (xy 383.54127 -281.59202)
			(xy 383.540772 -281.618669) (xy 383.769352 -281.618669) (xy 383.769352 -281.565371) (xy 383.777295 -281.512667)
			(xy 383.793005 -281.461737) (xy 383.816131 -281.413716) (xy 383.846155 -281.369679) (xy 383.882407 -281.330608)
			(xy 383.924078 -281.297377) (xy 383.970236 -281.270728) (xy 384.01985 -281.251256) (xy 384.071812 -281.239396)
			(xy 384.124962 -281.235413) (xy 384.178112 -281.239396) (xy 384.230074 -281.251256) (xy 384.279688 -281.270728)
			(xy 384.325846 -281.297377) (xy 384.367517 -281.330608) (xy 384.403769 -281.369679) (xy 384.433793 -281.413716)
			(xy 384.456919 -281.461737) (xy 384.472629 -281.512667) (xy 384.480572 -281.565371) (xy 384.48107 -281.59202)
			(xy 384.480572 -281.618669) (xy 384.709152 -281.618669) (xy 384.709152 -281.565371) (xy 384.717095 -281.512667)
			(xy 384.732805 -281.461737) (xy 384.755931 -281.413716) (xy 384.785955 -281.369679) (xy 384.822207 -281.330608)
			(xy 384.863878 -281.297377) (xy 384.910036 -281.270728) (xy 384.95965 -281.251256) (xy 385.011612 -281.239396)
			(xy 385.064762 -281.235413) (xy 385.117912 -281.239396) (xy 385.169874 -281.251256) (xy 385.219488 -281.270728)
			(xy 385.265646 -281.297377) (xy 385.307317 -281.330608) (xy 385.343569 -281.369679) (xy 385.373593 -281.413716)
			(xy 385.396719 -281.461737) (xy 385.412429 -281.512667) (xy 385.420372 -281.565371) (xy 385.42087 -281.59202)
			(xy 385.420372 -281.618669) (xy 385.648952 -281.618669) (xy 385.648952 -281.565371) (xy 385.656895 -281.512667)
			(xy 385.672605 -281.461737) (xy 385.695731 -281.413716) (xy 385.725755 -281.369679) (xy 385.762007 -281.330608)
			(xy 385.803678 -281.297377) (xy 385.849836 -281.270728) (xy 385.89945 -281.251256) (xy 385.951412 -281.239396)
			(xy 386.004562 -281.235413) (xy 386.057712 -281.239396) (xy 386.109674 -281.251256) (xy 386.159288 -281.270728)
			(xy 386.205446 -281.297377) (xy 386.247117 -281.330608) (xy 386.283369 -281.369679) (xy 386.313393 -281.413716)
			(xy 386.336519 -281.461737) (xy 386.352229 -281.512667) (xy 386.360172 -281.565371) (xy 386.36067 -281.59202)
			(xy 386.360172 -281.618669) (xy 386.352229 -281.671373) (xy 386.336519 -281.722303) (xy 386.313393 -281.770324)
			(xy 386.283369 -281.814361) (xy 386.247117 -281.853432) (xy 386.205446 -281.886663) (xy 386.159288 -281.913312)
			(xy 386.109674 -281.932784) (xy 386.057712 -281.944644) (xy 386.004562 -281.948628) (xy 385.951412 -281.944644)
			(xy 385.89945 -281.932784) (xy 385.849836 -281.913312) (xy 385.803678 -281.886663) (xy 385.762007 -281.853432)
			(xy 385.725755 -281.814361) (xy 385.695731 -281.770324) (xy 385.672605 -281.722303) (xy 385.656895 -281.671373)
			(xy 385.648952 -281.618669) (xy 385.420372 -281.618669) (xy 385.412429 -281.671373) (xy 385.396719 -281.722303)
			(xy 385.373593 -281.770324) (xy 385.343569 -281.814361) (xy 385.307317 -281.853432) (xy 385.265646 -281.886663)
			(xy 385.219488 -281.913312) (xy 385.169874 -281.932784) (xy 385.117912 -281.944644) (xy 385.064762 -281.948628)
			(xy 385.011612 -281.944644) (xy 384.95965 -281.932784) (xy 384.910036 -281.913312) (xy 384.863878 -281.886663)
			(xy 384.822207 -281.853432) (xy 384.785955 -281.814361) (xy 384.755931 -281.770324) (xy 384.732805 -281.722303)
			(xy 384.717095 -281.671373) (xy 384.709152 -281.618669) (xy 384.480572 -281.618669) (xy 384.472629 -281.671373)
			(xy 384.456919 -281.722303) (xy 384.433793 -281.770324) (xy 384.403769 -281.814361) (xy 384.367517 -281.853432)
			(xy 384.325846 -281.886663) (xy 384.279688 -281.913312) (xy 384.230074 -281.932784) (xy 384.178112 -281.944644)
			(xy 384.124962 -281.948628) (xy 384.071812 -281.944644) (xy 384.01985 -281.932784) (xy 383.970236 -281.913312)
			(xy 383.924078 -281.886663) (xy 383.882407 -281.853432) (xy 383.846155 -281.814361) (xy 383.816131 -281.770324)
			(xy 383.793005 -281.722303) (xy 383.777295 -281.671373) (xy 383.769352 -281.618669) (xy 383.540772 -281.618669)
			(xy 383.532829 -281.671373) (xy 383.517119 -281.722303) (xy 383.493993 -281.770324) (xy 383.463969 -281.814361)
			(xy 383.427717 -281.853432) (xy 383.386046 -281.886663) (xy 383.339888 -281.913312) (xy 383.290274 -281.932784)
			(xy 383.238312 -281.944644) (xy 383.185162 -281.948628) (xy 383.132012 -281.944644) (xy 383.08005 -281.932784)
			(xy 383.030436 -281.913312) (xy 382.984278 -281.886663) (xy 382.942607 -281.853432) (xy 382.906355 -281.814361)
			(xy 382.876331 -281.770324) (xy 382.853205 -281.722303) (xy 382.837495 -281.671373) (xy 382.829552 -281.618669)
			(xy 382.601226 -281.618669) (xy 382.593283 -281.671373) (xy 382.577573 -281.722303) (xy 382.554447 -281.770324)
			(xy 382.524423 -281.814361) (xy 382.488171 -281.853432) (xy 382.4465 -281.886663) (xy 382.400342 -281.913312)
			(xy 382.350728 -281.932784) (xy 382.298766 -281.944644) (xy 382.245616 -281.948628) (xy 382.192466 -281.944644)
			(xy 382.140504 -281.932784) (xy 382.09089 -281.913312) (xy 382.044732 -281.886663) (xy 382.003061 -281.853432)
			(xy 381.966809 -281.814361) (xy 381.936785 -281.770324) (xy 381.913659 -281.722303) (xy 381.897949 -281.671373)
			(xy 381.890006 -281.618669) (xy 381.661426 -281.618669) (xy 381.653483 -281.671373) (xy 381.637773 -281.722303)
			(xy 381.614647 -281.770324) (xy 381.584623 -281.814361) (xy 381.548371 -281.853432) (xy 381.5067 -281.886663)
			(xy 381.460542 -281.913312) (xy 381.410928 -281.932784) (xy 381.358966 -281.944644) (xy 381.305816 -281.948628)
			(xy 381.252666 -281.944644) (xy 381.200704 -281.932784) (xy 381.15109 -281.913312) (xy 381.104932 -281.886663)
			(xy 381.063261 -281.853432) (xy 381.027009 -281.814361) (xy 380.996985 -281.770324) (xy 380.973859 -281.722303)
			(xy 380.958149 -281.671373) (xy 380.950206 -281.618669) (xy 380.721626 -281.618669) (xy 380.713683 -281.671373)
			(xy 380.697973 -281.722303) (xy 380.674847 -281.770324) (xy 380.644823 -281.814361) (xy 380.608571 -281.853432)
			(xy 380.5669 -281.886663) (xy 380.520742 -281.913312) (xy 380.471128 -281.932784) (xy 380.419166 -281.944644)
			(xy 380.366016 -281.948628) (xy 380.312866 -281.944644) (xy 380.260904 -281.932784) (xy 380.21129 -281.913312)
			(xy 380.165132 -281.886663) (xy 380.123461 -281.853432) (xy 380.087209 -281.814361) (xy 380.057185 -281.770324)
			(xy 380.034059 -281.722303) (xy 380.018349 -281.671373) (xy 380.010406 -281.618669) (xy 379.781826 -281.618669)
			(xy 379.773883 -281.671373) (xy 379.758173 -281.722303) (xy 379.735047 -281.770324) (xy 379.705023 -281.814361)
			(xy 379.668771 -281.853432) (xy 379.6271 -281.886663) (xy 379.580942 -281.913312) (xy 379.531328 -281.932784)
			(xy 379.479366 -281.944644) (xy 379.426216 -281.948628) (xy 379.373066 -281.944644) (xy 379.321104 -281.932784)
			(xy 379.27149 -281.913312) (xy 379.225332 -281.886663) (xy 379.183661 -281.853432) (xy 379.147409 -281.814361)
			(xy 379.117385 -281.770324) (xy 379.094259 -281.722303) (xy 379.078549 -281.671373) (xy 379.070606 -281.618669)
			(xy 378.842026 -281.618669) (xy 378.834083 -281.671373) (xy 378.818373 -281.722303) (xy 378.795247 -281.770324)
			(xy 378.765223 -281.814361) (xy 378.728971 -281.853432) (xy 378.6873 -281.886663) (xy 378.641142 -281.913312)
			(xy 378.591528 -281.932784) (xy 378.539566 -281.944644) (xy 378.486416 -281.948628) (xy 378.433266 -281.944644)
			(xy 378.381304 -281.932784) (xy 378.33169 -281.913312) (xy 378.285532 -281.886663) (xy 378.243861 -281.853432)
			(xy 378.207609 -281.814361) (xy 378.177585 -281.770324) (xy 378.154459 -281.722303) (xy 378.138749 -281.671373)
			(xy 378.130806 -281.618669) (xy 377.901972 -281.618669) (xy 377.894029 -281.671373) (xy 377.878319 -281.722303)
			(xy 377.855193 -281.770324) (xy 377.825169 -281.814361) (xy 377.788917 -281.853432) (xy 377.747246 -281.886663)
			(xy 377.701088 -281.913312) (xy 377.651474 -281.932784) (xy 377.599512 -281.944644) (xy 377.546362 -281.948628)
			(xy 377.493212 -281.944644) (xy 377.44125 -281.932784) (xy 377.391636 -281.913312) (xy 377.345478 -281.886663)
			(xy 377.303807 -281.853432) (xy 377.267555 -281.814361) (xy 377.237531 -281.770324) (xy 377.214405 -281.722303)
			(xy 377.198695 -281.671373) (xy 377.190752 -281.618669) (xy 376.962426 -281.618669) (xy 376.954483 -281.671373)
			(xy 376.938773 -281.722303) (xy 376.915647 -281.770324) (xy 376.885623 -281.814361) (xy 376.849371 -281.853432)
			(xy 376.8077 -281.886663) (xy 376.761542 -281.913312) (xy 376.711928 -281.932784) (xy 376.659966 -281.944644)
			(xy 376.606816 -281.948628) (xy 376.553666 -281.944644) (xy 376.501704 -281.932784) (xy 376.45209 -281.913312)
			(xy 376.405932 -281.886663) (xy 376.364261 -281.853432) (xy 376.328009 -281.814361) (xy 376.297985 -281.770324)
			(xy 376.274859 -281.722303) (xy 376.259149 -281.671373) (xy 376.251206 -281.618669) (xy 376.022334 -281.618669)
			(xy 376.014429 -281.671119) (xy 375.998719 -281.722049) (xy 375.975593 -281.77007) (xy 375.945569 -281.814107)
			(xy 375.909317 -281.853178) (xy 375.867646 -281.886409) (xy 375.821488 -281.913058) (xy 375.771874 -281.93253)
			(xy 375.719912 -281.94439) (xy 375.666762 -281.948374) (xy 375.613612 -281.94439) (xy 375.56165 -281.93253)
			(xy 375.512036 -281.913058) (xy 375.465878 -281.886409) (xy 375.424207 -281.853178) (xy 375.387955 -281.814107)
			(xy 375.357931 -281.77007) (xy 375.334805 -281.722049) (xy 375.319095 -281.671119) (xy 375.311152 -281.618415)
			(xy 375.082577 -281.618415) (xy 375.082572 -281.618669) (xy 375.074629 -281.671373) (xy 375.058919 -281.722303)
			(xy 375.035793 -281.770324) (xy 375.005769 -281.814361) (xy 374.969517 -281.853432) (xy 374.927846 -281.886663)
			(xy 374.881688 -281.913312) (xy 374.832074 -281.932784) (xy 374.780112 -281.944644) (xy 374.726962 -281.948628)
			(xy 374.673812 -281.944644) (xy 374.62185 -281.932784) (xy 374.572236 -281.913312) (xy 374.526078 -281.886663)
			(xy 374.484407 -281.853432) (xy 374.448155 -281.814361) (xy 374.418131 -281.770324) (xy 374.395005 -281.722303)
			(xy 374.379295 -281.671373) (xy 374.371352 -281.618669) (xy 374.143026 -281.618669) (xy 374.135083 -281.671373)
			(xy 374.119373 -281.722303) (xy 374.096247 -281.770324) (xy 374.066223 -281.814361) (xy 374.029971 -281.853432)
			(xy 373.9883 -281.886663) (xy 373.942142 -281.913312) (xy 373.892528 -281.932784) (xy 373.840566 -281.944644)
			(xy 373.787416 -281.948628) (xy 373.734266 -281.944644) (xy 373.682304 -281.932784) (xy 373.63269 -281.913312)
			(xy 373.586532 -281.886663) (xy 373.544861 -281.853432) (xy 373.508609 -281.814361) (xy 373.478585 -281.770324)
			(xy 373.455459 -281.722303) (xy 373.439749 -281.671373) (xy 373.431806 -281.618669) (xy 373.203226 -281.618669)
			(xy 373.195283 -281.671373) (xy 373.179573 -281.722303) (xy 373.156447 -281.770324) (xy 373.126423 -281.814361)
			(xy 373.090171 -281.853432) (xy 373.0485 -281.886663) (xy 373.002342 -281.913312) (xy 372.952728 -281.932784)
			(xy 372.900766 -281.944644) (xy 372.847616 -281.948628) (xy 372.794466 -281.944644) (xy 372.742504 -281.932784)
			(xy 372.69289 -281.913312) (xy 372.646732 -281.886663) (xy 372.605061 -281.853432) (xy 372.568809 -281.814361)
			(xy 372.538785 -281.770324) (xy 372.515659 -281.722303) (xy 372.499949 -281.671373) (xy 372.492006 -281.618669)
			(xy 372.263426 -281.618669) (xy 372.255483 -281.671373) (xy 372.239773 -281.722303) (xy 372.216647 -281.770324)
			(xy 372.186623 -281.814361) (xy 372.150371 -281.853432) (xy 372.1087 -281.886663) (xy 372.062542 -281.913312)
			(xy 372.012928 -281.932784) (xy 371.960966 -281.944644) (xy 371.907816 -281.948628) (xy 371.854666 -281.944644)
			(xy 371.802704 -281.932784) (xy 371.75309 -281.913312) (xy 371.706932 -281.886663) (xy 371.665261 -281.853432)
			(xy 371.629009 -281.814361) (xy 371.598985 -281.770324) (xy 371.575859 -281.722303) (xy 371.560149 -281.671373)
			(xy 371.552206 -281.618669) (xy 371.323626 -281.618669) (xy 371.315683 -281.671373) (xy 371.299973 -281.722303)
			(xy 371.276847 -281.770324) (xy 371.246823 -281.814361) (xy 371.210571 -281.853432) (xy 371.1689 -281.886663)
			(xy 371.122742 -281.913312) (xy 371.073128 -281.932784) (xy 371.021166 -281.944644) (xy 370.968016 -281.948628)
			(xy 370.914866 -281.944644) (xy 370.862904 -281.932784) (xy 370.81329 -281.913312) (xy 370.767132 -281.886663)
			(xy 370.725461 -281.853432) (xy 370.689209 -281.814361) (xy 370.659185 -281.770324) (xy 370.636059 -281.722303)
			(xy 370.620349 -281.671373) (xy 370.612406 -281.618669) (xy 370.383826 -281.618669) (xy 370.375883 -281.671373)
			(xy 370.360173 -281.722303) (xy 370.337047 -281.770324) (xy 370.307023 -281.814361) (xy 370.270771 -281.853432)
			(xy 370.2291 -281.886663) (xy 370.182942 -281.913312) (xy 370.133328 -281.932784) (xy 370.081366 -281.944644)
			(xy 370.028216 -281.948628) (xy 369.975066 -281.944644) (xy 369.923104 -281.932784) (xy 369.87349 -281.913312)
			(xy 369.827332 -281.886663) (xy 369.785661 -281.853432) (xy 369.749409 -281.814361) (xy 369.719385 -281.770324)
			(xy 369.696259 -281.722303) (xy 369.680549 -281.671373) (xy 369.672606 -281.618669) (xy 369.444026 -281.618669)
			(xy 369.436083 -281.671373) (xy 369.420373 -281.722303) (xy 369.397247 -281.770324) (xy 369.367223 -281.814361)
			(xy 369.330971 -281.853432) (xy 369.2893 -281.886663) (xy 369.243142 -281.913312) (xy 369.193528 -281.932784)
			(xy 369.141566 -281.944644) (xy 369.088416 -281.948628) (xy 369.035266 -281.944644) (xy 368.983304 -281.932784)
			(xy 368.93369 -281.913312) (xy 368.887532 -281.886663) (xy 368.845861 -281.853432) (xy 368.809609 -281.814361)
			(xy 368.779585 -281.770324) (xy 368.756459 -281.722303) (xy 368.740749 -281.671373) (xy 368.732806 -281.618669)
			(xy 368.504226 -281.618669) (xy 368.496283 -281.671373) (xy 368.480573 -281.722303) (xy 368.457447 -281.770324)
			(xy 368.427423 -281.814361) (xy 368.391171 -281.853432) (xy 368.3495 -281.886663) (xy 368.303342 -281.913312)
			(xy 368.253728 -281.932784) (xy 368.201766 -281.944644) (xy 368.148616 -281.948628) (xy 368.095466 -281.944644)
			(xy 368.043504 -281.932784) (xy 367.99389 -281.913312) (xy 367.947732 -281.886663) (xy 367.906061 -281.853432)
			(xy 367.869809 -281.814361) (xy 367.839785 -281.770324) (xy 367.816659 -281.722303) (xy 367.800949 -281.671373)
			(xy 367.793006 -281.618669) (xy 367.564426 -281.618669) (xy 367.556483 -281.671373) (xy 367.540773 -281.722303)
			(xy 367.517647 -281.770324) (xy 367.487623 -281.814361) (xy 367.451371 -281.853432) (xy 367.4097 -281.886663)
			(xy 367.363542 -281.913312) (xy 367.313928 -281.932784) (xy 367.261966 -281.944644) (xy 367.208816 -281.948628)
			(xy 367.155666 -281.944644) (xy 367.103704 -281.932784) (xy 367.05409 -281.913312) (xy 367.007932 -281.886663)
			(xy 366.966261 -281.853432) (xy 366.930009 -281.814361) (xy 366.899985 -281.770324) (xy 366.876859 -281.722303)
			(xy 366.861149 -281.671373) (xy 366.853206 -281.618669) (xy 366.624372 -281.618669) (xy 366.616429 -281.671373)
			(xy 366.600719 -281.722303) (xy 366.577593 -281.770324) (xy 366.547569 -281.814361) (xy 366.511317 -281.853432)
			(xy 366.469646 -281.886663) (xy 366.423488 -281.913312) (xy 366.373874 -281.932784) (xy 366.321912 -281.944644)
			(xy 366.268762 -281.948628) (xy 366.215612 -281.944644) (xy 366.16365 -281.932784) (xy 366.114036 -281.913312)
			(xy 366.067878 -281.886663) (xy 366.026207 -281.853432) (xy 365.989955 -281.814361) (xy 365.959931 -281.770324)
			(xy 365.936805 -281.722303) (xy 365.921095 -281.671373) (xy 365.913152 -281.618669) (xy 365.684826 -281.618669)
			(xy 365.676883 -281.671373) (xy 365.661173 -281.722303) (xy 365.638047 -281.770324) (xy 365.608023 -281.814361)
			(xy 365.571771 -281.853432) (xy 365.5301 -281.886663) (xy 365.483942 -281.913312) (xy 365.434328 -281.932784)
			(xy 365.382366 -281.944644) (xy 365.329216 -281.948628) (xy 365.276066 -281.944644) (xy 365.224104 -281.932784)
			(xy 365.17449 -281.913312) (xy 365.128332 -281.886663) (xy 365.086661 -281.853432) (xy 365.050409 -281.814361)
			(xy 365.020385 -281.770324) (xy 364.997259 -281.722303) (xy 364.981549 -281.671373) (xy 364.973606 -281.618669)
			(xy 361.925372 -281.618669) (xy 361.917429 -281.671373) (xy 361.901719 -281.722303) (xy 361.878593 -281.770324)
			(xy 361.848569 -281.814361) (xy 361.812317 -281.853432) (xy 361.770646 -281.886663) (xy 361.724488 -281.913312)
			(xy 361.674874 -281.932784) (xy 361.622912 -281.944644) (xy 361.569762 -281.948628) (xy 361.516612 -281.944644)
			(xy 361.46465 -281.932784) (xy 361.415036 -281.913312) (xy 361.368878 -281.886663) (xy 361.327207 -281.853432)
			(xy 361.290955 -281.814361) (xy 361.260931 -281.770324) (xy 361.237805 -281.722303) (xy 361.222095 -281.671373)
			(xy 361.214152 -281.618669) (xy 355.347026 -281.618669) (xy 355.339083 -281.671373) (xy 355.323373 -281.722303)
			(xy 355.300247 -281.770324) (xy 355.270223 -281.814361) (xy 355.233971 -281.853432) (xy 355.1923 -281.886663)
			(xy 355.146142 -281.913312) (xy 355.096528 -281.932784) (xy 355.044566 -281.944644) (xy 354.991416 -281.948628)
			(xy 354.938266 -281.944644) (xy 354.886304 -281.932784) (xy 354.83669 -281.913312) (xy 354.790532 -281.886663)
			(xy 354.748861 -281.853432) (xy 354.712609 -281.814361) (xy 354.682585 -281.770324) (xy 354.659459 -281.722303)
			(xy 354.643749 -281.671373) (xy 354.635806 -281.618669) (xy 354.380762 -281.618669) (xy 354.380739 -281.619802)
			(xy 354.371414 -281.674578) (xy 354.362766 -281.700986) (xy 354.354892 -281.72283) (xy 354.55987 -282.077668)
			(xy 354.58273 -282.081986) (xy 354.607543 -282.087133) (xy 354.655283 -282.104127) (xy 354.699861 -282.128227)
			(xy 354.740227 -282.158863) (xy 354.775429 -282.195315) (xy 354.80464 -282.236724) (xy 354.82717 -282.282115)
			(xy 354.84249 -282.330419) (xy 354.850239 -282.380498) (xy 354.8507 -282.405836) (xy 354.850192 -282.431723)
			(xy 354.850071 -282.432485) (xy 355.105452 -282.432485) (xy 355.105452 -282.379187) (xy 355.113395 -282.326483)
			(xy 355.129105 -282.275553) (xy 355.152231 -282.227532) (xy 355.182255 -282.183495) (xy 355.218507 -282.144424)
			(xy 355.260178 -282.111193) (xy 355.306336 -282.084544) (xy 355.35595 -282.065072) (xy 355.407912 -282.053212)
			(xy 355.461062 -282.049229) (xy 355.514212 -282.053212) (xy 355.566174 -282.065072) (xy 355.615788 -282.084544)
			(xy 355.661946 -282.111193) (xy 355.703617 -282.144424) (xy 355.739869 -282.183495) (xy 355.769893 -282.227532)
			(xy 355.793019 -282.275553) (xy 355.808729 -282.326483) (xy 355.816672 -282.379187) (xy 355.81717 -282.405836)
			(xy 355.816672 -282.432485) (xy 357.924852 -282.432485) (xy 357.924852 -282.379187) (xy 357.932795 -282.326483)
			(xy 357.948505 -282.275553) (xy 357.971631 -282.227532) (xy 358.001655 -282.183495) (xy 358.037907 -282.144424)
			(xy 358.079578 -282.111193) (xy 358.125736 -282.084544) (xy 358.17535 -282.065072) (xy 358.227312 -282.053212)
			(xy 358.280462 -282.049229) (xy 358.333612 -282.053212) (xy 358.385574 -282.065072) (xy 358.435188 -282.084544)
			(xy 358.481346 -282.111193) (xy 358.523017 -282.144424) (xy 358.559269 -282.183495) (xy 358.589293 -282.227532)
			(xy 358.612419 -282.275553) (xy 358.628129 -282.326483) (xy 358.636072 -282.379187) (xy 358.63657 -282.405836)
			(xy 358.636072 -282.432485) (xy 365.443506 -282.432485) (xy 365.443506 -282.379187) (xy 365.451449 -282.326483)
			(xy 365.467159 -282.275553) (xy 365.490285 -282.227532) (xy 365.520309 -282.183495) (xy 365.556561 -282.144424)
			(xy 365.598232 -282.111193) (xy 365.64439 -282.084544) (xy 365.694004 -282.065072) (xy 365.745966 -282.053212)
			(xy 365.799116 -282.049229) (xy 365.852266 -282.053212) (xy 365.904228 -282.065072) (xy 365.953842 -282.084544)
			(xy 366 -282.111193) (xy 366.041671 -282.144424) (xy 366.077923 -282.183495) (xy 366.107947 -282.227532)
			(xy 366.131073 -282.275553) (xy 366.146783 -282.326483) (xy 366.154726 -282.379187) (xy 366.155224 -282.405836)
			(xy 366.154726 -282.432485) (xy 366.383052 -282.432485) (xy 366.383052 -282.379187) (xy 366.390995 -282.326483)
			(xy 366.406705 -282.275553) (xy 366.429831 -282.227532) (xy 366.459855 -282.183495) (xy 366.496107 -282.144424)
			(xy 366.537778 -282.111193) (xy 366.583936 -282.084544) (xy 366.63355 -282.065072) (xy 366.685512 -282.053212)
			(xy 366.738662 -282.049229) (xy 366.791812 -282.053212) (xy 366.843774 -282.065072) (xy 366.893388 -282.084544)
			(xy 366.939546 -282.111193) (xy 366.981217 -282.144424) (xy 367.017469 -282.183495) (xy 367.047493 -282.227532)
			(xy 367.070619 -282.275553) (xy 367.086329 -282.326483) (xy 367.094272 -282.379187) (xy 367.09477 -282.405836)
			(xy 367.094272 -282.432485) (xy 367.322852 -282.432485) (xy 367.322852 -282.379187) (xy 367.330795 -282.326483)
			(xy 367.346505 -282.275553) (xy 367.369631 -282.227532) (xy 367.399655 -282.183495) (xy 367.435907 -282.144424)
			(xy 367.477578 -282.111193) (xy 367.523736 -282.084544) (xy 367.57335 -282.065072) (xy 367.625312 -282.053212)
			(xy 367.678462 -282.049229) (xy 367.731612 -282.053212) (xy 367.783574 -282.065072) (xy 367.833188 -282.084544)
			(xy 367.879346 -282.111193) (xy 367.921017 -282.144424) (xy 367.957269 -282.183495) (xy 367.987293 -282.227532)
			(xy 368.010419 -282.275553) (xy 368.026129 -282.326483) (xy 368.034072 -282.379187) (xy 368.03457 -282.405836)
			(xy 368.034072 -282.432485) (xy 368.262652 -282.432485) (xy 368.262652 -282.379187) (xy 368.270595 -282.326483)
			(xy 368.286305 -282.275553) (xy 368.309431 -282.227532) (xy 368.339455 -282.183495) (xy 368.375707 -282.144424)
			(xy 368.417378 -282.111193) (xy 368.463536 -282.084544) (xy 368.51315 -282.065072) (xy 368.565112 -282.053212)
			(xy 368.618262 -282.049229) (xy 368.671412 -282.053212) (xy 368.723374 -282.065072) (xy 368.772988 -282.084544)
			(xy 368.819146 -282.111193) (xy 368.860817 -282.144424) (xy 368.897069 -282.183495) (xy 368.927093 -282.227532)
			(xy 368.950219 -282.275553) (xy 368.965929 -282.326483) (xy 368.973872 -282.379187) (xy 368.97437 -282.405836)
			(xy 368.973872 -282.432485) (xy 369.202452 -282.432485) (xy 369.202452 -282.379187) (xy 369.210395 -282.326483)
			(xy 369.226105 -282.275553) (xy 369.249231 -282.227532) (xy 369.279255 -282.183495) (xy 369.315507 -282.144424)
			(xy 369.357178 -282.111193) (xy 369.403336 -282.084544) (xy 369.45295 -282.065072) (xy 369.504912 -282.053212)
			(xy 369.558062 -282.049229) (xy 369.611212 -282.053212) (xy 369.663174 -282.065072) (xy 369.712788 -282.084544)
			(xy 369.758946 -282.111193) (xy 369.800617 -282.144424) (xy 369.836869 -282.183495) (xy 369.866893 -282.227532)
			(xy 369.890019 -282.275553) (xy 369.905729 -282.326483) (xy 369.913672 -282.379187) (xy 369.91417 -282.405836)
			(xy 369.913672 -282.432485) (xy 370.142252 -282.432485) (xy 370.142252 -282.379187) (xy 370.150195 -282.326483)
			(xy 370.165905 -282.275553) (xy 370.189031 -282.227532) (xy 370.219055 -282.183495) (xy 370.255307 -282.144424)
			(xy 370.296978 -282.111193) (xy 370.343136 -282.084544) (xy 370.39275 -282.065072) (xy 370.444712 -282.053212)
			(xy 370.497862 -282.049229) (xy 370.551012 -282.053212) (xy 370.602974 -282.065072) (xy 370.652588 -282.084544)
			(xy 370.698746 -282.111193) (xy 370.740417 -282.144424) (xy 370.776669 -282.183495) (xy 370.806693 -282.227532)
			(xy 370.829819 -282.275553) (xy 370.845529 -282.326483) (xy 370.853472 -282.379187) (xy 370.85397 -282.405836)
			(xy 370.853472 -282.432485) (xy 371.082052 -282.432485) (xy 371.082052 -282.379187) (xy 371.089995 -282.326483)
			(xy 371.105705 -282.275553) (xy 371.128831 -282.227532) (xy 371.158855 -282.183495) (xy 371.195107 -282.144424)
			(xy 371.236778 -282.111193) (xy 371.282936 -282.084544) (xy 371.33255 -282.065072) (xy 371.384512 -282.053212)
			(xy 371.437662 -282.049229) (xy 371.490812 -282.053212) (xy 371.542774 -282.065072) (xy 371.592388 -282.084544)
			(xy 371.638546 -282.111193) (xy 371.680217 -282.144424) (xy 371.716469 -282.183495) (xy 371.746493 -282.227532)
			(xy 371.769619 -282.275553) (xy 371.785329 -282.326483) (xy 371.793272 -282.379187) (xy 371.79377 -282.405836)
			(xy 371.793272 -282.432485) (xy 372.021852 -282.432485) (xy 372.021852 -282.379187) (xy 372.029795 -282.326483)
			(xy 372.045505 -282.275553) (xy 372.068631 -282.227532) (xy 372.098655 -282.183495) (xy 372.134907 -282.144424)
			(xy 372.176578 -282.111193) (xy 372.222736 -282.084544) (xy 372.27235 -282.065072) (xy 372.324312 -282.053212)
			(xy 372.377462 -282.049229) (xy 372.430612 -282.053212) (xy 372.482574 -282.065072) (xy 372.532188 -282.084544)
			(xy 372.578346 -282.111193) (xy 372.620017 -282.144424) (xy 372.656269 -282.183495) (xy 372.686293 -282.227532)
			(xy 372.709419 -282.275553) (xy 372.725129 -282.326483) (xy 372.733072 -282.379187) (xy 372.73357 -282.405836)
			(xy 372.733072 -282.432485) (xy 372.961652 -282.432485) (xy 372.961652 -282.379187) (xy 372.969595 -282.326483)
			(xy 372.985305 -282.275553) (xy 373.008431 -282.227532) (xy 373.038455 -282.183495) (xy 373.074707 -282.144424)
			(xy 373.116378 -282.111193) (xy 373.162536 -282.084544) (xy 373.21215 -282.065072) (xy 373.264112 -282.053212)
			(xy 373.317262 -282.049229) (xy 373.370412 -282.053212) (xy 373.422374 -282.065072) (xy 373.471988 -282.084544)
			(xy 373.518146 -282.111193) (xy 373.559817 -282.144424) (xy 373.596069 -282.183495) (xy 373.626093 -282.227532)
			(xy 373.649219 -282.275553) (xy 373.664929 -282.326483) (xy 373.672872 -282.379187) (xy 373.67337 -282.405836)
			(xy 373.672872 -282.432485) (xy 373.901706 -282.432485) (xy 373.901706 -282.379187) (xy 373.909649 -282.326483)
			(xy 373.925359 -282.275553) (xy 373.948485 -282.227532) (xy 373.978509 -282.183495) (xy 374.014761 -282.144424)
			(xy 374.056432 -282.111193) (xy 374.10259 -282.084544) (xy 374.152204 -282.065072) (xy 374.204166 -282.053212)
			(xy 374.257316 -282.049229) (xy 374.310466 -282.053212) (xy 374.362428 -282.065072) (xy 374.412042 -282.084544)
			(xy 374.4582 -282.111193) (xy 374.499871 -282.144424) (xy 374.536123 -282.183495) (xy 374.566147 -282.227532)
			(xy 374.589273 -282.275553) (xy 374.604983 -282.326483) (xy 374.612926 -282.379187) (xy 374.613424 -282.405836)
			(xy 374.612931 -282.432231) (xy 374.841506 -282.432231) (xy 374.841506 -282.378933) (xy 374.849449 -282.326229)
			(xy 374.865159 -282.275299) (xy 374.888285 -282.227278) (xy 374.918309 -282.183241) (xy 374.954561 -282.14417)
			(xy 374.996232 -282.110939) (xy 375.04239 -282.08429) (xy 375.092004 -282.064818) (xy 375.143966 -282.052958)
			(xy 375.197116 -282.048975) (xy 375.250266 -282.052958) (xy 375.302228 -282.064818) (xy 375.351842 -282.08429)
			(xy 375.398 -282.110939) (xy 375.439671 -282.14417) (xy 375.475923 -282.183241) (xy 375.505947 -282.227278)
			(xy 375.529073 -282.275299) (xy 375.544783 -282.326229) (xy 375.552726 -282.378933) (xy 375.553224 -282.405582)
			(xy 375.552726 -282.432231) (xy 375.781306 -282.432231) (xy 375.781306 -282.378933) (xy 375.789249 -282.326229)
			(xy 375.804959 -282.275299) (xy 375.828085 -282.227278) (xy 375.858109 -282.183241) (xy 375.894361 -282.14417)
			(xy 375.936032 -282.110939) (xy 375.98219 -282.08429) (xy 376.031804 -282.064818) (xy 376.083766 -282.052958)
			(xy 376.136916 -282.048975) (xy 376.190066 -282.052958) (xy 376.242028 -282.064818) (xy 376.291642 -282.08429)
			(xy 376.3378 -282.110939) (xy 376.379471 -282.14417) (xy 376.415723 -282.183241) (xy 376.445747 -282.227278)
			(xy 376.468873 -282.275299) (xy 376.484583 -282.326229) (xy 376.492526 -282.378933) (xy 376.493024 -282.405582)
			(xy 376.492526 -282.432231) (xy 376.721106 -282.432231) (xy 376.721106 -282.378933) (xy 376.729049 -282.326229)
			(xy 376.744759 -282.275299) (xy 376.767885 -282.227278) (xy 376.797909 -282.183241) (xy 376.834161 -282.14417)
			(xy 376.875832 -282.110939) (xy 376.92199 -282.08429) (xy 376.971604 -282.064818) (xy 377.023566 -282.052958)
			(xy 377.076716 -282.048975) (xy 377.129866 -282.052958) (xy 377.181828 -282.064818) (xy 377.231442 -282.08429)
			(xy 377.2776 -282.110939) (xy 377.319271 -282.14417) (xy 377.355523 -282.183241) (xy 377.385547 -282.227278)
			(xy 377.408673 -282.275299) (xy 377.424383 -282.326229) (xy 377.432326 -282.378933) (xy 377.432824 -282.405582)
			(xy 377.432326 -282.432231) (xy 377.660906 -282.432231) (xy 377.660906 -282.378933) (xy 377.668849 -282.326229)
			(xy 377.684559 -282.275299) (xy 377.707685 -282.227278) (xy 377.737709 -282.183241) (xy 377.773961 -282.14417)
			(xy 377.815632 -282.110939) (xy 377.86179 -282.08429) (xy 377.911404 -282.064818) (xy 377.963366 -282.052958)
			(xy 378.016516 -282.048975) (xy 378.069666 -282.052958) (xy 378.121628 -282.064818) (xy 378.171242 -282.08429)
			(xy 378.2174 -282.110939) (xy 378.259071 -282.14417) (xy 378.295323 -282.183241) (xy 378.325347 -282.227278)
			(xy 378.348473 -282.275299) (xy 378.364183 -282.326229) (xy 378.372126 -282.378933) (xy 378.372624 -282.405582)
			(xy 378.372126 -282.432231) (xy 378.372088 -282.432485) (xy 378.600452 -282.432485) (xy 378.600452 -282.379187)
			(xy 378.608395 -282.326483) (xy 378.624105 -282.275553) (xy 378.647231 -282.227532) (xy 378.677255 -282.183495)
			(xy 378.713507 -282.144424) (xy 378.755178 -282.111193) (xy 378.801336 -282.084544) (xy 378.85095 -282.065072)
			(xy 378.902912 -282.053212) (xy 378.956062 -282.049229) (xy 379.009212 -282.053212) (xy 379.061174 -282.065072)
			(xy 379.110788 -282.084544) (xy 379.156946 -282.111193) (xy 379.198617 -282.144424) (xy 379.234869 -282.183495)
			(xy 379.264893 -282.227532) (xy 379.288019 -282.275553) (xy 379.303729 -282.326483) (xy 379.311672 -282.379187)
			(xy 379.31217 -282.405836) (xy 379.311672 -282.432485) (xy 379.540252 -282.432485) (xy 379.540252 -282.379187)
			(xy 379.548195 -282.326483) (xy 379.563905 -282.275553) (xy 379.587031 -282.227532) (xy 379.617055 -282.183495)
			(xy 379.653307 -282.144424) (xy 379.694978 -282.111193) (xy 379.741136 -282.084544) (xy 379.79075 -282.065072)
			(xy 379.842712 -282.053212) (xy 379.895862 -282.049229) (xy 379.949012 -282.053212) (xy 380.000974 -282.065072)
			(xy 380.050588 -282.084544) (xy 380.096746 -282.111193) (xy 380.138417 -282.144424) (xy 380.174669 -282.183495)
			(xy 380.204693 -282.227532) (xy 380.227819 -282.275553) (xy 380.243529 -282.326483) (xy 380.251472 -282.379187)
			(xy 380.25197 -282.405836) (xy 380.251472 -282.432485) (xy 380.480052 -282.432485) (xy 380.480052 -282.379187)
			(xy 380.487995 -282.326483) (xy 380.503705 -282.275553) (xy 380.526831 -282.227532) (xy 380.556855 -282.183495)
			(xy 380.593107 -282.144424) (xy 380.634778 -282.111193) (xy 380.680936 -282.084544) (xy 380.73055 -282.065072)
			(xy 380.782512 -282.053212) (xy 380.835662 -282.049229) (xy 380.888812 -282.053212) (xy 380.940774 -282.065072)
			(xy 380.990388 -282.084544) (xy 381.036546 -282.111193) (xy 381.078217 -282.144424) (xy 381.114469 -282.183495)
			(xy 381.144493 -282.227532) (xy 381.167619 -282.275553) (xy 381.183329 -282.326483) (xy 381.191272 -282.379187)
			(xy 381.19177 -282.405836) (xy 381.191272 -282.432485) (xy 381.419852 -282.432485) (xy 381.419852 -282.379187)
			(xy 381.427795 -282.326483) (xy 381.443505 -282.275553) (xy 381.466631 -282.227532) (xy 381.496655 -282.183495)
			(xy 381.532907 -282.144424) (xy 381.574578 -282.111193) (xy 381.620736 -282.084544) (xy 381.67035 -282.065072)
			(xy 381.722312 -282.053212) (xy 381.775462 -282.049229) (xy 381.828612 -282.053212) (xy 381.880574 -282.065072)
			(xy 381.930188 -282.084544) (xy 381.976346 -282.111193) (xy 382.018017 -282.144424) (xy 382.054269 -282.183495)
			(xy 382.084293 -282.227532) (xy 382.107419 -282.275553) (xy 382.123129 -282.326483) (xy 382.131072 -282.379187)
			(xy 382.13157 -282.405836) (xy 382.131072 -282.432485) (xy 382.359906 -282.432485) (xy 382.359906 -282.379187)
			(xy 382.367849 -282.326483) (xy 382.383559 -282.275553) (xy 382.406685 -282.227532) (xy 382.436709 -282.183495)
			(xy 382.472961 -282.144424) (xy 382.514632 -282.111193) (xy 382.56079 -282.084544) (xy 382.610404 -282.065072)
			(xy 382.662366 -282.053212) (xy 382.715516 -282.049229) (xy 382.768666 -282.053212) (xy 382.820628 -282.065072)
			(xy 382.870242 -282.084544) (xy 382.9164 -282.111193) (xy 382.958071 -282.144424) (xy 382.994323 -282.183495)
			(xy 383.024347 -282.227532) (xy 383.047473 -282.275553) (xy 383.063183 -282.326483) (xy 383.071126 -282.379187)
			(xy 383.071624 -282.405836) (xy 383.071126 -282.432485) (xy 383.299452 -282.432485) (xy 383.299452 -282.379187)
			(xy 383.307395 -282.326483) (xy 383.323105 -282.275553) (xy 383.346231 -282.227532) (xy 383.376255 -282.183495)
			(xy 383.412507 -282.144424) (xy 383.454178 -282.111193) (xy 383.500336 -282.084544) (xy 383.54995 -282.065072)
			(xy 383.601912 -282.053212) (xy 383.655062 -282.049229) (xy 383.708212 -282.053212) (xy 383.760174 -282.065072)
			(xy 383.809788 -282.084544) (xy 383.855946 -282.111193) (xy 383.897617 -282.144424) (xy 383.933869 -282.183495)
			(xy 383.963893 -282.227532) (xy 383.987019 -282.275553) (xy 384.002729 -282.326483) (xy 384.010672 -282.379187)
			(xy 384.01117 -282.405836) (xy 384.010672 -282.432485) (xy 384.239252 -282.432485) (xy 384.239252 -282.379187)
			(xy 384.247195 -282.326483) (xy 384.262905 -282.275553) (xy 384.286031 -282.227532) (xy 384.316055 -282.183495)
			(xy 384.352307 -282.144424) (xy 384.393978 -282.111193) (xy 384.440136 -282.084544) (xy 384.48975 -282.065072)
			(xy 384.541712 -282.053212) (xy 384.594862 -282.049229) (xy 384.648012 -282.053212) (xy 384.699974 -282.065072)
			(xy 384.749588 -282.084544) (xy 384.795746 -282.111193) (xy 384.837417 -282.144424) (xy 384.873669 -282.183495)
			(xy 384.903693 -282.227532) (xy 384.926819 -282.275553) (xy 384.942529 -282.326483) (xy 384.950472 -282.379187)
			(xy 384.95097 -282.405836) (xy 384.950472 -282.432485) (xy 385.179052 -282.432485) (xy 385.179052 -282.379187)
			(xy 385.186995 -282.326483) (xy 385.202705 -282.275553) (xy 385.225831 -282.227532) (xy 385.255855 -282.183495)
			(xy 385.292107 -282.144424) (xy 385.333778 -282.111193) (xy 385.379936 -282.084544) (xy 385.42955 -282.065072)
			(xy 385.481512 -282.053212) (xy 385.534662 -282.049229) (xy 385.587812 -282.053212) (xy 385.639774 -282.065072)
			(xy 385.689388 -282.084544) (xy 385.735546 -282.111193) (xy 385.777217 -282.144424) (xy 385.813469 -282.183495)
			(xy 385.843493 -282.227532) (xy 385.866619 -282.275553) (xy 385.882329 -282.326483) (xy 385.890272 -282.379187)
			(xy 385.89077 -282.405836) (xy 385.890272 -282.432485) (xy 386.118852 -282.432485) (xy 386.118852 -282.379187)
			(xy 386.126795 -282.326483) (xy 386.142505 -282.275553) (xy 386.165631 -282.227532) (xy 386.195655 -282.183495)
			(xy 386.231907 -282.144424) (xy 386.273578 -282.111193) (xy 386.319736 -282.084544) (xy 386.36935 -282.065072)
			(xy 386.421312 -282.053212) (xy 386.474462 -282.049229) (xy 386.527612 -282.053212) (xy 386.579574 -282.065072)
			(xy 386.629188 -282.084544) (xy 386.675346 -282.111193) (xy 386.717017 -282.144424) (xy 386.753269 -282.183495)
			(xy 386.783293 -282.227532) (xy 386.806419 -282.275553) (xy 386.822129 -282.326483) (xy 386.830072 -282.379187)
			(xy 386.83057 -282.405836) (xy 386.830072 -282.432485) (xy 386.822129 -282.485189) (xy 386.806419 -282.536119)
			(xy 386.783293 -282.58414) (xy 386.753269 -282.628177) (xy 386.717017 -282.667248) (xy 386.675346 -282.700479)
			(xy 386.629188 -282.727128) (xy 386.579574 -282.7466) (xy 386.527612 -282.75846) (xy 386.474462 -282.762444)
			(xy 386.421312 -282.75846) (xy 386.36935 -282.7466) (xy 386.319736 -282.727128) (xy 386.273578 -282.700479)
			(xy 386.231907 -282.667248) (xy 386.195655 -282.628177) (xy 386.165631 -282.58414) (xy 386.142505 -282.536119)
			(xy 386.126795 -282.485189) (xy 386.118852 -282.432485) (xy 385.890272 -282.432485) (xy 385.882329 -282.485189)
			(xy 385.866619 -282.536119) (xy 385.843493 -282.58414) (xy 385.813469 -282.628177) (xy 385.777217 -282.667248)
			(xy 385.735546 -282.700479) (xy 385.689388 -282.727128) (xy 385.639774 -282.7466) (xy 385.587812 -282.75846)
			(xy 385.534662 -282.762444) (xy 385.481512 -282.75846) (xy 385.42955 -282.7466) (xy 385.379936 -282.727128)
			(xy 385.333778 -282.700479) (xy 385.292107 -282.667248) (xy 385.255855 -282.628177) (xy 385.225831 -282.58414)
			(xy 385.202705 -282.536119) (xy 385.186995 -282.485189) (xy 385.179052 -282.432485) (xy 384.950472 -282.432485)
			(xy 384.942529 -282.485189) (xy 384.926819 -282.536119) (xy 384.903693 -282.58414) (xy 384.873669 -282.628177)
			(xy 384.837417 -282.667248) (xy 384.795746 -282.700479) (xy 384.749588 -282.727128) (xy 384.699974 -282.7466)
			(xy 384.648012 -282.75846) (xy 384.594862 -282.762444) (xy 384.541712 -282.75846) (xy 384.48975 -282.7466)
			(xy 384.440136 -282.727128) (xy 384.393978 -282.700479) (xy 384.352307 -282.667248) (xy 384.316055 -282.628177)
			(xy 384.286031 -282.58414) (xy 384.262905 -282.536119) (xy 384.247195 -282.485189) (xy 384.239252 -282.432485)
			(xy 384.010672 -282.432485) (xy 384.002729 -282.485189) (xy 383.987019 -282.536119) (xy 383.963893 -282.58414)
			(xy 383.933869 -282.628177) (xy 383.897617 -282.667248) (xy 383.855946 -282.700479) (xy 383.809788 -282.727128)
			(xy 383.760174 -282.7466) (xy 383.708212 -282.75846) (xy 383.655062 -282.762444) (xy 383.601912 -282.75846)
			(xy 383.54995 -282.7466) (xy 383.500336 -282.727128) (xy 383.454178 -282.700479) (xy 383.412507 -282.667248)
			(xy 383.376255 -282.628177) (xy 383.346231 -282.58414) (xy 383.323105 -282.536119) (xy 383.307395 -282.485189)
			(xy 383.299452 -282.432485) (xy 383.071126 -282.432485) (xy 383.063183 -282.485189) (xy 383.047473 -282.536119)
			(xy 383.024347 -282.58414) (xy 382.994323 -282.628177) (xy 382.958071 -282.667248) (xy 382.9164 -282.700479)
			(xy 382.870242 -282.727128) (xy 382.820628 -282.7466) (xy 382.768666 -282.75846) (xy 382.715516 -282.762444)
			(xy 382.662366 -282.75846) (xy 382.610404 -282.7466) (xy 382.56079 -282.727128) (xy 382.514632 -282.700479)
			(xy 382.472961 -282.667248) (xy 382.436709 -282.628177) (xy 382.406685 -282.58414) (xy 382.383559 -282.536119)
			(xy 382.367849 -282.485189) (xy 382.359906 -282.432485) (xy 382.131072 -282.432485) (xy 382.123129 -282.485189)
			(xy 382.107419 -282.536119) (xy 382.084293 -282.58414) (xy 382.054269 -282.628177) (xy 382.018017 -282.667248)
			(xy 381.976346 -282.700479) (xy 381.930188 -282.727128) (xy 381.880574 -282.7466) (xy 381.828612 -282.75846)
			(xy 381.775462 -282.762444) (xy 381.722312 -282.75846) (xy 381.67035 -282.7466) (xy 381.620736 -282.727128)
			(xy 381.574578 -282.700479) (xy 381.532907 -282.667248) (xy 381.496655 -282.628177) (xy 381.466631 -282.58414)
			(xy 381.443505 -282.536119) (xy 381.427795 -282.485189) (xy 381.419852 -282.432485) (xy 381.191272 -282.432485)
			(xy 381.183329 -282.485189) (xy 381.167619 -282.536119) (xy 381.144493 -282.58414) (xy 381.114469 -282.628177)
			(xy 381.078217 -282.667248) (xy 381.036546 -282.700479) (xy 380.990388 -282.727128) (xy 380.940774 -282.7466)
			(xy 380.888812 -282.75846) (xy 380.835662 -282.762444) (xy 380.782512 -282.75846) (xy 380.73055 -282.7466)
			(xy 380.680936 -282.727128) (xy 380.634778 -282.700479) (xy 380.593107 -282.667248) (xy 380.556855 -282.628177)
			(xy 380.526831 -282.58414) (xy 380.503705 -282.536119) (xy 380.487995 -282.485189) (xy 380.480052 -282.432485)
			(xy 380.251472 -282.432485) (xy 380.243529 -282.485189) (xy 380.227819 -282.536119) (xy 380.204693 -282.58414)
			(xy 380.174669 -282.628177) (xy 380.138417 -282.667248) (xy 380.096746 -282.700479) (xy 380.050588 -282.727128)
			(xy 380.000974 -282.7466) (xy 379.949012 -282.75846) (xy 379.895862 -282.762444) (xy 379.842712 -282.75846)
			(xy 379.79075 -282.7466) (xy 379.741136 -282.727128) (xy 379.694978 -282.700479) (xy 379.653307 -282.667248)
			(xy 379.617055 -282.628177) (xy 379.587031 -282.58414) (xy 379.563905 -282.536119) (xy 379.548195 -282.485189)
			(xy 379.540252 -282.432485) (xy 379.311672 -282.432485) (xy 379.303729 -282.485189) (xy 379.288019 -282.536119)
			(xy 379.264893 -282.58414) (xy 379.234869 -282.628177) (xy 379.198617 -282.667248) (xy 379.156946 -282.700479)
			(xy 379.110788 -282.727128) (xy 379.061174 -282.7466) (xy 379.009212 -282.75846) (xy 378.956062 -282.762444)
			(xy 378.902912 -282.75846) (xy 378.85095 -282.7466) (xy 378.801336 -282.727128) (xy 378.755178 -282.700479)
			(xy 378.713507 -282.667248) (xy 378.677255 -282.628177) (xy 378.647231 -282.58414) (xy 378.624105 -282.536119)
			(xy 378.608395 -282.485189) (xy 378.600452 -282.432485) (xy 378.372088 -282.432485) (xy 378.364183 -282.484935)
			(xy 378.348473 -282.535865) (xy 378.325347 -282.583886) (xy 378.295323 -282.627923) (xy 378.259071 -282.666994)
			(xy 378.2174 -282.700225) (xy 378.171242 -282.726874) (xy 378.121628 -282.746346) (xy 378.069666 -282.758206)
			(xy 378.016516 -282.76219) (xy 377.963366 -282.758206) (xy 377.911404 -282.746346) (xy 377.86179 -282.726874)
			(xy 377.815632 -282.700225) (xy 377.773961 -282.666994) (xy 377.737709 -282.627923) (xy 377.707685 -282.583886)
			(xy 377.684559 -282.535865) (xy 377.668849 -282.484935) (xy 377.660906 -282.432231) (xy 377.432326 -282.432231)
			(xy 377.424383 -282.484935) (xy 377.408673 -282.535865) (xy 377.385547 -282.583886) (xy 377.355523 -282.627923)
			(xy 377.319271 -282.666994) (xy 377.2776 -282.700225) (xy 377.231442 -282.726874) (xy 377.181828 -282.746346)
			(xy 377.129866 -282.758206) (xy 377.076716 -282.76219) (xy 377.023566 -282.758206) (xy 376.971604 -282.746346)
			(xy 376.92199 -282.726874) (xy 376.875832 -282.700225) (xy 376.834161 -282.666994) (xy 376.797909 -282.627923)
			(xy 376.767885 -282.583886) (xy 376.744759 -282.535865) (xy 376.729049 -282.484935) (xy 376.721106 -282.432231)
			(xy 376.492526 -282.432231) (xy 376.484583 -282.484935) (xy 376.468873 -282.535865) (xy 376.445747 -282.583886)
			(xy 376.415723 -282.627923) (xy 376.379471 -282.666994) (xy 376.3378 -282.700225) (xy 376.291642 -282.726874)
			(xy 376.242028 -282.746346) (xy 376.190066 -282.758206) (xy 376.136916 -282.76219) (xy 376.083766 -282.758206)
			(xy 376.031804 -282.746346) (xy 375.98219 -282.726874) (xy 375.936032 -282.700225) (xy 375.894361 -282.666994)
			(xy 375.858109 -282.627923) (xy 375.828085 -282.583886) (xy 375.804959 -282.535865) (xy 375.789249 -282.484935)
			(xy 375.781306 -282.432231) (xy 375.552726 -282.432231) (xy 375.544783 -282.484935) (xy 375.529073 -282.535865)
			(xy 375.505947 -282.583886) (xy 375.475923 -282.627923) (xy 375.439671 -282.666994) (xy 375.398 -282.700225)
			(xy 375.351842 -282.726874) (xy 375.302228 -282.746346) (xy 375.250266 -282.758206) (xy 375.197116 -282.76219)
			(xy 375.143966 -282.758206) (xy 375.092004 -282.746346) (xy 375.04239 -282.726874) (xy 374.996232 -282.700225)
			(xy 374.954561 -282.666994) (xy 374.918309 -282.627923) (xy 374.888285 -282.583886) (xy 374.865159 -282.535865)
			(xy 374.849449 -282.484935) (xy 374.841506 -282.432231) (xy 374.612931 -282.432231) (xy 374.612926 -282.432485)
			(xy 374.604983 -282.485189) (xy 374.589273 -282.536119) (xy 374.566147 -282.58414) (xy 374.536123 -282.628177)
			(xy 374.499871 -282.667248) (xy 374.4582 -282.700479) (xy 374.412042 -282.727128) (xy 374.362428 -282.7466)
			(xy 374.310466 -282.75846) (xy 374.257316 -282.762444) (xy 374.204166 -282.75846) (xy 374.152204 -282.7466)
			(xy 374.10259 -282.727128) (xy 374.056432 -282.700479) (xy 374.014761 -282.667248) (xy 373.978509 -282.628177)
			(xy 373.948485 -282.58414) (xy 373.925359 -282.536119) (xy 373.909649 -282.485189) (xy 373.901706 -282.432485)
			(xy 373.672872 -282.432485) (xy 373.664929 -282.485189) (xy 373.649219 -282.536119) (xy 373.626093 -282.58414)
			(xy 373.596069 -282.628177) (xy 373.559817 -282.667248) (xy 373.518146 -282.700479) (xy 373.471988 -282.727128)
			(xy 373.422374 -282.7466) (xy 373.370412 -282.75846) (xy 373.317262 -282.762444) (xy 373.264112 -282.75846)
			(xy 373.21215 -282.7466) (xy 373.162536 -282.727128) (xy 373.116378 -282.700479) (xy 373.074707 -282.667248)
			(xy 373.038455 -282.628177) (xy 373.008431 -282.58414) (xy 372.985305 -282.536119) (xy 372.969595 -282.485189)
			(xy 372.961652 -282.432485) (xy 372.733072 -282.432485) (xy 372.725129 -282.485189) (xy 372.709419 -282.536119)
			(xy 372.686293 -282.58414) (xy 372.656269 -282.628177) (xy 372.620017 -282.667248) (xy 372.578346 -282.700479)
			(xy 372.532188 -282.727128) (xy 372.482574 -282.7466) (xy 372.430612 -282.75846) (xy 372.377462 -282.762444)
			(xy 372.324312 -282.75846) (xy 372.27235 -282.7466) (xy 372.222736 -282.727128) (xy 372.176578 -282.700479)
			(xy 372.134907 -282.667248) (xy 372.098655 -282.628177) (xy 372.068631 -282.58414) (xy 372.045505 -282.536119)
			(xy 372.029795 -282.485189) (xy 372.021852 -282.432485) (xy 371.793272 -282.432485) (xy 371.785329 -282.485189)
			(xy 371.769619 -282.536119) (xy 371.746493 -282.58414) (xy 371.716469 -282.628177) (xy 371.680217 -282.667248)
			(xy 371.638546 -282.700479) (xy 371.592388 -282.727128) (xy 371.542774 -282.7466) (xy 371.490812 -282.75846)
			(xy 371.437662 -282.762444) (xy 371.384512 -282.75846) (xy 371.33255 -282.7466) (xy 371.282936 -282.727128)
			(xy 371.236778 -282.700479) (xy 371.195107 -282.667248) (xy 371.158855 -282.628177) (xy 371.128831 -282.58414)
			(xy 371.105705 -282.536119) (xy 371.089995 -282.485189) (xy 371.082052 -282.432485) (xy 370.853472 -282.432485)
			(xy 370.845529 -282.485189) (xy 370.829819 -282.536119) (xy 370.806693 -282.58414) (xy 370.776669 -282.628177)
			(xy 370.740417 -282.667248) (xy 370.698746 -282.700479) (xy 370.652588 -282.727128) (xy 370.602974 -282.7466)
			(xy 370.551012 -282.75846) (xy 370.497862 -282.762444) (xy 370.444712 -282.75846) (xy 370.39275 -282.7466)
			(xy 370.343136 -282.727128) (xy 370.296978 -282.700479) (xy 370.255307 -282.667248) (xy 370.219055 -282.628177)
			(xy 370.189031 -282.58414) (xy 370.165905 -282.536119) (xy 370.150195 -282.485189) (xy 370.142252 -282.432485)
			(xy 369.913672 -282.432485) (xy 369.905729 -282.485189) (xy 369.890019 -282.536119) (xy 369.866893 -282.58414)
			(xy 369.836869 -282.628177) (xy 369.800617 -282.667248) (xy 369.758946 -282.700479) (xy 369.712788 -282.727128)
			(xy 369.663174 -282.7466) (xy 369.611212 -282.75846) (xy 369.558062 -282.762444) (xy 369.504912 -282.75846)
			(xy 369.45295 -282.7466) (xy 369.403336 -282.727128) (xy 369.357178 -282.700479) (xy 369.315507 -282.667248)
			(xy 369.279255 -282.628177) (xy 369.249231 -282.58414) (xy 369.226105 -282.536119) (xy 369.210395 -282.485189)
			(xy 369.202452 -282.432485) (xy 368.973872 -282.432485) (xy 368.965929 -282.485189) (xy 368.950219 -282.536119)
			(xy 368.927093 -282.58414) (xy 368.897069 -282.628177) (xy 368.860817 -282.667248) (xy 368.819146 -282.700479)
			(xy 368.772988 -282.727128) (xy 368.723374 -282.7466) (xy 368.671412 -282.75846) (xy 368.618262 -282.762444)
			(xy 368.565112 -282.75846) (xy 368.51315 -282.7466) (xy 368.463536 -282.727128) (xy 368.417378 -282.700479)
			(xy 368.375707 -282.667248) (xy 368.339455 -282.628177) (xy 368.309431 -282.58414) (xy 368.286305 -282.536119)
			(xy 368.270595 -282.485189) (xy 368.262652 -282.432485) (xy 368.034072 -282.432485) (xy 368.026129 -282.485189)
			(xy 368.010419 -282.536119) (xy 367.987293 -282.58414) (xy 367.957269 -282.628177) (xy 367.921017 -282.667248)
			(xy 367.879346 -282.700479) (xy 367.833188 -282.727128) (xy 367.783574 -282.7466) (xy 367.731612 -282.75846)
			(xy 367.678462 -282.762444) (xy 367.625312 -282.75846) (xy 367.57335 -282.7466) (xy 367.523736 -282.727128)
			(xy 367.477578 -282.700479) (xy 367.435907 -282.667248) (xy 367.399655 -282.628177) (xy 367.369631 -282.58414)
			(xy 367.346505 -282.536119) (xy 367.330795 -282.485189) (xy 367.322852 -282.432485) (xy 367.094272 -282.432485)
			(xy 367.086329 -282.485189) (xy 367.070619 -282.536119) (xy 367.047493 -282.58414) (xy 367.017469 -282.628177)
			(xy 366.981217 -282.667248) (xy 366.939546 -282.700479) (xy 366.893388 -282.727128) (xy 366.843774 -282.7466)
			(xy 366.791812 -282.75846) (xy 366.738662 -282.762444) (xy 366.685512 -282.75846) (xy 366.63355 -282.7466)
			(xy 366.583936 -282.727128) (xy 366.537778 -282.700479) (xy 366.496107 -282.667248) (xy 366.459855 -282.628177)
			(xy 366.429831 -282.58414) (xy 366.406705 -282.536119) (xy 366.390995 -282.485189) (xy 366.383052 -282.432485)
			(xy 366.154726 -282.432485) (xy 366.146783 -282.485189) (xy 366.131073 -282.536119) (xy 366.107947 -282.58414)
			(xy 366.077923 -282.628177) (xy 366.041671 -282.667248) (xy 366 -282.700479) (xy 365.953842 -282.727128)
			(xy 365.904228 -282.7466) (xy 365.852266 -282.75846) (xy 365.799116 -282.762444) (xy 365.745966 -282.75846)
			(xy 365.694004 -282.7466) (xy 365.64439 -282.727128) (xy 365.598232 -282.700479) (xy 365.556561 -282.667248)
			(xy 365.520309 -282.628177) (xy 365.490285 -282.58414) (xy 365.467159 -282.536119) (xy 365.451449 -282.485189)
			(xy 365.443506 -282.432485) (xy 358.636072 -282.432485) (xy 358.628129 -282.485189) (xy 358.612419 -282.536119)
			(xy 358.589293 -282.58414) (xy 358.559269 -282.628177) (xy 358.523017 -282.667248) (xy 358.481346 -282.700479)
			(xy 358.435188 -282.727128) (xy 358.385574 -282.7466) (xy 358.333612 -282.75846) (xy 358.280462 -282.762444)
			(xy 358.227312 -282.75846) (xy 358.17535 -282.7466) (xy 358.125736 -282.727128) (xy 358.079578 -282.700479)
			(xy 358.037907 -282.667248) (xy 358.001655 -282.628177) (xy 357.971631 -282.58414) (xy 357.948505 -282.536119)
			(xy 357.932795 -282.485189) (xy 357.924852 -282.432485) (xy 355.816672 -282.432485) (xy 355.808729 -282.485189)
			(xy 355.793019 -282.536119) (xy 355.769893 -282.58414) (xy 355.739869 -282.628177) (xy 355.703617 -282.667248)
			(xy 355.661946 -282.700479) (xy 355.615788 -282.727128) (xy 355.566174 -282.7466) (xy 355.514212 -282.75846)
			(xy 355.461062 -282.762444) (xy 355.407912 -282.75846) (xy 355.35595 -282.7466) (xy 355.306336 -282.727128)
			(xy 355.260178 -282.700479) (xy 355.218507 -282.667248) (xy 355.182255 -282.628177) (xy 355.152231 -282.58414)
			(xy 355.129105 -282.536119) (xy 355.113395 -282.485189) (xy 355.105452 -282.432485) (xy 354.850071 -282.432485)
			(xy 354.842093 -282.482861) (xy 354.826094 -282.532101) (xy 354.802588 -282.578233) (xy 354.772156 -282.62012)
			(xy 354.735546 -282.65673) (xy 354.693659 -282.687162) (xy 354.647527 -282.710668) (xy 354.598287 -282.726667)
			(xy 354.547149 -282.734766) (xy 354.495375 -282.734766) (xy 354.444237 -282.726667) (xy 354.394997 -282.710668)
			(xy 354.348865 -282.687162) (xy 354.306978 -282.65673) (xy 354.270368 -282.62012) (xy 354.239936 -282.578233)
			(xy 354.21643 -282.532101) (xy 354.200431 -282.482861) (xy 354.192332 -282.431723) (xy 354.191824 -282.405836)
			(xy 354.192361 -282.378128) (xy 354.201551 -282.323481) (xy 354.210112 -282.297124) (xy 354.217986 -282.275026)
			(xy 354.013008 -281.920188) (xy 353.990148 -281.91587) (xy 353.965319 -281.910737) (xy 353.917537 -281.893779)
			(xy 353.872916 -281.869705) (xy 353.832509 -281.83908) (xy 353.797268 -281.802629) (xy 353.768025 -281.761211)
			(xy 353.74547 -281.715803) (xy 353.730136 -281.667476) (xy 353.722383 -281.617371) (xy 353.721924 -281.59202)
			(xy 353.468308 -281.59202) (xy 353.464484 -281.64408) (xy 353.453093 -281.695041) (xy 353.43438 -281.743792)
			(xy 353.408745 -281.789287) (xy 353.37674 -281.830548) (xy 353.339051 -281.866692) (xy 353.296486 -281.896942)
			(xy 353.249958 -281.92065) (xy 353.200467 -281.937307) (xy 353.149073 -281.946555) (xy 353.122992 -281.947874)
			(xy 353.107351 -281.948959) (xy 353.077812 -281.95942) (xy 353.052831 -281.978338) (xy 353.034755 -282.003935)
			(xy 353.025284 -282.033805) (xy 353.024694 -282.049474) (xy 353.024694 -282.596844) (xy 353.025191 -282.611644)
			(xy 353.033668 -282.640005) (xy 353.049925 -282.664741) (xy 353.072596 -282.683772) (xy 353.099774 -282.6955)
			(xy 353.129174 -282.698936) (xy 353.158324 -282.693793) (xy 353.184772 -282.680503) (xy 353.206296 -282.660183)
			(xy 353.214178 -282.647644) (xy 353.278186 -282.5369) (xy 353.270566 -282.514802) (xy 353.261916 -282.488394)
			(xy 353.252587 -282.433618) (xy 353.252024 -282.405836) (xy 353.252532 -282.379949) (xy 353.260631 -282.328811)
			(xy 353.27663 -282.279571) (xy 353.300136 -282.233439) (xy 353.330568 -282.191552) (xy 353.367178 -282.154942)
			(xy 353.409065 -282.12451) (xy 353.455197 -282.101004) (xy 353.504437 -282.085005) (xy 353.555575 -282.076906)
			(xy 353.607349 -282.076906) (xy 353.658487 -282.085005) (xy 353.707727 -282.101004) (xy 353.753859 -282.12451)
			(xy 353.795746 -282.154942) (xy 353.832356 -282.191552) (xy 353.862788 -282.233439) (xy 353.886294 -282.279571)
			(xy 353.902293 -282.328811) (xy 353.910392 -282.379949) (xy 353.9109 -282.405836) (xy 353.910435 -282.431159)
			(xy 353.902687 -282.481208) (xy 353.887379 -282.529485) (xy 353.86487 -282.574853) (xy 353.835691 -282.616248)
			(xy 353.800526 -282.652695) (xy 353.760202 -282.683338) (xy 353.715668 -282.707456) (xy 353.66797 -282.724482)
			(xy 353.643184 -282.729686) (xy 353.620324 -282.734004) (xy 353.415092 -283.089096) (xy 353.422966 -283.111194)
			(xy 353.43159 -283.137542) (xy 353.440912 -283.192189) (xy 353.441508 -283.219906) (xy 353.44105 -283.245258)
			(xy 353.440849 -283.246555) (xy 353.695752 -283.246555) (xy 353.695752 -283.193257) (xy 353.703695 -283.140553)
			(xy 353.719405 -283.089623) (xy 353.742531 -283.041602) (xy 353.772555 -282.997565) (xy 353.808807 -282.958494)
			(xy 353.850478 -282.925263) (xy 353.896636 -282.898614) (xy 353.94625 -282.879142) (xy 353.998212 -282.867282)
			(xy 354.051362 -282.863299) (xy 354.104512 -282.867282) (xy 354.156474 -282.879142) (xy 354.206088 -282.898614)
			(xy 354.252246 -282.925263) (xy 354.293917 -282.958494) (xy 354.330169 -282.997565) (xy 354.360193 -283.041602)
			(xy 354.383319 -283.089623) (xy 354.399029 -283.140553) (xy 354.406972 -283.193257) (xy 354.40747 -283.219906)
			(xy 354.406972 -283.246555) (xy 354.635806 -283.246555) (xy 354.635806 -283.193257) (xy 354.643749 -283.140553)
			(xy 354.659459 -283.089623) (xy 354.682585 -283.041602) (xy 354.712609 -282.997565) (xy 354.748861 -282.958494)
			(xy 354.790532 -282.925263) (xy 354.83669 -282.898614) (xy 354.886304 -282.879142) (xy 354.938266 -282.867282)
			(xy 354.991416 -282.863299) (xy 355.044566 -282.867282) (xy 355.096528 -282.879142) (xy 355.146142 -282.898614)
			(xy 355.1923 -282.925263) (xy 355.233971 -282.958494) (xy 355.270223 -282.997565) (xy 355.300247 -283.041602)
			(xy 355.323373 -283.089623) (xy 355.339083 -283.140553) (xy 355.347026 -283.193257) (xy 355.347524 -283.219906)
			(xy 355.347026 -283.246555) (xy 361.214152 -283.246555) (xy 361.214152 -283.193257) (xy 361.222095 -283.140553)
			(xy 361.237805 -283.089623) (xy 361.260931 -283.041602) (xy 361.290955 -282.997565) (xy 361.327207 -282.958494)
			(xy 361.368878 -282.925263) (xy 361.415036 -282.898614) (xy 361.46465 -282.879142) (xy 361.516612 -282.867282)
			(xy 361.569762 -282.863299) (xy 361.622912 -282.867282) (xy 361.674874 -282.879142) (xy 361.724488 -282.898614)
			(xy 361.770646 -282.925263) (xy 361.812317 -282.958494) (xy 361.848569 -282.997565) (xy 361.878593 -283.041602)
			(xy 361.901719 -283.089623) (xy 361.917429 -283.140553) (xy 361.925372 -283.193257) (xy 361.92587 -283.219906)
			(xy 361.925372 -283.246555) (xy 364.033806 -283.246555) (xy 364.033806 -283.193257) (xy 364.041749 -283.140553)
			(xy 364.057459 -283.089623) (xy 364.080585 -283.041602) (xy 364.110609 -282.997565) (xy 364.146861 -282.958494)
			(xy 364.188532 -282.925263) (xy 364.23469 -282.898614) (xy 364.284304 -282.879142) (xy 364.336266 -282.867282)
			(xy 364.389416 -282.863299) (xy 364.442566 -282.867282) (xy 364.494528 -282.879142) (xy 364.544142 -282.898614)
			(xy 364.5903 -282.925263) (xy 364.631971 -282.958494) (xy 364.668223 -282.997565) (xy 364.698247 -283.041602)
			(xy 364.721373 -283.089623) (xy 364.737083 -283.140553) (xy 364.745026 -283.193257) (xy 364.745524 -283.219906)
			(xy 364.745026 -283.246555) (xy 365.913406 -283.246555) (xy 365.913406 -283.193257) (xy 365.921349 -283.140553)
			(xy 365.937059 -283.089623) (xy 365.960185 -283.041602) (xy 365.990209 -282.997565) (xy 366.026461 -282.958494)
			(xy 366.068132 -282.925263) (xy 366.11429 -282.898614) (xy 366.163904 -282.879142) (xy 366.215866 -282.867282)
			(xy 366.269016 -282.863299) (xy 366.322166 -282.867282) (xy 366.374128 -282.879142) (xy 366.423742 -282.898614)
			(xy 366.4699 -282.925263) (xy 366.511571 -282.958494) (xy 366.547823 -282.997565) (xy 366.577847 -283.041602)
			(xy 366.600973 -283.089623) (xy 366.616683 -283.140553) (xy 366.624626 -283.193257) (xy 366.625124 -283.219906)
			(xy 366.624626 -283.246555) (xy 366.852952 -283.246555) (xy 366.852952 -283.193257) (xy 366.860895 -283.140553)
			(xy 366.876605 -283.089623) (xy 366.899731 -283.041602) (xy 366.929755 -282.997565) (xy 366.966007 -282.958494)
			(xy 367.007678 -282.925263) (xy 367.053836 -282.898614) (xy 367.10345 -282.879142) (xy 367.155412 -282.867282)
			(xy 367.208562 -282.863299) (xy 367.261712 -282.867282) (xy 367.313674 -282.879142) (xy 367.363288 -282.898614)
			(xy 367.409446 -282.925263) (xy 367.451117 -282.958494) (xy 367.487369 -282.997565) (xy 367.517393 -283.041602)
			(xy 367.540519 -283.089623) (xy 367.556229 -283.140553) (xy 367.564172 -283.193257) (xy 367.56467 -283.219906)
			(xy 367.564172 -283.246555) (xy 367.793006 -283.246555) (xy 367.793006 -283.193257) (xy 367.800949 -283.140553)
			(xy 367.816659 -283.089623) (xy 367.839785 -283.041602) (xy 367.869809 -282.997565) (xy 367.906061 -282.958494)
			(xy 367.947732 -282.925263) (xy 367.99389 -282.898614) (xy 368.043504 -282.879142) (xy 368.095466 -282.867282)
			(xy 368.148616 -282.863299) (xy 368.201766 -282.867282) (xy 368.253728 -282.879142) (xy 368.303342 -282.898614)
			(xy 368.3495 -282.925263) (xy 368.391171 -282.958494) (xy 368.427423 -282.997565) (xy 368.457447 -283.041602)
			(xy 368.480573 -283.089623) (xy 368.496283 -283.140553) (xy 368.504226 -283.193257) (xy 368.504724 -283.219906)
			(xy 368.504226 -283.246555) (xy 368.732552 -283.246555) (xy 368.732552 -283.193257) (xy 368.740495 -283.140553)
			(xy 368.756205 -283.089623) (xy 368.779331 -283.041602) (xy 368.809355 -282.997565) (xy 368.845607 -282.958494)
			(xy 368.887278 -282.925263) (xy 368.933436 -282.898614) (xy 368.98305 -282.879142) (xy 369.035012 -282.867282)
			(xy 369.088162 -282.863299) (xy 369.141312 -282.867282) (xy 369.193274 -282.879142) (xy 369.242888 -282.898614)
			(xy 369.289046 -282.925263) (xy 369.330717 -282.958494) (xy 369.366969 -282.997565) (xy 369.396993 -283.041602)
			(xy 369.420119 -283.089623) (xy 369.435829 -283.140553) (xy 369.443772 -283.193257) (xy 369.44427 -283.219906)
			(xy 369.443772 -283.246555) (xy 369.672352 -283.246555) (xy 369.672352 -283.193257) (xy 369.680295 -283.140553)
			(xy 369.696005 -283.089623) (xy 369.719131 -283.041602) (xy 369.749155 -282.997565) (xy 369.785407 -282.958494)
			(xy 369.827078 -282.925263) (xy 369.873236 -282.898614) (xy 369.92285 -282.879142) (xy 369.974812 -282.867282)
			(xy 370.027962 -282.863299) (xy 370.081112 -282.867282) (xy 370.133074 -282.879142) (xy 370.182688 -282.898614)
			(xy 370.228846 -282.925263) (xy 370.270517 -282.958494) (xy 370.306769 -282.997565) (xy 370.336793 -283.041602)
			(xy 370.359919 -283.089623) (xy 370.375629 -283.140553) (xy 370.383572 -283.193257) (xy 370.38407 -283.219906)
			(xy 370.383572 -283.246555) (xy 370.612406 -283.246555) (xy 370.612406 -283.193257) (xy 370.620349 -283.140553)
			(xy 370.636059 -283.089623) (xy 370.659185 -283.041602) (xy 370.689209 -282.997565) (xy 370.725461 -282.958494)
			(xy 370.767132 -282.925263) (xy 370.81329 -282.898614) (xy 370.862904 -282.879142) (xy 370.914866 -282.867282)
			(xy 370.968016 -282.863299) (xy 371.021166 -282.867282) (xy 371.073128 -282.879142) (xy 371.122742 -282.898614)
			(xy 371.1689 -282.925263) (xy 371.210571 -282.958494) (xy 371.246823 -282.997565) (xy 371.276847 -283.041602)
			(xy 371.299973 -283.089623) (xy 371.315683 -283.140553) (xy 371.323626 -283.193257) (xy 371.324124 -283.219906)
			(xy 371.323626 -283.246555) (xy 371.552206 -283.246555) (xy 371.552206 -283.193257) (xy 371.560149 -283.140553)
			(xy 371.575859 -283.089623) (xy 371.598985 -283.041602) (xy 371.629009 -282.997565) (xy 371.665261 -282.958494)
			(xy 371.706932 -282.925263) (xy 371.75309 -282.898614) (xy 371.802704 -282.879142) (xy 371.854666 -282.867282)
			(xy 371.907816 -282.863299) (xy 371.960966 -282.867282) (xy 372.012928 -282.879142) (xy 372.062542 -282.898614)
			(xy 372.1087 -282.925263) (xy 372.150371 -282.958494) (xy 372.186623 -282.997565) (xy 372.216647 -283.041602)
			(xy 372.239773 -283.089623) (xy 372.255483 -283.140553) (xy 372.263426 -283.193257) (xy 372.263924 -283.219906)
			(xy 372.263426 -283.246555) (xy 372.492006 -283.246555) (xy 372.492006 -283.193257) (xy 372.499949 -283.140553)
			(xy 372.515659 -283.089623) (xy 372.538785 -283.041602) (xy 372.568809 -282.997565) (xy 372.605061 -282.958494)
			(xy 372.646732 -282.925263) (xy 372.69289 -282.898614) (xy 372.742504 -282.879142) (xy 372.794466 -282.867282)
			(xy 372.847616 -282.863299) (xy 372.900766 -282.867282) (xy 372.952728 -282.879142) (xy 373.002342 -282.898614)
			(xy 373.0485 -282.925263) (xy 373.090171 -282.958494) (xy 373.126423 -282.997565) (xy 373.156447 -283.041602)
			(xy 373.179573 -283.089623) (xy 373.195283 -283.140553) (xy 373.203226 -283.193257) (xy 373.203724 -283.219906)
			(xy 373.203226 -283.246555) (xy 373.431806 -283.246555) (xy 373.431806 -283.193257) (xy 373.439749 -283.140553)
			(xy 373.455459 -283.089623) (xy 373.478585 -283.041602) (xy 373.508609 -282.997565) (xy 373.544861 -282.958494)
			(xy 373.586532 -282.925263) (xy 373.63269 -282.898614) (xy 373.682304 -282.879142) (xy 373.734266 -282.867282)
			(xy 373.787416 -282.863299) (xy 373.840566 -282.867282) (xy 373.892528 -282.879142) (xy 373.942142 -282.898614)
			(xy 373.9883 -282.925263) (xy 374.029971 -282.958494) (xy 374.066223 -282.997565) (xy 374.096247 -283.041602)
			(xy 374.119373 -283.089623) (xy 374.135083 -283.140553) (xy 374.143026 -283.193257) (xy 374.143524 -283.219906)
			(xy 374.143026 -283.246555) (xy 374.371352 -283.246555) (xy 374.371352 -283.193257) (xy 374.379295 -283.140553)
			(xy 374.395005 -283.089623) (xy 374.418131 -283.041602) (xy 374.448155 -282.997565) (xy 374.484407 -282.958494)
			(xy 374.526078 -282.925263) (xy 374.572236 -282.898614) (xy 374.62185 -282.879142) (xy 374.673812 -282.867282)
			(xy 374.726962 -282.863299) (xy 374.780112 -282.867282) (xy 374.832074 -282.879142) (xy 374.881688 -282.898614)
			(xy 374.927846 -282.925263) (xy 374.969517 -282.958494) (xy 375.005769 -282.997565) (xy 375.035793 -283.041602)
			(xy 375.058919 -283.089623) (xy 375.074629 -283.140553) (xy 375.082572 -283.193257) (xy 375.08307 -283.219906)
			(xy 375.082572 -283.246555) (xy 375.311406 -283.246555) (xy 375.311406 -283.193257) (xy 375.319349 -283.140553)
			(xy 375.335059 -283.089623) (xy 375.358185 -283.041602) (xy 375.388209 -282.997565) (xy 375.424461 -282.958494)
			(xy 375.466132 -282.925263) (xy 375.51229 -282.898614) (xy 375.561904 -282.879142) (xy 375.613866 -282.867282)
			(xy 375.667016 -282.863299) (xy 375.720166 -282.867282) (xy 375.772128 -282.879142) (xy 375.821742 -282.898614)
			(xy 375.8679 -282.925263) (xy 375.909571 -282.958494) (xy 375.945823 -282.997565) (xy 375.975847 -283.041602)
			(xy 375.998973 -283.089623) (xy 376.014683 -283.140553) (xy 376.022626 -283.193257) (xy 376.023124 -283.219906)
			(xy 376.022631 -283.246301) (xy 376.250952 -283.246301) (xy 376.250952 -283.193003) (xy 376.258895 -283.140299)
			(xy 376.274605 -283.089369) (xy 376.297731 -283.041348) (xy 376.327755 -282.997311) (xy 376.364007 -282.95824)
			(xy 376.405678 -282.925009) (xy 376.451836 -282.89836) (xy 376.50145 -282.878888) (xy 376.553412 -282.867028)
			(xy 376.606562 -282.863045) (xy 376.659712 -282.867028) (xy 376.711674 -282.878888) (xy 376.761288 -282.89836)
			(xy 376.807446 -282.925009) (xy 376.849117 -282.95824) (xy 376.885369 -282.997311) (xy 376.915393 -283.041348)
			(xy 376.938519 -283.089369) (xy 376.954229 -283.140299) (xy 376.962172 -283.193003) (xy 376.96267 -283.219652)
			(xy 376.962172 -283.246301) (xy 376.962134 -283.246555) (xy 377.190752 -283.246555) (xy 377.190752 -283.193257)
			(xy 377.198695 -283.140553) (xy 377.214405 -283.089623) (xy 377.237531 -283.041602) (xy 377.267555 -282.997565)
			(xy 377.303807 -282.958494) (xy 377.345478 -282.925263) (xy 377.391636 -282.898614) (xy 377.44125 -282.879142)
			(xy 377.493212 -282.867282) (xy 377.546362 -282.863299) (xy 377.599512 -282.867282) (xy 377.651474 -282.879142)
			(xy 377.701088 -282.898614) (xy 377.747246 -282.925263) (xy 377.788917 -282.958494) (xy 377.825169 -282.997565)
			(xy 377.855193 -283.041602) (xy 377.878319 -283.089623) (xy 377.894029 -283.140553) (xy 377.901972 -283.193257)
			(xy 377.90247 -283.219906) (xy 377.901972 -283.246555) (xy 378.130552 -283.246555) (xy 378.130552 -283.193257)
			(xy 378.138495 -283.140553) (xy 378.154205 -283.089623) (xy 378.177331 -283.041602) (xy 378.207355 -282.997565)
			(xy 378.243607 -282.958494) (xy 378.285278 -282.925263) (xy 378.331436 -282.898614) (xy 378.38105 -282.879142)
			(xy 378.433012 -282.867282) (xy 378.486162 -282.863299) (xy 378.539312 -282.867282) (xy 378.591274 -282.879142)
			(xy 378.640888 -282.898614) (xy 378.687046 -282.925263) (xy 378.728717 -282.958494) (xy 378.764969 -282.997565)
			(xy 378.794993 -283.041602) (xy 378.818119 -283.089623) (xy 378.833829 -283.140553) (xy 378.841772 -283.193257)
			(xy 378.84227 -283.219906) (xy 378.841772 -283.246555) (xy 379.070606 -283.246555) (xy 379.070606 -283.193257)
			(xy 379.078549 -283.140553) (xy 379.094259 -283.089623) (xy 379.117385 -283.041602) (xy 379.147409 -282.997565)
			(xy 379.183661 -282.958494) (xy 379.225332 -282.925263) (xy 379.27149 -282.898614) (xy 379.321104 -282.879142)
			(xy 379.373066 -282.867282) (xy 379.426216 -282.863299) (xy 379.479366 -282.867282) (xy 379.531328 -282.879142)
			(xy 379.580942 -282.898614) (xy 379.6271 -282.925263) (xy 379.668771 -282.958494) (xy 379.705023 -282.997565)
			(xy 379.735047 -283.041602) (xy 379.758173 -283.089623) (xy 379.773883 -283.140553) (xy 379.781826 -283.193257)
			(xy 379.782324 -283.219906) (xy 379.781826 -283.246555) (xy 380.010152 -283.246555) (xy 380.010152 -283.193257)
			(xy 380.018095 -283.140553) (xy 380.033805 -283.089623) (xy 380.056931 -283.041602) (xy 380.086955 -282.997565)
			(xy 380.123207 -282.958494) (xy 380.164878 -282.925263) (xy 380.211036 -282.898614) (xy 380.26065 -282.879142)
			(xy 380.312612 -282.867282) (xy 380.365762 -282.863299) (xy 380.418912 -282.867282) (xy 380.470874 -282.879142)
			(xy 380.520488 -282.898614) (xy 380.566646 -282.925263) (xy 380.608317 -282.958494) (xy 380.644569 -282.997565)
			(xy 380.674593 -283.041602) (xy 380.697719 -283.089623) (xy 380.713429 -283.140553) (xy 380.721372 -283.193257)
			(xy 380.72187 -283.219906) (xy 380.721372 -283.246555) (xy 380.950206 -283.246555) (xy 380.950206 -283.193257)
			(xy 380.958149 -283.140553) (xy 380.973859 -283.089623) (xy 380.996985 -283.041602) (xy 381.027009 -282.997565)
			(xy 381.063261 -282.958494) (xy 381.104932 -282.925263) (xy 381.15109 -282.898614) (xy 381.200704 -282.879142)
			(xy 381.252666 -282.867282) (xy 381.305816 -282.863299) (xy 381.358966 -282.867282) (xy 381.410928 -282.879142)
			(xy 381.460542 -282.898614) (xy 381.5067 -282.925263) (xy 381.548371 -282.958494) (xy 381.584623 -282.997565)
			(xy 381.614647 -283.041602) (xy 381.637773 -283.089623) (xy 381.653483 -283.140553) (xy 381.661426 -283.193257)
			(xy 381.661924 -283.219906) (xy 381.661426 -283.246555) (xy 381.890006 -283.246555) (xy 381.890006 -283.193257)
			(xy 381.897949 -283.140553) (xy 381.913659 -283.089623) (xy 381.936785 -283.041602) (xy 381.966809 -282.997565)
			(xy 382.003061 -282.958494) (xy 382.044732 -282.925263) (xy 382.09089 -282.898614) (xy 382.140504 -282.879142)
			(xy 382.192466 -282.867282) (xy 382.245616 -282.863299) (xy 382.298766 -282.867282) (xy 382.350728 -282.879142)
			(xy 382.400342 -282.898614) (xy 382.4465 -282.925263) (xy 382.488171 -282.958494) (xy 382.524423 -282.997565)
			(xy 382.554447 -283.041602) (xy 382.577573 -283.089623) (xy 382.593283 -283.140553) (xy 382.601226 -283.193257)
			(xy 382.601724 -283.219906) (xy 382.601226 -283.246555) (xy 382.829552 -283.246555) (xy 382.829552 -283.193257)
			(xy 382.837495 -283.140553) (xy 382.853205 -283.089623) (xy 382.876331 -283.041602) (xy 382.906355 -282.997565)
			(xy 382.942607 -282.958494) (xy 382.984278 -282.925263) (xy 383.030436 -282.898614) (xy 383.08005 -282.879142)
			(xy 383.132012 -282.867282) (xy 383.185162 -282.863299) (xy 383.238312 -282.867282) (xy 383.290274 -282.879142)
			(xy 383.339888 -282.898614) (xy 383.386046 -282.925263) (xy 383.427717 -282.958494) (xy 383.463969 -282.997565)
			(xy 383.493993 -283.041602) (xy 383.517119 -283.089623) (xy 383.532829 -283.140553) (xy 383.540772 -283.193257)
			(xy 383.54127 -283.219906) (xy 383.540772 -283.246555) (xy 383.769352 -283.246555) (xy 383.769352 -283.193257)
			(xy 383.777295 -283.140553) (xy 383.793005 -283.089623) (xy 383.816131 -283.041602) (xy 383.846155 -282.997565)
			(xy 383.882407 -282.958494) (xy 383.924078 -282.925263) (xy 383.970236 -282.898614) (xy 384.01985 -282.879142)
			(xy 384.071812 -282.867282) (xy 384.124962 -282.863299) (xy 384.178112 -282.867282) (xy 384.230074 -282.879142)
			(xy 384.279688 -282.898614) (xy 384.325846 -282.925263) (xy 384.367517 -282.958494) (xy 384.403769 -282.997565)
			(xy 384.433793 -283.041602) (xy 384.456919 -283.089623) (xy 384.472629 -283.140553) (xy 384.480572 -283.193257)
			(xy 384.48107 -283.219906) (xy 384.480572 -283.246555) (xy 384.709406 -283.246555) (xy 384.709406 -283.193257)
			(xy 384.717349 -283.140553) (xy 384.733059 -283.089623) (xy 384.756185 -283.041602) (xy 384.786209 -282.997565)
			(xy 384.822461 -282.958494) (xy 384.864132 -282.925263) (xy 384.91029 -282.898614) (xy 384.959904 -282.879142)
			(xy 385.011866 -282.867282) (xy 385.065016 -282.863299) (xy 385.118166 -282.867282) (xy 385.170128 -282.879142)
			(xy 385.219742 -282.898614) (xy 385.2659 -282.925263) (xy 385.307571 -282.958494) (xy 385.343823 -282.997565)
			(xy 385.373847 -283.041602) (xy 385.396973 -283.089623) (xy 385.412683 -283.140553) (xy 385.420626 -283.193257)
			(xy 385.421124 -283.219906) (xy 385.420626 -283.246555) (xy 385.649206 -283.246555) (xy 385.649206 -283.193257)
			(xy 385.657149 -283.140553) (xy 385.672859 -283.089623) (xy 385.695985 -283.041602) (xy 385.726009 -282.997565)
			(xy 385.762261 -282.958494) (xy 385.803932 -282.925263) (xy 385.85009 -282.898614) (xy 385.899704 -282.879142)
			(xy 385.951666 -282.867282) (xy 386.004816 -282.863299) (xy 386.057966 -282.867282) (xy 386.109928 -282.879142)
			(xy 386.159542 -282.898614) (xy 386.2057 -282.925263) (xy 386.247371 -282.958494) (xy 386.283623 -282.997565)
			(xy 386.313647 -283.041602) (xy 386.336773 -283.089623) (xy 386.352483 -283.140553) (xy 386.360426 -283.193257)
			(xy 386.360924 -283.219906) (xy 386.360426 -283.246555) (xy 386.352483 -283.299259) (xy 386.336773 -283.350189)
			(xy 386.313647 -283.39821) (xy 386.283623 -283.442247) (xy 386.247371 -283.481318) (xy 386.2057 -283.514549)
			(xy 386.159542 -283.541198) (xy 386.109928 -283.56067) (xy 386.057966 -283.57253) (xy 386.004816 -283.576514)
			(xy 385.951666 -283.57253) (xy 385.899704 -283.56067) (xy 385.85009 -283.541198) (xy 385.803932 -283.514549)
			(xy 385.762261 -283.481318) (xy 385.726009 -283.442247) (xy 385.695985 -283.39821) (xy 385.672859 -283.350189)
			(xy 385.657149 -283.299259) (xy 385.649206 -283.246555) (xy 385.420626 -283.246555) (xy 385.412683 -283.299259)
			(xy 385.396973 -283.350189) (xy 385.373847 -283.39821) (xy 385.343823 -283.442247) (xy 385.307571 -283.481318)
			(xy 385.2659 -283.514549) (xy 385.219742 -283.541198) (xy 385.170128 -283.56067) (xy 385.118166 -283.57253)
			(xy 385.065016 -283.576514) (xy 385.011866 -283.57253) (xy 384.959904 -283.56067) (xy 384.91029 -283.541198)
			(xy 384.864132 -283.514549) (xy 384.822461 -283.481318) (xy 384.786209 -283.442247) (xy 384.756185 -283.39821)
			(xy 384.733059 -283.350189) (xy 384.717349 -283.299259) (xy 384.709406 -283.246555) (xy 384.480572 -283.246555)
			(xy 384.472629 -283.299259) (xy 384.456919 -283.350189) (xy 384.433793 -283.39821) (xy 384.403769 -283.442247)
			(xy 384.367517 -283.481318) (xy 384.325846 -283.514549) (xy 384.279688 -283.541198) (xy 384.230074 -283.56067)
			(xy 384.178112 -283.57253) (xy 384.124962 -283.576514) (xy 384.071812 -283.57253) (xy 384.01985 -283.56067)
			(xy 383.970236 -283.541198) (xy 383.924078 -283.514549) (xy 383.882407 -283.481318) (xy 383.846155 -283.442247)
			(xy 383.816131 -283.39821) (xy 383.793005 -283.350189) (xy 383.777295 -283.299259) (xy 383.769352 -283.246555)
			(xy 383.540772 -283.246555) (xy 383.532829 -283.299259) (xy 383.517119 -283.350189) (xy 383.493993 -283.39821)
			(xy 383.463969 -283.442247) (xy 383.427717 -283.481318) (xy 383.386046 -283.514549) (xy 383.339888 -283.541198)
			(xy 383.290274 -283.56067) (xy 383.238312 -283.57253) (xy 383.185162 -283.576514) (xy 383.132012 -283.57253)
			(xy 383.08005 -283.56067) (xy 383.030436 -283.541198) (xy 382.984278 -283.514549) (xy 382.942607 -283.481318)
			(xy 382.906355 -283.442247) (xy 382.876331 -283.39821) (xy 382.853205 -283.350189) (xy 382.837495 -283.299259)
			(xy 382.829552 -283.246555) (xy 382.601226 -283.246555) (xy 382.593283 -283.299259) (xy 382.577573 -283.350189)
			(xy 382.554447 -283.39821) (xy 382.524423 -283.442247) (xy 382.488171 -283.481318) (xy 382.4465 -283.514549)
			(xy 382.400342 -283.541198) (xy 382.350728 -283.56067) (xy 382.298766 -283.57253) (xy 382.245616 -283.576514)
			(xy 382.192466 -283.57253) (xy 382.140504 -283.56067) (xy 382.09089 -283.541198) (xy 382.044732 -283.514549)
			(xy 382.003061 -283.481318) (xy 381.966809 -283.442247) (xy 381.936785 -283.39821) (xy 381.913659 -283.350189)
			(xy 381.897949 -283.299259) (xy 381.890006 -283.246555) (xy 381.661426 -283.246555) (xy 381.653483 -283.299259)
			(xy 381.637773 -283.350189) (xy 381.614647 -283.39821) (xy 381.584623 -283.442247) (xy 381.548371 -283.481318)
			(xy 381.5067 -283.514549) (xy 381.460542 -283.541198) (xy 381.410928 -283.56067) (xy 381.358966 -283.57253)
			(xy 381.305816 -283.576514) (xy 381.252666 -283.57253) (xy 381.200704 -283.56067) (xy 381.15109 -283.541198)
			(xy 381.104932 -283.514549) (xy 381.063261 -283.481318) (xy 381.027009 -283.442247) (xy 380.996985 -283.39821)
			(xy 380.973859 -283.350189) (xy 380.958149 -283.299259) (xy 380.950206 -283.246555) (xy 380.721372 -283.246555)
			(xy 380.713429 -283.299259) (xy 380.697719 -283.350189) (xy 380.674593 -283.39821) (xy 380.644569 -283.442247)
			(xy 380.608317 -283.481318) (xy 380.566646 -283.514549) (xy 380.520488 -283.541198) (xy 380.470874 -283.56067)
			(xy 380.418912 -283.57253) (xy 380.365762 -283.576514) (xy 380.312612 -283.57253) (xy 380.26065 -283.56067)
			(xy 380.211036 -283.541198) (xy 380.164878 -283.514549) (xy 380.123207 -283.481318) (xy 380.086955 -283.442247)
			(xy 380.056931 -283.39821) (xy 380.033805 -283.350189) (xy 380.018095 -283.299259) (xy 380.010152 -283.246555)
			(xy 379.781826 -283.246555) (xy 379.773883 -283.299259) (xy 379.758173 -283.350189) (xy 379.735047 -283.39821)
			(xy 379.705023 -283.442247) (xy 379.668771 -283.481318) (xy 379.6271 -283.514549) (xy 379.580942 -283.541198)
			(xy 379.531328 -283.56067) (xy 379.479366 -283.57253) (xy 379.426216 -283.576514) (xy 379.373066 -283.57253)
			(xy 379.321104 -283.56067) (xy 379.27149 -283.541198) (xy 379.225332 -283.514549) (xy 379.183661 -283.481318)
			(xy 379.147409 -283.442247) (xy 379.117385 -283.39821) (xy 379.094259 -283.350189) (xy 379.078549 -283.299259)
			(xy 379.070606 -283.246555) (xy 378.841772 -283.246555) (xy 378.833829 -283.299259) (xy 378.818119 -283.350189)
			(xy 378.794993 -283.39821) (xy 378.764969 -283.442247) (xy 378.728717 -283.481318) (xy 378.687046 -283.514549)
			(xy 378.640888 -283.541198) (xy 378.591274 -283.56067) (xy 378.539312 -283.57253) (xy 378.486162 -283.576514)
			(xy 378.433012 -283.57253) (xy 378.38105 -283.56067) (xy 378.331436 -283.541198) (xy 378.285278 -283.514549)
			(xy 378.243607 -283.481318) (xy 378.207355 -283.442247) (xy 378.177331 -283.39821) (xy 378.154205 -283.350189)
			(xy 378.138495 -283.299259) (xy 378.130552 -283.246555) (xy 377.901972 -283.246555) (xy 377.894029 -283.299259)
			(xy 377.878319 -283.350189) (xy 377.855193 -283.39821) (xy 377.825169 -283.442247) (xy 377.788917 -283.481318)
			(xy 377.747246 -283.514549) (xy 377.701088 -283.541198) (xy 377.651474 -283.56067) (xy 377.599512 -283.57253)
			(xy 377.546362 -283.576514) (xy 377.493212 -283.57253) (xy 377.44125 -283.56067) (xy 377.391636 -283.541198)
			(xy 377.345478 -283.514549) (xy 377.303807 -283.481318) (xy 377.267555 -283.442247) (xy 377.237531 -283.39821)
			(xy 377.214405 -283.350189) (xy 377.198695 -283.299259) (xy 377.190752 -283.246555) (xy 376.962134 -283.246555)
			(xy 376.954229 -283.299005) (xy 376.938519 -283.349935) (xy 376.915393 -283.397956) (xy 376.885369 -283.441993)
			(xy 376.849117 -283.481064) (xy 376.807446 -283.514295) (xy 376.761288 -283.540944) (xy 376.711674 -283.560416)
			(xy 376.659712 -283.572276) (xy 376.606562 -283.57626) (xy 376.553412 -283.572276) (xy 376.50145 -283.560416)
			(xy 376.451836 -283.540944) (xy 376.405678 -283.514295) (xy 376.364007 -283.481064) (xy 376.327755 -283.441993)
			(xy 376.297731 -283.397956) (xy 376.274605 -283.349935) (xy 376.258895 -283.299005) (xy 376.250952 -283.246301)
			(xy 376.022631 -283.246301) (xy 376.022626 -283.246555) (xy 376.014683 -283.299259) (xy 375.998973 -283.350189)
			(xy 375.975847 -283.39821) (xy 375.945823 -283.442247) (xy 375.909571 -283.481318) (xy 375.8679 -283.514549)
			(xy 375.821742 -283.541198) (xy 375.772128 -283.56067) (xy 375.720166 -283.57253) (xy 375.667016 -283.576514)
			(xy 375.613866 -283.57253) (xy 375.561904 -283.56067) (xy 375.51229 -283.541198) (xy 375.466132 -283.514549)
			(xy 375.424461 -283.481318) (xy 375.388209 -283.442247) (xy 375.358185 -283.39821) (xy 375.335059 -283.350189)
			(xy 375.319349 -283.299259) (xy 375.311406 -283.246555) (xy 375.082572 -283.246555) (xy 375.074629 -283.299259)
			(xy 375.058919 -283.350189) (xy 375.035793 -283.39821) (xy 375.005769 -283.442247) (xy 374.969517 -283.481318)
			(xy 374.927846 -283.514549) (xy 374.881688 -283.541198) (xy 374.832074 -283.56067) (xy 374.780112 -283.57253)
			(xy 374.726962 -283.576514) (xy 374.673812 -283.57253) (xy 374.62185 -283.56067) (xy 374.572236 -283.541198)
			(xy 374.526078 -283.514549) (xy 374.484407 -283.481318) (xy 374.448155 -283.442247) (xy 374.418131 -283.39821)
			(xy 374.395005 -283.350189) (xy 374.379295 -283.299259) (xy 374.371352 -283.246555) (xy 374.143026 -283.246555)
			(xy 374.135083 -283.299259) (xy 374.119373 -283.350189) (xy 374.096247 -283.39821) (xy 374.066223 -283.442247)
			(xy 374.029971 -283.481318) (xy 373.9883 -283.514549) (xy 373.942142 -283.541198) (xy 373.892528 -283.56067)
			(xy 373.840566 -283.57253) (xy 373.787416 -283.576514) (xy 373.734266 -283.57253) (xy 373.682304 -283.56067)
			(xy 373.63269 -283.541198) (xy 373.586532 -283.514549) (xy 373.544861 -283.481318) (xy 373.508609 -283.442247)
			(xy 373.478585 -283.39821) (xy 373.455459 -283.350189) (xy 373.439749 -283.299259) (xy 373.431806 -283.246555)
			(xy 373.203226 -283.246555) (xy 373.195283 -283.299259) (xy 373.179573 -283.350189) (xy 373.156447 -283.39821)
			(xy 373.126423 -283.442247) (xy 373.090171 -283.481318) (xy 373.0485 -283.514549) (xy 373.002342 -283.541198)
			(xy 372.952728 -283.56067) (xy 372.900766 -283.57253) (xy 372.847616 -283.576514) (xy 372.794466 -283.57253)
			(xy 372.742504 -283.56067) (xy 372.69289 -283.541198) (xy 372.646732 -283.514549) (xy 372.605061 -283.481318)
			(xy 372.568809 -283.442247) (xy 372.538785 -283.39821) (xy 372.515659 -283.350189) (xy 372.499949 -283.299259)
			(xy 372.492006 -283.246555) (xy 372.263426 -283.246555) (xy 372.255483 -283.299259) (xy 372.239773 -283.350189)
			(xy 372.216647 -283.39821) (xy 372.186623 -283.442247) (xy 372.150371 -283.481318) (xy 372.1087 -283.514549)
			(xy 372.062542 -283.541198) (xy 372.012928 -283.56067) (xy 371.960966 -283.57253) (xy 371.907816 -283.576514)
			(xy 371.854666 -283.57253) (xy 371.802704 -283.56067) (xy 371.75309 -283.541198) (xy 371.706932 -283.514549)
			(xy 371.665261 -283.481318) (xy 371.629009 -283.442247) (xy 371.598985 -283.39821) (xy 371.575859 -283.350189)
			(xy 371.560149 -283.299259) (xy 371.552206 -283.246555) (xy 371.323626 -283.246555) (xy 371.315683 -283.299259)
			(xy 371.299973 -283.350189) (xy 371.276847 -283.39821) (xy 371.246823 -283.442247) (xy 371.210571 -283.481318)
			(xy 371.1689 -283.514549) (xy 371.122742 -283.541198) (xy 371.073128 -283.56067) (xy 371.021166 -283.57253)
			(xy 370.968016 -283.576514) (xy 370.914866 -283.57253) (xy 370.862904 -283.56067) (xy 370.81329 -283.541198)
			(xy 370.767132 -283.514549) (xy 370.725461 -283.481318) (xy 370.689209 -283.442247) (xy 370.659185 -283.39821)
			(xy 370.636059 -283.350189) (xy 370.620349 -283.299259) (xy 370.612406 -283.246555) (xy 370.383572 -283.246555)
			(xy 370.375629 -283.299259) (xy 370.359919 -283.350189) (xy 370.336793 -283.39821) (xy 370.306769 -283.442247)
			(xy 370.270517 -283.481318) (xy 370.228846 -283.514549) (xy 370.182688 -283.541198) (xy 370.133074 -283.56067)
			(xy 370.081112 -283.57253) (xy 370.027962 -283.576514) (xy 369.974812 -283.57253) (xy 369.92285 -283.56067)
			(xy 369.873236 -283.541198) (xy 369.827078 -283.514549) (xy 369.785407 -283.481318) (xy 369.749155 -283.442247)
			(xy 369.719131 -283.39821) (xy 369.696005 -283.350189) (xy 369.680295 -283.299259) (xy 369.672352 -283.246555)
			(xy 369.443772 -283.246555) (xy 369.435829 -283.299259) (xy 369.420119 -283.350189) (xy 369.396993 -283.39821)
			(xy 369.366969 -283.442247) (xy 369.330717 -283.481318) (xy 369.289046 -283.514549) (xy 369.242888 -283.541198)
			(xy 369.193274 -283.56067) (xy 369.141312 -283.57253) (xy 369.088162 -283.576514) (xy 369.035012 -283.57253)
			(xy 368.98305 -283.56067) (xy 368.933436 -283.541198) (xy 368.887278 -283.514549) (xy 368.845607 -283.481318)
			(xy 368.809355 -283.442247) (xy 368.779331 -283.39821) (xy 368.756205 -283.350189) (xy 368.740495 -283.299259)
			(xy 368.732552 -283.246555) (xy 368.504226 -283.246555) (xy 368.496283 -283.299259) (xy 368.480573 -283.350189)
			(xy 368.457447 -283.39821) (xy 368.427423 -283.442247) (xy 368.391171 -283.481318) (xy 368.3495 -283.514549)
			(xy 368.303342 -283.541198) (xy 368.253728 -283.56067) (xy 368.201766 -283.57253) (xy 368.148616 -283.576514)
			(xy 368.095466 -283.57253) (xy 368.043504 -283.56067) (xy 367.99389 -283.541198) (xy 367.947732 -283.514549)
			(xy 367.906061 -283.481318) (xy 367.869809 -283.442247) (xy 367.839785 -283.39821) (xy 367.816659 -283.350189)
			(xy 367.800949 -283.299259) (xy 367.793006 -283.246555) (xy 367.564172 -283.246555) (xy 367.556229 -283.299259)
			(xy 367.540519 -283.350189) (xy 367.517393 -283.39821) (xy 367.487369 -283.442247) (xy 367.451117 -283.481318)
			(xy 367.409446 -283.514549) (xy 367.363288 -283.541198) (xy 367.313674 -283.56067) (xy 367.261712 -283.57253)
			(xy 367.208562 -283.576514) (xy 367.155412 -283.57253) (xy 367.10345 -283.56067) (xy 367.053836 -283.541198)
			(xy 367.007678 -283.514549) (xy 366.966007 -283.481318) (xy 366.929755 -283.442247) (xy 366.899731 -283.39821)
			(xy 366.876605 -283.350189) (xy 366.860895 -283.299259) (xy 366.852952 -283.246555) (xy 366.624626 -283.246555)
			(xy 366.616683 -283.299259) (xy 366.600973 -283.350189) (xy 366.577847 -283.39821) (xy 366.547823 -283.442247)
			(xy 366.511571 -283.481318) (xy 366.4699 -283.514549) (xy 366.423742 -283.541198) (xy 366.374128 -283.56067)
			(xy 366.322166 -283.57253) (xy 366.269016 -283.576514) (xy 366.215866 -283.57253) (xy 366.163904 -283.56067)
			(xy 366.11429 -283.541198) (xy 366.068132 -283.514549) (xy 366.026461 -283.481318) (xy 365.990209 -283.442247)
			(xy 365.960185 -283.39821) (xy 365.937059 -283.350189) (xy 365.921349 -283.299259) (xy 365.913406 -283.246555)
			(xy 364.745026 -283.246555) (xy 364.737083 -283.299259) (xy 364.721373 -283.350189) (xy 364.698247 -283.39821)
			(xy 364.668223 -283.442247) (xy 364.631971 -283.481318) (xy 364.5903 -283.514549) (xy 364.544142 -283.541198)
			(xy 364.494528 -283.56067) (xy 364.442566 -283.57253) (xy 364.389416 -283.576514) (xy 364.336266 -283.57253)
			(xy 364.284304 -283.56067) (xy 364.23469 -283.541198) (xy 364.188532 -283.514549) (xy 364.146861 -283.481318)
			(xy 364.110609 -283.442247) (xy 364.080585 -283.39821) (xy 364.057459 -283.350189) (xy 364.041749 -283.299259)
			(xy 364.033806 -283.246555) (xy 361.925372 -283.246555) (xy 361.917429 -283.299259) (xy 361.901719 -283.350189)
			(xy 361.878593 -283.39821) (xy 361.848569 -283.442247) (xy 361.812317 -283.481318) (xy 361.770646 -283.514549)
			(xy 361.724488 -283.541198) (xy 361.674874 -283.56067) (xy 361.622912 -283.57253) (xy 361.569762 -283.576514)
			(xy 361.516612 -283.57253) (xy 361.46465 -283.56067) (xy 361.415036 -283.541198) (xy 361.368878 -283.514549)
			(xy 361.327207 -283.481318) (xy 361.290955 -283.442247) (xy 361.260931 -283.39821) (xy 361.237805 -283.350189)
			(xy 361.222095 -283.299259) (xy 361.214152 -283.246555) (xy 355.347026 -283.246555) (xy 355.339083 -283.299259)
			(xy 355.323373 -283.350189) (xy 355.300247 -283.39821) (xy 355.270223 -283.442247) (xy 355.233971 -283.481318)
			(xy 355.1923 -283.514549) (xy 355.146142 -283.541198) (xy 355.096528 -283.56067) (xy 355.044566 -283.57253)
			(xy 354.991416 -283.576514) (xy 354.938266 -283.57253) (xy 354.886304 -283.56067) (xy 354.83669 -283.541198)
			(xy 354.790532 -283.514549) (xy 354.748861 -283.481318) (xy 354.712609 -283.442247) (xy 354.682585 -283.39821)
			(xy 354.659459 -283.350189) (xy 354.643749 -283.299259) (xy 354.635806 -283.246555) (xy 354.406972 -283.246555)
			(xy 354.399029 -283.299259) (xy 354.383319 -283.350189) (xy 354.360193 -283.39821) (xy 354.330169 -283.442247)
			(xy 354.293917 -283.481318) (xy 354.252246 -283.514549) (xy 354.206088 -283.541198) (xy 354.156474 -283.56067)
			(xy 354.104512 -283.57253) (xy 354.051362 -283.576514) (xy 353.998212 -283.57253) (xy 353.94625 -283.56067)
			(xy 353.896636 -283.541198) (xy 353.850478 -283.514549) (xy 353.808807 -283.481318) (xy 353.772555 -283.442247)
			(xy 353.742531 -283.39821) (xy 353.719405 -283.350189) (xy 353.703695 -283.299259) (xy 353.695752 -283.246555)
			(xy 353.440849 -283.246555) (xy 353.4333 -283.295365) (xy 353.417968 -283.343694) (xy 353.395416 -283.389105)
			(xy 353.366175 -283.430527) (xy 353.330937 -283.466983) (xy 353.290531 -283.497612) (xy 353.245912 -283.521693)
			(xy 353.198131 -283.538656) (xy 353.148316 -283.548103) (xy 353.122992 -283.549344) (xy 353.10738 -283.550425)
			(xy 353.077893 -283.560856) (xy 353.052945 -283.579721) (xy 353.034876 -283.605251) (xy 353.025379 -283.635052)
			(xy 353.024694 -283.65069) (xy 353.024694 -284.060371) (xy 353.225852 -284.060371) (xy 353.225852 -284.007073)
			(xy 353.233795 -283.954369) (xy 353.249505 -283.903439) (xy 353.272631 -283.855418) (xy 353.302655 -283.811381)
			(xy 353.338907 -283.77231) (xy 353.380578 -283.739079) (xy 353.426736 -283.71243) (xy 353.47635 -283.692958)
			(xy 353.528312 -283.681098) (xy 353.581462 -283.677115) (xy 353.634612 -283.681098) (xy 353.686574 -283.692958)
			(xy 353.736188 -283.71243) (xy 353.782346 -283.739079) (xy 353.824017 -283.77231) (xy 353.860269 -283.811381)
			(xy 353.890293 -283.855418) (xy 353.913419 -283.903439) (xy 353.929129 -283.954369) (xy 353.937072 -284.007073)
			(xy 353.93757 -284.033722) (xy 353.937072 -284.060371) (xy 355.105452 -284.060371) (xy 355.105452 -284.007073)
			(xy 355.113395 -283.954369) (xy 355.129105 -283.903439) (xy 355.152231 -283.855418) (xy 355.182255 -283.811381)
			(xy 355.218507 -283.77231) (xy 355.260178 -283.739079) (xy 355.306336 -283.71243) (xy 355.35595 -283.692958)
			(xy 355.407912 -283.681098) (xy 355.461062 -283.677115) (xy 355.514212 -283.681098) (xy 355.566174 -283.692958)
			(xy 355.615788 -283.71243) (xy 355.661946 -283.739079) (xy 355.703617 -283.77231) (xy 355.739869 -283.811381)
			(xy 355.769893 -283.855418) (xy 355.793019 -283.903439) (xy 355.808729 -283.954369) (xy 355.816672 -284.007073)
			(xy 355.81717 -284.033722) (xy 355.816672 -284.060371) (xy 357.924852 -284.060371) (xy 357.924852 -284.007073)
			(xy 357.932795 -283.954369) (xy 357.948505 -283.903439) (xy 357.971631 -283.855418) (xy 358.001655 -283.811381)
			(xy 358.037907 -283.77231) (xy 358.079578 -283.739079) (xy 358.125736 -283.71243) (xy 358.17535 -283.692958)
			(xy 358.227312 -283.681098) (xy 358.280462 -283.677115) (xy 358.333612 -283.681098) (xy 358.385574 -283.692958)
			(xy 358.435188 -283.71243) (xy 358.481346 -283.739079) (xy 358.523017 -283.77231) (xy 358.559269 -283.811381)
			(xy 358.589293 -283.855418) (xy 358.612419 -283.903439) (xy 358.628129 -283.954369) (xy 358.636072 -284.007073)
			(xy 358.63657 -284.033722) (xy 358.636072 -284.060371) (xy 366.383052 -284.060371) (xy 366.383052 -284.007073)
			(xy 366.390995 -283.954369) (xy 366.406705 -283.903439) (xy 366.429831 -283.855418) (xy 366.459855 -283.811381)
			(xy 366.496107 -283.77231) (xy 366.537778 -283.739079) (xy 366.583936 -283.71243) (xy 366.63355 -283.692958)
			(xy 366.685512 -283.681098) (xy 366.738662 -283.677115) (xy 366.791812 -283.681098) (xy 366.843774 -283.692958)
			(xy 366.893388 -283.71243) (xy 366.939546 -283.739079) (xy 366.981217 -283.77231) (xy 367.017469 -283.811381)
			(xy 367.047493 -283.855418) (xy 367.070619 -283.903439) (xy 367.086329 -283.954369) (xy 367.094272 -284.007073)
			(xy 367.09477 -284.033722) (xy 367.094272 -284.060371) (xy 367.322852 -284.060371) (xy 367.322852 -284.007073)
			(xy 367.330795 -283.954369) (xy 367.346505 -283.903439) (xy 367.369631 -283.855418) (xy 367.399655 -283.811381)
			(xy 367.435907 -283.77231) (xy 367.477578 -283.739079) (xy 367.523736 -283.71243) (xy 367.57335 -283.692958)
			(xy 367.625312 -283.681098) (xy 367.678462 -283.677115) (xy 367.731612 -283.681098) (xy 367.783574 -283.692958)
			(xy 367.833188 -283.71243) (xy 367.879346 -283.739079) (xy 367.921017 -283.77231) (xy 367.957269 -283.811381)
			(xy 367.987293 -283.855418) (xy 368.010419 -283.903439) (xy 368.026129 -283.954369) (xy 368.034072 -284.007073)
			(xy 368.03457 -284.033722) (xy 368.034072 -284.060371) (xy 368.262652 -284.060371) (xy 368.262652 -284.007073)
			(xy 368.270595 -283.954369) (xy 368.286305 -283.903439) (xy 368.309431 -283.855418) (xy 368.339455 -283.811381)
			(xy 368.375707 -283.77231) (xy 368.417378 -283.739079) (xy 368.463536 -283.71243) (xy 368.51315 -283.692958)
			(xy 368.565112 -283.681098) (xy 368.618262 -283.677115) (xy 368.671412 -283.681098) (xy 368.723374 -283.692958)
			(xy 368.772988 -283.71243) (xy 368.819146 -283.739079) (xy 368.860817 -283.77231) (xy 368.897069 -283.811381)
			(xy 368.927093 -283.855418) (xy 368.950219 -283.903439) (xy 368.965929 -283.954369) (xy 368.973872 -284.007073)
			(xy 368.97437 -284.033722) (xy 368.973872 -284.060371) (xy 369.202452 -284.060371) (xy 369.202452 -284.007073)
			(xy 369.210395 -283.954369) (xy 369.226105 -283.903439) (xy 369.249231 -283.855418) (xy 369.279255 -283.811381)
			(xy 369.315507 -283.77231) (xy 369.357178 -283.739079) (xy 369.403336 -283.71243) (xy 369.45295 -283.692958)
			(xy 369.504912 -283.681098) (xy 369.558062 -283.677115) (xy 369.611212 -283.681098) (xy 369.663174 -283.692958)
			(xy 369.712788 -283.71243) (xy 369.758946 -283.739079) (xy 369.800617 -283.77231) (xy 369.836869 -283.811381)
			(xy 369.866893 -283.855418) (xy 369.890019 -283.903439) (xy 369.905729 -283.954369) (xy 369.913672 -284.007073)
			(xy 369.91417 -284.033722) (xy 369.913672 -284.060371) (xy 370.142252 -284.060371) (xy 370.142252 -284.007073)
			(xy 370.150195 -283.954369) (xy 370.165905 -283.903439) (xy 370.189031 -283.855418) (xy 370.219055 -283.811381)
			(xy 370.255307 -283.77231) (xy 370.296978 -283.739079) (xy 370.343136 -283.71243) (xy 370.39275 -283.692958)
			(xy 370.444712 -283.681098) (xy 370.497862 -283.677115) (xy 370.551012 -283.681098) (xy 370.602974 -283.692958)
			(xy 370.652588 -283.71243) (xy 370.698746 -283.739079) (xy 370.740417 -283.77231) (xy 370.776669 -283.811381)
			(xy 370.806693 -283.855418) (xy 370.829819 -283.903439) (xy 370.845529 -283.954369) (xy 370.853472 -284.007073)
			(xy 370.85397 -284.033722) (xy 370.853472 -284.060371) (xy 371.082052 -284.060371) (xy 371.082052 -284.007073)
			(xy 371.089995 -283.954369) (xy 371.105705 -283.903439) (xy 371.128831 -283.855418) (xy 371.158855 -283.811381)
			(xy 371.195107 -283.77231) (xy 371.236778 -283.739079) (xy 371.282936 -283.71243) (xy 371.33255 -283.692958)
			(xy 371.384512 -283.681098) (xy 371.437662 -283.677115) (xy 371.490812 -283.681098) (xy 371.542774 -283.692958)
			(xy 371.592388 -283.71243) (xy 371.638546 -283.739079) (xy 371.680217 -283.77231) (xy 371.716469 -283.811381)
			(xy 371.746493 -283.855418) (xy 371.769619 -283.903439) (xy 371.785329 -283.954369) (xy 371.793272 -284.007073)
			(xy 371.79377 -284.033722) (xy 371.793272 -284.060371) (xy 372.021852 -284.060371) (xy 372.021852 -284.007073)
			(xy 372.029795 -283.954369) (xy 372.045505 -283.903439) (xy 372.068631 -283.855418) (xy 372.098655 -283.811381)
			(xy 372.134907 -283.77231) (xy 372.176578 -283.739079) (xy 372.222736 -283.71243) (xy 372.27235 -283.692958)
			(xy 372.324312 -283.681098) (xy 372.377462 -283.677115) (xy 372.430612 -283.681098) (xy 372.482574 -283.692958)
			(xy 372.532188 -283.71243) (xy 372.578346 -283.739079) (xy 372.620017 -283.77231) (xy 372.656269 -283.811381)
			(xy 372.686293 -283.855418) (xy 372.709419 -283.903439) (xy 372.725129 -283.954369) (xy 372.733072 -284.007073)
			(xy 372.73357 -284.033722) (xy 372.733072 -284.060371) (xy 372.961906 -284.060371) (xy 372.961906 -284.007073)
			(xy 372.969849 -283.954369) (xy 372.985559 -283.903439) (xy 373.008685 -283.855418) (xy 373.038709 -283.811381)
			(xy 373.074961 -283.77231) (xy 373.116632 -283.739079) (xy 373.16279 -283.71243) (xy 373.212404 -283.692958)
			(xy 373.264366 -283.681098) (xy 373.317516 -283.677115) (xy 373.370666 -283.681098) (xy 373.422628 -283.692958)
			(xy 373.472242 -283.71243) (xy 373.5184 -283.739079) (xy 373.560071 -283.77231) (xy 373.596323 -283.811381)
			(xy 373.626347 -283.855418) (xy 373.649473 -283.903439) (xy 373.665183 -283.954369) (xy 373.673126 -284.007073)
			(xy 373.673624 -284.033722) (xy 373.673126 -284.060371) (xy 373.901452 -284.060371) (xy 373.901452 -284.007073)
			(xy 373.909395 -283.954369) (xy 373.925105 -283.903439) (xy 373.948231 -283.855418) (xy 373.978255 -283.811381)
			(xy 374.014507 -283.77231) (xy 374.056178 -283.739079) (xy 374.102336 -283.71243) (xy 374.15195 -283.692958)
			(xy 374.203912 -283.681098) (xy 374.257062 -283.677115) (xy 374.310212 -283.681098) (xy 374.362174 -283.692958)
			(xy 374.411788 -283.71243) (xy 374.457946 -283.739079) (xy 374.499617 -283.77231) (xy 374.535869 -283.811381)
			(xy 374.565893 -283.855418) (xy 374.589019 -283.903439) (xy 374.604729 -283.954369) (xy 374.612672 -284.007073)
			(xy 374.61317 -284.033722) (xy 374.612672 -284.060371) (xy 374.841252 -284.060371) (xy 374.841252 -284.007073)
			(xy 374.849195 -283.954369) (xy 374.864905 -283.903439) (xy 374.888031 -283.855418) (xy 374.918055 -283.811381)
			(xy 374.954307 -283.77231) (xy 374.995978 -283.739079) (xy 375.042136 -283.71243) (xy 375.09175 -283.692958)
			(xy 375.143712 -283.681098) (xy 375.196862 -283.677115) (xy 375.250012 -283.681098) (xy 375.301974 -283.692958)
			(xy 375.351588 -283.71243) (xy 375.397746 -283.739079) (xy 375.439417 -283.77231) (xy 375.475669 -283.811381)
			(xy 375.505693 -283.855418) (xy 375.528819 -283.903439) (xy 375.544529 -283.954369) (xy 375.552472 -284.007073)
			(xy 375.55297 -284.033722) (xy 375.552472 -284.060371) (xy 375.781052 -284.060371) (xy 375.781052 -284.007073)
			(xy 375.788995 -283.954369) (xy 375.804705 -283.903439) (xy 375.827831 -283.855418) (xy 375.857855 -283.811381)
			(xy 375.894107 -283.77231) (xy 375.935778 -283.739079) (xy 375.981936 -283.71243) (xy 376.03155 -283.692958)
			(xy 376.083512 -283.681098) (xy 376.136662 -283.677115) (xy 376.189812 -283.681098) (xy 376.241774 -283.692958)
			(xy 376.291388 -283.71243) (xy 376.337546 -283.739079) (xy 376.379217 -283.77231) (xy 376.415469 -283.811381)
			(xy 376.445493 -283.855418) (xy 376.468619 -283.903439) (xy 376.484329 -283.954369) (xy 376.492272 -284.007073)
			(xy 376.49277 -284.033722) (xy 376.492272 -284.060371) (xy 376.720852 -284.060371) (xy 376.720852 -284.007073)
			(xy 376.728795 -283.954369) (xy 376.744505 -283.903439) (xy 376.767631 -283.855418) (xy 376.797655 -283.811381)
			(xy 376.833907 -283.77231) (xy 376.875578 -283.739079) (xy 376.921736 -283.71243) (xy 376.97135 -283.692958)
			(xy 377.023312 -283.681098) (xy 377.076462 -283.677115) (xy 377.129612 -283.681098) (xy 377.181574 -283.692958)
			(xy 377.231188 -283.71243) (xy 377.277346 -283.739079) (xy 377.319017 -283.77231) (xy 377.355269 -283.811381)
			(xy 377.385293 -283.855418) (xy 377.408419 -283.903439) (xy 377.424129 -283.954369) (xy 377.432072 -284.007073)
			(xy 377.43257 -284.033722) (xy 377.432072 -284.060371) (xy 377.660652 -284.060371) (xy 377.660652 -284.007073)
			(xy 377.668595 -283.954369) (xy 377.684305 -283.903439) (xy 377.707431 -283.855418) (xy 377.737455 -283.811381)
			(xy 377.773707 -283.77231) (xy 377.815378 -283.739079) (xy 377.861536 -283.71243) (xy 377.91115 -283.692958)
			(xy 377.963112 -283.681098) (xy 378.016262 -283.677115) (xy 378.069412 -283.681098) (xy 378.121374 -283.692958)
			(xy 378.170988 -283.71243) (xy 378.217146 -283.739079) (xy 378.258817 -283.77231) (xy 378.295069 -283.811381)
			(xy 378.325093 -283.855418) (xy 378.348219 -283.903439) (xy 378.363929 -283.954369) (xy 378.371872 -284.007073)
			(xy 378.37237 -284.033722) (xy 378.371872 -284.060371) (xy 378.600452 -284.060371) (xy 378.600452 -284.007073)
			(xy 378.608395 -283.954369) (xy 378.624105 -283.903439) (xy 378.647231 -283.855418) (xy 378.677255 -283.811381)
			(xy 378.713507 -283.77231) (xy 378.755178 -283.739079) (xy 378.801336 -283.71243) (xy 378.85095 -283.692958)
			(xy 378.902912 -283.681098) (xy 378.956062 -283.677115) (xy 379.009212 -283.681098) (xy 379.061174 -283.692958)
			(xy 379.110788 -283.71243) (xy 379.156946 -283.739079) (xy 379.198617 -283.77231) (xy 379.234869 -283.811381)
			(xy 379.264893 -283.855418) (xy 379.288019 -283.903439) (xy 379.303729 -283.954369) (xy 379.311672 -284.007073)
			(xy 379.31217 -284.033722) (xy 379.311672 -284.060371) (xy 379.540252 -284.060371) (xy 379.540252 -284.007073)
			(xy 379.548195 -283.954369) (xy 379.563905 -283.903439) (xy 379.587031 -283.855418) (xy 379.617055 -283.811381)
			(xy 379.653307 -283.77231) (xy 379.694978 -283.739079) (xy 379.741136 -283.71243) (xy 379.79075 -283.692958)
			(xy 379.842712 -283.681098) (xy 379.895862 -283.677115) (xy 379.949012 -283.681098) (xy 380.000974 -283.692958)
			(xy 380.050588 -283.71243) (xy 380.096746 -283.739079) (xy 380.138417 -283.77231) (xy 380.174669 -283.811381)
			(xy 380.204693 -283.855418) (xy 380.227819 -283.903439) (xy 380.243529 -283.954369) (xy 380.251472 -284.007073)
			(xy 380.25197 -284.033722) (xy 380.251472 -284.060371) (xy 380.480052 -284.060371) (xy 380.480052 -284.007073)
			(xy 380.487995 -283.954369) (xy 380.503705 -283.903439) (xy 380.526831 -283.855418) (xy 380.556855 -283.811381)
			(xy 380.593107 -283.77231) (xy 380.634778 -283.739079) (xy 380.680936 -283.71243) (xy 380.73055 -283.692958)
			(xy 380.782512 -283.681098) (xy 380.835662 -283.677115) (xy 380.888812 -283.681098) (xy 380.940774 -283.692958)
			(xy 380.990388 -283.71243) (xy 381.036546 -283.739079) (xy 381.078217 -283.77231) (xy 381.114469 -283.811381)
			(xy 381.144493 -283.855418) (xy 381.167619 -283.903439) (xy 381.183329 -283.954369) (xy 381.191272 -284.007073)
			(xy 381.19177 -284.033722) (xy 381.191272 -284.060371) (xy 381.419852 -284.060371) (xy 381.419852 -284.007073)
			(xy 381.427795 -283.954369) (xy 381.443505 -283.903439) (xy 381.466631 -283.855418) (xy 381.496655 -283.811381)
			(xy 381.532907 -283.77231) (xy 381.574578 -283.739079) (xy 381.620736 -283.71243) (xy 381.67035 -283.692958)
			(xy 381.722312 -283.681098) (xy 381.775462 -283.677115) (xy 381.828612 -283.681098) (xy 381.880574 -283.692958)
			(xy 381.930188 -283.71243) (xy 381.976346 -283.739079) (xy 382.018017 -283.77231) (xy 382.054269 -283.811381)
			(xy 382.084293 -283.855418) (xy 382.107419 -283.903439) (xy 382.123129 -283.954369) (xy 382.131072 -284.007073)
			(xy 382.13157 -284.033722) (xy 382.131072 -284.060371) (xy 382.359652 -284.060371) (xy 382.359652 -284.007073)
			(xy 382.367595 -283.954369) (xy 382.383305 -283.903439) (xy 382.406431 -283.855418) (xy 382.436455 -283.811381)
			(xy 382.472707 -283.77231) (xy 382.514378 -283.739079) (xy 382.560536 -283.71243) (xy 382.61015 -283.692958)
			(xy 382.662112 -283.681098) (xy 382.715262 -283.677115) (xy 382.768412 -283.681098) (xy 382.820374 -283.692958)
			(xy 382.869988 -283.71243) (xy 382.916146 -283.739079) (xy 382.957817 -283.77231) (xy 382.994069 -283.811381)
			(xy 383.024093 -283.855418) (xy 383.047219 -283.903439) (xy 383.062929 -283.954369) (xy 383.070872 -284.007073)
			(xy 383.07137 -284.033722) (xy 383.070872 -284.060371) (xy 383.299452 -284.060371) (xy 383.299452 -284.007073)
			(xy 383.307395 -283.954369) (xy 383.323105 -283.903439) (xy 383.346231 -283.855418) (xy 383.376255 -283.811381)
			(xy 383.412507 -283.77231) (xy 383.454178 -283.739079) (xy 383.500336 -283.71243) (xy 383.54995 -283.692958)
			(xy 383.601912 -283.681098) (xy 383.655062 -283.677115) (xy 383.708212 -283.681098) (xy 383.760174 -283.692958)
			(xy 383.809788 -283.71243) (xy 383.855946 -283.739079) (xy 383.897617 -283.77231) (xy 383.933869 -283.811381)
			(xy 383.963893 -283.855418) (xy 383.987019 -283.903439) (xy 384.002729 -283.954369) (xy 384.010672 -284.007073)
			(xy 384.01117 -284.033722) (xy 384.010672 -284.060371) (xy 385.179052 -284.060371) (xy 385.179052 -284.007073)
			(xy 385.186995 -283.954369) (xy 385.202705 -283.903439) (xy 385.225831 -283.855418) (xy 385.255855 -283.811381)
			(xy 385.292107 -283.77231) (xy 385.333778 -283.739079) (xy 385.379936 -283.71243) (xy 385.42955 -283.692958)
			(xy 385.481512 -283.681098) (xy 385.534662 -283.677115) (xy 385.587812 -283.681098) (xy 385.639774 -283.692958)
			(xy 385.689388 -283.71243) (xy 385.735546 -283.739079) (xy 385.777217 -283.77231) (xy 385.813469 -283.811381)
			(xy 385.843493 -283.855418) (xy 385.866619 -283.903439) (xy 385.882329 -283.954369) (xy 385.890272 -284.007073)
			(xy 385.89077 -284.033722) (xy 385.890272 -284.060371) (xy 386.118852 -284.060371) (xy 386.118852 -284.007073)
			(xy 386.126795 -283.954369) (xy 386.142505 -283.903439) (xy 386.165631 -283.855418) (xy 386.195655 -283.811381)
			(xy 386.231907 -283.77231) (xy 386.273578 -283.739079) (xy 386.319736 -283.71243) (xy 386.36935 -283.692958)
			(xy 386.421312 -283.681098) (xy 386.474462 -283.677115) (xy 386.527612 -283.681098) (xy 386.579574 -283.692958)
			(xy 386.629188 -283.71243) (xy 386.675346 -283.739079) (xy 386.717017 -283.77231) (xy 386.753269 -283.811381)
			(xy 386.783293 -283.855418) (xy 386.806419 -283.903439) (xy 386.822129 -283.954369) (xy 386.830072 -284.007073)
			(xy 386.83057 -284.033722) (xy 386.830072 -284.060371) (xy 386.822129 -284.113075) (xy 386.806419 -284.164005)
			(xy 386.783293 -284.212026) (xy 386.753269 -284.256063) (xy 386.717017 -284.295134) (xy 386.675346 -284.328365)
			(xy 386.629188 -284.355014) (xy 386.579574 -284.374486) (xy 386.527612 -284.386346) (xy 386.474462 -284.39033)
			(xy 386.421312 -284.386346) (xy 386.36935 -284.374486) (xy 386.319736 -284.355014) (xy 386.273578 -284.328365)
			(xy 386.231907 -284.295134) (xy 386.195655 -284.256063) (xy 386.165631 -284.212026) (xy 386.142505 -284.164005)
			(xy 386.126795 -284.113075) (xy 386.118852 -284.060371) (xy 385.890272 -284.060371) (xy 385.882329 -284.113075)
			(xy 385.866619 -284.164005) (xy 385.843493 -284.212026) (xy 385.813469 -284.256063) (xy 385.777217 -284.295134)
			(xy 385.735546 -284.328365) (xy 385.689388 -284.355014) (xy 385.639774 -284.374486) (xy 385.587812 -284.386346)
			(xy 385.534662 -284.39033) (xy 385.481512 -284.386346) (xy 385.42955 -284.374486) (xy 385.379936 -284.355014)
			(xy 385.333778 -284.328365) (xy 385.292107 -284.295134) (xy 385.255855 -284.256063) (xy 385.225831 -284.212026)
			(xy 385.202705 -284.164005) (xy 385.186995 -284.113075) (xy 385.179052 -284.060371) (xy 384.010672 -284.060371)
			(xy 384.002729 -284.113075) (xy 383.987019 -284.164005) (xy 383.963893 -284.212026) (xy 383.933869 -284.256063)
			(xy 383.897617 -284.295134) (xy 383.855946 -284.328365) (xy 383.809788 -284.355014) (xy 383.760174 -284.374486)
			(xy 383.708212 -284.386346) (xy 383.655062 -284.39033) (xy 383.601912 -284.386346) (xy 383.54995 -284.374486)
			(xy 383.500336 -284.355014) (xy 383.454178 -284.328365) (xy 383.412507 -284.295134) (xy 383.376255 -284.256063)
			(xy 383.346231 -284.212026) (xy 383.323105 -284.164005) (xy 383.307395 -284.113075) (xy 383.299452 -284.060371)
			(xy 383.070872 -284.060371) (xy 383.062929 -284.113075) (xy 383.047219 -284.164005) (xy 383.024093 -284.212026)
			(xy 382.994069 -284.256063) (xy 382.957817 -284.295134) (xy 382.916146 -284.328365) (xy 382.869988 -284.355014)
			(xy 382.820374 -284.374486) (xy 382.768412 -284.386346) (xy 382.715262 -284.39033) (xy 382.662112 -284.386346)
			(xy 382.61015 -284.374486) (xy 382.560536 -284.355014) (xy 382.514378 -284.328365) (xy 382.472707 -284.295134)
			(xy 382.436455 -284.256063) (xy 382.406431 -284.212026) (xy 382.383305 -284.164005) (xy 382.367595 -284.113075)
			(xy 382.359652 -284.060371) (xy 382.131072 -284.060371) (xy 382.123129 -284.113075) (xy 382.107419 -284.164005)
			(xy 382.084293 -284.212026) (xy 382.054269 -284.256063) (xy 382.018017 -284.295134) (xy 381.976346 -284.328365)
			(xy 381.930188 -284.355014) (xy 381.880574 -284.374486) (xy 381.828612 -284.386346) (xy 381.775462 -284.39033)
			(xy 381.722312 -284.386346) (xy 381.67035 -284.374486) (xy 381.620736 -284.355014) (xy 381.574578 -284.328365)
			(xy 381.532907 -284.295134) (xy 381.496655 -284.256063) (xy 381.466631 -284.212026) (xy 381.443505 -284.164005)
			(xy 381.427795 -284.113075) (xy 381.419852 -284.060371) (xy 381.191272 -284.060371) (xy 381.183329 -284.113075)
			(xy 381.167619 -284.164005) (xy 381.144493 -284.212026) (xy 381.114469 -284.256063) (xy 381.078217 -284.295134)
			(xy 381.036546 -284.328365) (xy 380.990388 -284.355014) (xy 380.940774 -284.374486) (xy 380.888812 -284.386346)
			(xy 380.835662 -284.39033) (xy 380.782512 -284.386346) (xy 380.73055 -284.374486) (xy 380.680936 -284.355014)
			(xy 380.634778 -284.328365) (xy 380.593107 -284.295134) (xy 380.556855 -284.256063) (xy 380.526831 -284.212026)
			(xy 380.503705 -284.164005) (xy 380.487995 -284.113075) (xy 380.480052 -284.060371) (xy 380.251472 -284.060371)
			(xy 380.243529 -284.113075) (xy 380.227819 -284.164005) (xy 380.204693 -284.212026) (xy 380.174669 -284.256063)
			(xy 380.138417 -284.295134) (xy 380.096746 -284.328365) (xy 380.050588 -284.355014) (xy 380.000974 -284.374486)
			(xy 379.949012 -284.386346) (xy 379.895862 -284.39033) (xy 379.842712 -284.386346) (xy 379.79075 -284.374486)
			(xy 379.741136 -284.355014) (xy 379.694978 -284.328365) (xy 379.653307 -284.295134) (xy 379.617055 -284.256063)
			(xy 379.587031 -284.212026) (xy 379.563905 -284.164005) (xy 379.548195 -284.113075) (xy 379.540252 -284.060371)
			(xy 379.311672 -284.060371) (xy 379.303729 -284.113075) (xy 379.288019 -284.164005) (xy 379.264893 -284.212026)
			(xy 379.234869 -284.256063) (xy 379.198617 -284.295134) (xy 379.156946 -284.328365) (xy 379.110788 -284.355014)
			(xy 379.061174 -284.374486) (xy 379.009212 -284.386346) (xy 378.956062 -284.39033) (xy 378.902912 -284.386346)
			(xy 378.85095 -284.374486) (xy 378.801336 -284.355014) (xy 378.755178 -284.328365) (xy 378.713507 -284.295134)
			(xy 378.677255 -284.256063) (xy 378.647231 -284.212026) (xy 378.624105 -284.164005) (xy 378.608395 -284.113075)
			(xy 378.600452 -284.060371) (xy 378.371872 -284.060371) (xy 378.363929 -284.113075) (xy 378.348219 -284.164005)
			(xy 378.325093 -284.212026) (xy 378.295069 -284.256063) (xy 378.258817 -284.295134) (xy 378.217146 -284.328365)
			(xy 378.170988 -284.355014) (xy 378.121374 -284.374486) (xy 378.069412 -284.386346) (xy 378.016262 -284.39033)
			(xy 377.963112 -284.386346) (xy 377.91115 -284.374486) (xy 377.861536 -284.355014) (xy 377.815378 -284.328365)
			(xy 377.773707 -284.295134) (xy 377.737455 -284.256063) (xy 377.707431 -284.212026) (xy 377.684305 -284.164005)
			(xy 377.668595 -284.113075) (xy 377.660652 -284.060371) (xy 377.432072 -284.060371) (xy 377.424129 -284.113075)
			(xy 377.408419 -284.164005) (xy 377.385293 -284.212026) (xy 377.355269 -284.256063) (xy 377.319017 -284.295134)
			(xy 377.277346 -284.328365) (xy 377.231188 -284.355014) (xy 377.181574 -284.374486) (xy 377.129612 -284.386346)
			(xy 377.076462 -284.39033) (xy 377.023312 -284.386346) (xy 376.97135 -284.374486) (xy 376.921736 -284.355014)
			(xy 376.875578 -284.328365) (xy 376.833907 -284.295134) (xy 376.797655 -284.256063) (xy 376.767631 -284.212026)
			(xy 376.744505 -284.164005) (xy 376.728795 -284.113075) (xy 376.720852 -284.060371) (xy 376.492272 -284.060371)
			(xy 376.484329 -284.113075) (xy 376.468619 -284.164005) (xy 376.445493 -284.212026) (xy 376.415469 -284.256063)
			(xy 376.379217 -284.295134) (xy 376.337546 -284.328365) (xy 376.291388 -284.355014) (xy 376.241774 -284.374486)
			(xy 376.189812 -284.386346) (xy 376.136662 -284.39033) (xy 376.083512 -284.386346) (xy 376.03155 -284.374486)
			(xy 375.981936 -284.355014) (xy 375.935778 -284.328365) (xy 375.894107 -284.295134) (xy 375.857855 -284.256063)
			(xy 375.827831 -284.212026) (xy 375.804705 -284.164005) (xy 375.788995 -284.113075) (xy 375.781052 -284.060371)
			(xy 375.552472 -284.060371) (xy 375.544529 -284.113075) (xy 375.528819 -284.164005) (xy 375.505693 -284.212026)
			(xy 375.475669 -284.256063) (xy 375.439417 -284.295134) (xy 375.397746 -284.328365) (xy 375.351588 -284.355014)
			(xy 375.301974 -284.374486) (xy 375.250012 -284.386346) (xy 375.196862 -284.39033) (xy 375.143712 -284.386346)
			(xy 375.09175 -284.374486) (xy 375.042136 -284.355014) (xy 374.995978 -284.328365) (xy 374.954307 -284.295134)
			(xy 374.918055 -284.256063) (xy 374.888031 -284.212026) (xy 374.864905 -284.164005) (xy 374.849195 -284.113075)
			(xy 374.841252 -284.060371) (xy 374.612672 -284.060371) (xy 374.604729 -284.113075) (xy 374.589019 -284.164005)
			(xy 374.565893 -284.212026) (xy 374.535869 -284.256063) (xy 374.499617 -284.295134) (xy 374.457946 -284.328365)
			(xy 374.411788 -284.355014) (xy 374.362174 -284.374486) (xy 374.310212 -284.386346) (xy 374.257062 -284.39033)
			(xy 374.203912 -284.386346) (xy 374.15195 -284.374486) (xy 374.102336 -284.355014) (xy 374.056178 -284.328365)
			(xy 374.014507 -284.295134) (xy 373.978255 -284.256063) (xy 373.948231 -284.212026) (xy 373.925105 -284.164005)
			(xy 373.909395 -284.113075) (xy 373.901452 -284.060371) (xy 373.673126 -284.060371) (xy 373.665183 -284.113075)
			(xy 373.649473 -284.164005) (xy 373.626347 -284.212026) (xy 373.596323 -284.256063) (xy 373.560071 -284.295134)
			(xy 373.5184 -284.328365) (xy 373.472242 -284.355014) (xy 373.422628 -284.374486) (xy 373.370666 -284.386346)
			(xy 373.317516 -284.39033) (xy 373.264366 -284.386346) (xy 373.212404 -284.374486) (xy 373.16279 -284.355014)
			(xy 373.116632 -284.328365) (xy 373.074961 -284.295134) (xy 373.038709 -284.256063) (xy 373.008685 -284.212026)
			(xy 372.985559 -284.164005) (xy 372.969849 -284.113075) (xy 372.961906 -284.060371) (xy 372.733072 -284.060371)
			(xy 372.725129 -284.113075) (xy 372.709419 -284.164005) (xy 372.686293 -284.212026) (xy 372.656269 -284.256063)
			(xy 372.620017 -284.295134) (xy 372.578346 -284.328365) (xy 372.532188 -284.355014) (xy 372.482574 -284.374486)
			(xy 372.430612 -284.386346) (xy 372.377462 -284.39033) (xy 372.324312 -284.386346) (xy 372.27235 -284.374486)
			(xy 372.222736 -284.355014) (xy 372.176578 -284.328365) (xy 372.134907 -284.295134) (xy 372.098655 -284.256063)
			(xy 372.068631 -284.212026) (xy 372.045505 -284.164005) (xy 372.029795 -284.113075) (xy 372.021852 -284.060371)
			(xy 371.793272 -284.060371) (xy 371.785329 -284.113075) (xy 371.769619 -284.164005) (xy 371.746493 -284.212026)
			(xy 371.716469 -284.256063) (xy 371.680217 -284.295134) (xy 371.638546 -284.328365) (xy 371.592388 -284.355014)
			(xy 371.542774 -284.374486) (xy 371.490812 -284.386346) (xy 371.437662 -284.39033) (xy 371.384512 -284.386346)
			(xy 371.33255 -284.374486) (xy 371.282936 -284.355014) (xy 371.236778 -284.328365) (xy 371.195107 -284.295134)
			(xy 371.158855 -284.256063) (xy 371.128831 -284.212026) (xy 371.105705 -284.164005) (xy 371.089995 -284.113075)
			(xy 371.082052 -284.060371) (xy 370.853472 -284.060371) (xy 370.845529 -284.113075) (xy 370.829819 -284.164005)
			(xy 370.806693 -284.212026) (xy 370.776669 -284.256063) (xy 370.740417 -284.295134) (xy 370.698746 -284.328365)
			(xy 370.652588 -284.355014) (xy 370.602974 -284.374486) (xy 370.551012 -284.386346) (xy 370.497862 -284.39033)
			(xy 370.444712 -284.386346) (xy 370.39275 -284.374486) (xy 370.343136 -284.355014) (xy 370.296978 -284.328365)
			(xy 370.255307 -284.295134) (xy 370.219055 -284.256063) (xy 370.189031 -284.212026) (xy 370.165905 -284.164005)
			(xy 370.150195 -284.113075) (xy 370.142252 -284.060371) (xy 369.913672 -284.060371) (xy 369.905729 -284.113075)
			(xy 369.890019 -284.164005) (xy 369.866893 -284.212026) (xy 369.836869 -284.256063) (xy 369.800617 -284.295134)
			(xy 369.758946 -284.328365) (xy 369.712788 -284.355014) (xy 369.663174 -284.374486) (xy 369.611212 -284.386346)
			(xy 369.558062 -284.39033) (xy 369.504912 -284.386346) (xy 369.45295 -284.374486) (xy 369.403336 -284.355014)
			(xy 369.357178 -284.328365) (xy 369.315507 -284.295134) (xy 369.279255 -284.256063) (xy 369.249231 -284.212026)
			(xy 369.226105 -284.164005) (xy 369.210395 -284.113075) (xy 369.202452 -284.060371) (xy 368.973872 -284.060371)
			(xy 368.965929 -284.113075) (xy 368.950219 -284.164005) (xy 368.927093 -284.212026) (xy 368.897069 -284.256063)
			(xy 368.860817 -284.295134) (xy 368.819146 -284.328365) (xy 368.772988 -284.355014) (xy 368.723374 -284.374486)
			(xy 368.671412 -284.386346) (xy 368.618262 -284.39033) (xy 368.565112 -284.386346) (xy 368.51315 -284.374486)
			(xy 368.463536 -284.355014) (xy 368.417378 -284.328365) (xy 368.375707 -284.295134) (xy 368.339455 -284.256063)
			(xy 368.309431 -284.212026) (xy 368.286305 -284.164005) (xy 368.270595 -284.113075) (xy 368.262652 -284.060371)
			(xy 368.034072 -284.060371) (xy 368.026129 -284.113075) (xy 368.010419 -284.164005) (xy 367.987293 -284.212026)
			(xy 367.957269 -284.256063) (xy 367.921017 -284.295134) (xy 367.879346 -284.328365) (xy 367.833188 -284.355014)
			(xy 367.783574 -284.374486) (xy 367.731612 -284.386346) (xy 367.678462 -284.39033) (xy 367.625312 -284.386346)
			(xy 367.57335 -284.374486) (xy 367.523736 -284.355014) (xy 367.477578 -284.328365) (xy 367.435907 -284.295134)
			(xy 367.399655 -284.256063) (xy 367.369631 -284.212026) (xy 367.346505 -284.164005) (xy 367.330795 -284.113075)
			(xy 367.322852 -284.060371) (xy 367.094272 -284.060371) (xy 367.086329 -284.113075) (xy 367.070619 -284.164005)
			(xy 367.047493 -284.212026) (xy 367.017469 -284.256063) (xy 366.981217 -284.295134) (xy 366.939546 -284.328365)
			(xy 366.893388 -284.355014) (xy 366.843774 -284.374486) (xy 366.791812 -284.386346) (xy 366.738662 -284.39033)
			(xy 366.685512 -284.386346) (xy 366.63355 -284.374486) (xy 366.583936 -284.355014) (xy 366.537778 -284.328365)
			(xy 366.496107 -284.295134) (xy 366.459855 -284.256063) (xy 366.429831 -284.212026) (xy 366.406705 -284.164005)
			(xy 366.390995 -284.113075) (xy 366.383052 -284.060371) (xy 358.636072 -284.060371) (xy 358.628129 -284.113075)
			(xy 358.612419 -284.164005) (xy 358.589293 -284.212026) (xy 358.559269 -284.256063) (xy 358.523017 -284.295134)
			(xy 358.481346 -284.328365) (xy 358.435188 -284.355014) (xy 358.385574 -284.374486) (xy 358.333612 -284.386346)
			(xy 358.280462 -284.39033) (xy 358.227312 -284.386346) (xy 358.17535 -284.374486) (xy 358.125736 -284.355014)
			(xy 358.079578 -284.328365) (xy 358.037907 -284.295134) (xy 358.001655 -284.256063) (xy 357.971631 -284.212026)
			(xy 357.948505 -284.164005) (xy 357.932795 -284.113075) (xy 357.924852 -284.060371) (xy 355.816672 -284.060371)
			(xy 355.808729 -284.113075) (xy 355.793019 -284.164005) (xy 355.769893 -284.212026) (xy 355.739869 -284.256063)
			(xy 355.703617 -284.295134) (xy 355.661946 -284.328365) (xy 355.615788 -284.355014) (xy 355.566174 -284.374486)
			(xy 355.514212 -284.386346) (xy 355.461062 -284.39033) (xy 355.407912 -284.386346) (xy 355.35595 -284.374486)
			(xy 355.306336 -284.355014) (xy 355.260178 -284.328365) (xy 355.218507 -284.295134) (xy 355.182255 -284.256063)
			(xy 355.152231 -284.212026) (xy 355.129105 -284.164005) (xy 355.113395 -284.113075) (xy 355.105452 -284.060371)
			(xy 353.937072 -284.060371) (xy 353.929129 -284.113075) (xy 353.913419 -284.164005) (xy 353.890293 -284.212026)
			(xy 353.860269 -284.256063) (xy 353.824017 -284.295134) (xy 353.782346 -284.328365) (xy 353.736188 -284.355014)
			(xy 353.686574 -284.374486) (xy 353.634612 -284.386346) (xy 353.581462 -284.39033) (xy 353.528312 -284.386346)
			(xy 353.47635 -284.374486) (xy 353.426736 -284.355014) (xy 353.380578 -284.328365) (xy 353.338907 -284.295134)
			(xy 353.302655 -284.256063) (xy 353.272631 -284.212026) (xy 353.249505 -284.164005) (xy 353.233795 -284.113075)
			(xy 353.225852 -284.060371) (xy 353.024694 -284.060371) (xy 353.024694 -284.390084) (xy 353.025279 -284.405746)
			(xy 353.034778 -284.435596) (xy 353.052862 -284.461173) (xy 353.077835 -284.480083) (xy 353.107359 -284.490553)
			(xy 353.122992 -284.491684) (xy 353.149063 -284.492977) (xy 353.200432 -284.502248) (xy 353.249896 -284.51892)
			(xy 353.296395 -284.542638) (xy 353.338933 -284.572891) (xy 353.376597 -284.609032) (xy 353.408579 -284.650285)
			(xy 353.434194 -284.695766) (xy 353.452894 -284.7445) (xy 353.464276 -284.795443) (xy 353.468097 -284.847501)
			(xy 353.466138 -284.874187) (xy 361.214152 -284.874187) (xy 361.214152 -284.820889) (xy 361.222095 -284.768185)
			(xy 361.237805 -284.717255) (xy 361.260931 -284.669234) (xy 361.290955 -284.625197) (xy 361.327207 -284.586126)
			(xy 361.368878 -284.552895) (xy 361.415036 -284.526246) (xy 361.46465 -284.506774) (xy 361.516612 -284.494914)
			(xy 361.569762 -284.490931) (xy 361.622912 -284.494914) (xy 361.674874 -284.506774) (xy 361.724488 -284.526246)
			(xy 361.770646 -284.552895) (xy 361.812317 -284.586126) (xy 361.848569 -284.625197) (xy 361.878593 -284.669234)
			(xy 361.901719 -284.717255) (xy 361.917429 -284.768185) (xy 361.925372 -284.820889) (xy 361.92587 -284.847538)
			(xy 361.925372 -284.874187) (xy 364.033806 -284.874187) (xy 364.033806 -284.820889) (xy 364.041749 -284.768185)
			(xy 364.057459 -284.717255) (xy 364.080585 -284.669234) (xy 364.110609 -284.625197) (xy 364.146861 -284.586126)
			(xy 364.188532 -284.552895) (xy 364.23469 -284.526246) (xy 364.284304 -284.506774) (xy 364.336266 -284.494914)
			(xy 364.389416 -284.490931) (xy 364.442566 -284.494914) (xy 364.494528 -284.506774) (xy 364.544142 -284.526246)
			(xy 364.5903 -284.552895) (xy 364.631971 -284.586126) (xy 364.668223 -284.625197) (xy 364.698247 -284.669234)
			(xy 364.721373 -284.717255) (xy 364.737083 -284.768185) (xy 364.745026 -284.820889) (xy 364.745524 -284.847538)
			(xy 364.745026 -284.874187) (xy 365.913406 -284.874187) (xy 365.913406 -284.820889) (xy 365.921349 -284.768185)
			(xy 365.937059 -284.717255) (xy 365.960185 -284.669234) (xy 365.990209 -284.625197) (xy 366.026461 -284.586126)
			(xy 366.068132 -284.552895) (xy 366.11429 -284.526246) (xy 366.163904 -284.506774) (xy 366.215866 -284.494914)
			(xy 366.269016 -284.490931) (xy 366.322166 -284.494914) (xy 366.374128 -284.506774) (xy 366.423742 -284.526246)
			(xy 366.4699 -284.552895) (xy 366.511571 -284.586126) (xy 366.547823 -284.625197) (xy 366.577847 -284.669234)
			(xy 366.600973 -284.717255) (xy 366.616683 -284.768185) (xy 366.624626 -284.820889) (xy 366.625124 -284.847538)
			(xy 366.879124 -284.847538) (xy 366.879632 -284.821631) (xy 366.887738 -284.770454) (xy 366.90375 -284.721175)
			(xy 366.927273 -284.675008) (xy 366.957729 -284.633089) (xy 366.994367 -284.596451) (xy 367.036286 -284.565995)
			(xy 367.082453 -284.542472) (xy 367.131732 -284.52646) (xy 367.182909 -284.518354) (xy 367.234723 -284.518354)
			(xy 367.2859 -284.52646) (xy 367.335179 -284.542472) (xy 367.381346 -284.565995) (xy 367.423265 -284.596451)
			(xy 367.459903 -284.633089) (xy 367.490359 -284.675008) (xy 367.513882 -284.721175) (xy 367.529894 -284.770454)
			(xy 367.538 -284.821631) (xy 367.538508 -284.847538) (xy 367.537922 -284.874187) (xy 367.793006 -284.874187)
			(xy 367.793006 -284.820889) (xy 367.800949 -284.768185) (xy 367.816659 -284.717255) (xy 367.839785 -284.669234)
			(xy 367.869809 -284.625197) (xy 367.906061 -284.586126) (xy 367.947732 -284.552895) (xy 367.99389 -284.526246)
			(xy 368.043504 -284.506774) (xy 368.095466 -284.494914) (xy 368.148616 -284.490931) (xy 368.201766 -284.494914)
			(xy 368.253728 -284.506774) (xy 368.303342 -284.526246) (xy 368.3495 -284.552895) (xy 368.391171 -284.586126)
			(xy 368.427423 -284.625197) (xy 368.457447 -284.669234) (xy 368.480573 -284.717255) (xy 368.496283 -284.768185)
			(xy 368.504226 -284.820889) (xy 368.504724 -284.847538) (xy 368.758724 -284.847538) (xy 368.759232 -284.821631)
			(xy 368.767338 -284.770454) (xy 368.78335 -284.721175) (xy 368.806873 -284.675008) (xy 368.837329 -284.633089)
			(xy 368.873967 -284.596451) (xy 368.915886 -284.565995) (xy 368.962053 -284.542472) (xy 369.011332 -284.52646)
			(xy 369.062509 -284.518354) (xy 369.114323 -284.518354) (xy 369.1655 -284.52646) (xy 369.214779 -284.542472)
			(xy 369.260946 -284.565995) (xy 369.302865 -284.596451) (xy 369.339503 -284.633089) (xy 369.369959 -284.675008)
			(xy 369.393482 -284.721175) (xy 369.409494 -284.770454) (xy 369.4176 -284.821631) (xy 369.418108 -284.847538)
			(xy 369.417522 -284.874187) (xy 369.672606 -284.874187) (xy 369.672606 -284.820889) (xy 369.680549 -284.768185)
			(xy 369.696259 -284.717255) (xy 369.719385 -284.669234) (xy 369.749409 -284.625197) (xy 369.785661 -284.586126)
			(xy 369.827332 -284.552895) (xy 369.87349 -284.526246) (xy 369.923104 -284.506774) (xy 369.975066 -284.494914)
			(xy 370.028216 -284.490931) (xy 370.081366 -284.494914) (xy 370.133328 -284.506774) (xy 370.182942 -284.526246)
			(xy 370.2291 -284.552895) (xy 370.270771 -284.586126) (xy 370.307023 -284.625197) (xy 370.337047 -284.669234)
			(xy 370.360173 -284.717255) (xy 370.375883 -284.768185) (xy 370.383826 -284.820889) (xy 370.384324 -284.847538)
			(xy 370.638324 -284.847538) (xy 370.638832 -284.821631) (xy 370.646938 -284.770454) (xy 370.66295 -284.721175)
			(xy 370.686473 -284.675008) (xy 370.716929 -284.633089) (xy 370.753567 -284.596451) (xy 370.795486 -284.565995)
			(xy 370.841653 -284.542472) (xy 370.890932 -284.52646) (xy 370.942109 -284.518354) (xy 370.993923 -284.518354)
			(xy 371.0451 -284.52646) (xy 371.094379 -284.542472) (xy 371.140546 -284.565995) (xy 371.182465 -284.596451)
			(xy 371.219103 -284.633089) (xy 371.249559 -284.675008) (xy 371.273082 -284.721175) (xy 371.289094 -284.770454)
			(xy 371.2972 -284.821631) (xy 371.297708 -284.847538) (xy 371.297122 -284.874187) (xy 371.552206 -284.874187)
			(xy 371.552206 -284.820889) (xy 371.560149 -284.768185) (xy 371.575859 -284.717255) (xy 371.598985 -284.669234)
			(xy 371.629009 -284.625197) (xy 371.665261 -284.586126) (xy 371.706932 -284.552895) (xy 371.75309 -284.526246)
			(xy 371.802704 -284.506774) (xy 371.854666 -284.494914) (xy 371.907816 -284.490931) (xy 371.960966 -284.494914)
			(xy 372.012928 -284.506774) (xy 372.062542 -284.526246) (xy 372.1087 -284.552895) (xy 372.150371 -284.586126)
			(xy 372.186623 -284.625197) (xy 372.216647 -284.669234) (xy 372.239773 -284.717255) (xy 372.255483 -284.768185)
			(xy 372.263426 -284.820889) (xy 372.263924 -284.847538) (xy 372.517924 -284.847538) (xy 372.518432 -284.821631)
			(xy 372.526538 -284.770454) (xy 372.54255 -284.721175) (xy 372.566073 -284.675008) (xy 372.596529 -284.633089)
			(xy 372.633167 -284.596451) (xy 372.675086 -284.565995) (xy 372.721253 -284.542472) (xy 372.770532 -284.52646)
			(xy 372.821709 -284.518354) (xy 372.873523 -284.518354) (xy 372.9247 -284.52646) (xy 372.973979 -284.542472)
			(xy 373.020146 -284.565995) (xy 373.062065 -284.596451) (xy 373.098703 -284.633089) (xy 373.129159 -284.675008)
			(xy 373.152682 -284.721175) (xy 373.168694 -284.770454) (xy 373.1768 -284.821631) (xy 373.177308 -284.847538)
			(xy 373.176722 -284.874187) (xy 373.431806 -284.874187) (xy 373.431806 -284.820889) (xy 373.439749 -284.768185)
			(xy 373.455459 -284.717255) (xy 373.478585 -284.669234) (xy 373.508609 -284.625197) (xy 373.544861 -284.586126)
			(xy 373.586532 -284.552895) (xy 373.63269 -284.526246) (xy 373.682304 -284.506774) (xy 373.734266 -284.494914)
			(xy 373.787416 -284.490931) (xy 373.840566 -284.494914) (xy 373.892528 -284.506774) (xy 373.942142 -284.526246)
			(xy 373.9883 -284.552895) (xy 374.029971 -284.586126) (xy 374.066223 -284.625197) (xy 374.096247 -284.669234)
			(xy 374.119373 -284.717255) (xy 374.135083 -284.768185) (xy 374.143026 -284.820889) (xy 374.143524 -284.847538)
			(xy 374.397524 -284.847538) (xy 374.398032 -284.821631) (xy 374.406138 -284.770454) (xy 374.42215 -284.721175)
			(xy 374.445673 -284.675008) (xy 374.476129 -284.633089) (xy 374.512767 -284.596451) (xy 374.554686 -284.565995)
			(xy 374.600853 -284.542472) (xy 374.650132 -284.52646) (xy 374.701309 -284.518354) (xy 374.753123 -284.518354)
			(xy 374.8043 -284.52646) (xy 374.853579 -284.542472) (xy 374.899746 -284.565995) (xy 374.941665 -284.596451)
			(xy 374.978303 -284.633089) (xy 375.008759 -284.675008) (xy 375.032282 -284.721175) (xy 375.048294 -284.770454)
			(xy 375.0564 -284.821631) (xy 375.056908 -284.847538) (xy 375.056322 -284.874187) (xy 375.311406 -284.874187)
			(xy 375.311406 -284.820889) (xy 375.319349 -284.768185) (xy 375.335059 -284.717255) (xy 375.358185 -284.669234)
			(xy 375.388209 -284.625197) (xy 375.424461 -284.586126) (xy 375.466132 -284.552895) (xy 375.51229 -284.526246)
			(xy 375.561904 -284.506774) (xy 375.613866 -284.494914) (xy 375.667016 -284.490931) (xy 375.720166 -284.494914)
			(xy 375.772128 -284.506774) (xy 375.821742 -284.526246) (xy 375.8679 -284.552895) (xy 375.909571 -284.586126)
			(xy 375.945823 -284.625197) (xy 375.975847 -284.669234) (xy 375.998973 -284.717255) (xy 376.014683 -284.768185)
			(xy 376.022626 -284.820889) (xy 376.023124 -284.847538) (xy 376.277124 -284.847538) (xy 376.277632 -284.821631)
			(xy 376.285738 -284.770454) (xy 376.30175 -284.721175) (xy 376.325273 -284.675008) (xy 376.355729 -284.633089)
			(xy 376.392367 -284.596451) (xy 376.434286 -284.565995) (xy 376.480453 -284.542472) (xy 376.529732 -284.52646)
			(xy 376.580909 -284.518354) (xy 376.632723 -284.518354) (xy 376.6839 -284.52646) (xy 376.733179 -284.542472)
			(xy 376.779346 -284.565995) (xy 376.821265 -284.596451) (xy 376.857903 -284.633089) (xy 376.888359 -284.675008)
			(xy 376.911882 -284.721175) (xy 376.927894 -284.770454) (xy 376.936 -284.821631) (xy 376.936508 -284.847538)
			(xy 376.935922 -284.874187) (xy 377.191006 -284.874187) (xy 377.191006 -284.820889) (xy 377.198949 -284.768185)
			(xy 377.214659 -284.717255) (xy 377.237785 -284.669234) (xy 377.267809 -284.625197) (xy 377.304061 -284.586126)
			(xy 377.345732 -284.552895) (xy 377.39189 -284.526246) (xy 377.441504 -284.506774) (xy 377.493466 -284.494914)
			(xy 377.546616 -284.490931) (xy 377.599766 -284.494914) (xy 377.651728 -284.506774) (xy 377.701342 -284.526246)
			(xy 377.7475 -284.552895) (xy 377.789171 -284.586126) (xy 377.825423 -284.625197) (xy 377.855447 -284.669234)
			(xy 377.878573 -284.717255) (xy 377.894283 -284.768185) (xy 377.902226 -284.820889) (xy 377.902724 -284.847538)
			(xy 378.156724 -284.847538) (xy 378.157232 -284.821631) (xy 378.165338 -284.770454) (xy 378.18135 -284.721175)
			(xy 378.204873 -284.675008) (xy 378.235329 -284.633089) (xy 378.271967 -284.596451) (xy 378.313886 -284.565995)
			(xy 378.360053 -284.542472) (xy 378.409332 -284.52646) (xy 378.460509 -284.518354) (xy 378.512323 -284.518354)
			(xy 378.5635 -284.52646) (xy 378.612779 -284.542472) (xy 378.658946 -284.565995) (xy 378.700865 -284.596451)
			(xy 378.737503 -284.633089) (xy 378.767959 -284.675008) (xy 378.791482 -284.721175) (xy 378.807494 -284.770454)
			(xy 378.8156 -284.821631) (xy 378.816108 -284.847538) (xy 378.815522 -284.874187) (xy 379.070606 -284.874187)
			(xy 379.070606 -284.820889) (xy 379.078549 -284.768185) (xy 379.094259 -284.717255) (xy 379.117385 -284.669234)
			(xy 379.147409 -284.625197) (xy 379.183661 -284.586126) (xy 379.225332 -284.552895) (xy 379.27149 -284.526246)
			(xy 379.321104 -284.506774) (xy 379.373066 -284.494914) (xy 379.426216 -284.490931) (xy 379.479366 -284.494914)
			(xy 379.531328 -284.506774) (xy 379.580942 -284.526246) (xy 379.6271 -284.552895) (xy 379.668771 -284.586126)
			(xy 379.705023 -284.625197) (xy 379.735047 -284.669234) (xy 379.758173 -284.717255) (xy 379.773883 -284.768185)
			(xy 379.781826 -284.820889) (xy 379.782324 -284.847538) (xy 380.036324 -284.847538) (xy 380.036832 -284.821631)
			(xy 380.044938 -284.770454) (xy 380.06095 -284.721175) (xy 380.084473 -284.675008) (xy 380.114929 -284.633089)
			(xy 380.151567 -284.596451) (xy 380.193486 -284.565995) (xy 380.239653 -284.542472) (xy 380.288932 -284.52646)
			(xy 380.340109 -284.518354) (xy 380.391923 -284.518354) (xy 380.4431 -284.52646) (xy 380.492379 -284.542472)
			(xy 380.538546 -284.565995) (xy 380.580465 -284.596451) (xy 380.617103 -284.633089) (xy 380.647559 -284.675008)
			(xy 380.671082 -284.721175) (xy 380.687094 -284.770454) (xy 380.6952 -284.821631) (xy 380.695708 -284.847538)
			(xy 380.695122 -284.874187) (xy 380.950206 -284.874187) (xy 380.950206 -284.820889) (xy 380.958149 -284.768185)
			(xy 380.973859 -284.717255) (xy 380.996985 -284.669234) (xy 381.027009 -284.625197) (xy 381.063261 -284.586126)
			(xy 381.104932 -284.552895) (xy 381.15109 -284.526246) (xy 381.200704 -284.506774) (xy 381.252666 -284.494914)
			(xy 381.305816 -284.490931) (xy 381.358966 -284.494914) (xy 381.410928 -284.506774) (xy 381.460542 -284.526246)
			(xy 381.5067 -284.552895) (xy 381.548371 -284.586126) (xy 381.584623 -284.625197) (xy 381.614647 -284.669234)
			(xy 381.637773 -284.717255) (xy 381.653483 -284.768185) (xy 381.661426 -284.820889) (xy 381.661924 -284.847538)
			(xy 381.661426 -284.874187) (xy 381.890006 -284.874187) (xy 381.890006 -284.820889) (xy 381.897949 -284.768185)
			(xy 381.913659 -284.717255) (xy 381.936785 -284.669234) (xy 381.966809 -284.625197) (xy 382.003061 -284.586126)
			(xy 382.044732 -284.552895) (xy 382.09089 -284.526246) (xy 382.140504 -284.506774) (xy 382.192466 -284.494914)
			(xy 382.245616 -284.490931) (xy 382.298766 -284.494914) (xy 382.350728 -284.506774) (xy 382.400342 -284.526246)
			(xy 382.4465 -284.552895) (xy 382.488171 -284.586126) (xy 382.524423 -284.625197) (xy 382.554447 -284.669234)
			(xy 382.577573 -284.717255) (xy 382.593283 -284.768185) (xy 382.601226 -284.820889) (xy 382.601724 -284.847538)
			(xy 382.601231 -284.873933) (xy 382.829552 -284.873933) (xy 382.829552 -284.820635) (xy 382.837495 -284.767931)
			(xy 382.853205 -284.717001) (xy 382.876331 -284.66898) (xy 382.906355 -284.624943) (xy 382.942607 -284.585872)
			(xy 382.984278 -284.552641) (xy 383.030436 -284.525992) (xy 383.08005 -284.50652) (xy 383.132012 -284.49466)
			(xy 383.185162 -284.490677) (xy 383.238312 -284.49466) (xy 383.290274 -284.50652) (xy 383.339888 -284.525992)
			(xy 383.386046 -284.552641) (xy 383.427717 -284.585872) (xy 383.463969 -284.624943) (xy 383.493993 -284.66898)
			(xy 383.517119 -284.717001) (xy 383.532829 -284.767931) (xy 383.540772 -284.820635) (xy 383.54127 -284.847284)
			(xy 383.540772 -284.873933) (xy 383.769352 -284.873933) (xy 383.769352 -284.820635) (xy 383.777295 -284.767931)
			(xy 383.793005 -284.717001) (xy 383.816131 -284.66898) (xy 383.846155 -284.624943) (xy 383.882407 -284.585872)
			(xy 383.924078 -284.552641) (xy 383.970236 -284.525992) (xy 384.01985 -284.50652) (xy 384.071812 -284.49466)
			(xy 384.124962 -284.490677) (xy 384.178112 -284.49466) (xy 384.230074 -284.50652) (xy 384.279688 -284.525992)
			(xy 384.325846 -284.552641) (xy 384.367517 -284.585872) (xy 384.403769 -284.624943) (xy 384.433793 -284.66898)
			(xy 384.456919 -284.717001) (xy 384.472629 -284.767931) (xy 384.480572 -284.820635) (xy 384.48107 -284.847284)
			(xy 384.480572 -284.873933) (xy 384.709152 -284.873933) (xy 384.709152 -284.820635) (xy 384.717095 -284.767931)
			(xy 384.732805 -284.717001) (xy 384.755931 -284.66898) (xy 384.785955 -284.624943) (xy 384.822207 -284.585872)
			(xy 384.863878 -284.552641) (xy 384.910036 -284.525992) (xy 384.95965 -284.50652) (xy 385.011612 -284.49466)
			(xy 385.064762 -284.490677) (xy 385.117912 -284.49466) (xy 385.169874 -284.50652) (xy 385.219488 -284.525992)
			(xy 385.265646 -284.552641) (xy 385.307317 -284.585872) (xy 385.343569 -284.624943) (xy 385.373593 -284.66898)
			(xy 385.396719 -284.717001) (xy 385.412429 -284.767931) (xy 385.420372 -284.820635) (xy 385.42087 -284.847284)
			(xy 385.420372 -284.873933) (xy 385.648952 -284.873933) (xy 385.648952 -284.820635) (xy 385.656895 -284.767931)
			(xy 385.672605 -284.717001) (xy 385.695731 -284.66898) (xy 385.725755 -284.624943) (xy 385.762007 -284.585872)
			(xy 385.803678 -284.552641) (xy 385.849836 -284.525992) (xy 385.89945 -284.50652) (xy 385.951412 -284.49466)
			(xy 386.004562 -284.490677) (xy 386.057712 -284.49466) (xy 386.109674 -284.50652) (xy 386.159288 -284.525992)
			(xy 386.205446 -284.552641) (xy 386.247117 -284.585872) (xy 386.283369 -284.624943) (xy 386.313393 -284.66898)
			(xy 386.336519 -284.717001) (xy 386.352229 -284.767931) (xy 386.360172 -284.820635) (xy 386.36067 -284.847284)
			(xy 386.360172 -284.873933) (xy 386.352229 -284.926637) (xy 386.336519 -284.977567) (xy 386.313393 -285.025588)
			(xy 386.283369 -285.069625) (xy 386.247117 -285.108696) (xy 386.205446 -285.141927) (xy 386.159288 -285.168576)
			(xy 386.109674 -285.188048) (xy 386.057712 -285.199908) (xy 386.004562 -285.203892) (xy 385.951412 -285.199908)
			(xy 385.89945 -285.188048) (xy 385.849836 -285.168576) (xy 385.803678 -285.141927) (xy 385.762007 -285.108696)
			(xy 385.725755 -285.069625) (xy 385.695731 -285.025588) (xy 385.672605 -284.977567) (xy 385.656895 -284.926637)
			(xy 385.648952 -284.873933) (xy 385.420372 -284.873933) (xy 385.412429 -284.926637) (xy 385.396719 -284.977567)
			(xy 385.373593 -285.025588) (xy 385.343569 -285.069625) (xy 385.307317 -285.108696) (xy 385.265646 -285.141927)
			(xy 385.219488 -285.168576) (xy 385.169874 -285.188048) (xy 385.117912 -285.199908) (xy 385.064762 -285.203892)
			(xy 385.011612 -285.199908) (xy 384.95965 -285.188048) (xy 384.910036 -285.168576) (xy 384.863878 -285.141927)
			(xy 384.822207 -285.108696) (xy 384.785955 -285.069625) (xy 384.755931 -285.025588) (xy 384.732805 -284.977567)
			(xy 384.717095 -284.926637) (xy 384.709152 -284.873933) (xy 384.480572 -284.873933) (xy 384.472629 -284.926637)
			(xy 384.456919 -284.977567) (xy 384.433793 -285.025588) (xy 384.403769 -285.069625) (xy 384.367517 -285.108696)
			(xy 384.325846 -285.141927) (xy 384.279688 -285.168576) (xy 384.230074 -285.188048) (xy 384.178112 -285.199908)
			(xy 384.124962 -285.203892) (xy 384.071812 -285.199908) (xy 384.01985 -285.188048) (xy 383.970236 -285.168576)
			(xy 383.924078 -285.141927) (xy 383.882407 -285.108696) (xy 383.846155 -285.069625) (xy 383.816131 -285.025588)
			(xy 383.793005 -284.977567) (xy 383.777295 -284.926637) (xy 383.769352 -284.873933) (xy 383.540772 -284.873933)
			(xy 383.532829 -284.926637) (xy 383.517119 -284.977567) (xy 383.493993 -285.025588) (xy 383.463969 -285.069625)
			(xy 383.427717 -285.108696) (xy 383.386046 -285.141927) (xy 383.339888 -285.168576) (xy 383.290274 -285.188048)
			(xy 383.238312 -285.199908) (xy 383.185162 -285.203892) (xy 383.132012 -285.199908) (xy 383.08005 -285.188048)
			(xy 383.030436 -285.168576) (xy 382.984278 -285.141927) (xy 382.942607 -285.108696) (xy 382.906355 -285.069625)
			(xy 382.876331 -285.025588) (xy 382.853205 -284.977567) (xy 382.837495 -284.926637) (xy 382.829552 -284.873933)
			(xy 382.601231 -284.873933) (xy 382.601226 -284.874187) (xy 382.593283 -284.926891) (xy 382.577573 -284.977821)
			(xy 382.554447 -285.025842) (xy 382.524423 -285.069879) (xy 382.488171 -285.10895) (xy 382.4465 -285.142181)
			(xy 382.400342 -285.16883) (xy 382.350728 -285.188302) (xy 382.298766 -285.200162) (xy 382.245616 -285.204146)
			(xy 382.192466 -285.200162) (xy 382.140504 -285.188302) (xy 382.09089 -285.16883) (xy 382.044732 -285.142181)
			(xy 382.003061 -285.10895) (xy 381.966809 -285.069879) (xy 381.936785 -285.025842) (xy 381.913659 -284.977821)
			(xy 381.897949 -284.926891) (xy 381.890006 -284.874187) (xy 381.661426 -284.874187) (xy 381.653483 -284.926891)
			(xy 381.637773 -284.977821) (xy 381.614647 -285.025842) (xy 381.584623 -285.069879) (xy 381.548371 -285.10895)
			(xy 381.5067 -285.142181) (xy 381.460542 -285.16883) (xy 381.410928 -285.188302) (xy 381.358966 -285.200162)
			(xy 381.305816 -285.204146) (xy 381.252666 -285.200162) (xy 381.200704 -285.188302) (xy 381.15109 -285.16883)
			(xy 381.104932 -285.142181) (xy 381.063261 -285.10895) (xy 381.027009 -285.069879) (xy 380.996985 -285.025842)
			(xy 380.973859 -284.977821) (xy 380.958149 -284.926891) (xy 380.950206 -284.874187) (xy 380.695122 -284.874187)
			(xy 380.695098 -284.875255) (xy 380.685785 -284.929901) (xy 380.677166 -284.95625) (xy 380.669292 -284.978348)
			(xy 380.87427 -285.333186) (xy 380.89713 -285.337504) (xy 380.921947 -285.342634) (xy 380.969689 -285.35963)
			(xy 381.014267 -285.383731) (xy 381.054634 -285.414369) (xy 381.089836 -285.450823) (xy 381.119046 -285.492235)
			(xy 381.141576 -285.537628) (xy 381.156894 -285.585934) (xy 381.16464 -285.636016) (xy 381.1651 -285.661354)
			(xy 381.164592 -285.687241) (xy 381.156493 -285.738379) (xy 381.140494 -285.787619) (xy 381.116988 -285.833751)
			(xy 381.086556 -285.875638) (xy 381.049946 -285.912248) (xy 381.008059 -285.94268) (xy 380.961927 -285.966186)
			(xy 380.912687 -285.982185) (xy 380.861549 -285.990284) (xy 380.809775 -285.990284) (xy 380.758637 -285.982185)
			(xy 380.709397 -285.966186) (xy 380.663265 -285.94268) (xy 380.621378 -285.912248) (xy 380.584768 -285.875638)
			(xy 380.554336 -285.833751) (xy 380.53083 -285.787619) (xy 380.514831 -285.738379) (xy 380.506732 -285.687241)
			(xy 380.506224 -285.661354) (xy 380.506766 -285.633646) (xy 380.515953 -285.579) (xy 380.524512 -285.552642)
			(xy 380.532386 -285.530544) (xy 380.327408 -285.175706) (xy 380.304548 -285.171388) (xy 380.279723 -285.166238)
			(xy 380.231943 -285.149282) (xy 380.187323 -285.125209) (xy 380.146916 -285.094586) (xy 380.111675 -285.058137)
			(xy 380.082431 -285.016721) (xy 380.059876 -284.971315) (xy 380.044539 -284.922991) (xy 380.036785 -284.872888)
			(xy 380.036324 -284.847538) (xy 379.782324 -284.847538) (xy 379.781826 -284.874187) (xy 379.773883 -284.926891)
			(xy 379.758173 -284.977821) (xy 379.735047 -285.025842) (xy 379.705023 -285.069879) (xy 379.668771 -285.10895)
			(xy 379.6271 -285.142181) (xy 379.580942 -285.16883) (xy 379.531328 -285.188302) (xy 379.479366 -285.200162)
			(xy 379.426216 -285.204146) (xy 379.373066 -285.200162) (xy 379.321104 -285.188302) (xy 379.27149 -285.16883)
			(xy 379.225332 -285.142181) (xy 379.183661 -285.10895) (xy 379.147409 -285.069879) (xy 379.117385 -285.025842)
			(xy 379.094259 -284.977821) (xy 379.078549 -284.926891) (xy 379.070606 -284.874187) (xy 378.815522 -284.874187)
			(xy 378.815498 -284.875255) (xy 378.806185 -284.929901) (xy 378.797566 -284.95625) (xy 378.789692 -284.978348)
			(xy 378.99467 -285.333186) (xy 379.01753 -285.337504) (xy 379.042347 -285.342634) (xy 379.090089 -285.35963)
			(xy 379.134667 -285.383731) (xy 379.175034 -285.414369) (xy 379.210236 -285.450823) (xy 379.239446 -285.492235)
			(xy 379.261976 -285.537628) (xy 379.277294 -285.585934) (xy 379.28504 -285.636016) (xy 379.2855 -285.661354)
			(xy 379.284992 -285.687241) (xy 379.276893 -285.738379) (xy 379.260894 -285.787619) (xy 379.237388 -285.833751)
			(xy 379.206956 -285.875638) (xy 379.170346 -285.912248) (xy 379.128459 -285.94268) (xy 379.082327 -285.966186)
			(xy 379.033087 -285.982185) (xy 378.981949 -285.990284) (xy 378.930175 -285.990284) (xy 378.879037 -285.982185)
			(xy 378.829797 -285.966186) (xy 378.783665 -285.94268) (xy 378.741778 -285.912248) (xy 378.705168 -285.875638)
			(xy 378.674736 -285.833751) (xy 378.65123 -285.787619) (xy 378.635231 -285.738379) (xy 378.627132 -285.687241)
			(xy 378.626624 -285.661354) (xy 378.627166 -285.633646) (xy 378.636353 -285.579) (xy 378.644912 -285.552642)
			(xy 378.652786 -285.530544) (xy 378.447808 -285.175706) (xy 378.424948 -285.171388) (xy 378.400123 -285.166238)
			(xy 378.352343 -285.149282) (xy 378.307723 -285.125209) (xy 378.267316 -285.094586) (xy 378.232075 -285.058137)
			(xy 378.202831 -285.016721) (xy 378.180276 -284.971315) (xy 378.164939 -284.922991) (xy 378.157185 -284.872888)
			(xy 378.156724 -284.847538) (xy 377.902724 -284.847538) (xy 377.902226 -284.874187) (xy 377.894283 -284.926891)
			(xy 377.878573 -284.977821) (xy 377.855447 -285.025842) (xy 377.825423 -285.069879) (xy 377.789171 -285.10895)
			(xy 377.7475 -285.142181) (xy 377.701342 -285.16883) (xy 377.651728 -285.188302) (xy 377.599766 -285.200162)
			(xy 377.546616 -285.204146) (xy 377.493466 -285.200162) (xy 377.441504 -285.188302) (xy 377.39189 -285.16883)
			(xy 377.345732 -285.142181) (xy 377.304061 -285.10895) (xy 377.267809 -285.069879) (xy 377.237785 -285.025842)
			(xy 377.214659 -284.977821) (xy 377.198949 -284.926891) (xy 377.191006 -284.874187) (xy 376.935922 -284.874187)
			(xy 376.935898 -284.875255) (xy 376.926585 -284.929901) (xy 376.917966 -284.95625) (xy 376.910092 -284.978348)
			(xy 377.11507 -285.333186) (xy 377.13793 -285.337504) (xy 377.162747 -285.342634) (xy 377.210489 -285.35963)
			(xy 377.255067 -285.383731) (xy 377.295434 -285.414369) (xy 377.330636 -285.450823) (xy 377.359846 -285.492235)
			(xy 377.382376 -285.537628) (xy 377.397694 -285.585934) (xy 377.40544 -285.636016) (xy 377.4059 -285.661354)
			(xy 377.405392 -285.687241) (xy 377.397293 -285.738379) (xy 377.381294 -285.787619) (xy 377.357788 -285.833751)
			(xy 377.327356 -285.875638) (xy 377.290746 -285.912248) (xy 377.248859 -285.94268) (xy 377.202727 -285.966186)
			(xy 377.153487 -285.982185) (xy 377.102349 -285.990284) (xy 377.050575 -285.990284) (xy 376.999437 -285.982185)
			(xy 376.950197 -285.966186) (xy 376.904065 -285.94268) (xy 376.862178 -285.912248) (xy 376.825568 -285.875638)
			(xy 376.795136 -285.833751) (xy 376.77163 -285.787619) (xy 376.755631 -285.738379) (xy 376.747532 -285.687241)
			(xy 376.747024 -285.661354) (xy 376.747566 -285.633646) (xy 376.756753 -285.579) (xy 376.765312 -285.552642)
			(xy 376.773186 -285.530544) (xy 376.568208 -285.175706) (xy 376.545348 -285.171388) (xy 376.520523 -285.166238)
			(xy 376.472743 -285.149282) (xy 376.428123 -285.125209) (xy 376.387716 -285.094586) (xy 376.352475 -285.058137)
			(xy 376.323231 -285.016721) (xy 376.300676 -284.971315) (xy 376.285339 -284.922991) (xy 376.277585 -284.872888)
			(xy 376.277124 -284.847538) (xy 376.023124 -284.847538) (xy 376.022626 -284.874187) (xy 376.014683 -284.926891)
			(xy 375.998973 -284.977821) (xy 375.975847 -285.025842) (xy 375.945823 -285.069879) (xy 375.909571 -285.10895)
			(xy 375.8679 -285.142181) (xy 375.821742 -285.16883) (xy 375.772128 -285.188302) (xy 375.720166 -285.200162)
			(xy 375.667016 -285.204146) (xy 375.613866 -285.200162) (xy 375.561904 -285.188302) (xy 375.51229 -285.16883)
			(xy 375.466132 -285.142181) (xy 375.424461 -285.10895) (xy 375.388209 -285.069879) (xy 375.358185 -285.025842)
			(xy 375.335059 -284.977821) (xy 375.319349 -284.926891) (xy 375.311406 -284.874187) (xy 375.056322 -284.874187)
			(xy 375.056298 -284.875255) (xy 375.046985 -284.929901) (xy 375.038366 -284.95625) (xy 375.030492 -284.978348)
			(xy 375.23547 -285.333186) (xy 375.25833 -285.337504) (xy 375.283147 -285.342634) (xy 375.330889 -285.35963)
			(xy 375.375467 -285.383731) (xy 375.415834 -285.414369) (xy 375.451036 -285.450823) (xy 375.480246 -285.492235)
			(xy 375.502776 -285.537628) (xy 375.518094 -285.585934) (xy 375.52584 -285.636016) (xy 375.5263 -285.661354)
			(xy 375.525792 -285.687241) (xy 375.517693 -285.738379) (xy 375.501694 -285.787619) (xy 375.478188 -285.833751)
			(xy 375.447756 -285.875638) (xy 375.411146 -285.912248) (xy 375.369259 -285.94268) (xy 375.323127 -285.966186)
			(xy 375.273887 -285.982185) (xy 375.222749 -285.990284) (xy 375.170975 -285.990284) (xy 375.119837 -285.982185)
			(xy 375.070597 -285.966186) (xy 375.024465 -285.94268) (xy 374.982578 -285.912248) (xy 374.945968 -285.875638)
			(xy 374.915536 -285.833751) (xy 374.89203 -285.787619) (xy 374.876031 -285.738379) (xy 374.867932 -285.687241)
			(xy 374.867424 -285.661354) (xy 374.867966 -285.633646) (xy 374.877153 -285.579) (xy 374.885712 -285.552642)
			(xy 374.893586 -285.530544) (xy 374.688608 -285.175706) (xy 374.665748 -285.171388) (xy 374.640923 -285.166238)
			(xy 374.593143 -285.149282) (xy 374.548523 -285.125209) (xy 374.508116 -285.094586) (xy 374.472875 -285.058137)
			(xy 374.443631 -285.016721) (xy 374.421076 -284.971315) (xy 374.405739 -284.922991) (xy 374.397985 -284.872888)
			(xy 374.397524 -284.847538) (xy 374.143524 -284.847538) (xy 374.143026 -284.874187) (xy 374.135083 -284.926891)
			(xy 374.119373 -284.977821) (xy 374.096247 -285.025842) (xy 374.066223 -285.069879) (xy 374.029971 -285.10895)
			(xy 373.9883 -285.142181) (xy 373.942142 -285.16883) (xy 373.892528 -285.188302) (xy 373.840566 -285.200162)
			(xy 373.787416 -285.204146) (xy 373.734266 -285.200162) (xy 373.682304 -285.188302) (xy 373.63269 -285.16883)
			(xy 373.586532 -285.142181) (xy 373.544861 -285.10895) (xy 373.508609 -285.069879) (xy 373.478585 -285.025842)
			(xy 373.455459 -284.977821) (xy 373.439749 -284.926891) (xy 373.431806 -284.874187) (xy 373.176722 -284.874187)
			(xy 373.176698 -284.875255) (xy 373.167385 -284.929901) (xy 373.158766 -284.95625) (xy 373.150892 -284.978348)
			(xy 373.35587 -285.333186) (xy 373.37873 -285.337504) (xy 373.403547 -285.342634) (xy 373.451289 -285.35963)
			(xy 373.495867 -285.383731) (xy 373.536234 -285.414369) (xy 373.571436 -285.450823) (xy 373.600646 -285.492235)
			(xy 373.623176 -285.537628) (xy 373.638494 -285.585934) (xy 373.64624 -285.636016) (xy 373.6467 -285.661354)
			(xy 373.646192 -285.687241) (xy 373.638093 -285.738379) (xy 373.622094 -285.787619) (xy 373.598588 -285.833751)
			(xy 373.568156 -285.875638) (xy 373.531546 -285.912248) (xy 373.489659 -285.94268) (xy 373.443527 -285.966186)
			(xy 373.394287 -285.982185) (xy 373.343149 -285.990284) (xy 373.291375 -285.990284) (xy 373.240237 -285.982185)
			(xy 373.190997 -285.966186) (xy 373.144865 -285.94268) (xy 373.102978 -285.912248) (xy 373.066368 -285.875638)
			(xy 373.035936 -285.833751) (xy 373.01243 -285.787619) (xy 372.996431 -285.738379) (xy 372.988332 -285.687241)
			(xy 372.987824 -285.661354) (xy 372.988366 -285.633646) (xy 372.997553 -285.579) (xy 373.006112 -285.552642)
			(xy 373.013986 -285.530544) (xy 372.809008 -285.175706) (xy 372.786148 -285.171388) (xy 372.761323 -285.166238)
			(xy 372.713543 -285.149282) (xy 372.668923 -285.125209) (xy 372.628516 -285.094586) (xy 372.593275 -285.058137)
			(xy 372.564031 -285.016721) (xy 372.541476 -284.971315) (xy 372.526139 -284.922991) (xy 372.518385 -284.872888)
			(xy 372.517924 -284.847538) (xy 372.263924 -284.847538) (xy 372.263426 -284.874187) (xy 372.255483 -284.926891)
			(xy 372.239773 -284.977821) (xy 372.216647 -285.025842) (xy 372.186623 -285.069879) (xy 372.150371 -285.10895)
			(xy 372.1087 -285.142181) (xy 372.062542 -285.16883) (xy 372.012928 -285.188302) (xy 371.960966 -285.200162)
			(xy 371.907816 -285.204146) (xy 371.854666 -285.200162) (xy 371.802704 -285.188302) (xy 371.75309 -285.16883)
			(xy 371.706932 -285.142181) (xy 371.665261 -285.10895) (xy 371.629009 -285.069879) (xy 371.598985 -285.025842)
			(xy 371.575859 -284.977821) (xy 371.560149 -284.926891) (xy 371.552206 -284.874187) (xy 371.297122 -284.874187)
			(xy 371.297098 -284.875255) (xy 371.287785 -284.929901) (xy 371.279166 -284.95625) (xy 371.271292 -284.978348)
			(xy 371.47627 -285.333186) (xy 371.49913 -285.337504) (xy 371.523947 -285.342634) (xy 371.571689 -285.35963)
			(xy 371.616267 -285.383731) (xy 371.656634 -285.414369) (xy 371.691836 -285.450823) (xy 371.721046 -285.492235)
			(xy 371.743576 -285.537628) (xy 371.758894 -285.585934) (xy 371.76664 -285.636016) (xy 371.7671 -285.661354)
			(xy 371.766592 -285.687241) (xy 371.758493 -285.738379) (xy 371.742494 -285.787619) (xy 371.718988 -285.833751)
			(xy 371.688556 -285.875638) (xy 371.651946 -285.912248) (xy 371.610059 -285.94268) (xy 371.563927 -285.966186)
			(xy 371.514687 -285.982185) (xy 371.463549 -285.990284) (xy 371.411775 -285.990284) (xy 371.360637 -285.982185)
			(xy 371.311397 -285.966186) (xy 371.265265 -285.94268) (xy 371.223378 -285.912248) (xy 371.186768 -285.875638)
			(xy 371.156336 -285.833751) (xy 371.13283 -285.787619) (xy 371.116831 -285.738379) (xy 371.108732 -285.687241)
			(xy 371.108224 -285.661354) (xy 371.108766 -285.633646) (xy 371.117953 -285.579) (xy 371.126512 -285.552642)
			(xy 371.134386 -285.530544) (xy 370.929408 -285.175706) (xy 370.906548 -285.171388) (xy 370.881723 -285.166238)
			(xy 370.833943 -285.149282) (xy 370.789323 -285.125209) (xy 370.748916 -285.094586) (xy 370.713675 -285.058137)
			(xy 370.684431 -285.016721) (xy 370.661876 -284.971315) (xy 370.646539 -284.922991) (xy 370.638785 -284.872888)
			(xy 370.638324 -284.847538) (xy 370.384324 -284.847538) (xy 370.383826 -284.874187) (xy 370.375883 -284.926891)
			(xy 370.360173 -284.977821) (xy 370.337047 -285.025842) (xy 370.307023 -285.069879) (xy 370.270771 -285.10895)
			(xy 370.2291 -285.142181) (xy 370.182942 -285.16883) (xy 370.133328 -285.188302) (xy 370.081366 -285.200162)
			(xy 370.028216 -285.204146) (xy 369.975066 -285.200162) (xy 369.923104 -285.188302) (xy 369.87349 -285.16883)
			(xy 369.827332 -285.142181) (xy 369.785661 -285.10895) (xy 369.749409 -285.069879) (xy 369.719385 -285.025842)
			(xy 369.696259 -284.977821) (xy 369.680549 -284.926891) (xy 369.672606 -284.874187) (xy 369.417522 -284.874187)
			(xy 369.417498 -284.875255) (xy 369.408185 -284.929901) (xy 369.399566 -284.95625) (xy 369.391692 -284.978348)
			(xy 369.59667 -285.333186) (xy 369.61953 -285.337504) (xy 369.644347 -285.342634) (xy 369.692089 -285.35963)
			(xy 369.736667 -285.383731) (xy 369.777034 -285.414369) (xy 369.812236 -285.450823) (xy 369.841446 -285.492235)
			(xy 369.863976 -285.537628) (xy 369.879294 -285.585934) (xy 369.88704 -285.636016) (xy 369.8875 -285.661354)
			(xy 369.886992 -285.687241) (xy 369.878893 -285.738379) (xy 369.862894 -285.787619) (xy 369.839388 -285.833751)
			(xy 369.808956 -285.875638) (xy 369.772346 -285.912248) (xy 369.730459 -285.94268) (xy 369.684327 -285.966186)
			(xy 369.635087 -285.982185) (xy 369.583949 -285.990284) (xy 369.532175 -285.990284) (xy 369.481037 -285.982185)
			(xy 369.431797 -285.966186) (xy 369.385665 -285.94268) (xy 369.343778 -285.912248) (xy 369.307168 -285.875638)
			(xy 369.276736 -285.833751) (xy 369.25323 -285.787619) (xy 369.237231 -285.738379) (xy 369.229132 -285.687241)
			(xy 369.228624 -285.661354) (xy 369.229166 -285.633646) (xy 369.238353 -285.579) (xy 369.246912 -285.552642)
			(xy 369.254786 -285.530544) (xy 369.049808 -285.175706) (xy 369.026948 -285.171388) (xy 369.002123 -285.166238)
			(xy 368.954343 -285.149282) (xy 368.909723 -285.125209) (xy 368.869316 -285.094586) (xy 368.834075 -285.058137)
			(xy 368.804831 -285.016721) (xy 368.782276 -284.971315) (xy 368.766939 -284.922991) (xy 368.759185 -284.872888)
			(xy 368.758724 -284.847538) (xy 368.504724 -284.847538) (xy 368.504226 -284.874187) (xy 368.496283 -284.926891)
			(xy 368.480573 -284.977821) (xy 368.457447 -285.025842) (xy 368.427423 -285.069879) (xy 368.391171 -285.10895)
			(xy 368.3495 -285.142181) (xy 368.303342 -285.16883) (xy 368.253728 -285.188302) (xy 368.201766 -285.200162)
			(xy 368.148616 -285.204146) (xy 368.095466 -285.200162) (xy 368.043504 -285.188302) (xy 367.99389 -285.16883)
			(xy 367.947732 -285.142181) (xy 367.906061 -285.10895) (xy 367.869809 -285.069879) (xy 367.839785 -285.025842)
			(xy 367.816659 -284.977821) (xy 367.800949 -284.926891) (xy 367.793006 -284.874187) (xy 367.537922 -284.874187)
			(xy 367.537898 -284.875255) (xy 367.528585 -284.929901) (xy 367.519966 -284.95625) (xy 367.512092 -284.978348)
			(xy 367.71707 -285.333186) (xy 367.73993 -285.337504) (xy 367.764747 -285.342634) (xy 367.812489 -285.35963)
			(xy 367.857067 -285.383731) (xy 367.897434 -285.414369) (xy 367.932636 -285.450823) (xy 367.961846 -285.492235)
			(xy 367.984376 -285.537628) (xy 367.999694 -285.585934) (xy 368.00744 -285.636016) (xy 368.0079 -285.661354)
			(xy 368.007392 -285.687241) (xy 367.999293 -285.738379) (xy 367.983294 -285.787619) (xy 367.959788 -285.833751)
			(xy 367.929356 -285.875638) (xy 367.892746 -285.912248) (xy 367.850859 -285.94268) (xy 367.804727 -285.966186)
			(xy 367.755487 -285.982185) (xy 367.704349 -285.990284) (xy 367.652575 -285.990284) (xy 367.601437 -285.982185)
			(xy 367.552197 -285.966186) (xy 367.506065 -285.94268) (xy 367.464178 -285.912248) (xy 367.427568 -285.875638)
			(xy 367.397136 -285.833751) (xy 367.37363 -285.787619) (xy 367.357631 -285.738379) (xy 367.349532 -285.687241)
			(xy 367.349024 -285.661354) (xy 367.349566 -285.633646) (xy 367.358753 -285.579) (xy 367.367312 -285.552642)
			(xy 367.375186 -285.530544) (xy 367.170208 -285.175706) (xy 367.147348 -285.171388) (xy 367.122523 -285.166238)
			(xy 367.074743 -285.149282) (xy 367.030123 -285.125209) (xy 366.989716 -285.094586) (xy 366.954475 -285.058137)
			(xy 366.925231 -285.016721) (xy 366.902676 -284.971315) (xy 366.887339 -284.922991) (xy 366.879585 -284.872888)
			(xy 366.879124 -284.847538) (xy 366.625124 -284.847538) (xy 366.624626 -284.874187) (xy 366.616683 -284.926891)
			(xy 366.600973 -284.977821) (xy 366.577847 -285.025842) (xy 366.547823 -285.069879) (xy 366.511571 -285.10895)
			(xy 366.4699 -285.142181) (xy 366.423742 -285.16883) (xy 366.374128 -285.188302) (xy 366.322166 -285.200162)
			(xy 366.269016 -285.204146) (xy 366.215866 -285.200162) (xy 366.163904 -285.188302) (xy 366.11429 -285.16883)
			(xy 366.068132 -285.142181) (xy 366.026461 -285.10895) (xy 365.990209 -285.069879) (xy 365.960185 -285.025842)
			(xy 365.937059 -284.977821) (xy 365.921349 -284.926891) (xy 365.913406 -284.874187) (xy 364.745026 -284.874187)
			(xy 364.737083 -284.926891) (xy 364.721373 -284.977821) (xy 364.698247 -285.025842) (xy 364.668223 -285.069879)
			(xy 364.631971 -285.10895) (xy 364.5903 -285.142181) (xy 364.544142 -285.16883) (xy 364.494528 -285.188302)
			(xy 364.442566 -285.200162) (xy 364.389416 -285.204146) (xy 364.336266 -285.200162) (xy 364.284304 -285.188302)
			(xy 364.23469 -285.16883) (xy 364.188532 -285.142181) (xy 364.146861 -285.10895) (xy 364.110609 -285.069879)
			(xy 364.080585 -285.025842) (xy 364.057459 -284.977821) (xy 364.041749 -284.926891) (xy 364.033806 -284.874187)
			(xy 361.925372 -284.874187) (xy 361.917429 -284.926891) (xy 361.901719 -284.977821) (xy 361.878593 -285.025842)
			(xy 361.848569 -285.069879) (xy 361.812317 -285.10895) (xy 361.770646 -285.142181) (xy 361.724488 -285.16883)
			(xy 361.674874 -285.188302) (xy 361.622912 -285.200162) (xy 361.569762 -285.204146) (xy 361.516612 -285.200162)
			(xy 361.46465 -285.188302) (xy 361.415036 -285.16883) (xy 361.368878 -285.142181) (xy 361.327207 -285.10895)
			(xy 361.290955 -285.069879) (xy 361.260931 -285.025842) (xy 361.237805 -284.977821) (xy 361.222095 -284.926891)
			(xy 361.214152 -284.874187) (xy 353.466138 -284.874187) (xy 353.464276 -284.89956) (xy 353.452893 -284.950502)
			(xy 353.434193 -284.999236) (xy 353.408578 -285.044717) (xy 353.376595 -285.08597) (xy 353.338931 -285.122111)
			(xy 353.296393 -285.152363) (xy 353.249894 -285.17608) (xy 353.20043 -285.192753) (xy 353.149061 -285.202024)
			(xy 353.122992 -285.203392) (xy 353.107352 -285.204477) (xy 353.077816 -285.214938) (xy 353.052838 -285.233857)
			(xy 353.034766 -285.259455) (xy 353.025299 -285.289324) (xy 353.024694 -285.304992) (xy 353.024694 -285.688003)
			(xy 355.105452 -285.688003) (xy 355.105452 -285.634705) (xy 355.113395 -285.582001) (xy 355.129105 -285.531071)
			(xy 355.152231 -285.48305) (xy 355.182255 -285.439013) (xy 355.218507 -285.399942) (xy 355.260178 -285.366711)
			(xy 355.306336 -285.340062) (xy 355.35595 -285.32059) (xy 355.407912 -285.30873) (xy 355.461062 -285.304747)
			(xy 355.514212 -285.30873) (xy 355.566174 -285.32059) (xy 355.615788 -285.340062) (xy 355.661946 -285.366711)
			(xy 355.703617 -285.399942) (xy 355.739869 -285.439013) (xy 355.769893 -285.48305) (xy 355.793019 -285.531071)
			(xy 355.808729 -285.582001) (xy 355.816672 -285.634705) (xy 355.81717 -285.661354) (xy 355.816672 -285.688003)
			(xy 357.924852 -285.688003) (xy 357.924852 -285.634705) (xy 357.932795 -285.582001) (xy 357.948505 -285.531071)
			(xy 357.971631 -285.48305) (xy 358.001655 -285.439013) (xy 358.037907 -285.399942) (xy 358.079578 -285.366711)
			(xy 358.125736 -285.340062) (xy 358.17535 -285.32059) (xy 358.227312 -285.30873) (xy 358.280462 -285.304747)
			(xy 358.333612 -285.30873) (xy 358.385574 -285.32059) (xy 358.435188 -285.340062) (xy 358.481346 -285.366711)
			(xy 358.523017 -285.399942) (xy 358.559269 -285.439013) (xy 358.589293 -285.48305) (xy 358.612419 -285.531071)
			(xy 358.628129 -285.582001) (xy 358.636072 -285.634705) (xy 358.63657 -285.661354) (xy 358.636072 -285.688003)
			(xy 366.383306 -285.688003) (xy 366.383306 -285.634705) (xy 366.391249 -285.582001) (xy 366.406959 -285.531071)
			(xy 366.430085 -285.48305) (xy 366.460109 -285.439013) (xy 366.496361 -285.399942) (xy 366.538032 -285.366711)
			(xy 366.58419 -285.340062) (xy 366.633804 -285.32059) (xy 366.685766 -285.30873) (xy 366.738916 -285.304747)
			(xy 366.792066 -285.30873) (xy 366.844028 -285.32059) (xy 366.893642 -285.340062) (xy 366.9398 -285.366711)
			(xy 366.981471 -285.399942) (xy 367.017723 -285.439013) (xy 367.047747 -285.48305) (xy 367.070873 -285.531071)
			(xy 367.086583 -285.582001) (xy 367.094526 -285.634705) (xy 367.095024 -285.661354) (xy 367.094526 -285.688003)
			(xy 367.086583 -285.740707) (xy 367.070873 -285.791637) (xy 367.047747 -285.839658) (xy 367.017723 -285.883695)
			(xy 366.981471 -285.922766) (xy 366.9398 -285.955997) (xy 366.893642 -285.982646) (xy 366.844028 -286.002118)
			(xy 366.792066 -286.013978) (xy 366.738916 -286.017962) (xy 366.685766 -286.013978) (xy 366.633804 -286.002118)
			(xy 366.58419 -285.982646) (xy 366.538032 -285.955997) (xy 366.496361 -285.922766) (xy 366.460109 -285.883695)
			(xy 366.430085 -285.839658) (xy 366.406959 -285.791637) (xy 366.391249 -285.740707) (xy 366.383306 -285.688003)
			(xy 358.636072 -285.688003) (xy 358.628129 -285.740707) (xy 358.612419 -285.791637) (xy 358.589293 -285.839658)
			(xy 358.559269 -285.883695) (xy 358.523017 -285.922766) (xy 358.481346 -285.955997) (xy 358.435188 -285.982646)
			(xy 358.385574 -286.002118) (xy 358.333612 -286.013978) (xy 358.280462 -286.017962) (xy 358.227312 -286.013978)
			(xy 358.17535 -286.002118) (xy 358.125736 -285.982646) (xy 358.079578 -285.955997) (xy 358.037907 -285.922766)
			(xy 358.001655 -285.883695) (xy 357.971631 -285.839658) (xy 357.948505 -285.791637) (xy 357.932795 -285.740707)
			(xy 357.924852 -285.688003) (xy 355.816672 -285.688003) (xy 355.808729 -285.740707) (xy 355.793019 -285.791637)
			(xy 355.769893 -285.839658) (xy 355.739869 -285.883695) (xy 355.703617 -285.922766) (xy 355.661946 -285.955997)
			(xy 355.615788 -285.982646) (xy 355.566174 -286.002118) (xy 355.514212 -286.013978) (xy 355.461062 -286.017962)
			(xy 355.407912 -286.013978) (xy 355.35595 -286.002118) (xy 355.306336 -285.982646) (xy 355.260178 -285.955997)
			(xy 355.218507 -285.922766) (xy 355.182255 -285.883695) (xy 355.152231 -285.839658) (xy 355.129105 -285.791637)
			(xy 355.113395 -285.740707) (xy 355.105452 -285.688003) (xy 353.024694 -285.688003) (xy 353.024694 -285.73857)
			(xy 353.025103 -285.751723) (xy 353.03182 -285.777156) (xy 353.044816 -285.800028) (xy 353.063226 -285.818817)
			(xy 353.085828 -285.832276) (xy 353.11112 -285.839509) (xy 353.124262 -285.84017) (xy 353.159465 -285.841315)
			(xy 353.229309 -285.850436) (xy 353.297715 -285.867229) (xy 353.363842 -285.891487) (xy 353.42688 -285.922913)
			(xy 353.486054 -285.96112) (xy 353.540637 -286.00564) (xy 353.589959 -286.055926) (xy 353.633415 -286.11136)
			(xy 353.670471 -286.171262) (xy 353.700671 -286.234896) (xy 353.723646 -286.301481) (xy 353.739112 -286.370198)
			(xy 353.746881 -286.440205) (xy 353.747324 -286.475424) (xy 353.747324 -286.502073) (xy 361.214152 -286.502073)
			(xy 361.214152 -286.448775) (xy 361.222095 -286.396071) (xy 361.237805 -286.345141) (xy 361.260931 -286.29712)
			(xy 361.290955 -286.253083) (xy 361.327207 -286.214012) (xy 361.368878 -286.180781) (xy 361.415036 -286.154132)
			(xy 361.46465 -286.13466) (xy 361.516612 -286.1228) (xy 361.569762 -286.118817) (xy 361.622912 -286.1228)
			(xy 361.674874 -286.13466) (xy 361.724488 -286.154132) (xy 361.770646 -286.180781) (xy 361.812317 -286.214012)
			(xy 361.848569 -286.253083) (xy 361.878593 -286.29712) (xy 361.901719 -286.345141) (xy 361.917429 -286.396071)
			(xy 361.925372 -286.448775) (xy 361.92587 -286.475424) (xy 361.925372 -286.502073) (xy 364.033806 -286.502073)
			(xy 364.033806 -286.448775) (xy 364.041749 -286.396071) (xy 364.057459 -286.345141) (xy 364.080585 -286.29712)
			(xy 364.110609 -286.253083) (xy 364.146861 -286.214012) (xy 364.188532 -286.180781) (xy 364.23469 -286.154132)
			(xy 364.284304 -286.13466) (xy 364.336266 -286.1228) (xy 364.389416 -286.118817) (xy 364.442566 -286.1228)
			(xy 364.494528 -286.13466) (xy 364.544142 -286.154132) (xy 364.5903 -286.180781) (xy 364.631971 -286.214012)
			(xy 364.668223 -286.253083) (xy 364.698247 -286.29712) (xy 364.721373 -286.345141) (xy 364.737083 -286.396071)
			(xy 364.745026 -286.448775) (xy 364.745524 -286.475424) (xy 364.745026 -286.502073) (xy 366.853206 -286.502073)
			(xy 366.853206 -286.448775) (xy 366.861149 -286.396071) (xy 366.876859 -286.345141) (xy 366.899985 -286.29712)
			(xy 366.930009 -286.253083) (xy 366.966261 -286.214012) (xy 367.007932 -286.180781) (xy 367.05409 -286.154132)
			(xy 367.103704 -286.13466) (xy 367.155666 -286.1228) (xy 367.208816 -286.118817) (xy 367.261966 -286.1228)
			(xy 367.313928 -286.13466) (xy 367.363542 -286.154132) (xy 367.4097 -286.180781) (xy 367.451371 -286.214012)
			(xy 367.487623 -286.253083) (xy 367.517647 -286.29712) (xy 367.540773 -286.345141) (xy 367.556483 -286.396071)
			(xy 367.564426 -286.448775) (xy 367.564924 -286.475424) (xy 367.818924 -286.475424) (xy 367.819448 -286.45008)
			(xy 367.827216 -286.399991) (xy 367.842559 -286.351681) (xy 367.865115 -286.306288) (xy 367.894351 -286.264882)
			(xy 367.92958 -286.228438) (xy 367.969972 -286.197814) (xy 368.014574 -286.173733) (xy 368.062336 -286.156761)
			(xy 368.087148 -286.151574) (xy 368.110008 -286.147256) (xy 368.314986 -285.792164) (xy 368.307112 -285.77032)
			(xy 368.298538 -285.7439) (xy 368.289338 -285.689126) (xy 368.288824 -285.661354) (xy 368.289332 -285.635467)
			(xy 368.297431 -285.584329) (xy 368.31343 -285.535089) (xy 368.336936 -285.488957) (xy 368.367368 -285.44707)
			(xy 368.403978 -285.41046) (xy 368.445865 -285.380028) (xy 368.491997 -285.356522) (xy 368.541237 -285.340523)
			(xy 368.592375 -285.332424) (xy 368.644149 -285.332424) (xy 368.695287 -285.340523) (xy 368.744527 -285.356522)
			(xy 368.790659 -285.380028) (xy 368.832546 -285.41046) (xy 368.869156 -285.44707) (xy 368.899588 -285.488957)
			(xy 368.923094 -285.535089) (xy 368.939093 -285.584329) (xy 368.947192 -285.635467) (xy 368.9477 -285.661354)
			(xy 368.947266 -285.68669) (xy 368.939506 -285.736765) (xy 368.924176 -285.785062) (xy 368.901638 -285.830446)
			(xy 368.872422 -285.871848) (xy 368.837216 -285.908293) (xy 368.796849 -285.938922) (xy 368.752271 -285.963016)
			(xy 368.704531 -285.980006) (xy 368.67973 -285.985204) (xy 368.65687 -285.989522) (xy 368.451892 -286.344614)
			(xy 368.459766 -286.366458) (xy 368.468419 -286.392864) (xy 368.477734 -286.447642) (xy 368.478308 -286.475424)
			(xy 368.4778 -286.501331) (xy 368.477682 -286.502073) (xy 368.732552 -286.502073) (xy 368.732552 -286.448775)
			(xy 368.740495 -286.396071) (xy 368.756205 -286.345141) (xy 368.779331 -286.29712) (xy 368.809355 -286.253083)
			(xy 368.845607 -286.214012) (xy 368.887278 -286.180781) (xy 368.933436 -286.154132) (xy 368.98305 -286.13466)
			(xy 369.035012 -286.1228) (xy 369.088162 -286.118817) (xy 369.141312 -286.1228) (xy 369.193274 -286.13466)
			(xy 369.242888 -286.154132) (xy 369.289046 -286.180781) (xy 369.330717 -286.214012) (xy 369.366969 -286.253083)
			(xy 369.396993 -286.29712) (xy 369.420119 -286.345141) (xy 369.435829 -286.396071) (xy 369.443772 -286.448775)
			(xy 369.44427 -286.475424) (xy 369.698524 -286.475424) (xy 369.699048 -286.45008) (xy 369.706816 -286.399991)
			(xy 369.722159 -286.351681) (xy 369.744715 -286.306288) (xy 369.773951 -286.264882) (xy 369.80918 -286.228438)
			(xy 369.849572 -286.197814) (xy 369.894174 -286.173733) (xy 369.941936 -286.156761) (xy 369.966748 -286.151574)
			(xy 369.989608 -286.147256) (xy 370.194586 -285.792164) (xy 370.186712 -285.77032) (xy 370.178138 -285.7439)
			(xy 370.168938 -285.689126) (xy 370.168424 -285.661354) (xy 370.168932 -285.635467) (xy 370.177031 -285.584329)
			(xy 370.19303 -285.535089) (xy 370.216536 -285.488957) (xy 370.246968 -285.44707) (xy 370.283578 -285.41046)
			(xy 370.325465 -285.380028) (xy 370.371597 -285.356522) (xy 370.420837 -285.340523) (xy 370.471975 -285.332424)
			(xy 370.523749 -285.332424) (xy 370.574887 -285.340523) (xy 370.624127 -285.356522) (xy 370.670259 -285.380028)
			(xy 370.712146 -285.41046) (xy 370.748756 -285.44707) (xy 370.779188 -285.488957) (xy 370.802694 -285.535089)
			(xy 370.818693 -285.584329) (xy 370.826792 -285.635467) (xy 370.8273 -285.661354) (xy 370.826866 -285.68669)
			(xy 370.819106 -285.736765) (xy 370.803776 -285.785062) (xy 370.781238 -285.830446) (xy 370.752022 -285.871848)
			(xy 370.716816 -285.908293) (xy 370.676449 -285.938922) (xy 370.631871 -285.963016) (xy 370.584131 -285.980006)
			(xy 370.55933 -285.985204) (xy 370.53647 -285.989522) (xy 370.331492 -286.344614) (xy 370.339366 -286.366458)
			(xy 370.348019 -286.392864) (xy 370.357334 -286.447642) (xy 370.357908 -286.475424) (xy 370.3574 -286.501331)
			(xy 370.357282 -286.502073) (xy 370.612152 -286.502073) (xy 370.612152 -286.448775) (xy 370.620095 -286.396071)
			(xy 370.635805 -286.345141) (xy 370.658931 -286.29712) (xy 370.688955 -286.253083) (xy 370.725207 -286.214012)
			(xy 370.766878 -286.180781) (xy 370.813036 -286.154132) (xy 370.86265 -286.13466) (xy 370.914612 -286.1228)
			(xy 370.967762 -286.118817) (xy 371.020912 -286.1228) (xy 371.072874 -286.13466) (xy 371.122488 -286.154132)
			(xy 371.168646 -286.180781) (xy 371.210317 -286.214012) (xy 371.246569 -286.253083) (xy 371.276593 -286.29712)
			(xy 371.299719 -286.345141) (xy 371.315429 -286.396071) (xy 371.323372 -286.448775) (xy 371.32387 -286.475424)
			(xy 371.578124 -286.475424) (xy 371.578648 -286.45008) (xy 371.586416 -286.399991) (xy 371.601759 -286.351681)
			(xy 371.624315 -286.306288) (xy 371.653551 -286.264882) (xy 371.68878 -286.228438) (xy 371.729172 -286.197814)
			(xy 371.773774 -286.173733) (xy 371.821536 -286.156761) (xy 371.846348 -286.151574) (xy 371.869208 -286.147256)
			(xy 372.074186 -285.792164) (xy 372.066312 -285.77032) (xy 372.057738 -285.7439) (xy 372.048538 -285.689126)
			(xy 372.048024 -285.661354) (xy 372.048532 -285.635467) (xy 372.056631 -285.584329) (xy 372.07263 -285.535089)
			(xy 372.096136 -285.488957) (xy 372.126568 -285.44707) (xy 372.163178 -285.41046) (xy 372.205065 -285.380028)
			(xy 372.251197 -285.356522) (xy 372.300437 -285.340523) (xy 372.351575 -285.332424) (xy 372.403349 -285.332424)
			(xy 372.454487 -285.340523) (xy 372.503727 -285.356522) (xy 372.549859 -285.380028) (xy 372.591746 -285.41046)
			(xy 372.628356 -285.44707) (xy 372.658788 -285.488957) (xy 372.682294 -285.535089) (xy 372.698293 -285.584329)
			(xy 372.706392 -285.635467) (xy 372.7069 -285.661354) (xy 372.706466 -285.68669) (xy 372.698706 -285.736765)
			(xy 372.683376 -285.785062) (xy 372.660838 -285.830446) (xy 372.631622 -285.871848) (xy 372.596416 -285.908293)
			(xy 372.556049 -285.938922) (xy 372.511471 -285.963016) (xy 372.463731 -285.980006) (xy 372.43893 -285.985204)
			(xy 372.41607 -285.989522) (xy 372.211092 -286.344614) (xy 372.218966 -286.366458) (xy 372.227619 -286.392864)
			(xy 372.236934 -286.447642) (xy 372.237508 -286.475424) (xy 372.237 -286.501331) (xy 372.236882 -286.502073)
			(xy 372.491752 -286.502073) (xy 372.491752 -286.448775) (xy 372.499695 -286.396071) (xy 372.515405 -286.345141)
			(xy 372.538531 -286.29712) (xy 372.568555 -286.253083) (xy 372.604807 -286.214012) (xy 372.646478 -286.180781)
			(xy 372.692636 -286.154132) (xy 372.74225 -286.13466) (xy 372.794212 -286.1228) (xy 372.847362 -286.118817)
			(xy 372.900512 -286.1228) (xy 372.952474 -286.13466) (xy 373.002088 -286.154132) (xy 373.048246 -286.180781)
			(xy 373.089917 -286.214012) (xy 373.126169 -286.253083) (xy 373.156193 -286.29712) (xy 373.179319 -286.345141)
			(xy 373.195029 -286.396071) (xy 373.202972 -286.448775) (xy 373.20347 -286.475424) (xy 373.457724 -286.475424)
			(xy 373.458248 -286.45008) (xy 373.466016 -286.399991) (xy 373.481359 -286.351681) (xy 373.503915 -286.306288)
			(xy 373.533151 -286.264882) (xy 373.56838 -286.228438) (xy 373.608772 -286.197814) (xy 373.653374 -286.173733)
			(xy 373.701136 -286.156761) (xy 373.725948 -286.151574) (xy 373.748808 -286.147256) (xy 373.953786 -285.792164)
			(xy 373.945912 -285.77032) (xy 373.937338 -285.7439) (xy 373.928138 -285.689126) (xy 373.927624 -285.661354)
			(xy 373.928132 -285.635467) (xy 373.936231 -285.584329) (xy 373.95223 -285.535089) (xy 373.975736 -285.488957)
			(xy 374.006168 -285.44707) (xy 374.042778 -285.41046) (xy 374.084665 -285.380028) (xy 374.130797 -285.356522)
			(xy 374.180037 -285.340523) (xy 374.231175 -285.332424) (xy 374.282949 -285.332424) (xy 374.334087 -285.340523)
			(xy 374.383327 -285.356522) (xy 374.429459 -285.380028) (xy 374.471346 -285.41046) (xy 374.507956 -285.44707)
			(xy 374.538388 -285.488957) (xy 374.561894 -285.535089) (xy 374.577893 -285.584329) (xy 374.585992 -285.635467)
			(xy 374.5865 -285.661354) (xy 374.586066 -285.68669) (xy 374.578306 -285.736765) (xy 374.562976 -285.785062)
			(xy 374.540438 -285.830446) (xy 374.511222 -285.871848) (xy 374.476016 -285.908293) (xy 374.435649 -285.938922)
			(xy 374.391071 -285.963016) (xy 374.343331 -285.980006) (xy 374.31853 -285.985204) (xy 374.29567 -285.989522)
			(xy 374.090692 -286.344614) (xy 374.098566 -286.366458) (xy 374.107219 -286.392864) (xy 374.116534 -286.447642)
			(xy 374.117108 -286.475424) (xy 374.1166 -286.501331) (xy 374.116482 -286.502073) (xy 374.371352 -286.502073)
			(xy 374.371352 -286.448775) (xy 374.379295 -286.396071) (xy 374.395005 -286.345141) (xy 374.418131 -286.29712)
			(xy 374.448155 -286.253083) (xy 374.484407 -286.214012) (xy 374.526078 -286.180781) (xy 374.572236 -286.154132)
			(xy 374.62185 -286.13466) (xy 374.673812 -286.1228) (xy 374.726962 -286.118817) (xy 374.780112 -286.1228)
			(xy 374.832074 -286.13466) (xy 374.881688 -286.154132) (xy 374.927846 -286.180781) (xy 374.969517 -286.214012)
			(xy 375.005769 -286.253083) (xy 375.035793 -286.29712) (xy 375.058919 -286.345141) (xy 375.074629 -286.396071)
			(xy 375.082572 -286.448775) (xy 375.08307 -286.475424) (xy 375.337324 -286.475424) (xy 375.337848 -286.45008)
			(xy 375.345616 -286.399991) (xy 375.360959 -286.351681) (xy 375.383515 -286.306288) (xy 375.412751 -286.264882)
			(xy 375.44798 -286.228438) (xy 375.488372 -286.197814) (xy 375.532974 -286.173733) (xy 375.580736 -286.156761)
			(xy 375.605548 -286.151574) (xy 375.628408 -286.147256) (xy 375.833386 -285.792164) (xy 375.825512 -285.77032)
			(xy 375.816938 -285.7439) (xy 375.807738 -285.689126) (xy 375.807224 -285.661354) (xy 375.807732 -285.635467)
			(xy 375.815831 -285.584329) (xy 375.83183 -285.535089) (xy 375.855336 -285.488957) (xy 375.885768 -285.44707)
			(xy 375.922378 -285.41046) (xy 375.964265 -285.380028) (xy 376.010397 -285.356522) (xy 376.059637 -285.340523)
			(xy 376.110775 -285.332424) (xy 376.162549 -285.332424) (xy 376.213687 -285.340523) (xy 376.262927 -285.356522)
			(xy 376.309059 -285.380028) (xy 376.350946 -285.41046) (xy 376.387556 -285.44707) (xy 376.417988 -285.488957)
			(xy 376.441494 -285.535089) (xy 376.457493 -285.584329) (xy 376.465592 -285.635467) (xy 376.4661 -285.661354)
			(xy 376.465666 -285.68669) (xy 376.457906 -285.736765) (xy 376.442576 -285.785062) (xy 376.420038 -285.830446)
			(xy 376.390822 -285.871848) (xy 376.355616 -285.908293) (xy 376.315249 -285.938922) (xy 376.270671 -285.963016)
			(xy 376.222931 -285.980006) (xy 376.19813 -285.985204) (xy 376.17527 -285.989522) (xy 375.970292 -286.344614)
			(xy 375.978166 -286.366458) (xy 375.986819 -286.392864) (xy 375.996134 -286.447642) (xy 375.996708 -286.475424)
			(xy 375.9962 -286.501331) (xy 375.996082 -286.502073) (xy 376.250952 -286.502073) (xy 376.250952 -286.448775)
			(xy 376.258895 -286.396071) (xy 376.274605 -286.345141) (xy 376.297731 -286.29712) (xy 376.327755 -286.253083)
			(xy 376.364007 -286.214012) (xy 376.405678 -286.180781) (xy 376.451836 -286.154132) (xy 376.50145 -286.13466)
			(xy 376.553412 -286.1228) (xy 376.606562 -286.118817) (xy 376.659712 -286.1228) (xy 376.711674 -286.13466)
			(xy 376.761288 -286.154132) (xy 376.807446 -286.180781) (xy 376.849117 -286.214012) (xy 376.885369 -286.253083)
			(xy 376.915393 -286.29712) (xy 376.938519 -286.345141) (xy 376.954229 -286.396071) (xy 376.962172 -286.448775)
			(xy 376.96267 -286.475424) (xy 377.216924 -286.475424) (xy 377.217448 -286.45008) (xy 377.225216 -286.399991)
			(xy 377.240559 -286.351681) (xy 377.263115 -286.306288) (xy 377.292351 -286.264882) (xy 377.32758 -286.228438)
			(xy 377.367972 -286.197814) (xy 377.412574 -286.173733) (xy 377.460336 -286.156761) (xy 377.485148 -286.151574)
			(xy 377.508008 -286.147256) (xy 377.712986 -285.792164) (xy 377.705112 -285.77032) (xy 377.696538 -285.7439)
			(xy 377.687338 -285.689126) (xy 377.686824 -285.661354) (xy 377.687332 -285.635467) (xy 377.695431 -285.584329)
			(xy 377.71143 -285.535089) (xy 377.734936 -285.488957) (xy 377.765368 -285.44707) (xy 377.801978 -285.41046)
			(xy 377.843865 -285.380028) (xy 377.889997 -285.356522) (xy 377.939237 -285.340523) (xy 377.990375 -285.332424)
			(xy 378.042149 -285.332424) (xy 378.093287 -285.340523) (xy 378.142527 -285.356522) (xy 378.188659 -285.380028)
			(xy 378.230546 -285.41046) (xy 378.267156 -285.44707) (xy 378.297588 -285.488957) (xy 378.321094 -285.535089)
			(xy 378.337093 -285.584329) (xy 378.345192 -285.635467) (xy 378.3457 -285.661354) (xy 378.345266 -285.68669)
			(xy 378.337506 -285.736765) (xy 378.322176 -285.785062) (xy 378.299638 -285.830446) (xy 378.270422 -285.871848)
			(xy 378.235216 -285.908293) (xy 378.194849 -285.938922) (xy 378.150271 -285.963016) (xy 378.102531 -285.980006)
			(xy 378.07773 -285.985204) (xy 378.05487 -285.989522) (xy 377.849892 -286.344614) (xy 377.857766 -286.366458)
			(xy 377.866419 -286.392864) (xy 377.875734 -286.447642) (xy 377.876308 -286.475424) (xy 377.8758 -286.501331)
			(xy 377.875682 -286.502073) (xy 378.130552 -286.502073) (xy 378.130552 -286.448775) (xy 378.138495 -286.396071)
			(xy 378.154205 -286.345141) (xy 378.177331 -286.29712) (xy 378.207355 -286.253083) (xy 378.243607 -286.214012)
			(xy 378.285278 -286.180781) (xy 378.331436 -286.154132) (xy 378.38105 -286.13466) (xy 378.433012 -286.1228)
			(xy 378.486162 -286.118817) (xy 378.539312 -286.1228) (xy 378.591274 -286.13466) (xy 378.640888 -286.154132)
			(xy 378.687046 -286.180781) (xy 378.728717 -286.214012) (xy 378.764969 -286.253083) (xy 378.794993 -286.29712)
			(xy 378.818119 -286.345141) (xy 378.833829 -286.396071) (xy 378.841772 -286.448775) (xy 378.84227 -286.475424)
			(xy 379.096524 -286.475424) (xy 379.097048 -286.45008) (xy 379.104816 -286.399991) (xy 379.120159 -286.351681)
			(xy 379.142715 -286.306288) (xy 379.171951 -286.264882) (xy 379.20718 -286.228438) (xy 379.247572 -286.197814)
			(xy 379.292174 -286.173733) (xy 379.339936 -286.156761) (xy 379.364748 -286.151574) (xy 379.387608 -286.147256)
			(xy 379.592586 -285.792164) (xy 379.584712 -285.77032) (xy 379.576138 -285.7439) (xy 379.566938 -285.689126)
			(xy 379.566424 -285.661354) (xy 379.566932 -285.635467) (xy 379.575031 -285.584329) (xy 379.59103 -285.535089)
			(xy 379.614536 -285.488957) (xy 379.644968 -285.44707) (xy 379.681578 -285.41046) (xy 379.723465 -285.380028)
			(xy 379.769597 -285.356522) (xy 379.818837 -285.340523) (xy 379.869975 -285.332424) (xy 379.921749 -285.332424)
			(xy 379.972887 -285.340523) (xy 380.022127 -285.356522) (xy 380.068259 -285.380028) (xy 380.110146 -285.41046)
			(xy 380.146756 -285.44707) (xy 380.177188 -285.488957) (xy 380.200694 -285.535089) (xy 380.216693 -285.584329)
			(xy 380.224792 -285.635467) (xy 380.2253 -285.661354) (xy 380.224866 -285.68669) (xy 380.217106 -285.736765)
			(xy 380.201776 -285.785062) (xy 380.179238 -285.830446) (xy 380.150022 -285.871848) (xy 380.114816 -285.908293)
			(xy 380.074449 -285.938922) (xy 380.029871 -285.963016) (xy 379.982131 -285.980006) (xy 379.95733 -285.985204)
			(xy 379.93447 -285.989522) (xy 379.729492 -286.344614) (xy 379.737366 -286.366458) (xy 379.746019 -286.392864)
			(xy 379.755334 -286.447642) (xy 379.755908 -286.475424) (xy 379.7554 -286.501331) (xy 379.755282 -286.502073)
			(xy 380.010152 -286.502073) (xy 380.010152 -286.448775) (xy 380.018095 -286.396071) (xy 380.033805 -286.345141)
			(xy 380.056931 -286.29712) (xy 380.086955 -286.253083) (xy 380.123207 -286.214012) (xy 380.164878 -286.180781)
			(xy 380.211036 -286.154132) (xy 380.26065 -286.13466) (xy 380.312612 -286.1228) (xy 380.365762 -286.118817)
			(xy 380.418912 -286.1228) (xy 380.470874 -286.13466) (xy 380.520488 -286.154132) (xy 380.566646 -286.180781)
			(xy 380.608317 -286.214012) (xy 380.644569 -286.253083) (xy 380.674593 -286.29712) (xy 380.697719 -286.345141)
			(xy 380.713429 -286.396071) (xy 380.721372 -286.448775) (xy 380.72187 -286.475424) (xy 380.976124 -286.475424)
			(xy 380.976648 -286.45008) (xy 380.984416 -286.399991) (xy 380.999759 -286.351681) (xy 381.022315 -286.306288)
			(xy 381.051551 -286.264882) (xy 381.08678 -286.228438) (xy 381.127172 -286.197814) (xy 381.171774 -286.173733)
			(xy 381.219536 -286.156761) (xy 381.244348 -286.151574) (xy 381.267208 -286.147256) (xy 381.472186 -285.792164)
			(xy 381.464312 -285.77032) (xy 381.455738 -285.7439) (xy 381.446538 -285.689126) (xy 381.446024 -285.661354)
			(xy 381.446532 -285.635467) (xy 381.454631 -285.584329) (xy 381.47063 -285.535089) (xy 381.494136 -285.488957)
			(xy 381.524568 -285.44707) (xy 381.561178 -285.41046) (xy 381.603065 -285.380028) (xy 381.649197 -285.356522)
			(xy 381.698437 -285.340523) (xy 381.749575 -285.332424) (xy 381.801349 -285.332424) (xy 381.852487 -285.340523)
			(xy 381.901727 -285.356522) (xy 381.947859 -285.380028) (xy 381.989746 -285.41046) (xy 382.026356 -285.44707)
			(xy 382.056788 -285.488957) (xy 382.080294 -285.535089) (xy 382.096293 -285.584329) (xy 382.104392 -285.635467)
			(xy 382.1049 -285.661354) (xy 382.104466 -285.68669) (xy 382.104263 -285.688003) (xy 382.359652 -285.688003)
			(xy 382.359652 -285.634705) (xy 382.367595 -285.582001) (xy 382.383305 -285.531071) (xy 382.406431 -285.48305)
			(xy 382.436455 -285.439013) (xy 382.472707 -285.399942) (xy 382.514378 -285.366711) (xy 382.560536 -285.340062)
			(xy 382.61015 -285.32059) (xy 382.662112 -285.30873) (xy 382.715262 -285.304747) (xy 382.768412 -285.30873)
			(xy 382.820374 -285.32059) (xy 382.869988 -285.340062) (xy 382.916146 -285.366711) (xy 382.957817 -285.399942)
			(xy 382.994069 -285.439013) (xy 383.024093 -285.48305) (xy 383.047219 -285.531071) (xy 383.062929 -285.582001)
			(xy 383.070872 -285.634705) (xy 383.07137 -285.661354) (xy 383.070877 -285.687749) (xy 383.299452 -285.687749)
			(xy 383.299452 -285.634451) (xy 383.307395 -285.581747) (xy 383.323105 -285.530817) (xy 383.346231 -285.482796)
			(xy 383.376255 -285.438759) (xy 383.412507 -285.399688) (xy 383.454178 -285.366457) (xy 383.500336 -285.339808)
			(xy 383.54995 -285.320336) (xy 383.601912 -285.308476) (xy 383.655062 -285.304493) (xy 383.708212 -285.308476)
			(xy 383.760174 -285.320336) (xy 383.809788 -285.339808) (xy 383.855946 -285.366457) (xy 383.897617 -285.399688)
			(xy 383.933869 -285.438759) (xy 383.963893 -285.482796) (xy 383.987019 -285.530817) (xy 384.002729 -285.581747)
			(xy 384.010672 -285.634451) (xy 384.01117 -285.6611) (xy 384.010672 -285.687749) (xy 384.010634 -285.688003)
			(xy 384.239252 -285.688003) (xy 384.239252 -285.634705) (xy 384.247195 -285.582001) (xy 384.262905 -285.531071)
			(xy 384.286031 -285.48305) (xy 384.316055 -285.439013) (xy 384.352307 -285.399942) (xy 384.393978 -285.366711)
			(xy 384.440136 -285.340062) (xy 384.48975 -285.32059) (xy 384.541712 -285.30873) (xy 384.594862 -285.304747)
			(xy 384.648012 -285.30873) (xy 384.699974 -285.32059) (xy 384.749588 -285.340062) (xy 384.795746 -285.366711)
			(xy 384.837417 -285.399942) (xy 384.873669 -285.439013) (xy 384.903693 -285.48305) (xy 384.926819 -285.531071)
			(xy 384.942529 -285.582001) (xy 384.950472 -285.634705) (xy 384.95097 -285.661354) (xy 384.950477 -285.687749)
			(xy 385.179052 -285.687749) (xy 385.179052 -285.634451) (xy 385.186995 -285.581747) (xy 385.202705 -285.530817)
			(xy 385.225831 -285.482796) (xy 385.255855 -285.438759) (xy 385.292107 -285.399688) (xy 385.333778 -285.366457)
			(xy 385.379936 -285.339808) (xy 385.42955 -285.320336) (xy 385.481512 -285.308476) (xy 385.534662 -285.304493)
			(xy 385.587812 -285.308476) (xy 385.639774 -285.320336) (xy 385.689388 -285.339808) (xy 385.735546 -285.366457)
			(xy 385.777217 -285.399688) (xy 385.813469 -285.438759) (xy 385.843493 -285.482796) (xy 385.866619 -285.530817)
			(xy 385.882329 -285.581747) (xy 385.890272 -285.634451) (xy 385.89077 -285.6611) (xy 385.890272 -285.687749)
			(xy 385.890234 -285.688003) (xy 386.118852 -285.688003) (xy 386.118852 -285.634705) (xy 386.126795 -285.582001)
			(xy 386.142505 -285.531071) (xy 386.165631 -285.48305) (xy 386.195655 -285.439013) (xy 386.231907 -285.399942)
			(xy 386.273578 -285.366711) (xy 386.319736 -285.340062) (xy 386.36935 -285.32059) (xy 386.421312 -285.30873)
			(xy 386.474462 -285.304747) (xy 386.527612 -285.30873) (xy 386.579574 -285.32059) (xy 386.629188 -285.340062)
			(xy 386.675346 -285.366711) (xy 386.717017 -285.399942) (xy 386.753269 -285.439013) (xy 386.783293 -285.48305)
			(xy 386.806419 -285.531071) (xy 386.822129 -285.582001) (xy 386.830072 -285.634705) (xy 386.83057 -285.661354)
			(xy 386.830072 -285.688003) (xy 386.822129 -285.740707) (xy 386.806419 -285.791637) (xy 386.783293 -285.839658)
			(xy 386.753269 -285.883695) (xy 386.717017 -285.922766) (xy 386.675346 -285.955997) (xy 386.629188 -285.982646)
			(xy 386.579574 -286.002118) (xy 386.527612 -286.013978) (xy 386.474462 -286.017962) (xy 386.421312 -286.013978)
			(xy 386.36935 -286.002118) (xy 386.319736 -285.982646) (xy 386.273578 -285.955997) (xy 386.231907 -285.922766)
			(xy 386.195655 -285.883695) (xy 386.165631 -285.839658) (xy 386.142505 -285.791637) (xy 386.126795 -285.740707)
			(xy 386.118852 -285.688003) (xy 385.890234 -285.688003) (xy 385.882329 -285.740453) (xy 385.866619 -285.791383)
			(xy 385.843493 -285.839404) (xy 385.813469 -285.883441) (xy 385.777217 -285.922512) (xy 385.735546 -285.955743)
			(xy 385.689388 -285.982392) (xy 385.639774 -286.001864) (xy 385.587812 -286.013724) (xy 385.534662 -286.017708)
			(xy 385.481512 -286.013724) (xy 385.42955 -286.001864) (xy 385.379936 -285.982392) (xy 385.333778 -285.955743)
			(xy 385.292107 -285.922512) (xy 385.255855 -285.883441) (xy 385.225831 -285.839404) (xy 385.202705 -285.791383)
			(xy 385.186995 -285.740453) (xy 385.179052 -285.687749) (xy 384.950477 -285.687749) (xy 384.950472 -285.688003)
			(xy 384.942529 -285.740707) (xy 384.926819 -285.791637) (xy 384.903693 -285.839658) (xy 384.873669 -285.883695)
			(xy 384.837417 -285.922766) (xy 384.795746 -285.955997) (xy 384.749588 -285.982646) (xy 384.699974 -286.002118)
			(xy 384.648012 -286.013978) (xy 384.594862 -286.017962) (xy 384.541712 -286.013978) (xy 384.48975 -286.002118)
			(xy 384.440136 -285.982646) (xy 384.393978 -285.955997) (xy 384.352307 -285.922766) (xy 384.316055 -285.883695)
			(xy 384.286031 -285.839658) (xy 384.262905 -285.791637) (xy 384.247195 -285.740707) (xy 384.239252 -285.688003)
			(xy 384.010634 -285.688003) (xy 384.002729 -285.740453) (xy 383.987019 -285.791383) (xy 383.963893 -285.839404)
			(xy 383.933869 -285.883441) (xy 383.897617 -285.922512) (xy 383.855946 -285.955743) (xy 383.809788 -285.982392)
			(xy 383.760174 -286.001864) (xy 383.708212 -286.013724) (xy 383.655062 -286.017708) (xy 383.601912 -286.013724)
			(xy 383.54995 -286.001864) (xy 383.500336 -285.982392) (xy 383.454178 -285.955743) (xy 383.412507 -285.922512)
			(xy 383.376255 -285.883441) (xy 383.346231 -285.839404) (xy 383.323105 -285.791383) (xy 383.307395 -285.740453)
			(xy 383.299452 -285.687749) (xy 383.070877 -285.687749) (xy 383.070872 -285.688003) (xy 383.062929 -285.740707)
			(xy 383.047219 -285.791637) (xy 383.024093 -285.839658) (xy 382.994069 -285.883695) (xy 382.957817 -285.922766)
			(xy 382.916146 -285.955997) (xy 382.869988 -285.982646) (xy 382.820374 -286.002118) (xy 382.768412 -286.013978)
			(xy 382.715262 -286.017962) (xy 382.662112 -286.013978) (xy 382.61015 -286.002118) (xy 382.560536 -285.982646)
			(xy 382.514378 -285.955997) (xy 382.472707 -285.922766) (xy 382.436455 -285.883695) (xy 382.406431 -285.839658)
			(xy 382.383305 -285.791637) (xy 382.367595 -285.740707) (xy 382.359652 -285.688003) (xy 382.104263 -285.688003)
			(xy 382.096706 -285.736765) (xy 382.081376 -285.785062) (xy 382.058838 -285.830446) (xy 382.029622 -285.871848)
			(xy 381.994416 -285.908293) (xy 381.954049 -285.938922) (xy 381.909471 -285.963016) (xy 381.861731 -285.980006)
			(xy 381.83693 -285.985204) (xy 381.81407 -285.989522) (xy 381.609092 -286.344614) (xy 381.616966 -286.366458)
			(xy 381.625619 -286.392864) (xy 381.634934 -286.447642) (xy 381.635508 -286.475424) (xy 381.635 -286.501331)
			(xy 381.634882 -286.502073) (xy 381.890006 -286.502073) (xy 381.890006 -286.448775) (xy 381.897949 -286.396071)
			(xy 381.913659 -286.345141) (xy 381.936785 -286.29712) (xy 381.966809 -286.253083) (xy 382.003061 -286.214012)
			(xy 382.044732 -286.180781) (xy 382.09089 -286.154132) (xy 382.140504 -286.13466) (xy 382.192466 -286.1228)
			(xy 382.245616 -286.118817) (xy 382.298766 -286.1228) (xy 382.350728 -286.13466) (xy 382.400342 -286.154132)
			(xy 382.4465 -286.180781) (xy 382.488171 -286.214012) (xy 382.524423 -286.253083) (xy 382.554447 -286.29712)
			(xy 382.577573 -286.345141) (xy 382.593283 -286.396071) (xy 382.601226 -286.448775) (xy 382.601724 -286.475424)
			(xy 382.601231 -286.501819) (xy 382.829552 -286.501819) (xy 382.829552 -286.448521) (xy 382.837495 -286.395817)
			(xy 382.853205 -286.344887) (xy 382.876331 -286.296866) (xy 382.906355 -286.252829) (xy 382.942607 -286.213758)
			(xy 382.984278 -286.180527) (xy 383.030436 -286.153878) (xy 383.08005 -286.134406) (xy 383.132012 -286.122546)
			(xy 383.185162 -286.118563) (xy 383.238312 -286.122546) (xy 383.290274 -286.134406) (xy 383.339888 -286.153878)
			(xy 383.386046 -286.180527) (xy 383.427717 -286.213758) (xy 383.463969 -286.252829) (xy 383.493993 -286.296866)
			(xy 383.517119 -286.344887) (xy 383.532829 -286.395817) (xy 383.540772 -286.448521) (xy 383.54127 -286.47517)
			(xy 383.540772 -286.501819) (xy 383.769352 -286.501819) (xy 383.769352 -286.448521) (xy 383.777295 -286.395817)
			(xy 383.793005 -286.344887) (xy 383.816131 -286.296866) (xy 383.846155 -286.252829) (xy 383.882407 -286.213758)
			(xy 383.924078 -286.180527) (xy 383.970236 -286.153878) (xy 384.01985 -286.134406) (xy 384.071812 -286.122546)
			(xy 384.124962 -286.118563) (xy 384.178112 -286.122546) (xy 384.230074 -286.134406) (xy 384.279688 -286.153878)
			(xy 384.325846 -286.180527) (xy 384.367517 -286.213758) (xy 384.403769 -286.252829) (xy 384.433793 -286.296866)
			(xy 384.456919 -286.344887) (xy 384.472629 -286.395817) (xy 384.480572 -286.448521) (xy 384.48107 -286.47517)
			(xy 384.480572 -286.501819) (xy 384.709152 -286.501819) (xy 384.709152 -286.448521) (xy 384.717095 -286.395817)
			(xy 384.732805 -286.344887) (xy 384.755931 -286.296866) (xy 384.785955 -286.252829) (xy 384.822207 -286.213758)
			(xy 384.863878 -286.180527) (xy 384.910036 -286.153878) (xy 384.95965 -286.134406) (xy 385.011612 -286.122546)
			(xy 385.064762 -286.118563) (xy 385.117912 -286.122546) (xy 385.169874 -286.134406) (xy 385.219488 -286.153878)
			(xy 385.265646 -286.180527) (xy 385.307317 -286.213758) (xy 385.343569 -286.252829) (xy 385.373593 -286.296866)
			(xy 385.396719 -286.344887) (xy 385.412429 -286.395817) (xy 385.420372 -286.448521) (xy 385.42087 -286.47517)
			(xy 385.420372 -286.501819) (xy 385.648952 -286.501819) (xy 385.648952 -286.448521) (xy 385.656895 -286.395817)
			(xy 385.672605 -286.344887) (xy 385.695731 -286.296866) (xy 385.725755 -286.252829) (xy 385.762007 -286.213758)
			(xy 385.803678 -286.180527) (xy 385.849836 -286.153878) (xy 385.89945 -286.134406) (xy 385.951412 -286.122546)
			(xy 386.004562 -286.118563) (xy 386.057712 -286.122546) (xy 386.109674 -286.134406) (xy 386.159288 -286.153878)
			(xy 386.205446 -286.180527) (xy 386.247117 -286.213758) (xy 386.283369 -286.252829) (xy 386.313393 -286.296866)
			(xy 386.336519 -286.344887) (xy 386.352229 -286.395817) (xy 386.360172 -286.448521) (xy 386.36067 -286.47517)
			(xy 386.360172 -286.501819) (xy 386.352229 -286.554523) (xy 386.336519 -286.605453) (xy 386.313393 -286.653474)
			(xy 386.283369 -286.697511) (xy 386.247117 -286.736582) (xy 386.205446 -286.769813) (xy 386.159288 -286.796462)
			(xy 386.109674 -286.815934) (xy 386.057712 -286.827794) (xy 386.004562 -286.831778) (xy 385.951412 -286.827794)
			(xy 385.89945 -286.815934) (xy 385.849836 -286.796462) (xy 385.803678 -286.769813) (xy 385.762007 -286.736582)
			(xy 385.725755 -286.697511) (xy 385.695731 -286.653474) (xy 385.672605 -286.605453) (xy 385.656895 -286.554523)
			(xy 385.648952 -286.501819) (xy 385.420372 -286.501819) (xy 385.412429 -286.554523) (xy 385.396719 -286.605453)
			(xy 385.373593 -286.653474) (xy 385.343569 -286.697511) (xy 385.307317 -286.736582) (xy 385.265646 -286.769813)
			(xy 385.219488 -286.796462) (xy 385.169874 -286.815934) (xy 385.117912 -286.827794) (xy 385.064762 -286.831778)
			(xy 385.011612 -286.827794) (xy 384.95965 -286.815934) (xy 384.910036 -286.796462) (xy 384.863878 -286.769813)
			(xy 384.822207 -286.736582) (xy 384.785955 -286.697511) (xy 384.755931 -286.653474) (xy 384.732805 -286.605453)
			(xy 384.717095 -286.554523) (xy 384.709152 -286.501819) (xy 384.480572 -286.501819) (xy 384.472629 -286.554523)
			(xy 384.456919 -286.605453) (xy 384.433793 -286.653474) (xy 384.403769 -286.697511) (xy 384.367517 -286.736582)
			(xy 384.325846 -286.769813) (xy 384.279688 -286.796462) (xy 384.230074 -286.815934) (xy 384.178112 -286.827794)
			(xy 384.124962 -286.831778) (xy 384.071812 -286.827794) (xy 384.01985 -286.815934) (xy 383.970236 -286.796462)
			(xy 383.924078 -286.769813) (xy 383.882407 -286.736582) (xy 383.846155 -286.697511) (xy 383.816131 -286.653474)
			(xy 383.793005 -286.605453) (xy 383.777295 -286.554523) (xy 383.769352 -286.501819) (xy 383.540772 -286.501819)
			(xy 383.532829 -286.554523) (xy 383.517119 -286.605453) (xy 383.493993 -286.653474) (xy 383.463969 -286.697511)
			(xy 383.427717 -286.736582) (xy 383.386046 -286.769813) (xy 383.339888 -286.796462) (xy 383.290274 -286.815934)
			(xy 383.238312 -286.827794) (xy 383.185162 -286.831778) (xy 383.132012 -286.827794) (xy 383.08005 -286.815934)
			(xy 383.030436 -286.796462) (xy 382.984278 -286.769813) (xy 382.942607 -286.736582) (xy 382.906355 -286.697511)
			(xy 382.876331 -286.653474) (xy 382.853205 -286.605453) (xy 382.837495 -286.554523) (xy 382.829552 -286.501819)
			(xy 382.601231 -286.501819) (xy 382.601226 -286.502073) (xy 382.593283 -286.554777) (xy 382.577573 -286.605707)
			(xy 382.554447 -286.653728) (xy 382.524423 -286.697765) (xy 382.488171 -286.736836) (xy 382.4465 -286.770067)
			(xy 382.400342 -286.796716) (xy 382.350728 -286.816188) (xy 382.298766 -286.828048) (xy 382.245616 -286.832032)
			(xy 382.192466 -286.828048) (xy 382.140504 -286.816188) (xy 382.09089 -286.796716) (xy 382.044732 -286.770067)
			(xy 382.003061 -286.736836) (xy 381.966809 -286.697765) (xy 381.936785 -286.653728) (xy 381.913659 -286.605707)
			(xy 381.897949 -286.554777) (xy 381.890006 -286.502073) (xy 381.634882 -286.502073) (xy 381.626894 -286.552508)
			(xy 381.610882 -286.601787) (xy 381.587359 -286.647954) (xy 381.556903 -286.689873) (xy 381.520265 -286.726511)
			(xy 381.478346 -286.756967) (xy 381.432179 -286.78049) (xy 381.3829 -286.796502) (xy 381.331723 -286.804608)
			(xy 381.279909 -286.804608) (xy 381.228732 -286.796502) (xy 381.179453 -286.78049) (xy 381.133286 -286.756967)
			(xy 381.091367 -286.726511) (xy 381.054729 -286.689873) (xy 381.024273 -286.647954) (xy 381.00075 -286.601787)
			(xy 380.984738 -286.552508) (xy 380.976632 -286.501331) (xy 380.976124 -286.475424) (xy 380.72187 -286.475424)
			(xy 380.721372 -286.502073) (xy 380.713429 -286.554777) (xy 380.697719 -286.605707) (xy 380.674593 -286.653728)
			(xy 380.644569 -286.697765) (xy 380.608317 -286.736836) (xy 380.566646 -286.770067) (xy 380.520488 -286.796716)
			(xy 380.470874 -286.816188) (xy 380.418912 -286.828048) (xy 380.365762 -286.832032) (xy 380.312612 -286.828048)
			(xy 380.26065 -286.816188) (xy 380.211036 -286.796716) (xy 380.164878 -286.770067) (xy 380.123207 -286.736836)
			(xy 380.086955 -286.697765) (xy 380.056931 -286.653728) (xy 380.033805 -286.605707) (xy 380.018095 -286.554777)
			(xy 380.010152 -286.502073) (xy 379.755282 -286.502073) (xy 379.747294 -286.552508) (xy 379.731282 -286.601787)
			(xy 379.707759 -286.647954) (xy 379.677303 -286.689873) (xy 379.640665 -286.726511) (xy 379.598746 -286.756967)
			(xy 379.552579 -286.78049) (xy 379.5033 -286.796502) (xy 379.452123 -286.804608) (xy 379.400309 -286.804608)
			(xy 379.349132 -286.796502) (xy 379.299853 -286.78049) (xy 379.253686 -286.756967) (xy 379.211767 -286.726511)
			(xy 379.175129 -286.689873) (xy 379.144673 -286.647954) (xy 379.12115 -286.601787) (xy 379.105138 -286.552508)
			(xy 379.097032 -286.501331) (xy 379.096524 -286.475424) (xy 378.84227 -286.475424) (xy 378.841772 -286.502073)
			(xy 378.833829 -286.554777) (xy 378.818119 -286.605707) (xy 378.794993 -286.653728) (xy 378.764969 -286.697765)
			(xy 378.728717 -286.736836) (xy 378.687046 -286.770067) (xy 378.640888 -286.796716) (xy 378.591274 -286.816188)
			(xy 378.539312 -286.828048) (xy 378.486162 -286.832032) (xy 378.433012 -286.828048) (xy 378.38105 -286.816188)
			(xy 378.331436 -286.796716) (xy 378.285278 -286.770067) (xy 378.243607 -286.736836) (xy 378.207355 -286.697765)
			(xy 378.177331 -286.653728) (xy 378.154205 -286.605707) (xy 378.138495 -286.554777) (xy 378.130552 -286.502073)
			(xy 377.875682 -286.502073) (xy 377.867694 -286.552508) (xy 377.851682 -286.601787) (xy 377.828159 -286.647954)
			(xy 377.797703 -286.689873) (xy 377.761065 -286.726511) (xy 377.719146 -286.756967) (xy 377.672979 -286.78049)
			(xy 377.6237 -286.796502) (xy 377.572523 -286.804608) (xy 377.520709 -286.804608) (xy 377.469532 -286.796502)
			(xy 377.420253 -286.78049) (xy 377.374086 -286.756967) (xy 377.332167 -286.726511) (xy 377.295529 -286.689873)
			(xy 377.265073 -286.647954) (xy 377.24155 -286.601787) (xy 377.225538 -286.552508) (xy 377.217432 -286.501331)
			(xy 377.216924 -286.475424) (xy 376.96267 -286.475424) (xy 376.962172 -286.502073) (xy 376.954229 -286.554777)
			(xy 376.938519 -286.605707) (xy 376.915393 -286.653728) (xy 376.885369 -286.697765) (xy 376.849117 -286.736836)
			(xy 376.807446 -286.770067) (xy 376.761288 -286.796716) (xy 376.711674 -286.816188) (xy 376.659712 -286.828048)
			(xy 376.606562 -286.832032) (xy 376.553412 -286.828048) (xy 376.50145 -286.816188) (xy 376.451836 -286.796716)
			(xy 376.405678 -286.770067) (xy 376.364007 -286.736836) (xy 376.327755 -286.697765) (xy 376.297731 -286.653728)
			(xy 376.274605 -286.605707) (xy 376.258895 -286.554777) (xy 376.250952 -286.502073) (xy 375.996082 -286.502073)
			(xy 375.988094 -286.552508) (xy 375.972082 -286.601787) (xy 375.948559 -286.647954) (xy 375.918103 -286.689873)
			(xy 375.881465 -286.726511) (xy 375.839546 -286.756967) (xy 375.793379 -286.78049) (xy 375.7441 -286.796502)
			(xy 375.692923 -286.804608) (xy 375.641109 -286.804608) (xy 375.589932 -286.796502) (xy 375.540653 -286.78049)
			(xy 375.494486 -286.756967) (xy 375.452567 -286.726511) (xy 375.415929 -286.689873) (xy 375.385473 -286.647954)
			(xy 375.36195 -286.601787) (xy 375.345938 -286.552508) (xy 375.337832 -286.501331) (xy 375.337324 -286.475424)
			(xy 375.08307 -286.475424) (xy 375.082572 -286.502073) (xy 375.074629 -286.554777) (xy 375.058919 -286.605707)
			(xy 375.035793 -286.653728) (xy 375.005769 -286.697765) (xy 374.969517 -286.736836) (xy 374.927846 -286.770067)
			(xy 374.881688 -286.796716) (xy 374.832074 -286.816188) (xy 374.780112 -286.828048) (xy 374.726962 -286.832032)
			(xy 374.673812 -286.828048) (xy 374.62185 -286.816188) (xy 374.572236 -286.796716) (xy 374.526078 -286.770067)
			(xy 374.484407 -286.736836) (xy 374.448155 -286.697765) (xy 374.418131 -286.653728) (xy 374.395005 -286.605707)
			(xy 374.379295 -286.554777) (xy 374.371352 -286.502073) (xy 374.116482 -286.502073) (xy 374.108494 -286.552508)
			(xy 374.092482 -286.601787) (xy 374.068959 -286.647954) (xy 374.038503 -286.689873) (xy 374.001865 -286.726511)
			(xy 373.959946 -286.756967) (xy 373.913779 -286.78049) (xy 373.8645 -286.796502) (xy 373.813323 -286.804608)
			(xy 373.761509 -286.804608) (xy 373.710332 -286.796502) (xy 373.661053 -286.78049) (xy 373.614886 -286.756967)
			(xy 373.572967 -286.726511) (xy 373.536329 -286.689873) (xy 373.505873 -286.647954) (xy 373.48235 -286.601787)
			(xy 373.466338 -286.552508) (xy 373.458232 -286.501331) (xy 373.457724 -286.475424) (xy 373.20347 -286.475424)
			(xy 373.202972 -286.502073) (xy 373.195029 -286.554777) (xy 373.179319 -286.605707) (xy 373.156193 -286.653728)
			(xy 373.126169 -286.697765) (xy 373.089917 -286.736836) (xy 373.048246 -286.770067) (xy 373.002088 -286.796716)
			(xy 372.952474 -286.816188) (xy 372.900512 -286.828048) (xy 372.847362 -286.832032) (xy 372.794212 -286.828048)
			(xy 372.74225 -286.816188) (xy 372.692636 -286.796716) (xy 372.646478 -286.770067) (xy 372.604807 -286.736836)
			(xy 372.568555 -286.697765) (xy 372.538531 -286.653728) (xy 372.515405 -286.605707) (xy 372.499695 -286.554777)
			(xy 372.491752 -286.502073) (xy 372.236882 -286.502073) (xy 372.228894 -286.552508) (xy 372.212882 -286.601787)
			(xy 372.189359 -286.647954) (xy 372.158903 -286.689873) (xy 372.122265 -286.726511) (xy 372.080346 -286.756967)
			(xy 372.034179 -286.78049) (xy 371.9849 -286.796502) (xy 371.933723 -286.804608) (xy 371.881909 -286.804608)
			(xy 371.830732 -286.796502) (xy 371.781453 -286.78049) (xy 371.735286 -286.756967) (xy 371.693367 -286.726511)
			(xy 371.656729 -286.689873) (xy 371.626273 -286.647954) (xy 371.60275 -286.601787) (xy 371.586738 -286.552508)
			(xy 371.578632 -286.501331) (xy 371.578124 -286.475424) (xy 371.32387 -286.475424) (xy 371.323372 -286.502073)
			(xy 371.315429 -286.554777) (xy 371.299719 -286.605707) (xy 371.276593 -286.653728) (xy 371.246569 -286.697765)
			(xy 371.210317 -286.736836) (xy 371.168646 -286.770067) (xy 371.122488 -286.796716) (xy 371.072874 -286.816188)
			(xy 371.020912 -286.828048) (xy 370.967762 -286.832032) (xy 370.914612 -286.828048) (xy 370.86265 -286.816188)
			(xy 370.813036 -286.796716) (xy 370.766878 -286.770067) (xy 370.725207 -286.736836) (xy 370.688955 -286.697765)
			(xy 370.658931 -286.653728) (xy 370.635805 -286.605707) (xy 370.620095 -286.554777) (xy 370.612152 -286.502073)
			(xy 370.357282 -286.502073) (xy 370.349294 -286.552508) (xy 370.333282 -286.601787) (xy 370.309759 -286.647954)
			(xy 370.279303 -286.689873) (xy 370.242665 -286.726511) (xy 370.200746 -286.756967) (xy 370.154579 -286.78049)
			(xy 370.1053 -286.796502) (xy 370.054123 -286.804608) (xy 370.002309 -286.804608) (xy 369.951132 -286.796502)
			(xy 369.901853 -286.78049) (xy 369.855686 -286.756967) (xy 369.813767 -286.726511) (xy 369.777129 -286.689873)
			(xy 369.746673 -286.647954) (xy 369.72315 -286.601787) (xy 369.707138 -286.552508) (xy 369.699032 -286.501331)
			(xy 369.698524 -286.475424) (xy 369.44427 -286.475424) (xy 369.443772 -286.502073) (xy 369.435829 -286.554777)
			(xy 369.420119 -286.605707) (xy 369.396993 -286.653728) (xy 369.366969 -286.697765) (xy 369.330717 -286.736836)
			(xy 369.289046 -286.770067) (xy 369.242888 -286.796716) (xy 369.193274 -286.816188) (xy 369.141312 -286.828048)
			(xy 369.088162 -286.832032) (xy 369.035012 -286.828048) (xy 368.98305 -286.816188) (xy 368.933436 -286.796716)
			(xy 368.887278 -286.770067) (xy 368.845607 -286.736836) (xy 368.809355 -286.697765) (xy 368.779331 -286.653728)
			(xy 368.756205 -286.605707) (xy 368.740495 -286.554777) (xy 368.732552 -286.502073) (xy 368.477682 -286.502073)
			(xy 368.469694 -286.552508) (xy 368.453682 -286.601787) (xy 368.430159 -286.647954) (xy 368.399703 -286.689873)
			(xy 368.363065 -286.726511) (xy 368.321146 -286.756967) (xy 368.274979 -286.78049) (xy 368.2257 -286.796502)
			(xy 368.174523 -286.804608) (xy 368.122709 -286.804608) (xy 368.071532 -286.796502) (xy 368.022253 -286.78049)
			(xy 367.976086 -286.756967) (xy 367.934167 -286.726511) (xy 367.897529 -286.689873) (xy 367.867073 -286.647954)
			(xy 367.84355 -286.601787) (xy 367.827538 -286.552508) (xy 367.819432 -286.501331) (xy 367.818924 -286.475424)
			(xy 367.564924 -286.475424) (xy 367.564426 -286.502073) (xy 367.556483 -286.554777) (xy 367.540773 -286.605707)
			(xy 367.517647 -286.653728) (xy 367.487623 -286.697765) (xy 367.451371 -286.736836) (xy 367.4097 -286.770067)
			(xy 367.363542 -286.796716) (xy 367.313928 -286.816188) (xy 367.261966 -286.828048) (xy 367.208816 -286.832032)
			(xy 367.155666 -286.828048) (xy 367.103704 -286.816188) (xy 367.05409 -286.796716) (xy 367.007932 -286.770067)
			(xy 366.966261 -286.736836) (xy 366.930009 -286.697765) (xy 366.899985 -286.653728) (xy 366.876859 -286.605707)
			(xy 366.861149 -286.554777) (xy 366.853206 -286.502073) (xy 364.745026 -286.502073) (xy 364.737083 -286.554777)
			(xy 364.721373 -286.605707) (xy 364.698247 -286.653728) (xy 364.668223 -286.697765) (xy 364.631971 -286.736836)
			(xy 364.5903 -286.770067) (xy 364.544142 -286.796716) (xy 364.494528 -286.816188) (xy 364.442566 -286.828048)
			(xy 364.389416 -286.832032) (xy 364.336266 -286.828048) (xy 364.284304 -286.816188) (xy 364.23469 -286.796716)
			(xy 364.188532 -286.770067) (xy 364.146861 -286.736836) (xy 364.110609 -286.697765) (xy 364.080585 -286.653728)
			(xy 364.057459 -286.605707) (xy 364.041749 -286.554777) (xy 364.033806 -286.502073) (xy 361.925372 -286.502073)
			(xy 361.917429 -286.554777) (xy 361.901719 -286.605707) (xy 361.878593 -286.653728) (xy 361.848569 -286.697765)
			(xy 361.812317 -286.736836) (xy 361.770646 -286.770067) (xy 361.724488 -286.796716) (xy 361.674874 -286.816188)
			(xy 361.622912 -286.828048) (xy 361.569762 -286.832032) (xy 361.516612 -286.828048) (xy 361.46465 -286.816188)
			(xy 361.415036 -286.796716) (xy 361.368878 -286.770067) (xy 361.327207 -286.736836) (xy 361.290955 -286.697765)
			(xy 361.260931 -286.653728) (xy 361.237805 -286.605707) (xy 361.222095 -286.554777) (xy 361.214152 -286.502073)
			(xy 353.747324 -286.502073) (xy 353.747324 -287.002982) (xy 353.768495 -287.015765) (xy 353.807132 -287.046632)
			(xy 353.840741 -287.082908) (xy 353.868574 -287.123785) (xy 353.890009 -287.168351) (xy 353.904568 -287.215611)
			(xy 353.911926 -287.264514) (xy 353.912424 -287.28924) (xy 353.911971 -287.313912) (xy 353.911674 -287.315889)
			(xy 355.105452 -287.315889) (xy 355.105452 -287.262591) (xy 355.113395 -287.209887) (xy 355.129105 -287.158957)
			(xy 355.152231 -287.110936) (xy 355.182255 -287.066899) (xy 355.218507 -287.027828) (xy 355.260178 -286.994597)
			(xy 355.306336 -286.967948) (xy 355.35595 -286.948476) (xy 355.407912 -286.936616) (xy 355.461062 -286.932633)
			(xy 355.514212 -286.936616) (xy 355.566174 -286.948476) (xy 355.615788 -286.967948) (xy 355.661946 -286.994597)
			(xy 355.703617 -287.027828) (xy 355.739869 -287.066899) (xy 355.769893 -287.110936) (xy 355.793019 -287.158957)
			(xy 355.808729 -287.209887) (xy 355.816672 -287.262591) (xy 355.81717 -287.28924) (xy 355.816672 -287.315889)
			(xy 357.924852 -287.315889) (xy 357.924852 -287.262591) (xy 357.932795 -287.209887) (xy 357.948505 -287.158957)
			(xy 357.971631 -287.110936) (xy 358.001655 -287.066899) (xy 358.037907 -287.027828) (xy 358.079578 -286.994597)
			(xy 358.125736 -286.967948) (xy 358.17535 -286.948476) (xy 358.227312 -286.936616) (xy 358.280462 -286.932633)
			(xy 358.333612 -286.936616) (xy 358.385574 -286.948476) (xy 358.435188 -286.967948) (xy 358.481346 -286.994597)
			(xy 358.523017 -287.027828) (xy 358.559269 -287.066899) (xy 358.589293 -287.110936) (xy 358.612419 -287.158957)
			(xy 358.628129 -287.209887) (xy 358.636072 -287.262591) (xy 358.63657 -287.28924) (xy 358.636072 -287.315889)
			(xy 367.323106 -287.315889) (xy 367.323106 -287.262591) (xy 367.331049 -287.209887) (xy 367.346759 -287.158957)
			(xy 367.369885 -287.110936) (xy 367.399909 -287.066899) (xy 367.436161 -287.027828) (xy 367.477832 -286.994597)
			(xy 367.52399 -286.967948) (xy 367.573604 -286.948476) (xy 367.625566 -286.936616) (xy 367.678716 -286.932633)
			(xy 367.731866 -286.936616) (xy 367.783828 -286.948476) (xy 367.833442 -286.967948) (xy 367.8796 -286.994597)
			(xy 367.921271 -287.027828) (xy 367.957523 -287.066899) (xy 367.987547 -287.110936) (xy 368.010673 -287.158957)
			(xy 368.026383 -287.209887) (xy 368.034326 -287.262591) (xy 368.034824 -287.28924) (xy 368.034326 -287.315889)
			(xy 368.262652 -287.315889) (xy 368.262652 -287.262591) (xy 368.270595 -287.209887) (xy 368.286305 -287.158957)
			(xy 368.309431 -287.110936) (xy 368.339455 -287.066899) (xy 368.375707 -287.027828) (xy 368.417378 -286.994597)
			(xy 368.463536 -286.967948) (xy 368.51315 -286.948476) (xy 368.565112 -286.936616) (xy 368.618262 -286.932633)
			(xy 368.671412 -286.936616) (xy 368.723374 -286.948476) (xy 368.772988 -286.967948) (xy 368.819146 -286.994597)
			(xy 368.860817 -287.027828) (xy 368.897069 -287.066899) (xy 368.927093 -287.110936) (xy 368.950219 -287.158957)
			(xy 368.965929 -287.209887) (xy 368.973872 -287.262591) (xy 368.97437 -287.28924) (xy 368.973872 -287.315889)
			(xy 369.202452 -287.315889) (xy 369.202452 -287.262591) (xy 369.210395 -287.209887) (xy 369.226105 -287.158957)
			(xy 369.249231 -287.110936) (xy 369.279255 -287.066899) (xy 369.315507 -287.027828) (xy 369.357178 -286.994597)
			(xy 369.403336 -286.967948) (xy 369.45295 -286.948476) (xy 369.504912 -286.936616) (xy 369.558062 -286.932633)
			(xy 369.611212 -286.936616) (xy 369.663174 -286.948476) (xy 369.712788 -286.967948) (xy 369.758946 -286.994597)
			(xy 369.800617 -287.027828) (xy 369.836869 -287.066899) (xy 369.866893 -287.110936) (xy 369.890019 -287.158957)
			(xy 369.905729 -287.209887) (xy 369.913672 -287.262591) (xy 369.91417 -287.28924) (xy 369.913672 -287.315889)
			(xy 370.142252 -287.315889) (xy 370.142252 -287.262591) (xy 370.150195 -287.209887) (xy 370.165905 -287.158957)
			(xy 370.189031 -287.110936) (xy 370.219055 -287.066899) (xy 370.255307 -287.027828) (xy 370.296978 -286.994597)
			(xy 370.343136 -286.967948) (xy 370.39275 -286.948476) (xy 370.444712 -286.936616) (xy 370.497862 -286.932633)
			(xy 370.551012 -286.936616) (xy 370.602974 -286.948476) (xy 370.652588 -286.967948) (xy 370.698746 -286.994597)
			(xy 370.740417 -287.027828) (xy 370.776669 -287.066899) (xy 370.806693 -287.110936) (xy 370.829819 -287.158957)
			(xy 370.845529 -287.209887) (xy 370.853472 -287.262591) (xy 370.85397 -287.28924) (xy 370.853472 -287.315889)
			(xy 371.082052 -287.315889) (xy 371.082052 -287.262591) (xy 371.089995 -287.209887) (xy 371.105705 -287.158957)
			(xy 371.128831 -287.110936) (xy 371.158855 -287.066899) (xy 371.195107 -287.027828) (xy 371.236778 -286.994597)
			(xy 371.282936 -286.967948) (xy 371.33255 -286.948476) (xy 371.384512 -286.936616) (xy 371.437662 -286.932633)
			(xy 371.490812 -286.936616) (xy 371.542774 -286.948476) (xy 371.592388 -286.967948) (xy 371.638546 -286.994597)
			(xy 371.680217 -287.027828) (xy 371.716469 -287.066899) (xy 371.746493 -287.110936) (xy 371.769619 -287.158957)
			(xy 371.785329 -287.209887) (xy 371.793272 -287.262591) (xy 371.79377 -287.28924) (xy 371.793272 -287.315889)
			(xy 372.021852 -287.315889) (xy 372.021852 -287.262591) (xy 372.029795 -287.209887) (xy 372.045505 -287.158957)
			(xy 372.068631 -287.110936) (xy 372.098655 -287.066899) (xy 372.134907 -287.027828) (xy 372.176578 -286.994597)
			(xy 372.222736 -286.967948) (xy 372.27235 -286.948476) (xy 372.324312 -286.936616) (xy 372.377462 -286.932633)
			(xy 372.430612 -286.936616) (xy 372.482574 -286.948476) (xy 372.532188 -286.967948) (xy 372.578346 -286.994597)
			(xy 372.620017 -287.027828) (xy 372.656269 -287.066899) (xy 372.686293 -287.110936) (xy 372.709419 -287.158957)
			(xy 372.725129 -287.209887) (xy 372.733072 -287.262591) (xy 372.73357 -287.28924) (xy 372.733072 -287.315889)
			(xy 372.961652 -287.315889) (xy 372.961652 -287.262591) (xy 372.969595 -287.209887) (xy 372.985305 -287.158957)
			(xy 373.008431 -287.110936) (xy 373.038455 -287.066899) (xy 373.074707 -287.027828) (xy 373.116378 -286.994597)
			(xy 373.162536 -286.967948) (xy 373.21215 -286.948476) (xy 373.264112 -286.936616) (xy 373.317262 -286.932633)
			(xy 373.370412 -286.936616) (xy 373.422374 -286.948476) (xy 373.471988 -286.967948) (xy 373.518146 -286.994597)
			(xy 373.559817 -287.027828) (xy 373.596069 -287.066899) (xy 373.626093 -287.110936) (xy 373.649219 -287.158957)
			(xy 373.664929 -287.209887) (xy 373.672872 -287.262591) (xy 373.67337 -287.28924) (xy 373.672872 -287.315889)
			(xy 373.901452 -287.315889) (xy 373.901452 -287.262591) (xy 373.909395 -287.209887) (xy 373.925105 -287.158957)
			(xy 373.948231 -287.110936) (xy 373.978255 -287.066899) (xy 374.014507 -287.027828) (xy 374.056178 -286.994597)
			(xy 374.102336 -286.967948) (xy 374.15195 -286.948476) (xy 374.203912 -286.936616) (xy 374.257062 -286.932633)
			(xy 374.310212 -286.936616) (xy 374.362174 -286.948476) (xy 374.411788 -286.967948) (xy 374.457946 -286.994597)
			(xy 374.499617 -287.027828) (xy 374.535869 -287.066899) (xy 374.565893 -287.110936) (xy 374.589019 -287.158957)
			(xy 374.604729 -287.209887) (xy 374.612672 -287.262591) (xy 374.61317 -287.28924) (xy 374.612672 -287.315889)
			(xy 374.841252 -287.315889) (xy 374.841252 -287.262591) (xy 374.849195 -287.209887) (xy 374.864905 -287.158957)
			(xy 374.888031 -287.110936) (xy 374.918055 -287.066899) (xy 374.954307 -287.027828) (xy 374.995978 -286.994597)
			(xy 375.042136 -286.967948) (xy 375.09175 -286.948476) (xy 375.143712 -286.936616) (xy 375.196862 -286.932633)
			(xy 375.250012 -286.936616) (xy 375.301974 -286.948476) (xy 375.351588 -286.967948) (xy 375.397746 -286.994597)
			(xy 375.439417 -287.027828) (xy 375.475669 -287.066899) (xy 375.505693 -287.110936) (xy 375.528819 -287.158957)
			(xy 375.544529 -287.209887) (xy 375.552472 -287.262591) (xy 375.55297 -287.28924) (xy 375.552472 -287.315889)
			(xy 375.781052 -287.315889) (xy 375.781052 -287.262591) (xy 375.788995 -287.209887) (xy 375.804705 -287.158957)
			(xy 375.827831 -287.110936) (xy 375.857855 -287.066899) (xy 375.894107 -287.027828) (xy 375.935778 -286.994597)
			(xy 375.981936 -286.967948) (xy 376.03155 -286.948476) (xy 376.083512 -286.936616) (xy 376.136662 -286.932633)
			(xy 376.189812 -286.936616) (xy 376.241774 -286.948476) (xy 376.291388 -286.967948) (xy 376.337546 -286.994597)
			(xy 376.379217 -287.027828) (xy 376.415469 -287.066899) (xy 376.445493 -287.110936) (xy 376.468619 -287.158957)
			(xy 376.484329 -287.209887) (xy 376.492272 -287.262591) (xy 376.49277 -287.28924) (xy 376.492272 -287.315889)
			(xy 376.720852 -287.315889) (xy 376.720852 -287.262591) (xy 376.728795 -287.209887) (xy 376.744505 -287.158957)
			(xy 376.767631 -287.110936) (xy 376.797655 -287.066899) (xy 376.833907 -287.027828) (xy 376.875578 -286.994597)
			(xy 376.921736 -286.967948) (xy 376.97135 -286.948476) (xy 377.023312 -286.936616) (xy 377.076462 -286.932633)
			(xy 377.129612 -286.936616) (xy 377.181574 -286.948476) (xy 377.231188 -286.967948) (xy 377.277346 -286.994597)
			(xy 377.319017 -287.027828) (xy 377.355269 -287.066899) (xy 377.385293 -287.110936) (xy 377.408419 -287.158957)
			(xy 377.424129 -287.209887) (xy 377.432072 -287.262591) (xy 377.43257 -287.28924) (xy 377.432072 -287.315889)
			(xy 377.660652 -287.315889) (xy 377.660652 -287.262591) (xy 377.668595 -287.209887) (xy 377.684305 -287.158957)
			(xy 377.707431 -287.110936) (xy 377.737455 -287.066899) (xy 377.773707 -287.027828) (xy 377.815378 -286.994597)
			(xy 377.861536 -286.967948) (xy 377.91115 -286.948476) (xy 377.963112 -286.936616) (xy 378.016262 -286.932633)
			(xy 378.069412 -286.936616) (xy 378.121374 -286.948476) (xy 378.170988 -286.967948) (xy 378.217146 -286.994597)
			(xy 378.258817 -287.027828) (xy 378.295069 -287.066899) (xy 378.325093 -287.110936) (xy 378.348219 -287.158957)
			(xy 378.363929 -287.209887) (xy 378.371872 -287.262591) (xy 378.37237 -287.28924) (xy 378.371872 -287.315889)
			(xy 378.600452 -287.315889) (xy 378.600452 -287.262591) (xy 378.608395 -287.209887) (xy 378.624105 -287.158957)
			(xy 378.647231 -287.110936) (xy 378.677255 -287.066899) (xy 378.713507 -287.027828) (xy 378.755178 -286.994597)
			(xy 378.801336 -286.967948) (xy 378.85095 -286.948476) (xy 378.902912 -286.936616) (xy 378.956062 -286.932633)
			(xy 379.009212 -286.936616) (xy 379.061174 -286.948476) (xy 379.110788 -286.967948) (xy 379.156946 -286.994597)
			(xy 379.198617 -287.027828) (xy 379.234869 -287.066899) (xy 379.264893 -287.110936) (xy 379.288019 -287.158957)
			(xy 379.303729 -287.209887) (xy 379.311672 -287.262591) (xy 379.31217 -287.28924) (xy 379.311672 -287.315889)
			(xy 379.540252 -287.315889) (xy 379.540252 -287.262591) (xy 379.548195 -287.209887) (xy 379.563905 -287.158957)
			(xy 379.587031 -287.110936) (xy 379.617055 -287.066899) (xy 379.653307 -287.027828) (xy 379.694978 -286.994597)
			(xy 379.741136 -286.967948) (xy 379.79075 -286.948476) (xy 379.842712 -286.936616) (xy 379.895862 -286.932633)
			(xy 379.949012 -286.936616) (xy 380.000974 -286.948476) (xy 380.050588 -286.967948) (xy 380.096746 -286.994597)
			(xy 380.138417 -287.027828) (xy 380.174669 -287.066899) (xy 380.204693 -287.110936) (xy 380.227819 -287.158957)
			(xy 380.243529 -287.209887) (xy 380.251472 -287.262591) (xy 380.25197 -287.28924) (xy 380.251472 -287.315889)
			(xy 380.480052 -287.315889) (xy 380.480052 -287.262591) (xy 380.487995 -287.209887) (xy 380.503705 -287.158957)
			(xy 380.526831 -287.110936) (xy 380.556855 -287.066899) (xy 380.593107 -287.027828) (xy 380.634778 -286.994597)
			(xy 380.680936 -286.967948) (xy 380.73055 -286.948476) (xy 380.782512 -286.936616) (xy 380.835662 -286.932633)
			(xy 380.888812 -286.936616) (xy 380.940774 -286.948476) (xy 380.990388 -286.967948) (xy 381.036546 -286.994597)
			(xy 381.078217 -287.027828) (xy 381.114469 -287.066899) (xy 381.144493 -287.110936) (xy 381.167619 -287.158957)
			(xy 381.183329 -287.209887) (xy 381.191272 -287.262591) (xy 381.19177 -287.28924) (xy 381.191272 -287.315889)
			(xy 381.419852 -287.315889) (xy 381.419852 -287.262591) (xy 381.427795 -287.209887) (xy 381.443505 -287.158957)
			(xy 381.466631 -287.110936) (xy 381.496655 -287.066899) (xy 381.532907 -287.027828) (xy 381.574578 -286.994597)
			(xy 381.620736 -286.967948) (xy 381.67035 -286.948476) (xy 381.722312 -286.936616) (xy 381.775462 -286.932633)
			(xy 381.828612 -286.936616) (xy 381.880574 -286.948476) (xy 381.930188 -286.967948) (xy 381.976346 -286.994597)
			(xy 382.018017 -287.027828) (xy 382.054269 -287.066899) (xy 382.084293 -287.110936) (xy 382.107419 -287.158957)
			(xy 382.123129 -287.209887) (xy 382.131072 -287.262591) (xy 382.13157 -287.28924) (xy 382.131072 -287.315889)
			(xy 382.359652 -287.315889) (xy 382.359652 -287.262591) (xy 382.367595 -287.209887) (xy 382.383305 -287.158957)
			(xy 382.406431 -287.110936) (xy 382.436455 -287.066899) (xy 382.472707 -287.027828) (xy 382.514378 -286.994597)
			(xy 382.560536 -286.967948) (xy 382.61015 -286.948476) (xy 382.662112 -286.936616) (xy 382.715262 -286.932633)
			(xy 382.768412 -286.936616) (xy 382.820374 -286.948476) (xy 382.869988 -286.967948) (xy 382.916146 -286.994597)
			(xy 382.957817 -287.027828) (xy 382.994069 -287.066899) (xy 383.024093 -287.110936) (xy 383.047219 -287.158957)
			(xy 383.062929 -287.209887) (xy 383.070872 -287.262591) (xy 383.07137 -287.28924) (xy 383.070872 -287.315889)
			(xy 383.299452 -287.315889) (xy 383.299452 -287.262591) (xy 383.307395 -287.209887) (xy 383.323105 -287.158957)
			(xy 383.346231 -287.110936) (xy 383.376255 -287.066899) (xy 383.412507 -287.027828) (xy 383.454178 -286.994597)
			(xy 383.500336 -286.967948) (xy 383.54995 -286.948476) (xy 383.601912 -286.936616) (xy 383.655062 -286.932633)
			(xy 383.708212 -286.936616) (xy 383.760174 -286.948476) (xy 383.809788 -286.967948) (xy 383.855946 -286.994597)
			(xy 383.897617 -287.027828) (xy 383.933869 -287.066899) (xy 383.963893 -287.110936) (xy 383.987019 -287.158957)
			(xy 384.002729 -287.209887) (xy 384.010672 -287.262591) (xy 384.01117 -287.28924) (xy 384.010677 -287.315635)
			(xy 384.239506 -287.315635) (xy 384.239506 -287.262337) (xy 384.247449 -287.209633) (xy 384.263159 -287.158703)
			(xy 384.286285 -287.110682) (xy 384.316309 -287.066645) (xy 384.352561 -287.027574) (xy 384.394232 -286.994343)
			(xy 384.44039 -286.967694) (xy 384.490004 -286.948222) (xy 384.541966 -286.936362) (xy 384.595116 -286.932379)
			(xy 384.648266 -286.936362) (xy 384.700228 -286.948222) (xy 384.749842 -286.967694) (xy 384.796 -286.994343)
			(xy 384.837671 -287.027574) (xy 384.873923 -287.066645) (xy 384.903947 -287.110682) (xy 384.927073 -287.158703)
			(xy 384.942783 -287.209633) (xy 384.950726 -287.262337) (xy 384.951224 -287.288986) (xy 384.950726 -287.315635)
			(xy 384.942783 -287.368339) (xy 384.927073 -287.419269) (xy 384.915698 -287.442889) (xy 385.179306 -287.442889)
			(xy 385.179306 -287.389591) (xy 385.187249 -287.336887) (xy 385.202959 -287.285957) (xy 385.226085 -287.237936)
			(xy 385.256109 -287.193899) (xy 385.292361 -287.154828) (xy 385.334032 -287.121597) (xy 385.38019 -287.094948)
			(xy 385.429804 -287.075476) (xy 385.481766 -287.063616) (xy 385.534916 -287.059633) (xy 385.588066 -287.063616)
			(xy 385.640028 -287.075476) (xy 385.689642 -287.094948) (xy 385.7358 -287.121597) (xy 385.777471 -287.154828)
			(xy 385.813723 -287.193899) (xy 385.843747 -287.237936) (xy 385.866873 -287.285957) (xy 385.882583 -287.336887)
			(xy 385.890526 -287.389591) (xy 385.891024 -287.41624) (xy 385.890526 -287.442889) (xy 385.882583 -287.495593)
			(xy 385.866873 -287.546523) (xy 385.843747 -287.594544) (xy 385.813723 -287.638581) (xy 385.777471 -287.677652)
			(xy 385.7358 -287.710883) (xy 385.689642 -287.737532) (xy 385.640028 -287.757004) (xy 385.588066 -287.768864)
			(xy 385.534916 -287.772848) (xy 385.481766 -287.768864) (xy 385.429804 -287.757004) (xy 385.38019 -287.737532)
			(xy 385.334032 -287.710883) (xy 385.292361 -287.677652) (xy 385.256109 -287.638581) (xy 385.226085 -287.594544)
			(xy 385.202959 -287.546523) (xy 385.187249 -287.495593) (xy 385.179306 -287.442889) (xy 384.915698 -287.442889)
			(xy 384.903947 -287.46729) (xy 384.873923 -287.511327) (xy 384.837671 -287.550398) (xy 384.796 -287.583629)
			(xy 384.749842 -287.610278) (xy 384.700228 -287.62975) (xy 384.648266 -287.64161) (xy 384.595116 -287.645594)
			(xy 384.541966 -287.64161) (xy 384.490004 -287.62975) (xy 384.44039 -287.610278) (xy 384.394232 -287.583629)
			(xy 384.352561 -287.550398) (xy 384.316309 -287.511327) (xy 384.286285 -287.46729) (xy 384.263159 -287.419269)
			(xy 384.247449 -287.368339) (xy 384.239506 -287.315635) (xy 384.010677 -287.315635) (xy 384.010672 -287.315889)
			(xy 384.002729 -287.368593) (xy 383.987019 -287.419523) (xy 383.963893 -287.467544) (xy 383.933869 -287.511581)
			(xy 383.897617 -287.550652) (xy 383.855946 -287.583883) (xy 383.809788 -287.610532) (xy 383.760174 -287.630004)
			(xy 383.708212 -287.641864) (xy 383.655062 -287.645848) (xy 383.601912 -287.641864) (xy 383.54995 -287.630004)
			(xy 383.500336 -287.610532) (xy 383.454178 -287.583883) (xy 383.412507 -287.550652) (xy 383.376255 -287.511581)
			(xy 383.346231 -287.467544) (xy 383.323105 -287.419523) (xy 383.307395 -287.368593) (xy 383.299452 -287.315889)
			(xy 383.070872 -287.315889) (xy 383.062929 -287.368593) (xy 383.047219 -287.419523) (xy 383.024093 -287.467544)
			(xy 382.994069 -287.511581) (xy 382.957817 -287.550652) (xy 382.916146 -287.583883) (xy 382.869988 -287.610532)
			(xy 382.820374 -287.630004) (xy 382.768412 -287.641864) (xy 382.715262 -287.645848) (xy 382.662112 -287.641864)
			(xy 382.61015 -287.630004) (xy 382.560536 -287.610532) (xy 382.514378 -287.583883) (xy 382.472707 -287.550652)
			(xy 382.436455 -287.511581) (xy 382.406431 -287.467544) (xy 382.383305 -287.419523) (xy 382.367595 -287.368593)
			(xy 382.359652 -287.315889) (xy 382.131072 -287.315889) (xy 382.123129 -287.368593) (xy 382.107419 -287.419523)
			(xy 382.084293 -287.467544) (xy 382.054269 -287.511581) (xy 382.018017 -287.550652) (xy 381.976346 -287.583883)
			(xy 381.930188 -287.610532) (xy 381.880574 -287.630004) (xy 381.828612 -287.641864) (xy 381.775462 -287.645848)
			(xy 381.722312 -287.641864) (xy 381.67035 -287.630004) (xy 381.620736 -287.610532) (xy 381.574578 -287.583883)
			(xy 381.532907 -287.550652) (xy 381.496655 -287.511581) (xy 381.466631 -287.467544) (xy 381.443505 -287.419523)
			(xy 381.427795 -287.368593) (xy 381.419852 -287.315889) (xy 381.191272 -287.315889) (xy 381.183329 -287.368593)
			(xy 381.167619 -287.419523) (xy 381.144493 -287.467544) (xy 381.114469 -287.511581) (xy 381.078217 -287.550652)
			(xy 381.036546 -287.583883) (xy 380.990388 -287.610532) (xy 380.940774 -287.630004) (xy 380.888812 -287.641864)
			(xy 380.835662 -287.645848) (xy 380.782512 -287.641864) (xy 380.73055 -287.630004) (xy 380.680936 -287.610532)
			(xy 380.634778 -287.583883) (xy 380.593107 -287.550652) (xy 380.556855 -287.511581) (xy 380.526831 -287.467544)
			(xy 380.503705 -287.419523) (xy 380.487995 -287.368593) (xy 380.480052 -287.315889) (xy 380.251472 -287.315889)
			(xy 380.243529 -287.368593) (xy 380.227819 -287.419523) (xy 380.204693 -287.467544) (xy 380.174669 -287.511581)
			(xy 380.138417 -287.550652) (xy 380.096746 -287.583883) (xy 380.050588 -287.610532) (xy 380.000974 -287.630004)
			(xy 379.949012 -287.641864) (xy 379.895862 -287.645848) (xy 379.842712 -287.641864) (xy 379.79075 -287.630004)
			(xy 379.741136 -287.610532) (xy 379.694978 -287.583883) (xy 379.653307 -287.550652) (xy 379.617055 -287.511581)
			(xy 379.587031 -287.467544) (xy 379.563905 -287.419523) (xy 379.548195 -287.368593) (xy 379.540252 -287.315889)
			(xy 379.311672 -287.315889) (xy 379.303729 -287.368593) (xy 379.288019 -287.419523) (xy 379.264893 -287.467544)
			(xy 379.234869 -287.511581) (xy 379.198617 -287.550652) (xy 379.156946 -287.583883) (xy 379.110788 -287.610532)
			(xy 379.061174 -287.630004) (xy 379.009212 -287.641864) (xy 378.956062 -287.645848) (xy 378.902912 -287.641864)
			(xy 378.85095 -287.630004) (xy 378.801336 -287.610532) (xy 378.755178 -287.583883) (xy 378.713507 -287.550652)
			(xy 378.677255 -287.511581) (xy 378.647231 -287.467544) (xy 378.624105 -287.419523) (xy 378.608395 -287.368593)
			(xy 378.600452 -287.315889) (xy 378.371872 -287.315889) (xy 378.363929 -287.368593) (xy 378.348219 -287.419523)
			(xy 378.325093 -287.467544) (xy 378.295069 -287.511581) (xy 378.258817 -287.550652) (xy 378.217146 -287.583883)
			(xy 378.170988 -287.610532) (xy 378.121374 -287.630004) (xy 378.069412 -287.641864) (xy 378.016262 -287.645848)
			(xy 377.963112 -287.641864) (xy 377.91115 -287.630004) (xy 377.861536 -287.610532) (xy 377.815378 -287.583883)
			(xy 377.773707 -287.550652) (xy 377.737455 -287.511581) (xy 377.707431 -287.467544) (xy 377.684305 -287.419523)
			(xy 377.668595 -287.368593) (xy 377.660652 -287.315889) (xy 377.432072 -287.315889) (xy 377.424129 -287.368593)
			(xy 377.408419 -287.419523) (xy 377.385293 -287.467544) (xy 377.355269 -287.511581) (xy 377.319017 -287.550652)
			(xy 377.277346 -287.583883) (xy 377.231188 -287.610532) (xy 377.181574 -287.630004) (xy 377.129612 -287.641864)
			(xy 377.076462 -287.645848) (xy 377.023312 -287.641864) (xy 376.97135 -287.630004) (xy 376.921736 -287.610532)
			(xy 376.875578 -287.583883) (xy 376.833907 -287.550652) (xy 376.797655 -287.511581) (xy 376.767631 -287.467544)
			(xy 376.744505 -287.419523) (xy 376.728795 -287.368593) (xy 376.720852 -287.315889) (xy 376.492272 -287.315889)
			(xy 376.484329 -287.368593) (xy 376.468619 -287.419523) (xy 376.445493 -287.467544) (xy 376.415469 -287.511581)
			(xy 376.379217 -287.550652) (xy 376.337546 -287.583883) (xy 376.291388 -287.610532) (xy 376.241774 -287.630004)
			(xy 376.189812 -287.641864) (xy 376.136662 -287.645848) (xy 376.083512 -287.641864) (xy 376.03155 -287.630004)
			(xy 375.981936 -287.610532) (xy 375.935778 -287.583883) (xy 375.894107 -287.550652) (xy 375.857855 -287.511581)
			(xy 375.827831 -287.467544) (xy 375.804705 -287.419523) (xy 375.788995 -287.368593) (xy 375.781052 -287.315889)
			(xy 375.552472 -287.315889) (xy 375.544529 -287.368593) (xy 375.528819 -287.419523) (xy 375.505693 -287.467544)
			(xy 375.475669 -287.511581) (xy 375.439417 -287.550652) (xy 375.397746 -287.583883) (xy 375.351588 -287.610532)
			(xy 375.301974 -287.630004) (xy 375.250012 -287.641864) (xy 375.196862 -287.645848) (xy 375.143712 -287.641864)
			(xy 375.09175 -287.630004) (xy 375.042136 -287.610532) (xy 374.995978 -287.583883) (xy 374.954307 -287.550652)
			(xy 374.918055 -287.511581) (xy 374.888031 -287.467544) (xy 374.864905 -287.419523) (xy 374.849195 -287.368593)
			(xy 374.841252 -287.315889) (xy 374.612672 -287.315889) (xy 374.604729 -287.368593) (xy 374.589019 -287.419523)
			(xy 374.565893 -287.467544) (xy 374.535869 -287.511581) (xy 374.499617 -287.550652) (xy 374.457946 -287.583883)
			(xy 374.411788 -287.610532) (xy 374.362174 -287.630004) (xy 374.310212 -287.641864) (xy 374.257062 -287.645848)
			(xy 374.203912 -287.641864) (xy 374.15195 -287.630004) (xy 374.102336 -287.610532) (xy 374.056178 -287.583883)
			(xy 374.014507 -287.550652) (xy 373.978255 -287.511581) (xy 373.948231 -287.467544) (xy 373.925105 -287.419523)
			(xy 373.909395 -287.368593) (xy 373.901452 -287.315889) (xy 373.672872 -287.315889) (xy 373.664929 -287.368593)
			(xy 373.649219 -287.419523) (xy 373.626093 -287.467544) (xy 373.596069 -287.511581) (xy 373.559817 -287.550652)
			(xy 373.518146 -287.583883) (xy 373.471988 -287.610532) (xy 373.422374 -287.630004) (xy 373.370412 -287.641864)
			(xy 373.317262 -287.645848) (xy 373.264112 -287.641864) (xy 373.21215 -287.630004) (xy 373.162536 -287.610532)
			(xy 373.116378 -287.583883) (xy 373.074707 -287.550652) (xy 373.038455 -287.511581) (xy 373.008431 -287.467544)
			(xy 372.985305 -287.419523) (xy 372.969595 -287.368593) (xy 372.961652 -287.315889) (xy 372.733072 -287.315889)
			(xy 372.725129 -287.368593) (xy 372.709419 -287.419523) (xy 372.686293 -287.467544) (xy 372.656269 -287.511581)
			(xy 372.620017 -287.550652) (xy 372.578346 -287.583883) (xy 372.532188 -287.610532) (xy 372.482574 -287.630004)
			(xy 372.430612 -287.641864) (xy 372.377462 -287.645848) (xy 372.324312 -287.641864) (xy 372.27235 -287.630004)
			(xy 372.222736 -287.610532) (xy 372.176578 -287.583883) (xy 372.134907 -287.550652) (xy 372.098655 -287.511581)
			(xy 372.068631 -287.467544) (xy 372.045505 -287.419523) (xy 372.029795 -287.368593) (xy 372.021852 -287.315889)
			(xy 371.793272 -287.315889) (xy 371.785329 -287.368593) (xy 371.769619 -287.419523) (xy 371.746493 -287.467544)
			(xy 371.716469 -287.511581) (xy 371.680217 -287.550652) (xy 371.638546 -287.583883) (xy 371.592388 -287.610532)
			(xy 371.542774 -287.630004) (xy 371.490812 -287.641864) (xy 371.437662 -287.645848) (xy 371.384512 -287.641864)
			(xy 371.33255 -287.630004) (xy 371.282936 -287.610532) (xy 371.236778 -287.583883) (xy 371.195107 -287.550652)
			(xy 371.158855 -287.511581) (xy 371.128831 -287.467544) (xy 371.105705 -287.419523) (xy 371.089995 -287.368593)
			(xy 371.082052 -287.315889) (xy 370.853472 -287.315889) (xy 370.845529 -287.368593) (xy 370.829819 -287.419523)
			(xy 370.806693 -287.467544) (xy 370.776669 -287.511581) (xy 370.740417 -287.550652) (xy 370.698746 -287.583883)
			(xy 370.652588 -287.610532) (xy 370.602974 -287.630004) (xy 370.551012 -287.641864) (xy 370.497862 -287.645848)
			(xy 370.444712 -287.641864) (xy 370.39275 -287.630004) (xy 370.343136 -287.610532) (xy 370.296978 -287.583883)
			(xy 370.255307 -287.550652) (xy 370.219055 -287.511581) (xy 370.189031 -287.467544) (xy 370.165905 -287.419523)
			(xy 370.150195 -287.368593) (xy 370.142252 -287.315889) (xy 369.913672 -287.315889) (xy 369.905729 -287.368593)
			(xy 369.890019 -287.419523) (xy 369.866893 -287.467544) (xy 369.836869 -287.511581) (xy 369.800617 -287.550652)
			(xy 369.758946 -287.583883) (xy 369.712788 -287.610532) (xy 369.663174 -287.630004) (xy 369.611212 -287.641864)
			(xy 369.558062 -287.645848) (xy 369.504912 -287.641864) (xy 369.45295 -287.630004) (xy 369.403336 -287.610532)
			(xy 369.357178 -287.583883) (xy 369.315507 -287.550652) (xy 369.279255 -287.511581) (xy 369.249231 -287.467544)
			(xy 369.226105 -287.419523) (xy 369.210395 -287.368593) (xy 369.202452 -287.315889) (xy 368.973872 -287.315889)
			(xy 368.965929 -287.368593) (xy 368.950219 -287.419523) (xy 368.927093 -287.467544) (xy 368.897069 -287.511581)
			(xy 368.860817 -287.550652) (xy 368.819146 -287.583883) (xy 368.772988 -287.610532) (xy 368.723374 -287.630004)
			(xy 368.671412 -287.641864) (xy 368.618262 -287.645848) (xy 368.565112 -287.641864) (xy 368.51315 -287.630004)
			(xy 368.463536 -287.610532) (xy 368.417378 -287.583883) (xy 368.375707 -287.550652) (xy 368.339455 -287.511581)
			(xy 368.309431 -287.467544) (xy 368.286305 -287.419523) (xy 368.270595 -287.368593) (xy 368.262652 -287.315889)
			(xy 368.034326 -287.315889) (xy 368.026383 -287.368593) (xy 368.010673 -287.419523) (xy 367.987547 -287.467544)
			(xy 367.957523 -287.511581) (xy 367.921271 -287.550652) (xy 367.8796 -287.583883) (xy 367.833442 -287.610532)
			(xy 367.783828 -287.630004) (xy 367.731866 -287.641864) (xy 367.678716 -287.645848) (xy 367.625566 -287.641864)
			(xy 367.573604 -287.630004) (xy 367.52399 -287.610532) (xy 367.477832 -287.583883) (xy 367.436161 -287.550652)
			(xy 367.399909 -287.511581) (xy 367.369885 -287.467544) (xy 367.346759 -287.419523) (xy 367.331049 -287.368593)
			(xy 367.323106 -287.315889) (xy 358.636072 -287.315889) (xy 358.628129 -287.368593) (xy 358.612419 -287.419523)
			(xy 358.589293 -287.467544) (xy 358.559269 -287.511581) (xy 358.523017 -287.550652) (xy 358.481346 -287.583883)
			(xy 358.435188 -287.610532) (xy 358.385574 -287.630004) (xy 358.333612 -287.641864) (xy 358.280462 -287.645848)
			(xy 358.227312 -287.641864) (xy 358.17535 -287.630004) (xy 358.125736 -287.610532) (xy 358.079578 -287.583883)
			(xy 358.037907 -287.550652) (xy 358.001655 -287.511581) (xy 357.971631 -287.467544) (xy 357.948505 -287.419523)
			(xy 357.932795 -287.368593) (xy 357.924852 -287.315889) (xy 355.816672 -287.315889) (xy 355.808729 -287.368593)
			(xy 355.793019 -287.419523) (xy 355.769893 -287.467544) (xy 355.739869 -287.511581) (xy 355.703617 -287.550652)
			(xy 355.661946 -287.583883) (xy 355.615788 -287.610532) (xy 355.566174 -287.630004) (xy 355.514212 -287.641864)
			(xy 355.461062 -287.645848) (xy 355.407912 -287.641864) (xy 355.35595 -287.630004) (xy 355.306336 -287.610532)
			(xy 355.260178 -287.583883) (xy 355.218507 -287.550652) (xy 355.182255 -287.511581) (xy 355.152231 -287.467544)
			(xy 355.129105 -287.419523) (xy 355.113395 -287.368593) (xy 355.105452 -287.315889) (xy 353.911674 -287.315889)
			(xy 353.904644 -287.36271) (xy 353.890144 -287.409876) (xy 353.868792 -287.454363) (xy 353.841064 -287.49518)
			(xy 353.807576 -287.531422) (xy 353.769072 -287.562282) (xy 353.726408 -287.587075) (xy 353.703636 -287.59658)
			(xy 353.689125 -287.644712) (xy 353.652536 -287.738356) (xy 353.607586 -287.828285) (xy 353.554647 -287.913756)
			(xy 353.494156 -287.99406) (xy 353.460812 -288.031682) (xy 353.464169 -288.049334) (xy 353.467732 -288.085089)
			(xy 353.467924 -288.103056) (xy 353.467413 -288.129705) (xy 361.214152 -288.129705) (xy 361.214152 -288.076407)
			(xy 361.222095 -288.023703) (xy 361.237805 -287.972773) (xy 361.260931 -287.924752) (xy 361.290955 -287.880715)
			(xy 361.327207 -287.841644) (xy 361.368878 -287.808413) (xy 361.415036 -287.781764) (xy 361.46465 -287.762292)
			(xy 361.516612 -287.750432) (xy 361.569762 -287.746449) (xy 361.622912 -287.750432) (xy 361.674874 -287.762292)
			(xy 361.724488 -287.781764) (xy 361.770646 -287.808413) (xy 361.812317 -287.841644) (xy 361.848569 -287.880715)
			(xy 361.878593 -287.924752) (xy 361.901719 -287.972773) (xy 361.917429 -288.023703) (xy 361.925372 -288.076407)
			(xy 361.92587 -288.103056) (xy 361.925372 -288.129705) (xy 364.033806 -288.129705) (xy 364.033806 -288.076407)
			(xy 364.041749 -288.023703) (xy 364.057459 -287.972773) (xy 364.080585 -287.924752) (xy 364.110609 -287.880715)
			(xy 364.146861 -287.841644) (xy 364.188532 -287.808413) (xy 364.23469 -287.781764) (xy 364.284304 -287.762292)
			(xy 364.336266 -287.750432) (xy 364.389416 -287.746449) (xy 364.442566 -287.750432) (xy 364.494528 -287.762292)
			(xy 364.544142 -287.781764) (xy 364.5903 -287.808413) (xy 364.631971 -287.841644) (xy 364.668223 -287.880715)
			(xy 364.698247 -287.924752) (xy 364.721373 -287.972773) (xy 364.737083 -288.023703) (xy 364.745026 -288.076407)
			(xy 364.745524 -288.103056) (xy 364.745026 -288.129705) (xy 367.792752 -288.129705) (xy 367.792752 -288.076407)
			(xy 367.800695 -288.023703) (xy 367.816405 -287.972773) (xy 367.839531 -287.924752) (xy 367.869555 -287.880715)
			(xy 367.905807 -287.841644) (xy 367.947478 -287.808413) (xy 367.993636 -287.781764) (xy 368.04325 -287.762292)
			(xy 368.095212 -287.750432) (xy 368.148362 -287.746449) (xy 368.201512 -287.750432) (xy 368.253474 -287.762292)
			(xy 368.303088 -287.781764) (xy 368.349246 -287.808413) (xy 368.390917 -287.841644) (xy 368.427169 -287.880715)
			(xy 368.457193 -287.924752) (xy 368.480319 -287.972773) (xy 368.496029 -288.023703) (xy 368.503972 -288.076407)
			(xy 368.50447 -288.103056) (xy 368.758724 -288.103056) (xy 368.759232 -288.077149) (xy 368.767338 -288.025972)
			(xy 368.78335 -287.976693) (xy 368.806873 -287.930526) (xy 368.837329 -287.888607) (xy 368.873967 -287.851969)
			(xy 368.915886 -287.821513) (xy 368.962053 -287.79799) (xy 369.011332 -287.781978) (xy 369.062509 -287.773872)
			(xy 369.114323 -287.773872) (xy 369.1655 -287.781978) (xy 369.214779 -287.79799) (xy 369.260946 -287.821513)
			(xy 369.302865 -287.851969) (xy 369.339503 -287.888607) (xy 369.369959 -287.930526) (xy 369.393482 -287.976693)
			(xy 369.409494 -288.025972) (xy 369.4176 -288.077149) (xy 369.418108 -288.103056) (xy 369.417526 -288.129705)
			(xy 369.672606 -288.129705) (xy 369.672606 -288.076407) (xy 369.680549 -288.023703) (xy 369.696259 -287.972773)
			(xy 369.719385 -287.924752) (xy 369.749409 -287.880715) (xy 369.785661 -287.841644) (xy 369.827332 -287.808413)
			(xy 369.87349 -287.781764) (xy 369.923104 -287.762292) (xy 369.975066 -287.750432) (xy 370.028216 -287.746449)
			(xy 370.081366 -287.750432) (xy 370.133328 -287.762292) (xy 370.182942 -287.781764) (xy 370.2291 -287.808413)
			(xy 370.270771 -287.841644) (xy 370.307023 -287.880715) (xy 370.337047 -287.924752) (xy 370.360173 -287.972773)
			(xy 370.375883 -288.023703) (xy 370.383826 -288.076407) (xy 370.384324 -288.103056) (xy 370.638324 -288.103056)
			(xy 370.638832 -288.077149) (xy 370.646938 -288.025972) (xy 370.66295 -287.976693) (xy 370.686473 -287.930526)
			(xy 370.716929 -287.888607) (xy 370.753567 -287.851969) (xy 370.795486 -287.821513) (xy 370.841653 -287.79799)
			(xy 370.890932 -287.781978) (xy 370.942109 -287.773872) (xy 370.993923 -287.773872) (xy 371.0451 -287.781978)
			(xy 371.094379 -287.79799) (xy 371.140546 -287.821513) (xy 371.182465 -287.851969) (xy 371.219103 -287.888607)
			(xy 371.249559 -287.930526) (xy 371.273082 -287.976693) (xy 371.289094 -288.025972) (xy 371.2972 -288.077149)
			(xy 371.297708 -288.103056) (xy 371.297126 -288.129705) (xy 371.552206 -288.129705) (xy 371.552206 -288.076407)
			(xy 371.560149 -288.023703) (xy 371.575859 -287.972773) (xy 371.598985 -287.924752) (xy 371.629009 -287.880715)
			(xy 371.665261 -287.841644) (xy 371.706932 -287.808413) (xy 371.75309 -287.781764) (xy 371.802704 -287.762292)
			(xy 371.854666 -287.750432) (xy 371.907816 -287.746449) (xy 371.960966 -287.750432) (xy 372.012928 -287.762292)
			(xy 372.062542 -287.781764) (xy 372.1087 -287.808413) (xy 372.150371 -287.841644) (xy 372.186623 -287.880715)
			(xy 372.216647 -287.924752) (xy 372.239773 -287.972773) (xy 372.255483 -288.023703) (xy 372.263426 -288.076407)
			(xy 372.263924 -288.103056) (xy 372.517924 -288.103056) (xy 372.518432 -288.077149) (xy 372.526538 -288.025972)
			(xy 372.54255 -287.976693) (xy 372.566073 -287.930526) (xy 372.596529 -287.888607) (xy 372.633167 -287.851969)
			(xy 372.675086 -287.821513) (xy 372.721253 -287.79799) (xy 372.770532 -287.781978) (xy 372.821709 -287.773872)
			(xy 372.873523 -287.773872) (xy 372.9247 -287.781978) (xy 372.973979 -287.79799) (xy 373.020146 -287.821513)
			(xy 373.062065 -287.851969) (xy 373.098703 -287.888607) (xy 373.129159 -287.930526) (xy 373.152682 -287.976693)
			(xy 373.168694 -288.025972) (xy 373.1768 -288.077149) (xy 373.177308 -288.103056) (xy 373.176726 -288.129705)
			(xy 373.431806 -288.129705) (xy 373.431806 -288.076407) (xy 373.439749 -288.023703) (xy 373.455459 -287.972773)
			(xy 373.478585 -287.924752) (xy 373.508609 -287.880715) (xy 373.544861 -287.841644) (xy 373.586532 -287.808413)
			(xy 373.63269 -287.781764) (xy 373.682304 -287.762292) (xy 373.734266 -287.750432) (xy 373.787416 -287.746449)
			(xy 373.840566 -287.750432) (xy 373.892528 -287.762292) (xy 373.942142 -287.781764) (xy 373.9883 -287.808413)
			(xy 374.029971 -287.841644) (xy 374.066223 -287.880715) (xy 374.096247 -287.924752) (xy 374.119373 -287.972773)
			(xy 374.135083 -288.023703) (xy 374.143026 -288.076407) (xy 374.143524 -288.103056) (xy 374.397524 -288.103056)
			(xy 374.398032 -288.077149) (xy 374.406138 -288.025972) (xy 374.42215 -287.976693) (xy 374.445673 -287.930526)
			(xy 374.476129 -287.888607) (xy 374.512767 -287.851969) (xy 374.554686 -287.821513) (xy 374.600853 -287.79799)
			(xy 374.650132 -287.781978) (xy 374.701309 -287.773872) (xy 374.753123 -287.773872) (xy 374.8043 -287.781978)
			(xy 374.853579 -287.79799) (xy 374.899746 -287.821513) (xy 374.941665 -287.851969) (xy 374.978303 -287.888607)
			(xy 375.008759 -287.930526) (xy 375.032282 -287.976693) (xy 375.048294 -288.025972) (xy 375.0564 -288.077149)
			(xy 375.056908 -288.103056) (xy 375.056326 -288.129705) (xy 375.311406 -288.129705) (xy 375.311406 -288.076407)
			(xy 375.319349 -288.023703) (xy 375.335059 -287.972773) (xy 375.358185 -287.924752) (xy 375.388209 -287.880715)
			(xy 375.424461 -287.841644) (xy 375.466132 -287.808413) (xy 375.51229 -287.781764) (xy 375.561904 -287.762292)
			(xy 375.613866 -287.750432) (xy 375.667016 -287.746449) (xy 375.720166 -287.750432) (xy 375.772128 -287.762292)
			(xy 375.821742 -287.781764) (xy 375.8679 -287.808413) (xy 375.909571 -287.841644) (xy 375.945823 -287.880715)
			(xy 375.975847 -287.924752) (xy 375.998973 -287.972773) (xy 376.014683 -288.023703) (xy 376.022626 -288.076407)
			(xy 376.023124 -288.103056) (xy 376.277124 -288.103056) (xy 376.277632 -288.077149) (xy 376.285738 -288.025972)
			(xy 376.30175 -287.976693) (xy 376.325273 -287.930526) (xy 376.355729 -287.888607) (xy 376.392367 -287.851969)
			(xy 376.434286 -287.821513) (xy 376.480453 -287.79799) (xy 376.529732 -287.781978) (xy 376.580909 -287.773872)
			(xy 376.632723 -287.773872) (xy 376.6839 -287.781978) (xy 376.733179 -287.79799) (xy 376.779346 -287.821513)
			(xy 376.821265 -287.851969) (xy 376.857903 -287.888607) (xy 376.888359 -287.930526) (xy 376.911882 -287.976693)
			(xy 376.927894 -288.025972) (xy 376.936 -288.077149) (xy 376.936508 -288.103056) (xy 376.935926 -288.129705)
			(xy 377.191006 -288.129705) (xy 377.191006 -288.076407) (xy 377.198949 -288.023703) (xy 377.214659 -287.972773)
			(xy 377.237785 -287.924752) (xy 377.267809 -287.880715) (xy 377.304061 -287.841644) (xy 377.345732 -287.808413)
			(xy 377.39189 -287.781764) (xy 377.441504 -287.762292) (xy 377.493466 -287.750432) (xy 377.546616 -287.746449)
			(xy 377.599766 -287.750432) (xy 377.651728 -287.762292) (xy 377.701342 -287.781764) (xy 377.7475 -287.808413)
			(xy 377.789171 -287.841644) (xy 377.825423 -287.880715) (xy 377.855447 -287.924752) (xy 377.878573 -287.972773)
			(xy 377.894283 -288.023703) (xy 377.902226 -288.076407) (xy 377.902724 -288.103056) (xy 378.156724 -288.103056)
			(xy 378.157232 -288.077149) (xy 378.165338 -288.025972) (xy 378.18135 -287.976693) (xy 378.204873 -287.930526)
			(xy 378.235329 -287.888607) (xy 378.271967 -287.851969) (xy 378.313886 -287.821513) (xy 378.360053 -287.79799)
			(xy 378.409332 -287.781978) (xy 378.460509 -287.773872) (xy 378.512323 -287.773872) (xy 378.5635 -287.781978)
			(xy 378.612779 -287.79799) (xy 378.658946 -287.821513) (xy 378.700865 -287.851969) (xy 378.737503 -287.888607)
			(xy 378.767959 -287.930526) (xy 378.791482 -287.976693) (xy 378.807494 -288.025972) (xy 378.8156 -288.077149)
			(xy 378.816108 -288.103056) (xy 378.815526 -288.129705) (xy 379.070606 -288.129705) (xy 379.070606 -288.076407)
			(xy 379.078549 -288.023703) (xy 379.094259 -287.972773) (xy 379.117385 -287.924752) (xy 379.147409 -287.880715)
			(xy 379.183661 -287.841644) (xy 379.225332 -287.808413) (xy 379.27149 -287.781764) (xy 379.321104 -287.762292)
			(xy 379.373066 -287.750432) (xy 379.426216 -287.746449) (xy 379.479366 -287.750432) (xy 379.531328 -287.762292)
			(xy 379.580942 -287.781764) (xy 379.6271 -287.808413) (xy 379.668771 -287.841644) (xy 379.705023 -287.880715)
			(xy 379.735047 -287.924752) (xy 379.758173 -287.972773) (xy 379.773883 -288.023703) (xy 379.781826 -288.076407)
			(xy 379.782324 -288.103056) (xy 380.036324 -288.103056) (xy 380.036832 -288.077149) (xy 380.044938 -288.025972)
			(xy 380.06095 -287.976693) (xy 380.084473 -287.930526) (xy 380.114929 -287.888607) (xy 380.151567 -287.851969)
			(xy 380.193486 -287.821513) (xy 380.239653 -287.79799) (xy 380.288932 -287.781978) (xy 380.340109 -287.773872)
			(xy 380.391923 -287.773872) (xy 380.4431 -287.781978) (xy 380.492379 -287.79799) (xy 380.538546 -287.821513)
			(xy 380.580465 -287.851969) (xy 380.617103 -287.888607) (xy 380.647559 -287.930526) (xy 380.671082 -287.976693)
			(xy 380.687094 -288.025972) (xy 380.6952 -288.077149) (xy 380.695708 -288.103056) (xy 380.695126 -288.129705)
			(xy 380.950206 -288.129705) (xy 380.950206 -288.076407) (xy 380.958149 -288.023703) (xy 380.973859 -287.972773)
			(xy 380.996985 -287.924752) (xy 381.027009 -287.880715) (xy 381.063261 -287.841644) (xy 381.104932 -287.808413)
			(xy 381.15109 -287.781764) (xy 381.200704 -287.762292) (xy 381.252666 -287.750432) (xy 381.305816 -287.746449)
			(xy 381.358966 -287.750432) (xy 381.410928 -287.762292) (xy 381.460542 -287.781764) (xy 381.5067 -287.808413)
			(xy 381.548371 -287.841644) (xy 381.584623 -287.880715) (xy 381.614647 -287.924752) (xy 381.637773 -287.972773)
			(xy 381.653483 -288.023703) (xy 381.661426 -288.076407) (xy 381.661924 -288.103056) (xy 381.661426 -288.129705)
			(xy 381.890006 -288.129705) (xy 381.890006 -288.076407) (xy 381.897949 -288.023703) (xy 381.913659 -287.972773)
			(xy 381.936785 -287.924752) (xy 381.966809 -287.880715) (xy 382.003061 -287.841644) (xy 382.044732 -287.808413)
			(xy 382.09089 -287.781764) (xy 382.140504 -287.762292) (xy 382.192466 -287.750432) (xy 382.245616 -287.746449)
			(xy 382.298766 -287.750432) (xy 382.350728 -287.762292) (xy 382.400342 -287.781764) (xy 382.4465 -287.808413)
			(xy 382.488171 -287.841644) (xy 382.524423 -287.880715) (xy 382.554447 -287.924752) (xy 382.577573 -287.972773)
			(xy 382.593283 -288.023703) (xy 382.601226 -288.076407) (xy 382.601724 -288.103056) (xy 382.855724 -288.103056)
			(xy 382.856232 -288.077149) (xy 382.864338 -288.025972) (xy 382.88035 -287.976693) (xy 382.903873 -287.930526)
			(xy 382.934329 -287.888607) (xy 382.970967 -287.851969) (xy 383.012886 -287.821513) (xy 383.059053 -287.79799)
			(xy 383.108332 -287.781978) (xy 383.159509 -287.773872) (xy 383.211323 -287.773872) (xy 383.2625 -287.781978)
			(xy 383.311779 -287.79799) (xy 383.357946 -287.821513) (xy 383.399865 -287.851969) (xy 383.436503 -287.888607)
			(xy 383.466959 -287.930526) (xy 383.490482 -287.976693) (xy 383.506494 -288.025972) (xy 383.5146 -288.077149)
			(xy 383.515108 -288.103056) (xy 383.514526 -288.129705) (xy 383.769606 -288.129705) (xy 383.769606 -288.076407)
			(xy 383.777549 -288.023703) (xy 383.793259 -287.972773) (xy 383.816385 -287.924752) (xy 383.846409 -287.880715)
			(xy 383.882661 -287.841644) (xy 383.924332 -287.808413) (xy 383.97049 -287.781764) (xy 384.020104 -287.762292)
			(xy 384.072066 -287.750432) (xy 384.125216 -287.746449) (xy 384.178366 -287.750432) (xy 384.230328 -287.762292)
			(xy 384.279942 -287.781764) (xy 384.3261 -287.808413) (xy 384.367771 -287.841644) (xy 384.404023 -287.880715)
			(xy 384.434047 -287.924752) (xy 384.457173 -287.972773) (xy 384.472883 -288.023703) (xy 384.480826 -288.076407)
			(xy 384.481324 -288.103056) (xy 384.480826 -288.129705) (xy 384.472883 -288.182409) (xy 384.457173 -288.233339)
			(xy 384.434047 -288.28136) (xy 384.404023 -288.325397) (xy 384.367771 -288.364468) (xy 384.3261 -288.397699)
			(xy 384.279942 -288.424348) (xy 384.230328 -288.44382) (xy 384.178366 -288.45568) (xy 384.125216 -288.459664)
			(xy 384.072066 -288.45568) (xy 384.020104 -288.44382) (xy 383.97049 -288.424348) (xy 383.924332 -288.397699)
			(xy 383.882661 -288.364468) (xy 383.846409 -288.325397) (xy 383.816385 -288.28136) (xy 383.793259 -288.233339)
			(xy 383.777549 -288.182409) (xy 383.769606 -288.129705) (xy 383.514526 -288.129705) (xy 383.514503 -288.130773)
			(xy 383.505187 -288.185419) (xy 383.496566 -288.211768) (xy 383.488692 -288.233866) (xy 383.693924 -288.588958)
			(xy 383.716784 -288.593276) (xy 383.741606 -288.598437) (xy 383.789384 -288.615395) (xy 383.834001 -288.639469)
			(xy 383.874406 -288.67009) (xy 383.909646 -288.706538) (xy 383.93889 -288.747952) (xy 383.961447 -288.793355)
			(xy 383.976786 -288.841676) (xy 383.984545 -288.891777) (xy 383.985008 -288.917126) (xy 383.9845 -288.943033)
			(xy 383.976394 -288.99421) (xy 383.960382 -289.043489) (xy 383.936859 -289.089656) (xy 383.906403 -289.131575)
			(xy 383.869765 -289.168213) (xy 383.827846 -289.198669) (xy 383.781679 -289.222192) (xy 383.7324 -289.238204)
			(xy 383.681223 -289.24631) (xy 383.629409 -289.24631) (xy 383.578232 -289.238204) (xy 383.528953 -289.222192)
			(xy 383.482786 -289.198669) (xy 383.440867 -289.168213) (xy 383.404229 -289.131575) (xy 383.373773 -289.089656)
			(xy 383.35025 -289.043489) (xy 383.334238 -288.99421) (xy 383.326132 -288.943033) (xy 383.325624 -288.917126)
			(xy 383.326223 -288.889409) (xy 383.335543 -288.834762) (xy 383.344166 -288.808414) (xy 383.35204 -288.786316)
			(xy 383.146808 -288.431224) (xy 383.123948 -288.426906) (xy 383.099127 -288.421739) (xy 383.051348 -288.404784)
			(xy 383.006729 -288.380713) (xy 382.966322 -288.350092) (xy 382.931082 -288.313646) (xy 382.901838 -288.272232)
			(xy 382.879281 -288.226828) (xy 382.863943 -288.178506) (xy 382.856186 -288.128405) (xy 382.855724 -288.103056)
			(xy 382.601724 -288.103056) (xy 382.601226 -288.129705) (xy 382.593283 -288.182409) (xy 382.577573 -288.233339)
			(xy 382.554447 -288.28136) (xy 382.524423 -288.325397) (xy 382.488171 -288.364468) (xy 382.4465 -288.397699)
			(xy 382.400342 -288.424348) (xy 382.350728 -288.44382) (xy 382.298766 -288.45568) (xy 382.245616 -288.459664)
			(xy 382.192466 -288.45568) (xy 382.140504 -288.44382) (xy 382.09089 -288.424348) (xy 382.044732 -288.397699)
			(xy 382.003061 -288.364468) (xy 381.966809 -288.325397) (xy 381.936785 -288.28136) (xy 381.913659 -288.233339)
			(xy 381.897949 -288.182409) (xy 381.890006 -288.129705) (xy 381.661426 -288.129705) (xy 381.653483 -288.182409)
			(xy 381.637773 -288.233339) (xy 381.614647 -288.28136) (xy 381.584623 -288.325397) (xy 381.548371 -288.364468)
			(xy 381.5067 -288.397699) (xy 381.460542 -288.424348) (xy 381.410928 -288.44382) (xy 381.358966 -288.45568)
			(xy 381.305816 -288.459664) (xy 381.252666 -288.45568) (xy 381.200704 -288.44382) (xy 381.15109 -288.424348)
			(xy 381.104932 -288.397699) (xy 381.063261 -288.364468) (xy 381.027009 -288.325397) (xy 380.996985 -288.28136)
			(xy 380.973859 -288.233339) (xy 380.958149 -288.182409) (xy 380.950206 -288.129705) (xy 380.695126 -288.129705)
			(xy 380.695103 -288.130773) (xy 380.685787 -288.185419) (xy 380.677166 -288.211768) (xy 380.669546 -288.233866)
			(xy 380.874524 -288.588958) (xy 380.897384 -288.593276) (xy 380.922206 -288.598437) (xy 380.969984 -288.615395)
			(xy 381.014601 -288.639469) (xy 381.055006 -288.67009) (xy 381.090246 -288.706538) (xy 381.11949 -288.747952)
			(xy 381.142047 -288.793355) (xy 381.157386 -288.841676) (xy 381.165145 -288.891777) (xy 381.165608 -288.917126)
			(xy 381.1651 -288.943033) (xy 381.156994 -288.99421) (xy 381.140982 -289.043489) (xy 381.117459 -289.089656)
			(xy 381.087003 -289.131575) (xy 381.050365 -289.168213) (xy 381.008446 -289.198669) (xy 380.962279 -289.222192)
			(xy 380.913 -289.238204) (xy 380.861823 -289.24631) (xy 380.810009 -289.24631) (xy 380.758832 -289.238204)
			(xy 380.709553 -289.222192) (xy 380.663386 -289.198669) (xy 380.621467 -289.168213) (xy 380.584829 -289.131575)
			(xy 380.554373 -289.089656) (xy 380.53085 -289.043489) (xy 380.514838 -288.99421) (xy 380.506732 -288.943033)
			(xy 380.506224 -288.917126) (xy 380.506823 -288.889409) (xy 380.516143 -288.834762) (xy 380.524766 -288.808414)
			(xy 380.53264 -288.786316) (xy 380.327662 -288.431224) (xy 380.304802 -288.426906) (xy 380.279961 -288.421779)
			(xy 380.232152 -288.40484) (xy 380.187502 -288.380778) (xy 380.147063 -288.350162) (xy 380.111791 -288.313713)
			(xy 380.082517 -288.272293) (xy 380.059933 -288.226877) (xy 380.044571 -288.178538) (xy 380.036794 -288.128417)
			(xy 380.036324 -288.103056) (xy 379.782324 -288.103056) (xy 379.781826 -288.129705) (xy 379.773883 -288.182409)
			(xy 379.758173 -288.233339) (xy 379.735047 -288.28136) (xy 379.705023 -288.325397) (xy 379.668771 -288.364468)
			(xy 379.6271 -288.397699) (xy 379.580942 -288.424348) (xy 379.531328 -288.44382) (xy 379.479366 -288.45568)
			(xy 379.426216 -288.459664) (xy 379.373066 -288.45568) (xy 379.321104 -288.44382) (xy 379.27149 -288.424348)
			(xy 379.225332 -288.397699) (xy 379.183661 -288.364468) (xy 379.147409 -288.325397) (xy 379.117385 -288.28136)
			(xy 379.094259 -288.233339) (xy 379.078549 -288.182409) (xy 379.070606 -288.129705) (xy 378.815526 -288.129705)
			(xy 378.815503 -288.130773) (xy 378.806187 -288.185419) (xy 378.797566 -288.211768) (xy 378.789946 -288.233866)
			(xy 378.994924 -288.588958) (xy 379.017784 -288.593276) (xy 379.042606 -288.598437) (xy 379.090384 -288.615395)
			(xy 379.135001 -288.639469) (xy 379.175406 -288.67009) (xy 379.210646 -288.706538) (xy 379.23989 -288.747952)
			(xy 379.262447 -288.793355) (xy 379.277786 -288.841676) (xy 379.285545 -288.891777) (xy 379.286008 -288.917126)
			(xy 379.2855 -288.943033) (xy 379.277394 -288.99421) (xy 379.261382 -289.043489) (xy 379.237859 -289.089656)
			(xy 379.207403 -289.131575) (xy 379.170765 -289.168213) (xy 379.128846 -289.198669) (xy 379.082679 -289.222192)
			(xy 379.0334 -289.238204) (xy 378.982223 -289.24631) (xy 378.930409 -289.24631) (xy 378.879232 -289.238204)
			(xy 378.829953 -289.222192) (xy 378.783786 -289.198669) (xy 378.741867 -289.168213) (xy 378.705229 -289.131575)
			(xy 378.674773 -289.089656) (xy 378.65125 -289.043489) (xy 378.635238 -288.99421) (xy 378.627132 -288.943033)
			(xy 378.626624 -288.917126) (xy 378.627223 -288.889409) (xy 378.636543 -288.834762) (xy 378.645166 -288.808414)
			(xy 378.65304 -288.786316) (xy 378.448062 -288.431224) (xy 378.425202 -288.426906) (xy 378.400361 -288.421779)
			(xy 378.352552 -288.40484) (xy 378.307902 -288.380778) (xy 378.267463 -288.350162) (xy 378.232191 -288.313713)
			(xy 378.202917 -288.272293) (xy 378.180333 -288.226877) (xy 378.164971 -288.178538) (xy 378.157194 -288.128417)
			(xy 378.156724 -288.103056) (xy 377.902724 -288.103056) (xy 377.902226 -288.129705) (xy 377.894283 -288.182409)
			(xy 377.878573 -288.233339) (xy 377.855447 -288.28136) (xy 377.825423 -288.325397) (xy 377.789171 -288.364468)
			(xy 377.7475 -288.397699) (xy 377.701342 -288.424348) (xy 377.651728 -288.44382) (xy 377.599766 -288.45568)
			(xy 377.546616 -288.459664) (xy 377.493466 -288.45568) (xy 377.441504 -288.44382) (xy 377.39189 -288.424348)
			(xy 377.345732 -288.397699) (xy 377.304061 -288.364468) (xy 377.267809 -288.325397) (xy 377.237785 -288.28136)
			(xy 377.214659 -288.233339) (xy 377.198949 -288.182409) (xy 377.191006 -288.129705) (xy 376.935926 -288.129705)
			(xy 376.935903 -288.130773) (xy 376.926587 -288.185419) (xy 376.917966 -288.211768) (xy 376.910346 -288.233866)
			(xy 377.115324 -288.588958) (xy 377.138184 -288.593276) (xy 377.163006 -288.598437) (xy 377.210784 -288.615395)
			(xy 377.255401 -288.639469) (xy 377.295806 -288.67009) (xy 377.331046 -288.706538) (xy 377.36029 -288.747952)
			(xy 377.382847 -288.793355) (xy 377.398186 -288.841676) (xy 377.405945 -288.891777) (xy 377.406408 -288.917126)
			(xy 377.4059 -288.943033) (xy 377.397794 -288.99421) (xy 377.381782 -289.043489) (xy 377.358259 -289.089656)
			(xy 377.327803 -289.131575) (xy 377.291165 -289.168213) (xy 377.249246 -289.198669) (xy 377.203079 -289.222192)
			(xy 377.1538 -289.238204) (xy 377.102623 -289.24631) (xy 377.050809 -289.24631) (xy 376.999632 -289.238204)
			(xy 376.950353 -289.222192) (xy 376.904186 -289.198669) (xy 376.862267 -289.168213) (xy 376.825629 -289.131575)
			(xy 376.795173 -289.089656) (xy 376.77165 -289.043489) (xy 376.755638 -288.99421) (xy 376.747532 -288.943033)
			(xy 376.747024 -288.917126) (xy 376.747623 -288.889409) (xy 376.756943 -288.834762) (xy 376.765566 -288.808414)
			(xy 376.77344 -288.786316) (xy 376.568462 -288.431224) (xy 376.545602 -288.426906) (xy 376.520761 -288.421779)
			(xy 376.472952 -288.40484) (xy 376.428302 -288.380778) (xy 376.387863 -288.350162) (xy 376.352591 -288.313713)
			(xy 376.323317 -288.272293) (xy 376.300733 -288.226877) (xy 376.285371 -288.178538) (xy 376.277594 -288.128417)
			(xy 376.277124 -288.103056) (xy 376.023124 -288.103056) (xy 376.022626 -288.129705) (xy 376.014683 -288.182409)
			(xy 375.998973 -288.233339) (xy 375.975847 -288.28136) (xy 375.945823 -288.325397) (xy 375.909571 -288.364468)
			(xy 375.8679 -288.397699) (xy 375.821742 -288.424348) (xy 375.772128 -288.44382) (xy 375.720166 -288.45568)
			(xy 375.667016 -288.459664) (xy 375.613866 -288.45568) (xy 375.561904 -288.44382) (xy 375.51229 -288.424348)
			(xy 375.466132 -288.397699) (xy 375.424461 -288.364468) (xy 375.388209 -288.325397) (xy 375.358185 -288.28136)
			(xy 375.335059 -288.233339) (xy 375.319349 -288.182409) (xy 375.311406 -288.129705) (xy 375.056326 -288.129705)
			(xy 375.056303 -288.130773) (xy 375.046987 -288.185419) (xy 375.038366 -288.211768) (xy 375.030746 -288.233866)
			(xy 375.235724 -288.588958) (xy 375.258584 -288.593276) (xy 375.283406 -288.598437) (xy 375.331184 -288.615395)
			(xy 375.375801 -288.639469) (xy 375.416206 -288.67009) (xy 375.451446 -288.706538) (xy 375.48069 -288.747952)
			(xy 375.503247 -288.793355) (xy 375.518586 -288.841676) (xy 375.526345 -288.891777) (xy 375.526808 -288.917126)
			(xy 375.5263 -288.943033) (xy 375.518194 -288.99421) (xy 375.502182 -289.043489) (xy 375.478659 -289.089656)
			(xy 375.448203 -289.131575) (xy 375.411565 -289.168213) (xy 375.369646 -289.198669) (xy 375.323479 -289.222192)
			(xy 375.2742 -289.238204) (xy 375.223023 -289.24631) (xy 375.171209 -289.24631) (xy 375.120032 -289.238204)
			(xy 375.070753 -289.222192) (xy 375.024586 -289.198669) (xy 374.982667 -289.168213) (xy 374.946029 -289.131575)
			(xy 374.915573 -289.089656) (xy 374.89205 -289.043489) (xy 374.876038 -288.99421) (xy 374.867932 -288.943033)
			(xy 374.867424 -288.917126) (xy 374.868023 -288.889409) (xy 374.877343 -288.834762) (xy 374.885966 -288.808414)
			(xy 374.89384 -288.786316) (xy 374.688862 -288.431224) (xy 374.666002 -288.426906) (xy 374.641161 -288.421779)
			(xy 374.593352 -288.40484) (xy 374.548702 -288.380778) (xy 374.508263 -288.350162) (xy 374.472991 -288.313713)
			(xy 374.443717 -288.272293) (xy 374.421133 -288.226877) (xy 374.405771 -288.178538) (xy 374.397994 -288.128417)
			(xy 374.397524 -288.103056) (xy 374.143524 -288.103056) (xy 374.143026 -288.129705) (xy 374.135083 -288.182409)
			(xy 374.119373 -288.233339) (xy 374.096247 -288.28136) (xy 374.066223 -288.325397) (xy 374.029971 -288.364468)
			(xy 373.9883 -288.397699) (xy 373.942142 -288.424348) (xy 373.892528 -288.44382) (xy 373.840566 -288.45568)
			(xy 373.787416 -288.459664) (xy 373.734266 -288.45568) (xy 373.682304 -288.44382) (xy 373.63269 -288.424348)
			(xy 373.586532 -288.397699) (xy 373.544861 -288.364468) (xy 373.508609 -288.325397) (xy 373.478585 -288.28136)
			(xy 373.455459 -288.233339) (xy 373.439749 -288.182409) (xy 373.431806 -288.129705) (xy 373.176726 -288.129705)
			(xy 373.176703 -288.130773) (xy 373.167387 -288.185419) (xy 373.158766 -288.211768) (xy 373.151146 -288.233866)
			(xy 373.356124 -288.588958) (xy 373.378984 -288.593276) (xy 373.403806 -288.598437) (xy 373.451584 -288.615395)
			(xy 373.496201 -288.639469) (xy 373.536606 -288.67009) (xy 373.571846 -288.706538) (xy 373.60109 -288.747952)
			(xy 373.623647 -288.793355) (xy 373.638986 -288.841676) (xy 373.646745 -288.891777) (xy 373.647208 -288.917126)
			(xy 373.6467 -288.943033) (xy 373.638594 -288.99421) (xy 373.622582 -289.043489) (xy 373.599059 -289.089656)
			(xy 373.568603 -289.131575) (xy 373.531965 -289.168213) (xy 373.490046 -289.198669) (xy 373.443879 -289.222192)
			(xy 373.3946 -289.238204) (xy 373.343423 -289.24631) (xy 373.291609 -289.24631) (xy 373.240432 -289.238204)
			(xy 373.191153 -289.222192) (xy 373.144986 -289.198669) (xy 373.103067 -289.168213) (xy 373.066429 -289.131575)
			(xy 373.035973 -289.089656) (xy 373.01245 -289.043489) (xy 372.996438 -288.99421) (xy 372.988332 -288.943033)
			(xy 372.987824 -288.917126) (xy 372.988423 -288.889409) (xy 372.997743 -288.834762) (xy 373.006366 -288.808414)
			(xy 373.01424 -288.786316) (xy 372.809262 -288.431224) (xy 372.786402 -288.426906) (xy 372.761561 -288.421779)
			(xy 372.713752 -288.40484) (xy 372.669102 -288.380778) (xy 372.628663 -288.350162) (xy 372.593391 -288.313713)
			(xy 372.564117 -288.272293) (xy 372.541533 -288.226877) (xy 372.526171 -288.178538) (xy 372.518394 -288.128417)
			(xy 372.517924 -288.103056) (xy 372.263924 -288.103056) (xy 372.263426 -288.129705) (xy 372.255483 -288.182409)
			(xy 372.239773 -288.233339) (xy 372.216647 -288.28136) (xy 372.186623 -288.325397) (xy 372.150371 -288.364468)
			(xy 372.1087 -288.397699) (xy 372.062542 -288.424348) (xy 372.012928 -288.44382) (xy 371.960966 -288.45568)
			(xy 371.907816 -288.459664) (xy 371.854666 -288.45568) (xy 371.802704 -288.44382) (xy 371.75309 -288.424348)
			(xy 371.706932 -288.397699) (xy 371.665261 -288.364468) (xy 371.629009 -288.325397) (xy 371.598985 -288.28136)
			(xy 371.575859 -288.233339) (xy 371.560149 -288.182409) (xy 371.552206 -288.129705) (xy 371.297126 -288.129705)
			(xy 371.297103 -288.130773) (xy 371.287787 -288.185419) (xy 371.279166 -288.211768) (xy 371.271546 -288.233866)
			(xy 371.476524 -288.588958) (xy 371.499384 -288.593276) (xy 371.524206 -288.598437) (xy 371.571984 -288.615395)
			(xy 371.616601 -288.639469) (xy 371.657006 -288.67009) (xy 371.692246 -288.706538) (xy 371.72149 -288.747952)
			(xy 371.744047 -288.793355) (xy 371.759386 -288.841676) (xy 371.767145 -288.891777) (xy 371.767608 -288.917126)
			(xy 371.7671 -288.943033) (xy 371.758994 -288.99421) (xy 371.742982 -289.043489) (xy 371.719459 -289.089656)
			(xy 371.689003 -289.131575) (xy 371.652365 -289.168213) (xy 371.610446 -289.198669) (xy 371.564279 -289.222192)
			(xy 371.515 -289.238204) (xy 371.463823 -289.24631) (xy 371.412009 -289.24631) (xy 371.360832 -289.238204)
			(xy 371.311553 -289.222192) (xy 371.265386 -289.198669) (xy 371.223467 -289.168213) (xy 371.186829 -289.131575)
			(xy 371.156373 -289.089656) (xy 371.13285 -289.043489) (xy 371.116838 -288.99421) (xy 371.108732 -288.943033)
			(xy 371.108224 -288.917126) (xy 371.108823 -288.889409) (xy 371.118143 -288.834762) (xy 371.126766 -288.808414)
			(xy 371.13464 -288.786316) (xy 370.929662 -288.431224) (xy 370.906802 -288.426906) (xy 370.881961 -288.421779)
			(xy 370.834152 -288.40484) (xy 370.789502 -288.380778) (xy 370.749063 -288.350162) (xy 370.713791 -288.313713)
			(xy 370.684517 -288.272293) (xy 370.661933 -288.226877) (xy 370.646571 -288.178538) (xy 370.638794 -288.128417)
			(xy 370.638324 -288.103056) (xy 370.384324 -288.103056) (xy 370.383826 -288.129705) (xy 370.375883 -288.182409)
			(xy 370.360173 -288.233339) (xy 370.337047 -288.28136) (xy 370.307023 -288.325397) (xy 370.270771 -288.364468)
			(xy 370.2291 -288.397699) (xy 370.182942 -288.424348) (xy 370.133328 -288.44382) (xy 370.081366 -288.45568)
			(xy 370.028216 -288.459664) (xy 369.975066 -288.45568) (xy 369.923104 -288.44382) (xy 369.87349 -288.424348)
			(xy 369.827332 -288.397699) (xy 369.785661 -288.364468) (xy 369.749409 -288.325397) (xy 369.719385 -288.28136)
			(xy 369.696259 -288.233339) (xy 369.680549 -288.182409) (xy 369.672606 -288.129705) (xy 369.417526 -288.129705)
			(xy 369.417503 -288.130773) (xy 369.408187 -288.185419) (xy 369.399566 -288.211768) (xy 369.391692 -288.233866)
			(xy 369.596924 -288.588958) (xy 369.619784 -288.593276) (xy 369.644606 -288.598437) (xy 369.692384 -288.615395)
			(xy 369.737001 -288.639469) (xy 369.777406 -288.67009) (xy 369.812646 -288.706538) (xy 369.84189 -288.747952)
			(xy 369.864447 -288.793355) (xy 369.879786 -288.841676) (xy 369.887545 -288.891777) (xy 369.888008 -288.917126)
			(xy 369.8875 -288.943033) (xy 369.879394 -288.99421) (xy 369.863382 -289.043489) (xy 369.839859 -289.089656)
			(xy 369.809403 -289.131575) (xy 369.772765 -289.168213) (xy 369.730846 -289.198669) (xy 369.684679 -289.222192)
			(xy 369.6354 -289.238204) (xy 369.584223 -289.24631) (xy 369.532409 -289.24631) (xy 369.481232 -289.238204)
			(xy 369.431953 -289.222192) (xy 369.385786 -289.198669) (xy 369.343867 -289.168213) (xy 369.307229 -289.131575)
			(xy 369.276773 -289.089656) (xy 369.25325 -289.043489) (xy 369.237238 -288.99421) (xy 369.229132 -288.943033)
			(xy 369.228624 -288.917126) (xy 369.229223 -288.889409) (xy 369.238543 -288.834762) (xy 369.247166 -288.808414)
			(xy 369.25504 -288.786316) (xy 369.049808 -288.431224) (xy 369.026948 -288.426906) (xy 369.002127 -288.421739)
			(xy 368.954348 -288.404784) (xy 368.909729 -288.380713) (xy 368.869322 -288.350092) (xy 368.834082 -288.313646)
			(xy 368.804838 -288.272232) (xy 368.782281 -288.226828) (xy 368.766943 -288.178506) (xy 368.759186 -288.128405)
			(xy 368.758724 -288.103056) (xy 368.50447 -288.103056) (xy 368.503972 -288.129705) (xy 368.496029 -288.182409)
			(xy 368.480319 -288.233339) (xy 368.457193 -288.28136) (xy 368.427169 -288.325397) (xy 368.390917 -288.364468)
			(xy 368.349246 -288.397699) (xy 368.303088 -288.424348) (xy 368.253474 -288.44382) (xy 368.201512 -288.45568)
			(xy 368.148362 -288.459664) (xy 368.095212 -288.45568) (xy 368.04325 -288.44382) (xy 367.993636 -288.424348)
			(xy 367.947478 -288.397699) (xy 367.905807 -288.364468) (xy 367.869555 -288.325397) (xy 367.839531 -288.28136)
			(xy 367.816405 -288.233339) (xy 367.800695 -288.182409) (xy 367.792752 -288.129705) (xy 364.745026 -288.129705)
			(xy 364.737083 -288.182409) (xy 364.721373 -288.233339) (xy 364.698247 -288.28136) (xy 364.668223 -288.325397)
			(xy 364.631971 -288.364468) (xy 364.5903 -288.397699) (xy 364.544142 -288.424348) (xy 364.494528 -288.44382)
			(xy 364.442566 -288.45568) (xy 364.389416 -288.459664) (xy 364.336266 -288.45568) (xy 364.284304 -288.44382)
			(xy 364.23469 -288.424348) (xy 364.188532 -288.397699) (xy 364.146861 -288.364468) (xy 364.110609 -288.325397)
			(xy 364.080585 -288.28136) (xy 364.057459 -288.233339) (xy 364.041749 -288.182409) (xy 364.033806 -288.129705)
			(xy 361.925372 -288.129705) (xy 361.917429 -288.182409) (xy 361.901719 -288.233339) (xy 361.878593 -288.28136)
			(xy 361.848569 -288.325397) (xy 361.812317 -288.364468) (xy 361.770646 -288.397699) (xy 361.724488 -288.424348)
			(xy 361.674874 -288.44382) (xy 361.622912 -288.45568) (xy 361.569762 -288.459664) (xy 361.516612 -288.45568)
			(xy 361.46465 -288.44382) (xy 361.415036 -288.424348) (xy 361.368878 -288.397699) (xy 361.327207 -288.364468)
			(xy 361.290955 -288.325397) (xy 361.260931 -288.28136) (xy 361.237805 -288.233339) (xy 361.222095 -288.182409)
			(xy 361.214152 -288.129705) (xy 353.467413 -288.129705) (xy 353.467391 -288.130876) (xy 353.458742 -288.185839)
			(xy 353.441649 -288.238788) (xy 353.416526 -288.288432) (xy 353.383987 -288.333565) (xy 353.344823 -288.373086)
			(xy 353.299987 -288.406033) (xy 353.250572 -288.431605) (xy 353.224338 -288.440876) (xy 353.213542 -288.473737)
			(xy 353.18838 -288.538175) (xy 353.174046 -288.569654) (xy 353.193704 -288.600736) (xy 353.226525 -288.666551)
			(xy 353.251534 -288.735714) (xy 353.268398 -288.8073) (xy 353.276891 -288.880353) (xy 353.277424 -288.917126)
			(xy 353.277424 -288.943775) (xy 355.105706 -288.943775) (xy 355.105706 -288.890477) (xy 355.113649 -288.837773)
			(xy 355.129359 -288.786843) (xy 355.152485 -288.738822) (xy 355.182509 -288.694785) (xy 355.218761 -288.655714)
			(xy 355.260432 -288.622483) (xy 355.30659 -288.595834) (xy 355.356204 -288.576362) (xy 355.408166 -288.564502)
			(xy 355.461316 -288.560519) (xy 355.514466 -288.564502) (xy 355.566428 -288.576362) (xy 355.616042 -288.595834)
			(xy 355.6622 -288.622483) (xy 355.703871 -288.655714) (xy 355.740123 -288.694785) (xy 355.770147 -288.738822)
			(xy 355.793273 -288.786843) (xy 355.808983 -288.837773) (xy 355.816926 -288.890477) (xy 355.817424 -288.917126)
			(xy 355.816926 -288.943775) (xy 355.808983 -288.996479) (xy 355.801735 -289.019975) (xy 357.925106 -289.019975)
			(xy 357.925106 -288.966677) (xy 357.933049 -288.913973) (xy 357.948759 -288.863043) (xy 357.971885 -288.815022)
			(xy 358.001909 -288.770985) (xy 358.038161 -288.731914) (xy 358.079832 -288.698683) (xy 358.12599 -288.672034)
			(xy 358.175604 -288.652562) (xy 358.227566 -288.640702) (xy 358.280716 -288.636719) (xy 358.333866 -288.640702)
			(xy 358.385828 -288.652562) (xy 358.435442 -288.672034) (xy 358.4816 -288.698683) (xy 358.523271 -288.731914)
			(xy 358.559523 -288.770985) (xy 358.589547 -288.815022) (xy 358.612673 -288.863043) (xy 358.628383 -288.913973)
			(xy 358.632874 -288.943775) (xy 367.323106 -288.943775) (xy 367.323106 -288.890477) (xy 367.331049 -288.837773)
			(xy 367.346759 -288.786843) (xy 367.369885 -288.738822) (xy 367.399909 -288.694785) (xy 367.436161 -288.655714)
			(xy 367.477832 -288.622483) (xy 367.52399 -288.595834) (xy 367.573604 -288.576362) (xy 367.625566 -288.564502)
			(xy 367.678716 -288.560519) (xy 367.731866 -288.564502) (xy 367.783828 -288.576362) (xy 367.833442 -288.595834)
			(xy 367.8796 -288.622483) (xy 367.921271 -288.655714) (xy 367.957523 -288.694785) (xy 367.987547 -288.738822)
			(xy 368.010673 -288.786843) (xy 368.026383 -288.837773) (xy 368.034326 -288.890477) (xy 368.034824 -288.917126)
			(xy 368.034326 -288.943775) (xy 368.026383 -288.996479) (xy 368.010673 -289.047409) (xy 367.987547 -289.09543)
			(xy 367.957523 -289.139467) (xy 367.921271 -289.178538) (xy 367.8796 -289.211769) (xy 367.833442 -289.238418)
			(xy 367.783828 -289.25789) (xy 367.731866 -289.26975) (xy 367.678716 -289.273734) (xy 367.625566 -289.26975)
			(xy 367.573604 -289.25789) (xy 367.52399 -289.238418) (xy 367.477832 -289.211769) (xy 367.436161 -289.178538)
			(xy 367.399909 -289.139467) (xy 367.369885 -289.09543) (xy 367.346759 -289.047409) (xy 367.331049 -288.996479)
			(xy 367.323106 -288.943775) (xy 358.632874 -288.943775) (xy 358.636326 -288.966677) (xy 358.636824 -288.993326)
			(xy 358.636326 -289.019975) (xy 358.628383 -289.072679) (xy 358.612673 -289.123609) (xy 358.589547 -289.17163)
			(xy 358.559523 -289.215667) (xy 358.523271 -289.254738) (xy 358.4816 -289.287969) (xy 358.435442 -289.314618)
			(xy 358.385828 -289.33409) (xy 358.333866 -289.34595) (xy 358.280716 -289.349934) (xy 358.227566 -289.34595)
			(xy 358.175604 -289.33409) (xy 358.12599 -289.314618) (xy 358.079832 -289.287969) (xy 358.038161 -289.254738)
			(xy 358.001909 -289.215667) (xy 357.971885 -289.17163) (xy 357.948759 -289.123609) (xy 357.933049 -289.072679)
			(xy 357.925106 -289.019975) (xy 355.801735 -289.019975) (xy 355.793273 -289.047409) (xy 355.770147 -289.09543)
			(xy 355.740123 -289.139467) (xy 355.703871 -289.178538) (xy 355.6622 -289.211769) (xy 355.616042 -289.238418)
			(xy 355.566428 -289.25789) (xy 355.514466 -289.26975) (xy 355.461316 -289.273734) (xy 355.408166 -289.26975)
			(xy 355.356204 -289.25789) (xy 355.30659 -289.238418) (xy 355.260432 -289.211769) (xy 355.218761 -289.178538)
			(xy 355.182509 -289.139467) (xy 355.152485 -289.09543) (xy 355.129359 -289.047409) (xy 355.113649 -288.996479)
			(xy 355.105706 -288.943775) (xy 353.277424 -288.943775) (xy 353.277424 -289.521138) (xy 353.300176 -289.534932)
			(xy 353.341347 -289.568627) (xy 353.376588 -289.608484) (xy 353.404989 -289.653472) (xy 353.425815 -289.702429)
			(xy 353.438528 -289.75409) (xy 353.4428 -289.807121) (xy 353.440648 -289.833791) (xy 366.852952 -289.833791)
			(xy 366.852952 -289.780493) (xy 366.860895 -289.727789) (xy 366.876605 -289.676859) (xy 366.899731 -289.628838)
			(xy 366.929755 -289.584801) (xy 366.966007 -289.54573) (xy 367.007678 -289.512499) (xy 367.053836 -289.48585)
			(xy 367.10345 -289.466378) (xy 367.155412 -289.454518) (xy 367.208562 -289.450535) (xy 367.261712 -289.454518)
			(xy 367.313674 -289.466378) (xy 367.363288 -289.48585) (xy 367.409446 -289.512499) (xy 367.451117 -289.54573)
			(xy 367.487369 -289.584801) (xy 367.517393 -289.628838) (xy 367.540519 -289.676859) (xy 367.556229 -289.727789)
			(xy 367.564172 -289.780493) (xy 367.56467 -289.807142) (xy 367.818924 -289.807142) (xy 367.819411 -289.781712)
			(xy 367.827244 -289.73146) (xy 367.842699 -289.683005) (xy 367.86541 -289.637498) (xy 367.894839 -289.596018)
			(xy 367.930287 -289.559547) (xy 367.970914 -289.528951) (xy 368.015757 -289.504956) (xy 368.063753 -289.48813)
			(xy 368.088672 -289.483038) (xy 368.112802 -289.478466) (xy 368.327178 -289.073082) (xy 368.317272 -289.050476)
			(xy 368.308309 -289.029398) (xy 368.295664 -288.985377) (xy 368.289249 -288.940026) (xy 368.288824 -288.917126)
			(xy 368.289332 -288.891219) (xy 368.297438 -288.840042) (xy 368.31345 -288.790763) (xy 368.336973 -288.744596)
			(xy 368.367429 -288.702677) (xy 368.404067 -288.666039) (xy 368.445986 -288.635583) (xy 368.492153 -288.61206)
			(xy 368.541432 -288.596048) (xy 368.592609 -288.587942) (xy 368.644423 -288.587942) (xy 368.6956 -288.596048)
			(xy 368.744879 -288.61206) (xy 368.791046 -288.635583) (xy 368.832965 -288.666039) (xy 368.869603 -288.702677)
			(xy 368.900059 -288.744596) (xy 368.923582 -288.790763) (xy 368.939594 -288.840042) (xy 368.9477 -288.891219)
			(xy 368.948208 -288.917126) (xy 368.947753 -288.942575) (xy 368.939949 -288.992871) (xy 368.924499 -289.041367)
			(xy 368.901771 -289.086909) (xy 368.872307 -289.128411) (xy 368.836809 -289.164887) (xy 368.796121 -289.195466)
			(xy 368.751213 -289.21942) (xy 368.703153 -289.23618) (xy 368.678206 -289.24123) (xy 368.654076 -289.245802)
			(xy 368.4397 -289.651186) (xy 368.449606 -289.673792) (xy 368.458528 -289.694877) (xy 368.471078 -289.738907)
			(xy 368.47741 -289.78425) (xy 368.4778 -289.807142) (xy 368.477292 -289.833029) (xy 368.477171 -289.833791)
			(xy 368.732552 -289.833791) (xy 368.732552 -289.780493) (xy 368.740495 -289.727789) (xy 368.756205 -289.676859)
			(xy 368.779331 -289.628838) (xy 368.809355 -289.584801) (xy 368.845607 -289.54573) (xy 368.887278 -289.512499)
			(xy 368.933436 -289.48585) (xy 368.98305 -289.466378) (xy 369.035012 -289.454518) (xy 369.088162 -289.450535)
			(xy 369.141312 -289.454518) (xy 369.193274 -289.466378) (xy 369.242888 -289.48585) (xy 369.289046 -289.512499)
			(xy 369.330717 -289.54573) (xy 369.366969 -289.584801) (xy 369.396993 -289.628838) (xy 369.420119 -289.676859)
			(xy 369.435829 -289.727789) (xy 369.443772 -289.780493) (xy 369.44427 -289.807142) (xy 369.698524 -289.807142)
			(xy 369.699011 -289.781712) (xy 369.706844 -289.73146) (xy 369.722299 -289.683005) (xy 369.74501 -289.637498)
			(xy 369.774439 -289.596018) (xy 369.809887 -289.559547) (xy 369.850514 -289.528951) (xy 369.895357 -289.504956)
			(xy 369.943353 -289.48813) (xy 369.968272 -289.483038) (xy 369.992402 -289.478466) (xy 370.206778 -289.073082)
			(xy 370.196872 -289.050476) (xy 370.187909 -289.029398) (xy 370.175264 -288.985377) (xy 370.168849 -288.940026)
			(xy 370.168424 -288.917126) (xy 370.168932 -288.891219) (xy 370.177038 -288.840042) (xy 370.19305 -288.790763)
			(xy 370.216573 -288.744596) (xy 370.247029 -288.702677) (xy 370.283667 -288.666039) (xy 370.325586 -288.635583)
			(xy 370.371753 -288.61206) (xy 370.421032 -288.596048) (xy 370.472209 -288.587942) (xy 370.524023 -288.587942)
			(xy 370.5752 -288.596048) (xy 370.624479 -288.61206) (xy 370.670646 -288.635583) (xy 370.712565 -288.666039)
			(xy 370.749203 -288.702677) (xy 370.779659 -288.744596) (xy 370.803182 -288.790763) (xy 370.819194 -288.840042)
			(xy 370.8273 -288.891219) (xy 370.827808 -288.917126) (xy 370.827353 -288.942575) (xy 370.819549 -288.992871)
			(xy 370.804099 -289.041367) (xy 370.781371 -289.086909) (xy 370.751907 -289.128411) (xy 370.716409 -289.164887)
			(xy 370.675721 -289.195466) (xy 370.630813 -289.21942) (xy 370.582753 -289.23618) (xy 370.557806 -289.24123)
			(xy 370.533676 -289.245802) (xy 370.3193 -289.651186) (xy 370.329206 -289.673792) (xy 370.338128 -289.694877)
			(xy 370.350678 -289.738907) (xy 370.35701 -289.78425) (xy 370.3574 -289.807142) (xy 370.356892 -289.833029)
			(xy 370.356771 -289.833791) (xy 370.612152 -289.833791) (xy 370.612152 -289.780493) (xy 370.620095 -289.727789)
			(xy 370.635805 -289.676859) (xy 370.658931 -289.628838) (xy 370.688955 -289.584801) (xy 370.725207 -289.54573)
			(xy 370.766878 -289.512499) (xy 370.813036 -289.48585) (xy 370.86265 -289.466378) (xy 370.914612 -289.454518)
			(xy 370.967762 -289.450535) (xy 371.020912 -289.454518) (xy 371.072874 -289.466378) (xy 371.122488 -289.48585)
			(xy 371.168646 -289.512499) (xy 371.210317 -289.54573) (xy 371.246569 -289.584801) (xy 371.276593 -289.628838)
			(xy 371.299719 -289.676859) (xy 371.315429 -289.727789) (xy 371.323372 -289.780493) (xy 371.32387 -289.807142)
			(xy 371.578124 -289.807142) (xy 371.578611 -289.781712) (xy 371.586444 -289.73146) (xy 371.601899 -289.683005)
			(xy 371.62461 -289.637498) (xy 371.654039 -289.596018) (xy 371.689487 -289.559547) (xy 371.730114 -289.528951)
			(xy 371.774957 -289.504956) (xy 371.822953 -289.48813) (xy 371.847872 -289.483038) (xy 371.872002 -289.478466)
			(xy 372.086378 -289.073082) (xy 372.076472 -289.050476) (xy 372.067509 -289.029398) (xy 372.054864 -288.985377)
			(xy 372.048449 -288.940026) (xy 372.048024 -288.917126) (xy 372.048532 -288.891219) (xy 372.056638 -288.840042)
			(xy 372.07265 -288.790763) (xy 372.096173 -288.744596) (xy 372.126629 -288.702677) (xy 372.163267 -288.666039)
			(xy 372.205186 -288.635583) (xy 372.251353 -288.61206) (xy 372.300632 -288.596048) (xy 372.351809 -288.587942)
			(xy 372.403623 -288.587942) (xy 372.4548 -288.596048) (xy 372.504079 -288.61206) (xy 372.550246 -288.635583)
			(xy 372.592165 -288.666039) (xy 372.628803 -288.702677) (xy 372.659259 -288.744596) (xy 372.682782 -288.790763)
			(xy 372.698794 -288.840042) (xy 372.7069 -288.891219) (xy 372.707408 -288.917126) (xy 372.706953 -288.942575)
			(xy 372.699149 -288.992871) (xy 372.683699 -289.041367) (xy 372.660971 -289.086909) (xy 372.631507 -289.128411)
			(xy 372.596009 -289.164887) (xy 372.555321 -289.195466) (xy 372.510413 -289.21942) (xy 372.462353 -289.23618)
			(xy 372.437406 -289.24123) (xy 372.413276 -289.245802) (xy 372.1989 -289.651186) (xy 372.208806 -289.673792)
			(xy 372.217728 -289.694877) (xy 372.230278 -289.738907) (xy 372.23661 -289.78425) (xy 372.237 -289.807142)
			(xy 372.236492 -289.833029) (xy 372.236371 -289.833791) (xy 372.491752 -289.833791) (xy 372.491752 -289.780493)
			(xy 372.499695 -289.727789) (xy 372.515405 -289.676859) (xy 372.538531 -289.628838) (xy 372.568555 -289.584801)
			(xy 372.604807 -289.54573) (xy 372.646478 -289.512499) (xy 372.692636 -289.48585) (xy 372.74225 -289.466378)
			(xy 372.794212 -289.454518) (xy 372.847362 -289.450535) (xy 372.900512 -289.454518) (xy 372.952474 -289.466378)
			(xy 373.002088 -289.48585) (xy 373.048246 -289.512499) (xy 373.089917 -289.54573) (xy 373.126169 -289.584801)
			(xy 373.156193 -289.628838) (xy 373.179319 -289.676859) (xy 373.195029 -289.727789) (xy 373.202972 -289.780493)
			(xy 373.20347 -289.807142) (xy 373.457724 -289.807142) (xy 373.458211 -289.781712) (xy 373.466044 -289.73146)
			(xy 373.481499 -289.683005) (xy 373.50421 -289.637498) (xy 373.533639 -289.596018) (xy 373.569087 -289.559547)
			(xy 373.609714 -289.528951) (xy 373.654557 -289.504956) (xy 373.702553 -289.48813) (xy 373.727472 -289.483038)
			(xy 373.751602 -289.478466) (xy 373.965978 -289.073082) (xy 373.956072 -289.050476) (xy 373.947109 -289.029398)
			(xy 373.934464 -288.985377) (xy 373.928049 -288.940026) (xy 373.927624 -288.917126) (xy 373.928132 -288.891219)
			(xy 373.936238 -288.840042) (xy 373.95225 -288.790763) (xy 373.975773 -288.744596) (xy 374.006229 -288.702677)
			(xy 374.042867 -288.666039) (xy 374.084786 -288.635583) (xy 374.130953 -288.61206) (xy 374.180232 -288.596048)
			(xy 374.231409 -288.587942) (xy 374.283223 -288.587942) (xy 374.3344 -288.596048) (xy 374.383679 -288.61206)
			(xy 374.429846 -288.635583) (xy 374.471765 -288.666039) (xy 374.508403 -288.702677) (xy 374.538859 -288.744596)
			(xy 374.562382 -288.790763) (xy 374.578394 -288.840042) (xy 374.5865 -288.891219) (xy 374.587008 -288.917126)
			(xy 374.586553 -288.942575) (xy 374.578749 -288.992871) (xy 374.563299 -289.041367) (xy 374.540571 -289.086909)
			(xy 374.511107 -289.128411) (xy 374.475609 -289.164887) (xy 374.434921 -289.195466) (xy 374.390013 -289.21942)
			(xy 374.341953 -289.23618) (xy 374.317006 -289.24123) (xy 374.292876 -289.245802) (xy 374.0785 -289.651186)
			(xy 374.088406 -289.673792) (xy 374.097328 -289.694877) (xy 374.109878 -289.738907) (xy 374.11621 -289.78425)
			(xy 374.1166 -289.807142) (xy 374.116092 -289.833029) (xy 374.115971 -289.833791) (xy 374.371352 -289.833791)
			(xy 374.371352 -289.780493) (xy 374.379295 -289.727789) (xy 374.395005 -289.676859) (xy 374.418131 -289.628838)
			(xy 374.448155 -289.584801) (xy 374.484407 -289.54573) (xy 374.526078 -289.512499) (xy 374.572236 -289.48585)
			(xy 374.62185 -289.466378) (xy 374.673812 -289.454518) (xy 374.726962 -289.450535) (xy 374.780112 -289.454518)
			(xy 374.832074 -289.466378) (xy 374.881688 -289.48585) (xy 374.927846 -289.512499) (xy 374.969517 -289.54573)
			(xy 375.005769 -289.584801) (xy 375.035793 -289.628838) (xy 375.058919 -289.676859) (xy 375.074629 -289.727789)
			(xy 375.082572 -289.780493) (xy 375.08307 -289.807142) (xy 375.337324 -289.807142) (xy 375.337811 -289.781712)
			(xy 375.345644 -289.73146) (xy 375.361099 -289.683005) (xy 375.38381 -289.637498) (xy 375.413239 -289.596018)
			(xy 375.448687 -289.559547) (xy 375.489314 -289.528951) (xy 375.534157 -289.504956) (xy 375.582153 -289.48813)
			(xy 375.607072 -289.483038) (xy 375.631202 -289.478466) (xy 375.845578 -289.073082) (xy 375.835672 -289.050476)
			(xy 375.826709 -289.029398) (xy 375.814064 -288.985377) (xy 375.807649 -288.940026) (xy 375.807224 -288.917126)
			(xy 375.807732 -288.891219) (xy 375.815838 -288.840042) (xy 375.83185 -288.790763) (xy 375.855373 -288.744596)
			(xy 375.885829 -288.702677) (xy 375.922467 -288.666039) (xy 375.964386 -288.635583) (xy 376.010553 -288.61206)
			(xy 376.059832 -288.596048) (xy 376.111009 -288.587942) (xy 376.162823 -288.587942) (xy 376.214 -288.596048)
			(xy 376.263279 -288.61206) (xy 376.309446 -288.635583) (xy 376.351365 -288.666039) (xy 376.388003 -288.702677)
			(xy 376.418459 -288.744596) (xy 376.441982 -288.790763) (xy 376.457994 -288.840042) (xy 376.4661 -288.891219)
			(xy 376.466608 -288.917126) (xy 376.466153 -288.942575) (xy 376.458349 -288.992871) (xy 376.442899 -289.041367)
			(xy 376.420171 -289.086909) (xy 376.390707 -289.128411) (xy 376.355209 -289.164887) (xy 376.314521 -289.195466)
			(xy 376.269613 -289.21942) (xy 376.221553 -289.23618) (xy 376.196606 -289.24123) (xy 376.172476 -289.245802)
			(xy 375.9581 -289.651186) (xy 375.968006 -289.673792) (xy 375.976928 -289.694877) (xy 375.989478 -289.738907)
			(xy 375.99581 -289.78425) (xy 375.9962 -289.807142) (xy 375.995692 -289.833029) (xy 375.995571 -289.833791)
			(xy 376.250952 -289.833791) (xy 376.250952 -289.780493) (xy 376.258895 -289.727789) (xy 376.274605 -289.676859)
			(xy 376.297731 -289.628838) (xy 376.327755 -289.584801) (xy 376.364007 -289.54573) (xy 376.405678 -289.512499)
			(xy 376.451836 -289.48585) (xy 376.50145 -289.466378) (xy 376.553412 -289.454518) (xy 376.606562 -289.450535)
			(xy 376.659712 -289.454518) (xy 376.711674 -289.466378) (xy 376.761288 -289.48585) (xy 376.807446 -289.512499)
			(xy 376.849117 -289.54573) (xy 376.885369 -289.584801) (xy 376.915393 -289.628838) (xy 376.938519 -289.676859)
			(xy 376.954229 -289.727789) (xy 376.962172 -289.780493) (xy 376.96267 -289.807142) (xy 377.216924 -289.807142)
			(xy 377.217411 -289.781712) (xy 377.225244 -289.73146) (xy 377.240699 -289.683005) (xy 377.26341 -289.637498)
			(xy 377.292839 -289.596018) (xy 377.328287 -289.559547) (xy 377.368914 -289.528951) (xy 377.413757 -289.504956)
			(xy 377.461753 -289.48813) (xy 377.486672 -289.483038) (xy 377.510802 -289.478466) (xy 377.725178 -289.073082)
			(xy 377.715272 -289.050476) (xy 377.706309 -289.029398) (xy 377.693664 -288.985377) (xy 377.687249 -288.940026)
			(xy 377.686824 -288.917126) (xy 377.687332 -288.891219) (xy 377.695438 -288.840042) (xy 377.71145 -288.790763)
			(xy 377.734973 -288.744596) (xy 377.765429 -288.702677) (xy 377.802067 -288.666039) (xy 377.843986 -288.635583)
			(xy 377.890153 -288.61206) (xy 377.939432 -288.596048) (xy 377.990609 -288.587942) (xy 378.042423 -288.587942)
			(xy 378.0936 -288.596048) (xy 378.142879 -288.61206) (xy 378.189046 -288.635583) (xy 378.230965 -288.666039)
			(xy 378.267603 -288.702677) (xy 378.298059 -288.744596) (xy 378.321582 -288.790763) (xy 378.337594 -288.840042)
			(xy 378.3457 -288.891219) (xy 378.346208 -288.917126) (xy 378.345753 -288.942575) (xy 378.337949 -288.992871)
			(xy 378.322499 -289.041367) (xy 378.299771 -289.086909) (xy 378.270307 -289.128411) (xy 378.234809 -289.164887)
			(xy 378.194121 -289.195466) (xy 378.149213 -289.21942) (xy 378.101153 -289.23618) (xy 378.076206 -289.24123)
			(xy 378.052076 -289.245802) (xy 377.8377 -289.651186) (xy 377.847606 -289.673792) (xy 377.856528 -289.694877)
			(xy 377.869078 -289.738907) (xy 377.87541 -289.78425) (xy 377.8758 -289.807142) (xy 377.875292 -289.833029)
			(xy 377.875171 -289.833791) (xy 378.130552 -289.833791) (xy 378.130552 -289.780493) (xy 378.138495 -289.727789)
			(xy 378.154205 -289.676859) (xy 378.177331 -289.628838) (xy 378.207355 -289.584801) (xy 378.243607 -289.54573)
			(xy 378.285278 -289.512499) (xy 378.331436 -289.48585) (xy 378.38105 -289.466378) (xy 378.433012 -289.454518)
			(xy 378.486162 -289.450535) (xy 378.539312 -289.454518) (xy 378.591274 -289.466378) (xy 378.640888 -289.48585)
			(xy 378.687046 -289.512499) (xy 378.728717 -289.54573) (xy 378.764969 -289.584801) (xy 378.794993 -289.628838)
			(xy 378.818119 -289.676859) (xy 378.833829 -289.727789) (xy 378.841772 -289.780493) (xy 378.84227 -289.807142)
			(xy 379.096524 -289.807142) (xy 379.097011 -289.781712) (xy 379.104844 -289.73146) (xy 379.120299 -289.683005)
			(xy 379.14301 -289.637498) (xy 379.172439 -289.596018) (xy 379.207887 -289.559547) (xy 379.248514 -289.528951)
			(xy 379.293357 -289.504956) (xy 379.341353 -289.48813) (xy 379.366272 -289.483038) (xy 379.390402 -289.478466)
			(xy 379.604778 -289.073082) (xy 379.594872 -289.050476) (xy 379.585909 -289.029398) (xy 379.573264 -288.985377)
			(xy 379.566849 -288.940026) (xy 379.566424 -288.917126) (xy 379.566932 -288.891219) (xy 379.575038 -288.840042)
			(xy 379.59105 -288.790763) (xy 379.614573 -288.744596) (xy 379.645029 -288.702677) (xy 379.681667 -288.666039)
			(xy 379.723586 -288.635583) (xy 379.769753 -288.61206) (xy 379.819032 -288.596048) (xy 379.870209 -288.587942)
			(xy 379.922023 -288.587942) (xy 379.9732 -288.596048) (xy 380.022479 -288.61206) (xy 380.068646 -288.635583)
			(xy 380.110565 -288.666039) (xy 380.147203 -288.702677) (xy 380.177659 -288.744596) (xy 380.201182 -288.790763)
			(xy 380.217194 -288.840042) (xy 380.2253 -288.891219) (xy 380.225808 -288.917126) (xy 380.225353 -288.942575)
			(xy 380.217549 -288.992871) (xy 380.202099 -289.041367) (xy 380.179371 -289.086909) (xy 380.149907 -289.128411)
			(xy 380.114409 -289.164887) (xy 380.073721 -289.195466) (xy 380.028813 -289.21942) (xy 379.980753 -289.23618)
			(xy 379.955806 -289.24123) (xy 379.931676 -289.245802) (xy 379.7173 -289.651186) (xy 379.727206 -289.673792)
			(xy 379.736128 -289.694877) (xy 379.748678 -289.738907) (xy 379.75501 -289.78425) (xy 379.7554 -289.807142)
			(xy 379.754892 -289.833029) (xy 379.754771 -289.833791) (xy 380.010152 -289.833791) (xy 380.010152 -289.780493)
			(xy 380.018095 -289.727789) (xy 380.033805 -289.676859) (xy 380.056931 -289.628838) (xy 380.086955 -289.584801)
			(xy 380.123207 -289.54573) (xy 380.164878 -289.512499) (xy 380.211036 -289.48585) (xy 380.26065 -289.466378)
			(xy 380.312612 -289.454518) (xy 380.365762 -289.450535) (xy 380.418912 -289.454518) (xy 380.470874 -289.466378)
			(xy 380.520488 -289.48585) (xy 380.566646 -289.512499) (xy 380.608317 -289.54573) (xy 380.644569 -289.584801)
			(xy 380.674593 -289.628838) (xy 380.697719 -289.676859) (xy 380.713429 -289.727789) (xy 380.721372 -289.780493)
			(xy 380.72187 -289.807142) (xy 380.976124 -289.807142) (xy 380.976611 -289.781712) (xy 380.984444 -289.73146)
			(xy 380.999899 -289.683005) (xy 381.02261 -289.637498) (xy 381.052039 -289.596018) (xy 381.087487 -289.559547)
			(xy 381.128114 -289.528951) (xy 381.172957 -289.504956) (xy 381.220953 -289.48813) (xy 381.245872 -289.483038)
			(xy 381.270002 -289.478466) (xy 381.484378 -289.073082) (xy 381.474472 -289.050476) (xy 381.465509 -289.029398)
			(xy 381.452864 -288.985377) (xy 381.446449 -288.940026) (xy 381.446024 -288.917126) (xy 381.446532 -288.891219)
			(xy 381.454638 -288.840042) (xy 381.47065 -288.790763) (xy 381.494173 -288.744596) (xy 381.524629 -288.702677)
			(xy 381.561267 -288.666039) (xy 381.603186 -288.635583) (xy 381.649353 -288.61206) (xy 381.698632 -288.596048)
			(xy 381.749809 -288.587942) (xy 381.801623 -288.587942) (xy 381.8528 -288.596048) (xy 381.902079 -288.61206)
			(xy 381.948246 -288.635583) (xy 381.990165 -288.666039) (xy 382.026803 -288.702677) (xy 382.057259 -288.744596)
			(xy 382.080782 -288.790763) (xy 382.096794 -288.840042) (xy 382.1049 -288.891219) (xy 382.105408 -288.917126)
			(xy 382.104953 -288.942575) (xy 382.104767 -288.943775) (xy 382.359906 -288.943775) (xy 382.359906 -288.890477)
			(xy 382.367849 -288.837773) (xy 382.383559 -288.786843) (xy 382.406685 -288.738822) (xy 382.436709 -288.694785)
			(xy 382.472961 -288.655714) (xy 382.514632 -288.622483) (xy 382.56079 -288.595834) (xy 382.610404 -288.576362)
			(xy 382.662366 -288.564502) (xy 382.715516 -288.560519) (xy 382.768666 -288.564502) (xy 382.820628 -288.576362)
			(xy 382.870242 -288.595834) (xy 382.9164 -288.622483) (xy 382.958071 -288.655714) (xy 382.994323 -288.694785)
			(xy 383.024347 -288.738822) (xy 383.047473 -288.786843) (xy 383.063183 -288.837773) (xy 383.071126 -288.890477)
			(xy 383.071624 -288.917126) (xy 383.071126 -288.943775) (xy 383.063183 -288.996479) (xy 383.047473 -289.047409)
			(xy 383.024347 -289.09543) (xy 382.994323 -289.139467) (xy 382.958071 -289.178538) (xy 382.9164 -289.211769)
			(xy 382.870242 -289.238418) (xy 382.820628 -289.25789) (xy 382.768666 -289.26975) (xy 382.715516 -289.273734)
			(xy 382.662366 -289.26975) (xy 382.610404 -289.25789) (xy 382.56079 -289.238418) (xy 382.514632 -289.211769)
			(xy 382.472961 -289.178538) (xy 382.436709 -289.139467) (xy 382.406685 -289.09543) (xy 382.383559 -289.047409)
			(xy 382.367849 -288.996479) (xy 382.359906 -288.943775) (xy 382.104767 -288.943775) (xy 382.097149 -288.992871)
			(xy 382.081699 -289.041367) (xy 382.058971 -289.086909) (xy 382.029507 -289.128411) (xy 381.994009 -289.164887)
			(xy 381.953321 -289.195466) (xy 381.908413 -289.21942) (xy 381.860353 -289.23618) (xy 381.835406 -289.24123)
			(xy 381.811276 -289.245802) (xy 381.5969 -289.651186) (xy 381.606806 -289.673792) (xy 381.615728 -289.694877)
			(xy 381.628278 -289.738907) (xy 381.63461 -289.78425) (xy 381.635 -289.807142) (xy 381.634492 -289.833029)
			(xy 381.626393 -289.884167) (xy 381.610394 -289.933407) (xy 381.586888 -289.979539) (xy 381.556456 -290.021426)
			(xy 381.519846 -290.058036) (xy 381.477959 -290.088468) (xy 381.431827 -290.111974) (xy 381.382587 -290.127973)
			(xy 381.331449 -290.136072) (xy 381.279675 -290.136072) (xy 381.228537 -290.127973) (xy 381.179297 -290.111974)
			(xy 381.133165 -290.088468) (xy 381.091278 -290.058036) (xy 381.054668 -290.021426) (xy 381.024236 -289.979539)
			(xy 381.00073 -289.933407) (xy 380.984731 -289.884167) (xy 380.976632 -289.833029) (xy 380.976124 -289.807142)
			(xy 380.72187 -289.807142) (xy 380.721372 -289.833791) (xy 380.713429 -289.886495) (xy 380.697719 -289.937425)
			(xy 380.674593 -289.985446) (xy 380.644569 -290.029483) (xy 380.608317 -290.068554) (xy 380.566646 -290.101785)
			(xy 380.520488 -290.128434) (xy 380.470874 -290.147906) (xy 380.418912 -290.159766) (xy 380.365762 -290.16375)
			(xy 380.312612 -290.159766) (xy 380.26065 -290.147906) (xy 380.211036 -290.128434) (xy 380.164878 -290.101785)
			(xy 380.123207 -290.068554) (xy 380.086955 -290.029483) (xy 380.056931 -289.985446) (xy 380.033805 -289.937425)
			(xy 380.018095 -289.886495) (xy 380.010152 -289.833791) (xy 379.754771 -289.833791) (xy 379.746793 -289.884167)
			(xy 379.730794 -289.933407) (xy 379.707288 -289.979539) (xy 379.676856 -290.021426) (xy 379.640246 -290.058036)
			(xy 379.598359 -290.088468) (xy 379.552227 -290.111974) (xy 379.502987 -290.127973) (xy 379.451849 -290.136072)
			(xy 379.400075 -290.136072) (xy 379.348937 -290.127973) (xy 379.299697 -290.111974) (xy 379.253565 -290.088468)
			(xy 379.211678 -290.058036) (xy 379.175068 -290.021426) (xy 379.144636 -289.979539) (xy 379.12113 -289.933407)
			(xy 379.105131 -289.884167) (xy 379.097032 -289.833029) (xy 379.096524 -289.807142) (xy 378.84227 -289.807142)
			(xy 378.841772 -289.833791) (xy 378.833829 -289.886495) (xy 378.818119 -289.937425) (xy 378.794993 -289.985446)
			(xy 378.764969 -290.029483) (xy 378.728717 -290.068554) (xy 378.687046 -290.101785) (xy 378.640888 -290.128434)
			(xy 378.591274 -290.147906) (xy 378.539312 -290.159766) (xy 378.486162 -290.16375) (xy 378.433012 -290.159766)
			(xy 378.38105 -290.147906) (xy 378.331436 -290.128434) (xy 378.285278 -290.101785) (xy 378.243607 -290.068554)
			(xy 378.207355 -290.029483) (xy 378.177331 -289.985446) (xy 378.154205 -289.937425) (xy 378.138495 -289.886495)
			(xy 378.130552 -289.833791) (xy 377.875171 -289.833791) (xy 377.867193 -289.884167) (xy 377.851194 -289.933407)
			(xy 377.827688 -289.979539) (xy 377.797256 -290.021426) (xy 377.760646 -290.058036) (xy 377.718759 -290.088468)
			(xy 377.672627 -290.111974) (xy 377.623387 -290.127973) (xy 377.572249 -290.136072) (xy 377.520475 -290.136072)
			(xy 377.469337 -290.127973) (xy 377.420097 -290.111974) (xy 377.373965 -290.088468) (xy 377.332078 -290.058036)
			(xy 377.295468 -290.021426) (xy 377.265036 -289.979539) (xy 377.24153 -289.933407) (xy 377.225531 -289.884167)
			(xy 377.217432 -289.833029) (xy 377.216924 -289.807142) (xy 376.96267 -289.807142) (xy 376.962172 -289.833791)
			(xy 376.954229 -289.886495) (xy 376.938519 -289.937425) (xy 376.915393 -289.985446) (xy 376.885369 -290.029483)
			(xy 376.849117 -290.068554) (xy 376.807446 -290.101785) (xy 376.761288 -290.128434) (xy 376.711674 -290.147906)
			(xy 376.659712 -290.159766) (xy 376.606562 -290.16375) (xy 376.553412 -290.159766) (xy 376.50145 -290.147906)
			(xy 376.451836 -290.128434) (xy 376.405678 -290.101785) (xy 376.364007 -290.068554) (xy 376.327755 -290.029483)
			(xy 376.297731 -289.985446) (xy 376.274605 -289.937425) (xy 376.258895 -289.886495) (xy 376.250952 -289.833791)
			(xy 375.995571 -289.833791) (xy 375.987593 -289.884167) (xy 375.971594 -289.933407) (xy 375.948088 -289.979539)
			(xy 375.917656 -290.021426) (xy 375.881046 -290.058036) (xy 375.839159 -290.088468) (xy 375.793027 -290.111974)
			(xy 375.743787 -290.127973) (xy 375.692649 -290.136072) (xy 375.640875 -290.136072) (xy 375.589737 -290.127973)
			(xy 375.540497 -290.111974) (xy 375.494365 -290.088468) (xy 375.452478 -290.058036) (xy 375.415868 -290.021426)
			(xy 375.385436 -289.979539) (xy 375.36193 -289.933407) (xy 375.345931 -289.884167) (xy 375.337832 -289.833029)
			(xy 375.337324 -289.807142) (xy 375.08307 -289.807142) (xy 375.082572 -289.833791) (xy 375.074629 -289.886495)
			(xy 375.058919 -289.937425) (xy 375.035793 -289.985446) (xy 375.005769 -290.029483) (xy 374.969517 -290.068554)
			(xy 374.927846 -290.101785) (xy 374.881688 -290.128434) (xy 374.832074 -290.147906) (xy 374.780112 -290.159766)
			(xy 374.726962 -290.16375) (xy 374.673812 -290.159766) (xy 374.62185 -290.147906) (xy 374.572236 -290.128434)
			(xy 374.526078 -290.101785) (xy 374.484407 -290.068554) (xy 374.448155 -290.029483) (xy 374.418131 -289.985446)
			(xy 374.395005 -289.937425) (xy 374.379295 -289.886495) (xy 374.371352 -289.833791) (xy 374.115971 -289.833791)
			(xy 374.107993 -289.884167) (xy 374.091994 -289.933407) (xy 374.068488 -289.979539) (xy 374.038056 -290.021426)
			(xy 374.001446 -290.058036) (xy 373.959559 -290.088468) (xy 373.913427 -290.111974) (xy 373.864187 -290.127973)
			(xy 373.813049 -290.136072) (xy 373.761275 -290.136072) (xy 373.710137 -290.127973) (xy 373.660897 -290.111974)
			(xy 373.614765 -290.088468) (xy 373.572878 -290.058036) (xy 373.536268 -290.021426) (xy 373.505836 -289.979539)
			(xy 373.48233 -289.933407) (xy 373.466331 -289.884167) (xy 373.458232 -289.833029) (xy 373.457724 -289.807142)
			(xy 373.20347 -289.807142) (xy 373.202972 -289.833791) (xy 373.195029 -289.886495) (xy 373.179319 -289.937425)
			(xy 373.156193 -289.985446) (xy 373.126169 -290.029483) (xy 373.089917 -290.068554) (xy 373.048246 -290.101785)
			(xy 373.002088 -290.128434) (xy 372.952474 -290.147906) (xy 372.900512 -290.159766) (xy 372.847362 -290.16375)
			(xy 372.794212 -290.159766) (xy 372.74225 -290.147906) (xy 372.692636 -290.128434) (xy 372.646478 -290.101785)
			(xy 372.604807 -290.068554) (xy 372.568555 -290.029483) (xy 372.538531 -289.985446) (xy 372.515405 -289.937425)
			(xy 372.499695 -289.886495) (xy 372.491752 -289.833791) (xy 372.236371 -289.833791) (xy 372.228393 -289.884167)
			(xy 372.212394 -289.933407) (xy 372.188888 -289.979539) (xy 372.158456 -290.021426) (xy 372.121846 -290.058036)
			(xy 372.079959 -290.088468) (xy 372.033827 -290.111974) (xy 371.984587 -290.127973) (xy 371.933449 -290.136072)
			(xy 371.881675 -290.136072) (xy 371.830537 -290.127973) (xy 371.781297 -290.111974) (xy 371.735165 -290.088468)
			(xy 371.693278 -290.058036) (xy 371.656668 -290.021426) (xy 371.626236 -289.979539) (xy 371.60273 -289.933407)
			(xy 371.586731 -289.884167) (xy 371.578632 -289.833029) (xy 371.578124 -289.807142) (xy 371.32387 -289.807142)
			(xy 371.323372 -289.833791) (xy 371.315429 -289.886495) (xy 371.299719 -289.937425) (xy 371.276593 -289.985446)
			(xy 371.246569 -290.029483) (xy 371.210317 -290.068554) (xy 371.168646 -290.101785) (xy 371.122488 -290.128434)
			(xy 371.072874 -290.147906) (xy 371.020912 -290.159766) (xy 370.967762 -290.16375) (xy 370.914612 -290.159766)
			(xy 370.86265 -290.147906) (xy 370.813036 -290.128434) (xy 370.766878 -290.101785) (xy 370.725207 -290.068554)
			(xy 370.688955 -290.029483) (xy 370.658931 -289.985446) (xy 370.635805 -289.937425) (xy 370.620095 -289.886495)
			(xy 370.612152 -289.833791) (xy 370.356771 -289.833791) (xy 370.348793 -289.884167) (xy 370.332794 -289.933407)
			(xy 370.309288 -289.979539) (xy 370.278856 -290.021426) (xy 370.242246 -290.058036) (xy 370.200359 -290.088468)
			(xy 370.154227 -290.111974) (xy 370.104987 -290.127973) (xy 370.053849 -290.136072) (xy 370.002075 -290.136072)
			(xy 369.950937 -290.127973) (xy 369.901697 -290.111974) (xy 369.855565 -290.088468) (xy 369.813678 -290.058036)
			(xy 369.777068 -290.021426) (xy 369.746636 -289.979539) (xy 369.72313 -289.933407) (xy 369.707131 -289.884167)
			(xy 369.699032 -289.833029) (xy 369.698524 -289.807142) (xy 369.44427 -289.807142) (xy 369.443772 -289.833791)
			(xy 369.435829 -289.886495) (xy 369.420119 -289.937425) (xy 369.396993 -289.985446) (xy 369.366969 -290.029483)
			(xy 369.330717 -290.068554) (xy 369.289046 -290.101785) (xy 369.242888 -290.128434) (xy 369.193274 -290.147906)
			(xy 369.141312 -290.159766) (xy 369.088162 -290.16375) (xy 369.035012 -290.159766) (xy 368.98305 -290.147906)
			(xy 368.933436 -290.128434) (xy 368.887278 -290.101785) (xy 368.845607 -290.068554) (xy 368.809355 -290.029483)
			(xy 368.779331 -289.985446) (xy 368.756205 -289.937425) (xy 368.740495 -289.886495) (xy 368.732552 -289.833791)
			(xy 368.477171 -289.833791) (xy 368.469193 -289.884167) (xy 368.453194 -289.933407) (xy 368.429688 -289.979539)
			(xy 368.399256 -290.021426) (xy 368.362646 -290.058036) (xy 368.320759 -290.088468) (xy 368.274627 -290.111974)
			(xy 368.225387 -290.127973) (xy 368.174249 -290.136072) (xy 368.122475 -290.136072) (xy 368.071337 -290.127973)
			(xy 368.022097 -290.111974) (xy 367.975965 -290.088468) (xy 367.934078 -290.058036) (xy 367.897468 -290.021426)
			(xy 367.867036 -289.979539) (xy 367.84353 -289.933407) (xy 367.827531 -289.884167) (xy 367.819432 -289.833029)
			(xy 367.818924 -289.807142) (xy 367.56467 -289.807142) (xy 367.564172 -289.833791) (xy 367.556229 -289.886495)
			(xy 367.540519 -289.937425) (xy 367.517393 -289.985446) (xy 367.487369 -290.029483) (xy 367.451117 -290.068554)
			(xy 367.409446 -290.101785) (xy 367.363288 -290.128434) (xy 367.313674 -290.147906) (xy 367.261712 -290.159766)
			(xy 367.208562 -290.16375) (xy 367.155412 -290.159766) (xy 367.10345 -290.147906) (xy 367.053836 -290.128434)
			(xy 367.007678 -290.101785) (xy 366.966007 -290.068554) (xy 366.929755 -290.029483) (xy 366.899731 -289.985446)
			(xy 366.876605 -289.937425) (xy 366.860895 -289.886495) (xy 366.852952 -289.833791) (xy 353.440648 -289.833791)
			(xy 353.438521 -289.860151) (xy 353.425801 -289.911811) (xy 353.404969 -289.960765) (xy 353.376563 -290.005749)
			(xy 353.341317 -290.045602) (xy 353.300141 -290.079292) (xy 353.277424 -290.093146) (xy 353.277424 -290.218368)
			(xy 353.276944 -290.25403) (xy 353.26896 -290.324906) (xy 353.253088 -290.394441) (xy 353.229528 -290.461761)
			(xy 353.198577 -290.52602) (xy 353.160624 -290.586407) (xy 353.116146 -290.642165) (xy 353.091242 -290.667694)
			(xy 352.95967 -290.799266) (xy 352.934119 -290.824147) (xy 352.878366 -290.868625) (xy 352.817982 -290.906578)
			(xy 352.753727 -290.937529) (xy 352.68641 -290.961088) (xy 352.616877 -290.976958) (xy 352.546004 -290.984941)
			(xy 352.510344 -290.985448) (xy 352.172016 -290.985448) (xy 351.110042 -292.047422) (xy 351.084493 -292.072307)
			(xy 351.028743 -292.116795) (xy 350.968361 -292.154757) (xy 350.904106 -292.185718) (xy 350.836788 -292.209286)
			(xy 350.767254 -292.225165) (xy 350.696378 -292.233156) (xy 350.660716 -292.233604) (xy 332.68412 -292.233604)
			(xy 327.402698 -297.515026) (xy 336.155548 -297.515026) (xy 336.159529 -297.382006) (xy 336.171458 -297.249461)
			(xy 336.191293 -297.117868) (xy 336.218962 -296.987696) (xy 336.254366 -296.859411) (xy 336.297379 -296.733474)
			(xy 336.347846 -296.610335) (xy 336.405587 -296.490434) (xy 336.470396 -296.374201) (xy 336.54204 -296.262051)
			(xy 336.620262 -296.154387) (xy 336.704783 -296.051594) (xy 336.795301 -295.954039) (xy 336.89149 -295.862073)
			(xy 336.993008 -295.776023) (xy 337.099489 -295.696199) (xy 337.210554 -295.622886) (xy 337.325805 -295.556346)
			(xy 337.444829 -295.496817) (xy 337.5672 -295.444513) (xy 337.692479 -295.399621) (xy 337.82022 -295.362302)
			(xy 337.949963 -295.332689) (xy 338.081245 -295.310888) (xy 338.213596 -295.296978) (xy 338.346542 -295.291007)
			(xy 338.479607 -295.292998) (xy 338.612315 -295.302943) (xy 338.744191 -295.320807) (xy 338.874762 -295.346525)
			(xy 339.003562 -295.380006) (xy 339.130128 -295.42113) (xy 339.254009 -295.46975) (xy 339.37476 -295.525691)
			(xy 339.49195 -295.588753) (xy 339.605159 -295.658711) (xy 339.713981 -295.735315) (xy 339.818027 -295.818289)
			(xy 339.916925 -295.907337) (xy 340.01032 -296.00214) (xy 340.097878 -296.102358) (xy 340.179287 -296.207634)
			(xy 340.254253 -296.31759) (xy 340.32251 -296.431832) (xy 340.383812 -296.549952) (xy 340.437941 -296.671527)
			(xy 340.484702 -296.796121) (xy 340.523928 -296.923289) (xy 340.555478 -297.052575) (xy 340.570029 -297.132756)
			(xy 350.597216 -297.132756) (xy 350.597216 -293.122096) (xy 351.287334 -292.432232) (xy 352.763074 -292.432232)
			(xy 353.447604 -293.116508) (xy 353.447604 -297.125136) (xy 353.19208 -297.38066) (xy 356.9462 -297.38066)
			(xy 356.9462 -292.72738) (xy 357.35514 -292.31844) (xy 359.390442 -292.31844) (xy 359.775252 -292.702996)
			(xy 359.775252 -297.384216) (xy 359.709164 -297.450256) (xy 363.309916 -297.450256) (xy 363.309916 -292.662864)
			(xy 363.639354 -292.33368) (xy 365.813594 -292.33368) (xy 366.137952 -292.657784) (xy 366.137952 -297.379136)
			(xy 366.041432 -297.475656) (xy 369.667536 -297.475656) (xy 369.667536 -293.195756) (xy 369.918234 -292.945312)
			(xy 370.982494 -292.945312) (xy 371.215412 -293.177976) (xy 371.215412 -297.389296) (xy 371.089585 -297.515026)
			(xy 379.13565 -297.515026) (xy 379.139631 -297.382006) (xy 379.15156 -297.249461) (xy 379.171395 -297.117868)
			(xy 379.199064 -296.987696) (xy 379.234468 -296.859411) (xy 379.277481 -296.733474) (xy 379.327948 -296.610335)
			(xy 379.385689 -296.490434) (xy 379.450498 -296.374201) (xy 379.522142 -296.262051) (xy 379.600364 -296.154387)
			(xy 379.684885 -296.051594) (xy 379.775403 -295.954039) (xy 379.871592 -295.862073) (xy 379.97311 -295.776023)
			(xy 380.079591 -295.696199) (xy 380.190656 -295.622886) (xy 380.305907 -295.556346) (xy 380.424931 -295.496817)
			(xy 380.547302 -295.444513) (xy 380.672581 -295.399621) (xy 380.800322 -295.362302) (xy 380.930065 -295.332689)
			(xy 381.061347 -295.310888) (xy 381.193698 -295.296978) (xy 381.326644 -295.291007) (xy 381.459709 -295.292998)
			(xy 381.592417 -295.302943) (xy 381.724293 -295.320807) (xy 381.854864 -295.346525) (xy 381.983664 -295.380006)
			(xy 382.11023 -295.42113) (xy 382.234111 -295.46975) (xy 382.354862 -295.525691) (xy 382.472052 -295.588753)
			(xy 382.585261 -295.658711) (xy 382.694083 -295.735315) (xy 382.798129 -295.818289) (xy 382.897027 -295.907337)
			(xy 382.990422 -296.00214) (xy 383.07798 -296.102358) (xy 383.159389 -296.207634) (xy 383.234355 -296.31759)
			(xy 383.302612 -296.431832) (xy 383.363914 -296.549952) (xy 383.418043 -296.671527) (xy 383.464804 -296.796121)
			(xy 383.50403 -296.923289) (xy 383.53558 -297.052575) (xy 383.559343 -297.183516) (xy 383.575232 -297.315644)
			(xy 383.58319 -297.448486) (xy 383.583688 -297.515026) (xy 383.58319 -297.581566) (xy 383.575232 -297.714408)
			(xy 383.559343 -297.846536) (xy 383.53558 -297.977477) (xy 383.50403 -298.106763) (xy 383.464804 -298.233931)
			(xy 383.418043 -298.358525) (xy 383.363914 -298.4801) (xy 383.302612 -298.59822) (xy 383.234355 -298.712462)
			(xy 383.159389 -298.822418) (xy 383.07798 -298.927694) (xy 382.990422 -299.027912) (xy 382.897027 -299.122715)
			(xy 382.798129 -299.211763) (xy 382.694083 -299.294737) (xy 382.585261 -299.371341) (xy 382.472052 -299.441299)
			(xy 382.354862 -299.504361) (xy 382.234111 -299.560302) (xy 382.11023 -299.608922) (xy 381.983664 -299.650046)
			(xy 381.854864 -299.683527) (xy 381.724293 -299.709245) (xy 381.592417 -299.727109) (xy 381.459709 -299.737054)
			(xy 381.326644 -299.739045) (xy 381.193698 -299.733074) (xy 381.061347 -299.719164) (xy 380.930065 -299.697363)
			(xy 380.800322 -299.66775) (xy 380.672581 -299.630431) (xy 380.547302 -299.585539) (xy 380.424931 -299.533235)
			(xy 380.305907 -299.473706) (xy 380.190656 -299.407166) (xy 380.079591 -299.333853) (xy 379.97311 -299.254029)
			(xy 379.871592 -299.167979) (xy 379.775403 -299.076013) (xy 379.684885 -298.978458) (xy 379.600364 -298.875665)
			(xy 379.522142 -298.768001) (xy 379.450498 -298.655851) (xy 379.385689 -298.539618) (xy 379.327948 -298.419717)
			(xy 379.277481 -298.296578) (xy 379.234468 -298.170641) (xy 379.199064 -298.042356) (xy 379.171395 -297.912184)
			(xy 379.15156 -297.780591) (xy 379.139631 -297.648046) (xy 379.13565 -297.515026) (xy 371.089585 -297.515026)
			(xy 370.885974 -297.71848) (xy 369.910614 -297.71848) (xy 369.667536 -297.475656) (xy 366.041432 -297.475656)
			(xy 365.765588 -297.7515) (xy 363.61116 -297.7515) (xy 363.309916 -297.450256) (xy 359.709164 -297.450256)
			(xy 359.422954 -297.73626) (xy 357.302054 -297.73626) (xy 356.9462 -297.38066) (xy 353.19208 -297.38066)
			(xy 353.01174 -297.561) (xy 351.02546 -297.561) (xy 350.597216 -297.132756) (xy 340.570029 -297.132756)
			(xy 340.579241 -297.183516) (xy 340.59513 -297.315644) (xy 340.603088 -297.448486) (xy 340.603586 -297.515026)
			(xy 340.603088 -297.581566) (xy 340.59513 -297.714408) (xy 340.579241 -297.846536) (xy 340.555478 -297.977477)
			(xy 340.523928 -298.106763) (xy 340.484702 -298.233931) (xy 340.437941 -298.358525) (xy 340.383812 -298.4801)
			(xy 340.32251 -298.59822) (xy 340.254253 -298.712462) (xy 340.179287 -298.822418) (xy 340.097878 -298.927694)
			(xy 340.01032 -299.027912) (xy 339.916925 -299.122715) (xy 339.818027 -299.211763) (xy 339.713981 -299.294737)
			(xy 339.605159 -299.371341) (xy 339.49195 -299.441299) (xy 339.37476 -299.504361) (xy 339.254009 -299.560302)
			(xy 339.130128 -299.608922) (xy 339.003562 -299.650046) (xy 338.874762 -299.683527) (xy 338.744191 -299.709245)
			(xy 338.612315 -299.727109) (xy 338.479607 -299.737054) (xy 338.346542 -299.739045) (xy 338.213596 -299.733074)
			(xy 338.081245 -299.719164) (xy 337.949963 -299.697363) (xy 337.82022 -299.66775) (xy 337.692479 -299.630431)
			(xy 337.5672 -299.585539) (xy 337.444829 -299.533235) (xy 337.325805 -299.473706) (xy 337.210554 -299.407166)
			(xy 337.099489 -299.333853) (xy 336.993008 -299.254029) (xy 336.89149 -299.167979) (xy 336.795301 -299.076013)
			(xy 336.704783 -298.978458) (xy 336.620262 -298.875665) (xy 336.54204 -298.768001) (xy 336.470396 -298.655851)
			(xy 336.405587 -298.539618) (xy 336.347846 -298.419717) (xy 336.297379 -298.296578) (xy 336.254366 -298.170641)
			(xy 336.218962 -298.042356) (xy 336.191293 -297.912184) (xy 336.171458 -297.780591) (xy 336.159529 -297.648046)
			(xy 336.155548 -297.515026) (xy 327.402698 -297.515026) (xy 326.991472 -297.926252) (xy 326.991472 -316.45479)
			(xy 345.576144 -316.45479) (xy 345.576144 -314.87999) (xy 345.576536 -314.866611) (xy 345.583474 -314.840769)
			(xy 345.596873 -314.817609) (xy 345.615818 -314.798713) (xy 345.639013 -314.785374) (xy 345.664872 -314.778502)
			(xy 345.678252 -314.778136) (xy 347.253052 -314.778136) (xy 347.266418 -314.778568) (xy 347.292243 -314.785468)
			(xy 347.315406 -314.79881) (xy 347.334332 -314.817688) (xy 347.347733 -314.840817) (xy 347.354698 -314.866625)
			(xy 347.35516 -314.87999) (xy 347.35516 -315.66739) (xy 347.550237 -315.66739) (xy 347.554259 -315.58167)
			(xy 347.56629 -315.496702) (xy 347.586226 -315.413235) (xy 347.613889 -315.332001) (xy 347.649038 -315.253715)
			(xy 347.691364 -315.179064) (xy 347.740493 -315.108705) (xy 347.795996 -315.043255) (xy 347.857383 -314.983291)
			(xy 347.924116 -314.929338) (xy 347.995608 -314.881871) (xy 348.07123 -314.841307) (xy 348.150319 -314.808003)
			(xy 348.232179 -314.782251) (xy 348.31609 -314.764278) (xy 348.401316 -314.754242) (xy 348.487108 -314.75223)
			(xy 348.57271 -314.758261) (xy 348.657372 -314.772281) (xy 348.740349 -314.794167) (xy 348.820912 -314.823728)
			(xy 348.898352 -314.860702) (xy 348.971991 -314.904766) (xy 349.041179 -314.955532) (xy 349.10531 -315.012553)
			(xy 349.163819 -315.075329) (xy 349.216192 -315.143309) (xy 349.26197 -315.215894) (xy 349.30075 -315.292446)
			(xy 349.332191 -315.372294) (xy 349.356017 -315.454735) (xy 349.372018 -315.539045) (xy 349.380053 -315.624483)
			(xy 349.380556 -315.66739) (xy 349.380053 -315.710297) (xy 349.372018 -315.795735) (xy 349.356017 -315.880045)
			(xy 349.332191 -315.962486) (xy 349.30075 -316.042334) (xy 349.26197 -316.118886) (xy 349.216192 -316.191471)
			(xy 349.163819 -316.259451) (xy 349.10531 -316.322227) (xy 349.041179 -316.379248) (xy 348.971991 -316.430014)
			(xy 348.930586 -316.45479) (xy 351.773744 -316.45479) (xy 351.773744 -314.87999) (xy 351.774136 -314.866611)
			(xy 351.781074 -314.840769) (xy 351.794473 -314.817609) (xy 351.813418 -314.798713) (xy 351.836613 -314.785374)
			(xy 351.862472 -314.778502) (xy 351.875852 -314.778136) (xy 353.450652 -314.778136) (xy 353.464018 -314.778568)
			(xy 353.489843 -314.785468) (xy 353.513006 -314.79881) (xy 353.531932 -314.817688) (xy 353.545333 -314.840817)
			(xy 353.552298 -314.866625) (xy 353.55276 -314.87999) (xy 353.55276 -315.66739) (xy 353.747837 -315.66739)
			(xy 353.751859 -315.58167) (xy 353.76389 -315.496702) (xy 353.783826 -315.413235) (xy 353.811489 -315.332001)
			(xy 353.846638 -315.253715) (xy 353.888964 -315.179064) (xy 353.938093 -315.108705) (xy 353.993596 -315.043255)
			(xy 354.054983 -314.983291) (xy 354.121716 -314.929338) (xy 354.193208 -314.881871) (xy 354.26883 -314.841307)
			(xy 354.347919 -314.808003) (xy 354.429779 -314.782251) (xy 354.51369 -314.764278) (xy 354.598916 -314.754242)
			(xy 354.684708 -314.75223) (xy 354.77031 -314.758261) (xy 354.854972 -314.772281) (xy 354.937949 -314.794167)
			(xy 355.018512 -314.823728) (xy 355.095952 -314.860702) (xy 355.169591 -314.904766) (xy 355.238779 -314.955532)
			(xy 355.30291 -315.012553) (xy 355.361419 -315.075329) (xy 355.413792 -315.143309) (xy 355.45957 -315.215894)
			(xy 355.49835 -315.292446) (xy 355.529791 -315.372294) (xy 355.553617 -315.454735) (xy 355.569618 -315.539045)
			(xy 355.577653 -315.624483) (xy 355.578156 -315.66739) (xy 355.577653 -315.710297) (xy 355.569618 -315.795735)
			(xy 355.553617 -315.880045) (xy 355.529791 -315.962486) (xy 355.49835 -316.042334) (xy 355.45957 -316.118886)
			(xy 355.413792 -316.191471) (xy 355.361419 -316.259451) (xy 355.30291 -316.322227) (xy 355.238779 -316.379248)
			(xy 355.169591 -316.430014) (xy 355.128186 -316.45479) (xy 357.951532 -316.45479) (xy 357.951532 -314.87999)
			(xy 357.951936 -314.866612) (xy 357.958873 -314.840772) (xy 357.97227 -314.817613) (xy 357.991212 -314.798718)
			(xy 358.014404 -314.785377) (xy 358.040262 -314.778504) (xy 358.05364 -314.778136) (xy 359.62844 -314.778136)
			(xy 359.64181 -314.778491) (xy 359.667638 -314.785412) (xy 359.690801 -314.798772) (xy 359.709724 -314.817664)
			(xy 359.723123 -314.840804) (xy 359.730086 -314.866621) (xy 359.730548 -314.87999) (xy 359.730548 -315.66739)
			(xy 359.925625 -315.66739) (xy 359.929647 -315.58167) (xy 359.941678 -315.496702) (xy 359.961614 -315.413235)
			(xy 359.989277 -315.332001) (xy 360.024426 -315.253715) (xy 360.066752 -315.179064) (xy 360.115881 -315.108705)
			(xy 360.171384 -315.043255) (xy 360.232771 -314.983291) (xy 360.299504 -314.929338) (xy 360.370996 -314.881871)
			(xy 360.446618 -314.841307) (xy 360.525707 -314.808003) (xy 360.607567 -314.782251) (xy 360.691478 -314.764278)
			(xy 360.776704 -314.754242) (xy 360.862496 -314.75223) (xy 360.948098 -314.758261) (xy 361.03276 -314.772281)
			(xy 361.115737 -314.794167) (xy 361.1963 -314.823728) (xy 361.27374 -314.860702) (xy 361.347379 -314.904766)
			(xy 361.416567 -314.955532) (xy 361.480698 -315.012553) (xy 361.539207 -315.075329) (xy 361.59158 -315.143309)
			(xy 361.637358 -315.215894) (xy 361.676138 -315.292446) (xy 361.707579 -315.372294) (xy 361.731405 -315.454735)
			(xy 361.747406 -315.539045) (xy 361.755441 -315.624483) (xy 361.755944 -315.66739) (xy 361.755441 -315.710297)
			(xy 361.747406 -315.795735) (xy 361.731405 -315.880045) (xy 361.707579 -315.962486) (xy 361.676138 -316.042334)
			(xy 361.637358 -316.118886) (xy 361.59158 -316.191471) (xy 361.539207 -316.259451) (xy 361.480698 -316.322227)
			(xy 361.416567 -316.379248) (xy 361.347379 -316.430014) (xy 361.305974 -316.45479) (xy 364.149132 -316.45479)
			(xy 364.149132 -314.87999) (xy 364.149536 -314.866612) (xy 364.156473 -314.840772) (xy 364.16987 -314.817613)
			(xy 364.188812 -314.798718) (xy 364.212004 -314.785377) (xy 364.237862 -314.778504) (xy 364.25124 -314.778136)
			(xy 365.82604 -314.778136) (xy 365.83941 -314.778491) (xy 365.865238 -314.785412) (xy 365.888401 -314.798772)
			(xy 365.907324 -314.817664) (xy 365.920723 -314.840804) (xy 365.927686 -314.866621) (xy 365.928148 -314.87999)
			(xy 365.928148 -315.66739) (xy 366.123225 -315.66739) (xy 366.127247 -315.58167) (xy 366.139278 -315.496702)
			(xy 366.159214 -315.413235) (xy 366.186877 -315.332001) (xy 366.222026 -315.253715) (xy 366.264352 -315.179064)
			(xy 366.313481 -315.108705) (xy 366.368984 -315.043255) (xy 366.430371 -314.983291) (xy 366.497104 -314.929338)
			(xy 366.568596 -314.881871) (xy 366.644218 -314.841307) (xy 366.723307 -314.808003) (xy 366.805167 -314.782251)
			(xy 366.889078 -314.764278) (xy 366.974304 -314.754242) (xy 367.060096 -314.75223) (xy 367.145698 -314.758261)
			(xy 367.23036 -314.772281) (xy 367.313337 -314.794167) (xy 367.3939 -314.823728) (xy 367.47134 -314.860702)
			(xy 367.544979 -314.904766) (xy 367.614167 -314.955532) (xy 367.678298 -315.012553) (xy 367.736807 -315.075329)
			(xy 367.78918 -315.143309) (xy 367.834958 -315.215894) (xy 367.873738 -315.292446) (xy 367.905179 -315.372294)
			(xy 367.929005 -315.454735) (xy 367.945006 -315.539045) (xy 367.953041 -315.624483) (xy 367.953544 -315.66739)
			(xy 367.953041 -315.710297) (xy 367.945006 -315.795735) (xy 367.929005 -315.880045) (xy 367.905179 -315.962486)
			(xy 367.873738 -316.042334) (xy 367.834958 -316.118886) (xy 367.78918 -316.191471) (xy 367.736807 -316.259451)
			(xy 367.678298 -316.322227) (xy 367.614167 -316.379248) (xy 367.544979 -316.430014) (xy 367.503574 -316.45479)
			(xy 370.346732 -316.45479) (xy 370.346732 -314.87999) (xy 370.347136 -314.866612) (xy 370.354073 -314.840772)
			(xy 370.36747 -314.817613) (xy 370.386412 -314.798718) (xy 370.409604 -314.785377) (xy 370.435462 -314.778504)
			(xy 370.44884 -314.778136) (xy 372.02364 -314.778136) (xy 372.03701 -314.778491) (xy 372.062838 -314.785412)
			(xy 372.086001 -314.798772) (xy 372.104924 -314.817664) (xy 372.118323 -314.840804) (xy 372.125286 -314.866621)
			(xy 372.125748 -314.87999) (xy 372.125748 -315.66739) (xy 372.320825 -315.66739) (xy 372.324847 -315.58167)
			(xy 372.336878 -315.496702) (xy 372.356814 -315.413235) (xy 372.384477 -315.332001) (xy 372.419626 -315.253715)
			(xy 372.461952 -315.179064) (xy 372.511081 -315.108705) (xy 372.566584 -315.043255) (xy 372.627971 -314.983291)
			(xy 372.694704 -314.929338) (xy 372.766196 -314.881871) (xy 372.841818 -314.841307) (xy 372.920907 -314.808003)
			(xy 373.002767 -314.782251) (xy 373.086678 -314.764278) (xy 373.171904 -314.754242) (xy 373.257696 -314.75223)
			(xy 373.343298 -314.758261) (xy 373.42796 -314.772281) (xy 373.510937 -314.794167) (xy 373.5915 -314.823728)
			(xy 373.66894 -314.860702) (xy 373.742579 -314.904766) (xy 373.811767 -314.955532) (xy 373.875898 -315.012553)
			(xy 373.934407 -315.075329) (xy 373.98678 -315.143309) (xy 374.032558 -315.215894) (xy 374.071338 -315.292446)
			(xy 374.102779 -315.372294) (xy 374.126605 -315.454735) (xy 374.142606 -315.539045) (xy 374.150641 -315.624483)
			(xy 374.151144 -315.66739) (xy 374.150641 -315.710297) (xy 374.142606 -315.795735) (xy 374.126605 -315.880045)
			(xy 374.102779 -315.962486) (xy 374.071338 -316.042334) (xy 374.032558 -316.118886) (xy 373.98678 -316.191471)
			(xy 373.934407 -316.259451) (xy 373.875898 -316.322227) (xy 373.811767 -316.379248) (xy 373.742579 -316.430014)
			(xy 373.66894 -316.474078) (xy 373.5915 -316.511052) (xy 373.510937 -316.540613) (xy 373.42796 -316.562499)
			(xy 373.343298 -316.576519) (xy 373.257696 -316.58255) (xy 373.171904 -316.580538) (xy 373.086678 -316.570502)
			(xy 373.002767 -316.552529) (xy 372.920907 -316.526777) (xy 372.841818 -316.493473) (xy 372.766196 -316.452909)
			(xy 372.694704 -316.405442) (xy 372.627971 -316.351489) (xy 372.566584 -316.291525) (xy 372.511081 -316.226075)
			(xy 372.461952 -316.155716) (xy 372.419626 -316.081065) (xy 372.384477 -316.002779) (xy 372.356814 -315.921545)
			(xy 372.336878 -315.838078) (xy 372.324847 -315.75311) (xy 372.320825 -315.66739) (xy 372.125748 -315.66739)
			(xy 372.125748 -316.45479) (xy 372.125346 -316.468168) (xy 372.118412 -316.494011) (xy 372.105015 -316.517172)
			(xy 372.086073 -316.536068) (xy 372.062878 -316.549408) (xy 372.037019 -316.556278) (xy 372.02364 -316.556644)
			(xy 370.44884 -316.556644) (xy 370.43548 -316.55614) (xy 370.409667 -316.549245) (xy 370.386511 -316.535914)
			(xy 370.367588 -316.517051) (xy 370.354182 -316.493939) (xy 370.347204 -316.468148) (xy 370.346732 -316.45479)
			(xy 367.503574 -316.45479) (xy 367.47134 -316.474078) (xy 367.3939 -316.511052) (xy 367.313337 -316.540613)
			(xy 367.23036 -316.562499) (xy 367.145698 -316.576519) (xy 367.060096 -316.58255) (xy 366.974304 -316.580538)
			(xy 366.889078 -316.570502) (xy 366.805167 -316.552529) (xy 366.723307 -316.526777) (xy 366.644218 -316.493473)
			(xy 366.568596 -316.452909) (xy 366.497104 -316.405442) (xy 366.430371 -316.351489) (xy 366.368984 -316.291525)
			(xy 366.313481 -316.226075) (xy 366.264352 -316.155716) (xy 366.222026 -316.081065) (xy 366.186877 -316.002779)
			(xy 366.159214 -315.921545) (xy 366.139278 -315.838078) (xy 366.127247 -315.75311) (xy 366.123225 -315.66739)
			(xy 365.928148 -315.66739) (xy 365.928148 -316.45479) (xy 365.927746 -316.468168) (xy 365.920812 -316.494011)
			(xy 365.907415 -316.517172) (xy 365.888473 -316.536068) (xy 365.865278 -316.549408) (xy 365.839419 -316.556278)
			(xy 365.82604 -316.556644) (xy 364.25124 -316.556644) (xy 364.23788 -316.55614) (xy 364.212067 -316.549245)
			(xy 364.188911 -316.535914) (xy 364.169988 -316.517051) (xy 364.156582 -316.493939) (xy 364.149604 -316.468148)
			(xy 364.149132 -316.45479) (xy 361.305974 -316.45479) (xy 361.27374 -316.474078) (xy 361.1963 -316.511052)
			(xy 361.115737 -316.540613) (xy 361.03276 -316.562499) (xy 360.948098 -316.576519) (xy 360.862496 -316.58255)
			(xy 360.776704 -316.580538) (xy 360.691478 -316.570502) (xy 360.607567 -316.552529) (xy 360.525707 -316.526777)
			(xy 360.446618 -316.493473) (xy 360.370996 -316.452909) (xy 360.299504 -316.405442) (xy 360.232771 -316.351489)
			(xy 360.171384 -316.291525) (xy 360.115881 -316.226075) (xy 360.066752 -316.155716) (xy 360.024426 -316.081065)
			(xy 359.989277 -316.002779) (xy 359.961614 -315.921545) (xy 359.941678 -315.838078) (xy 359.929647 -315.75311)
			(xy 359.925625 -315.66739) (xy 359.730548 -315.66739) (xy 359.730548 -316.45479) (xy 359.730146 -316.468168)
			(xy 359.723212 -316.494011) (xy 359.709815 -316.517172) (xy 359.690873 -316.536068) (xy 359.667678 -316.549408)
			(xy 359.641819 -316.556278) (xy 359.62844 -316.556644) (xy 358.05364 -316.556644) (xy 358.04028 -316.55614)
			(xy 358.014467 -316.549245) (xy 357.991311 -316.535914) (xy 357.972388 -316.517051) (xy 357.958982 -316.493939)
			(xy 357.952004 -316.468148) (xy 357.951532 -316.45479) (xy 355.128186 -316.45479) (xy 355.095952 -316.474078)
			(xy 355.018512 -316.511052) (xy 354.937949 -316.540613) (xy 354.854972 -316.562499) (xy 354.77031 -316.576519)
			(xy 354.684708 -316.58255) (xy 354.598916 -316.580538) (xy 354.51369 -316.570502) (xy 354.429779 -316.552529)
			(xy 354.347919 -316.526777) (xy 354.26883 -316.493473) (xy 354.193208 -316.452909) (xy 354.121716 -316.405442)
			(xy 354.054983 -316.351489) (xy 353.993596 -316.291525) (xy 353.938093 -316.226075) (xy 353.888964 -316.155716)
			(xy 353.846638 -316.081065) (xy 353.811489 -316.002779) (xy 353.783826 -315.921545) (xy 353.76389 -315.838078)
			(xy 353.751859 -315.75311) (xy 353.747837 -315.66739) (xy 353.55276 -315.66739) (xy 353.55276 -316.45479)
			(xy 353.552346 -316.468167) (xy 353.545413 -316.494008) (xy 353.532018 -316.517168) (xy 353.513078 -316.536064)
			(xy 353.489887 -316.549404) (xy 353.46403 -316.556277) (xy 353.450652 -316.556644) (xy 351.875852 -316.556644)
			(xy 351.862489 -316.556217) (xy 351.836672 -316.549302) (xy 351.813517 -316.535953) (xy 351.794595 -316.517076)
			(xy 351.781192 -316.493953) (xy 351.774215 -316.468152) (xy 351.773744 -316.45479) (xy 348.930586 -316.45479)
			(xy 348.898352 -316.474078) (xy 348.820912 -316.511052) (xy 348.740349 -316.540613) (xy 348.657372 -316.562499)
			(xy 348.57271 -316.576519) (xy 348.487108 -316.58255) (xy 348.401316 -316.580538) (xy 348.31609 -316.570502)
			(xy 348.232179 -316.552529) (xy 348.150319 -316.526777) (xy 348.07123 -316.493473) (xy 347.995608 -316.452909)
			(xy 347.924116 -316.405442) (xy 347.857383 -316.351489) (xy 347.795996 -316.291525) (xy 347.740493 -316.226075)
			(xy 347.691364 -316.155716) (xy 347.649038 -316.081065) (xy 347.613889 -316.002779) (xy 347.586226 -315.921545)
			(xy 347.56629 -315.838078) (xy 347.554259 -315.75311) (xy 347.550237 -315.66739) (xy 347.35516 -315.66739)
			(xy 347.35516 -316.45479) (xy 347.354746 -316.468167) (xy 347.347813 -316.494008) (xy 347.334418 -316.517168)
			(xy 347.315478 -316.536064) (xy 347.292287 -316.549404) (xy 347.26643 -316.556277) (xy 347.253052 -316.556644)
			(xy 345.678252 -316.556644) (xy 345.664889 -316.556217) (xy 345.639072 -316.549302) (xy 345.615917 -316.535953)
			(xy 345.596995 -316.517076) (xy 345.583592 -316.493953) (xy 345.576615 -316.468152) (xy 345.576144 -316.45479)
			(xy 326.991472 -316.45479) (xy 326.991472 -331.965046) (xy 326.990958 -332.000629) (xy 326.982975 -332.071346)
			(xy 326.967146 -332.140731) (xy 326.943671 -332.207914) (xy 326.912842 -332.272056) (xy 326.875045 -332.332356)
			(xy 326.853296 -332.360524) (xy 326.853296 -333.510128) (xy 326.983598 -333.64043) (xy 331.890624 -333.64043)
		)
		(stroke
			(width 0)
			(type solid)
		)
		(fill yes)
		(layer "B.Cu")
		(net "PVCCIN_CPU0")
	)
	(gr_poly
		(pts
			(xy 143.088614 -333.648812) (xy 143.098492 -333.648353) (xy 143.116792 -333.640912) (xy 143.124174 -333.634334)
			(xy 143.48968 -333.268828) (xy 143.496256 -333.261445) (xy 143.503696 -333.243146) (xy 143.504158 -333.233268)
			(xy 143.504158 -283.27858) (xy 139.105386 -278.879808) (xy 139.086745 -278.860478) (xy 139.054915 -278.817231)
			(xy 139.029958 -278.769686) (xy 139.012441 -278.718925) (xy 139.007088 -278.69261) (xy 139.004294 -278.69261)
			(xy 138.976311 -278.692061) (xy 138.921035 -278.683305) (xy 138.867808 -278.66601) (xy 138.817943 -278.640601)
			(xy 138.772666 -278.607705) (xy 138.733092 -278.568131) (xy 138.700197 -278.522854) (xy 138.674789 -278.472988)
			(xy 138.657494 -278.419762) (xy 138.648739 -278.364485) (xy 138.648186 -278.336502) (xy 138.644884 -278.3332)
			(xy 138.618446 -278.327578) (xy 138.567537 -278.309423) (xy 138.519951 -278.283793) (xy 138.498072 -278.267922)
			(xy 138.489955 -278.263221) (xy 138.471598 -278.259445) (xy 138.453108 -278.262505) (xy 138.436947 -278.271995)
			(xy 138.425266 -278.286651) (xy 138.41962 -278.304521) (xy 138.41984 -278.313896) (xy 138.420602 -278.336502)
			(xy 138.420096 -278.363582) (xy 138.411895 -278.417116) (xy 138.395681 -278.468792) (xy 138.37183 -278.517416)
			(xy 138.34089 -278.561868) (xy 138.303576 -278.601122) (xy 138.260748 -278.634273) (xy 138.213395 -278.660556)
			(xy 138.162607 -278.679366) (xy 138.109556 -278.690268) (xy 138.055466 -278.693012) (xy 138.001585 -278.687533)
			(xy 137.949155 -278.673958) (xy 137.899385 -278.6526) (xy 137.853423 -278.623952) (xy 137.812329 -278.588674)
			(xy 137.777051 -278.547581) (xy 137.748402 -278.501619) (xy 137.727044 -278.451849) (xy 137.713468 -278.399419)
			(xy 137.707989 -278.345538) (xy 137.710731 -278.291448) (xy 137.721633 -278.238397) (xy 137.740442 -278.187609)
			(xy 137.766725 -278.140255) (xy 137.799876 -278.097427) (xy 137.839129 -278.060112) (xy 137.883581 -278.029172)
			(xy 137.932205 -278.00532) (xy 137.98388 -277.989106) (xy 138.037414 -277.980904) (xy 138.064494 -277.980394)
			(xy 138.065002 -277.980394) (xy 138.097564 -277.98114) (xy 138.161597 -277.993022) (xy 138.192256 -278.004016)
			(xy 138.204859 -278.008416) (xy 138.231402 -278.011176) (xy 138.257753 -278.006964) (xy 138.282114 -277.996069)
			(xy 138.30282 -277.979234) (xy 138.318456 -277.957609) (xy 138.327957 -277.932671) (xy 138.32967 -277.919434)
			(xy 138.333734 -277.890478) (xy 138.336919 -277.874525) (xy 138.345823 -277.843234) (xy 138.351514 -277.827994)
			(xy 138.332451 -277.816205) (xy 138.297166 -277.788563) (xy 138.281156 -277.772876) (xy 136.908032 -277.772876)
			(xy 136.889693 -277.790769) (xy 136.848803 -277.821643) (xy 136.803913 -277.846342) (xy 136.755948 -277.864357)
			(xy 136.705898 -277.875317) (xy 136.654794 -277.878996) (xy 136.60369 -277.875317) (xy 136.55364 -277.864357)
			(xy 136.505675 -277.846342) (xy 136.460785 -277.821643) (xy 136.419895 -277.790769) (xy 136.401556 -277.772876)
			(xy 135.925306 -277.772876) (xy 135.905526 -277.788861) (xy 135.861996 -277.815154) (xy 135.814923 -277.8344)
			(xy 135.765441 -277.846136) (xy 135.71474 -277.850079) (xy 135.664039 -277.846136) (xy 135.614557 -277.8344)
			(xy 135.567484 -277.815154) (xy 135.523954 -277.788861) (xy 135.504174 -277.772876) (xy 134.98576 -277.772876)
			(xy 134.96598 -277.788861) (xy 134.92245 -277.815154) (xy 134.875377 -277.8344) (xy 134.825895 -277.846136)
			(xy 134.775194 -277.850079) (xy 134.724493 -277.846136) (xy 134.675011 -277.8344) (xy 134.627938 -277.815154)
			(xy 134.584408 -277.788861) (xy 134.564628 -277.772876) (xy 134.04596 -277.772876) (xy 134.02618 -277.788861)
			(xy 133.98265 -277.815154) (xy 133.935577 -277.8344) (xy 133.886095 -277.846136) (xy 133.835394 -277.850079)
			(xy 133.784693 -277.846136) (xy 133.735211 -277.8344) (xy 133.688138 -277.815154) (xy 133.644608 -277.788861)
			(xy 133.624828 -277.772876) (xy 133.10616 -277.772876) (xy 133.08638 -277.788861) (xy 133.04285 -277.815154)
			(xy 132.995777 -277.8344) (xy 132.946295 -277.846136) (xy 132.895594 -277.850079) (xy 132.844893 -277.846136)
			(xy 132.795411 -277.8344) (xy 132.748338 -277.815154) (xy 132.704808 -277.788861) (xy 132.685028 -277.772876)
			(xy 132.209032 -277.772876) (xy 132.190693 -277.790769) (xy 132.149803 -277.821643) (xy 132.104913 -277.846342)
			(xy 132.056948 -277.864357) (xy 132.006898 -277.875317) (xy 131.955794 -277.878996) (xy 131.90469 -277.875317)
			(xy 131.85464 -277.864357) (xy 131.806675 -277.846342) (xy 131.761785 -277.821643) (xy 131.720895 -277.790769)
			(xy 131.702556 -277.772876) (xy 131.269486 -277.772876) (xy 131.251147 -277.790769) (xy 131.210257 -277.821643)
			(xy 131.165367 -277.846342) (xy 131.117402 -277.864357) (xy 131.067352 -277.875317) (xy 131.016248 -277.878996)
			(xy 130.965144 -277.875317) (xy 130.915094 -277.864357) (xy 130.867129 -277.846342) (xy 130.822239 -277.821643)
			(xy 130.781349 -277.790769) (xy 130.76301 -277.772876) (xy 130.329686 -277.772876) (xy 130.311347 -277.790769)
			(xy 130.270457 -277.821643) (xy 130.225567 -277.846342) (xy 130.177602 -277.864357) (xy 130.127552 -277.875317)
			(xy 130.076448 -277.878996) (xy 130.025344 -277.875317) (xy 129.975294 -277.864357) (xy 129.927329 -277.846342)
			(xy 129.882439 -277.821643) (xy 129.841549 -277.790769) (xy 129.82321 -277.772876) (xy 129.34696 -277.772876)
			(xy 129.32718 -277.788861) (xy 129.28365 -277.815154) (xy 129.236577 -277.8344) (xy 129.187095 -277.846136)
			(xy 129.136394 -277.850079) (xy 129.085693 -277.846136) (xy 129.036211 -277.8344) (xy 128.989138 -277.815154)
			(xy 128.945608 -277.788861) (xy 128.925828 -277.772876) (xy 128.40716 -277.772876) (xy 128.38738 -277.788861)
			(xy 128.34385 -277.815154) (xy 128.296777 -277.8344) (xy 128.247295 -277.846136) (xy 128.196594 -277.850079)
			(xy 128.145893 -277.846136) (xy 128.096411 -277.8344) (xy 128.049338 -277.815154) (xy 128.005808 -277.788861)
			(xy 127.986028 -277.772876) (xy 127.46736 -277.772876) (xy 127.44758 -277.788861) (xy 127.40405 -277.815154)
			(xy 127.356977 -277.8344) (xy 127.307495 -277.846136) (xy 127.256794 -277.850079) (xy 127.206093 -277.846136)
			(xy 127.156611 -277.8344) (xy 127.109538 -277.815154) (xy 127.066008 -277.788861) (xy 127.046228 -277.772876)
			(xy 126.52756 -277.772876) (xy 126.50778 -277.788861) (xy 126.46425 -277.815154) (xy 126.417177 -277.8344)
			(xy 126.367695 -277.846136) (xy 126.316994 -277.850079) (xy 126.266293 -277.846136) (xy 126.216811 -277.8344)
			(xy 126.169738 -277.815154) (xy 126.126208 -277.788861) (xy 126.106428 -277.772876) (xy 125.630686 -277.772876)
			(xy 125.612347 -277.790769) (xy 125.571457 -277.821643) (xy 125.526567 -277.846342) (xy 125.478602 -277.864357)
			(xy 125.428552 -277.875317) (xy 125.377448 -277.878996) (xy 125.326344 -277.875317) (xy 125.276294 -277.864357)
			(xy 125.228329 -277.846342) (xy 125.183439 -277.821643) (xy 125.142549 -277.790769) (xy 125.12421 -277.772876)
			(xy 124.690632 -277.772876) (xy 124.672293 -277.790769) (xy 124.631403 -277.821643) (xy 124.586513 -277.846342)
			(xy 124.538548 -277.864357) (xy 124.488498 -277.875317) (xy 124.437394 -277.878996) (xy 124.38629 -277.875317)
			(xy 124.33624 -277.864357) (xy 124.288275 -277.846342) (xy 124.243385 -277.821643) (xy 124.202495 -277.790769)
			(xy 124.184156 -277.772876) (xy 123.750832 -277.772876) (xy 123.732493 -277.790769) (xy 123.691603 -277.821643)
			(xy 123.646713 -277.846342) (xy 123.598748 -277.864357) (xy 123.548698 -277.875317) (xy 123.497594 -277.878996)
			(xy 123.44649 -277.875317) (xy 123.39644 -277.864357) (xy 123.348475 -277.846342) (xy 123.303585 -277.821643)
			(xy 123.262695 -277.790769) (xy 123.244356 -277.772876) (xy 122.811032 -277.772876) (xy 122.7927 -277.790729)
			(xy 122.751837 -277.821529) (xy 122.706988 -277.846168) (xy 122.659076 -277.864138) (xy 122.609087 -277.87507)
			(xy 122.558048 -277.878739) (xy 122.507009 -277.87507) (xy 122.45702 -277.864138) (xy 122.409108 -277.846168)
			(xy 122.364259 -277.821529) (xy 122.323396 -277.790729) (xy 122.305064 -277.772876) (xy 121.871232 -277.772876)
			(xy 121.8529 -277.790729) (xy 121.812037 -277.821529) (xy 121.767188 -277.846168) (xy 121.719276 -277.864138)
			(xy 121.669287 -277.87507) (xy 121.618248 -277.878739) (xy 121.567209 -277.87507) (xy 121.51722 -277.864138)
			(xy 121.469308 -277.846168) (xy 121.424459 -277.821529) (xy 121.383596 -277.790729) (xy 121.365264 -277.772876)
			(xy 120.931432 -277.772876) (xy 120.9131 -277.790729) (xy 120.872237 -277.821529) (xy 120.827388 -277.846168)
			(xy 120.779476 -277.864138) (xy 120.729487 -277.87507) (xy 120.678448 -277.878739) (xy 120.627409 -277.87507)
			(xy 120.57742 -277.864138) (xy 120.529508 -277.846168) (xy 120.484659 -277.821529) (xy 120.443796 -277.790729)
			(xy 120.425464 -277.772876) (xy 119.991632 -277.772876) (xy 119.9733 -277.790729) (xy 119.932437 -277.821529)
			(xy 119.887588 -277.846168) (xy 119.839676 -277.864138) (xy 119.789687 -277.87507) (xy 119.738648 -277.878739)
			(xy 119.687609 -277.87507) (xy 119.63762 -277.864138) (xy 119.589708 -277.846168) (xy 119.544859 -277.821529)
			(xy 119.503996 -277.790729) (xy 119.485664 -277.772876) (xy 119.052086 -277.772876) (xy 119.033747 -277.790769)
			(xy 118.992857 -277.821643) (xy 118.947967 -277.846342) (xy 118.900002 -277.864357) (xy 118.849952 -277.875317)
			(xy 118.798848 -277.878996) (xy 118.747744 -277.875317) (xy 118.697694 -277.864357) (xy 118.649729 -277.846342)
			(xy 118.604839 -277.821643) (xy 118.563949 -277.790769) (xy 118.54561 -277.772876) (xy 118.25351 -277.772876)
			(xy 118.243748 -277.764024) (xy 118.220752 -277.751174) (xy 118.195235 -277.744628) (xy 118.168893 -277.744819)
			(xy 118.143474 -277.751735) (xy 118.120666 -277.764917) (xy 118.111016 -277.773892) (xy 118.090826 -277.7933)
			(xy 118.045517 -277.826213) (xy 117.995619 -277.851635) (xy 117.942359 -277.868941) (xy 117.887048 -277.877706)
			(xy 117.859048 -277.878286) (xy 117.831061 -277.877769) (xy 117.775775 -277.869019) (xy 117.722538 -277.851727)
			(xy 117.672663 -277.826319) (xy 117.627377 -277.793421) (xy 117.587796 -277.753843) (xy 117.554894 -277.708559)
			(xy 117.529483 -277.658686) (xy 117.512187 -277.605451) (xy 117.503433 -277.550165) (xy 117.50294 -277.522178)
			(xy 117.50347 -277.494455) (xy 117.512066 -277.439679) (xy 117.529047 -277.386896) (xy 117.554002 -277.337383)
			(xy 117.586328 -277.292335) (xy 117.625245 -277.252841) (xy 117.647212 -277.23592) (xy 117.647212 -277.13813)
			(xy 117.646741 -277.124187) (xy 117.639126 -277.097358) (xy 117.624537 -277.073589) (xy 117.604063 -277.054653)
			(xy 117.57923 -277.041961) (xy 117.55189 -277.036459) (xy 117.52408 -277.038558) (xy 117.510814 -277.04288)
			(xy 117.481348 -277.052961) (xy 117.42003 -277.063823) (xy 117.388894 -277.06447) (xy 117.362248 -277.063972)
			(xy 117.309551 -277.056028) (xy 117.258626 -277.040319) (xy 117.210612 -277.017196) (xy 117.16658 -276.987175)
			(xy 117.127514 -276.950926) (xy 117.094288 -276.909261) (xy 117.067642 -276.863108) (xy 117.048172 -276.813499)
			(xy 117.036313 -276.761543) (xy 117.032331 -276.7084) (xy 117.036313 -276.655257) (xy 117.048172 -276.603301)
			(xy 117.067642 -276.553692) (xy 117.094288 -276.507539) (xy 117.127514 -276.465874) (xy 117.16658 -276.429625)
			(xy 117.210612 -276.399604) (xy 117.258626 -276.376481) (xy 117.309551 -276.360772) (xy 117.362248 -276.352828)
			(xy 117.388894 -276.352254) (xy 117.420025 -276.352956) (xy 117.481336 -276.363809) (xy 117.510814 -276.373844)
			(xy 117.524067 -276.378212) (xy 117.551884 -276.380314) (xy 117.579231 -276.374811) (xy 117.604069 -276.362111)
			(xy 117.624542 -276.343163) (xy 117.639123 -276.319381) (xy 117.646724 -276.292541) (xy 117.647212 -276.278594)
			(xy 117.647212 -276.181312) (xy 117.625209 -276.164389) (xy 117.58623 -276.124871) (xy 117.55385 -276.079786)
			(xy 117.528855 -276.030226) (xy 117.511847 -275.977389) (xy 117.503239 -275.922553) (xy 117.503239 -275.867047)
			(xy 117.511847 -275.812211) (xy 117.528855 -275.759374) (xy 117.55385 -275.709814) (xy 117.58623 -275.664729)
			(xy 117.625209 -275.625211) (xy 117.647212 -275.608288) (xy 117.647212 -275.39442) (xy 117.5639 -275.39442)
			(xy 117.55374 -275.396706) (xy 117.547644 -275.399754) (xy 117.522887 -275.411476) (xy 117.47067 -275.428018)
			(xy 117.416536 -275.436368) (xy 117.389148 -275.436838) (xy 117.361761 -275.436355) (xy 117.307627 -275.428009)
			(xy 117.255409 -275.411475) (xy 117.230652 -275.399754) (xy 117.224556 -275.396706) (xy 117.214396 -275.39442)
			(xy 116.623846 -275.39442) (xy 116.613686 -275.396706) (xy 116.60759 -275.399754) (xy 116.582832 -275.411472)
			(xy 116.530615 -275.428006) (xy 116.476481 -275.436348) (xy 116.449094 -275.436838) (xy 116.421708 -275.436351)
			(xy 116.367577 -275.427997) (xy 116.315363 -275.411457) (xy 116.290598 -275.399754) (xy 116.284502 -275.396706)
			(xy 116.274342 -275.39442) (xy 115.6843 -275.39442) (xy 115.673632 -275.39696) (xy 115.66779 -275.399754)
			(xy 115.643071 -275.411456) (xy 115.590938 -275.427977) (xy 115.536892 -275.436332) (xy 115.509548 -275.436838)
			(xy 115.50904 -275.436838) (xy 115.48362 -275.436381) (xy 115.433296 -275.429143) (xy 115.384514 -275.414821)
			(xy 115.338264 -275.393708) (xy 115.295487 -275.366231) (xy 115.257052 -275.332951) (xy 115.223741 -275.294543)
			(xy 115.19623 -275.251788) (xy 115.175079 -275.205555) (xy 115.16741 -275.181314) (xy 115.162838 -275.16582)
			(xy 115.114578 -275.127974) (xy 115.112546 -275.127974) (xy 115.095274 -275.129244) (xy 115.063029 -275.13105)
			(xy 114.998445 -275.130416) (xy 114.966242 -275.127974) (xy 114.954661 -275.128182) (xy 114.933568 -275.137692)
			(xy 114.918781 -275.155488) (xy 114.915442 -275.166582) (xy 114.908654 -275.191972) (xy 114.88863 -275.240564)
			(xy 114.86168 -275.285684) (xy 114.82839 -275.326353) (xy 114.789484 -275.361685) (xy 114.745806 -275.390914)
			(xy 114.698305 -275.413404) (xy 114.648014 -275.428667) (xy 114.596026 -275.436371) (xy 114.569748 -275.436838)
			(xy 114.56924 -275.436838) (xy 114.54382 -275.436381) (xy 114.493496 -275.429143) (xy 114.444714 -275.414821)
			(xy 114.398464 -275.393708) (xy 114.355687 -275.366231) (xy 114.317252 -275.332951) (xy 114.283941 -275.294543)
			(xy 114.25643 -275.251788) (xy 114.235279 -275.205555) (xy 114.22761 -275.181314) (xy 114.223038 -275.16582)
			(xy 114.174778 -275.127974) (xy 114.172746 -275.127974) (xy 114.155474 -275.129244) (xy 114.123166 -275.131043)
			(xy 114.058455 -275.130408) (xy 114.026188 -275.127974) (xy 114.014601 -275.128173) (xy 113.99349 -275.137673)
			(xy 113.978687 -275.155472) (xy 113.975388 -275.166582) (xy 113.968599 -275.191971) (xy 113.948574 -275.240558)
			(xy 113.921623 -275.285674) (xy 113.888333 -275.326337) (xy 113.849425 -275.361664) (xy 113.805747 -275.390887)
			(xy 113.758246 -275.413371) (xy 113.707957 -275.428626) (xy 113.655971 -275.436323) (xy 113.629694 -275.436838)
			(xy 113.60171 -275.436289) (xy 113.546432 -275.427533) (xy 113.493204 -275.410238) (xy 113.443336 -275.38483)
			(xy 113.398057 -275.351935) (xy 113.358481 -275.312361) (xy 113.325582 -275.267084) (xy 113.300171 -275.217218)
			(xy 113.282873 -275.163991) (xy 113.274113 -275.108714) (xy 113.273586 -275.08073) (xy 113.274114 -275.052978)
			(xy 113.282718 -274.998146) (xy 113.299723 -274.945312) (xy 113.324717 -274.895754) (xy 113.357094 -274.850673)
			(xy 113.376202 -274.83054) (xy 113.38306 -274.823682) (xy 113.3983 -274.787614) (xy 113.389156 -274.758912)
			(xy 113.385092 -274.752816) (xy 113.362049 -274.718012) (xy 113.322007 -274.644767) (xy 113.28921 -274.568004)
			(xy 113.263965 -274.488438) (xy 113.246506 -274.406808) (xy 113.236996 -274.323876) (xy 113.23574 -274.282154)
			(xy 113.23574 -274.251674) (xy 113.236945 -274.209947) (xy 113.24643 -274.127005) (xy 113.263877 -274.045366)
			(xy 113.289123 -273.965792) (xy 113.321933 -273.889027) (xy 113.362 -273.815787) (xy 113.385092 -273.781012)
			(xy 113.389156 -273.774916) (xy 113.3983 -273.746214) (xy 113.38306 -273.710146) (xy 113.376202 -273.703288)
			(xy 113.359518 -273.685762) (xy 113.330547 -273.647004) (xy 113.30708 -273.604686) (xy 113.289547 -273.559585)
			(xy 113.283492 -273.536156) (xy 113.27747 -273.508847) (xy 113.273082 -273.453098) (xy 113.27747 -273.397349)
			(xy 113.283492 -273.37004) (xy 113.289506 -273.346598) (xy 113.307022 -273.301483) (xy 113.330494 -273.25916)
			(xy 113.359488 -273.220411) (xy 113.376202 -273.202908) (xy 113.38306 -273.19605) (xy 113.3983 -273.159982)
			(xy 113.389156 -273.13128) (xy 113.385092 -273.125184) (xy 113.362047 -273.090381) (xy 113.321998 -273.017137)
			(xy 113.289196 -272.940375) (xy 113.263944 -272.860808) (xy 113.246479 -272.779179) (xy 113.236962 -272.696246)
			(xy 113.23574 -272.654522) (xy 113.23574 -272.610834) (xy 113.237528 -272.570209) (xy 113.247798 -272.489537)
			(xy 113.265604 -272.410187) (xy 113.29079 -272.332862) (xy 113.323131 -272.258246) (xy 113.362342 -272.187001)
			(xy 113.384838 -272.153126) (xy 113.389156 -272.14703) (xy 113.398046 -272.118328) (xy 113.382806 -272.082006)
			(xy 113.382552 -272.081752) (xy 113.362322 -272.061452) (xy 113.327966 -272.015585) (xy 113.301396 -271.96481)
			(xy 113.283297 -271.910436) (xy 113.274137 -271.853866) (xy 113.273586 -271.825212) (xy 113.274116 -271.797461)
			(xy 113.282722 -271.74263) (xy 113.299729 -271.689797) (xy 113.324724 -271.640242) (xy 113.357103 -271.595163)
			(xy 113.376202 -271.575022) (xy 113.38306 -271.568164) (xy 113.3983 -271.532096) (xy 113.389156 -271.503394)
			(xy 113.385092 -271.497298) (xy 113.362046 -271.462495) (xy 113.321997 -271.389252) (xy 113.289193 -271.312489)
			(xy 113.26394 -271.232923) (xy 113.246473 -271.151293) (xy 113.236955 -271.06836) (xy 113.23574 -271.026636)
			(xy 113.23574 -271.011396) (xy 113.235204 -270.998966) (xy 113.227163 -270.975438) (xy 113.212025 -270.955714)
			(xy 113.201958 -270.948404) (xy 113.198656 -270.946372) (xy 113.19764 -270.945864) (xy 113.162852 -270.925236)
			(xy 113.096891 -270.878425) (xy 113.035595 -270.825654) (xy 112.9795 -270.767382) (xy 112.929099 -270.704123)
			(xy 112.884833 -270.636428) (xy 112.847089 -270.564892) (xy 112.816197 -270.49014) (xy 112.79243 -270.412828)
			(xy 112.775994 -270.333632) (xy 112.767033 -270.253247) (xy 112.76584 -270.21282) (xy 112.76584 -270.169132)
			(xy 112.767382 -270.133755) (xy 112.775543 -270.06341) (xy 112.789441 -269.993971) (xy 112.79886 -269.959836)
			(xy 112.810682 -269.920296) (xy 112.840858 -269.843476) (xy 112.878213 -269.76988) (xy 112.922409 -269.700176)
			(xy 112.973042 -269.634999) (xy 113.029652 -269.57494) (xy 113.091726 -269.520546) (xy 113.158698 -269.472311)
			(xy 113.194084 -269.451074) (xy 113.194846 -269.45082) (xy 113.19764 -269.449042) (xy 113.197894 -269.449042)
			(xy 113.204498 -269.445232) (xy 113.213902 -269.437774) (xy 113.22795 -269.418331) (xy 113.235318 -269.395504)
			(xy 113.23574 -269.38351) (xy 113.236243 -269.341963) (xy 113.244239 -269.259255) (xy 113.260139 -269.177696)
			(xy 113.283796 -269.098041) (xy 113.314992 -269.021025) (xy 113.333784 -268.983968) (xy 113.345561 -268.961732)
			(xy 113.371359 -268.918524) (xy 113.385346 -268.897608) (xy 113.38941 -268.891512) (xy 113.3983 -268.863064)
			(xy 113.38306 -268.826742) (xy 113.382806 -268.826488) (xy 113.36255 -268.806169) (xy 113.328145 -268.760259)
			(xy 113.301531 -268.709436) (xy 113.283392 -268.655008) (xy 113.274197 -268.598379) (xy 113.273586 -268.569694)
			(xy 113.274135 -268.541711) (xy 113.282891 -268.486434) (xy 113.300186 -268.433208) (xy 113.325594 -268.383342)
			(xy 113.358491 -268.338064) (xy 113.398064 -268.298491) (xy 113.443342 -268.265594) (xy 113.493208 -268.240186)
			(xy 113.546434 -268.222891) (xy 113.601711 -268.214135) (xy 113.629694 -268.213586) (xy 113.642437 -268.213684)
			(xy 113.667861 -268.215465) (xy 113.680494 -268.217142) (xy 113.70556 -268.221212) (xy 113.754282 -268.235524)
			(xy 113.800479 -268.256606) (xy 113.843217 -268.284032) (xy 113.881629 -268.317246) (xy 113.914938 -268.355575)
			(xy 113.94247 -268.398245) (xy 113.963666 -268.44439) (xy 113.971324 -268.468602) (xy 113.975896 -268.48435)
			(xy 114.024664 -268.52245) (xy 114.026696 -268.52245) (xy 114.043968 -268.52118) (xy 114.076276 -268.519382)
			(xy 114.140987 -268.520021) (xy 114.173254 -268.52245) (xy 114.184837 -268.522243) (xy 114.205936 -268.512736)
			(xy 114.220732 -268.494942) (xy 114.224054 -268.483842) (xy 114.230841 -268.45845) (xy 114.250862 -268.409855)
			(xy 114.27781 -268.364732) (xy 114.3111 -268.324061) (xy 114.350006 -268.288725) (xy 114.393685 -268.259494)
			(xy 114.441187 -268.237001) (xy 114.491479 -268.221736) (xy 114.543469 -268.214031) (xy 114.569748 -268.213586)
			(xy 114.595123 -268.214071) (xy 114.645353 -268.221333) (xy 114.669824 -268.228064) (xy 114.68089 -268.230253)
			(xy 114.703 -268.225927) (xy 114.721144 -268.212572) (xy 114.726974 -268.202918) (xy 114.74178 -268.172062)
			(xy 114.775602 -268.112555) (xy 114.794538 -268.084046) (xy 114.798856 -268.07795) (xy 114.808 -268.048994)
			(xy 114.79276 -268.012926) (xy 114.785902 -268.006068) (xy 114.772953 -267.99257) (xy 114.749661 -267.9633)
			(xy 114.73942 -267.947648) (xy 114.724882 -267.923953) (xy 114.70255 -267.873048) (xy 114.69497 -267.846302)
			(xy 114.693446 -267.841476) (xy 114.644678 -267.803376) (xy 114.625374 -267.804646) (xy 114.513868 -267.804646)
			(xy 114.494564 -267.803376) (xy 114.445796 -267.841476) (xy 114.441224 -267.85697) (xy 114.433568 -267.88119)
			(xy 114.412349 -267.927342) (xy 114.384792 -267.970013) (xy 114.351455 -268.008338) (xy 114.313013 -268.041541)
			(xy 114.270246 -268.068949) (xy 114.22402 -268.090005) (xy 114.175273 -268.104285) (xy 114.124992 -268.111497)
			(xy 114.099594 -268.111986) (xy 114.07161 -268.111465) (xy 114.01633 -268.102708) (xy 113.963101 -268.085412)
			(xy 113.913233 -268.060001) (xy 113.867955 -268.027102) (xy 113.82838 -267.987524) (xy 113.795485 -267.942243)
			(xy 113.770078 -267.892373) (xy 113.752785 -267.839143) (xy 113.744033 -267.783862) (xy 113.743486 -267.755878)
			(xy 113.744018 -267.728128) (xy 113.752629 -267.6733) (xy 113.76964 -267.62047) (xy 113.794638 -267.570919)
			(xy 113.827019 -267.525843) (xy 113.846102 -267.505688) (xy 113.85296 -267.49883) (xy 113.8682 -267.462762)
			(xy 113.859056 -267.43406) (xy 113.85677 -267.430504) (xy 113.837557 -267.401895) (xy 113.803224 -267.342134)
			(xy 113.78819 -267.311124) (xy 113.787174 -267.309092) (xy 113.785904 -267.306806) (xy 113.782602 -267.30198)
			(xy 113.776067 -267.294159) (xy 113.758391 -267.284051) (xy 113.738173 -267.281625) (xy 113.728246 -267.283946)
			(xy 113.704132 -267.29047) (xy 113.654671 -267.297476) (xy 113.629694 -267.297916) (xy 113.603044 -267.297418)
			(xy 113.550341 -267.289473) (xy 113.499409 -267.273762) (xy 113.451389 -267.250636) (xy 113.407351 -267.220611)
			(xy 113.36828 -267.184358) (xy 113.335049 -267.142687) (xy 113.3084 -267.096528) (xy 113.288928 -267.046913)
			(xy 113.277068 -266.99495) (xy 113.273084 -266.9418) (xy 113.277068 -266.88865) (xy 113.288928 -266.836687)
			(xy 113.3084 -266.787072) (xy 113.335049 -266.740913) (xy 113.36828 -266.699242) (xy 113.407351 -266.662989)
			(xy 113.451389 -266.632964) (xy 113.499409 -266.609838) (xy 113.550341 -266.594127) (xy 113.603044 -266.586182)
			(xy 113.629694 -266.5857) (xy 113.629948 -266.5857) (xy 113.655323 -266.586185) (xy 113.705553 -266.593447)
			(xy 113.730024 -266.600178) (xy 113.741087 -266.602369) (xy 113.763191 -266.598039) (xy 113.78132 -266.584671)
			(xy 113.787174 -266.575032) (xy 113.80198 -266.544175) (xy 113.835801 -266.484668) (xy 113.854738 -266.45616)
			(xy 113.859056 -266.450064) (xy 113.867946 -266.421362) (xy 113.852706 -266.38504) (xy 113.852452 -266.384786)
			(xy 113.832226 -266.364485) (xy 113.797878 -266.318616) (xy 113.771318 -266.26784) (xy 113.753229 -266.213466)
			(xy 113.744079 -266.156898) (xy 113.743486 -266.128246) (xy 113.744003 -266.100258) (xy 113.752753 -266.044971)
			(xy 113.770044 -265.991733) (xy 113.795452 -265.941855) (xy 113.82835 -265.896567) (xy 113.867928 -265.856984)
			(xy 113.913211 -265.824079) (xy 113.963084 -265.798664) (xy 114.01632 -265.781365) (xy 114.071606 -265.772607)
			(xy 114.099594 -265.772138) (xy 114.124969 -265.772626) (xy 114.175197 -265.779893) (xy 114.19967 -265.786616)
			(xy 114.211012 -265.788911) (xy 114.233641 -265.784193) (xy 114.251918 -265.77004) (xy 114.257582 -265.759946)
			(xy 114.262662 -265.749532) (xy 114.277326 -265.720135) (xy 114.310509 -265.663431) (xy 114.328956 -265.636248)
			(xy 114.33379 -265.628669) (xy 114.338327 -265.611284) (xy 114.336602 -265.593401) (xy 114.328827 -265.577204)
			(xy 114.322606 -265.570716) (xy 114.302339 -265.550435) (xy 114.267914 -265.504589) (xy 114.241285 -265.453817)
			(xy 114.223141 -265.399432) (xy 114.213952 -265.342842) (xy 114.213386 -265.314176) (xy 114.213937 -265.286194)
			(xy 114.222695 -265.230919) (xy 114.239991 -265.177695) (xy 114.265401 -265.127832) (xy 114.298297 -265.082557)
			(xy 114.337871 -265.042985) (xy 114.383147 -265.010091) (xy 114.433012 -264.984684) (xy 114.486237 -264.967391)
			(xy 114.541512 -264.958635) (xy 114.569494 -264.958068) (xy 114.569748 -264.958068) (xy 114.595123 -264.958552)
			(xy 114.645353 -264.965815) (xy 114.669824 -264.972546) (xy 114.68105 -264.974736) (xy 114.703441 -264.970227)
			(xy 114.721698 -264.956502) (xy 114.727482 -264.946638) (xy 114.745008 -264.911332) (xy 114.757282 -264.888408)
			(xy 114.784226 -264.843928) (xy 114.798856 -264.822432) (xy 114.808 -264.793476) (xy 114.79276 -264.757408)
			(xy 114.785902 -264.75055) (xy 114.766794 -264.730417) (xy 114.734422 -264.685333) (xy 114.70943 -264.635775)
			(xy 114.692422 -264.582942) (xy 114.683809 -264.528111) (xy 114.683286 -264.50036) (xy 114.683838 -264.472379)
			(xy 114.692598 -264.417106) (xy 114.709896 -264.363884) (xy 114.735306 -264.314023) (xy 114.768203 -264.26875)
			(xy 114.807776 -264.229181) (xy 114.853052 -264.196288) (xy 114.902915 -264.170883) (xy 114.956139 -264.15359)
			(xy 115.011413 -264.144835) (xy 115.039394 -264.144252) (xy 115.039902 -264.144252) (xy 115.063331 -264.144643)
			(xy 115.109782 -264.15082) (xy 115.155023 -264.16303) (xy 115.198274 -264.18106) (xy 115.218718 -264.192512)
			(xy 115.218972 -264.192766) (xy 115.23091 -264.199624) (xy 115.258088 -264.199878) (xy 115.34648 -264.149332)
			(xy 115.352636 -264.145498) (xy 115.362688 -264.135052) (xy 115.366292 -264.128758) (xy 115.367562 -264.125964)
			(xy 115.369567 -264.121124) (xy 115.371748 -264.110881) (xy 115.37188 -264.105644) (xy 115.37188 -264.033)
			(xy 115.363244 -264.018776) (xy 115.354862 -264.0076) (xy 115.351814 -264.006076) (xy 115.344448 -264.002266)
			(xy 115.321726 -263.989866) (xy 115.279804 -263.959502) (xy 115.242717 -263.923391) (xy 115.211247 -263.882293)
			(xy 115.186054 -263.837074) (xy 115.167669 -263.788686) (xy 115.156481 -263.738147) (xy 115.152723 -263.68652)
			(xy 115.156475 -263.634894) (xy 115.167658 -263.584353) (xy 115.186037 -263.535963) (xy 115.211224 -263.490741)
			(xy 115.24269 -263.44964) (xy 115.279773 -263.413525) (xy 115.321691 -263.383156) (xy 115.344448 -263.370822)
			(xy 115.351814 -263.367012) (xy 115.354862 -263.365488) (xy 115.363244 -263.354312) (xy 115.37188 -263.340088)
			(xy 115.37188 -260.364732) (xy 115.371393 -260.35477) (xy 115.363803 -260.336348) (xy 115.357148 -260.328918)
			(xy 114.971068 -259.942838) (xy 114.964224 -259.93544) (xy 114.956501 -259.91684) (xy 114.956082 -259.90677)
			(xy 114.956082 -258.199128) (xy 114.962432 -258.192524) (xy 114.962432 -258.191) (xy 115.272058 -257.881374)
			(xy 115.292886 -257.872992) (xy 117.198648 -257.872992) (xy 117.21719 -257.865372) (xy 117.221508 -257.861054)
			(xy 117.221508 -257.670046) (xy 117.221024 -257.660083) (xy 117.21344 -257.641654) (xy 117.206776 -257.634232)
			(xy 117.155976 -257.583432) (xy 117.148605 -257.57669) (xy 117.130143 -257.569102) (xy 117.120162 -257.5687)
			(xy 115.690142 -257.5687) (xy 115.680077 -257.568266) (xy 115.661487 -257.560537) (xy 115.654074 -257.553714)
			(xy 115.616482 -257.516122) (xy 115.606322 -257.516122) (xy 115.386866 -257.296666) (xy 115.380018 -257.289269)
			(xy 115.372285 -257.27067) (xy 115.37188 -257.260598) (xy 115.37188 -256.997962) (xy 115.371399 -256.987998)
			(xy 115.363816 -256.969568) (xy 115.357148 -256.962148) (xy 115.022376 -256.627376) (xy 115.016994 -256.621554)
			(xy 115.00976 -256.607455) (xy 115.008152 -256.59969) (xy 115.005358 -256.587752) (xy 114.966242 -256.548636)
			(xy 114.959401 -256.541236) (xy 114.951683 -256.522637) (xy 114.951256 -256.512568) (xy 114.951256 -255.592072)
			(xy 114.951686 -255.582005) (xy 114.959414 -255.563414) (xy 114.966242 -255.556004) (xy 115.00739 -255.514856)
			(xy 115.00739 -255.5113) (xy 115.184936 -255.333754) (xy 115.209574 -255.32334) (xy 115.496086 -255.32334)
			(xy 115.505104 -255.323696) (xy 115.522028 -255.329934) (xy 115.529106 -255.335532) (xy 115.59413 -255.391412)
			(xy 115.596924 -255.393952) (xy 115.621816 -255.418844) (xy 115.629229 -255.425521) (xy 115.647664 -255.43309)
			(xy 115.65763 -255.433576) (xy 120.51665 -255.433576) (xy 120.527064 -255.423162) (xy 120.527064 -253.971298)
			(xy 120.526661 -253.962017) (xy 120.520015 -253.944688) (xy 120.51411 -253.937516) (xy 120.50268 -253.925832)
			(xy 120.432068 -253.85522) (xy 120.425536 -253.849192) (xy 120.409401 -253.841765) (xy 120.400572 -253.840742)
			(xy 120.398032 -253.840488) (xy 119.039894 -253.840488) (xy 119.030658 -253.841399) (xy 119.013724 -253.848957)
			(xy 119.006874 -253.85522) (xy 118.977156 -253.884938) (xy 118.970482 -253.892352) (xy 118.962921 -253.910787)
			(xy 118.962424 -253.920752) (xy 118.962424 -254.135128) (xy 118.961996 -254.145196) (xy 118.954278 -254.163796)
			(xy 118.947438 -254.171196) (xy 118.917212 -254.201422) (xy 118.917212 -254.211582) (xy 118.885462 -254.243332)
			(xy 118.80596 -254.32258) (xy 118.72722 -254.40132) (xy 118.72595 -254.40132) (xy 118.69547 -254.4318)
			(xy 118.686834 -254.4318) (xy 118.649242 -254.469646) (xy 118.641843 -254.476489) (xy 118.623244 -254.484211)
			(xy 118.613174 -254.484632) (xy 117.566186 -254.484632) (xy 117.556116 -254.484207) (xy 117.537512 -254.476493)
			(xy 117.530118 -254.469646) (xy 117.507512 -254.446786) (xy 117.500118 -254.439928) (xy 117.481519 -254.432176)
			(xy 117.471444 -254.4318) (xy 117.446552 -254.4318) (xy 117.436486 -254.431368) (xy 117.417894 -254.423641)
			(xy 117.410484 -254.416814) (xy 117.267736 -254.274066) (xy 117.260891 -254.266667) (xy 117.253163 -254.248069)
			(xy 117.25275 -254.237998) (xy 117.25275 -254.192024) (xy 117.249956 -254.18923) (xy 117.249956 -253.996952)
			(xy 117.249472 -253.986989) (xy 117.241884 -253.968564) (xy 117.235224 -253.961138) (xy 117.126004 -253.851918)
			(xy 117.118596 -253.845231) (xy 117.100159 -253.837645) (xy 117.09019 -253.837186) (xy 115.733576 -253.837186)
			(xy 115.731544 -253.835408) (xy 115.664742 -253.835408) (xy 115.654676 -253.834975) (xy 115.636086 -253.827246)
			(xy 115.628674 -253.820422) (xy 114.981482 -253.172976) (xy 114.97463 -253.16558) (xy 114.966892 -253.146981)
			(xy 114.966496 -253.136908) (xy 114.966496 -252.005592) (xy 114.97691 -251.979684) (xy 114.97691 -251.943362)
			(xy 114.97734 -251.933295) (xy 114.985066 -251.914702) (xy 114.991896 -251.907294) (xy 115.082828 -251.816362)
			(xy 115.090225 -251.809513) (xy 115.108824 -251.801779) (xy 115.118896 -251.801376) (xy 115.1382 -251.801376)
			(xy 115.148078 -251.800919) (xy 115.166379 -251.793477) (xy 115.17376 -251.786898) (xy 115.19662 -251.764038)
			(xy 115.204018 -251.75719) (xy 115.222616 -251.749457) (xy 115.232688 -251.749052) (xy 115.730274 -251.749052)
			(xy 115.735354 -251.754132) (xy 120.499124 -251.754132) (xy 120.509131 -251.75364) (xy 120.52762 -251.745978)
			(xy 120.541773 -251.731827) (xy 120.549439 -251.713339) (xy 120.549924 -251.703332) (xy 120.549924 -250.43003)
			(xy 120.549438 -250.420068) (xy 120.541852 -250.401642) (xy 120.535192 -250.394216) (xy 120.534938 -250.393962)
			(xy 120.339866 -250.199144) (xy 120.32869 -250.188476) (xy 120.321516 -250.182552) (xy 120.304198 -250.17579)
			(xy 120.294908 -250.175268) (xy 119.085868 -250.175268) (xy 119.084598 -250.175522) (xy 119.075644 -250.176503)
			(xy 119.059248 -250.183928) (xy 119.052594 -250.19) (xy 118.903496 -250.339098) (xy 118.896812 -250.346508)
			(xy 118.88923 -250.364944) (xy 118.888764 -250.374912) (xy 118.888764 -250.552712) (xy 118.888338 -250.56278)
			(xy 118.880616 -250.581378) (xy 118.873778 -250.58878) (xy 118.695216 -250.767342) (xy 118.687816 -250.774181)
			(xy 118.669217 -250.781894) (xy 118.659148 -250.782328) (xy 117.549422 -250.782328) (xy 117.539638 -250.781876)
			(xy 117.521491 -250.774551) (xy 117.514116 -250.768104) (xy 117.507004 -250.761246) (xy 117.48897 -250.75388)
			(xy 117.398292 -250.75388) (xy 117.388223 -250.753455) (xy 117.369622 -250.745736) (xy 117.362224 -250.738894)
			(xy 117.277896 -250.654566) (xy 117.271055 -250.647165) (xy 117.263334 -250.628567) (xy 117.26291 -250.618498)
			(xy 117.26291 -250.53798) (xy 117.262432 -250.528014) (xy 117.254857 -250.509577) (xy 117.248178 -250.502166)
			(xy 117.242336 -250.496324) (xy 117.242336 -250.306332) (xy 117.24185 -250.296369) (xy 117.234266 -250.277942)
			(xy 117.227604 -250.270518) (xy 117.126004 -250.168918) (xy 117.118596 -250.162231) (xy 117.100159 -250.154645)
			(xy 117.09019 -250.154186) (xy 115.511326 -250.154186) (xy 115.501262 -250.153749) (xy 115.482678 -250.146014)
			(xy 115.475258 -250.1392) (xy 114.958876 -249.622818) (xy 114.952498 -249.615873) (xy 114.944809 -249.598674)
			(xy 114.94389 -249.58929) (xy 114.942366 -249.57278) (xy 114.928142 -249.558556) (xy 114.921298 -249.551157)
			(xy 114.913573 -249.532558) (xy 114.913156 -249.522488) (xy 114.913156 -248.411492) (xy 114.913582 -248.401424)
			(xy 114.921305 -248.382827) (xy 114.928142 -248.375424) (xy 114.929158 -248.374408) (xy 114.935508 -248.366788)
			(xy 114.936524 -248.364756) (xy 114.939914 -248.358751) (xy 114.943656 -248.345485) (xy 114.94389 -248.338594)
			(xy 114.94389 -248.336562) (xy 114.94432 -248.326495) (xy 114.952043 -248.307899) (xy 114.958876 -248.300494)
			(xy 115.094004 -248.165366) (xy 115.101399 -248.158513) (xy 115.119998 -248.150769) (xy 115.130072 -248.15038)
			(xy 115.14201 -248.15038) (xy 115.16106 -248.142252) (xy 115.795044 -248.142252) (xy 115.795044 -248.14276)
			(xy 118.8339 -248.14276) (xy 118.843969 -248.142336) (xy 118.86257 -248.134617) (xy 118.869968 -248.127774)
			(xy 118.873778 -248.123964) (xy 118.881398 -248.105422) (xy 118.881398 -247.266714) (xy 118.880908 -247.256753)
			(xy 118.873315 -247.238334) (xy 118.866666 -247.2309) (xy 118.762272 -247.126506) (xy 118.720362 -247.126506)
			(xy 118.712996 -247.133872) (xy 117.675406 -247.133872) (xy 117.665336 -247.133449) (xy 117.646732 -247.125733)
			(xy 117.639338 -247.118886) (xy 117.629432 -247.108726) (xy 117.622031 -247.101888) (xy 117.603433 -247.094174)
			(xy 117.593364 -247.09374) (xy 117.58803 -247.09374) (xy 117.389656 -246.895366) (xy 117.383431 -246.888624)
			(xy 117.375766 -246.871965) (xy 117.37467 -246.862854) (xy 117.374162 -246.856758) (xy 117.364256 -246.832628)
			(xy 117.364256 -246.580152) (xy 117.363772 -246.570189) (xy 117.356184 -246.551764) (xy 117.349524 -246.544338)
			(xy 117.28958 -246.484394) (xy 117.282169 -246.477713) (xy 117.263733 -246.470139) (xy 117.253766 -246.469662)
			(xy 115.575334 -246.469662) (xy 115.56527 -246.469226) (xy 115.546686 -246.461491) (xy 115.539266 -246.454676)
			(xy 114.989356 -245.904766) (xy 114.982509 -245.897368) (xy 114.974778 -245.87877) (xy 114.97437 -245.868698)
			(xy 114.97437 -245.859046) (xy 114.973885 -245.849083) (xy 114.966298 -245.830659) (xy 114.959638 -245.823232)
			(xy 114.95913 -245.822724) (xy 114.952292 -245.815323) (xy 114.944581 -245.796724) (xy 114.944144 -245.786656)
			(xy 114.944144 -244.613176) (xy 114.944573 -244.603109) (xy 114.952298 -244.584515) (xy 114.95913 -244.577108)
			(xy 114.959892 -244.576346) (xy 114.96647 -244.568963) (xy 114.973914 -244.550664) (xy 114.97437 -244.540786)
			(xy 114.97437 -244.518434) (xy 114.974873 -244.508382) (xy 114.98259 -244.489818) (xy 114.989356 -244.482366)
			(xy 115.124484 -244.347238) (xy 115.131885 -244.340401) (xy 115.150484 -244.332691) (xy 115.160552 -244.332252)
			(xy 115.183158 -244.332252) (xy 115.192883 -244.331777) (xy 115.210916 -244.324476) (xy 115.21821 -244.318028)
			(xy 115.22456 -244.311424) (xy 115.577112 -244.311424) (xy 115.587139 -244.311873) (xy 115.605697 -244.319465)
			(xy 115.61318 -244.326156) (xy 115.707922 -244.420898) (xy 115.714357 -244.426516) (xy 115.72993 -244.433514)
			(xy 115.738402 -244.434614) (xy 115.740942 -244.434868) (xy 120.46966 -244.434868) (xy 120.479684 -244.434455)
			(xy 120.498209 -244.426791) (xy 120.512386 -244.412616) (xy 120.520053 -244.394092) (xy 120.52046 -244.384068)
			(xy 120.52046 -243.620544) (xy 120.520895 -243.61048) (xy 120.52863 -243.591896) (xy 120.535446 -243.584476)
			(xy 120.556782 -243.563394) (xy 120.563629 -243.555996) (xy 120.571364 -243.537398) (xy 120.571768 -243.527326)
			(xy 120.571768 -242.825524) (xy 120.571279 -242.815563) (xy 120.563686 -242.797144) (xy 120.557036 -242.78971)
			(xy 120.496838 -242.729512) (xy 120.489431 -242.722821) (xy 120.470995 -242.715223) (xy 120.461024 -242.71478)
			(xy 119.067072 -242.71478) (xy 119.057106 -242.715259) (xy 119.03867 -242.722834) (xy 119.031258 -242.729512)
			(xy 118.92661 -242.83416) (xy 118.919919 -242.841567) (xy 118.91232 -242.860003) (xy 118.911878 -242.869974)
			(xy 118.911878 -243.10213) (xy 118.911449 -243.112197) (xy 118.903724 -243.130792) (xy 118.896892 -243.138198)
			(xy 118.66499 -243.3701) (xy 118.663974 -243.3701) (xy 118.63578 -243.398294) (xy 118.628381 -243.405138)
			(xy 118.609783 -243.412866) (xy 118.599712 -243.41328) (xy 117.536468 -243.41328) (xy 117.526401 -243.412851)
			(xy 117.507807 -243.405126) (xy 117.5004 -243.398294) (xy 117.486938 -243.384832) (xy 117.479532 -243.378138)
			(xy 117.461096 -243.370538) (xy 117.451124 -243.3701) (xy 117.446552 -243.3701) (xy 117.436486 -243.369668)
			(xy 117.417894 -243.361941) (xy 117.410484 -243.355114) (xy 117.272816 -243.217446) (xy 117.265976 -243.210045)
			(xy 117.258259 -243.191447) (xy 117.25783 -243.181378) (xy 117.25783 -243.176806) (xy 117.257358 -243.166837)
			(xy 117.249792 -243.148391) (xy 117.243098 -243.140992) (xy 117.242082 -243.139976) (xy 117.23523 -243.13258)
			(xy 117.227492 -243.113981) (xy 117.227096 -243.103908) (xy 117.227096 -242.912392) (xy 117.22662 -242.902425)
			(xy 117.219047 -242.883986) (xy 117.212364 -242.876578) (xy 117.145562 -242.809776) (xy 117.138149 -242.8031)
			(xy 117.119713 -242.795536) (xy 117.109748 -242.795044) (xy 115.246912 -242.795044) (xy 115.236842 -242.794622)
			(xy 115.21824 -242.786904) (xy 115.210844 -242.780058) (xy 114.935762 -242.504976) (xy 114.928913 -242.497579)
			(xy 114.921177 -242.47898) (xy 114.920776 -242.468908) (xy 114.920776 -240.870232) (xy 114.921211 -240.860167)
			(xy 114.92894 -240.841578) (xy 114.935762 -240.834164) (xy 114.949478 -240.820448) (xy 114.955828 -240.812828)
			(xy 114.956844 -240.810796) (xy 114.960252 -240.8048) (xy 114.963985 -240.791527) (xy 114.96421 -240.784634)
			(xy 114.96421 -240.782348) (xy 115.106704 -240.639854) (xy 115.114591 -240.6327) (xy 115.134408 -240.624978)
			(xy 115.145058 -240.624868) (xy 115.146836 -240.62309) (xy 115.154403 -240.615475) (xy 115.173963 -240.606688)
			(xy 115.184682 -240.606072) (xy 115.594384 -240.606072) (xy 115.604537 -240.606528) (xy 115.623259 -240.614395)
			(xy 115.630706 -240.621312) (xy 115.634262 -240.624868) (xy 115.635278 -240.624868) (xy 115.67795 -240.66754)
			(xy 115.68481 -240.673788) (xy 115.701738 -240.681354) (xy 115.71097 -240.682272) (xy 118.80088 -240.682272)
			(xy 118.87708 -240.606072) (xy 118.87708 -239.94618) (xy 118.77548 -239.84458) (xy 117.212872 -239.84458)
			(xy 117.202804 -239.844151) (xy 117.184209 -239.836427) (xy 117.176804 -239.829594) (xy 117.031516 -239.684306)
			(xy 117.024667 -239.676908) (xy 117.016928 -239.65831) (xy 117.01653 -239.648238) (xy 117.01653 -239.622076)
			(xy 117.016052 -239.61211) (xy 117.008479 -239.593672) (xy 117.001798 -239.586262) (xy 116.992654 -239.577118)
			(xy 116.985814 -239.569718) (xy 116.978101 -239.551119) (xy 116.977668 -239.54105) (xy 116.977668 -238.192564)
			(xy 116.969794 -238.174022) (xy 116.963444 -238.167672) (xy 114.840258 -238.167672) (xy 114.830293 -238.168153)
			(xy 114.81186 -238.175731) (xy 114.804444 -238.182404) (xy 114.264186 -238.722662) (xy 114.256789 -238.72951)
			(xy 114.23819 -238.737246) (xy 114.228118 -238.737648) (xy 113.931192 -238.737648) (xy 113.918777 -238.738269)
			(xy 113.896819 -238.74986) (xy 113.889282 -238.759746) (xy 113.842292 -238.83493) (xy 113.840006 -238.839248)
			(xy 113.840006 -238.88319) (xy 113.844578 -238.893096) (xy 113.854506 -238.916196) (xy 113.868511 -238.964485)
			(xy 113.875604 -239.014261) (xy 113.876074 -239.0394) (xy 113.876074 -239.039654) (xy 113.875576 -239.066303)
			(xy 113.867633 -239.119007) (xy 113.851923 -239.169937) (xy 113.828797 -239.217958) (xy 113.798773 -239.261995)
			(xy 113.762521 -239.301066) (xy 113.72085 -239.334297) (xy 113.674692 -239.360946) (xy 113.625078 -239.380418)
			(xy 113.573116 -239.392278) (xy 113.519966 -239.396262) (xy 113.466816 -239.392278) (xy 113.414854 -239.380418)
			(xy 113.36524 -239.360946) (xy 113.319082 -239.334297) (xy 113.277411 -239.301066) (xy 113.241159 -239.261995)
			(xy 113.211135 -239.217958) (xy 113.188009 -239.169937) (xy 113.172299 -239.119007) (xy 113.164356 -239.066303)
			(xy 113.163858 -239.039654) (xy 113.164376 -239.012733) (xy 113.172526 -238.959511) (xy 113.188588 -238.908121)
			(xy 113.199926 -238.883698) (xy 113.199926 -238.883444) (xy 113.204775 -238.871951) (xy 113.20383 -238.847053)
			(xy 113.198148 -238.835946) (xy 113.150396 -238.759746) (xy 113.142823 -238.750005) (xy 113.121053 -238.738476)
			(xy 113.10874 -238.737648) (xy 108.757212 -238.737648) (xy 108.747253 -238.738139) (xy 108.728838 -238.745738)
			(xy 108.721398 -238.75238) (xy 108.721144 -238.752634) (xy 108.478066 -238.995458) (xy 108.477812 -238.995712)
			(xy 108.471128 -239.003121) (xy 108.463549 -239.021558) (xy 108.46308 -239.031526) (xy 108.46308 -239.880119)
			(xy 109.87531 -239.880119) (xy 109.87531 -239.826821) (xy 109.883253 -239.774117) (xy 109.898963 -239.723187)
			(xy 109.922089 -239.675166) (xy 109.952113 -239.631129) (xy 109.988365 -239.592058) (xy 110.030036 -239.558827)
			(xy 110.076194 -239.532178) (xy 110.125808 -239.512706) (xy 110.17777 -239.500846) (xy 110.23092 -239.496863)
			(xy 110.28407 -239.500846) (xy 110.336032 -239.512706) (xy 110.385646 -239.532178) (xy 110.431804 -239.558827)
			(xy 110.473475 -239.592058) (xy 110.509727 -239.631129) (xy 110.539751 -239.675166) (xy 110.562877 -239.723187)
			(xy 110.578587 -239.774117) (xy 110.58653 -239.826821) (xy 110.587028 -239.85347) (xy 110.58653 -239.880119)
			(xy 110.578587 -239.932823) (xy 110.562877 -239.983753) (xy 110.539751 -240.031774) (xy 110.509727 -240.075811)
			(xy 110.473475 -240.114882) (xy 110.431804 -240.148113) (xy 110.385646 -240.174762) (xy 110.336032 -240.194234)
			(xy 110.28407 -240.206094) (xy 110.23092 -240.210078) (xy 110.17777 -240.206094) (xy 110.125808 -240.194234)
			(xy 110.076194 -240.174762) (xy 110.030036 -240.148113) (xy 109.988365 -240.114882) (xy 109.952113 -240.075811)
			(xy 109.922089 -240.031774) (xy 109.898963 -239.983753) (xy 109.883253 -239.932823) (xy 109.87531 -239.880119)
			(xy 108.46308 -239.880119) (xy 108.46308 -239.917478) (xy 108.46355 -239.927351) (xy 108.471006 -239.945636)
			(xy 108.477558 -239.953038) (xy 108.916724 -240.392204) (xy 108.923578 -240.399599) (xy 108.931323 -240.418198)
			(xy 108.93171 -240.428272) (xy 108.93171 -240.694189) (xy 113.16461 -240.694189) (xy 113.16461 -240.640891)
			(xy 113.172553 -240.588187) (xy 113.188263 -240.537257) (xy 113.211389 -240.489236) (xy 113.241413 -240.445199)
			(xy 113.277665 -240.406128) (xy 113.319336 -240.372897) (xy 113.365494 -240.346248) (xy 113.415108 -240.326776)
			(xy 113.46707 -240.314916) (xy 113.52022 -240.310933) (xy 113.57337 -240.314916) (xy 113.625332 -240.326776)
			(xy 113.674946 -240.346248) (xy 113.721104 -240.372897) (xy 113.762775 -240.406128) (xy 113.799027 -240.445199)
			(xy 113.829051 -240.489236) (xy 113.852177 -240.537257) (xy 113.867887 -240.588187) (xy 113.87583 -240.640891)
			(xy 113.876328 -240.66754) (xy 113.87583 -240.694189) (xy 113.867887 -240.746893) (xy 113.852177 -240.797823)
			(xy 113.829051 -240.845844) (xy 113.799027 -240.889881) (xy 113.762775 -240.928952) (xy 113.721104 -240.962183)
			(xy 113.674946 -240.988832) (xy 113.625332 -241.008304) (xy 113.57337 -241.020164) (xy 113.52022 -241.024148)
			(xy 113.46707 -241.020164) (xy 113.415108 -241.008304) (xy 113.365494 -240.988832) (xy 113.319336 -240.962183)
			(xy 113.277665 -240.928952) (xy 113.241413 -240.889881) (xy 113.211389 -240.845844) (xy 113.188263 -240.797823)
			(xy 113.172553 -240.746893) (xy 113.16461 -240.694189) (xy 108.93171 -240.694189) (xy 108.93171 -241.383058)
			(xy 108.931277 -241.393124) (xy 108.923549 -241.411714) (xy 108.916724 -241.419126) (xy 108.827845 -241.508005)
			(xy 109.87531 -241.508005) (xy 109.87531 -241.454707) (xy 109.883253 -241.402003) (xy 109.898963 -241.351073)
			(xy 109.922089 -241.303052) (xy 109.952113 -241.259015) (xy 109.988365 -241.219944) (xy 110.030036 -241.186713)
			(xy 110.076194 -241.160064) (xy 110.125808 -241.140592) (xy 110.17777 -241.128732) (xy 110.23092 -241.124749)
			(xy 110.28407 -241.128732) (xy 110.336032 -241.140592) (xy 110.385646 -241.160064) (xy 110.431804 -241.186713)
			(xy 110.473475 -241.219944) (xy 110.509727 -241.259015) (xy 110.539751 -241.303052) (xy 110.562877 -241.351073)
			(xy 110.578587 -241.402003) (xy 110.58653 -241.454707) (xy 110.587028 -241.481356) (xy 110.58653 -241.508005)
			(xy 110.578587 -241.560709) (xy 110.562877 -241.611639) (xy 110.539751 -241.65966) (xy 110.509727 -241.703697)
			(xy 110.473475 -241.742768) (xy 110.431804 -241.775999) (xy 110.385646 -241.802648) (xy 110.336032 -241.82212)
			(xy 110.28407 -241.83398) (xy 110.23092 -241.837964) (xy 110.17777 -241.83398) (xy 110.125808 -241.82212)
			(xy 110.076194 -241.802648) (xy 110.030036 -241.775999) (xy 109.988365 -241.742768) (xy 109.952113 -241.703697)
			(xy 109.922089 -241.65966) (xy 109.898963 -241.611639) (xy 109.883253 -241.560709) (xy 109.87531 -241.508005)
			(xy 108.827845 -241.508005) (xy 108.766356 -241.569494) (xy 108.758955 -241.576334) (xy 108.740357 -241.584054)
			(xy 108.730288 -241.58448) (xy 108.662724 -241.58448) (xy 108.644182 -241.5921) (xy 108.638594 -241.597688)
			(xy 107.187746 -241.597688) (xy 107.155488 -241.58448) (xy 106.985562 -241.58448) (xy 106.975495 -241.584049)
			(xy 106.956903 -241.576323) (xy 106.949494 -241.569494) (xy 106.7562 -241.3762) (xy 106.74879 -241.369516)
			(xy 106.730354 -241.361934) (xy 106.720386 -241.361468) (xy 104.805734 -241.361468) (xy 104.797019 -241.361877)
			(xy 104.78062 -241.367797) (xy 104.767127 -241.378838) (xy 104.7623 -241.386106) (xy 104.718104 -241.467894)
			(xy 104.715582 -241.473334) (xy 104.712877 -241.485013) (xy 104.71277 -241.491008) (xy 104.720644 -241.518186)
			(xy 104.723946 -241.52352) (xy 104.7321 -241.538452) (xy 104.740975 -241.571283) (xy 104.741472 -241.58829)
			(xy 104.741472 -242.321821) (xy 113.16461 -242.321821) (xy 113.16461 -242.268523) (xy 113.172553 -242.215819)
			(xy 113.188263 -242.164889) (xy 113.211389 -242.116868) (xy 113.241413 -242.072831) (xy 113.277665 -242.03376)
			(xy 113.319336 -242.000529) (xy 113.365494 -241.97388) (xy 113.415108 -241.954408) (xy 113.46707 -241.942548)
			(xy 113.52022 -241.938565) (xy 113.57337 -241.942548) (xy 113.625332 -241.954408) (xy 113.674946 -241.97388)
			(xy 113.721104 -242.000529) (xy 113.762775 -242.03376) (xy 113.799027 -242.072831) (xy 113.829051 -242.116868)
			(xy 113.852177 -242.164889) (xy 113.867887 -242.215819) (xy 113.87583 -242.268523) (xy 113.876328 -242.295172)
			(xy 113.87583 -242.321821) (xy 113.867887 -242.374525) (xy 113.852177 -242.425455) (xy 113.829051 -242.473476)
			(xy 113.799027 -242.517513) (xy 113.762775 -242.556584) (xy 113.721104 -242.589815) (xy 113.674946 -242.616464)
			(xy 113.625332 -242.635936) (xy 113.57337 -242.647796) (xy 113.52022 -242.65178) (xy 113.46707 -242.647796)
			(xy 113.415108 -242.635936) (xy 113.365494 -242.616464) (xy 113.319336 -242.589815) (xy 113.277665 -242.556584)
			(xy 113.241413 -242.517513) (xy 113.211389 -242.473476) (xy 113.188263 -242.425455) (xy 113.172553 -242.374525)
			(xy 113.16461 -242.321821) (xy 104.741472 -242.321821) (xy 104.741472 -242.60429) (xy 104.740929 -242.620973)
			(xy 104.732296 -242.653204) (xy 104.715615 -242.682102) (xy 104.692024 -242.705698) (xy 104.66313 -242.722385)
			(xy 104.630901 -242.731025) (xy 104.614218 -242.731544) (xy 104.073198 -242.731544) (xy 104.063129 -242.731969)
			(xy 104.044529 -242.739689) (xy 104.03713 -242.74653) (xy 104.002586 -242.781074) (xy 103.996245 -242.78697)
			(xy 103.980666 -242.7945) (xy 103.972106 -242.795806) (xy 103.96474 -242.796568) (xy 103.94696 -242.804188)
			(xy 103.338884 -242.804188) (xy 103.337614 -242.804442) (xy 103.328659 -242.805421) (xy 103.312261 -242.812845)
			(xy 103.30561 -242.81892) (xy 103.218742 -242.905788) (xy 103.212052 -242.913195) (xy 103.204459 -242.931632)
			(xy 103.20401 -242.941602) (xy 103.20401 -243.135891) (xy 109.87531 -243.135891) (xy 109.87531 -243.082593)
			(xy 109.883253 -243.029889) (xy 109.898963 -242.978959) (xy 109.922089 -242.930938) (xy 109.952113 -242.886901)
			(xy 109.988365 -242.84783) (xy 110.030036 -242.814599) (xy 110.076194 -242.78795) (xy 110.125808 -242.768478)
			(xy 110.17777 -242.756618) (xy 110.23092 -242.752635) (xy 110.28407 -242.756618) (xy 110.336032 -242.768478)
			(xy 110.385646 -242.78795) (xy 110.431804 -242.814599) (xy 110.473475 -242.84783) (xy 110.509727 -242.886901)
			(xy 110.539751 -242.930938) (xy 110.562877 -242.978959) (xy 110.578587 -243.029889) (xy 110.58653 -243.082593)
			(xy 110.587028 -243.109242) (xy 110.58653 -243.135891) (xy 110.578587 -243.188595) (xy 110.562877 -243.239525)
			(xy 110.539751 -243.287546) (xy 110.509727 -243.331583) (xy 110.473475 -243.370654) (xy 110.431804 -243.403885)
			(xy 110.385646 -243.430534) (xy 110.336032 -243.450006) (xy 110.28407 -243.461866) (xy 110.23092 -243.46585)
			(xy 110.17777 -243.461866) (xy 110.125808 -243.450006) (xy 110.076194 -243.430534) (xy 110.030036 -243.403885)
			(xy 109.988365 -243.370654) (xy 109.952113 -243.331583) (xy 109.922089 -243.287546) (xy 109.898963 -243.239525)
			(xy 109.883253 -243.188595) (xy 109.87531 -243.135891) (xy 103.20401 -243.135891) (xy 103.20401 -243.949707)
			(xy 113.16461 -243.949707) (xy 113.16461 -243.896409) (xy 113.172553 -243.843705) (xy 113.188263 -243.792775)
			(xy 113.211389 -243.744754) (xy 113.241413 -243.700717) (xy 113.277665 -243.661646) (xy 113.319336 -243.628415)
			(xy 113.365494 -243.601766) (xy 113.415108 -243.582294) (xy 113.46707 -243.570434) (xy 113.52022 -243.566451)
			(xy 113.57337 -243.570434) (xy 113.625332 -243.582294) (xy 113.674946 -243.601766) (xy 113.721104 -243.628415)
			(xy 113.762775 -243.661646) (xy 113.799027 -243.700717) (xy 113.829051 -243.744754) (xy 113.852177 -243.792775)
			(xy 113.867887 -243.843705) (xy 113.87583 -243.896409) (xy 113.876328 -243.923058) (xy 113.87583 -243.949707)
			(xy 113.867887 -244.002411) (xy 113.852177 -244.053341) (xy 113.829051 -244.101362) (xy 113.799027 -244.145399)
			(xy 113.762775 -244.18447) (xy 113.721104 -244.217701) (xy 113.674946 -244.24435) (xy 113.625332 -244.263822)
			(xy 113.57337 -244.275682) (xy 113.52022 -244.279666) (xy 113.46707 -244.275682) (xy 113.415108 -244.263822)
			(xy 113.365494 -244.24435) (xy 113.319336 -244.217701) (xy 113.277665 -244.18447) (xy 113.241413 -244.145399)
			(xy 113.211389 -244.101362) (xy 113.188263 -244.053341) (xy 113.172553 -244.002411) (xy 113.16461 -243.949707)
			(xy 103.20401 -243.949707) (xy 103.20401 -244.354858) (xy 103.204361 -244.364117) (xy 103.210873 -244.381445)
			(xy 103.21671 -244.38864) (xy 103.21798 -244.38991) (xy 103.218742 -244.390672) (xy 103.286814 -244.458744)
			(xy 103.293518 -244.464738) (xy 103.30989 -244.472143) (xy 103.318818 -244.473222) (xy 103.320088 -244.473476)
			(xy 107.984036 -244.473476) (xy 107.985306 -244.473222) (xy 107.993988 -244.472265) (xy 108.00997 -244.465252)
			(xy 108.016548 -244.459506) (xy 108.158788 -244.317012) (xy 108.166211 -244.310231) (xy 108.184808 -244.302631)
			(xy 108.194856 -244.30228) (xy 108.612432 -244.30228) (xy 108.6225 -244.302708) (xy 108.641098 -244.310429)
			(xy 108.6485 -244.317266) (xy 108.655358 -244.324124) (xy 108.662738 -244.330708) (xy 108.681038 -244.338161)
			(xy 108.690918 -244.338602) (xy 108.699808 -244.338602) (xy 108.71835 -244.346222) (xy 108.885482 -244.513608)
			(xy 108.87837 -244.52072) (xy 108.87837 -244.526054) (xy 108.878853 -244.536018) (xy 108.886434 -244.554448)
			(xy 108.893102 -244.561868) (xy 108.898436 -244.567202) (xy 108.906056 -244.585744) (xy 108.906056 -244.763523)
			(xy 109.87531 -244.763523) (xy 109.87531 -244.710225) (xy 109.883253 -244.657521) (xy 109.898963 -244.606591)
			(xy 109.922089 -244.55857) (xy 109.952113 -244.514533) (xy 109.988365 -244.475462) (xy 110.030036 -244.442231)
			(xy 110.076194 -244.415582) (xy 110.125808 -244.39611) (xy 110.17777 -244.38425) (xy 110.23092 -244.380267)
			(xy 110.28407 -244.38425) (xy 110.336032 -244.39611) (xy 110.385646 -244.415582) (xy 110.431804 -244.442231)
			(xy 110.473475 -244.475462) (xy 110.509727 -244.514533) (xy 110.539751 -244.55857) (xy 110.562877 -244.606591)
			(xy 110.578587 -244.657521) (xy 110.58653 -244.710225) (xy 110.587028 -244.736874) (xy 110.58653 -244.763523)
			(xy 110.578587 -244.816227) (xy 110.562877 -244.867157) (xy 110.539751 -244.915178) (xy 110.509727 -244.959215)
			(xy 110.473475 -244.998286) (xy 110.431804 -245.031517) (xy 110.385646 -245.058166) (xy 110.336032 -245.077638)
			(xy 110.28407 -245.089498) (xy 110.23092 -245.093482) (xy 110.17777 -245.089498) (xy 110.125808 -245.077638)
			(xy 110.076194 -245.058166) (xy 110.030036 -245.031517) (xy 109.988365 -244.998286) (xy 109.952113 -244.959215)
			(xy 109.922089 -244.915178) (xy 109.898963 -244.867157) (xy 109.883253 -244.816227) (xy 109.87531 -244.763523)
			(xy 108.906056 -244.763523) (xy 108.906056 -245.577593) (xy 113.16461 -245.577593) (xy 113.16461 -245.524295)
			(xy 113.172553 -245.471591) (xy 113.188263 -245.420661) (xy 113.211389 -245.37264) (xy 113.241413 -245.328603)
			(xy 113.277665 -245.289532) (xy 113.319336 -245.256301) (xy 113.365494 -245.229652) (xy 113.415108 -245.21018)
			(xy 113.46707 -245.19832) (xy 113.52022 -245.194337) (xy 113.57337 -245.19832) (xy 113.625332 -245.21018)
			(xy 113.674946 -245.229652) (xy 113.721104 -245.256301) (xy 113.762775 -245.289532) (xy 113.799027 -245.328603)
			(xy 113.829051 -245.37264) (xy 113.852177 -245.420661) (xy 113.867887 -245.471591) (xy 113.87583 -245.524295)
			(xy 113.876328 -245.550944) (xy 113.87583 -245.577593) (xy 113.867887 -245.630297) (xy 113.852177 -245.681227)
			(xy 113.829051 -245.729248) (xy 113.799027 -245.773285) (xy 113.762775 -245.812356) (xy 113.721104 -245.845587)
			(xy 113.674946 -245.872236) (xy 113.625332 -245.891708) (xy 113.57337 -245.903568) (xy 113.52022 -245.907552)
			(xy 113.46707 -245.903568) (xy 113.415108 -245.891708) (xy 113.365494 -245.872236) (xy 113.319336 -245.845587)
			(xy 113.277665 -245.812356) (xy 113.241413 -245.773285) (xy 113.211389 -245.729248) (xy 113.188263 -245.681227)
			(xy 113.172553 -245.630297) (xy 113.16461 -245.577593) (xy 108.906056 -245.577593) (xy 108.906056 -245.66626)
			(xy 108.905616 -245.676291) (xy 108.898035 -245.69486) (xy 108.891324 -245.702328) (xy 108.693204 -245.900448)
			(xy 108.69295 -245.900448) (xy 108.201785 -246.391409) (xy 109.87531 -246.391409) (xy 109.87531 -246.338111)
			(xy 109.883253 -246.285407) (xy 109.898963 -246.234477) (xy 109.922089 -246.186456) (xy 109.952113 -246.142419)
			(xy 109.988365 -246.103348) (xy 110.030036 -246.070117) (xy 110.076194 -246.043468) (xy 110.125808 -246.023996)
			(xy 110.17777 -246.012136) (xy 110.23092 -246.008153) (xy 110.28407 -246.012136) (xy 110.336032 -246.023996)
			(xy 110.385646 -246.043468) (xy 110.431804 -246.070117) (xy 110.473475 -246.103348) (xy 110.509727 -246.142419)
			(xy 110.539751 -246.186456) (xy 110.562877 -246.234477) (xy 110.578587 -246.285407) (xy 110.58653 -246.338111)
			(xy 110.587028 -246.36476) (xy 110.58653 -246.391409) (xy 110.578587 -246.444113) (xy 110.562877 -246.495043)
			(xy 110.539751 -246.543064) (xy 110.509727 -246.587101) (xy 110.473475 -246.626172) (xy 110.431804 -246.659403)
			(xy 110.385646 -246.686052) (xy 110.336032 -246.705524) (xy 110.28407 -246.717384) (xy 110.23092 -246.721368)
			(xy 110.17777 -246.717384) (xy 110.125808 -246.705524) (xy 110.076194 -246.686052) (xy 110.030036 -246.659403)
			(xy 109.988365 -246.626172) (xy 109.952113 -246.587101) (xy 109.922089 -246.543064) (xy 109.898963 -246.495043)
			(xy 109.883253 -246.444113) (xy 109.87531 -246.391409) (xy 108.201785 -246.391409) (xy 108.082334 -246.51081)
			(xy 108.074936 -246.517656) (xy 108.056337 -246.52538) (xy 108.046266 -246.525796) (xy 106.594656 -246.525796)
			(xy 106.584692 -246.526278) (xy 106.566262 -246.53386) (xy 106.558842 -246.540528) (xy 106.529378 -246.569992)
			(xy 106.522695 -246.577402) (xy 106.515113 -246.595838) (xy 106.514646 -246.605806) (xy 106.514646 -246.85879)
			(xy 106.514223 -246.86886) (xy 106.506505 -246.887462) (xy 106.49966 -246.894858) (xy 106.318304 -247.076214)
			(xy 106.31091 -247.08307) (xy 106.292311 -247.09082) (xy 106.282236 -247.0912) (xy 105.058972 -247.0912)
			(xy 105.04043 -247.099074) (xy 105.038144 -247.10136) (xy 105.038144 -247.205225) (xy 113.16461 -247.205225)
			(xy 113.16461 -247.151927) (xy 113.172553 -247.099223) (xy 113.188263 -247.048293) (xy 113.211389 -247.000272)
			(xy 113.241413 -246.956235) (xy 113.277665 -246.917164) (xy 113.319336 -246.883933) (xy 113.365494 -246.857284)
			(xy 113.415108 -246.837812) (xy 113.46707 -246.825952) (xy 113.52022 -246.821969) (xy 113.57337 -246.825952)
			(xy 113.625332 -246.837812) (xy 113.674946 -246.857284) (xy 113.721104 -246.883933) (xy 113.762775 -246.917164)
			(xy 113.799027 -246.956235) (xy 113.829051 -247.000272) (xy 113.852177 -247.048293) (xy 113.867887 -247.099223)
			(xy 113.87583 -247.151927) (xy 113.876328 -247.178576) (xy 113.87583 -247.205225) (xy 113.867887 -247.257929)
			(xy 113.852177 -247.308859) (xy 113.829051 -247.35688) (xy 113.799027 -247.400917) (xy 113.762775 -247.439988)
			(xy 113.721104 -247.473219) (xy 113.674946 -247.499868) (xy 113.625332 -247.51934) (xy 113.57337 -247.5312)
			(xy 113.52022 -247.535184) (xy 113.46707 -247.5312) (xy 113.415108 -247.51934) (xy 113.365494 -247.499868)
			(xy 113.319336 -247.473219) (xy 113.277665 -247.439988) (xy 113.241413 -247.400917) (xy 113.211389 -247.35688)
			(xy 113.188263 -247.308859) (xy 113.172553 -247.257929) (xy 113.16461 -247.205225) (xy 105.038144 -247.205225)
			(xy 105.038144 -248.0945) (xy 105.038665 -248.104398) (xy 105.04625 -248.122688) (xy 105.052876 -248.13006)
			(xy 105.05567 -248.132854) (xy 105.074212 -248.140728) (xy 108.018072 -248.140728) (xy 108.027945 -248.140259)
			(xy 108.046233 -248.132805) (xy 108.053632 -248.12625) (xy 108.1913 -247.988582) (xy 108.198695 -247.981727)
			(xy 108.217294 -247.973979) (xy 108.227368 -247.973596) (xy 108.258864 -247.973596) (xy 108.277406 -247.965976)
			(xy 108.279438 -247.963944) (xy 108.601256 -247.963944) (xy 108.619798 -247.971564) (xy 108.624624 -247.973596)
			(xy 108.661708 -247.973596) (xy 108.671778 -247.974021) (xy 108.69038 -247.981737) (xy 108.697776 -247.988582)
			(xy 108.728235 -248.019041) (xy 109.87531 -248.019041) (xy 109.87531 -247.965743) (xy 109.883253 -247.913039)
			(xy 109.898963 -247.862109) (xy 109.922089 -247.814088) (xy 109.952113 -247.770051) (xy 109.988365 -247.73098)
			(xy 110.030036 -247.697749) (xy 110.076194 -247.6711) (xy 110.125808 -247.651628) (xy 110.17777 -247.639768)
			(xy 110.23092 -247.635785) (xy 110.28407 -247.639768) (xy 110.336032 -247.651628) (xy 110.385646 -247.6711)
			(xy 110.431804 -247.697749) (xy 110.473475 -247.73098) (xy 110.509727 -247.770051) (xy 110.539751 -247.814088)
			(xy 110.562877 -247.862109) (xy 110.578587 -247.913039) (xy 110.58653 -247.965743) (xy 110.587028 -247.992392)
			(xy 110.58653 -248.019041) (xy 110.578587 -248.071745) (xy 110.562877 -248.122675) (xy 110.539751 -248.170696)
			(xy 110.509727 -248.214733) (xy 110.473475 -248.253804) (xy 110.431804 -248.287035) (xy 110.385646 -248.313684)
			(xy 110.336032 -248.333156) (xy 110.28407 -248.345016) (xy 110.23092 -248.349) (xy 110.17777 -248.345016)
			(xy 110.125808 -248.333156) (xy 110.076194 -248.313684) (xy 110.030036 -248.287035) (xy 109.988365 -248.253804)
			(xy 109.952113 -248.214733) (xy 109.922089 -248.170696) (xy 109.898963 -248.122675) (xy 109.883253 -248.071745)
			(xy 109.87531 -248.019041) (xy 108.728235 -248.019041) (xy 108.843064 -248.13387) (xy 108.849903 -248.141271)
			(xy 108.857618 -248.159869) (xy 108.85805 -248.169938) (xy 108.85805 -248.188734) (xy 108.858512 -248.198611)
			(xy 108.865954 -248.21691) (xy 108.872528 -248.224294) (xy 108.873544 -248.22531) (xy 108.873544 -248.833111)
			(xy 113.16461 -248.833111) (xy 113.16461 -248.779813) (xy 113.172553 -248.727109) (xy 113.188263 -248.676179)
			(xy 113.211389 -248.628158) (xy 113.241413 -248.584121) (xy 113.277665 -248.54505) (xy 113.319336 -248.511819)
			(xy 113.365494 -248.48517) (xy 113.415108 -248.465698) (xy 113.46707 -248.453838) (xy 113.52022 -248.449855)
			(xy 113.57337 -248.453838) (xy 113.625332 -248.465698) (xy 113.674946 -248.48517) (xy 113.721104 -248.511819)
			(xy 113.762775 -248.54505) (xy 113.799027 -248.584121) (xy 113.829051 -248.628158) (xy 113.852177 -248.676179)
			(xy 113.867887 -248.727109) (xy 113.87583 -248.779813) (xy 113.876328 -248.806462) (xy 113.87583 -248.833111)
			(xy 113.867887 -248.885815) (xy 113.852177 -248.936745) (xy 113.829051 -248.984766) (xy 113.799027 -249.028803)
			(xy 113.762775 -249.067874) (xy 113.721104 -249.101105) (xy 113.674946 -249.127754) (xy 113.625332 -249.147226)
			(xy 113.57337 -249.159086) (xy 113.52022 -249.16307) (xy 113.46707 -249.159086) (xy 113.415108 -249.147226)
			(xy 113.365494 -249.127754) (xy 113.319336 -249.101105) (xy 113.277665 -249.067874) (xy 113.241413 -249.028803)
			(xy 113.211389 -248.984766) (xy 113.188263 -248.936745) (xy 113.172553 -248.885815) (xy 113.16461 -248.833111)
			(xy 108.873544 -248.833111) (xy 108.873544 -249.227848) (xy 108.873111 -249.237913) (xy 108.865378 -249.2565)
			(xy 108.858558 -249.263916) (xy 108.475547 -249.646927) (xy 109.87531 -249.646927) (xy 109.87531 -249.593629)
			(xy 109.883253 -249.540925) (xy 109.898963 -249.489995) (xy 109.922089 -249.441974) (xy 109.952113 -249.397937)
			(xy 109.988365 -249.358866) (xy 110.030036 -249.325635) (xy 110.076194 -249.298986) (xy 110.125808 -249.279514)
			(xy 110.17777 -249.267654) (xy 110.23092 -249.263671) (xy 110.28407 -249.267654) (xy 110.336032 -249.279514)
			(xy 110.385646 -249.298986) (xy 110.431804 -249.325635) (xy 110.473475 -249.358866) (xy 110.509727 -249.397937)
			(xy 110.539751 -249.441974) (xy 110.562877 -249.489995) (xy 110.578587 -249.540925) (xy 110.58653 -249.593629)
			(xy 110.587028 -249.620278) (xy 110.58653 -249.646927) (xy 110.578587 -249.699631) (xy 110.562877 -249.750561)
			(xy 110.539751 -249.798582) (xy 110.509727 -249.842619) (xy 110.473475 -249.88169) (xy 110.431804 -249.914921)
			(xy 110.385646 -249.94157) (xy 110.336032 -249.961042) (xy 110.28407 -249.972902) (xy 110.23092 -249.976886)
			(xy 110.17777 -249.972902) (xy 110.125808 -249.961042) (xy 110.076194 -249.94157) (xy 110.030036 -249.914921)
			(xy 109.988365 -249.88169) (xy 109.952113 -249.842619) (xy 109.922089 -249.798582) (xy 109.898963 -249.750561)
			(xy 109.883253 -249.699631) (xy 109.87531 -249.646927) (xy 108.475547 -249.646927) (xy 108.462064 -249.66041)
			(xy 108.455385 -249.667822) (xy 108.447812 -249.686258) (xy 108.447332 -249.696224) (xy 108.447332 -249.991118)
			(xy 108.446906 -250.001187) (xy 108.439191 -250.01979) (xy 108.432346 -250.027186) (xy 108.286042 -250.17349)
			(xy 108.278641 -250.180329) (xy 108.260043 -250.188043) (xy 108.249974 -250.188476) (xy 106.603292 -250.188476)
			(xy 106.593325 -250.188951) (xy 106.574883 -250.196521) (xy 106.567478 -250.203208) (xy 106.556556 -250.21413)
			(xy 106.549881 -250.221543) (xy 106.542317 -250.239979) (xy 106.541824 -250.249944) (xy 106.541824 -250.50877)
			(xy 106.538268 -250.512326) (xy 106.538268 -250.56592) (xy 106.537841 -250.575988) (xy 106.530117 -250.594584)
			(xy 106.523282 -250.601988) (xy 106.404156 -250.721114) (xy 106.396759 -250.727963) (xy 106.37816 -250.735695)
			(xy 106.368088 -250.7361) (xy 106.335576 -250.7361) (xy 106.32561 -250.736579) (xy 106.307175 -250.744156)
			(xy 106.299762 -250.750832) (xy 106.285284 -250.76531) (xy 106.277889 -250.772164) (xy 106.25929 -250.779907)
			(xy 106.249216 -250.780296) (xy 105.228644 -250.780296) (xy 105.218578 -250.779862) (xy 105.199989 -250.772133)
			(xy 105.192576 -250.76531) (xy 104.981502 -250.554236) (xy 104.974665 -250.546834) (xy 104.966954 -250.528236)
			(xy 104.966516 -250.518168) (xy 104.966516 -250.270772) (xy 104.966037 -250.260806) (xy 104.958461 -250.242371)
			(xy 104.951784 -250.234958) (xy 104.920034 -250.203208) (xy 104.912627 -250.196518) (xy 104.89419 -250.188922)
			(xy 104.88422 -250.188476) (xy 103.387144 -250.188476) (xy 103.37718 -250.18896) (xy 103.358751 -250.196542)
			(xy 103.35133 -250.203208) (xy 103.33736 -250.217178) (xy 103.330677 -250.224588) (xy 103.323093 -250.243024)
			(xy 103.322628 -250.252992) (xy 103.322628 -251.759212) (xy 103.323054 -251.769281) (xy 103.330775 -251.787879)
			(xy 103.337614 -251.79528) (xy 103.34371 -251.801376) (xy 108.044234 -251.801376) (xy 108.054109 -251.800913)
			(xy 108.072402 -251.793463) (xy 108.079794 -251.786898) (xy 108.206286 -251.660406) (xy 108.213689 -251.653573)
			(xy 108.232287 -251.645869) (xy 108.242354 -251.64542) (xy 108.277152 -251.64542) (xy 108.287027 -251.644955)
			(xy 108.305319 -251.637505) (xy 108.312712 -251.630942) (xy 108.316268 -251.627386) (xy 108.323666 -251.620541)
			(xy 108.342265 -251.612818) (xy 108.352336 -251.6124) (xy 108.597192 -251.6124) (xy 108.607263 -251.612822)
			(xy 108.625869 -251.620534) (xy 108.63326 -251.627386) (xy 108.636816 -251.630942) (xy 108.644195 -251.637531)
			(xy 108.662494 -251.644996) (xy 108.672376 -251.64542) (xy 108.689648 -251.64542) (xy 108.699714 -251.645852)
			(xy 108.718304 -251.653581) (xy 108.725716 -251.660406) (xy 108.878624 -251.813314) (xy 108.885476 -251.82071)
			(xy 108.893218 -251.839309) (xy 108.89361 -251.849382) (xy 108.89361 -252.820932) (xy 108.893182 -252.831)
			(xy 108.88546 -252.849597) (xy 108.878624 -252.857) (xy 108.484416 -253.251208) (xy 108.477731 -253.258617)
			(xy 108.470149 -253.277054) (xy 108.469684 -253.287022) (xy 108.469684 -253.530608) (xy 108.469259 -253.540677)
			(xy 108.461541 -253.559278) (xy 108.454698 -253.566676) (xy 108.177584 -253.84379) (xy 108.177076 -253.844044)
			(xy 108.158534 -253.851664) (xy 106.643932 -253.851664) (xy 106.633969 -253.85215) (xy 106.615542 -253.859734)
			(xy 106.608118 -253.866396) (xy 106.563414 -253.9111) (xy 106.556728 -253.918509) (xy 106.549144 -253.936945)
			(xy 106.548695 -253.946639) (xy 113.274338 -253.946639) (xy 113.274338 -253.893341) (xy 113.282281 -253.840637)
			(xy 113.297991 -253.789707) (xy 113.321117 -253.741686) (xy 113.351141 -253.697649) (xy 113.387393 -253.658578)
			(xy 113.429064 -253.625347) (xy 113.475222 -253.598698) (xy 113.524836 -253.579226) (xy 113.576798 -253.567366)
			(xy 113.629948 -253.563383) (xy 113.683098 -253.567366) (xy 113.73506 -253.579226) (xy 113.784674 -253.598698)
			(xy 113.830832 -253.625347) (xy 113.872503 -253.658578) (xy 113.908755 -253.697649) (xy 113.938779 -253.741686)
			(xy 113.961905 -253.789707) (xy 113.977615 -253.840637) (xy 113.985558 -253.893341) (xy 113.986056 -253.91999)
			(xy 113.985558 -253.946639) (xy 113.977615 -253.999343) (xy 113.961905 -254.050273) (xy 113.938779 -254.098294)
			(xy 113.908755 -254.142331) (xy 113.872503 -254.181402) (xy 113.830832 -254.214633) (xy 113.784674 -254.241282)
			(xy 113.73506 -254.260754) (xy 113.683098 -254.272614) (xy 113.629948 -254.276598) (xy 113.576798 -254.272614)
			(xy 113.524836 -254.260754) (xy 113.475222 -254.241282) (xy 113.429064 -254.214633) (xy 113.387393 -254.181402)
			(xy 113.351141 -254.142331) (xy 113.321117 -254.098294) (xy 113.297991 -254.050273) (xy 113.282281 -253.999343)
			(xy 113.274338 -253.946639) (xy 106.548695 -253.946639) (xy 106.548682 -253.946914) (xy 106.548682 -254.253746)
			(xy 106.54825 -254.263812) (xy 106.540522 -254.282403) (xy 106.533696 -254.289814) (xy 106.404156 -254.419354)
			(xy 106.396757 -254.426198) (xy 106.378159 -254.433924) (xy 106.368088 -254.43434) (xy 106.282236 -254.43434)
			(xy 106.263694 -254.442214) (xy 106.25836 -254.447548) (xy 105.250742 -254.447548) (xy 105.220008 -254.434594)
			(xy 105.214674 -254.433578) (xy 105.207161 -254.431899) (xy 105.193589 -254.424653) (xy 105.188004 -254.419354)
			(xy 104.996996 -254.228346) (xy 104.990158 -254.220944) (xy 104.982444 -254.202346) (xy 104.98201 -254.192278)
			(xy 104.98201 -253.904242) (xy 104.981525 -253.894279) (xy 104.973941 -253.875852) (xy 104.967278 -253.868428)
			(xy 104.93629 -253.83744) (xy 104.929426 -253.831202) (xy 104.912497 -253.823659) (xy 104.90327 -253.822708)
			(xy 104.011984 -253.822708) (xy 104.002018 -253.823185) (xy 103.983581 -253.830761) (xy 103.97617 -253.83744)
			(xy 103.965502 -253.848108) (xy 103.958819 -253.855518) (xy 103.951239 -253.873954) (xy 103.95077 -253.883922)
			(xy 103.95077 -254.128778) (xy 103.95124 -254.138651) (xy 103.958695 -254.156937) (xy 103.965248 -254.164338)
			(xy 103.976932 -254.176022) (xy 103.984311 -254.182611) (xy 104.00261 -254.190074) (xy 104.012492 -254.1905)
			(xy 104.60609 -254.1905) (xy 104.613456 -254.197612) (xy 104.746044 -254.197612) (xy 104.756045 -254.198108)
			(xy 104.77452 -254.205776) (xy 104.788656 -254.219927) (xy 104.796303 -254.238411) (xy 104.796844 -254.248412)
			(xy 104.796844 -254.381254) (xy 104.79913 -254.38354) (xy 104.79913 -254.760455) (xy 109.985038 -254.760455)
			(xy 109.985038 -254.707157) (xy 109.992981 -254.654453) (xy 110.008691 -254.603523) (xy 110.031817 -254.555502)
			(xy 110.061841 -254.511465) (xy 110.098093 -254.472394) (xy 110.139764 -254.439163) (xy 110.185922 -254.412514)
			(xy 110.235536 -254.393042) (xy 110.287498 -254.381182) (xy 110.340648 -254.377199) (xy 110.393798 -254.381182)
			(xy 110.44576 -254.393042) (xy 110.495374 -254.412514) (xy 110.541532 -254.439163) (xy 110.583203 -254.472394)
			(xy 110.619455 -254.511465) (xy 110.649479 -254.555502) (xy 110.672605 -254.603523) (xy 110.688315 -254.654453)
			(xy 110.696258 -254.707157) (xy 110.696756 -254.733806) (xy 110.696258 -254.760455) (xy 110.688315 -254.813159)
			(xy 110.672605 -254.864089) (xy 110.649479 -254.91211) (xy 110.619455 -254.956147) (xy 110.583203 -254.995218)
			(xy 110.541532 -255.028449) (xy 110.495374 -255.055098) (xy 110.44576 -255.07457) (xy 110.393798 -255.08643)
			(xy 110.340648 -255.090414) (xy 110.287498 -255.08643) (xy 110.235536 -255.07457) (xy 110.185922 -255.055098)
			(xy 110.139764 -255.028449) (xy 110.098093 -254.995218) (xy 110.061841 -254.956147) (xy 110.031817 -254.91211)
			(xy 110.008691 -254.864089) (xy 109.992981 -254.813159) (xy 109.985038 -254.760455) (xy 104.79913 -254.760455)
			(xy 104.79913 -255.309116) (xy 104.79959 -255.318993) (xy 104.807036 -255.337289) (xy 104.813608 -255.344676)
			(xy 104.86771 -255.398778) (xy 104.87509 -255.405364) (xy 104.893389 -255.412826) (xy 104.90327 -255.413256)
			(xy 108.072936 -255.413256) (xy 108.081541 -255.412925) (xy 108.097775 -255.407216) (xy 108.104686 -255.40208)
			(xy 108.106718 -255.400556) (xy 108.108496 -255.398778) (xy 108.187998 -255.319022) (xy 108.195395 -255.312173)
			(xy 108.213994 -255.304434) (xy 108.224066 -255.304036) (xy 108.251244 -255.304036) (xy 108.260948 -255.303411)
			(xy 108.27884 -255.295837) (xy 108.286042 -255.289304) (xy 108.301282 -255.27381) (xy 108.308705 -255.267028)
			(xy 108.327302 -255.259427) (xy 108.33735 -255.259078) (xy 108.666788 -255.259078) (xy 108.67686 -255.259498)
			(xy 108.695469 -255.267207) (xy 108.702856 -255.274064) (xy 108.909104 -255.480312) (xy 108.915948 -255.487711)
			(xy 108.923678 -255.506309) (xy 108.92409 -255.51638) (xy 108.92409 -255.574525) (xy 113.274338 -255.574525)
			(xy 113.274338 -255.521227) (xy 113.282281 -255.468523) (xy 113.297991 -255.417593) (xy 113.321117 -255.369572)
			(xy 113.351141 -255.325535) (xy 113.387393 -255.286464) (xy 113.429064 -255.253233) (xy 113.475222 -255.226584)
			(xy 113.524836 -255.207112) (xy 113.576798 -255.195252) (xy 113.629948 -255.191269) (xy 113.683098 -255.195252)
			(xy 113.73506 -255.207112) (xy 113.784674 -255.226584) (xy 113.830832 -255.253233) (xy 113.872503 -255.286464)
			(xy 113.908755 -255.325535) (xy 113.938779 -255.369572) (xy 113.961905 -255.417593) (xy 113.977615 -255.468523)
			(xy 113.985558 -255.521227) (xy 113.986056 -255.547876) (xy 113.985558 -255.574525) (xy 113.977615 -255.627229)
			(xy 113.961905 -255.678159) (xy 113.938779 -255.72618) (xy 113.908755 -255.770217) (xy 113.872503 -255.809288)
			(xy 113.830832 -255.842519) (xy 113.784674 -255.869168) (xy 113.73506 -255.88864) (xy 113.683098 -255.9005)
			(xy 113.629948 -255.904484) (xy 113.576798 -255.9005) (xy 113.524836 -255.88864) (xy 113.475222 -255.869168)
			(xy 113.429064 -255.842519) (xy 113.387393 -255.809288) (xy 113.351141 -255.770217) (xy 113.321117 -255.72618)
			(xy 113.297991 -255.678159) (xy 113.282281 -255.627229) (xy 113.274338 -255.574525) (xy 108.92409 -255.574525)
			(xy 108.92409 -256.388341) (xy 109.984784 -256.388341) (xy 109.984784 -256.335043) (xy 109.992727 -256.282339)
			(xy 110.008437 -256.231409) (xy 110.031563 -256.183388) (xy 110.061587 -256.139351) (xy 110.097839 -256.10028)
			(xy 110.13951 -256.067049) (xy 110.185668 -256.0404) (xy 110.235282 -256.020928) (xy 110.287244 -256.009068)
			(xy 110.340394 -256.005085) (xy 110.393544 -256.009068) (xy 110.445506 -256.020928) (xy 110.49512 -256.0404)
			(xy 110.541278 -256.067049) (xy 110.582949 -256.10028) (xy 110.619201 -256.139351) (xy 110.649225 -256.183388)
			(xy 110.672351 -256.231409) (xy 110.688061 -256.282339) (xy 110.696004 -256.335043) (xy 110.696502 -256.361692)
			(xy 110.696004 -256.388341) (xy 110.688061 -256.441045) (xy 110.672351 -256.491975) (xy 110.649225 -256.539996)
			(xy 110.619201 -256.584033) (xy 110.582949 -256.623104) (xy 110.541278 -256.656335) (xy 110.49512 -256.682984)
			(xy 110.445506 -256.702456) (xy 110.393544 -256.714316) (xy 110.340394 -256.7183) (xy 110.287244 -256.714316)
			(xy 110.235282 -256.702456) (xy 110.185668 -256.682984) (xy 110.13951 -256.656335) (xy 110.097839 -256.623104)
			(xy 110.061587 -256.584033) (xy 110.031563 -256.539996) (xy 110.008437 -256.491975) (xy 109.992727 -256.441045)
			(xy 109.984784 -256.388341) (xy 108.92409 -256.388341) (xy 108.92409 -256.570988) (xy 108.923669 -256.581059)
			(xy 108.915956 -256.599666) (xy 108.909104 -256.607056) (xy 108.881164 -256.634996) (xy 108.881164 -256.643124)
			(xy 108.503212 -257.021076) (xy 108.496523 -257.028484) (xy 108.48893 -257.04692) (xy 108.48848 -257.05689)
			(xy 108.48848 -257.202157) (xy 113.274338 -257.202157) (xy 113.274338 -257.148859) (xy 113.282281 -257.096155)
			(xy 113.297991 -257.045225) (xy 113.321117 -256.997204) (xy 113.351141 -256.953167) (xy 113.387393 -256.914096)
			(xy 113.429064 -256.880865) (xy 113.475222 -256.854216) (xy 113.524836 -256.834744) (xy 113.576798 -256.822884)
			(xy 113.629948 -256.818901) (xy 113.683098 -256.822884) (xy 113.73506 -256.834744) (xy 113.784674 -256.854216)
			(xy 113.830832 -256.880865) (xy 113.872503 -256.914096) (xy 113.908755 -256.953167) (xy 113.938779 -256.997204)
			(xy 113.961905 -257.045225) (xy 113.977615 -257.096155) (xy 113.985558 -257.148859) (xy 113.986056 -257.175508)
			(xy 113.985558 -257.202157) (xy 113.977615 -257.254861) (xy 113.961905 -257.305791) (xy 113.938779 -257.353812)
			(xy 113.908755 -257.397849) (xy 113.872503 -257.43692) (xy 113.830832 -257.470151) (xy 113.784674 -257.4968)
			(xy 113.73506 -257.516272) (xy 113.683098 -257.528132) (xy 113.629948 -257.532116) (xy 113.576798 -257.528132)
			(xy 113.524836 -257.516272) (xy 113.475222 -257.4968) (xy 113.429064 -257.470151) (xy 113.387393 -257.43692)
			(xy 113.351141 -257.397849) (xy 113.321117 -257.353812) (xy 113.297991 -257.305791) (xy 113.282281 -257.254861)
			(xy 113.274338 -257.202157) (xy 108.48848 -257.202157) (xy 108.48848 -257.235198) (xy 108.488057 -257.245268)
			(xy 108.480341 -257.263871) (xy 108.473494 -257.271266) (xy 108.249212 -257.495548) (xy 108.246926 -257.495548)
			(xy 108.224066 -257.518662) (xy 108.216668 -257.525507) (xy 108.198069 -257.533236) (xy 108.187998 -257.533648)
			(xy 106.762804 -257.533648) (xy 106.752786 -257.534068) (xy 106.734276 -257.541739) (xy 106.720114 -257.555913)
			(xy 106.712459 -257.574429) (xy 106.712004 -257.584448) (xy 106.712004 -257.789172) (xy 106.712419 -257.799197)
			(xy 106.720084 -257.817723) (xy 106.734257 -257.831903) (xy 106.752779 -257.839577) (xy 106.762804 -257.839972)
			(xy 108.208572 -257.839972) (xy 108.218623 -257.840476) (xy 108.237186 -257.848195) (xy 108.24464 -257.854958)
			(xy 108.405655 -258.015973) (xy 109.985038 -258.015973) (xy 109.985038 -257.962675) (xy 109.992981 -257.909971)
			(xy 110.008691 -257.859041) (xy 110.031817 -257.81102) (xy 110.061841 -257.766983) (xy 110.098093 -257.727912)
			(xy 110.139764 -257.694681) (xy 110.185922 -257.668032) (xy 110.235536 -257.64856) (xy 110.287498 -257.6367)
			(xy 110.340648 -257.632717) (xy 110.393798 -257.6367) (xy 110.44576 -257.64856) (xy 110.495374 -257.668032)
			(xy 110.541532 -257.694681) (xy 110.583203 -257.727912) (xy 110.619455 -257.766983) (xy 110.649479 -257.81102)
			(xy 110.672605 -257.859041) (xy 110.688315 -257.909971) (xy 110.696258 -257.962675) (xy 110.696756 -257.989324)
			(xy 110.696258 -258.015973) (xy 110.688315 -258.068677) (xy 110.672605 -258.119607) (xy 110.649479 -258.167628)
			(xy 110.619455 -258.211665) (xy 110.583203 -258.250736) (xy 110.541532 -258.283967) (xy 110.495374 -258.310616)
			(xy 110.44576 -258.330088) (xy 110.393798 -258.341948) (xy 110.340648 -258.345932) (xy 110.287498 -258.341948)
			(xy 110.235536 -258.330088) (xy 110.185922 -258.310616) (xy 110.139764 -258.283967) (xy 110.098093 -258.250736)
			(xy 110.061841 -258.211665) (xy 110.031817 -258.167628) (xy 110.008691 -258.119607) (xy 109.992981 -258.068677)
			(xy 109.985038 -258.015973) (xy 108.405655 -258.015973) (xy 108.427012 -258.03733) (xy 108.433784 -258.044757)
			(xy 108.441365 -258.063353) (xy 108.441744 -258.073398) (xy 108.441744 -258.115308) (xy 108.442201 -258.125187)
			(xy 108.449636 -258.143493) (xy 108.456222 -258.150868) (xy 108.878878 -258.573524) (xy 108.885723 -258.580923)
			(xy 108.893452 -258.599521) (xy 108.893864 -258.609592) (xy 108.893864 -258.830043) (xy 113.274338 -258.830043)
			(xy 113.274338 -258.776745) (xy 113.282281 -258.724041) (xy 113.297991 -258.673111) (xy 113.321117 -258.62509)
			(xy 113.351141 -258.581053) (xy 113.387393 -258.541982) (xy 113.429064 -258.508751) (xy 113.475222 -258.482102)
			(xy 113.524836 -258.46263) (xy 113.576798 -258.45077) (xy 113.629948 -258.446787) (xy 113.683098 -258.45077)
			(xy 113.73506 -258.46263) (xy 113.784674 -258.482102) (xy 113.830832 -258.508751) (xy 113.872503 -258.541982)
			(xy 113.908755 -258.581053) (xy 113.938779 -258.62509) (xy 113.961905 -258.673111) (xy 113.977615 -258.724041)
			(xy 113.985558 -258.776745) (xy 113.986056 -258.803394) (xy 113.985558 -258.830043) (xy 113.977615 -258.882747)
			(xy 113.961905 -258.933677) (xy 113.938779 -258.981698) (xy 113.908755 -259.025735) (xy 113.872503 -259.064806)
			(xy 113.830832 -259.098037) (xy 113.784674 -259.124686) (xy 113.73506 -259.144158) (xy 113.683098 -259.156018)
			(xy 113.629948 -259.160002) (xy 113.576798 -259.156018) (xy 113.524836 -259.144158) (xy 113.475222 -259.124686)
			(xy 113.429064 -259.098037) (xy 113.387393 -259.064806) (xy 113.351141 -259.025735) (xy 113.321117 -258.981698)
			(xy 113.297991 -258.933677) (xy 113.282281 -258.882747) (xy 113.274338 -258.830043) (xy 108.893864 -258.830043)
			(xy 108.893864 -259.643859) (xy 109.984784 -259.643859) (xy 109.984784 -259.590561) (xy 109.992727 -259.537857)
			(xy 110.008437 -259.486927) (xy 110.031563 -259.438906) (xy 110.061587 -259.394869) (xy 110.097839 -259.355798)
			(xy 110.13951 -259.322567) (xy 110.185668 -259.295918) (xy 110.235282 -259.276446) (xy 110.287244 -259.264586)
			(xy 110.340394 -259.260603) (xy 110.393544 -259.264586) (xy 110.445506 -259.276446) (xy 110.49512 -259.295918)
			(xy 110.541278 -259.322567) (xy 110.582949 -259.355798) (xy 110.619201 -259.394869) (xy 110.649225 -259.438906)
			(xy 110.672351 -259.486927) (xy 110.688061 -259.537857) (xy 110.696004 -259.590561) (xy 110.696502 -259.61721)
			(xy 110.696004 -259.643859) (xy 110.688061 -259.696563) (xy 110.672351 -259.747493) (xy 110.649225 -259.795514)
			(xy 110.619201 -259.839551) (xy 110.582949 -259.878622) (xy 110.541278 -259.911853) (xy 110.49512 -259.938502)
			(xy 110.445506 -259.957974) (xy 110.393544 -259.969834) (xy 110.340394 -259.973818) (xy 110.287244 -259.969834)
			(xy 110.235282 -259.957974) (xy 110.185668 -259.938502) (xy 110.13951 -259.911853) (xy 110.097839 -259.878622)
			(xy 110.061587 -259.839551) (xy 110.031563 -259.795514) (xy 110.008437 -259.747493) (xy 109.992727 -259.696563)
			(xy 109.984784 -259.643859) (xy 108.893864 -259.643859) (xy 108.893864 -259.730748) (xy 108.893471 -259.739668)
			(xy 108.887363 -259.756431) (xy 108.881926 -259.763514) (xy 108.87329 -259.774944) (xy 108.87329 -259.841238)
			(xy 108.87286 -259.851305) (xy 108.865134 -259.869898) (xy 108.858304 -259.877306) (xy 108.427012 -260.308598)
			(xy 108.420326 -260.316007) (xy 108.412741 -260.334443) (xy 108.41228 -260.344412) (xy 108.41228 -260.457675)
			(xy 113.274338 -260.457675) (xy 113.274338 -260.404377) (xy 113.282281 -260.351673) (xy 113.297991 -260.300743)
			(xy 113.321117 -260.252722) (xy 113.351141 -260.208685) (xy 113.387393 -260.169614) (xy 113.429064 -260.136383)
			(xy 113.475222 -260.109734) (xy 113.524836 -260.090262) (xy 113.576798 -260.078402) (xy 113.629948 -260.074419)
			(xy 113.683098 -260.078402) (xy 113.73506 -260.090262) (xy 113.784674 -260.109734) (xy 113.830832 -260.136383)
			(xy 113.872503 -260.169614) (xy 113.908755 -260.208685) (xy 113.938779 -260.252722) (xy 113.961905 -260.300743)
			(xy 113.977615 -260.351673) (xy 113.985558 -260.404377) (xy 113.986056 -260.431026) (xy 113.985558 -260.457675)
			(xy 113.977615 -260.510379) (xy 113.961905 -260.561309) (xy 113.938779 -260.60933) (xy 113.908755 -260.653367)
			(xy 113.872503 -260.692438) (xy 113.830832 -260.725669) (xy 113.784674 -260.752318) (xy 113.73506 -260.77179)
			(xy 113.683098 -260.78365) (xy 113.629948 -260.787634) (xy 113.576798 -260.78365) (xy 113.524836 -260.77179)
			(xy 113.475222 -260.752318) (xy 113.429064 -260.725669) (xy 113.387393 -260.692438) (xy 113.351141 -260.653367)
			(xy 113.321117 -260.60933) (xy 113.297991 -260.561309) (xy 113.282281 -260.510379) (xy 113.274338 -260.457675)
			(xy 108.41228 -260.457675) (xy 108.41228 -261.271745) (xy 109.984784 -261.271745) (xy 109.984784 -261.218447)
			(xy 109.992727 -261.165743) (xy 110.008437 -261.114813) (xy 110.031563 -261.066792) (xy 110.061587 -261.022755)
			(xy 110.097839 -260.983684) (xy 110.13951 -260.950453) (xy 110.185668 -260.923804) (xy 110.235282 -260.904332)
			(xy 110.287244 -260.892472) (xy 110.340394 -260.888489) (xy 110.393544 -260.892472) (xy 110.445506 -260.904332)
			(xy 110.49512 -260.923804) (xy 110.541278 -260.950453) (xy 110.582949 -260.983684) (xy 110.619201 -261.022755)
			(xy 110.649225 -261.066792) (xy 110.672351 -261.114813) (xy 110.688061 -261.165743) (xy 110.696004 -261.218447)
			(xy 110.696502 -261.245096) (xy 110.696004 -261.271745) (xy 110.688061 -261.324449) (xy 110.672351 -261.375379)
			(xy 110.649225 -261.4234) (xy 110.619201 -261.467437) (xy 110.582949 -261.506508) (xy 110.541278 -261.539739)
			(xy 110.49512 -261.566388) (xy 110.445506 -261.58586) (xy 110.393544 -261.59772) (xy 110.340394 -261.601704)
			(xy 110.287244 -261.59772) (xy 110.235282 -261.58586) (xy 110.185668 -261.566388) (xy 110.13951 -261.539739)
			(xy 110.097839 -261.506508) (xy 110.061587 -261.467437) (xy 110.031563 -261.4234) (xy 110.008437 -261.375379)
			(xy 109.992727 -261.324449) (xy 109.984784 -261.271745) (xy 108.41228 -261.271745) (xy 108.41228 -261.527798)
			(xy 108.411857 -261.537868) (xy 108.404141 -261.556471) (xy 108.397294 -261.563866) (xy 108.185966 -261.775194)
			(xy 108.178566 -261.782036) (xy 108.159968 -261.789759) (xy 108.149898 -261.79018) (xy 108.068872 -261.79018)
			(xy 108.05033 -261.7978) (xy 108.046266 -261.801864) (xy 106.161078 -261.801864) (xy 106.151111 -261.802341)
			(xy 106.132672 -261.809914) (xy 106.125264 -261.816596) (xy 105.988612 -261.953248) (xy 105.981919 -261.960654)
			(xy 105.974316 -261.97909) (xy 105.97388 -261.989062) (xy 105.97388 -262.085561) (xy 113.274338 -262.085561)
			(xy 113.274338 -262.032263) (xy 113.282281 -261.979559) (xy 113.297991 -261.928629) (xy 113.321117 -261.880608)
			(xy 113.351141 -261.836571) (xy 113.387393 -261.7975) (xy 113.429064 -261.764269) (xy 113.475222 -261.73762)
			(xy 113.524836 -261.718148) (xy 113.576798 -261.706288) (xy 113.629948 -261.702305) (xy 113.683098 -261.706288)
			(xy 113.73506 -261.718148) (xy 113.784674 -261.73762) (xy 113.830832 -261.764269) (xy 113.872503 -261.7975)
			(xy 113.908755 -261.836571) (xy 113.938779 -261.880608) (xy 113.961905 -261.928629) (xy 113.977615 -261.979559)
			(xy 113.985558 -262.032263) (xy 113.986056 -262.058912) (xy 113.985558 -262.085561) (xy 113.977615 -262.138265)
			(xy 113.961905 -262.189195) (xy 113.938779 -262.237216) (xy 113.908755 -262.281253) (xy 113.872503 -262.320324)
			(xy 113.830832 -262.353555) (xy 113.784674 -262.380204) (xy 113.73506 -262.399676) (xy 113.683098 -262.411536)
			(xy 113.629948 -262.41552) (xy 113.576798 -262.411536) (xy 113.524836 -262.399676) (xy 113.475222 -262.380204)
			(xy 113.429064 -262.353555) (xy 113.387393 -262.320324) (xy 113.351141 -262.281253) (xy 113.321117 -262.237216)
			(xy 113.297991 -262.189195) (xy 113.282281 -262.138265) (xy 113.274338 -262.085561) (xy 105.97388 -262.085561)
			(xy 105.97388 -262.899377) (xy 109.985038 -262.899377) (xy 109.985038 -262.846079) (xy 109.992981 -262.793375)
			(xy 110.008691 -262.742445) (xy 110.031817 -262.694424) (xy 110.061841 -262.650387) (xy 110.098093 -262.611316)
			(xy 110.139764 -262.578085) (xy 110.185922 -262.551436) (xy 110.235536 -262.531964) (xy 110.287498 -262.520104)
			(xy 110.340648 -262.516121) (xy 110.393798 -262.520104) (xy 110.44576 -262.531964) (xy 110.495374 -262.551436)
			(xy 110.541532 -262.578085) (xy 110.583203 -262.611316) (xy 110.619455 -262.650387) (xy 110.649479 -262.694424)
			(xy 110.672605 -262.742445) (xy 110.688315 -262.793375) (xy 110.696258 -262.846079) (xy 110.696756 -262.872728)
			(xy 110.696258 -262.899377) (xy 110.688315 -262.952081) (xy 110.672605 -263.003011) (xy 110.649479 -263.051032)
			(xy 110.619455 -263.095069) (xy 110.583203 -263.13414) (xy 110.541532 -263.167371) (xy 110.495374 -263.19402)
			(xy 110.44576 -263.213492) (xy 110.393798 -263.225352) (xy 110.340648 -263.229336) (xy 110.287498 -263.225352)
			(xy 110.235536 -263.213492) (xy 110.185922 -263.19402) (xy 110.139764 -263.167371) (xy 110.098093 -263.13414)
			(xy 110.061841 -263.095069) (xy 110.031817 -263.051032) (xy 110.008691 -263.003011) (xy 109.992981 -262.952081)
			(xy 109.985038 -262.899377) (xy 105.97388 -262.899377) (xy 105.97388 -263.305798) (xy 105.974336 -263.315677)
			(xy 105.981772 -263.333983) (xy 105.988358 -263.341358) (xy 106.245914 -263.598914) (xy 106.249113 -263.602007)
			(xy 106.256397 -263.607115) (xy 106.260392 -263.609074) (xy 106.518249 -263.713193) (xy 113.27383 -263.713193)
			(xy 113.27383 -263.659895) (xy 113.281773 -263.607191) (xy 113.297483 -263.556261) (xy 113.320609 -263.50824)
			(xy 113.350633 -263.464203) (xy 113.386885 -263.425132) (xy 113.428556 -263.391901) (xy 113.474714 -263.365252)
			(xy 113.524328 -263.34578) (xy 113.57629 -263.33392) (xy 113.62944 -263.329937) (xy 113.68259 -263.33392)
			(xy 113.734552 -263.34578) (xy 113.784166 -263.365252) (xy 113.830324 -263.391901) (xy 113.871995 -263.425132)
			(xy 113.908247 -263.464203) (xy 113.938271 -263.50824) (xy 113.961397 -263.556261) (xy 113.977107 -263.607191)
			(xy 113.98505 -263.659895) (xy 113.985548 -263.686544) (xy 113.98505 -263.713193) (xy 113.977107 -263.765897)
			(xy 113.961397 -263.816827) (xy 113.938271 -263.864848) (xy 113.908247 -263.908885) (xy 113.871995 -263.947956)
			(xy 113.830324 -263.981187) (xy 113.784166 -264.007836) (xy 113.734552 -264.027308) (xy 113.68259 -264.039168)
			(xy 113.62944 -264.043152) (xy 113.57629 -264.039168) (xy 113.524328 -264.027308) (xy 113.474714 -264.007836)
			(xy 113.428556 -263.981187) (xy 113.386885 -263.947956) (xy 113.350633 -263.908885) (xy 113.320609 -263.864848)
			(xy 113.297483 -263.816827) (xy 113.281773 -263.765897) (xy 113.27383 -263.713193) (xy 106.518249 -263.713193)
			(xy 107.226608 -263.999218) (xy 107.233653 -264.002371) (xy 107.245536 -264.012207) (xy 107.249976 -264.018522)
			(xy 107.344464 -264.162794) (xy 107.378246 -264.173716) (xy 107.39501 -264.167366) (xy 107.425449 -264.156583)
			(xy 107.488963 -264.144953) (xy 107.521248 -264.144252) (xy 107.547055 -264.144707) (xy 107.598131 -264.15215)
			(xy 107.647597 -264.166888) (xy 107.694417 -264.188612) (xy 107.737611 -264.216868) (xy 107.776274 -264.251062)
			(xy 107.809596 -264.29048) (xy 107.836879 -264.334294) (xy 107.857551 -264.381588) (xy 107.87118 -264.431371)
			(xy 107.874816 -264.456926) (xy 107.87634 -264.469372) (xy 107.87761 -264.50036) (xy 107.877112 -264.527009)
			(xy 108.105438 -264.527009) (xy 108.105438 -264.473711) (xy 108.113381 -264.421007) (xy 108.129091 -264.370077)
			(xy 108.152217 -264.322056) (xy 108.182241 -264.278019) (xy 108.218493 -264.238948) (xy 108.260164 -264.205717)
			(xy 108.306322 -264.179068) (xy 108.355936 -264.159596) (xy 108.407898 -264.147736) (xy 108.461048 -264.143753)
			(xy 108.514198 -264.147736) (xy 108.56616 -264.159596) (xy 108.615774 -264.179068) (xy 108.661932 -264.205717)
			(xy 108.703603 -264.238948) (xy 108.739855 -264.278019) (xy 108.769879 -264.322056) (xy 108.793005 -264.370077)
			(xy 108.808715 -264.421007) (xy 108.816658 -264.473711) (xy 108.817156 -264.50036) (xy 108.816658 -264.527009)
			(xy 108.808715 -264.579713) (xy 108.793005 -264.630643) (xy 108.769879 -264.678664) (xy 108.739855 -264.722701)
			(xy 108.703603 -264.761772) (xy 108.661932 -264.795003) (xy 108.615774 -264.821652) (xy 108.56616 -264.841124)
			(xy 108.514198 -264.852984) (xy 108.461048 -264.856968) (xy 108.407898 -264.852984) (xy 108.355936 -264.841124)
			(xy 108.306322 -264.821652) (xy 108.260164 -264.795003) (xy 108.218493 -264.761772) (xy 108.182241 -264.722701)
			(xy 108.152217 -264.678664) (xy 108.129091 -264.630643) (xy 108.113381 -264.579713) (xy 108.105438 -264.527009)
			(xy 107.877112 -264.527009) (xy 107.877094 -264.527969) (xy 107.868582 -264.582528) (xy 107.851755 -264.63512)
			(xy 107.827015 -264.684486) (xy 107.794957 -264.729445) (xy 107.77601 -264.749534) (xy 107.773216 -264.752582)
			(xy 107.766679 -264.761214) (xy 107.760894 -264.782059) (xy 107.764181 -264.803441) (xy 107.76966 -264.81278)
			(xy 107.84078 -264.921238) (xy 107.865672 -264.959084) (xy 107.894882 -264.971022) (xy 107.910884 -264.967212)
			(xy 107.930921 -264.962873) (xy 107.971664 -264.958293) (xy 107.992164 -264.958068) (xy 107.992418 -264.958068)
			(xy 108.020339 -264.958708) (xy 108.075471 -264.967613) (xy 108.128537 -264.985015) (xy 108.178236 -265.010487)
			(xy 108.22335 -265.043404) (xy 108.262773 -265.08296) (xy 108.295538 -265.128184) (xy 108.320843 -265.177968)
			(xy 108.338067 -265.231092) (xy 108.346788 -265.286253) (xy 108.347256 -265.314176) (xy 108.346722 -265.340825)
			(xy 108.575338 -265.340825) (xy 108.575338 -265.287527) (xy 108.583281 -265.234823) (xy 108.598991 -265.183893)
			(xy 108.622117 -265.135872) (xy 108.652141 -265.091835) (xy 108.688393 -265.052764) (xy 108.730064 -265.019533)
			(xy 108.776222 -264.992884) (xy 108.825836 -264.973412) (xy 108.877798 -264.961552) (xy 108.930948 -264.957569)
			(xy 108.984098 -264.961552) (xy 109.03606 -264.973412) (xy 109.085674 -264.992884) (xy 109.131832 -265.019533)
			(xy 109.173503 -265.052764) (xy 109.209755 -265.091835) (xy 109.239779 -265.135872) (xy 109.262905 -265.183893)
			(xy 109.278615 -265.234823) (xy 109.286558 -265.287527) (xy 109.287056 -265.314176) (xy 109.286558 -265.340825)
			(xy 109.278615 -265.393529) (xy 109.262905 -265.444459) (xy 109.239779 -265.49248) (xy 109.209755 -265.536517)
			(xy 109.173503 -265.575588) (xy 109.131832 -265.608819) (xy 109.085674 -265.635468) (xy 109.03606 -265.65494)
			(xy 108.984098 -265.6668) (xy 108.930948 -265.670784) (xy 108.877798 -265.6668) (xy 108.825836 -265.65494)
			(xy 108.776222 -265.635468) (xy 108.730064 -265.608819) (xy 108.688393 -265.575588) (xy 108.652141 -265.536517)
			(xy 108.622117 -265.49248) (xy 108.598991 -265.444459) (xy 108.583281 -265.393529) (xy 108.575338 -265.340825)
			(xy 108.346722 -265.340825) (xy 108.346681 -265.342868) (xy 108.337481 -265.39951) (xy 108.319316 -265.453944)
			(xy 108.292656 -265.504759) (xy 108.275882 -265.528044) (xy 108.270802 -265.534902) (xy 108.265722 -265.550142)
			(xy 108.265722 -265.581638) (xy 108.26635 -265.593479) (xy 108.276957 -265.614654) (xy 108.286042 -265.622278)
			(xy 108.47578 -265.76528) (xy 108.481113 -265.768801) (xy 108.493071 -265.773301) (xy 108.499402 -265.77417)
			(xy 108.499656 -265.77417) (xy 108.526013 -265.777553) (xy 108.577389 -265.791127) (xy 108.626175 -265.812188)
			(xy 108.671288 -265.840267) (xy 108.711726 -265.874742) (xy 108.746589 -265.914845) (xy 108.775102 -265.959685)
			(xy 108.796633 -266.008265) (xy 108.810703 -266.059507) (xy 108.814362 -266.085828) (xy 108.817042 -266.111907)
			(xy 108.81588 -266.154895) (xy 109.045238 -266.154895) (xy 109.045238 -266.101597) (xy 109.053181 -266.048893)
			(xy 109.068891 -265.997963) (xy 109.092017 -265.949942) (xy 109.122041 -265.905905) (xy 109.158293 -265.866834)
			(xy 109.199964 -265.833603) (xy 109.246122 -265.806954) (xy 109.295736 -265.787482) (xy 109.347698 -265.775622)
			(xy 109.400848 -265.771639) (xy 109.453998 -265.775622) (xy 109.50596 -265.787482) (xy 109.555574 -265.806954)
			(xy 109.601732 -265.833603) (xy 109.643403 -265.866834) (xy 109.679655 -265.905905) (xy 109.709679 -265.949942)
			(xy 109.732805 -265.997963) (xy 109.748515 -266.048893) (xy 109.756458 -266.101597) (xy 109.756956 -266.128246)
			(xy 109.756458 -266.154895) (xy 109.748515 -266.207599) (xy 109.732805 -266.258529) (xy 109.709679 -266.30655)
			(xy 109.679655 -266.350587) (xy 109.643403 -266.389658) (xy 109.601732 -266.422889) (xy 109.555574 -266.449538)
			(xy 109.50596 -266.46901) (xy 109.453998 -266.48087) (xy 109.400848 -266.484854) (xy 109.347698 -266.48087)
			(xy 109.295736 -266.46901) (xy 109.246122 -266.449538) (xy 109.199964 -266.422889) (xy 109.158293 -266.389658)
			(xy 109.122041 -266.350587) (xy 109.092017 -266.30655) (xy 109.068891 -266.258529) (xy 109.053181 -266.207599)
			(xy 109.045238 -266.154895) (xy 108.81588 -266.154895) (xy 108.815625 -266.164313) (xy 108.806533 -266.215944)
			(xy 108.789964 -266.265681) (xy 108.778548 -266.289282) (xy 108.77296 -266.300204) (xy 108.77296 -266.348718)
			(xy 108.774757 -266.351832) (xy 108.779091 -266.357569) (xy 108.781596 -266.360148) (xy 109.01299 -266.591542)
			(xy 109.023912 -266.597892) (xy 109.030262 -266.59967) (xy 109.054727 -266.607237) (xy 109.101353 -266.628413)
			(xy 109.144467 -266.656047) (xy 109.18318 -266.689569) (xy 109.216694 -266.728289) (xy 109.24432 -266.771408)
			(xy 109.265487 -266.818038) (xy 109.273086 -266.842494) (xy 109.274864 -266.848844) (xy 109.281214 -266.859766)
			(xy 109.349032 -266.927584) (xy 109.355457 -266.933554) (xy 109.371273 -266.941103) (xy 109.388711 -266.942851)
			(xy 109.397292 -266.941046) (xy 109.485684 -266.913868) (xy 109.520482 -266.875514) (xy 109.523276 -266.86256)
			(xy 109.529669 -266.836682) (xy 109.549146 -266.787064) (xy 109.575801 -266.740905) (xy 109.60904 -266.699234)
			(xy 109.648119 -266.662984) (xy 109.692165 -266.632964) (xy 109.740194 -266.609845) (xy 109.791132 -266.594145)
			(xy 109.843842 -266.586213) (xy 109.870494 -266.5857) (xy 109.898479 -266.58622) (xy 109.953761 -266.594975)
			(xy 110.006993 -266.612271) (xy 110.056863 -266.637681) (xy 110.102145 -266.670579) (xy 110.141722 -266.710157)
			(xy 110.17462 -266.755438) (xy 110.20003 -266.805309) (xy 110.217325 -266.858541) (xy 110.22608 -266.913823)
			(xy 110.226602 -266.941808) (xy 110.226101 -266.969163) (xy 110.21773 -267.02323) (xy 110.201185 -267.075379)
			(xy 110.176857 -267.124383) (xy 110.145318 -267.169088) (xy 110.107311 -267.208441) (xy 110.06373 -267.241517)
			(xy 110.015603 -267.267536) (xy 109.964061 -267.285885) (xy 109.937296 -267.291566) (xy 109.923326 -267.29436)
			(xy 109.902498 -267.312902) (xy 109.87151 -267.414756) (xy 109.869659 -267.423363) (xy 109.871275 -267.440882)
			(xy 109.878735 -267.456814) (xy 109.884718 -267.46327) (xy 109.887258 -267.46581) (xy 109.897164 -267.489686)
			(xy 109.977174 -267.519912) (xy 110.016798 -267.534898) (xy 110.026538 -267.538102) (xy 110.047008 -267.537296)
			(xy 110.065521 -267.528526) (xy 110.072678 -267.521182) (xy 110.072932 -267.520928) (xy 110.089905 -267.502251)
			(xy 110.128215 -267.469397) (xy 110.170781 -267.442284) (xy 110.21675 -267.421454) (xy 110.2652 -267.407326)
			(xy 110.31516 -267.400183) (xy 110.340394 -267.39977) (xy 110.367047 -267.400243) (xy 110.419758 -267.408187)
			(xy 110.470696 -267.423898) (xy 110.518724 -267.447027) (xy 110.562767 -267.477055) (xy 110.601844 -267.513312)
			(xy 110.63508 -267.554988) (xy 110.661733 -267.601152) (xy 110.681209 -267.650773) (xy 110.69307 -267.702743)
			(xy 110.697054 -267.7559) (xy 110.69307 -267.809057) (xy 110.681209 -267.861027) (xy 110.661733 -267.910648)
			(xy 110.63508 -267.956812) (xy 110.601844 -267.998488) (xy 110.562767 -268.034745) (xy 110.518724 -268.064773)
			(xy 110.470696 -268.087902) (xy 110.419758 -268.103613) (xy 110.367047 -268.111557) (xy 110.340394 -268.111986)
			(xy 110.315161 -268.111545) (xy 110.265201 -268.104413) (xy 110.21675 -268.090293) (xy 110.170781 -268.069468)
			(xy 110.128216 -268.042356) (xy 110.089909 -268.009501) (xy 110.072932 -267.990828) (xy 110.072678 -267.990574)
			(xy 110.065508 -267.983256) (xy 110.046993 -267.974526) (xy 110.026541 -267.973689) (xy 110.016798 -267.976858)
			(xy 109.927644 -268.010386) (xy 109.918208 -268.014474) (xy 109.903396 -268.028711) (xy 109.895343 -268.047612)
			(xy 109.894878 -268.057884) (xy 109.894878 -268.169898) (xy 109.895409 -268.181435) (xy 109.905464 -268.202202)
			(xy 109.923592 -268.216475) (xy 109.934756 -268.219428) (xy 109.961715 -268.224893) (xy 110.013647 -268.243019)
			(xy 110.062176 -268.268914) (xy 110.106145 -268.301963) (xy 110.14451 -268.34138) (xy 110.176358 -268.386227)
			(xy 110.200932 -268.435437) (xy 110.217647 -268.487841) (xy 110.226105 -268.542192) (xy 110.226602 -268.569694)
			(xy 110.22608 -268.59699) (xy 110.217749 -268.650943) (xy 110.20128 -268.702992) (xy 110.177059 -268.751918)
			(xy 110.145655 -268.796574) (xy 110.107803 -268.835913) (xy 110.06439 -268.869014) (xy 110.016434 -268.8951)
			(xy 109.965058 -268.913562) (xy 109.911466 -268.923965) (xy 109.88421 -268.925548) (xy 109.874304 -268.926056)
			(xy 109.857286 -268.933422) (xy 109.688884 -269.101824) (xy 109.682728 -269.108565) (xy 109.675206 -269.125185)
			(xy 109.673942 -269.143384) (xy 109.679095 -269.160884) (xy 109.684312 -269.168372) (xy 109.701334 -269.19173)
			(xy 109.728377 -269.242805) (xy 109.746811 -269.29758) (xy 109.756149 -269.354613) (xy 109.756702 -269.38351)
			(xy 109.756204 -269.410159) (xy 109.984784 -269.410159) (xy 109.984784 -269.356861) (xy 109.992727 -269.304157)
			(xy 110.008437 -269.253227) (xy 110.031563 -269.205206) (xy 110.061587 -269.161169) (xy 110.097839 -269.122098)
			(xy 110.13951 -269.088867) (xy 110.185668 -269.062218) (xy 110.235282 -269.042746) (xy 110.287244 -269.030886)
			(xy 110.340394 -269.026903) (xy 110.393544 -269.030886) (xy 110.445506 -269.042746) (xy 110.49512 -269.062218)
			(xy 110.541278 -269.088867) (xy 110.582949 -269.122098) (xy 110.619201 -269.161169) (xy 110.649225 -269.205206)
			(xy 110.672351 -269.253227) (xy 110.688061 -269.304157) (xy 110.696004 -269.356861) (xy 110.696502 -269.38351)
			(xy 110.696004 -269.410159) (xy 110.688061 -269.462863) (xy 110.672351 -269.513793) (xy 110.649225 -269.561814)
			(xy 110.619201 -269.605851) (xy 110.582949 -269.644922) (xy 110.541278 -269.678153) (xy 110.49512 -269.704802)
			(xy 110.445506 -269.724274) (xy 110.393544 -269.736134) (xy 110.340394 -269.740118) (xy 110.287244 -269.736134)
			(xy 110.235282 -269.724274) (xy 110.185668 -269.704802) (xy 110.13951 -269.678153) (xy 110.097839 -269.644922)
			(xy 110.061587 -269.605851) (xy 110.031563 -269.561814) (xy 110.008437 -269.513793) (xy 109.992727 -269.462863)
			(xy 109.984784 -269.410159) (xy 109.756204 -269.410159) (xy 109.748261 -269.462863) (xy 109.732551 -269.513793)
			(xy 109.709425 -269.561814) (xy 109.679401 -269.605851) (xy 109.643149 -269.644922) (xy 109.601478 -269.678153)
			(xy 109.55532 -269.704802) (xy 109.505706 -269.724274) (xy 109.453744 -269.736134) (xy 109.400594 -269.740118)
			(xy 109.347444 -269.736134) (xy 109.295482 -269.724274) (xy 109.245868 -269.704802) (xy 109.19971 -269.678153)
			(xy 109.158039 -269.644922) (xy 109.121787 -269.605851) (xy 109.091763 -269.561814) (xy 109.068637 -269.513793)
			(xy 109.052927 -269.462863) (xy 109.044984 -269.410159) (xy 109.044486 -269.38351) (xy 109.044961 -269.357406)
			(xy 109.052609 -269.30576) (xy 109.059726 -269.28064) (xy 109.063282 -269.268956) (xy 109.058964 -269.245334)
			(xy 109.055662 -269.241016) (xy 109.003084 -269.170404) (xy 108.995528 -269.161205) (xy 108.974329 -269.150443)
			(xy 108.962444 -269.14983) (xy 108.898944 -269.14983) (xy 108.887078 -269.150526) (xy 108.8659 -269.16126)
			(xy 108.858304 -269.170404) (xy 108.805726 -269.241016) (xy 108.802424 -269.245334) (xy 108.798106 -269.268956)
			(xy 108.801662 -269.28064) (xy 108.808786 -269.305759) (xy 108.816439 -269.357405) (xy 108.816902 -269.38351)
			(xy 108.816352 -269.411492) (xy 108.807596 -269.466768) (xy 108.7903 -269.519993) (xy 108.764892 -269.569858)
			(xy 108.731995 -269.615134) (xy 108.692421 -269.654706) (xy 108.647144 -269.6876) (xy 108.597279 -269.713007)
			(xy 108.544052 -269.7303) (xy 108.488776 -269.739054) (xy 108.460794 -269.739618) (xy 108.435882 -269.739148)
			(xy 108.386551 -269.732144) (xy 108.362496 -269.725648) (xy 108.353742 -269.723506) (xy 108.335781 -269.724846)
			(xy 108.319402 -269.732338) (xy 108.306644 -269.74505) (xy 108.302552 -269.75308) (xy 108.296037 -269.766685)
			(xy 108.282189 -269.793487) (xy 108.274866 -269.806674) (xy 108.272326 -269.810992) (xy 108.269264 -269.816755)
			(xy 108.265907 -269.829361) (xy 108.265722 -269.835884) (xy 108.265722 -269.953232) (xy 108.265991 -269.96035)
			(xy 108.269979 -269.97402) (xy 108.273596 -269.980156) (xy 108.28909 -270.001037) (xy 108.314501 -270.046399)
			(xy 108.333049 -270.094973) (xy 108.344338 -270.145728) (xy 108.34813 -270.197584) (xy 108.346184 -270.224229)
			(xy 108.575084 -270.224229) (xy 108.575084 -270.170931) (xy 108.583027 -270.118227) (xy 108.598737 -270.067297)
			(xy 108.621863 -270.019276) (xy 108.651887 -269.975239) (xy 108.688139 -269.936168) (xy 108.72981 -269.902937)
			(xy 108.775968 -269.876288) (xy 108.825582 -269.856816) (xy 108.877544 -269.844956) (xy 108.930694 -269.840973)
			(xy 108.983844 -269.844956) (xy 109.035806 -269.856816) (xy 109.08542 -269.876288) (xy 109.131578 -269.902937)
			(xy 109.173249 -269.936168) (xy 109.209501 -269.975239) (xy 109.239525 -270.019276) (xy 109.262651 -270.067297)
			(xy 109.278361 -270.118227) (xy 109.286304 -270.170931) (xy 109.286802 -270.19758) (xy 109.286304 -270.224229)
			(xy 109.278361 -270.276933) (xy 109.262651 -270.327863) (xy 109.239525 -270.375884) (xy 109.209501 -270.419921)
			(xy 109.173249 -270.458992) (xy 109.131578 -270.492223) (xy 109.08542 -270.518872) (xy 109.035806 -270.538344)
			(xy 108.983844 -270.550204) (xy 108.930694 -270.554188) (xy 108.877544 -270.550204) (xy 108.825582 -270.538344)
			(xy 108.775968 -270.518872) (xy 108.72981 -270.492223) (xy 108.688139 -270.458992) (xy 108.651887 -270.419921)
			(xy 108.621863 -270.375884) (xy 108.598737 -270.327863) (xy 108.583027 -270.276933) (xy 108.575084 -270.224229)
			(xy 108.346184 -270.224229) (xy 108.344343 -270.249441) (xy 108.333058 -270.300196) (xy 108.314515 -270.348772)
			(xy 108.289107 -270.394136) (xy 108.273596 -270.415004) (xy 108.269985 -270.421145) (xy 108.265979 -270.434809)
			(xy 108.265722 -270.441928) (xy 108.265722 -270.56334) (xy 108.266335 -270.574378) (xy 108.275695 -270.59438)
			(xy 108.283756 -270.601948) (xy 108.346748 -270.653002) (xy 108.353744 -270.658091) (xy 108.370105 -270.663675)
			(xy 108.378752 -270.663924) (xy 108.386626 -270.663162) (xy 108.38688 -270.663162) (xy 108.38942 -270.6624)
			(xy 108.407072 -270.659045) (xy 108.442827 -270.655485) (xy 108.460794 -270.655288) (xy 108.487446 -270.655761)
			(xy 108.540154 -270.663704) (xy 108.591089 -270.679415) (xy 108.639115 -270.702542) (xy 108.683156 -270.732569)
			(xy 108.722231 -270.768824) (xy 108.755465 -270.810498) (xy 108.782117 -270.85666) (xy 108.801591 -270.906279)
			(xy 108.813453 -270.958246) (xy 108.817436 -271.0114) (xy 108.815439 -271.038045) (xy 109.044984 -271.038045)
			(xy 109.044984 -270.984747) (xy 109.052927 -270.932043) (xy 109.068637 -270.881113) (xy 109.091763 -270.833092)
			(xy 109.121787 -270.789055) (xy 109.158039 -270.749984) (xy 109.19971 -270.716753) (xy 109.245868 -270.690104)
			(xy 109.295482 -270.670632) (xy 109.347444 -270.658772) (xy 109.400594 -270.654789) (xy 109.453744 -270.658772)
			(xy 109.505706 -270.670632) (xy 109.55532 -270.690104) (xy 109.601478 -270.716753) (xy 109.643149 -270.749984)
			(xy 109.679401 -270.789055) (xy 109.709425 -270.833092) (xy 109.732551 -270.881113) (xy 109.748261 -270.932043)
			(xy 109.756204 -270.984747) (xy 109.756702 -271.011396) (xy 109.756204 -271.038045) (xy 109.984784 -271.038045)
			(xy 109.984784 -270.984747) (xy 109.992727 -270.932043) (xy 110.008437 -270.881113) (xy 110.031563 -270.833092)
			(xy 110.061587 -270.789055) (xy 110.097839 -270.749984) (xy 110.13951 -270.716753) (xy 110.185668 -270.690104)
			(xy 110.235282 -270.670632) (xy 110.287244 -270.658772) (xy 110.340394 -270.654789) (xy 110.393544 -270.658772)
			(xy 110.445506 -270.670632) (xy 110.49512 -270.690104) (xy 110.541278 -270.716753) (xy 110.582949 -270.749984)
			(xy 110.619201 -270.789055) (xy 110.649225 -270.833092) (xy 110.672351 -270.881113) (xy 110.688061 -270.932043)
			(xy 110.696004 -270.984747) (xy 110.696502 -271.011396) (xy 110.696004 -271.038045) (xy 110.688061 -271.090749)
			(xy 110.672351 -271.141679) (xy 110.649225 -271.1897) (xy 110.619201 -271.233737) (xy 110.582949 -271.272808)
			(xy 110.541278 -271.306039) (xy 110.49512 -271.332688) (xy 110.445506 -271.35216) (xy 110.393544 -271.36402)
			(xy 110.340394 -271.368004) (xy 110.287244 -271.36402) (xy 110.235282 -271.35216) (xy 110.185668 -271.332688)
			(xy 110.13951 -271.306039) (xy 110.097839 -271.272808) (xy 110.061587 -271.233737) (xy 110.031563 -271.1897)
			(xy 110.008437 -271.141679) (xy 109.992727 -271.090749) (xy 109.984784 -271.038045) (xy 109.756204 -271.038045)
			(xy 109.748261 -271.090749) (xy 109.732551 -271.141679) (xy 109.709425 -271.1897) (xy 109.679401 -271.233737)
			(xy 109.643149 -271.272808) (xy 109.601478 -271.306039) (xy 109.55532 -271.332688) (xy 109.505706 -271.35216)
			(xy 109.453744 -271.36402) (xy 109.400594 -271.368004) (xy 109.347444 -271.36402) (xy 109.295482 -271.35216)
			(xy 109.245868 -271.332688) (xy 109.19971 -271.306039) (xy 109.158039 -271.272808) (xy 109.121787 -271.233737)
			(xy 109.091763 -271.1897) (xy 109.068637 -271.141679) (xy 109.052927 -271.090749) (xy 109.044984 -271.038045)
			(xy 108.815439 -271.038045) (xy 108.813453 -271.064554) (xy 108.801591 -271.116521) (xy 108.782117 -271.16614)
			(xy 108.755465 -271.212302) (xy 108.722231 -271.253976) (xy 108.683156 -271.290231) (xy 108.639115 -271.320258)
			(xy 108.591089 -271.343385) (xy 108.540154 -271.359096) (xy 108.487446 -271.367039) (xy 108.460794 -271.367504)
			(xy 108.442504 -271.367294) (xy 108.406111 -271.3636) (xy 108.38815 -271.360138) (xy 108.376466 -271.357598)
			(xy 108.354876 -271.362932) (xy 108.284518 -271.420082) (xy 108.276116 -271.427698) (xy 108.266348 -271.448131)
			(xy 108.265722 -271.459452) (xy 108.265722 -271.580864) (xy 108.265995 -271.587981) (xy 108.269991 -271.601646)
			(xy 108.273596 -271.607788) (xy 108.289088 -271.628669) (xy 108.314495 -271.674031) (xy 108.333038 -271.722603)
			(xy 108.344323 -271.773356) (xy 108.34811 -271.82521) (xy 108.346162 -271.851861) (xy 108.575338 -271.851861)
			(xy 108.575338 -271.798563) (xy 108.583281 -271.745859) (xy 108.598991 -271.694929) (xy 108.622117 -271.646908)
			(xy 108.652141 -271.602871) (xy 108.688393 -271.5638) (xy 108.730064 -271.530569) (xy 108.776222 -271.50392)
			(xy 108.825836 -271.484448) (xy 108.877798 -271.472588) (xy 108.930948 -271.468605) (xy 108.984098 -271.472588)
			(xy 109.03606 -271.484448) (xy 109.085674 -271.50392) (xy 109.131832 -271.530569) (xy 109.173503 -271.5638)
			(xy 109.209755 -271.602871) (xy 109.239779 -271.646908) (xy 109.262905 -271.694929) (xy 109.278615 -271.745859)
			(xy 109.286558 -271.798563) (xy 109.287056 -271.825212) (xy 109.286558 -271.851861) (xy 109.51463 -271.851861)
			(xy 109.51463 -271.798563) (xy 109.522573 -271.745859) (xy 109.538283 -271.694929) (xy 109.561409 -271.646908)
			(xy 109.591433 -271.602871) (xy 109.627685 -271.5638) (xy 109.669356 -271.530569) (xy 109.715514 -271.50392)
			(xy 109.765128 -271.484448) (xy 109.81709 -271.472588) (xy 109.87024 -271.468605) (xy 109.92339 -271.472588)
			(xy 109.975352 -271.484448) (xy 110.024966 -271.50392) (xy 110.071124 -271.530569) (xy 110.112795 -271.5638)
			(xy 110.149047 -271.602871) (xy 110.179071 -271.646908) (xy 110.202197 -271.694929) (xy 110.217907 -271.745859)
			(xy 110.22585 -271.798563) (xy 110.226348 -271.825212) (xy 110.22585 -271.851861) (xy 110.217907 -271.904565)
			(xy 110.202197 -271.955495) (xy 110.179071 -272.003516) (xy 110.149047 -272.047553) (xy 110.112795 -272.086624)
			(xy 110.071124 -272.119855) (xy 110.024966 -272.146504) (xy 109.975352 -272.165976) (xy 109.92339 -272.177836)
			(xy 109.87024 -272.18182) (xy 109.81709 -272.177836) (xy 109.765128 -272.165976) (xy 109.715514 -272.146504)
			(xy 109.669356 -272.119855) (xy 109.627685 -272.086624) (xy 109.591433 -272.047553) (xy 109.561409 -272.003516)
			(xy 109.538283 -271.955495) (xy 109.522573 -271.904565) (xy 109.51463 -271.851861) (xy 109.286558 -271.851861)
			(xy 109.278615 -271.904565) (xy 109.262905 -271.955495) (xy 109.239779 -272.003516) (xy 109.209755 -272.047553)
			(xy 109.173503 -272.086624) (xy 109.131832 -272.119855) (xy 109.085674 -272.146504) (xy 109.03606 -272.165976)
			(xy 108.984098 -272.177836) (xy 108.930948 -272.18182) (xy 108.877798 -272.177836) (xy 108.825836 -272.165976)
			(xy 108.776222 -272.146504) (xy 108.730064 -272.119855) (xy 108.688393 -272.086624) (xy 108.652141 -272.047553)
			(xy 108.622117 -272.003516) (xy 108.598991 -271.955495) (xy 108.583281 -271.904565) (xy 108.575338 -271.851861)
			(xy 108.346162 -271.851861) (xy 108.34432 -271.877063) (xy 108.333032 -271.927815) (xy 108.314486 -271.976387)
			(xy 108.289077 -272.021747) (xy 108.273596 -272.042636) (xy 108.269989 -272.048778) (xy 108.265992 -272.062443)
			(xy 108.265722 -272.06956) (xy 108.265722 -272.191226) (xy 108.266332 -272.202265) (xy 108.275689 -272.222272)
			(xy 108.283756 -272.229834) (xy 108.346748 -272.280888) (xy 108.353743 -272.285978) (xy 108.370105 -272.291564)
			(xy 108.378752 -272.29181) (xy 108.386626 -272.291048) (xy 108.38688 -272.291048) (xy 108.38942 -272.290286)
			(xy 108.407072 -272.286931) (xy 108.442827 -272.283371) (xy 108.460794 -272.283174) (xy 108.487447 -272.283647)
			(xy 108.540157 -272.291591) (xy 108.591095 -272.307302) (xy 108.639122 -272.33043) (xy 108.683165 -272.360458)
			(xy 108.722241 -272.396714) (xy 108.755477 -272.43839) (xy 108.78213 -272.484554) (xy 108.801605 -272.534174)
			(xy 108.813466 -272.586144) (xy 108.81745 -272.6393) (xy 108.815454 -272.665931) (xy 109.044984 -272.665931)
			(xy 109.044984 -272.612633) (xy 109.052927 -272.559929) (xy 109.068637 -272.508999) (xy 109.091763 -272.460978)
			(xy 109.121787 -272.416941) (xy 109.158039 -272.37787) (xy 109.19971 -272.344639) (xy 109.245868 -272.31799)
			(xy 109.295482 -272.298518) (xy 109.347444 -272.286658) (xy 109.400594 -272.282675) (xy 109.453744 -272.286658)
			(xy 109.505706 -272.298518) (xy 109.55532 -272.31799) (xy 109.601478 -272.344639) (xy 109.643149 -272.37787)
			(xy 109.679401 -272.416941) (xy 109.709425 -272.460978) (xy 109.732551 -272.508999) (xy 109.748261 -272.559929)
			(xy 109.756204 -272.612633) (xy 109.756702 -272.639282) (xy 109.756204 -272.665931) (xy 109.984784 -272.665931)
			(xy 109.984784 -272.612633) (xy 109.992727 -272.559929) (xy 110.008437 -272.508999) (xy 110.031563 -272.460978)
			(xy 110.061587 -272.416941) (xy 110.097839 -272.37787) (xy 110.13951 -272.344639) (xy 110.185668 -272.31799)
			(xy 110.235282 -272.298518) (xy 110.287244 -272.286658) (xy 110.340394 -272.282675) (xy 110.393544 -272.286658)
			(xy 110.445506 -272.298518) (xy 110.49512 -272.31799) (xy 110.541278 -272.344639) (xy 110.582949 -272.37787)
			(xy 110.619201 -272.416941) (xy 110.649225 -272.460978) (xy 110.672351 -272.508999) (xy 110.688061 -272.559929)
			(xy 110.696004 -272.612633) (xy 110.696502 -272.639282) (xy 110.696004 -272.665931) (xy 110.688061 -272.718635)
			(xy 110.672351 -272.769565) (xy 110.649225 -272.817586) (xy 110.619201 -272.861623) (xy 110.582949 -272.900694)
			(xy 110.541278 -272.933925) (xy 110.49512 -272.960574) (xy 110.445506 -272.980046) (xy 110.393544 -272.991906)
			(xy 110.340394 -272.99589) (xy 110.287244 -272.991906) (xy 110.235282 -272.980046) (xy 110.185668 -272.960574)
			(xy 110.13951 -272.933925) (xy 110.097839 -272.900694) (xy 110.061587 -272.861623) (xy 110.031563 -272.817586)
			(xy 110.008437 -272.769565) (xy 109.992727 -272.718635) (xy 109.984784 -272.665931) (xy 109.756204 -272.665931)
			(xy 109.748261 -272.718635) (xy 109.732551 -272.769565) (xy 109.709425 -272.817586) (xy 109.679401 -272.861623)
			(xy 109.643149 -272.900694) (xy 109.601478 -272.933925) (xy 109.55532 -272.960574) (xy 109.505706 -272.980046)
			(xy 109.453744 -272.991906) (xy 109.400594 -272.99589) (xy 109.347444 -272.991906) (xy 109.295482 -272.980046)
			(xy 109.245868 -272.960574) (xy 109.19971 -272.933925) (xy 109.158039 -272.900694) (xy 109.121787 -272.861623)
			(xy 109.091763 -272.817586) (xy 109.068637 -272.769565) (xy 109.052927 -272.718635) (xy 109.044984 -272.665931)
			(xy 108.815454 -272.665931) (xy 108.813466 -272.692456) (xy 108.801605 -272.744426) (xy 108.78213 -272.794046)
			(xy 108.755477 -272.84021) (xy 108.722241 -272.881886) (xy 108.683165 -272.918142) (xy 108.639122 -272.94817)
			(xy 108.591095 -272.971298) (xy 108.540157 -272.987009) (xy 108.487447 -272.994953) (xy 108.460794 -272.99539)
			(xy 108.442504 -272.99518) (xy 108.406111 -272.991485) (xy 108.38815 -272.988024) (xy 108.376466 -272.985484)
			(xy 108.354876 -272.990818) (xy 108.284518 -273.047968) (xy 108.27613 -273.055589) (xy 108.266395 -273.076023)
			(xy 108.265722 -273.087338) (xy 108.265722 -273.20875) (xy 108.265993 -273.215868) (xy 108.269986 -273.229534)
			(xy 108.273596 -273.235674) (xy 108.290948 -273.259184) (xy 108.318551 -273.31068) (xy 108.337383 -273.36599)
			(xy 108.34694 -273.42363) (xy 108.34751 -273.452844) (xy 108.34751 -273.453098) (xy 108.601256 -273.453098)
			(xy 108.601764 -273.427211) (xy 108.609863 -273.376073) (xy 108.625862 -273.326833) (xy 108.649368 -273.280701)
			(xy 108.6798 -273.238814) (xy 108.71641 -273.202204) (xy 108.758297 -273.171772) (xy 108.804429 -273.148266)
			(xy 108.853669 -273.132267) (xy 108.904807 -273.124168) (xy 108.956581 -273.124168) (xy 109.007719 -273.132267)
			(xy 109.056959 -273.148266) (xy 109.103091 -273.171772) (xy 109.144978 -273.202204) (xy 109.181588 -273.238814)
			(xy 109.21202 -273.280701) (xy 109.235526 -273.326833) (xy 109.251525 -273.376073) (xy 109.259624 -273.427211)
			(xy 109.260132 -273.453098) (xy 109.259621 -273.479747) (xy 109.514884 -273.479747) (xy 109.514884 -273.426449)
			(xy 109.522827 -273.373745) (xy 109.538537 -273.322815) (xy 109.561663 -273.274794) (xy 109.591687 -273.230757)
			(xy 109.627939 -273.191686) (xy 109.66961 -273.158455) (xy 109.715768 -273.131806) (xy 109.765382 -273.112334)
			(xy 109.817344 -273.100474) (xy 109.870494 -273.096491) (xy 109.923644 -273.100474) (xy 109.975606 -273.112334)
			(xy 110.02522 -273.131806) (xy 110.071378 -273.158455) (xy 110.113049 -273.191686) (xy 110.149301 -273.230757)
			(xy 110.179325 -273.274794) (xy 110.202451 -273.322815) (xy 110.218161 -273.373745) (xy 110.226104 -273.426449)
			(xy 110.226602 -273.453098) (xy 110.226104 -273.479747) (xy 110.218161 -273.532451) (xy 110.202451 -273.583381)
			(xy 110.179325 -273.631402) (xy 110.149301 -273.675439) (xy 110.113049 -273.71451) (xy 110.071378 -273.747741)
			(xy 110.02522 -273.77439) (xy 109.975606 -273.793862) (xy 109.923644 -273.805722) (xy 109.870494 -273.809706)
			(xy 109.817344 -273.805722) (xy 109.765382 -273.793862) (xy 109.715768 -273.77439) (xy 109.66961 -273.747741)
			(xy 109.627939 -273.71451) (xy 109.591687 -273.675439) (xy 109.561663 -273.631402) (xy 109.538537 -273.583381)
			(xy 109.522827 -273.532451) (xy 109.514884 -273.479747) (xy 109.259621 -273.479747) (xy 109.259601 -273.480806)
			(xy 109.250407 -273.535453) (xy 109.241844 -273.56181) (xy 109.234224 -273.583654) (xy 109.439202 -273.938746)
			(xy 109.462062 -273.943064) (xy 109.486859 -273.948281) (xy 109.534598 -273.965264) (xy 109.579176 -273.989353)
			(xy 109.619543 -274.019979) (xy 109.654747 -274.056422) (xy 109.683961 -274.097824) (xy 109.706494 -274.143208)
			(xy 109.721817 -274.191505) (xy 109.729569 -274.241579) (xy 109.730032 -274.266914) (xy 109.729524 -274.292801)
			(xy 109.729403 -274.293563) (xy 109.984784 -274.293563) (xy 109.984784 -274.240265) (xy 109.992727 -274.187561)
			(xy 110.008437 -274.136631) (xy 110.031563 -274.08861) (xy 110.061587 -274.044573) (xy 110.097839 -274.005502)
			(xy 110.13951 -273.972271) (xy 110.185668 -273.945622) (xy 110.235282 -273.92615) (xy 110.287244 -273.91429)
			(xy 110.340394 -273.910307) (xy 110.393544 -273.91429) (xy 110.445506 -273.92615) (xy 110.49512 -273.945622)
			(xy 110.541278 -273.972271) (xy 110.582949 -274.005502) (xy 110.619201 -274.044573) (xy 110.649225 -274.08861)
			(xy 110.672351 -274.136631) (xy 110.688061 -274.187561) (xy 110.696004 -274.240265) (xy 110.696502 -274.266914)
			(xy 110.696004 -274.293563) (xy 110.688061 -274.346267) (xy 110.672351 -274.397197) (xy 110.649225 -274.445218)
			(xy 110.619201 -274.489255) (xy 110.582949 -274.528326) (xy 110.541278 -274.561557) (xy 110.49512 -274.588206)
			(xy 110.445506 -274.607678) (xy 110.393544 -274.619538) (xy 110.340394 -274.623522) (xy 110.287244 -274.619538)
			(xy 110.235282 -274.607678) (xy 110.185668 -274.588206) (xy 110.13951 -274.561557) (xy 110.097839 -274.528326)
			(xy 110.061587 -274.489255) (xy 110.031563 -274.445218) (xy 110.008437 -274.397197) (xy 109.992727 -274.346267)
			(xy 109.984784 -274.293563) (xy 109.729403 -274.293563) (xy 109.721425 -274.343939) (xy 109.705426 -274.393179)
			(xy 109.68192 -274.439311) (xy 109.651488 -274.481198) (xy 109.614878 -274.517808) (xy 109.572991 -274.54824)
			(xy 109.526859 -274.571746) (xy 109.477619 -274.587745) (xy 109.426481 -274.595844) (xy 109.374707 -274.595844)
			(xy 109.323569 -274.587745) (xy 109.274329 -274.571746) (xy 109.228197 -274.54824) (xy 109.18631 -274.517808)
			(xy 109.1497 -274.481198) (xy 109.119268 -274.439311) (xy 109.095762 -274.393179) (xy 109.079763 -274.343939)
			(xy 109.071664 -274.292801) (xy 109.071156 -274.266914) (xy 109.071691 -274.239206) (xy 109.080883 -274.184559)
			(xy 109.089444 -274.158202) (xy 109.097318 -274.136104) (xy 108.89234 -273.781266) (xy 108.86948 -273.776948)
			(xy 108.844673 -273.771718) (xy 108.796897 -273.754771) (xy 108.75228 -273.730708) (xy 108.711874 -273.700095)
			(xy 108.676632 -273.663656) (xy 108.647386 -273.622251) (xy 108.624826 -273.576855) (xy 108.609484 -273.528539)
			(xy 108.601721 -273.478444) (xy 108.601256 -273.453098) (xy 108.34751 -273.453098) (xy 108.347084 -273.477601)
			(xy 108.340336 -273.526142) (xy 108.327009 -273.573303) (xy 108.307352 -273.618196) (xy 108.281737 -273.659976)
			(xy 108.266484 -273.679158) (xy 108.265468 -273.680174) (xy 108.263944 -273.681952) (xy 108.253819 -273.693766)
			(xy 108.231818 -273.715771) (xy 108.220002 -273.725894) (xy 108.218224 -273.727418) (xy 107.86364 -274.082002)
			(xy 107.862624 -274.083018) (xy 107.86237 -274.083272) (xy 107.856189 -274.090533) (xy 107.849269 -274.108287)
			(xy 107.849351 -274.127342) (xy 107.852464 -274.136358) (xy 107.863912 -274.16758) (xy 107.876308 -274.232907)
			(xy 107.877102 -274.266152) (xy 107.877102 -274.266914) (xy 107.876578 -274.293563) (xy 108.105438 -274.293563)
			(xy 108.105438 -274.240265) (xy 108.113381 -274.187561) (xy 108.129091 -274.136631) (xy 108.152217 -274.08861)
			(xy 108.182241 -274.044573) (xy 108.218493 -274.005502) (xy 108.260164 -273.972271) (xy 108.306322 -273.945622)
			(xy 108.355936 -273.92615) (xy 108.407898 -273.91429) (xy 108.461048 -273.910307) (xy 108.514198 -273.91429)
			(xy 108.56616 -273.92615) (xy 108.615774 -273.945622) (xy 108.661932 -273.972271) (xy 108.703603 -274.005502)
			(xy 108.739855 -274.044573) (xy 108.769879 -274.08861) (xy 108.793005 -274.136631) (xy 108.808715 -274.187561)
			(xy 108.816658 -274.240265) (xy 108.817156 -274.266914) (xy 108.816658 -274.293563) (xy 108.808715 -274.346267)
			(xy 108.793005 -274.397197) (xy 108.769879 -274.445218) (xy 108.739855 -274.489255) (xy 108.703603 -274.528326)
			(xy 108.661932 -274.561557) (xy 108.615774 -274.588206) (xy 108.56616 -274.607678) (xy 108.514198 -274.619538)
			(xy 108.461048 -274.623522) (xy 108.407898 -274.619538) (xy 108.355936 -274.607678) (xy 108.306322 -274.588206)
			(xy 108.260164 -274.561557) (xy 108.218493 -274.528326) (xy 108.182241 -274.489255) (xy 108.152217 -274.445218)
			(xy 108.129091 -274.397197) (xy 108.113381 -274.346267) (xy 108.105438 -274.293563) (xy 107.876578 -274.293563)
			(xy 107.876552 -274.294896) (xy 107.867795 -274.350171) (xy 107.850499 -274.403396) (xy 107.82509 -274.45326)
			(xy 107.792194 -274.498535) (xy 107.75262 -274.538107) (xy 107.707343 -274.571001) (xy 107.657478 -274.596407)
			(xy 107.604252 -274.6137) (xy 107.548976 -274.622454) (xy 107.520994 -274.623022) (xy 107.520232 -274.623022)
			(xy 107.486984 -274.622257) (xy 107.421654 -274.609854) (xy 107.390438 -274.598384) (xy 107.381076 -274.59522)
			(xy 107.361334 -274.595492) (xy 107.343145 -274.603171) (xy 107.335828 -274.609814) (xy 107.280964 -274.664678)
			(xy 107.273981 -274.672429) (xy 107.266384 -274.691837) (xy 107.266232 -274.70227) (xy 107.269026 -274.786852)
			(xy 107.277916 -274.805648) (xy 107.286044 -274.81276) (xy 107.304767 -274.829758) (xy 107.337701 -274.868132)
			(xy 107.364878 -274.910777) (xy 107.385753 -274.956836) (xy 107.399905 -275.005384) (xy 107.407051 -275.055446)
			(xy 107.407456 -275.08073) (xy 107.661456 -275.08073) (xy 107.661964 -275.054823) (xy 107.67007 -275.003646)
			(xy 107.686082 -274.954367) (xy 107.709605 -274.9082) (xy 107.740061 -274.866281) (xy 107.776699 -274.829643)
			(xy 107.818618 -274.799187) (xy 107.864785 -274.775664) (xy 107.914064 -274.759652) (xy 107.965241 -274.751546)
			(xy 108.017055 -274.751546) (xy 108.068232 -274.759652) (xy 108.117511 -274.775664) (xy 108.163678 -274.799187)
			(xy 108.205597 -274.829643) (xy 108.242235 -274.866281) (xy 108.272691 -274.9082) (xy 108.296214 -274.954367)
			(xy 108.312226 -275.003646) (xy 108.320332 -275.054823) (xy 108.32084 -275.08073) (xy 108.320255 -275.107379)
			(xy 108.575084 -275.107379) (xy 108.575084 -275.054081) (xy 108.583027 -275.001377) (xy 108.598737 -274.950447)
			(xy 108.621863 -274.902426) (xy 108.651887 -274.858389) (xy 108.688139 -274.819318) (xy 108.72981 -274.786087)
			(xy 108.775968 -274.759438) (xy 108.825582 -274.739966) (xy 108.877544 -274.728106) (xy 108.930694 -274.724123)
			(xy 108.983844 -274.728106) (xy 109.035806 -274.739966) (xy 109.08542 -274.759438) (xy 109.131578 -274.786087)
			(xy 109.173249 -274.819318) (xy 109.209501 -274.858389) (xy 109.239525 -274.902426) (xy 109.262651 -274.950447)
			(xy 109.278361 -275.001377) (xy 109.286304 -275.054081) (xy 109.286802 -275.08073) (xy 109.286304 -275.107379)
			(xy 109.514884 -275.107379) (xy 109.514884 -275.054081) (xy 109.522827 -275.001377) (xy 109.538537 -274.950447)
			(xy 109.561663 -274.902426) (xy 109.591687 -274.858389) (xy 109.627939 -274.819318) (xy 109.66961 -274.786087)
			(xy 109.715768 -274.759438) (xy 109.765382 -274.739966) (xy 109.817344 -274.728106) (xy 109.870494 -274.724123)
			(xy 109.923644 -274.728106) (xy 109.975606 -274.739966) (xy 110.02522 -274.759438) (xy 110.071378 -274.786087)
			(xy 110.113049 -274.819318) (xy 110.149301 -274.858389) (xy 110.179325 -274.902426) (xy 110.202451 -274.950447)
			(xy 110.218161 -275.001377) (xy 110.226104 -275.054081) (xy 110.226602 -275.08073) (xy 110.226104 -275.107379)
			(xy 110.218161 -275.160083) (xy 110.202451 -275.211013) (xy 110.179325 -275.259034) (xy 110.149301 -275.303071)
			(xy 110.113049 -275.342142) (xy 110.071378 -275.375373) (xy 110.02522 -275.402022) (xy 109.975606 -275.421494)
			(xy 109.923644 -275.433354) (xy 109.870494 -275.437338) (xy 109.817344 -275.433354) (xy 109.765382 -275.421494)
			(xy 109.715768 -275.402022) (xy 109.66961 -275.375373) (xy 109.627939 -275.342142) (xy 109.591687 -275.303071)
			(xy 109.561663 -275.259034) (xy 109.538537 -275.211013) (xy 109.522827 -275.160083) (xy 109.514884 -275.107379)
			(xy 109.286304 -275.107379) (xy 109.278361 -275.160083) (xy 109.262651 -275.211013) (xy 109.239525 -275.259034)
			(xy 109.209501 -275.303071) (xy 109.173249 -275.342142) (xy 109.131578 -275.375373) (xy 109.08542 -275.402022)
			(xy 109.035806 -275.421494) (xy 108.983844 -275.433354) (xy 108.930694 -275.437338) (xy 108.877544 -275.433354)
			(xy 108.825582 -275.421494) (xy 108.775968 -275.402022) (xy 108.72981 -275.375373) (xy 108.688139 -275.342142)
			(xy 108.651887 -275.303071) (xy 108.621863 -275.259034) (xy 108.598737 -275.211013) (xy 108.583027 -275.160083)
			(xy 108.575084 -275.107379) (xy 108.320255 -275.107379) (xy 108.320232 -275.108447) (xy 108.310918 -275.163093)
			(xy 108.302298 -275.189442) (xy 108.294424 -275.21154) (xy 108.499656 -275.566632) (xy 108.522516 -275.57095)
			(xy 108.547321 -275.576185) (xy 108.595097 -275.593131) (xy 108.639715 -275.617194) (xy 108.680121 -275.647805)
			(xy 108.715363 -275.684244) (xy 108.744609 -275.725649) (xy 108.767169 -275.771044) (xy 108.782512 -275.819359)
			(xy 108.790275 -275.869454) (xy 108.79074 -275.8948) (xy 108.790232 -275.920707) (xy 108.782126 -275.971884)
			(xy 108.766114 -276.021163) (xy 108.742591 -276.06733) (xy 108.712135 -276.109249) (xy 108.675497 -276.145887)
			(xy 108.633578 -276.176343) (xy 108.587411 -276.199866) (xy 108.538132 -276.215878) (xy 108.486955 -276.223984)
			(xy 108.435141 -276.223984) (xy 108.383964 -276.215878) (xy 108.334685 -276.199866) (xy 108.288518 -276.176343)
			(xy 108.246599 -276.145887) (xy 108.209961 -276.109249) (xy 108.179505 -276.06733) (xy 108.155982 -276.021163)
			(xy 108.13997 -275.971884) (xy 108.131864 -275.920707) (xy 108.131356 -275.8948) (xy 108.131947 -275.867082)
			(xy 108.141272 -275.812436) (xy 108.149898 -275.786088) (xy 108.157772 -275.76399) (xy 107.95254 -275.408898)
			(xy 107.92968 -275.40458) (xy 107.904858 -275.399414) (xy 107.857077 -275.382462) (xy 107.812456 -275.358392)
			(xy 107.772048 -275.327773) (xy 107.736806 -275.291325) (xy 107.707562 -275.249911) (xy 107.685006 -275.204506)
			(xy 107.66967 -275.156182) (xy 107.661916 -275.10608) (xy 107.661456 -275.08073) (xy 107.407456 -275.08073)
			(xy 107.406905 -275.108713) (xy 107.398146 -275.163989) (xy 107.38085 -275.217215) (xy 107.355441 -275.267081)
			(xy 107.322545 -275.312358) (xy 107.282972 -275.351933) (xy 107.237696 -275.384831) (xy 107.187832 -275.410243)
			(xy 107.134607 -275.427542) (xy 107.079331 -275.436303) (xy 107.051348 -275.436838) (xy 107.026067 -275.436393)
			(xy 106.976013 -275.42924) (xy 106.927473 -275.415086) (xy 106.88142 -275.394214) (xy 106.838778 -275.367044)
			(xy 106.800404 -275.33412) (xy 106.783378 -275.315426) (xy 106.776266 -275.307298) (xy 106.75747 -275.298408)
			(xy 106.672888 -275.295614) (xy 106.662453 -275.295748) (xy 106.643041 -275.303352) (xy 106.635296 -275.310346)
			(xy 106.552492 -275.39315) (xy 106.548246 -275.397626) (xy 106.541817 -275.408151) (xy 106.539792 -275.413978)
			(xy 106.53903 -275.416772) (xy 106.537552 -275.423716) (xy 106.538058 -275.437898) (xy 106.540046 -275.444712)
			(xy 106.571542 -275.532596) (xy 106.613706 -275.56587) (xy 106.627422 -275.567648) (xy 106.653208 -275.571765)
			(xy 106.703131 -275.587071) (xy 106.75002 -275.610049) (xy 106.792704 -275.640125) (xy 106.830119 -275.676549)
			(xy 106.846116 -275.697188) (xy 107.257088 -275.697188) (xy 107.272762 -275.677053) (xy 107.309271 -275.641408)
			(xy 107.350837 -275.611815) (xy 107.396465 -275.588978) (xy 107.445067 -275.573443) (xy 107.495482 -275.565581)
			(xy 107.520994 -275.565108) (xy 107.546904 -275.565589) (xy 107.598085 -275.573695) (xy 107.647369 -275.589707)
			(xy 107.693541 -275.613232) (xy 107.735464 -275.64369) (xy 107.772106 -275.680332) (xy 107.802565 -275.722254)
			(xy 107.826091 -275.768426) (xy 107.842104 -275.817709) (xy 107.85021 -275.86889) (xy 107.85021 -275.92071)
			(xy 107.842104 -275.971891) (xy 107.826091 -276.021174) (xy 107.802565 -276.067346) (xy 107.772106 -276.109268)
			(xy 107.735464 -276.14591) (xy 107.693541 -276.176368) (xy 107.647369 -276.199893) (xy 107.598085 -276.215905)
			(xy 107.546904 -276.224011) (xy 107.520994 -276.224492) (xy 107.495482 -276.224014) (xy 107.445068 -276.216152)
			(xy 107.396467 -276.200618) (xy 107.350839 -276.177781) (xy 107.309275 -276.148188) (xy 107.272765 -276.112544)
			(xy 107.257088 -276.092412) (xy 106.846116 -276.092412) (xy 106.830398 -276.112654) (xy 106.793769 -276.148493)
			(xy 106.752053 -276.178257) (xy 106.706247 -276.201234) (xy 106.657446 -276.216875) (xy 106.606817 -276.224805)
			(xy 106.581194 -276.225254) (xy 106.554921 -276.224746) (xy 106.503038 -276.216428) (xy 106.453127 -276.200001)
			(xy 106.406444 -276.17588) (xy 106.364169 -276.144673) (xy 106.327367 -276.107168) (xy 106.296966 -276.064311)
			(xy 106.273732 -276.017181) (xy 106.258252 -275.966967) (xy 106.254042 -275.941028) (xy 106.252264 -275.927312)
			(xy 106.21899 -275.885148) (xy 106.131106 -275.853652) (xy 106.124288 -275.851688) (xy 106.110113 -275.851185)
			(xy 106.103166 -275.852636) (xy 106.100372 -275.853398) (xy 106.094534 -275.855403) (xy 106.083988 -275.861815)
			(xy 106.079544 -275.866098) (xy 106.00436 -275.941282) (xy 105.999238 -275.946741) (xy 105.992141 -275.959912)
			(xy 105.99039 -275.96719) (xy 105.984789 -275.991964) (xy 105.967508 -276.039724) (xy 105.94362 -276.084545)
			(xy 105.913607 -276.125519) (xy 105.896156 -276.143974) (xy 105.877169 -276.162656) (xy 105.834654 -276.194746)
			(xy 105.787839 -276.220154) (xy 105.737765 -276.238315) (xy 105.711752 -276.24405) (xy 105.705208 -276.245923)
			(xy 105.693359 -276.252613) (xy 105.688384 -276.257258) (xy 105.452926 -276.492716) (xy 105.448608 -276.527006)
			(xy 105.457244 -276.541992) (xy 105.47134 -276.567386) (xy 105.491371 -276.621899) (xy 105.501577 -276.679071)
			(xy 105.502202 -276.708108) (xy 105.502202 -276.708616) (xy 105.501742 -276.734025) (xy 105.50155 -276.735265)
			(xy 105.755684 -276.735265) (xy 105.755684 -276.681967) (xy 105.763627 -276.629263) (xy 105.779337 -276.578333)
			(xy 105.802463 -276.530312) (xy 105.832487 -276.486275) (xy 105.868739 -276.447204) (xy 105.91041 -276.413973)
			(xy 105.956568 -276.387324) (xy 106.006182 -276.367852) (xy 106.058144 -276.355992) (xy 106.111294 -276.352009)
			(xy 106.164444 -276.355992) (xy 106.216406 -276.367852) (xy 106.26602 -276.387324) (xy 106.312178 -276.413973)
			(xy 106.353849 -276.447204) (xy 106.390101 -276.486275) (xy 106.420125 -276.530312) (xy 106.443251 -276.578333)
			(xy 106.458961 -276.629263) (xy 106.466904 -276.681967) (xy 106.467402 -276.708616) (xy 106.466904 -276.735265)
			(xy 106.458961 -276.787969) (xy 106.443251 -276.838899) (xy 106.420125 -276.88692) (xy 106.390101 -276.930957)
			(xy 106.353849 -276.970028) (xy 106.312178 -277.003259) (xy 106.26602 -277.029908) (xy 106.216406 -277.04938)
			(xy 106.164444 -277.06124) (xy 106.111294 -277.065224) (xy 106.058144 -277.06124) (xy 106.006182 -277.04938)
			(xy 105.956568 -277.029908) (xy 105.91041 -277.003259) (xy 105.868739 -276.970028) (xy 105.832487 -276.930957)
			(xy 105.802463 -276.88692) (xy 105.779337 -276.838899) (xy 105.763627 -276.787969) (xy 105.755684 -276.735265)
			(xy 105.50155 -276.735265) (xy 105.493971 -276.784245) (xy 105.4786 -276.832683) (xy 105.455992 -276.878195)
			(xy 105.42668 -276.919707) (xy 105.391356 -276.95624) (xy 105.350853 -276.986931) (xy 105.306127 -277.011057)
			(xy 105.258234 -277.028048) (xy 105.208303 -277.037503) (xy 105.182924 -277.038816) (xy 105.172764 -277.03907)
			(xy 105.155238 -277.046944) (xy 105.136442 -277.066248) (xy 105.099104 -277.10511) (xy 105.092622 -277.112462)
			(xy 105.085302 -277.130624) (xy 105.08488 -277.140416) (xy 105.08488 -277.549081) (xy 105.285784 -277.549081)
			(xy 105.285784 -277.495783) (xy 105.293727 -277.443079) (xy 105.309437 -277.392149) (xy 105.332563 -277.344128)
			(xy 105.362587 -277.300091) (xy 105.398839 -277.26102) (xy 105.44051 -277.227789) (xy 105.486668 -277.20114)
			(xy 105.536282 -277.181668) (xy 105.588244 -277.169808) (xy 105.641394 -277.165825) (xy 105.694544 -277.169808)
			(xy 105.746506 -277.181668) (xy 105.79612 -277.20114) (xy 105.842278 -277.227789) (xy 105.883949 -277.26102)
			(xy 105.920201 -277.300091) (xy 105.950225 -277.344128) (xy 105.973351 -277.392149) (xy 105.989061 -277.443079)
			(xy 105.997004 -277.495783) (xy 105.997502 -277.522432) (xy 106.251756 -277.522432) (xy 106.252213 -277.497097)
			(xy 106.259974 -277.447026) (xy 106.275303 -277.39873) (xy 106.297839 -277.353349) (xy 106.327053 -277.311948)
			(xy 106.362255 -277.275504) (xy 106.402618 -277.244873) (xy 106.447192 -277.220777) (xy 106.494926 -277.203783)
			(xy 106.519726 -277.198582) (xy 106.542586 -277.194264) (xy 106.747818 -276.838918) (xy 106.740198 -276.817074)
			(xy 106.731593 -276.790786) (xy 106.722266 -276.736269) (xy 106.721656 -276.708616) (xy 106.722164 -276.682709)
			(xy 106.73027 -276.631532) (xy 106.746282 -276.582253) (xy 106.769805 -276.536086) (xy 106.800261 -276.494167)
			(xy 106.836899 -276.457529) (xy 106.878818 -276.427073) (xy 106.924985 -276.40355) (xy 106.974264 -276.387538)
			(xy 107.025441 -276.379432) (xy 107.077255 -276.379432) (xy 107.128432 -276.387538) (xy 107.177711 -276.40355)
			(xy 107.223878 -276.427073) (xy 107.265797 -276.457529) (xy 107.302435 -276.494167) (xy 107.332891 -276.536086)
			(xy 107.356414 -276.582253) (xy 107.372426 -276.631532) (xy 107.380532 -276.682709) (xy 107.38104 -276.708616)
			(xy 107.380628 -276.733993) (xy 107.380431 -276.735265) (xy 107.635538 -276.735265) (xy 107.635538 -276.681967)
			(xy 107.643481 -276.629263) (xy 107.659191 -276.578333) (xy 107.682317 -276.530312) (xy 107.712341 -276.486275)
			(xy 107.748593 -276.447204) (xy 107.790264 -276.413973) (xy 107.836422 -276.387324) (xy 107.886036 -276.367852)
			(xy 107.937998 -276.355992) (xy 107.991148 -276.352009) (xy 108.044298 -276.355992) (xy 108.09626 -276.367852)
			(xy 108.145874 -276.387324) (xy 108.192032 -276.413973) (xy 108.233703 -276.447204) (xy 108.269955 -276.486275)
			(xy 108.299979 -276.530312) (xy 108.323105 -276.578333) (xy 108.338815 -276.629263) (xy 108.346758 -276.681967)
			(xy 108.347256 -276.708616) (xy 108.601256 -276.708616) (xy 108.601789 -276.683284) (xy 108.609538 -276.633215)
			(xy 108.624856 -276.584922) (xy 108.647381 -276.53954) (xy 108.676585 -276.498139) (xy 108.711779 -276.461694)
			(xy 108.752134 -276.431062) (xy 108.796701 -276.406964) (xy 108.844429 -276.389968) (xy 108.869226 -276.384766)
			(xy 108.892086 -276.380448) (xy 109.097064 -276.02561) (xy 109.08919 -276.003766) (xy 109.080545 -275.977358)
			(xy 109.071224 -275.922582) (xy 109.070648 -275.8948) (xy 109.071156 -275.868893) (xy 109.079262 -275.817716)
			(xy 109.095274 -275.768437) (xy 109.118797 -275.72227) (xy 109.149253 -275.680351) (xy 109.185891 -275.643713)
			(xy 109.22781 -275.613257) (xy 109.273977 -275.589734) (xy 109.323256 -275.573722) (xy 109.374433 -275.565616)
			(xy 109.426247 -275.565616) (xy 109.477424 -275.573722) (xy 109.526703 -275.589734) (xy 109.57287 -275.613257)
			(xy 109.614789 -275.643713) (xy 109.651427 -275.680351) (xy 109.681883 -275.72227) (xy 109.705406 -275.768437)
			(xy 109.721418 -275.817716) (xy 109.729524 -275.868893) (xy 109.730032 -275.8948) (xy 109.729566 -275.920146)
			(xy 109.729364 -275.921449) (xy 109.984784 -275.921449) (xy 109.984784 -275.868151) (xy 109.992727 -275.815447)
			(xy 110.008437 -275.764517) (xy 110.031563 -275.716496) (xy 110.061587 -275.672459) (xy 110.097839 -275.633388)
			(xy 110.13951 -275.600157) (xy 110.185668 -275.573508) (xy 110.235282 -275.554036) (xy 110.287244 -275.542176)
			(xy 110.340394 -275.538193) (xy 110.393544 -275.542176) (xy 110.445506 -275.554036) (xy 110.49512 -275.573508)
			(xy 110.541278 -275.600157) (xy 110.582949 -275.633388) (xy 110.619201 -275.672459) (xy 110.649225 -275.716496)
			(xy 110.672351 -275.764517) (xy 110.688061 -275.815447) (xy 110.696004 -275.868151) (xy 110.696502 -275.8948)
			(xy 110.696004 -275.921449) (xy 113.744238 -275.921449) (xy 113.744238 -275.868151) (xy 113.752181 -275.815447)
			(xy 113.767891 -275.764517) (xy 113.791017 -275.716496) (xy 113.821041 -275.672459) (xy 113.857293 -275.633388)
			(xy 113.898964 -275.600157) (xy 113.945122 -275.573508) (xy 113.994736 -275.554036) (xy 114.046698 -275.542176)
			(xy 114.099848 -275.538193) (xy 114.152998 -275.542176) (xy 114.20496 -275.554036) (xy 114.254574 -275.573508)
			(xy 114.300732 -275.600157) (xy 114.342403 -275.633388) (xy 114.378655 -275.672459) (xy 114.408679 -275.716496)
			(xy 114.431805 -275.764517) (xy 114.447515 -275.815447) (xy 114.455458 -275.868151) (xy 114.455956 -275.8948)
			(xy 114.455458 -275.921449) (xy 114.683784 -275.921449) (xy 114.683784 -275.868151) (xy 114.691727 -275.815447)
			(xy 114.707437 -275.764517) (xy 114.730563 -275.716496) (xy 114.760587 -275.672459) (xy 114.796839 -275.633388)
			(xy 114.83851 -275.600157) (xy 114.884668 -275.573508) (xy 114.934282 -275.554036) (xy 114.986244 -275.542176)
			(xy 115.039394 -275.538193) (xy 115.092544 -275.542176) (xy 115.144506 -275.554036) (xy 115.19412 -275.573508)
			(xy 115.240278 -275.600157) (xy 115.281949 -275.633388) (xy 115.318201 -275.672459) (xy 115.348225 -275.716496)
			(xy 115.371351 -275.764517) (xy 115.387061 -275.815447) (xy 115.395004 -275.868151) (xy 115.395502 -275.8948)
			(xy 115.395004 -275.921449) (xy 115.623584 -275.921449) (xy 115.623584 -275.868151) (xy 115.631527 -275.815447)
			(xy 115.647237 -275.764517) (xy 115.670363 -275.716496) (xy 115.700387 -275.672459) (xy 115.736639 -275.633388)
			(xy 115.77831 -275.600157) (xy 115.824468 -275.573508) (xy 115.874082 -275.554036) (xy 115.926044 -275.542176)
			(xy 115.979194 -275.538193) (xy 116.032344 -275.542176) (xy 116.084306 -275.554036) (xy 116.13392 -275.573508)
			(xy 116.180078 -275.600157) (xy 116.221749 -275.633388) (xy 116.258001 -275.672459) (xy 116.288025 -275.716496)
			(xy 116.311151 -275.764517) (xy 116.326861 -275.815447) (xy 116.334804 -275.868151) (xy 116.335302 -275.8948)
			(xy 116.334804 -275.921449) (xy 116.563384 -275.921449) (xy 116.563384 -275.868151) (xy 116.571327 -275.815447)
			(xy 116.587037 -275.764517) (xy 116.610163 -275.716496) (xy 116.640187 -275.672459) (xy 116.676439 -275.633388)
			(xy 116.71811 -275.600157) (xy 116.764268 -275.573508) (xy 116.813882 -275.554036) (xy 116.865844 -275.542176)
			(xy 116.918994 -275.538193) (xy 116.972144 -275.542176) (xy 117.024106 -275.554036) (xy 117.07372 -275.573508)
			(xy 117.119878 -275.600157) (xy 117.161549 -275.633388) (xy 117.197801 -275.672459) (xy 117.227825 -275.716496)
			(xy 117.250951 -275.764517) (xy 117.266661 -275.815447) (xy 117.274604 -275.868151) (xy 117.275102 -275.8948)
			(xy 117.274604 -275.921449) (xy 117.266661 -275.974153) (xy 117.250951 -276.025083) (xy 117.227825 -276.073104)
			(xy 117.197801 -276.117141) (xy 117.161549 -276.156212) (xy 117.119878 -276.189443) (xy 117.07372 -276.216092)
			(xy 117.024106 -276.235564) (xy 116.972144 -276.247424) (xy 116.918994 -276.251408) (xy 116.865844 -276.247424)
			(xy 116.813882 -276.235564) (xy 116.764268 -276.216092) (xy 116.71811 -276.189443) (xy 116.676439 -276.156212)
			(xy 116.640187 -276.117141) (xy 116.610163 -276.073104) (xy 116.587037 -276.025083) (xy 116.571327 -275.974153)
			(xy 116.563384 -275.921449) (xy 116.334804 -275.921449) (xy 116.326861 -275.974153) (xy 116.311151 -276.025083)
			(xy 116.288025 -276.073104) (xy 116.258001 -276.117141) (xy 116.221749 -276.156212) (xy 116.180078 -276.189443)
			(xy 116.13392 -276.216092) (xy 116.084306 -276.235564) (xy 116.032344 -276.247424) (xy 115.979194 -276.251408)
			(xy 115.926044 -276.247424) (xy 115.874082 -276.235564) (xy 115.824468 -276.216092) (xy 115.77831 -276.189443)
			(xy 115.736639 -276.156212) (xy 115.700387 -276.117141) (xy 115.670363 -276.073104) (xy 115.647237 -276.025083)
			(xy 115.631527 -275.974153) (xy 115.623584 -275.921449) (xy 115.395004 -275.921449) (xy 115.387061 -275.974153)
			(xy 115.371351 -276.025083) (xy 115.348225 -276.073104) (xy 115.318201 -276.117141) (xy 115.281949 -276.156212)
			(xy 115.240278 -276.189443) (xy 115.19412 -276.216092) (xy 115.144506 -276.235564) (xy 115.092544 -276.247424)
			(xy 115.039394 -276.251408) (xy 114.986244 -276.247424) (xy 114.934282 -276.235564) (xy 114.884668 -276.216092)
			(xy 114.83851 -276.189443) (xy 114.796839 -276.156212) (xy 114.760587 -276.117141) (xy 114.730563 -276.073104)
			(xy 114.707437 -276.025083) (xy 114.691727 -275.974153) (xy 114.683784 -275.921449) (xy 114.455458 -275.921449)
			(xy 114.447515 -275.974153) (xy 114.431805 -276.025083) (xy 114.408679 -276.073104) (xy 114.378655 -276.117141)
			(xy 114.342403 -276.156212) (xy 114.300732 -276.189443) (xy 114.254574 -276.216092) (xy 114.20496 -276.235564)
			(xy 114.152998 -276.247424) (xy 114.099848 -276.251408) (xy 114.046698 -276.247424) (xy 113.994736 -276.235564)
			(xy 113.945122 -276.216092) (xy 113.898964 -276.189443) (xy 113.857293 -276.156212) (xy 113.821041 -276.117141)
			(xy 113.791017 -276.073104) (xy 113.767891 -276.025083) (xy 113.752181 -275.974153) (xy 113.744238 -275.921449)
			(xy 110.696004 -275.921449) (xy 110.688061 -275.974153) (xy 110.672351 -276.025083) (xy 110.649225 -276.073104)
			(xy 110.619201 -276.117141) (xy 110.582949 -276.156212) (xy 110.541278 -276.189443) (xy 110.49512 -276.216092)
			(xy 110.445506 -276.235564) (xy 110.393544 -276.247424) (xy 110.340394 -276.251408) (xy 110.287244 -276.247424)
			(xy 110.235282 -276.235564) (xy 110.185668 -276.216092) (xy 110.13951 -276.189443) (xy 110.097839 -276.156212)
			(xy 110.061587 -276.117141) (xy 110.031563 -276.073104) (xy 110.008437 -276.025083) (xy 109.992727 -275.974153)
			(xy 109.984784 -275.921449) (xy 109.729364 -275.921449) (xy 109.721792 -275.97024) (xy 109.706443 -276.018553)
			(xy 109.683881 -276.063948) (xy 109.654638 -276.105356) (xy 109.619401 -276.1418) (xy 109.579002 -276.172421)
			(xy 109.534392 -276.196499) (xy 109.486623 -276.213466) (xy 109.461808 -276.21865) (xy 109.438948 -276.222968)
			(xy 109.23397 -276.577806) (xy 109.241844 -276.599904) (xy 109.250407 -276.626262) (xy 109.259604 -276.680908)
			(xy 109.260132 -276.708616) (xy 109.259624 -276.734503) (xy 109.259503 -276.735265) (xy 109.514884 -276.735265)
			(xy 109.514884 -276.681967) (xy 109.522827 -276.629263) (xy 109.538537 -276.578333) (xy 109.561663 -276.530312)
			(xy 109.591687 -276.486275) (xy 109.627939 -276.447204) (xy 109.66961 -276.413973) (xy 109.715768 -276.387324)
			(xy 109.765382 -276.367852) (xy 109.817344 -276.355992) (xy 109.870494 -276.352009) (xy 109.923644 -276.355992)
			(xy 109.975606 -276.367852) (xy 110.02522 -276.387324) (xy 110.071378 -276.413973) (xy 110.113049 -276.447204)
			(xy 110.149301 -276.486275) (xy 110.179325 -276.530312) (xy 110.202451 -276.578333) (xy 110.218161 -276.629263)
			(xy 110.226104 -276.681967) (xy 110.226602 -276.708616) (xy 110.226104 -276.735265) (xy 114.214138 -276.735265)
			(xy 114.214138 -276.681967) (xy 114.222081 -276.629263) (xy 114.237791 -276.578333) (xy 114.260917 -276.530312)
			(xy 114.290941 -276.486275) (xy 114.327193 -276.447204) (xy 114.368864 -276.413973) (xy 114.415022 -276.387324)
			(xy 114.464636 -276.367852) (xy 114.516598 -276.355992) (xy 114.569748 -276.352009) (xy 114.622898 -276.355992)
			(xy 114.67486 -276.367852) (xy 114.724474 -276.387324) (xy 114.770632 -276.413973) (xy 114.812303 -276.447204)
			(xy 114.848555 -276.486275) (xy 114.878579 -276.530312) (xy 114.901705 -276.578333) (xy 114.917415 -276.629263)
			(xy 114.925358 -276.681967) (xy 114.925856 -276.708616) (xy 114.925363 -276.735011) (xy 115.153684 -276.735011)
			(xy 115.153684 -276.681713) (xy 115.161627 -276.629009) (xy 115.177337 -276.578079) (xy 115.200463 -276.530058)
			(xy 115.230487 -276.486021) (xy 115.266739 -276.44695) (xy 115.30841 -276.413719) (xy 115.354568 -276.38707)
			(xy 115.404182 -276.367598) (xy 115.456144 -276.355738) (xy 115.509294 -276.351755) (xy 115.562444 -276.355738)
			(xy 115.614406 -276.367598) (xy 115.66402 -276.38707) (xy 115.710178 -276.413719) (xy 115.751849 -276.44695)
			(xy 115.788101 -276.486021) (xy 115.818125 -276.530058) (xy 115.841251 -276.578079) (xy 115.856961 -276.629009)
			(xy 115.864904 -276.681713) (xy 115.865402 -276.708362) (xy 115.864904 -276.735011) (xy 116.093484 -276.735011)
			(xy 116.093484 -276.681713) (xy 116.101427 -276.629009) (xy 116.117137 -276.578079) (xy 116.140263 -276.530058)
			(xy 116.170287 -276.486021) (xy 116.206539 -276.44695) (xy 116.24821 -276.413719) (xy 116.294368 -276.38707)
			(xy 116.343982 -276.367598) (xy 116.395944 -276.355738) (xy 116.449094 -276.351755) (xy 116.502244 -276.355738)
			(xy 116.554206 -276.367598) (xy 116.60382 -276.38707) (xy 116.649978 -276.413719) (xy 116.691649 -276.44695)
			(xy 116.727901 -276.486021) (xy 116.757925 -276.530058) (xy 116.781051 -276.578079) (xy 116.796761 -276.629009)
			(xy 116.804704 -276.681713) (xy 116.805202 -276.708362) (xy 116.804704 -276.735011) (xy 116.796761 -276.787715)
			(xy 116.781051 -276.838645) (xy 116.757925 -276.886666) (xy 116.727901 -276.930703) (xy 116.691649 -276.969774)
			(xy 116.649978 -277.003005) (xy 116.60382 -277.029654) (xy 116.554206 -277.049126) (xy 116.502244 -277.060986)
			(xy 116.449094 -277.06497) (xy 116.395944 -277.060986) (xy 116.343982 -277.049126) (xy 116.294368 -277.029654)
			(xy 116.24821 -277.003005) (xy 116.206539 -276.969774) (xy 116.170287 -276.930703) (xy 116.140263 -276.886666)
			(xy 116.117137 -276.838645) (xy 116.101427 -276.787715) (xy 116.093484 -276.735011) (xy 115.864904 -276.735011)
			(xy 115.856961 -276.787715) (xy 115.841251 -276.838645) (xy 115.818125 -276.886666) (xy 115.788101 -276.930703)
			(xy 115.751849 -276.969774) (xy 115.710178 -277.003005) (xy 115.66402 -277.029654) (xy 115.614406 -277.049126)
			(xy 115.562444 -277.060986) (xy 115.509294 -277.06497) (xy 115.456144 -277.060986) (xy 115.404182 -277.049126)
			(xy 115.354568 -277.029654) (xy 115.30841 -277.003005) (xy 115.266739 -276.969774) (xy 115.230487 -276.930703)
			(xy 115.200463 -276.886666) (xy 115.177337 -276.838645) (xy 115.161627 -276.787715) (xy 115.153684 -276.735011)
			(xy 114.925363 -276.735011) (xy 114.925358 -276.735265) (xy 114.917415 -276.787969) (xy 114.901705 -276.838899)
			(xy 114.878579 -276.88692) (xy 114.848555 -276.930957) (xy 114.812303 -276.970028) (xy 114.770632 -277.003259)
			(xy 114.724474 -277.029908) (xy 114.67486 -277.04938) (xy 114.622898 -277.06124) (xy 114.569748 -277.065224)
			(xy 114.516598 -277.06124) (xy 114.464636 -277.04938) (xy 114.415022 -277.029908) (xy 114.368864 -277.003259)
			(xy 114.327193 -276.970028) (xy 114.290941 -276.930957) (xy 114.260917 -276.88692) (xy 114.237791 -276.838899)
			(xy 114.222081 -276.787969) (xy 114.214138 -276.735265) (xy 110.226104 -276.735265) (xy 110.218161 -276.787969)
			(xy 110.202451 -276.838899) (xy 110.179325 -276.88692) (xy 110.149301 -276.930957) (xy 110.113049 -276.970028)
			(xy 110.071378 -277.003259) (xy 110.02522 -277.029908) (xy 109.975606 -277.04938) (xy 109.923644 -277.06124)
			(xy 109.870494 -277.065224) (xy 109.817344 -277.06124) (xy 109.765382 -277.04938) (xy 109.715768 -277.029908)
			(xy 109.66961 -277.003259) (xy 109.627939 -276.970028) (xy 109.591687 -276.930957) (xy 109.561663 -276.88692)
			(xy 109.538537 -276.838899) (xy 109.522827 -276.787969) (xy 109.514884 -276.735265) (xy 109.259503 -276.735265)
			(xy 109.251525 -276.785641) (xy 109.235526 -276.834881) (xy 109.21202 -276.881013) (xy 109.181588 -276.9229)
			(xy 109.144978 -276.95951) (xy 109.103091 -276.989942) (xy 109.056959 -277.013448) (xy 109.007719 -277.029447)
			(xy 108.956581 -277.037546) (xy 108.904807 -277.037546) (xy 108.853669 -277.029447) (xy 108.804429 -277.013448)
			(xy 108.758297 -276.989942) (xy 108.71641 -276.95951) (xy 108.6798 -276.9229) (xy 108.649368 -276.881013)
			(xy 108.625862 -276.834881) (xy 108.609863 -276.785641) (xy 108.601764 -276.734503) (xy 108.601256 -276.708616)
			(xy 108.347256 -276.708616) (xy 108.346758 -276.735265) (xy 108.338815 -276.787969) (xy 108.323105 -276.838899)
			(xy 108.299979 -276.88692) (xy 108.269955 -276.930957) (xy 108.233703 -276.970028) (xy 108.192032 -277.003259)
			(xy 108.145874 -277.029908) (xy 108.09626 -277.04938) (xy 108.044298 -277.06124) (xy 107.991148 -277.065224)
			(xy 107.937998 -277.06124) (xy 107.886036 -277.04938) (xy 107.836422 -277.029908) (xy 107.790264 -277.003259)
			(xy 107.748593 -276.970028) (xy 107.712341 -276.930957) (xy 107.682317 -276.88692) (xy 107.659191 -276.838899)
			(xy 107.643481 -276.787969) (xy 107.635538 -276.735265) (xy 107.380431 -276.735265) (xy 107.372856 -276.784149)
			(xy 107.357482 -276.832518) (xy 107.334871 -276.877958) (xy 107.305557 -276.91939) (xy 107.270234 -276.955836)
			(xy 107.229739 -276.986433) (xy 107.18503 -277.010456) (xy 107.137166 -277.027337) (xy 107.112308 -277.032466)
			(xy 107.089448 -277.036784) (xy 106.88447 -277.391622) (xy 106.892344 -277.41372) (xy 106.90091 -277.440076)
			(xy 106.910105 -277.494723) (xy 106.910632 -277.522432) (xy 107.191556 -277.522432) (xy 107.192064 -277.496545)
			(xy 107.200163 -277.445407) (xy 107.216162 -277.396167) (xy 107.239668 -277.350035) (xy 107.2701 -277.308148)
			(xy 107.30671 -277.271538) (xy 107.348597 -277.241106) (xy 107.394729 -277.2176) (xy 107.443969 -277.201601)
			(xy 107.495107 -277.193502) (xy 107.546881 -277.193502) (xy 107.598019 -277.201601) (xy 107.647259 -277.2176)
			(xy 107.693391 -277.241106) (xy 107.735278 -277.271538) (xy 107.771888 -277.308148) (xy 107.80232 -277.350035)
			(xy 107.825826 -277.396167) (xy 107.841825 -277.445407) (xy 107.849924 -277.496545) (xy 107.850432 -277.522432)
			(xy 107.850432 -277.52294) (xy 107.849894 -277.548305) (xy 108.131648 -277.548305) (xy 108.131648 -277.496495)
			(xy 108.139753 -277.445324) (xy 108.155763 -277.396051) (xy 108.179283 -277.349889) (xy 108.209735 -277.307974)
			(xy 108.24637 -277.271339) (xy 108.288284 -277.240886) (xy 108.334445 -277.217365) (xy 108.383718 -277.201354)
			(xy 108.43489 -277.193249) (xy 108.460794 -277.19274) (xy 108.486306 -277.193209) (xy 108.536722 -277.20107)
			(xy 108.585325 -277.216605) (xy 108.630953 -277.239442) (xy 108.672518 -277.269037) (xy 108.709027 -277.304684)
			(xy 108.7247 -277.32482) (xy 109.136688 -277.32482) (xy 109.152374 -277.304695) (xy 109.18888 -277.269049)
			(xy 109.230443 -277.239454) (xy 109.276069 -277.216616) (xy 109.324669 -277.20108) (xy 109.375083 -277.193218)
			(xy 109.400594 -277.19274) (xy 109.426506 -277.193157) (xy 109.477693 -277.201263) (xy 109.526981 -277.217277)
			(xy 109.573157 -277.240805) (xy 109.615085 -277.271266) (xy 109.65173 -277.307911) (xy 109.682192 -277.349838)
			(xy 109.70572 -277.396013) (xy 109.721735 -277.445301) (xy 109.729842 -277.496488) (xy 109.729842 -277.548312)
			(xy 109.72972 -277.549081) (xy 109.984784 -277.549081) (xy 109.984784 -277.495783) (xy 109.992727 -277.443079)
			(xy 110.008437 -277.392149) (xy 110.031563 -277.344128) (xy 110.061587 -277.300091) (xy 110.097839 -277.26102)
			(xy 110.13951 -277.227789) (xy 110.185668 -277.20114) (xy 110.235282 -277.181668) (xy 110.287244 -277.169808)
			(xy 110.340394 -277.165825) (xy 110.393544 -277.169808) (xy 110.445506 -277.181668) (xy 110.49512 -277.20114)
			(xy 110.541278 -277.227789) (xy 110.582949 -277.26102) (xy 110.619201 -277.300091) (xy 110.649225 -277.344128)
			(xy 110.672351 -277.392149) (xy 110.688061 -277.443079) (xy 110.696004 -277.495783) (xy 110.696502 -277.522432)
			(xy 110.696004 -277.549081) (xy 114.683784 -277.549081) (xy 114.683784 -277.495783) (xy 114.691727 -277.443079)
			(xy 114.707437 -277.392149) (xy 114.730563 -277.344128) (xy 114.760587 -277.300091) (xy 114.796839 -277.26102)
			(xy 114.83851 -277.227789) (xy 114.884668 -277.20114) (xy 114.934282 -277.181668) (xy 114.986244 -277.169808)
			(xy 115.039394 -277.165825) (xy 115.092544 -277.169808) (xy 115.144506 -277.181668) (xy 115.19412 -277.20114)
			(xy 115.240278 -277.227789) (xy 115.281949 -277.26102) (xy 115.318201 -277.300091) (xy 115.348225 -277.344128)
			(xy 115.371351 -277.392149) (xy 115.387061 -277.443079) (xy 115.395004 -277.495783) (xy 115.395502 -277.522432)
			(xy 115.395009 -277.548827) (xy 115.623838 -277.548827) (xy 115.623838 -277.495529) (xy 115.631781 -277.442825)
			(xy 115.647491 -277.391895) (xy 115.670617 -277.343874) (xy 115.700641 -277.299837) (xy 115.736893 -277.260766)
			(xy 115.778564 -277.227535) (xy 115.824722 -277.200886) (xy 115.874336 -277.181414) (xy 115.926298 -277.169554)
			(xy 115.979448 -277.165571) (xy 116.032598 -277.169554) (xy 116.08456 -277.181414) (xy 116.134174 -277.200886)
			(xy 116.180332 -277.227535) (xy 116.222003 -277.260766) (xy 116.258255 -277.299837) (xy 116.288279 -277.343874)
			(xy 116.311405 -277.391895) (xy 116.327115 -277.442825) (xy 116.335058 -277.495529) (xy 116.335556 -277.522178)
			(xy 116.335058 -277.548827) (xy 116.33502 -277.549081) (xy 116.563384 -277.549081) (xy 116.563384 -277.495783)
			(xy 116.571327 -277.443079) (xy 116.587037 -277.392149) (xy 116.610163 -277.344128) (xy 116.640187 -277.300091)
			(xy 116.676439 -277.26102) (xy 116.71811 -277.227789) (xy 116.764268 -277.20114) (xy 116.813882 -277.181668)
			(xy 116.865844 -277.169808) (xy 116.918994 -277.165825) (xy 116.972144 -277.169808) (xy 117.024106 -277.181668)
			(xy 117.07372 -277.20114) (xy 117.119878 -277.227789) (xy 117.161549 -277.26102) (xy 117.197801 -277.300091)
			(xy 117.227825 -277.344128) (xy 117.250951 -277.392149) (xy 117.266661 -277.443079) (xy 117.274604 -277.495783)
			(xy 117.275102 -277.522432) (xy 117.274604 -277.549081) (xy 117.266661 -277.601785) (xy 117.250951 -277.652715)
			(xy 117.227825 -277.700736) (xy 117.197801 -277.744773) (xy 117.161549 -277.783844) (xy 117.119878 -277.817075)
			(xy 117.07372 -277.843724) (xy 117.024106 -277.863196) (xy 116.972144 -277.875056) (xy 116.918994 -277.87904)
			(xy 116.865844 -277.875056) (xy 116.813882 -277.863196) (xy 116.764268 -277.843724) (xy 116.71811 -277.817075)
			(xy 116.676439 -277.783844) (xy 116.640187 -277.744773) (xy 116.610163 -277.700736) (xy 116.587037 -277.652715)
			(xy 116.571327 -277.601785) (xy 116.563384 -277.549081) (xy 116.33502 -277.549081) (xy 116.327115 -277.601531)
			(xy 116.311405 -277.652461) (xy 116.288279 -277.700482) (xy 116.258255 -277.744519) (xy 116.222003 -277.78359)
			(xy 116.180332 -277.816821) (xy 116.134174 -277.84347) (xy 116.08456 -277.862942) (xy 116.032598 -277.874802)
			(xy 115.979448 -277.878786) (xy 115.926298 -277.874802) (xy 115.874336 -277.862942) (xy 115.824722 -277.84347)
			(xy 115.778564 -277.816821) (xy 115.736893 -277.78359) (xy 115.700641 -277.744519) (xy 115.670617 -277.700482)
			(xy 115.647491 -277.652461) (xy 115.631781 -277.601531) (xy 115.623838 -277.548827) (xy 115.395009 -277.548827)
			(xy 115.395004 -277.549081) (xy 115.387061 -277.601785) (xy 115.371351 -277.652715) (xy 115.348225 -277.700736)
			(xy 115.318201 -277.744773) (xy 115.281949 -277.783844) (xy 115.240278 -277.817075) (xy 115.19412 -277.843724)
			(xy 115.144506 -277.863196) (xy 115.092544 -277.875056) (xy 115.039394 -277.87904) (xy 114.986244 -277.875056)
			(xy 114.934282 -277.863196) (xy 114.884668 -277.843724) (xy 114.83851 -277.817075) (xy 114.796839 -277.783844)
			(xy 114.760587 -277.744773) (xy 114.730563 -277.700736) (xy 114.707437 -277.652715) (xy 114.691727 -277.601785)
			(xy 114.683784 -277.549081) (xy 110.696004 -277.549081) (xy 110.688061 -277.601785) (xy 110.672351 -277.652715)
			(xy 110.649225 -277.700736) (xy 110.619201 -277.744773) (xy 110.582949 -277.783844) (xy 110.541278 -277.817075)
			(xy 110.49512 -277.843724) (xy 110.445506 -277.863196) (xy 110.393544 -277.875056) (xy 110.340394 -277.87904)
			(xy 110.287244 -277.875056) (xy 110.235282 -277.863196) (xy 110.185668 -277.843724) (xy 110.13951 -277.817075)
			(xy 110.097839 -277.783844) (xy 110.061587 -277.744773) (xy 110.031563 -277.700736) (xy 110.008437 -277.652715)
			(xy 109.992727 -277.601785) (xy 109.984784 -277.549081) (xy 109.72972 -277.549081) (xy 109.721735 -277.599499)
			(xy 109.70572 -277.648787) (xy 109.682192 -277.694962) (xy 109.65173 -277.736889) (xy 109.615085 -277.773534)
			(xy 109.573157 -277.803995) (xy 109.526981 -277.827523) (xy 109.477693 -277.843537) (xy 109.426506 -277.851643)
			(xy 109.400594 -277.852124) (xy 109.375083 -277.851639) (xy 109.324669 -277.843778) (xy 109.276068 -277.828245)
			(xy 109.230439 -277.80541) (xy 109.188874 -277.775819) (xy 109.152362 -277.740178) (xy 109.136688 -277.720044)
			(xy 108.7247 -277.720044) (xy 108.709039 -277.740189) (xy 108.672525 -277.77583) (xy 108.630957 -277.805422)
			(xy 108.585326 -277.828256) (xy 108.536723 -277.843788) (xy 108.486307 -277.851647) (xy 108.460794 -277.852124)
			(xy 108.43489 -277.851551) (xy 108.383718 -277.843446) (xy 108.334445 -277.827435) (xy 108.288284 -277.803914)
			(xy 108.24637 -277.773461) (xy 108.209735 -277.736826) (xy 108.179283 -277.694911) (xy 108.155763 -277.648749)
			(xy 108.139753 -277.599476) (xy 108.131648 -277.548305) (xy 107.849894 -277.548305) (xy 107.849848 -277.550456)
			(xy 107.840658 -277.604717) (xy 107.832144 -277.63089) (xy 107.824524 -277.652988) (xy 108.029756 -278.008334)
			(xy 108.052616 -278.012652) (xy 108.077422 -278.017885) (xy 108.125198 -278.034831) (xy 108.169815 -278.058894)
			(xy 108.210222 -278.089506) (xy 108.245463 -278.125945) (xy 108.27471 -278.16735) (xy 108.29727 -278.212746)
			(xy 108.312612 -278.261061) (xy 108.320375 -278.311156) (xy 108.32084 -278.336502) (xy 108.320332 -278.362409)
			(xy 108.320214 -278.363151) (xy 108.575084 -278.363151) (xy 108.575084 -278.309853) (xy 108.583027 -278.257149)
			(xy 108.598737 -278.206219) (xy 108.621863 -278.158198) (xy 108.651887 -278.114161) (xy 108.688139 -278.07509)
			(xy 108.72981 -278.041859) (xy 108.775968 -278.01521) (xy 108.825582 -277.995738) (xy 108.877544 -277.983878)
			(xy 108.930694 -277.979895) (xy 108.983844 -277.983878) (xy 109.035806 -277.995738) (xy 109.08542 -278.01521)
			(xy 109.131578 -278.041859) (xy 109.173249 -278.07509) (xy 109.209501 -278.114161) (xy 109.239525 -278.158198)
			(xy 109.262651 -278.206219) (xy 109.278361 -278.257149) (xy 109.286304 -278.309853) (xy 109.286802 -278.336502)
			(xy 109.286304 -278.363151) (xy 109.514884 -278.363151) (xy 109.514884 -278.309853) (xy 109.522827 -278.257149)
			(xy 109.538537 -278.206219) (xy 109.561663 -278.158198) (xy 109.591687 -278.114161) (xy 109.627939 -278.07509)
			(xy 109.66961 -278.041859) (xy 109.715768 -278.01521) (xy 109.765382 -277.995738) (xy 109.817344 -277.983878)
			(xy 109.870494 -277.979895) (xy 109.923644 -277.983878) (xy 109.975606 -277.995738) (xy 110.02522 -278.01521)
			(xy 110.071378 -278.041859) (xy 110.113049 -278.07509) (xy 110.149301 -278.114161) (xy 110.179325 -278.158198)
			(xy 110.202451 -278.206219) (xy 110.218161 -278.257149) (xy 110.226104 -278.309853) (xy 110.226602 -278.336502)
			(xy 110.226104 -278.363151) (xy 114.214138 -278.363151) (xy 114.214138 -278.309853) (xy 114.222081 -278.257149)
			(xy 114.237791 -278.206219) (xy 114.260917 -278.158198) (xy 114.290941 -278.114161) (xy 114.327193 -278.07509)
			(xy 114.368864 -278.041859) (xy 114.415022 -278.01521) (xy 114.464636 -277.995738) (xy 114.516598 -277.983878)
			(xy 114.569748 -277.979895) (xy 114.622898 -277.983878) (xy 114.67486 -277.995738) (xy 114.724474 -278.01521)
			(xy 114.770632 -278.041859) (xy 114.812303 -278.07509) (xy 114.848555 -278.114161) (xy 114.878579 -278.158198)
			(xy 114.901705 -278.206219) (xy 114.917415 -278.257149) (xy 114.925358 -278.309853) (xy 114.925856 -278.336502)
			(xy 114.925363 -278.362897) (xy 115.153684 -278.362897) (xy 115.153684 -278.309599) (xy 115.161627 -278.256895)
			(xy 115.177337 -278.205965) (xy 115.200463 -278.157944) (xy 115.230487 -278.113907) (xy 115.266739 -278.074836)
			(xy 115.30841 -278.041605) (xy 115.354568 -278.014956) (xy 115.404182 -277.995484) (xy 115.456144 -277.983624)
			(xy 115.509294 -277.979641) (xy 115.562444 -277.983624) (xy 115.614406 -277.995484) (xy 115.66402 -278.014956)
			(xy 115.710178 -278.041605) (xy 115.751849 -278.074836) (xy 115.788101 -278.113907) (xy 115.818125 -278.157944)
			(xy 115.841251 -278.205965) (xy 115.856961 -278.256895) (xy 115.864904 -278.309599) (xy 115.865402 -278.336248)
			(xy 115.864904 -278.362897) (xy 116.093484 -278.362897) (xy 116.093484 -278.309599) (xy 116.101427 -278.256895)
			(xy 116.117137 -278.205965) (xy 116.140263 -278.157944) (xy 116.170287 -278.113907) (xy 116.206539 -278.074836)
			(xy 116.24821 -278.041605) (xy 116.294368 -278.014956) (xy 116.343982 -277.995484) (xy 116.395944 -277.983624)
			(xy 116.449094 -277.979641) (xy 116.502244 -277.983624) (xy 116.554206 -277.995484) (xy 116.60382 -278.014956)
			(xy 116.649978 -278.041605) (xy 116.691649 -278.074836) (xy 116.727901 -278.113907) (xy 116.757925 -278.157944)
			(xy 116.781051 -278.205965) (xy 116.796761 -278.256895) (xy 116.804704 -278.309599) (xy 116.805202 -278.336248)
			(xy 116.804704 -278.362897) (xy 117.033284 -278.362897) (xy 117.033284 -278.309599) (xy 117.041227 -278.256895)
			(xy 117.056937 -278.205965) (xy 117.080063 -278.157944) (xy 117.110087 -278.113907) (xy 117.146339 -278.074836)
			(xy 117.18801 -278.041605) (xy 117.234168 -278.014956) (xy 117.283782 -277.995484) (xy 117.335744 -277.983624)
			(xy 117.388894 -277.979641) (xy 117.442044 -277.983624) (xy 117.494006 -277.995484) (xy 117.54362 -278.014956)
			(xy 117.589778 -278.041605) (xy 117.631449 -278.074836) (xy 117.667701 -278.113907) (xy 117.697725 -278.157944)
			(xy 117.720851 -278.205965) (xy 117.736561 -278.256895) (xy 117.744504 -278.309599) (xy 117.745002 -278.336248)
			(xy 117.744504 -278.362897) (xy 117.973084 -278.362897) (xy 117.973084 -278.309599) (xy 117.981027 -278.256895)
			(xy 117.996737 -278.205965) (xy 118.019863 -278.157944) (xy 118.049887 -278.113907) (xy 118.086139 -278.074836)
			(xy 118.12781 -278.041605) (xy 118.173968 -278.014956) (xy 118.223582 -277.995484) (xy 118.275544 -277.983624)
			(xy 118.328694 -277.979641) (xy 118.381844 -277.983624) (xy 118.433806 -277.995484) (xy 118.48342 -278.014956)
			(xy 118.529578 -278.041605) (xy 118.571249 -278.074836) (xy 118.607501 -278.113907) (xy 118.637525 -278.157944)
			(xy 118.660651 -278.205965) (xy 118.676361 -278.256895) (xy 118.684304 -278.309599) (xy 118.684802 -278.336248)
			(xy 118.684304 -278.362897) (xy 118.684266 -278.363151) (xy 118.913138 -278.363151) (xy 118.913138 -278.309853)
			(xy 118.921081 -278.257149) (xy 118.936791 -278.206219) (xy 118.959917 -278.158198) (xy 118.989941 -278.114161)
			(xy 119.026193 -278.07509) (xy 119.067864 -278.041859) (xy 119.114022 -278.01521) (xy 119.163636 -277.995738)
			(xy 119.215598 -277.983878) (xy 119.268748 -277.979895) (xy 119.321898 -277.983878) (xy 119.37386 -277.995738)
			(xy 119.423474 -278.01521) (xy 119.469632 -278.041859) (xy 119.511303 -278.07509) (xy 119.547555 -278.114161)
			(xy 119.577579 -278.158198) (xy 119.600705 -278.206219) (xy 119.616415 -278.257149) (xy 119.624358 -278.309853)
			(xy 119.624856 -278.336502) (xy 119.624358 -278.363151) (xy 119.852938 -278.363151) (xy 119.852938 -278.309853)
			(xy 119.860881 -278.257149) (xy 119.876591 -278.206219) (xy 119.899717 -278.158198) (xy 119.929741 -278.114161)
			(xy 119.965993 -278.07509) (xy 120.007664 -278.041859) (xy 120.053822 -278.01521) (xy 120.103436 -277.995738)
			(xy 120.155398 -277.983878) (xy 120.208548 -277.979895) (xy 120.261698 -277.983878) (xy 120.31366 -277.995738)
			(xy 120.363274 -278.01521) (xy 120.409432 -278.041859) (xy 120.451103 -278.07509) (xy 120.487355 -278.114161)
			(xy 120.517379 -278.158198) (xy 120.540505 -278.206219) (xy 120.556215 -278.257149) (xy 120.564158 -278.309853)
			(xy 120.564656 -278.336502) (xy 120.564163 -278.362897) (xy 120.792484 -278.362897) (xy 120.792484 -278.309599)
			(xy 120.800427 -278.256895) (xy 120.816137 -278.205965) (xy 120.839263 -278.157944) (xy 120.869287 -278.113907)
			(xy 120.905539 -278.074836) (xy 120.94721 -278.041605) (xy 120.993368 -278.014956) (xy 121.042982 -277.995484)
			(xy 121.094944 -277.983624) (xy 121.148094 -277.979641) (xy 121.201244 -277.983624) (xy 121.253206 -277.995484)
			(xy 121.30282 -278.014956) (xy 121.348978 -278.041605) (xy 121.390649 -278.074836) (xy 121.426901 -278.113907)
			(xy 121.456925 -278.157944) (xy 121.480051 -278.205965) (xy 121.495761 -278.256895) (xy 121.503704 -278.309599)
			(xy 121.504202 -278.336248) (xy 121.503704 -278.362897) (xy 121.503666 -278.363151) (xy 121.732284 -278.363151)
			(xy 121.732284 -278.309853) (xy 121.740227 -278.257149) (xy 121.755937 -278.206219) (xy 121.779063 -278.158198)
			(xy 121.809087 -278.114161) (xy 121.845339 -278.07509) (xy 121.88701 -278.041859) (xy 121.933168 -278.01521)
			(xy 121.982782 -277.995738) (xy 122.034744 -277.983878) (xy 122.087894 -277.979895) (xy 122.141044 -277.983878)
			(xy 122.193006 -277.995738) (xy 122.24262 -278.01521) (xy 122.288778 -278.041859) (xy 122.330449 -278.07509)
			(xy 122.366701 -278.114161) (xy 122.396725 -278.158198) (xy 122.419851 -278.206219) (xy 122.435561 -278.257149)
			(xy 122.443504 -278.309853) (xy 122.444002 -278.336502) (xy 122.443504 -278.363151) (xy 122.672338 -278.363151)
			(xy 122.672338 -278.309853) (xy 122.680281 -278.257149) (xy 122.695991 -278.206219) (xy 122.719117 -278.158198)
			(xy 122.749141 -278.114161) (xy 122.785393 -278.07509) (xy 122.827064 -278.041859) (xy 122.873222 -278.01521)
			(xy 122.922836 -277.995738) (xy 122.974798 -277.983878) (xy 123.027948 -277.979895) (xy 123.081098 -277.983878)
			(xy 123.13306 -277.995738) (xy 123.182674 -278.01521) (xy 123.228832 -278.041859) (xy 123.270503 -278.07509)
			(xy 123.306755 -278.114161) (xy 123.336779 -278.158198) (xy 123.359905 -278.206219) (xy 123.375615 -278.257149)
			(xy 123.383558 -278.309853) (xy 123.384056 -278.336502) (xy 123.383558 -278.363151) (xy 123.612138 -278.363151)
			(xy 123.612138 -278.309853) (xy 123.620081 -278.257149) (xy 123.635791 -278.206219) (xy 123.658917 -278.158198)
			(xy 123.688941 -278.114161) (xy 123.725193 -278.07509) (xy 123.766864 -278.041859) (xy 123.813022 -278.01521)
			(xy 123.862636 -277.995738) (xy 123.914598 -277.983878) (xy 123.967748 -277.979895) (xy 124.020898 -277.983878)
			(xy 124.07286 -277.995738) (xy 124.122474 -278.01521) (xy 124.168632 -278.041859) (xy 124.210303 -278.07509)
			(xy 124.246555 -278.114161) (xy 124.276579 -278.158198) (xy 124.299705 -278.206219) (xy 124.315415 -278.257149)
			(xy 124.323358 -278.309853) (xy 124.323856 -278.336502) (xy 124.323358 -278.363151) (xy 124.551938 -278.363151)
			(xy 124.551938 -278.309853) (xy 124.559881 -278.257149) (xy 124.575591 -278.206219) (xy 124.598717 -278.158198)
			(xy 124.628741 -278.114161) (xy 124.664993 -278.07509) (xy 124.706664 -278.041859) (xy 124.752822 -278.01521)
			(xy 124.802436 -277.995738) (xy 124.854398 -277.983878) (xy 124.907548 -277.979895) (xy 124.960698 -277.983878)
			(xy 125.01266 -277.995738) (xy 125.062274 -278.01521) (xy 125.108432 -278.041859) (xy 125.150103 -278.07509)
			(xy 125.186355 -278.114161) (xy 125.216379 -278.158198) (xy 125.239505 -278.206219) (xy 125.255215 -278.257149)
			(xy 125.263158 -278.309853) (xy 125.263656 -278.336502) (xy 125.263158 -278.363151) (xy 125.491738 -278.363151)
			(xy 125.491738 -278.309853) (xy 125.499681 -278.257149) (xy 125.515391 -278.206219) (xy 125.538517 -278.158198)
			(xy 125.568541 -278.114161) (xy 125.604793 -278.07509) (xy 125.646464 -278.041859) (xy 125.692622 -278.01521)
			(xy 125.742236 -277.995738) (xy 125.794198 -277.983878) (xy 125.847348 -277.979895) (xy 125.900498 -277.983878)
			(xy 125.95246 -277.995738) (xy 126.002074 -278.01521) (xy 126.048232 -278.041859) (xy 126.089903 -278.07509)
			(xy 126.126155 -278.114161) (xy 126.156179 -278.158198) (xy 126.179305 -278.206219) (xy 126.195015 -278.257149)
			(xy 126.202958 -278.309853) (xy 126.203456 -278.336502) (xy 126.202958 -278.363151) (xy 126.431538 -278.363151)
			(xy 126.431538 -278.309853) (xy 126.439481 -278.257149) (xy 126.455191 -278.206219) (xy 126.478317 -278.158198)
			(xy 126.508341 -278.114161) (xy 126.544593 -278.07509) (xy 126.586264 -278.041859) (xy 126.632422 -278.01521)
			(xy 126.682036 -277.995738) (xy 126.733998 -277.983878) (xy 126.787148 -277.979895) (xy 126.840298 -277.983878)
			(xy 126.89226 -277.995738) (xy 126.941874 -278.01521) (xy 126.988032 -278.041859) (xy 127.029703 -278.07509)
			(xy 127.065955 -278.114161) (xy 127.095979 -278.158198) (xy 127.119105 -278.206219) (xy 127.134815 -278.257149)
			(xy 127.142758 -278.309853) (xy 127.143256 -278.336502) (xy 127.142758 -278.363151) (xy 127.371338 -278.363151)
			(xy 127.371338 -278.309853) (xy 127.379281 -278.257149) (xy 127.394991 -278.206219) (xy 127.418117 -278.158198)
			(xy 127.448141 -278.114161) (xy 127.484393 -278.07509) (xy 127.526064 -278.041859) (xy 127.572222 -278.01521)
			(xy 127.621836 -277.995738) (xy 127.673798 -277.983878) (xy 127.726948 -277.979895) (xy 127.780098 -277.983878)
			(xy 127.83206 -277.995738) (xy 127.881674 -278.01521) (xy 127.927832 -278.041859) (xy 127.969503 -278.07509)
			(xy 128.005755 -278.114161) (xy 128.035779 -278.158198) (xy 128.058905 -278.206219) (xy 128.074615 -278.257149)
			(xy 128.082558 -278.309853) (xy 128.083056 -278.336502) (xy 128.082576 -278.36221) (xy 128.339846 -278.36221)
			(xy 128.339846 -278.310794) (xy 128.347889 -278.260012) (xy 128.363777 -278.211113) (xy 128.38712 -278.165301)
			(xy 128.417341 -278.123705) (xy 128.453697 -278.087349) (xy 128.495293 -278.057128) (xy 128.541105 -278.033785)
			(xy 128.590004 -278.017897) (xy 128.640786 -278.009854) (xy 128.692202 -278.009854) (xy 128.742984 -278.017897)
			(xy 128.791883 -278.033785) (xy 128.837695 -278.057128) (xy 128.879291 -278.087349) (xy 128.915647 -278.123705)
			(xy 128.945868 -278.165301) (xy 128.969211 -278.211113) (xy 128.985099 -278.260012) (xy 128.993142 -278.310794)
			(xy 128.993646 -278.336502) (xy 128.993142 -278.36221) (xy 129.2799 -278.36221) (xy 129.2799 -278.310794)
			(xy 129.287943 -278.260012) (xy 129.303831 -278.211113) (xy 129.327174 -278.165301) (xy 129.357395 -278.123705)
			(xy 129.393751 -278.087349) (xy 129.435347 -278.057128) (xy 129.481159 -278.033785) (xy 129.530058 -278.017897)
			(xy 129.58084 -278.009854) (xy 129.632256 -278.009854) (xy 129.683038 -278.017897) (xy 129.731937 -278.033785)
			(xy 129.777749 -278.057128) (xy 129.819345 -278.087349) (xy 129.855701 -278.123705) (xy 129.885922 -278.165301)
			(xy 129.909265 -278.211113) (xy 129.925153 -278.260012) (xy 129.933196 -278.310794) (xy 129.9337 -278.336502)
			(xy 129.933196 -278.36221) (xy 129.933047 -278.363151) (xy 130.190484 -278.363151) (xy 130.190484 -278.309853)
			(xy 130.198427 -278.257149) (xy 130.214137 -278.206219) (xy 130.237263 -278.158198) (xy 130.267287 -278.114161)
			(xy 130.303539 -278.07509) (xy 130.34521 -278.041859) (xy 130.391368 -278.01521) (xy 130.440982 -277.995738)
			(xy 130.492944 -277.983878) (xy 130.546094 -277.979895) (xy 130.599244 -277.983878) (xy 130.651206 -277.995738)
			(xy 130.70082 -278.01521) (xy 130.746978 -278.041859) (xy 130.788649 -278.07509) (xy 130.824901 -278.114161)
			(xy 130.854925 -278.158198) (xy 130.878051 -278.206219) (xy 130.893761 -278.257149) (xy 130.901704 -278.309853)
			(xy 130.902202 -278.336502) (xy 130.901704 -278.363151) (xy 131.130538 -278.363151) (xy 131.130538 -278.309853)
			(xy 131.138481 -278.257149) (xy 131.154191 -278.206219) (xy 131.177317 -278.158198) (xy 131.207341 -278.114161)
			(xy 131.243593 -278.07509) (xy 131.285264 -278.041859) (xy 131.331422 -278.01521) (xy 131.381036 -277.995738)
			(xy 131.432998 -277.983878) (xy 131.486148 -277.979895) (xy 131.539298 -277.983878) (xy 131.59126 -277.995738)
			(xy 131.640874 -278.01521) (xy 131.687032 -278.041859) (xy 131.728703 -278.07509) (xy 131.764955 -278.114161)
			(xy 131.794979 -278.158198) (xy 131.818105 -278.206219) (xy 131.833815 -278.257149) (xy 131.841758 -278.309853)
			(xy 131.842256 -278.336502) (xy 131.841776 -278.36221) (xy 132.0993 -278.36221) (xy 132.0993 -278.310794)
			(xy 132.107343 -278.260012) (xy 132.123231 -278.211113) (xy 132.146574 -278.165301) (xy 132.176795 -278.123705)
			(xy 132.213151 -278.087349) (xy 132.254747 -278.057128) (xy 132.300559 -278.033785) (xy 132.349458 -278.017897)
			(xy 132.40024 -278.009854) (xy 132.451656 -278.009854) (xy 132.502438 -278.017897) (xy 132.551337 -278.033785)
			(xy 132.597149 -278.057128) (xy 132.638745 -278.087349) (xy 132.675101 -278.123705) (xy 132.705322 -278.165301)
			(xy 132.728665 -278.211113) (xy 132.744553 -278.260012) (xy 132.752596 -278.310794) (xy 132.7531 -278.336502)
			(xy 132.752596 -278.36221) (xy 133.0391 -278.36221) (xy 133.0391 -278.310794) (xy 133.047143 -278.260012)
			(xy 133.063031 -278.211113) (xy 133.086374 -278.165301) (xy 133.116595 -278.123705) (xy 133.152951 -278.087349)
			(xy 133.194547 -278.057128) (xy 133.240359 -278.033785) (xy 133.289258 -278.017897) (xy 133.34004 -278.009854)
			(xy 133.391456 -278.009854) (xy 133.442238 -278.017897) (xy 133.491137 -278.033785) (xy 133.536949 -278.057128)
			(xy 133.578545 -278.087349) (xy 133.614901 -278.123705) (xy 133.645122 -278.165301) (xy 133.668465 -278.211113)
			(xy 133.684353 -278.260012) (xy 133.692396 -278.310794) (xy 133.6929 -278.336502) (xy 133.692396 -278.36221)
			(xy 133.692247 -278.363151) (xy 133.949684 -278.363151) (xy 133.949684 -278.309853) (xy 133.957627 -278.257149)
			(xy 133.973337 -278.206219) (xy 133.996463 -278.158198) (xy 134.026487 -278.114161) (xy 134.062739 -278.07509)
			(xy 134.10441 -278.041859) (xy 134.150568 -278.01521) (xy 134.200182 -277.995738) (xy 134.252144 -277.983878)
			(xy 134.305294 -277.979895) (xy 134.358444 -277.983878) (xy 134.410406 -277.995738) (xy 134.46002 -278.01521)
			(xy 134.506178 -278.041859) (xy 134.547849 -278.07509) (xy 134.584101 -278.114161) (xy 134.614125 -278.158198)
			(xy 134.637251 -278.206219) (xy 134.652961 -278.257149) (xy 134.660904 -278.309853) (xy 134.661402 -278.336502)
			(xy 134.660922 -278.36221) (xy 134.918446 -278.36221) (xy 134.918446 -278.310794) (xy 134.926489 -278.260012)
			(xy 134.942377 -278.211113) (xy 134.96572 -278.165301) (xy 134.995941 -278.123705) (xy 135.032297 -278.087349)
			(xy 135.073893 -278.057128) (xy 135.119705 -278.033785) (xy 135.168604 -278.017897) (xy 135.219386 -278.009854)
			(xy 135.270802 -278.009854) (xy 135.321584 -278.017897) (xy 135.370483 -278.033785) (xy 135.416295 -278.057128)
			(xy 135.457891 -278.087349) (xy 135.494247 -278.123705) (xy 135.524468 -278.165301) (xy 135.547811 -278.211113)
			(xy 135.563699 -278.260012) (xy 135.571742 -278.310794) (xy 135.572246 -278.336502) (xy 135.571742 -278.36221)
			(xy 135.571593 -278.363151) (xy 135.829284 -278.363151) (xy 135.829284 -278.309853) (xy 135.837227 -278.257149)
			(xy 135.852937 -278.206219) (xy 135.876063 -278.158198) (xy 135.906087 -278.114161) (xy 135.942339 -278.07509)
			(xy 135.98401 -278.041859) (xy 136.030168 -278.01521) (xy 136.079782 -277.995738) (xy 136.131744 -277.983878)
			(xy 136.184894 -277.979895) (xy 136.238044 -277.983878) (xy 136.290006 -277.995738) (xy 136.33962 -278.01521)
			(xy 136.385778 -278.041859) (xy 136.427449 -278.07509) (xy 136.463701 -278.114161) (xy 136.493725 -278.158198)
			(xy 136.516851 -278.206219) (xy 136.532561 -278.257149) (xy 136.540504 -278.309853) (xy 136.541002 -278.336502)
			(xy 136.540504 -278.363151) (xy 136.532561 -278.415855) (xy 136.516851 -278.466785) (xy 136.493725 -278.514806)
			(xy 136.463701 -278.558843) (xy 136.427449 -278.597914) (xy 136.385778 -278.631145) (xy 136.33962 -278.657794)
			(xy 136.290006 -278.677266) (xy 136.238044 -278.689126) (xy 136.184894 -278.69311) (xy 136.131744 -278.689126)
			(xy 136.079782 -278.677266) (xy 136.030168 -278.657794) (xy 135.98401 -278.631145) (xy 135.942339 -278.597914)
			(xy 135.906087 -278.558843) (xy 135.876063 -278.514806) (xy 135.852937 -278.466785) (xy 135.837227 -278.415855)
			(xy 135.829284 -278.363151) (xy 135.571593 -278.363151) (xy 135.563699 -278.412992) (xy 135.547811 -278.461891)
			(xy 135.524468 -278.507703) (xy 135.494247 -278.549299) (xy 135.457891 -278.585655) (xy 135.416295 -278.615876)
			(xy 135.370483 -278.639219) (xy 135.321584 -278.655107) (xy 135.270802 -278.66315) (xy 135.219386 -278.66315)
			(xy 135.168604 -278.655107) (xy 135.119705 -278.639219) (xy 135.073893 -278.615876) (xy 135.032297 -278.585655)
			(xy 134.995941 -278.549299) (xy 134.96572 -278.507703) (xy 134.942377 -278.461891) (xy 134.926489 -278.412992)
			(xy 134.918446 -278.36221) (xy 134.660922 -278.36221) (xy 134.660904 -278.363151) (xy 134.652961 -278.415855)
			(xy 134.637251 -278.466785) (xy 134.614125 -278.514806) (xy 134.584101 -278.558843) (xy 134.547849 -278.597914)
			(xy 134.506178 -278.631145) (xy 134.46002 -278.657794) (xy 134.410406 -278.677266) (xy 134.358444 -278.689126)
			(xy 134.305294 -278.69311) (xy 134.252144 -278.689126) (xy 134.200182 -278.677266) (xy 134.150568 -278.657794)
			(xy 134.10441 -278.631145) (xy 134.062739 -278.597914) (xy 134.026487 -278.558843) (xy 133.996463 -278.514806)
			(xy 133.973337 -278.466785) (xy 133.957627 -278.415855) (xy 133.949684 -278.363151) (xy 133.692247 -278.363151)
			(xy 133.684353 -278.412992) (xy 133.668465 -278.461891) (xy 133.645122 -278.507703) (xy 133.614901 -278.549299)
			(xy 133.578545 -278.585655) (xy 133.536949 -278.615876) (xy 133.491137 -278.639219) (xy 133.442238 -278.655107)
			(xy 133.391456 -278.66315) (xy 133.34004 -278.66315) (xy 133.289258 -278.655107) (xy 133.240359 -278.639219)
			(xy 133.194547 -278.615876) (xy 133.152951 -278.585655) (xy 133.116595 -278.549299) (xy 133.086374 -278.507703)
			(xy 133.063031 -278.461891) (xy 133.047143 -278.412992) (xy 133.0391 -278.36221) (xy 132.752596 -278.36221)
			(xy 132.744553 -278.412992) (xy 132.728665 -278.461891) (xy 132.705322 -278.507703) (xy 132.675101 -278.549299)
			(xy 132.638745 -278.585655) (xy 132.597149 -278.615876) (xy 132.551337 -278.639219) (xy 132.502438 -278.655107)
			(xy 132.451656 -278.66315) (xy 132.40024 -278.66315) (xy 132.349458 -278.655107) (xy 132.300559 -278.639219)
			(xy 132.254747 -278.615876) (xy 132.213151 -278.585655) (xy 132.176795 -278.549299) (xy 132.146574 -278.507703)
			(xy 132.123231 -278.461891) (xy 132.107343 -278.412992) (xy 132.0993 -278.36221) (xy 131.841776 -278.36221)
			(xy 131.841758 -278.363151) (xy 131.833815 -278.415855) (xy 131.818105 -278.466785) (xy 131.794979 -278.514806)
			(xy 131.764955 -278.558843) (xy 131.728703 -278.597914) (xy 131.687032 -278.631145) (xy 131.640874 -278.657794)
			(xy 131.59126 -278.677266) (xy 131.539298 -278.689126) (xy 131.486148 -278.69311) (xy 131.432998 -278.689126)
			(xy 131.381036 -278.677266) (xy 131.331422 -278.657794) (xy 131.285264 -278.631145) (xy 131.243593 -278.597914)
			(xy 131.207341 -278.558843) (xy 131.177317 -278.514806) (xy 131.154191 -278.466785) (xy 131.138481 -278.415855)
			(xy 131.130538 -278.363151) (xy 130.901704 -278.363151) (xy 130.893761 -278.415855) (xy 130.878051 -278.466785)
			(xy 130.854925 -278.514806) (xy 130.824901 -278.558843) (xy 130.788649 -278.597914) (xy 130.746978 -278.631145)
			(xy 130.70082 -278.657794) (xy 130.651206 -278.677266) (xy 130.599244 -278.689126) (xy 130.546094 -278.69311)
			(xy 130.492944 -278.689126) (xy 130.440982 -278.677266) (xy 130.391368 -278.657794) (xy 130.34521 -278.631145)
			(xy 130.303539 -278.597914) (xy 130.267287 -278.558843) (xy 130.237263 -278.514806) (xy 130.214137 -278.466785)
			(xy 130.198427 -278.415855) (xy 130.190484 -278.363151) (xy 129.933047 -278.363151) (xy 129.925153 -278.412992)
			(xy 129.909265 -278.461891) (xy 129.885922 -278.507703) (xy 129.855701 -278.549299) (xy 129.819345 -278.585655)
			(xy 129.777749 -278.615876) (xy 129.731937 -278.639219) (xy 129.683038 -278.655107) (xy 129.632256 -278.66315)
			(xy 129.58084 -278.66315) (xy 129.530058 -278.655107) (xy 129.481159 -278.639219) (xy 129.435347 -278.615876)
			(xy 129.393751 -278.585655) (xy 129.357395 -278.549299) (xy 129.327174 -278.507703) (xy 129.303831 -278.461891)
			(xy 129.287943 -278.412992) (xy 129.2799 -278.36221) (xy 128.993142 -278.36221) (xy 128.985099 -278.412992)
			(xy 128.969211 -278.461891) (xy 128.945868 -278.507703) (xy 128.915647 -278.549299) (xy 128.879291 -278.585655)
			(xy 128.837695 -278.615876) (xy 128.791883 -278.639219) (xy 128.742984 -278.655107) (xy 128.692202 -278.66315)
			(xy 128.640786 -278.66315) (xy 128.590004 -278.655107) (xy 128.541105 -278.639219) (xy 128.495293 -278.615876)
			(xy 128.453697 -278.585655) (xy 128.417341 -278.549299) (xy 128.38712 -278.507703) (xy 128.363777 -278.461891)
			(xy 128.347889 -278.412992) (xy 128.339846 -278.36221) (xy 128.082576 -278.36221) (xy 128.082558 -278.363151)
			(xy 128.074615 -278.415855) (xy 128.058905 -278.466785) (xy 128.035779 -278.514806) (xy 128.005755 -278.558843)
			(xy 127.969503 -278.597914) (xy 127.927832 -278.631145) (xy 127.881674 -278.657794) (xy 127.83206 -278.677266)
			(xy 127.780098 -278.689126) (xy 127.726948 -278.69311) (xy 127.673798 -278.689126) (xy 127.621836 -278.677266)
			(xy 127.572222 -278.657794) (xy 127.526064 -278.631145) (xy 127.484393 -278.597914) (xy 127.448141 -278.558843)
			(xy 127.418117 -278.514806) (xy 127.394991 -278.466785) (xy 127.379281 -278.415855) (xy 127.371338 -278.363151)
			(xy 127.142758 -278.363151) (xy 127.134815 -278.415855) (xy 127.119105 -278.466785) (xy 127.095979 -278.514806)
			(xy 127.065955 -278.558843) (xy 127.029703 -278.597914) (xy 126.988032 -278.631145) (xy 126.941874 -278.657794)
			(xy 126.89226 -278.677266) (xy 126.840298 -278.689126) (xy 126.787148 -278.69311) (xy 126.733998 -278.689126)
			(xy 126.682036 -278.677266) (xy 126.632422 -278.657794) (xy 126.586264 -278.631145) (xy 126.544593 -278.597914)
			(xy 126.508341 -278.558843) (xy 126.478317 -278.514806) (xy 126.455191 -278.466785) (xy 126.439481 -278.415855)
			(xy 126.431538 -278.363151) (xy 126.202958 -278.363151) (xy 126.195015 -278.415855) (xy 126.179305 -278.466785)
			(xy 126.156179 -278.514806) (xy 126.126155 -278.558843) (xy 126.089903 -278.597914) (xy 126.048232 -278.631145)
			(xy 126.002074 -278.657794) (xy 125.95246 -278.677266) (xy 125.900498 -278.689126) (xy 125.847348 -278.69311)
			(xy 125.794198 -278.689126) (xy 125.742236 -278.677266) (xy 125.692622 -278.657794) (xy 125.646464 -278.631145)
			(xy 125.604793 -278.597914) (xy 125.568541 -278.558843) (xy 125.538517 -278.514806) (xy 125.515391 -278.466785)
			(xy 125.499681 -278.415855) (xy 125.491738 -278.363151) (xy 125.263158 -278.363151) (xy 125.255215 -278.415855)
			(xy 125.239505 -278.466785) (xy 125.216379 -278.514806) (xy 125.186355 -278.558843) (xy 125.150103 -278.597914)
			(xy 125.108432 -278.631145) (xy 125.062274 -278.657794) (xy 125.01266 -278.677266) (xy 124.960698 -278.689126)
			(xy 124.907548 -278.69311) (xy 124.854398 -278.689126) (xy 124.802436 -278.677266) (xy 124.752822 -278.657794)
			(xy 124.706664 -278.631145) (xy 124.664993 -278.597914) (xy 124.628741 -278.558843) (xy 124.598717 -278.514806)
			(xy 124.575591 -278.466785) (xy 124.559881 -278.415855) (xy 124.551938 -278.363151) (xy 124.323358 -278.363151)
			(xy 124.315415 -278.415855) (xy 124.299705 -278.466785) (xy 124.276579 -278.514806) (xy 124.246555 -278.558843)
			(xy 124.210303 -278.597914) (xy 124.168632 -278.631145) (xy 124.122474 -278.657794) (xy 124.07286 -278.677266)
			(xy 124.020898 -278.689126) (xy 123.967748 -278.69311) (xy 123.914598 -278.689126) (xy 123.862636 -278.677266)
			(xy 123.813022 -278.657794) (xy 123.766864 -278.631145) (xy 123.725193 -278.597914) (xy 123.688941 -278.558843)
			(xy 123.658917 -278.514806) (xy 123.635791 -278.466785) (xy 123.620081 -278.415855) (xy 123.612138 -278.363151)
			(xy 123.383558 -278.363151) (xy 123.375615 -278.415855) (xy 123.359905 -278.466785) (xy 123.336779 -278.514806)
			(xy 123.306755 -278.558843) (xy 123.270503 -278.597914) (xy 123.228832 -278.631145) (xy 123.182674 -278.657794)
			(xy 123.13306 -278.677266) (xy 123.081098 -278.689126) (xy 123.027948 -278.69311) (xy 122.974798 -278.689126)
			(xy 122.922836 -278.677266) (xy 122.873222 -278.657794) (xy 122.827064 -278.631145) (xy 122.785393 -278.597914)
			(xy 122.749141 -278.558843) (xy 122.719117 -278.514806) (xy 122.695991 -278.466785) (xy 122.680281 -278.415855)
			(xy 122.672338 -278.363151) (xy 122.443504 -278.363151) (xy 122.435561 -278.415855) (xy 122.419851 -278.466785)
			(xy 122.396725 -278.514806) (xy 122.366701 -278.558843) (xy 122.330449 -278.597914) (xy 122.288778 -278.631145)
			(xy 122.24262 -278.657794) (xy 122.193006 -278.677266) (xy 122.141044 -278.689126) (xy 122.087894 -278.69311)
			(xy 122.034744 -278.689126) (xy 121.982782 -278.677266) (xy 121.933168 -278.657794) (xy 121.88701 -278.631145)
			(xy 121.845339 -278.597914) (xy 121.809087 -278.558843) (xy 121.779063 -278.514806) (xy 121.755937 -278.466785)
			(xy 121.740227 -278.415855) (xy 121.732284 -278.363151) (xy 121.503666 -278.363151) (xy 121.495761 -278.415601)
			(xy 121.480051 -278.466531) (xy 121.456925 -278.514552) (xy 121.426901 -278.558589) (xy 121.390649 -278.59766)
			(xy 121.348978 -278.630891) (xy 121.30282 -278.65754) (xy 121.253206 -278.677012) (xy 121.201244 -278.688872)
			(xy 121.148094 -278.692856) (xy 121.094944 -278.688872) (xy 121.042982 -278.677012) (xy 120.993368 -278.65754)
			(xy 120.94721 -278.630891) (xy 120.905539 -278.59766) (xy 120.869287 -278.558589) (xy 120.839263 -278.514552)
			(xy 120.816137 -278.466531) (xy 120.800427 -278.415601) (xy 120.792484 -278.362897) (xy 120.564163 -278.362897)
			(xy 120.564158 -278.363151) (xy 120.556215 -278.415855) (xy 120.540505 -278.466785) (xy 120.517379 -278.514806)
			(xy 120.487355 -278.558843) (xy 120.451103 -278.597914) (xy 120.409432 -278.631145) (xy 120.363274 -278.657794)
			(xy 120.31366 -278.677266) (xy 120.261698 -278.689126) (xy 120.208548 -278.69311) (xy 120.155398 -278.689126)
			(xy 120.103436 -278.677266) (xy 120.053822 -278.657794) (xy 120.007664 -278.631145) (xy 119.965993 -278.597914)
			(xy 119.929741 -278.558843) (xy 119.899717 -278.514806) (xy 119.876591 -278.466785) (xy 119.860881 -278.415855)
			(xy 119.852938 -278.363151) (xy 119.624358 -278.363151) (xy 119.616415 -278.415855) (xy 119.600705 -278.466785)
			(xy 119.577579 -278.514806) (xy 119.547555 -278.558843) (xy 119.511303 -278.597914) (xy 119.469632 -278.631145)
			(xy 119.423474 -278.657794) (xy 119.37386 -278.677266) (xy 119.321898 -278.689126) (xy 119.268748 -278.69311)
			(xy 119.215598 -278.689126) (xy 119.163636 -278.677266) (xy 119.114022 -278.657794) (xy 119.067864 -278.631145)
			(xy 119.026193 -278.597914) (xy 118.989941 -278.558843) (xy 118.959917 -278.514806) (xy 118.936791 -278.466785)
			(xy 118.921081 -278.415855) (xy 118.913138 -278.363151) (xy 118.684266 -278.363151) (xy 118.676361 -278.415601)
			(xy 118.660651 -278.466531) (xy 118.637525 -278.514552) (xy 118.607501 -278.558589) (xy 118.571249 -278.59766)
			(xy 118.529578 -278.630891) (xy 118.48342 -278.65754) (xy 118.433806 -278.677012) (xy 118.381844 -278.688872)
			(xy 118.328694 -278.692856) (xy 118.275544 -278.688872) (xy 118.223582 -278.677012) (xy 118.173968 -278.65754)
			(xy 118.12781 -278.630891) (xy 118.086139 -278.59766) (xy 118.049887 -278.558589) (xy 118.019863 -278.514552)
			(xy 117.996737 -278.466531) (xy 117.981027 -278.415601) (xy 117.973084 -278.362897) (xy 117.744504 -278.362897)
			(xy 117.736561 -278.415601) (xy 117.720851 -278.466531) (xy 117.697725 -278.514552) (xy 117.667701 -278.558589)
			(xy 117.631449 -278.59766) (xy 117.589778 -278.630891) (xy 117.54362 -278.65754) (xy 117.494006 -278.677012)
			(xy 117.442044 -278.688872) (xy 117.388894 -278.692856) (xy 117.335744 -278.688872) (xy 117.283782 -278.677012)
			(xy 117.234168 -278.65754) (xy 117.18801 -278.630891) (xy 117.146339 -278.59766) (xy 117.110087 -278.558589)
			(xy 117.080063 -278.514552) (xy 117.056937 -278.466531) (xy 117.041227 -278.415601) (xy 117.033284 -278.362897)
			(xy 116.804704 -278.362897) (xy 116.796761 -278.415601) (xy 116.781051 -278.466531) (xy 116.757925 -278.514552)
			(xy 116.727901 -278.558589) (xy 116.691649 -278.59766) (xy 116.649978 -278.630891) (xy 116.60382 -278.65754)
			(xy 116.554206 -278.677012) (xy 116.502244 -278.688872) (xy 116.449094 -278.692856) (xy 116.395944 -278.688872)
			(xy 116.343982 -278.677012) (xy 116.294368 -278.65754) (xy 116.24821 -278.630891) (xy 116.206539 -278.59766)
			(xy 116.170287 -278.558589) (xy 116.140263 -278.514552) (xy 116.117137 -278.466531) (xy 116.101427 -278.415601)
			(xy 116.093484 -278.362897) (xy 115.864904 -278.362897) (xy 115.856961 -278.415601) (xy 115.841251 -278.466531)
			(xy 115.818125 -278.514552) (xy 115.788101 -278.558589) (xy 115.751849 -278.59766) (xy 115.710178 -278.630891)
			(xy 115.66402 -278.65754) (xy 115.614406 -278.677012) (xy 115.562444 -278.688872) (xy 115.509294 -278.692856)
			(xy 115.456144 -278.688872) (xy 115.404182 -278.677012) (xy 115.354568 -278.65754) (xy 115.30841 -278.630891)
			(xy 115.266739 -278.59766) (xy 115.230487 -278.558589) (xy 115.200463 -278.514552) (xy 115.177337 -278.466531)
			(xy 115.161627 -278.415601) (xy 115.153684 -278.362897) (xy 114.925363 -278.362897) (xy 114.925358 -278.363151)
			(xy 114.917415 -278.415855) (xy 114.901705 -278.466785) (xy 114.878579 -278.514806) (xy 114.848555 -278.558843)
			(xy 114.812303 -278.597914) (xy 114.770632 -278.631145) (xy 114.724474 -278.657794) (xy 114.67486 -278.677266)
			(xy 114.622898 -278.689126) (xy 114.569748 -278.69311) (xy 114.516598 -278.689126) (xy 114.464636 -278.677266)
			(xy 114.415022 -278.657794) (xy 114.368864 -278.631145) (xy 114.327193 -278.597914) (xy 114.290941 -278.558843)
			(xy 114.260917 -278.514806) (xy 114.237791 -278.466785) (xy 114.222081 -278.415855) (xy 114.214138 -278.363151)
			(xy 110.226104 -278.363151) (xy 110.218161 -278.415855) (xy 110.202451 -278.466785) (xy 110.179325 -278.514806)
			(xy 110.149301 -278.558843) (xy 110.113049 -278.597914) (xy 110.071378 -278.631145) (xy 110.02522 -278.657794)
			(xy 109.975606 -278.677266) (xy 109.923644 -278.689126) (xy 109.870494 -278.69311) (xy 109.817344 -278.689126)
			(xy 109.765382 -278.677266) (xy 109.715768 -278.657794) (xy 109.66961 -278.631145) (xy 109.627939 -278.597914)
			(xy 109.591687 -278.558843) (xy 109.561663 -278.514806) (xy 109.538537 -278.466785) (xy 109.522827 -278.415855)
			(xy 109.514884 -278.363151) (xy 109.286304 -278.363151) (xy 109.278361 -278.415855) (xy 109.262651 -278.466785)
			(xy 109.239525 -278.514806) (xy 109.209501 -278.558843) (xy 109.173249 -278.597914) (xy 109.131578 -278.631145)
			(xy 109.08542 -278.657794) (xy 109.035806 -278.677266) (xy 108.983844 -278.689126) (xy 108.930694 -278.69311)
			(xy 108.877544 -278.689126) (xy 108.825582 -278.677266) (xy 108.775968 -278.657794) (xy 108.72981 -278.631145)
			(xy 108.688139 -278.597914) (xy 108.651887 -278.558843) (xy 108.621863 -278.514806) (xy 108.598737 -278.466785)
			(xy 108.583027 -278.415855) (xy 108.575084 -278.363151) (xy 108.320214 -278.363151) (xy 108.312226 -278.413586)
			(xy 108.296214 -278.462865) (xy 108.272691 -278.509032) (xy 108.242235 -278.550951) (xy 108.205597 -278.587589)
			(xy 108.163678 -278.618045) (xy 108.117511 -278.641568) (xy 108.068232 -278.65758) (xy 108.017055 -278.665686)
			(xy 107.965241 -278.665686) (xy 107.914064 -278.65758) (xy 107.864785 -278.641568) (xy 107.818618 -278.618045)
			(xy 107.776699 -278.587589) (xy 107.740061 -278.550951) (xy 107.709605 -278.509032) (xy 107.686082 -278.462865)
			(xy 107.67007 -278.413586) (xy 107.661964 -278.362409) (xy 107.661456 -278.336502) (xy 107.662047 -278.308784)
			(xy 107.671372 -278.254138) (xy 107.679998 -278.22779) (xy 107.687872 -278.205692) (xy 107.482894 -277.8506)
			(xy 107.45978 -277.846282) (xy 107.434959 -277.841114) (xy 107.387178 -277.824162) (xy 107.342557 -277.800093)
			(xy 107.302149 -277.769473) (xy 107.266907 -277.733026) (xy 107.237663 -277.691612) (xy 107.215107 -277.646207)
			(xy 107.199771 -277.597884) (xy 107.192016 -277.547781) (xy 107.191556 -277.522432) (xy 106.910632 -277.522432)
			(xy 106.910124 -277.548319) (xy 106.902025 -277.599457) (xy 106.886026 -277.648697) (xy 106.86252 -277.694829)
			(xy 106.832088 -277.736716) (xy 106.795478 -277.773326) (xy 106.753591 -277.803758) (xy 106.707459 -277.827264)
			(xy 106.658219 -277.843263) (xy 106.607081 -277.851362) (xy 106.555307 -277.851362) (xy 106.504169 -277.843263)
			(xy 106.454929 -277.827264) (xy 106.408797 -277.803758) (xy 106.36691 -277.773326) (xy 106.3303 -277.736716)
			(xy 106.299868 -277.694829) (xy 106.276362 -277.648697) (xy 106.260363 -277.599457) (xy 106.252264 -277.548319)
			(xy 106.251756 -277.522432) (xy 105.997502 -277.522432) (xy 105.997004 -277.549081) (xy 105.989061 -277.601785)
			(xy 105.973351 -277.652715) (xy 105.950225 -277.700736) (xy 105.920201 -277.744773) (xy 105.883949 -277.783844)
			(xy 105.842278 -277.817075) (xy 105.79612 -277.843724) (xy 105.746506 -277.863196) (xy 105.694544 -277.875056)
			(xy 105.641394 -277.87904) (xy 105.588244 -277.875056) (xy 105.536282 -277.863196) (xy 105.486668 -277.843724)
			(xy 105.44051 -277.817075) (xy 105.398839 -277.783844) (xy 105.362587 -277.744773) (xy 105.332563 -277.700736)
			(xy 105.309437 -277.652715) (xy 105.293727 -277.601785) (xy 105.285784 -277.549081) (xy 105.08488 -277.549081)
			(xy 105.08488 -277.879048) (xy 105.085237 -277.88843) (xy 105.092018 -277.905922) (xy 105.098088 -277.913084)
			(xy 105.123742 -277.939754) (xy 105.14838 -277.965154) (xy 105.1553 -277.97174) (xy 105.172656 -277.97969)
			(xy 105.182162 -277.980648) (xy 105.183178 -277.980648) (xy 105.209238 -277.98196) (xy 105.26058 -277.991265)
			(xy 105.310014 -278.007963) (xy 105.356481 -278.031697) (xy 105.398987 -278.06196) (xy 105.436621 -278.098102)
			(xy 105.468576 -278.13935) (xy 105.49417 -278.18482) (xy 105.512852 -278.233538) (xy 105.524225 -278.284462)
			(xy 105.528043 -278.3365) (xy 105.526088 -278.363151) (xy 105.755938 -278.363151) (xy 105.755938 -278.309853)
			(xy 105.763881 -278.257149) (xy 105.779591 -278.206219) (xy 105.802717 -278.158198) (xy 105.832741 -278.114161)
			(xy 105.868993 -278.07509) (xy 105.910664 -278.041859) (xy 105.956822 -278.01521) (xy 106.006436 -277.995738)
			(xy 106.058398 -277.983878) (xy 106.111548 -277.979895) (xy 106.164698 -277.983878) (xy 106.21666 -277.995738)
			(xy 106.266274 -278.01521) (xy 106.312432 -278.041859) (xy 106.354103 -278.07509) (xy 106.390355 -278.114161)
			(xy 106.420379 -278.158198) (xy 106.443505 -278.206219) (xy 106.459215 -278.257149) (xy 106.467158 -278.309853)
			(xy 106.467656 -278.336502) (xy 106.467158 -278.363151) (xy 106.695738 -278.363151) (xy 106.695738 -278.309853)
			(xy 106.703681 -278.257149) (xy 106.719391 -278.206219) (xy 106.742517 -278.158198) (xy 106.772541 -278.114161)
			(xy 106.808793 -278.07509) (xy 106.850464 -278.041859) (xy 106.896622 -278.01521) (xy 106.946236 -277.995738)
			(xy 106.998198 -277.983878) (xy 107.051348 -277.979895) (xy 107.104498 -277.983878) (xy 107.15646 -277.995738)
			(xy 107.206074 -278.01521) (xy 107.252232 -278.041859) (xy 107.293903 -278.07509) (xy 107.330155 -278.114161)
			(xy 107.360179 -278.158198) (xy 107.383305 -278.206219) (xy 107.399015 -278.257149) (xy 107.406958 -278.309853)
			(xy 107.407456 -278.336502) (xy 107.406958 -278.363151) (xy 107.399015 -278.415855) (xy 107.383305 -278.466785)
			(xy 107.360179 -278.514806) (xy 107.330155 -278.558843) (xy 107.293903 -278.597914) (xy 107.252232 -278.631145)
			(xy 107.206074 -278.657794) (xy 107.15646 -278.677266) (xy 107.104498 -278.689126) (xy 107.051348 -278.69311)
			(xy 106.998198 -278.689126) (xy 106.946236 -278.677266) (xy 106.896622 -278.657794) (xy 106.850464 -278.631145)
			(xy 106.808793 -278.597914) (xy 106.772541 -278.558843) (xy 106.742517 -278.514806) (xy 106.719391 -278.466785)
			(xy 106.703681 -278.415855) (xy 106.695738 -278.363151) (xy 106.467158 -278.363151) (xy 106.459215 -278.415855)
			(xy 106.443505 -278.466785) (xy 106.420379 -278.514806) (xy 106.390355 -278.558843) (xy 106.354103 -278.597914)
			(xy 106.312432 -278.631145) (xy 106.266274 -278.657794) (xy 106.21666 -278.677266) (xy 106.164698 -278.689126)
			(xy 106.111548 -278.69311) (xy 106.058398 -278.689126) (xy 106.006436 -278.677266) (xy 105.956822 -278.657794)
			(xy 105.910664 -278.631145) (xy 105.868993 -278.597914) (xy 105.832741 -278.558843) (xy 105.802717 -278.514806)
			(xy 105.779591 -278.466785) (xy 105.763881 -278.415855) (xy 105.755938 -278.363151) (xy 105.526088 -278.363151)
			(xy 105.524225 -278.388538) (xy 105.512852 -278.439462) (xy 105.49417 -278.48818) (xy 105.468576 -278.533651)
			(xy 105.43662 -278.574898) (xy 105.398987 -278.61104) (xy 105.356481 -278.641303) (xy 105.310014 -278.665037)
			(xy 105.26058 -278.681735) (xy 105.209238 -278.69104) (xy 105.183178 -278.692356) (xy 105.182162 -278.692356)
			(xy 105.172647 -278.693276) (xy 105.155285 -278.701239) (xy 105.14838 -278.70785) (xy 105.123742 -278.73325)
			(xy 105.098088 -278.75992) (xy 105.092131 -278.767149) (xy 105.085369 -278.784601) (xy 105.08488 -278.793956)
			(xy 105.08488 -279.176967) (xy 105.286038 -279.176967) (xy 105.286038 -279.123669) (xy 105.293981 -279.070965)
			(xy 105.309691 -279.020035) (xy 105.332817 -278.972014) (xy 105.362841 -278.927977) (xy 105.399093 -278.888906)
			(xy 105.440764 -278.855675) (xy 105.486922 -278.829026) (xy 105.536536 -278.809554) (xy 105.588498 -278.797694)
			(xy 105.641648 -278.793711) (xy 105.694798 -278.797694) (xy 105.74676 -278.809554) (xy 105.796374 -278.829026)
			(xy 105.842532 -278.855675) (xy 105.884203 -278.888906) (xy 105.920455 -278.927977) (xy 105.950479 -278.972014)
			(xy 105.973605 -279.020035) (xy 105.989315 -279.070965) (xy 105.997258 -279.123669) (xy 105.997756 -279.150318)
			(xy 105.997258 -279.176967) (xy 106.225838 -279.176967) (xy 106.225838 -279.123669) (xy 106.233781 -279.070965)
			(xy 106.249491 -279.020035) (xy 106.272617 -278.972014) (xy 106.302641 -278.927977) (xy 106.338893 -278.888906)
			(xy 106.380564 -278.855675) (xy 106.426722 -278.829026) (xy 106.476336 -278.809554) (xy 106.528298 -278.797694)
			(xy 106.581448 -278.793711) (xy 106.634598 -278.797694) (xy 106.68656 -278.809554) (xy 106.736174 -278.829026)
			(xy 106.782332 -278.855675) (xy 106.824003 -278.888906) (xy 106.860255 -278.927977) (xy 106.890279 -278.972014)
			(xy 106.913405 -279.020035) (xy 106.929115 -279.070965) (xy 106.937058 -279.123669) (xy 106.937556 -279.150318)
			(xy 106.937058 -279.176967) (xy 107.165384 -279.176967) (xy 107.165384 -279.123669) (xy 107.173327 -279.070965)
			(xy 107.189037 -279.020035) (xy 107.212163 -278.972014) (xy 107.242187 -278.927977) (xy 107.278439 -278.888906)
			(xy 107.32011 -278.855675) (xy 107.366268 -278.829026) (xy 107.415882 -278.809554) (xy 107.467844 -278.797694)
			(xy 107.520994 -278.793711) (xy 107.574144 -278.797694) (xy 107.626106 -278.809554) (xy 107.67572 -278.829026)
			(xy 107.721878 -278.855675) (xy 107.763549 -278.888906) (xy 107.799801 -278.927977) (xy 107.829825 -278.972014)
			(xy 107.852951 -279.020035) (xy 107.868661 -279.070965) (xy 107.876604 -279.123669) (xy 107.877102 -279.150318)
			(xy 107.876604 -279.176967) (xy 108.105184 -279.176967) (xy 108.105184 -279.123669) (xy 108.113127 -279.070965)
			(xy 108.128837 -279.020035) (xy 108.151963 -278.972014) (xy 108.181987 -278.927977) (xy 108.218239 -278.888906)
			(xy 108.25991 -278.855675) (xy 108.306068 -278.829026) (xy 108.355682 -278.809554) (xy 108.407644 -278.797694)
			(xy 108.460794 -278.793711) (xy 108.513944 -278.797694) (xy 108.565906 -278.809554) (xy 108.61552 -278.829026)
			(xy 108.661678 -278.855675) (xy 108.703349 -278.888906) (xy 108.739601 -278.927977) (xy 108.769625 -278.972014)
			(xy 108.792751 -279.020035) (xy 108.808461 -279.070965) (xy 108.816404 -279.123669) (xy 108.816902 -279.150318)
			(xy 108.816404 -279.176967) (xy 114.683784 -279.176967) (xy 114.683784 -279.123669) (xy 114.691727 -279.070965)
			(xy 114.707437 -279.020035) (xy 114.730563 -278.972014) (xy 114.760587 -278.927977) (xy 114.796839 -278.888906)
			(xy 114.83851 -278.855675) (xy 114.884668 -278.829026) (xy 114.934282 -278.809554) (xy 114.986244 -278.797694)
			(xy 115.039394 -278.793711) (xy 115.092544 -278.797694) (xy 115.144506 -278.809554) (xy 115.19412 -278.829026)
			(xy 115.240278 -278.855675) (xy 115.281949 -278.888906) (xy 115.318201 -278.927977) (xy 115.348225 -278.972014)
			(xy 115.371351 -279.020035) (xy 115.387061 -279.070965) (xy 115.395004 -279.123669) (xy 115.395502 -279.150318)
			(xy 115.395004 -279.176967) (xy 115.623584 -279.176967) (xy 115.623584 -279.123669) (xy 115.631527 -279.070965)
			(xy 115.647237 -279.020035) (xy 115.670363 -278.972014) (xy 115.700387 -278.927977) (xy 115.736639 -278.888906)
			(xy 115.77831 -278.855675) (xy 115.824468 -278.829026) (xy 115.874082 -278.809554) (xy 115.926044 -278.797694)
			(xy 115.979194 -278.793711) (xy 116.032344 -278.797694) (xy 116.084306 -278.809554) (xy 116.13392 -278.829026)
			(xy 116.180078 -278.855675) (xy 116.221749 -278.888906) (xy 116.258001 -278.927977) (xy 116.288025 -278.972014)
			(xy 116.311151 -279.020035) (xy 116.326861 -279.070965) (xy 116.334804 -279.123669) (xy 116.335302 -279.150318)
			(xy 116.334809 -279.176713) (xy 116.563638 -279.176713) (xy 116.563638 -279.123415) (xy 116.571581 -279.070711)
			(xy 116.587291 -279.019781) (xy 116.610417 -278.97176) (xy 116.640441 -278.927723) (xy 116.676693 -278.888652)
			(xy 116.718364 -278.855421) (xy 116.764522 -278.828772) (xy 116.814136 -278.8093) (xy 116.866098 -278.79744)
			(xy 116.919248 -278.793457) (xy 116.972398 -278.79744) (xy 117.02436 -278.8093) (xy 117.073974 -278.828772)
			(xy 117.120132 -278.855421) (xy 117.161803 -278.888652) (xy 117.198055 -278.927723) (xy 117.228079 -278.97176)
			(xy 117.251205 -279.019781) (xy 117.266915 -279.070711) (xy 117.274858 -279.123415) (xy 117.275356 -279.150064)
			(xy 117.274858 -279.176713) (xy 117.27482 -279.176967) (xy 117.503438 -279.176967) (xy 117.503438 -279.123669)
			(xy 117.511381 -279.070965) (xy 117.527091 -279.020035) (xy 117.550217 -278.972014) (xy 117.580241 -278.927977)
			(xy 117.616493 -278.888906) (xy 117.658164 -278.855675) (xy 117.704322 -278.829026) (xy 117.753936 -278.809554)
			(xy 117.805898 -278.797694) (xy 117.859048 -278.793711) (xy 117.912198 -278.797694) (xy 117.96416 -278.809554)
			(xy 118.013774 -278.829026) (xy 118.059932 -278.855675) (xy 118.101603 -278.888906) (xy 118.137855 -278.927977)
			(xy 118.167879 -278.972014) (xy 118.191005 -279.020035) (xy 118.206715 -279.070965) (xy 118.214658 -279.123669)
			(xy 118.215156 -279.150318) (xy 118.214658 -279.176967) (xy 118.442984 -279.176967) (xy 118.442984 -279.123669)
			(xy 118.450927 -279.070965) (xy 118.466637 -279.020035) (xy 118.489763 -278.972014) (xy 118.519787 -278.927977)
			(xy 118.556039 -278.888906) (xy 118.59771 -278.855675) (xy 118.643868 -278.829026) (xy 118.693482 -278.809554)
			(xy 118.745444 -278.797694) (xy 118.798594 -278.793711) (xy 118.851744 -278.797694) (xy 118.903706 -278.809554)
			(xy 118.95332 -278.829026) (xy 118.999478 -278.855675) (xy 119.041149 -278.888906) (xy 119.077401 -278.927977)
			(xy 119.107425 -278.972014) (xy 119.130551 -279.020035) (xy 119.146261 -279.070965) (xy 119.154204 -279.123669)
			(xy 119.154702 -279.150318) (xy 119.154204 -279.176967) (xy 119.382784 -279.176967) (xy 119.382784 -279.123669)
			(xy 119.390727 -279.070965) (xy 119.406437 -279.020035) (xy 119.429563 -278.972014) (xy 119.459587 -278.927977)
			(xy 119.495839 -278.888906) (xy 119.53751 -278.855675) (xy 119.583668 -278.829026) (xy 119.633282 -278.809554)
			(xy 119.685244 -278.797694) (xy 119.738394 -278.793711) (xy 119.791544 -278.797694) (xy 119.843506 -278.809554)
			(xy 119.89312 -278.829026) (xy 119.939278 -278.855675) (xy 119.980949 -278.888906) (xy 120.017201 -278.927977)
			(xy 120.047225 -278.972014) (xy 120.070351 -279.020035) (xy 120.086061 -279.070965) (xy 120.094004 -279.123669)
			(xy 120.094502 -279.150318) (xy 120.094004 -279.176967) (xy 120.322838 -279.176967) (xy 120.322838 -279.123669)
			(xy 120.330781 -279.070965) (xy 120.346491 -279.020035) (xy 120.369617 -278.972014) (xy 120.399641 -278.927977)
			(xy 120.435893 -278.888906) (xy 120.477564 -278.855675) (xy 120.523722 -278.829026) (xy 120.573336 -278.809554)
			(xy 120.625298 -278.797694) (xy 120.678448 -278.793711) (xy 120.731598 -278.797694) (xy 120.78356 -278.809554)
			(xy 120.833174 -278.829026) (xy 120.879332 -278.855675) (xy 120.921003 -278.888906) (xy 120.957255 -278.927977)
			(xy 120.987279 -278.972014) (xy 121.010405 -279.020035) (xy 121.026115 -279.070965) (xy 121.034058 -279.123669)
			(xy 121.034556 -279.150318) (xy 121.034058 -279.176967) (xy 121.262384 -279.176967) (xy 121.262384 -279.123669)
			(xy 121.270327 -279.070965) (xy 121.286037 -279.020035) (xy 121.309163 -278.972014) (xy 121.339187 -278.927977)
			(xy 121.375439 -278.888906) (xy 121.41711 -278.855675) (xy 121.463268 -278.829026) (xy 121.512882 -278.809554)
			(xy 121.564844 -278.797694) (xy 121.617994 -278.793711) (xy 121.671144 -278.797694) (xy 121.723106 -278.809554)
			(xy 121.77272 -278.829026) (xy 121.818878 -278.855675) (xy 121.860549 -278.888906) (xy 121.896801 -278.927977)
			(xy 121.926825 -278.972014) (xy 121.949951 -279.020035) (xy 121.965661 -279.070965) (xy 121.973604 -279.123669)
			(xy 121.974102 -279.150318) (xy 121.973604 -279.176967) (xy 122.202184 -279.176967) (xy 122.202184 -279.123669)
			(xy 122.210127 -279.070965) (xy 122.225837 -279.020035) (xy 122.248963 -278.972014) (xy 122.278987 -278.927977)
			(xy 122.315239 -278.888906) (xy 122.35691 -278.855675) (xy 122.403068 -278.829026) (xy 122.452682 -278.809554)
			(xy 122.504644 -278.797694) (xy 122.557794 -278.793711) (xy 122.610944 -278.797694) (xy 122.662906 -278.809554)
			(xy 122.71252 -278.829026) (xy 122.758678 -278.855675) (xy 122.800349 -278.888906) (xy 122.836601 -278.927977)
			(xy 122.866625 -278.972014) (xy 122.889751 -279.020035) (xy 122.905461 -279.070965) (xy 122.913404 -279.123669)
			(xy 122.913902 -279.150318) (xy 122.913404 -279.176967) (xy 123.142238 -279.176967) (xy 123.142238 -279.123669)
			(xy 123.150181 -279.070965) (xy 123.165891 -279.020035) (xy 123.189017 -278.972014) (xy 123.219041 -278.927977)
			(xy 123.255293 -278.888906) (xy 123.296964 -278.855675) (xy 123.343122 -278.829026) (xy 123.392736 -278.809554)
			(xy 123.444698 -278.797694) (xy 123.497848 -278.793711) (xy 123.550998 -278.797694) (xy 123.60296 -278.809554)
			(xy 123.652574 -278.829026) (xy 123.698732 -278.855675) (xy 123.740403 -278.888906) (xy 123.776655 -278.927977)
			(xy 123.806679 -278.972014) (xy 123.829805 -279.020035) (xy 123.845515 -279.070965) (xy 123.853458 -279.123669)
			(xy 123.853956 -279.150318) (xy 123.853458 -279.176967) (xy 124.081784 -279.176967) (xy 124.081784 -279.123669)
			(xy 124.089727 -279.070965) (xy 124.105437 -279.020035) (xy 124.128563 -278.972014) (xy 124.158587 -278.927977)
			(xy 124.194839 -278.888906) (xy 124.23651 -278.855675) (xy 124.282668 -278.829026) (xy 124.332282 -278.809554)
			(xy 124.384244 -278.797694) (xy 124.437394 -278.793711) (xy 124.490544 -278.797694) (xy 124.542506 -278.809554)
			(xy 124.59212 -278.829026) (xy 124.638278 -278.855675) (xy 124.679949 -278.888906) (xy 124.716201 -278.927977)
			(xy 124.746225 -278.972014) (xy 124.769351 -279.020035) (xy 124.785061 -279.070965) (xy 124.793004 -279.123669)
			(xy 124.793502 -279.150318) (xy 124.793004 -279.176967) (xy 125.021584 -279.176967) (xy 125.021584 -279.123669)
			(xy 125.029527 -279.070965) (xy 125.045237 -279.020035) (xy 125.068363 -278.972014) (xy 125.098387 -278.927977)
			(xy 125.134639 -278.888906) (xy 125.17631 -278.855675) (xy 125.222468 -278.829026) (xy 125.272082 -278.809554)
			(xy 125.324044 -278.797694) (xy 125.377194 -278.793711) (xy 125.430344 -278.797694) (xy 125.482306 -278.809554)
			(xy 125.53192 -278.829026) (xy 125.578078 -278.855675) (xy 125.619749 -278.888906) (xy 125.656001 -278.927977)
			(xy 125.686025 -278.972014) (xy 125.709151 -279.020035) (xy 125.724861 -279.070965) (xy 125.732804 -279.123669)
			(xy 125.733302 -279.150318) (xy 125.732804 -279.176967) (xy 125.961384 -279.176967) (xy 125.961384 -279.123669)
			(xy 125.969327 -279.070965) (xy 125.985037 -279.020035) (xy 126.008163 -278.972014) (xy 126.038187 -278.927977)
			(xy 126.074439 -278.888906) (xy 126.11611 -278.855675) (xy 126.162268 -278.829026) (xy 126.211882 -278.809554)
			(xy 126.263844 -278.797694) (xy 126.316994 -278.793711) (xy 126.370144 -278.797694) (xy 126.422106 -278.809554)
			(xy 126.47172 -278.829026) (xy 126.517878 -278.855675) (xy 126.559549 -278.888906) (xy 126.595801 -278.927977)
			(xy 126.625825 -278.972014) (xy 126.648951 -279.020035) (xy 126.664661 -279.070965) (xy 126.672604 -279.123669)
			(xy 126.673102 -279.150318) (xy 126.672604 -279.176967) (xy 126.901184 -279.176967) (xy 126.901184 -279.123669)
			(xy 126.909127 -279.070965) (xy 126.924837 -279.020035) (xy 126.947963 -278.972014) (xy 126.977987 -278.927977)
			(xy 127.014239 -278.888906) (xy 127.05591 -278.855675) (xy 127.102068 -278.829026) (xy 127.151682 -278.809554)
			(xy 127.203644 -278.797694) (xy 127.256794 -278.793711) (xy 127.309944 -278.797694) (xy 127.361906 -278.809554)
			(xy 127.41152 -278.829026) (xy 127.457678 -278.855675) (xy 127.499349 -278.888906) (xy 127.535601 -278.927977)
			(xy 127.565625 -278.972014) (xy 127.588751 -279.020035) (xy 127.604461 -279.070965) (xy 127.612404 -279.123669)
			(xy 127.612902 -279.150318) (xy 127.612404 -279.176967) (xy 127.840984 -279.176967) (xy 127.840984 -279.123669)
			(xy 127.848927 -279.070965) (xy 127.864637 -279.020035) (xy 127.887763 -278.972014) (xy 127.917787 -278.927977)
			(xy 127.954039 -278.888906) (xy 127.99571 -278.855675) (xy 128.041868 -278.829026) (xy 128.091482 -278.809554)
			(xy 128.143444 -278.797694) (xy 128.196594 -278.793711) (xy 128.249744 -278.797694) (xy 128.301706 -278.809554)
			(xy 128.35132 -278.829026) (xy 128.397478 -278.855675) (xy 128.439149 -278.888906) (xy 128.475401 -278.927977)
			(xy 128.505425 -278.972014) (xy 128.528551 -279.020035) (xy 128.544261 -279.070965) (xy 128.552204 -279.123669)
			(xy 128.552702 -279.150318) (xy 128.552204 -279.176967) (xy 128.780784 -279.176967) (xy 128.780784 -279.123669)
			(xy 128.788727 -279.070965) (xy 128.804437 -279.020035) (xy 128.827563 -278.972014) (xy 128.857587 -278.927977)
			(xy 128.893839 -278.888906) (xy 128.93551 -278.855675) (xy 128.981668 -278.829026) (xy 129.031282 -278.809554)
			(xy 129.083244 -278.797694) (xy 129.136394 -278.793711) (xy 129.189544 -278.797694) (xy 129.241506 -278.809554)
			(xy 129.29112 -278.829026) (xy 129.337278 -278.855675) (xy 129.378949 -278.888906) (xy 129.415201 -278.927977)
			(xy 129.445225 -278.972014) (xy 129.468351 -279.020035) (xy 129.484061 -279.070965) (xy 129.492004 -279.123669)
			(xy 129.492502 -279.150318) (xy 129.492004 -279.176967) (xy 129.720838 -279.176967) (xy 129.720838 -279.123669)
			(xy 129.728781 -279.070965) (xy 129.744491 -279.020035) (xy 129.767617 -278.972014) (xy 129.797641 -278.927977)
			(xy 129.833893 -278.888906) (xy 129.875564 -278.855675) (xy 129.921722 -278.829026) (xy 129.971336 -278.809554)
			(xy 130.023298 -278.797694) (xy 130.076448 -278.793711) (xy 130.129598 -278.797694) (xy 130.18156 -278.809554)
			(xy 130.231174 -278.829026) (xy 130.277332 -278.855675) (xy 130.319003 -278.888906) (xy 130.355255 -278.927977)
			(xy 130.385279 -278.972014) (xy 130.408405 -279.020035) (xy 130.424115 -279.070965) (xy 130.432058 -279.123669)
			(xy 130.432556 -279.150318) (xy 130.432076 -279.176026) (xy 130.689346 -279.176026) (xy 130.689346 -279.12461)
			(xy 130.697389 -279.073828) (xy 130.713277 -279.024929) (xy 130.73662 -278.979117) (xy 130.766841 -278.937521)
			(xy 130.803197 -278.901165) (xy 130.844793 -278.870944) (xy 130.890605 -278.847601) (xy 130.939504 -278.831713)
			(xy 130.990286 -278.82367) (xy 131.041702 -278.82367) (xy 131.092484 -278.831713) (xy 131.141383 -278.847601)
			(xy 131.187195 -278.870944) (xy 131.228791 -278.901165) (xy 131.265147 -278.937521) (xy 131.295368 -278.979117)
			(xy 131.318711 -279.024929) (xy 131.334599 -279.073828) (xy 131.342642 -279.12461) (xy 131.343146 -279.150318)
			(xy 131.342642 -279.176026) (xy 131.342493 -279.176967) (xy 131.600438 -279.176967) (xy 131.600438 -279.123669)
			(xy 131.608381 -279.070965) (xy 131.624091 -279.020035) (xy 131.647217 -278.972014) (xy 131.677241 -278.927977)
			(xy 131.713493 -278.888906) (xy 131.755164 -278.855675) (xy 131.801322 -278.829026) (xy 131.850936 -278.809554)
			(xy 131.902898 -278.797694) (xy 131.956048 -278.793711) (xy 132.009198 -278.797694) (xy 132.06116 -278.809554)
			(xy 132.110774 -278.829026) (xy 132.156932 -278.855675) (xy 132.198603 -278.888906) (xy 132.234855 -278.927977)
			(xy 132.264879 -278.972014) (xy 132.288005 -279.020035) (xy 132.303715 -279.070965) (xy 132.311658 -279.123669)
			(xy 132.312156 -279.150318) (xy 132.311658 -279.176967) (xy 132.540238 -279.176967) (xy 132.540238 -279.123669)
			(xy 132.548181 -279.070965) (xy 132.563891 -279.020035) (xy 132.587017 -278.972014) (xy 132.617041 -278.927977)
			(xy 132.653293 -278.888906) (xy 132.694964 -278.855675) (xy 132.741122 -278.829026) (xy 132.790736 -278.809554)
			(xy 132.842698 -278.797694) (xy 132.895848 -278.793711) (xy 132.948998 -278.797694) (xy 133.00096 -278.809554)
			(xy 133.050574 -278.829026) (xy 133.096732 -278.855675) (xy 133.138403 -278.888906) (xy 133.174655 -278.927977)
			(xy 133.204679 -278.972014) (xy 133.227805 -279.020035) (xy 133.243515 -279.070965) (xy 133.251458 -279.123669)
			(xy 133.251956 -279.150318) (xy 133.251458 -279.176967) (xy 133.479784 -279.176967) (xy 133.479784 -279.123669)
			(xy 133.487727 -279.070965) (xy 133.503437 -279.020035) (xy 133.526563 -278.972014) (xy 133.556587 -278.927977)
			(xy 133.592839 -278.888906) (xy 133.63451 -278.855675) (xy 133.680668 -278.829026) (xy 133.730282 -278.809554)
			(xy 133.782244 -278.797694) (xy 133.835394 -278.793711) (xy 133.888544 -278.797694) (xy 133.940506 -278.809554)
			(xy 133.99012 -278.829026) (xy 134.036278 -278.855675) (xy 134.077949 -278.888906) (xy 134.114201 -278.927977)
			(xy 134.144225 -278.972014) (xy 134.167351 -279.020035) (xy 134.183061 -279.070965) (xy 134.191004 -279.123669)
			(xy 134.191502 -279.150318) (xy 134.191022 -279.176026) (xy 134.448546 -279.176026) (xy 134.448546 -279.12461)
			(xy 134.456589 -279.073828) (xy 134.472477 -279.024929) (xy 134.49582 -278.979117) (xy 134.526041 -278.937521)
			(xy 134.562397 -278.901165) (xy 134.603993 -278.870944) (xy 134.649805 -278.847601) (xy 134.698704 -278.831713)
			(xy 134.749486 -278.82367) (xy 134.800902 -278.82367) (xy 134.851684 -278.831713) (xy 134.900583 -278.847601)
			(xy 134.946395 -278.870944) (xy 134.987991 -278.901165) (xy 135.024347 -278.937521) (xy 135.054568 -278.979117)
			(xy 135.077911 -279.024929) (xy 135.093799 -279.073828) (xy 135.101842 -279.12461) (xy 135.102346 -279.150318)
			(xy 135.101842 -279.176026) (xy 135.101693 -279.176967) (xy 135.359384 -279.176967) (xy 135.359384 -279.123669)
			(xy 135.367327 -279.070965) (xy 135.383037 -279.020035) (xy 135.406163 -278.972014) (xy 135.436187 -278.927977)
			(xy 135.472439 -278.888906) (xy 135.51411 -278.855675) (xy 135.560268 -278.829026) (xy 135.609882 -278.809554)
			(xy 135.661844 -278.797694) (xy 135.714994 -278.793711) (xy 135.768144 -278.797694) (xy 135.820106 -278.809554)
			(xy 135.86972 -278.829026) (xy 135.915878 -278.855675) (xy 135.957549 -278.888906) (xy 135.993801 -278.927977)
			(xy 136.023825 -278.972014) (xy 136.046951 -279.020035) (xy 136.062661 -279.070965) (xy 136.070604 -279.123669)
			(xy 136.071102 -279.150318) (xy 136.070604 -279.176967) (xy 136.062661 -279.229671) (xy 136.046951 -279.280601)
			(xy 136.023825 -279.328622) (xy 135.993801 -279.372659) (xy 135.957549 -279.41173) (xy 135.915878 -279.444961)
			(xy 135.86972 -279.47161) (xy 135.820106 -279.491082) (xy 135.768144 -279.502942) (xy 135.714994 -279.506926)
			(xy 135.661844 -279.502942) (xy 135.609882 -279.491082) (xy 135.560268 -279.47161) (xy 135.51411 -279.444961)
			(xy 135.472439 -279.41173) (xy 135.436187 -279.372659) (xy 135.406163 -279.328622) (xy 135.383037 -279.280601)
			(xy 135.367327 -279.229671) (xy 135.359384 -279.176967) (xy 135.101693 -279.176967) (xy 135.093799 -279.226808)
			(xy 135.077911 -279.275707) (xy 135.054568 -279.321519) (xy 135.024347 -279.363115) (xy 134.987991 -279.399471)
			(xy 134.946395 -279.429692) (xy 134.900583 -279.453035) (xy 134.851684 -279.468923) (xy 134.800902 -279.476966)
			(xy 134.749486 -279.476966) (xy 134.698704 -279.468923) (xy 134.649805 -279.453035) (xy 134.603993 -279.429692)
			(xy 134.562397 -279.399471) (xy 134.526041 -279.363115) (xy 134.49582 -279.321519) (xy 134.472477 -279.275707)
			(xy 134.456589 -279.226808) (xy 134.448546 -279.176026) (xy 134.191022 -279.176026) (xy 134.191004 -279.176967)
			(xy 134.183061 -279.229671) (xy 134.167351 -279.280601) (xy 134.144225 -279.328622) (xy 134.114201 -279.372659)
			(xy 134.077949 -279.41173) (xy 134.036278 -279.444961) (xy 133.99012 -279.47161) (xy 133.940506 -279.491082)
			(xy 133.888544 -279.502942) (xy 133.835394 -279.506926) (xy 133.782244 -279.502942) (xy 133.730282 -279.491082)
			(xy 133.680668 -279.47161) (xy 133.63451 -279.444961) (xy 133.592839 -279.41173) (xy 133.556587 -279.372659)
			(xy 133.526563 -279.328622) (xy 133.503437 -279.280601) (xy 133.487727 -279.229671) (xy 133.479784 -279.176967)
			(xy 133.251458 -279.176967) (xy 133.243515 -279.229671) (xy 133.227805 -279.280601) (xy 133.204679 -279.328622)
			(xy 133.174655 -279.372659) (xy 133.138403 -279.41173) (xy 133.096732 -279.444961) (xy 133.050574 -279.47161)
			(xy 133.00096 -279.491082) (xy 132.948998 -279.502942) (xy 132.895848 -279.506926) (xy 132.842698 -279.502942)
			(xy 132.790736 -279.491082) (xy 132.741122 -279.47161) (xy 132.694964 -279.444961) (xy 132.653293 -279.41173)
			(xy 132.617041 -279.372659) (xy 132.587017 -279.328622) (xy 132.563891 -279.280601) (xy 132.548181 -279.229671)
			(xy 132.540238 -279.176967) (xy 132.311658 -279.176967) (xy 132.303715 -279.229671) (xy 132.288005 -279.280601)
			(xy 132.264879 -279.328622) (xy 132.234855 -279.372659) (xy 132.198603 -279.41173) (xy 132.156932 -279.444961)
			(xy 132.110774 -279.47161) (xy 132.06116 -279.491082) (xy 132.009198 -279.502942) (xy 131.956048 -279.506926)
			(xy 131.902898 -279.502942) (xy 131.850936 -279.491082) (xy 131.801322 -279.47161) (xy 131.755164 -279.444961)
			(xy 131.713493 -279.41173) (xy 131.677241 -279.372659) (xy 131.647217 -279.328622) (xy 131.624091 -279.280601)
			(xy 131.608381 -279.229671) (xy 131.600438 -279.176967) (xy 131.342493 -279.176967) (xy 131.334599 -279.226808)
			(xy 131.318711 -279.275707) (xy 131.295368 -279.321519) (xy 131.265147 -279.363115) (xy 131.228791 -279.399471)
			(xy 131.187195 -279.429692) (xy 131.141383 -279.453035) (xy 131.092484 -279.468923) (xy 131.041702 -279.476966)
			(xy 130.990286 -279.476966) (xy 130.939504 -279.468923) (xy 130.890605 -279.453035) (xy 130.844793 -279.429692)
			(xy 130.803197 -279.399471) (xy 130.766841 -279.363115) (xy 130.73662 -279.321519) (xy 130.713277 -279.275707)
			(xy 130.697389 -279.226808) (xy 130.689346 -279.176026) (xy 130.432076 -279.176026) (xy 130.432058 -279.176967)
			(xy 130.424115 -279.229671) (xy 130.408405 -279.280601) (xy 130.385279 -279.328622) (xy 130.355255 -279.372659)
			(xy 130.319003 -279.41173) (xy 130.277332 -279.444961) (xy 130.231174 -279.47161) (xy 130.18156 -279.491082)
			(xy 130.129598 -279.502942) (xy 130.076448 -279.506926) (xy 130.023298 -279.502942) (xy 129.971336 -279.491082)
			(xy 129.921722 -279.47161) (xy 129.875564 -279.444961) (xy 129.833893 -279.41173) (xy 129.797641 -279.372659)
			(xy 129.767617 -279.328622) (xy 129.744491 -279.280601) (xy 129.728781 -279.229671) (xy 129.720838 -279.176967)
			(xy 129.492004 -279.176967) (xy 129.484061 -279.229671) (xy 129.468351 -279.280601) (xy 129.445225 -279.328622)
			(xy 129.415201 -279.372659) (xy 129.378949 -279.41173) (xy 129.337278 -279.444961) (xy 129.29112 -279.47161)
			(xy 129.241506 -279.491082) (xy 129.189544 -279.502942) (xy 129.136394 -279.506926) (xy 129.083244 -279.502942)
			(xy 129.031282 -279.491082) (xy 128.981668 -279.47161) (xy 128.93551 -279.444961) (xy 128.893839 -279.41173)
			(xy 128.857587 -279.372659) (xy 128.827563 -279.328622) (xy 128.804437 -279.280601) (xy 128.788727 -279.229671)
			(xy 128.780784 -279.176967) (xy 128.552204 -279.176967) (xy 128.544261 -279.229671) (xy 128.528551 -279.280601)
			(xy 128.505425 -279.328622) (xy 128.475401 -279.372659) (xy 128.439149 -279.41173) (xy 128.397478 -279.444961)
			(xy 128.35132 -279.47161) (xy 128.301706 -279.491082) (xy 128.249744 -279.502942) (xy 128.196594 -279.506926)
			(xy 128.143444 -279.502942) (xy 128.091482 -279.491082) (xy 128.041868 -279.47161) (xy 127.99571 -279.444961)
			(xy 127.954039 -279.41173) (xy 127.917787 -279.372659) (xy 127.887763 -279.328622) (xy 127.864637 -279.280601)
			(xy 127.848927 -279.229671) (xy 127.840984 -279.176967) (xy 127.612404 -279.176967) (xy 127.604461 -279.229671)
			(xy 127.588751 -279.280601) (xy 127.565625 -279.328622) (xy 127.535601 -279.372659) (xy 127.499349 -279.41173)
			(xy 127.457678 -279.444961) (xy 127.41152 -279.47161) (xy 127.361906 -279.491082) (xy 127.309944 -279.502942)
			(xy 127.256794 -279.506926) (xy 127.203644 -279.502942) (xy 127.151682 -279.491082) (xy 127.102068 -279.47161)
			(xy 127.05591 -279.444961) (xy 127.014239 -279.41173) (xy 126.977987 -279.372659) (xy 126.947963 -279.328622)
			(xy 126.924837 -279.280601) (xy 126.909127 -279.229671) (xy 126.901184 -279.176967) (xy 126.672604 -279.176967)
			(xy 126.664661 -279.229671) (xy 126.648951 -279.280601) (xy 126.625825 -279.328622) (xy 126.595801 -279.372659)
			(xy 126.559549 -279.41173) (xy 126.517878 -279.444961) (xy 126.47172 -279.47161) (xy 126.422106 -279.491082)
			(xy 126.370144 -279.502942) (xy 126.316994 -279.506926) (xy 126.263844 -279.502942) (xy 126.211882 -279.491082)
			(xy 126.162268 -279.47161) (xy 126.11611 -279.444961) (xy 126.074439 -279.41173) (xy 126.038187 -279.372659)
			(xy 126.008163 -279.328622) (xy 125.985037 -279.280601) (xy 125.969327 -279.229671) (xy 125.961384 -279.176967)
			(xy 125.732804 -279.176967) (xy 125.724861 -279.229671) (xy 125.709151 -279.280601) (xy 125.686025 -279.328622)
			(xy 125.656001 -279.372659) (xy 125.619749 -279.41173) (xy 125.578078 -279.444961) (xy 125.53192 -279.47161)
			(xy 125.482306 -279.491082) (xy 125.430344 -279.502942) (xy 125.377194 -279.506926) (xy 125.324044 -279.502942)
			(xy 125.272082 -279.491082) (xy 125.222468 -279.47161) (xy 125.17631 -279.444961) (xy 125.134639 -279.41173)
			(xy 125.098387 -279.372659) (xy 125.068363 -279.328622) (xy 125.045237 -279.280601) (xy 125.029527 -279.229671)
			(xy 125.021584 -279.176967) (xy 124.793004 -279.176967) (xy 124.785061 -279.229671) (xy 124.769351 -279.280601)
			(xy 124.746225 -279.328622) (xy 124.716201 -279.372659) (xy 124.679949 -279.41173) (xy 124.638278 -279.444961)
			(xy 124.59212 -279.47161) (xy 124.542506 -279.491082) (xy 124.490544 -279.502942) (xy 124.437394 -279.506926)
			(xy 124.384244 -279.502942) (xy 124.332282 -279.491082) (xy 124.282668 -279.47161) (xy 124.23651 -279.444961)
			(xy 124.194839 -279.41173) (xy 124.158587 -279.372659) (xy 124.128563 -279.328622) (xy 124.105437 -279.280601)
			(xy 124.089727 -279.229671) (xy 124.081784 -279.176967) (xy 123.853458 -279.176967) (xy 123.845515 -279.229671)
			(xy 123.829805 -279.280601) (xy 123.806679 -279.328622) (xy 123.776655 -279.372659) (xy 123.740403 -279.41173)
			(xy 123.698732 -279.444961) (xy 123.652574 -279.47161) (xy 123.60296 -279.491082) (xy 123.550998 -279.502942)
			(xy 123.497848 -279.506926) (xy 123.444698 -279.502942) (xy 123.392736 -279.491082) (xy 123.343122 -279.47161)
			(xy 123.296964 -279.444961) (xy 123.255293 -279.41173) (xy 123.219041 -279.372659) (xy 123.189017 -279.328622)
			(xy 123.165891 -279.280601) (xy 123.150181 -279.229671) (xy 123.142238 -279.176967) (xy 122.913404 -279.176967)
			(xy 122.905461 -279.229671) (xy 122.889751 -279.280601) (xy 122.866625 -279.328622) (xy 122.836601 -279.372659)
			(xy 122.800349 -279.41173) (xy 122.758678 -279.444961) (xy 122.71252 -279.47161) (xy 122.662906 -279.491082)
			(xy 122.610944 -279.502942) (xy 122.557794 -279.506926) (xy 122.504644 -279.502942) (xy 122.452682 -279.491082)
			(xy 122.403068 -279.47161) (xy 122.35691 -279.444961) (xy 122.315239 -279.41173) (xy 122.278987 -279.372659)
			(xy 122.248963 -279.328622) (xy 122.225837 -279.280601) (xy 122.210127 -279.229671) (xy 122.202184 -279.176967)
			(xy 121.973604 -279.176967) (xy 121.965661 -279.229671) (xy 121.949951 -279.280601) (xy 121.926825 -279.328622)
			(xy 121.896801 -279.372659) (xy 121.860549 -279.41173) (xy 121.818878 -279.444961) (xy 121.77272 -279.47161)
			(xy 121.723106 -279.491082) (xy 121.671144 -279.502942) (xy 121.617994 -279.506926) (xy 121.564844 -279.502942)
			(xy 121.512882 -279.491082) (xy 121.463268 -279.47161) (xy 121.41711 -279.444961) (xy 121.375439 -279.41173)
			(xy 121.339187 -279.372659) (xy 121.309163 -279.328622) (xy 121.286037 -279.280601) (xy 121.270327 -279.229671)
			(xy 121.262384 -279.176967) (xy 121.034058 -279.176967) (xy 121.026115 -279.229671) (xy 121.010405 -279.280601)
			(xy 120.987279 -279.328622) (xy 120.957255 -279.372659) (xy 120.921003 -279.41173) (xy 120.879332 -279.444961)
			(xy 120.833174 -279.47161) (xy 120.78356 -279.491082) (xy 120.731598 -279.502942) (xy 120.678448 -279.506926)
			(xy 120.625298 -279.502942) (xy 120.573336 -279.491082) (xy 120.523722 -279.47161) (xy 120.477564 -279.444961)
			(xy 120.435893 -279.41173) (xy 120.399641 -279.372659) (xy 120.369617 -279.328622) (xy 120.346491 -279.280601)
			(xy 120.330781 -279.229671) (xy 120.322838 -279.176967) (xy 120.094004 -279.176967) (xy 120.086061 -279.229671)
			(xy 120.070351 -279.280601) (xy 120.047225 -279.328622) (xy 120.017201 -279.372659) (xy 119.980949 -279.41173)
			(xy 119.939278 -279.444961) (xy 119.89312 -279.47161) (xy 119.843506 -279.491082) (xy 119.791544 -279.502942)
			(xy 119.738394 -279.506926) (xy 119.685244 -279.502942) (xy 119.633282 -279.491082) (xy 119.583668 -279.47161)
			(xy 119.53751 -279.444961) (xy 119.495839 -279.41173) (xy 119.459587 -279.372659) (xy 119.429563 -279.328622)
			(xy 119.406437 -279.280601) (xy 119.390727 -279.229671) (xy 119.382784 -279.176967) (xy 119.154204 -279.176967)
			(xy 119.146261 -279.229671) (xy 119.130551 -279.280601) (xy 119.107425 -279.328622) (xy 119.077401 -279.372659)
			(xy 119.041149 -279.41173) (xy 118.999478 -279.444961) (xy 118.95332 -279.47161) (xy 118.903706 -279.491082)
			(xy 118.851744 -279.502942) (xy 118.798594 -279.506926) (xy 118.745444 -279.502942) (xy 118.693482 -279.491082)
			(xy 118.643868 -279.47161) (xy 118.59771 -279.444961) (xy 118.556039 -279.41173) (xy 118.519787 -279.372659)
			(xy 118.489763 -279.328622) (xy 118.466637 -279.280601) (xy 118.450927 -279.229671) (xy 118.442984 -279.176967)
			(xy 118.214658 -279.176967) (xy 118.206715 -279.229671) (xy 118.191005 -279.280601) (xy 118.167879 -279.328622)
			(xy 118.137855 -279.372659) (xy 118.101603 -279.41173) (xy 118.059932 -279.444961) (xy 118.013774 -279.47161)
			(xy 117.96416 -279.491082) (xy 117.912198 -279.502942) (xy 117.859048 -279.506926) (xy 117.805898 -279.502942)
			(xy 117.753936 -279.491082) (xy 117.704322 -279.47161) (xy 117.658164 -279.444961) (xy 117.616493 -279.41173)
			(xy 117.580241 -279.372659) (xy 117.550217 -279.328622) (xy 117.527091 -279.280601) (xy 117.511381 -279.229671)
			(xy 117.503438 -279.176967) (xy 117.27482 -279.176967) (xy 117.266915 -279.229417) (xy 117.251205 -279.280347)
			(xy 117.228079 -279.328368) (xy 117.198055 -279.372405) (xy 117.161803 -279.411476) (xy 117.120132 -279.444707)
			(xy 117.073974 -279.471356) (xy 117.02436 -279.490828) (xy 116.972398 -279.502688) (xy 116.919248 -279.506672)
			(xy 116.866098 -279.502688) (xy 116.814136 -279.490828) (xy 116.764522 -279.471356) (xy 116.718364 -279.444707)
			(xy 116.676693 -279.411476) (xy 116.640441 -279.372405) (xy 116.610417 -279.328368) (xy 116.587291 -279.280347)
			(xy 116.571581 -279.229417) (xy 116.563638 -279.176713) (xy 116.334809 -279.176713) (xy 116.334804 -279.176967)
			(xy 116.326861 -279.229671) (xy 116.311151 -279.280601) (xy 116.288025 -279.328622) (xy 116.258001 -279.372659)
			(xy 116.221749 -279.41173) (xy 116.180078 -279.444961) (xy 116.13392 -279.47161) (xy 116.084306 -279.491082)
			(xy 116.032344 -279.502942) (xy 115.979194 -279.506926) (xy 115.926044 -279.502942) (xy 115.874082 -279.491082)
			(xy 115.824468 -279.47161) (xy 115.77831 -279.444961) (xy 115.736639 -279.41173) (xy 115.700387 -279.372659)
			(xy 115.670363 -279.328622) (xy 115.647237 -279.280601) (xy 115.631527 -279.229671) (xy 115.623584 -279.176967)
			(xy 115.395004 -279.176967) (xy 115.387061 -279.229671) (xy 115.371351 -279.280601) (xy 115.348225 -279.328622)
			(xy 115.318201 -279.372659) (xy 115.281949 -279.41173) (xy 115.240278 -279.444961) (xy 115.19412 -279.47161)
			(xy 115.144506 -279.491082) (xy 115.092544 -279.502942) (xy 115.039394 -279.506926) (xy 114.986244 -279.502942)
			(xy 114.934282 -279.491082) (xy 114.884668 -279.47161) (xy 114.83851 -279.444961) (xy 114.796839 -279.41173)
			(xy 114.760587 -279.372659) (xy 114.730563 -279.328622) (xy 114.707437 -279.280601) (xy 114.691727 -279.229671)
			(xy 114.683784 -279.176967) (xy 108.816404 -279.176967) (xy 108.808461 -279.229671) (xy 108.792751 -279.280601)
			(xy 108.769625 -279.328622) (xy 108.739601 -279.372659) (xy 108.703349 -279.41173) (xy 108.661678 -279.444961)
			(xy 108.61552 -279.47161) (xy 108.565906 -279.491082) (xy 108.513944 -279.502942) (xy 108.460794 -279.506926)
			(xy 108.407644 -279.502942) (xy 108.355682 -279.491082) (xy 108.306068 -279.47161) (xy 108.25991 -279.444961)
			(xy 108.218239 -279.41173) (xy 108.181987 -279.372659) (xy 108.151963 -279.328622) (xy 108.128837 -279.280601)
			(xy 108.113127 -279.229671) (xy 108.105184 -279.176967) (xy 107.876604 -279.176967) (xy 107.868661 -279.229671)
			(xy 107.852951 -279.280601) (xy 107.829825 -279.328622) (xy 107.799801 -279.372659) (xy 107.763549 -279.41173)
			(xy 107.721878 -279.444961) (xy 107.67572 -279.47161) (xy 107.626106 -279.491082) (xy 107.574144 -279.502942)
			(xy 107.520994 -279.506926) (xy 107.467844 -279.502942) (xy 107.415882 -279.491082) (xy 107.366268 -279.47161)
			(xy 107.32011 -279.444961) (xy 107.278439 -279.41173) (xy 107.242187 -279.372659) (xy 107.212163 -279.328622)
			(xy 107.189037 -279.280601) (xy 107.173327 -279.229671) (xy 107.165384 -279.176967) (xy 106.937058 -279.176967)
			(xy 106.929115 -279.229671) (xy 106.913405 -279.280601) (xy 106.890279 -279.328622) (xy 106.860255 -279.372659)
			(xy 106.824003 -279.41173) (xy 106.782332 -279.444961) (xy 106.736174 -279.47161) (xy 106.68656 -279.491082)
			(xy 106.634598 -279.502942) (xy 106.581448 -279.506926) (xy 106.528298 -279.502942) (xy 106.476336 -279.491082)
			(xy 106.426722 -279.47161) (xy 106.380564 -279.444961) (xy 106.338893 -279.41173) (xy 106.302641 -279.372659)
			(xy 106.272617 -279.328622) (xy 106.249491 -279.280601) (xy 106.233781 -279.229671) (xy 106.225838 -279.176967)
			(xy 105.997258 -279.176967) (xy 105.989315 -279.229671) (xy 105.973605 -279.280601) (xy 105.950479 -279.328622)
			(xy 105.920455 -279.372659) (xy 105.884203 -279.41173) (xy 105.842532 -279.444961) (xy 105.796374 -279.47161)
			(xy 105.74676 -279.491082) (xy 105.694798 -279.502942) (xy 105.641648 -279.506926) (xy 105.588498 -279.502942)
			(xy 105.536536 -279.491082) (xy 105.486922 -279.47161) (xy 105.440764 -279.444961) (xy 105.399093 -279.41173)
			(xy 105.362841 -279.372659) (xy 105.332817 -279.328622) (xy 105.309691 -279.280601) (xy 105.293981 -279.229671)
			(xy 105.286038 -279.176967) (xy 105.08488 -279.176967) (xy 105.08488 -279.50668) (xy 105.085277 -279.515869)
			(xy 105.091802 -279.53305) (xy 105.09758 -279.540208) (xy 105.15092 -279.595326) (xy 105.157576 -279.600852)
			(xy 105.173549 -279.607466) (xy 105.182162 -279.60828) (xy 105.183178 -279.60828) (xy 105.209685 -279.609602)
			(xy 105.261894 -279.619122) (xy 105.312113 -279.636285) (xy 105.359228 -279.660711) (xy 105.402196 -279.691859)
			(xy 105.440066 -279.729039) (xy 105.471998 -279.771428) (xy 105.497286 -279.818086) (xy 105.515368 -279.867981)
			(xy 105.525846 -279.920007) (xy 105.528486 -279.973012) (xy 105.526717 -279.990783) (xy 105.755938 -279.990783)
			(xy 105.755938 -279.937485) (xy 105.763881 -279.884781) (xy 105.779591 -279.833851) (xy 105.802717 -279.78583)
			(xy 105.832741 -279.741793) (xy 105.868993 -279.702722) (xy 105.910664 -279.669491) (xy 105.956822 -279.642842)
			(xy 106.006436 -279.62337) (xy 106.058398 -279.61151) (xy 106.111548 -279.607527) (xy 106.164698 -279.61151)
			(xy 106.21666 -279.62337) (xy 106.266274 -279.642842) (xy 106.312432 -279.669491) (xy 106.354103 -279.702722)
			(xy 106.390355 -279.741793) (xy 106.420379 -279.78583) (xy 106.443505 -279.833851) (xy 106.459215 -279.884781)
			(xy 106.467158 -279.937485) (xy 106.467656 -279.964134) (xy 106.467158 -279.990783) (xy 106.695738 -279.990783)
			(xy 106.695738 -279.937485) (xy 106.703681 -279.884781) (xy 106.719391 -279.833851) (xy 106.742517 -279.78583)
			(xy 106.772541 -279.741793) (xy 106.808793 -279.702722) (xy 106.850464 -279.669491) (xy 106.896622 -279.642842)
			(xy 106.946236 -279.62337) (xy 106.998198 -279.61151) (xy 107.051348 -279.607527) (xy 107.104498 -279.61151)
			(xy 107.15646 -279.62337) (xy 107.206074 -279.642842) (xy 107.252232 -279.669491) (xy 107.293903 -279.702722)
			(xy 107.330155 -279.741793) (xy 107.360179 -279.78583) (xy 107.383305 -279.833851) (xy 107.399015 -279.884781)
			(xy 107.406958 -279.937485) (xy 107.407456 -279.964134) (xy 107.406958 -279.990783) (xy 107.635284 -279.990783)
			(xy 107.635284 -279.937485) (xy 107.643227 -279.884781) (xy 107.658937 -279.833851) (xy 107.682063 -279.78583)
			(xy 107.712087 -279.741793) (xy 107.748339 -279.702722) (xy 107.79001 -279.669491) (xy 107.836168 -279.642842)
			(xy 107.885782 -279.62337) (xy 107.937744 -279.61151) (xy 107.990894 -279.607527) (xy 108.044044 -279.61151)
			(xy 108.096006 -279.62337) (xy 108.14562 -279.642842) (xy 108.191778 -279.669491) (xy 108.233449 -279.702722)
			(xy 108.269701 -279.741793) (xy 108.299725 -279.78583) (xy 108.322851 -279.833851) (xy 108.338561 -279.884781)
			(xy 108.346504 -279.937485) (xy 108.347002 -279.964134) (xy 108.346504 -279.990783) (xy 113.274084 -279.990783)
			(xy 113.274084 -279.937485) (xy 113.282027 -279.884781) (xy 113.297737 -279.833851) (xy 113.320863 -279.78583)
			(xy 113.350887 -279.741793) (xy 113.387139 -279.702722) (xy 113.42881 -279.669491) (xy 113.474968 -279.642842)
			(xy 113.524582 -279.62337) (xy 113.576544 -279.61151) (xy 113.629694 -279.607527) (xy 113.682844 -279.61151)
			(xy 113.734806 -279.62337) (xy 113.78442 -279.642842) (xy 113.830578 -279.669491) (xy 113.872249 -279.702722)
			(xy 113.908501 -279.741793) (xy 113.938525 -279.78583) (xy 113.961651 -279.833851) (xy 113.977361 -279.884781)
			(xy 113.985304 -279.937485) (xy 113.985802 -279.964134) (xy 113.985304 -279.990783) (xy 116.093738 -279.990783)
			(xy 116.093738 -279.937485) (xy 116.101681 -279.884781) (xy 116.117391 -279.833851) (xy 116.140517 -279.78583)
			(xy 116.170541 -279.741793) (xy 116.206793 -279.702722) (xy 116.248464 -279.669491) (xy 116.294622 -279.642842)
			(xy 116.344236 -279.62337) (xy 116.396198 -279.61151) (xy 116.449348 -279.607527) (xy 116.502498 -279.61151)
			(xy 116.55446 -279.62337) (xy 116.604074 -279.642842) (xy 116.650232 -279.669491) (xy 116.691903 -279.702722)
			(xy 116.728155 -279.741793) (xy 116.758179 -279.78583) (xy 116.781305 -279.833851) (xy 116.797015 -279.884781)
			(xy 116.804958 -279.937485) (xy 116.805456 -279.964134) (xy 116.804958 -279.990783) (xy 117.033538 -279.990783)
			(xy 117.033538 -279.937485) (xy 117.041481 -279.884781) (xy 117.057191 -279.833851) (xy 117.080317 -279.78583)
			(xy 117.110341 -279.741793) (xy 117.146593 -279.702722) (xy 117.188264 -279.669491) (xy 117.234422 -279.642842)
			(xy 117.284036 -279.62337) (xy 117.335998 -279.61151) (xy 117.389148 -279.607527) (xy 117.442298 -279.61151)
			(xy 117.49426 -279.62337) (xy 117.543874 -279.642842) (xy 117.590032 -279.669491) (xy 117.631703 -279.702722)
			(xy 117.667955 -279.741793) (xy 117.697979 -279.78583) (xy 117.721105 -279.833851) (xy 117.736815 -279.884781)
			(xy 117.744758 -279.937485) (xy 117.745256 -279.964134) (xy 117.744758 -279.990783) (xy 117.973084 -279.990783)
			(xy 117.973084 -279.937485) (xy 117.981027 -279.884781) (xy 117.996737 -279.833851) (xy 118.019863 -279.78583)
			(xy 118.049887 -279.741793) (xy 118.086139 -279.702722) (xy 118.12781 -279.669491) (xy 118.173968 -279.642842)
			(xy 118.223582 -279.62337) (xy 118.275544 -279.61151) (xy 118.328694 -279.607527) (xy 118.381844 -279.61151)
			(xy 118.433806 -279.62337) (xy 118.48342 -279.642842) (xy 118.529578 -279.669491) (xy 118.571249 -279.702722)
			(xy 118.607501 -279.741793) (xy 118.637525 -279.78583) (xy 118.660651 -279.833851) (xy 118.676361 -279.884781)
			(xy 118.684304 -279.937485) (xy 118.684802 -279.964134) (xy 118.684304 -279.990783) (xy 118.913138 -279.990783)
			(xy 118.913138 -279.937485) (xy 118.921081 -279.884781) (xy 118.936791 -279.833851) (xy 118.959917 -279.78583)
			(xy 118.989941 -279.741793) (xy 119.026193 -279.702722) (xy 119.067864 -279.669491) (xy 119.114022 -279.642842)
			(xy 119.163636 -279.62337) (xy 119.215598 -279.61151) (xy 119.268748 -279.607527) (xy 119.321898 -279.61151)
			(xy 119.37386 -279.62337) (xy 119.423474 -279.642842) (xy 119.469632 -279.669491) (xy 119.511303 -279.702722)
			(xy 119.547555 -279.741793) (xy 119.577579 -279.78583) (xy 119.600705 -279.833851) (xy 119.616415 -279.884781)
			(xy 119.624358 -279.937485) (xy 119.624856 -279.964134) (xy 119.624358 -279.990783) (xy 119.852938 -279.990783)
			(xy 119.852938 -279.937485) (xy 119.860881 -279.884781) (xy 119.876591 -279.833851) (xy 119.899717 -279.78583)
			(xy 119.929741 -279.741793) (xy 119.965993 -279.702722) (xy 120.007664 -279.669491) (xy 120.053822 -279.642842)
			(xy 120.103436 -279.62337) (xy 120.155398 -279.61151) (xy 120.208548 -279.607527) (xy 120.261698 -279.61151)
			(xy 120.31366 -279.62337) (xy 120.363274 -279.642842) (xy 120.409432 -279.669491) (xy 120.451103 -279.702722)
			(xy 120.487355 -279.741793) (xy 120.517379 -279.78583) (xy 120.540505 -279.833851) (xy 120.556215 -279.884781)
			(xy 120.564158 -279.937485) (xy 120.564656 -279.964134) (xy 120.564158 -279.990783) (xy 120.792738 -279.990783)
			(xy 120.792738 -279.937485) (xy 120.800681 -279.884781) (xy 120.816391 -279.833851) (xy 120.839517 -279.78583)
			(xy 120.869541 -279.741793) (xy 120.905793 -279.702722) (xy 120.947464 -279.669491) (xy 120.993622 -279.642842)
			(xy 121.043236 -279.62337) (xy 121.095198 -279.61151) (xy 121.148348 -279.607527) (xy 121.201498 -279.61151)
			(xy 121.25346 -279.62337) (xy 121.303074 -279.642842) (xy 121.349232 -279.669491) (xy 121.390903 -279.702722)
			(xy 121.427155 -279.741793) (xy 121.457179 -279.78583) (xy 121.480305 -279.833851) (xy 121.496015 -279.884781)
			(xy 121.503958 -279.937485) (xy 121.504456 -279.964134) (xy 121.503958 -279.990783) (xy 121.732538 -279.990783)
			(xy 121.732538 -279.937485) (xy 121.740481 -279.884781) (xy 121.756191 -279.833851) (xy 121.779317 -279.78583)
			(xy 121.809341 -279.741793) (xy 121.845593 -279.702722) (xy 121.887264 -279.669491) (xy 121.933422 -279.642842)
			(xy 121.983036 -279.62337) (xy 122.034998 -279.61151) (xy 122.088148 -279.607527) (xy 122.141298 -279.61151)
			(xy 122.19326 -279.62337) (xy 122.242874 -279.642842) (xy 122.289032 -279.669491) (xy 122.330703 -279.702722)
			(xy 122.366955 -279.741793) (xy 122.396979 -279.78583) (xy 122.420105 -279.833851) (xy 122.435815 -279.884781)
			(xy 122.443758 -279.937485) (xy 122.444256 -279.964134) (xy 122.443758 -279.990783) (xy 122.672338 -279.990783)
			(xy 122.672338 -279.937485) (xy 122.680281 -279.884781) (xy 122.695991 -279.833851) (xy 122.719117 -279.78583)
			(xy 122.749141 -279.741793) (xy 122.785393 -279.702722) (xy 122.827064 -279.669491) (xy 122.873222 -279.642842)
			(xy 122.922836 -279.62337) (xy 122.974798 -279.61151) (xy 123.027948 -279.607527) (xy 123.081098 -279.61151)
			(xy 123.13306 -279.62337) (xy 123.182674 -279.642842) (xy 123.228832 -279.669491) (xy 123.270503 -279.702722)
			(xy 123.306755 -279.741793) (xy 123.336779 -279.78583) (xy 123.359905 -279.833851) (xy 123.375615 -279.884781)
			(xy 123.383558 -279.937485) (xy 123.384056 -279.964134) (xy 123.383558 -279.990783) (xy 123.611884 -279.990783)
			(xy 123.611884 -279.937485) (xy 123.619827 -279.884781) (xy 123.635537 -279.833851) (xy 123.658663 -279.78583)
			(xy 123.688687 -279.741793) (xy 123.724939 -279.702722) (xy 123.76661 -279.669491) (xy 123.812768 -279.642842)
			(xy 123.862382 -279.62337) (xy 123.914344 -279.61151) (xy 123.967494 -279.607527) (xy 124.020644 -279.61151)
			(xy 124.072606 -279.62337) (xy 124.12222 -279.642842) (xy 124.168378 -279.669491) (xy 124.210049 -279.702722)
			(xy 124.246301 -279.741793) (xy 124.276325 -279.78583) (xy 124.299451 -279.833851) (xy 124.315161 -279.884781)
			(xy 124.323104 -279.937485) (xy 124.323602 -279.964134) (xy 124.323104 -279.990783) (xy 124.551938 -279.990783)
			(xy 124.551938 -279.937485) (xy 124.559881 -279.884781) (xy 124.575591 -279.833851) (xy 124.598717 -279.78583)
			(xy 124.628741 -279.741793) (xy 124.664993 -279.702722) (xy 124.706664 -279.669491) (xy 124.752822 -279.642842)
			(xy 124.802436 -279.62337) (xy 124.854398 -279.61151) (xy 124.907548 -279.607527) (xy 124.960698 -279.61151)
			(xy 125.01266 -279.62337) (xy 125.062274 -279.642842) (xy 125.108432 -279.669491) (xy 125.150103 -279.702722)
			(xy 125.186355 -279.741793) (xy 125.216379 -279.78583) (xy 125.239505 -279.833851) (xy 125.255215 -279.884781)
			(xy 125.263158 -279.937485) (xy 125.263656 -279.964134) (xy 125.263158 -279.990783) (xy 125.491738 -279.990783)
			(xy 125.491738 -279.937485) (xy 125.499681 -279.884781) (xy 125.515391 -279.833851) (xy 125.538517 -279.78583)
			(xy 125.568541 -279.741793) (xy 125.604793 -279.702722) (xy 125.646464 -279.669491) (xy 125.692622 -279.642842)
			(xy 125.742236 -279.62337) (xy 125.794198 -279.61151) (xy 125.847348 -279.607527) (xy 125.900498 -279.61151)
			(xy 125.95246 -279.62337) (xy 126.002074 -279.642842) (xy 126.048232 -279.669491) (xy 126.089903 -279.702722)
			(xy 126.126155 -279.741793) (xy 126.156179 -279.78583) (xy 126.179305 -279.833851) (xy 126.195015 -279.884781)
			(xy 126.202958 -279.937485) (xy 126.203456 -279.964134) (xy 126.202958 -279.990783) (xy 126.431284 -279.990783)
			(xy 126.431284 -279.937485) (xy 126.439227 -279.884781) (xy 126.454937 -279.833851) (xy 126.478063 -279.78583)
			(xy 126.508087 -279.741793) (xy 126.544339 -279.702722) (xy 126.58601 -279.669491) (xy 126.632168 -279.642842)
			(xy 126.681782 -279.62337) (xy 126.733744 -279.61151) (xy 126.786894 -279.607527) (xy 126.840044 -279.61151)
			(xy 126.892006 -279.62337) (xy 126.94162 -279.642842) (xy 126.987778 -279.669491) (xy 127.029449 -279.702722)
			(xy 127.065701 -279.741793) (xy 127.095725 -279.78583) (xy 127.118851 -279.833851) (xy 127.134561 -279.884781)
			(xy 127.142504 -279.937485) (xy 127.143002 -279.964134) (xy 127.142504 -279.990783) (xy 127.371338 -279.990783)
			(xy 127.371338 -279.937485) (xy 127.379281 -279.884781) (xy 127.394991 -279.833851) (xy 127.418117 -279.78583)
			(xy 127.448141 -279.741793) (xy 127.484393 -279.702722) (xy 127.526064 -279.669491) (xy 127.572222 -279.642842)
			(xy 127.621836 -279.62337) (xy 127.673798 -279.61151) (xy 127.726948 -279.607527) (xy 127.780098 -279.61151)
			(xy 127.83206 -279.62337) (xy 127.881674 -279.642842) (xy 127.927832 -279.669491) (xy 127.969503 -279.702722)
			(xy 128.005755 -279.741793) (xy 128.035779 -279.78583) (xy 128.058905 -279.833851) (xy 128.074615 -279.884781)
			(xy 128.082558 -279.937485) (xy 128.083056 -279.964134) (xy 128.082563 -279.990529) (xy 128.310884 -279.990529)
			(xy 128.310884 -279.937231) (xy 128.318827 -279.884527) (xy 128.334537 -279.833597) (xy 128.357663 -279.785576)
			(xy 128.387687 -279.741539) (xy 128.423939 -279.702468) (xy 128.46561 -279.669237) (xy 128.511768 -279.642588)
			(xy 128.561382 -279.623116) (xy 128.613344 -279.611256) (xy 128.666494 -279.607273) (xy 128.719644 -279.611256)
			(xy 128.771606 -279.623116) (xy 128.82122 -279.642588) (xy 128.867378 -279.669237) (xy 128.909049 -279.702468)
			(xy 128.945301 -279.741539) (xy 128.975325 -279.785576) (xy 128.998451 -279.833597) (xy 129.014161 -279.884527)
			(xy 129.022104 -279.937231) (xy 129.022602 -279.96388) (xy 129.022104 -279.990529) (xy 129.022066 -279.990783)
			(xy 129.250938 -279.990783) (xy 129.250938 -279.937485) (xy 129.258881 -279.884781) (xy 129.274591 -279.833851)
			(xy 129.297717 -279.78583) (xy 129.327741 -279.741793) (xy 129.363993 -279.702722) (xy 129.405664 -279.669491)
			(xy 129.451822 -279.642842) (xy 129.501436 -279.62337) (xy 129.553398 -279.61151) (xy 129.606548 -279.607527)
			(xy 129.659698 -279.61151) (xy 129.71166 -279.62337) (xy 129.761274 -279.642842) (xy 129.807432 -279.669491)
			(xy 129.849103 -279.702722) (xy 129.885355 -279.741793) (xy 129.915379 -279.78583) (xy 129.938505 -279.833851)
			(xy 129.954215 -279.884781) (xy 129.962158 -279.937485) (xy 129.962656 -279.964134) (xy 129.962158 -279.990783)
			(xy 130.190738 -279.990783) (xy 130.190738 -279.937485) (xy 130.198681 -279.884781) (xy 130.214391 -279.833851)
			(xy 130.237517 -279.78583) (xy 130.267541 -279.741793) (xy 130.303793 -279.702722) (xy 130.345464 -279.669491)
			(xy 130.391622 -279.642842) (xy 130.441236 -279.62337) (xy 130.493198 -279.61151) (xy 130.546348 -279.607527)
			(xy 130.599498 -279.61151) (xy 130.65146 -279.62337) (xy 130.701074 -279.642842) (xy 130.747232 -279.669491)
			(xy 130.788903 -279.702722) (xy 130.825155 -279.741793) (xy 130.855179 -279.78583) (xy 130.878305 -279.833851)
			(xy 130.894015 -279.884781) (xy 130.901958 -279.937485) (xy 130.902456 -279.964134) (xy 130.901976 -279.989842)
			(xy 131.1595 -279.989842) (xy 131.1595 -279.938426) (xy 131.167543 -279.887644) (xy 131.183431 -279.838745)
			(xy 131.206774 -279.792933) (xy 131.236995 -279.751337) (xy 131.273351 -279.714981) (xy 131.314947 -279.68476)
			(xy 131.360759 -279.661417) (xy 131.409658 -279.645529) (xy 131.46044 -279.637486) (xy 131.511856 -279.637486)
			(xy 131.562638 -279.645529) (xy 131.611537 -279.661417) (xy 131.657349 -279.68476) (xy 131.698945 -279.714981)
			(xy 131.735301 -279.751337) (xy 131.765522 -279.792933) (xy 131.788865 -279.838745) (xy 131.804753 -279.887644)
			(xy 131.812796 -279.938426) (xy 131.8133 -279.964134) (xy 131.812796 -279.989842) (xy 131.812647 -279.990783)
			(xy 132.070084 -279.990783) (xy 132.070084 -279.937485) (xy 132.078027 -279.884781) (xy 132.093737 -279.833851)
			(xy 132.116863 -279.78583) (xy 132.146887 -279.741793) (xy 132.183139 -279.702722) (xy 132.22481 -279.669491)
			(xy 132.270968 -279.642842) (xy 132.320582 -279.62337) (xy 132.372544 -279.61151) (xy 132.425694 -279.607527)
			(xy 132.478844 -279.61151) (xy 132.530806 -279.62337) (xy 132.58042 -279.642842) (xy 132.626578 -279.669491)
			(xy 132.668249 -279.702722) (xy 132.704501 -279.741793) (xy 132.734525 -279.78583) (xy 132.757651 -279.833851)
			(xy 132.773361 -279.884781) (xy 132.781304 -279.937485) (xy 132.781802 -279.964134) (xy 132.781304 -279.990783)
			(xy 133.010138 -279.990783) (xy 133.010138 -279.937485) (xy 133.018081 -279.884781) (xy 133.033791 -279.833851)
			(xy 133.056917 -279.78583) (xy 133.086941 -279.741793) (xy 133.123193 -279.702722) (xy 133.164864 -279.669491)
			(xy 133.211022 -279.642842) (xy 133.260636 -279.62337) (xy 133.312598 -279.61151) (xy 133.365748 -279.607527)
			(xy 133.418898 -279.61151) (xy 133.47086 -279.62337) (xy 133.520474 -279.642842) (xy 133.566632 -279.669491)
			(xy 133.608303 -279.702722) (xy 133.644555 -279.741793) (xy 133.674579 -279.78583) (xy 133.697705 -279.833851)
			(xy 133.713415 -279.884781) (xy 133.721358 -279.937485) (xy 133.721856 -279.964134) (xy 133.721358 -279.990783)
			(xy 133.949938 -279.990783) (xy 133.949938 -279.937485) (xy 133.957881 -279.884781) (xy 133.973591 -279.833851)
			(xy 133.996717 -279.78583) (xy 134.026741 -279.741793) (xy 134.062993 -279.702722) (xy 134.104664 -279.669491)
			(xy 134.150822 -279.642842) (xy 134.200436 -279.62337) (xy 134.252398 -279.61151) (xy 134.305548 -279.607527)
			(xy 134.358698 -279.61151) (xy 134.41066 -279.62337) (xy 134.460274 -279.642842) (xy 134.506432 -279.669491)
			(xy 134.548103 -279.702722) (xy 134.584355 -279.741793) (xy 134.614379 -279.78583) (xy 134.637505 -279.833851)
			(xy 134.653215 -279.884781) (xy 134.661158 -279.937485) (xy 134.661656 -279.964134) (xy 134.661158 -279.990783)
			(xy 134.88923 -279.990783) (xy 134.88923 -279.937485) (xy 134.897173 -279.884781) (xy 134.912883 -279.833851)
			(xy 134.936009 -279.78583) (xy 134.966033 -279.741793) (xy 135.002285 -279.702722) (xy 135.043956 -279.669491)
			(xy 135.090114 -279.642842) (xy 135.139728 -279.62337) (xy 135.19169 -279.61151) (xy 135.24484 -279.607527)
			(xy 135.29799 -279.61151) (xy 135.349952 -279.62337) (xy 135.399566 -279.642842) (xy 135.445724 -279.669491)
			(xy 135.487395 -279.702722) (xy 135.523647 -279.741793) (xy 135.553671 -279.78583) (xy 135.576797 -279.833851)
			(xy 135.592507 -279.884781) (xy 135.60045 -279.937485) (xy 135.600948 -279.964134) (xy 135.60045 -279.990783)
			(xy 135.829284 -279.990783) (xy 135.829284 -279.937485) (xy 135.837227 -279.884781) (xy 135.852937 -279.833851)
			(xy 135.876063 -279.78583) (xy 135.906087 -279.741793) (xy 135.942339 -279.702722) (xy 135.98401 -279.669491)
			(xy 136.030168 -279.642842) (xy 136.079782 -279.62337) (xy 136.131744 -279.61151) (xy 136.184894 -279.607527)
			(xy 136.238044 -279.61151) (xy 136.290006 -279.62337) (xy 136.33962 -279.642842) (xy 136.385778 -279.669491)
			(xy 136.427449 -279.702722) (xy 136.463701 -279.741793) (xy 136.493725 -279.78583) (xy 136.516851 -279.833851)
			(xy 136.532561 -279.884781) (xy 136.540504 -279.937485) (xy 136.541002 -279.964134) (xy 136.540504 -279.990783)
			(xy 136.769084 -279.990783) (xy 136.769084 -279.937485) (xy 136.777027 -279.884781) (xy 136.792737 -279.833851)
			(xy 136.815863 -279.78583) (xy 136.845887 -279.741793) (xy 136.882139 -279.702722) (xy 136.92381 -279.669491)
			(xy 136.969968 -279.642842) (xy 137.019582 -279.62337) (xy 137.071544 -279.61151) (xy 137.124694 -279.607527)
			(xy 137.177844 -279.61151) (xy 137.229806 -279.62337) (xy 137.27942 -279.642842) (xy 137.325578 -279.669491)
			(xy 137.367249 -279.702722) (xy 137.403501 -279.741793) (xy 137.433525 -279.78583) (xy 137.456651 -279.833851)
			(xy 137.472361 -279.884781) (xy 137.480304 -279.937485) (xy 137.480802 -279.964134) (xy 137.480304 -279.990783)
			(xy 137.472361 -280.043487) (xy 137.456651 -280.094417) (xy 137.433525 -280.142438) (xy 137.403501 -280.186475)
			(xy 137.367249 -280.225546) (xy 137.325578 -280.258777) (xy 137.27942 -280.285426) (xy 137.229806 -280.304898)
			(xy 137.177844 -280.316758) (xy 137.124694 -280.320742) (xy 137.071544 -280.316758) (xy 137.019582 -280.304898)
			(xy 136.969968 -280.285426) (xy 136.92381 -280.258777) (xy 136.882139 -280.225546) (xy 136.845887 -280.186475)
			(xy 136.815863 -280.142438) (xy 136.792737 -280.094417) (xy 136.777027 -280.043487) (xy 136.769084 -279.990783)
			(xy 136.540504 -279.990783) (xy 136.532561 -280.043487) (xy 136.516851 -280.094417) (xy 136.493725 -280.142438)
			(xy 136.463701 -280.186475) (xy 136.427449 -280.225546) (xy 136.385778 -280.258777) (xy 136.33962 -280.285426)
			(xy 136.290006 -280.304898) (xy 136.238044 -280.316758) (xy 136.184894 -280.320742) (xy 136.131744 -280.316758)
			(xy 136.079782 -280.304898) (xy 136.030168 -280.285426) (xy 135.98401 -280.258777) (xy 135.942339 -280.225546)
			(xy 135.906087 -280.186475) (xy 135.876063 -280.142438) (xy 135.852937 -280.094417) (xy 135.837227 -280.043487)
			(xy 135.829284 -279.990783) (xy 135.60045 -279.990783) (xy 135.592507 -280.043487) (xy 135.576797 -280.094417)
			(xy 135.553671 -280.142438) (xy 135.523647 -280.186475) (xy 135.487395 -280.225546) (xy 135.445724 -280.258777)
			(xy 135.399566 -280.285426) (xy 135.349952 -280.304898) (xy 135.29799 -280.316758) (xy 135.24484 -280.320742)
			(xy 135.19169 -280.316758) (xy 135.139728 -280.304898) (xy 135.090114 -280.285426) (xy 135.043956 -280.258777)
			(xy 135.002285 -280.225546) (xy 134.966033 -280.186475) (xy 134.936009 -280.142438) (xy 134.912883 -280.094417)
			(xy 134.897173 -280.043487) (xy 134.88923 -279.990783) (xy 134.661158 -279.990783) (xy 134.653215 -280.043487)
			(xy 134.637505 -280.094417) (xy 134.614379 -280.142438) (xy 134.584355 -280.186475) (xy 134.548103 -280.225546)
			(xy 134.506432 -280.258777) (xy 134.460274 -280.285426) (xy 134.41066 -280.304898) (xy 134.358698 -280.316758)
			(xy 134.305548 -280.320742) (xy 134.252398 -280.316758) (xy 134.200436 -280.304898) (xy 134.150822 -280.285426)
			(xy 134.104664 -280.258777) (xy 134.062993 -280.225546) (xy 134.026741 -280.186475) (xy 133.996717 -280.142438)
			(xy 133.973591 -280.094417) (xy 133.957881 -280.043487) (xy 133.949938 -279.990783) (xy 133.721358 -279.990783)
			(xy 133.713415 -280.043487) (xy 133.697705 -280.094417) (xy 133.674579 -280.142438) (xy 133.644555 -280.186475)
			(xy 133.608303 -280.225546) (xy 133.566632 -280.258777) (xy 133.520474 -280.285426) (xy 133.47086 -280.304898)
			(xy 133.418898 -280.316758) (xy 133.365748 -280.320742) (xy 133.312598 -280.316758) (xy 133.260636 -280.304898)
			(xy 133.211022 -280.285426) (xy 133.164864 -280.258777) (xy 133.123193 -280.225546) (xy 133.086941 -280.186475)
			(xy 133.056917 -280.142438) (xy 133.033791 -280.094417) (xy 133.018081 -280.043487) (xy 133.010138 -279.990783)
			(xy 132.781304 -279.990783) (xy 132.773361 -280.043487) (xy 132.757651 -280.094417) (xy 132.734525 -280.142438)
			(xy 132.704501 -280.186475) (xy 132.668249 -280.225546) (xy 132.626578 -280.258777) (xy 132.58042 -280.285426)
			(xy 132.530806 -280.304898) (xy 132.478844 -280.316758) (xy 132.425694 -280.320742) (xy 132.372544 -280.316758)
			(xy 132.320582 -280.304898) (xy 132.270968 -280.285426) (xy 132.22481 -280.258777) (xy 132.183139 -280.225546)
			(xy 132.146887 -280.186475) (xy 132.116863 -280.142438) (xy 132.093737 -280.094417) (xy 132.078027 -280.043487)
			(xy 132.070084 -279.990783) (xy 131.812647 -279.990783) (xy 131.804753 -280.040624) (xy 131.788865 -280.089523)
			(xy 131.765522 -280.135335) (xy 131.735301 -280.176931) (xy 131.698945 -280.213287) (xy 131.657349 -280.243508)
			(xy 131.611537 -280.266851) (xy 131.562638 -280.282739) (xy 131.511856 -280.290782) (xy 131.46044 -280.290782)
			(xy 131.409658 -280.282739) (xy 131.360759 -280.266851) (xy 131.314947 -280.243508) (xy 131.273351 -280.213287)
			(xy 131.236995 -280.176931) (xy 131.206774 -280.135335) (xy 131.183431 -280.089523) (xy 131.167543 -280.040624)
			(xy 131.1595 -279.989842) (xy 130.901976 -279.989842) (xy 130.901958 -279.990783) (xy 130.894015 -280.043487)
			(xy 130.878305 -280.094417) (xy 130.855179 -280.142438) (xy 130.825155 -280.186475) (xy 130.788903 -280.225546)
			(xy 130.747232 -280.258777) (xy 130.701074 -280.285426) (xy 130.65146 -280.304898) (xy 130.599498 -280.316758)
			(xy 130.546348 -280.320742) (xy 130.493198 -280.316758) (xy 130.441236 -280.304898) (xy 130.391622 -280.285426)
			(xy 130.345464 -280.258777) (xy 130.303793 -280.225546) (xy 130.267541 -280.186475) (xy 130.237517 -280.142438)
			(xy 130.214391 -280.094417) (xy 130.198681 -280.043487) (xy 130.190738 -279.990783) (xy 129.962158 -279.990783)
			(xy 129.954215 -280.043487) (xy 129.938505 -280.094417) (xy 129.915379 -280.142438) (xy 129.885355 -280.186475)
			(xy 129.849103 -280.225546) (xy 129.807432 -280.258777) (xy 129.761274 -280.285426) (xy 129.71166 -280.304898)
			(xy 129.659698 -280.316758) (xy 129.606548 -280.320742) (xy 129.553398 -280.316758) (xy 129.501436 -280.304898)
			(xy 129.451822 -280.285426) (xy 129.405664 -280.258777) (xy 129.363993 -280.225546) (xy 129.327741 -280.186475)
			(xy 129.297717 -280.142438) (xy 129.274591 -280.094417) (xy 129.258881 -280.043487) (xy 129.250938 -279.990783)
			(xy 129.022066 -279.990783) (xy 129.014161 -280.043233) (xy 128.998451 -280.094163) (xy 128.975325 -280.142184)
			(xy 128.945301 -280.186221) (xy 128.909049 -280.225292) (xy 128.867378 -280.258523) (xy 128.82122 -280.285172)
			(xy 128.771606 -280.304644) (xy 128.719644 -280.316504) (xy 128.666494 -280.320488) (xy 128.613344 -280.316504)
			(xy 128.561382 -280.304644) (xy 128.511768 -280.285172) (xy 128.46561 -280.258523) (xy 128.423939 -280.225292)
			(xy 128.387687 -280.186221) (xy 128.357663 -280.142184) (xy 128.334537 -280.094163) (xy 128.318827 -280.043233)
			(xy 128.310884 -279.990529) (xy 128.082563 -279.990529) (xy 128.082558 -279.990783) (xy 128.074615 -280.043487)
			(xy 128.058905 -280.094417) (xy 128.035779 -280.142438) (xy 128.005755 -280.186475) (xy 127.969503 -280.225546)
			(xy 127.927832 -280.258777) (xy 127.881674 -280.285426) (xy 127.83206 -280.304898) (xy 127.780098 -280.316758)
			(xy 127.726948 -280.320742) (xy 127.673798 -280.316758) (xy 127.621836 -280.304898) (xy 127.572222 -280.285426)
			(xy 127.526064 -280.258777) (xy 127.484393 -280.225546) (xy 127.448141 -280.186475) (xy 127.418117 -280.142438)
			(xy 127.394991 -280.094417) (xy 127.379281 -280.043487) (xy 127.371338 -279.990783) (xy 127.142504 -279.990783)
			(xy 127.134561 -280.043487) (xy 127.118851 -280.094417) (xy 127.095725 -280.142438) (xy 127.065701 -280.186475)
			(xy 127.029449 -280.225546) (xy 126.987778 -280.258777) (xy 126.94162 -280.285426) (xy 126.892006 -280.304898)
			(xy 126.840044 -280.316758) (xy 126.786894 -280.320742) (xy 126.733744 -280.316758) (xy 126.681782 -280.304898)
			(xy 126.632168 -280.285426) (xy 126.58601 -280.258777) (xy 126.544339 -280.225546) (xy 126.508087 -280.186475)
			(xy 126.478063 -280.142438) (xy 126.454937 -280.094417) (xy 126.439227 -280.043487) (xy 126.431284 -279.990783)
			(xy 126.202958 -279.990783) (xy 126.195015 -280.043487) (xy 126.179305 -280.094417) (xy 126.156179 -280.142438)
			(xy 126.126155 -280.186475) (xy 126.089903 -280.225546) (xy 126.048232 -280.258777) (xy 126.002074 -280.285426)
			(xy 125.95246 -280.304898) (xy 125.900498 -280.316758) (xy 125.847348 -280.320742) (xy 125.794198 -280.316758)
			(xy 125.742236 -280.304898) (xy 125.692622 -280.285426) (xy 125.646464 -280.258777) (xy 125.604793 -280.225546)
			(xy 125.568541 -280.186475) (xy 125.538517 -280.142438) (xy 125.515391 -280.094417) (xy 125.499681 -280.043487)
			(xy 125.491738 -279.990783) (xy 125.263158 -279.990783) (xy 125.255215 -280.043487) (xy 125.239505 -280.094417)
			(xy 125.216379 -280.142438) (xy 125.186355 -280.186475) (xy 125.150103 -280.225546) (xy 125.108432 -280.258777)
			(xy 125.062274 -280.285426) (xy 125.01266 -280.304898) (xy 124.960698 -280.316758) (xy 124.907548 -280.320742)
			(xy 124.854398 -280.316758) (xy 124.802436 -280.304898) (xy 124.752822 -280.285426) (xy 124.706664 -280.258777)
			(xy 124.664993 -280.225546) (xy 124.628741 -280.186475) (xy 124.598717 -280.142438) (xy 124.575591 -280.094417)
			(xy 124.559881 -280.043487) (xy 124.551938 -279.990783) (xy 124.323104 -279.990783) (xy 124.315161 -280.043487)
			(xy 124.299451 -280.094417) (xy 124.276325 -280.142438) (xy 124.246301 -280.186475) (xy 124.210049 -280.225546)
			(xy 124.168378 -280.258777) (xy 124.12222 -280.285426) (xy 124.072606 -280.304898) (xy 124.020644 -280.316758)
			(xy 123.967494 -280.320742) (xy 123.914344 -280.316758) (xy 123.862382 -280.304898) (xy 123.812768 -280.285426)
			(xy 123.76661 -280.258777) (xy 123.724939 -280.225546) (xy 123.688687 -280.186475) (xy 123.658663 -280.142438)
			(xy 123.635537 -280.094417) (xy 123.619827 -280.043487) (xy 123.611884 -279.990783) (xy 123.383558 -279.990783)
			(xy 123.375615 -280.043487) (xy 123.359905 -280.094417) (xy 123.336779 -280.142438) (xy 123.306755 -280.186475)
			(xy 123.270503 -280.225546) (xy 123.228832 -280.258777) (xy 123.182674 -280.285426) (xy 123.13306 -280.304898)
			(xy 123.081098 -280.316758) (xy 123.027948 -280.320742) (xy 122.974798 -280.316758) (xy 122.922836 -280.304898)
			(xy 122.873222 -280.285426) (xy 122.827064 -280.258777) (xy 122.785393 -280.225546) (xy 122.749141 -280.186475)
			(xy 122.719117 -280.142438) (xy 122.695991 -280.094417) (xy 122.680281 -280.043487) (xy 122.672338 -279.990783)
			(xy 122.443758 -279.990783) (xy 122.435815 -280.043487) (xy 122.420105 -280.094417) (xy 122.396979 -280.142438)
			(xy 122.366955 -280.186475) (xy 122.330703 -280.225546) (xy 122.289032 -280.258777) (xy 122.242874 -280.285426)
			(xy 122.19326 -280.304898) (xy 122.141298 -280.316758) (xy 122.088148 -280.320742) (xy 122.034998 -280.316758)
			(xy 121.983036 -280.304898) (xy 121.933422 -280.285426) (xy 121.887264 -280.258777) (xy 121.845593 -280.225546)
			(xy 121.809341 -280.186475) (xy 121.779317 -280.142438) (xy 121.756191 -280.094417) (xy 121.740481 -280.043487)
			(xy 121.732538 -279.990783) (xy 121.503958 -279.990783) (xy 121.496015 -280.043487) (xy 121.480305 -280.094417)
			(xy 121.457179 -280.142438) (xy 121.427155 -280.186475) (xy 121.390903 -280.225546) (xy 121.349232 -280.258777)
			(xy 121.303074 -280.285426) (xy 121.25346 -280.304898) (xy 121.201498 -280.316758) (xy 121.148348 -280.320742)
			(xy 121.095198 -280.316758) (xy 121.043236 -280.304898) (xy 120.993622 -280.285426) (xy 120.947464 -280.258777)
			(xy 120.905793 -280.225546) (xy 120.869541 -280.186475) (xy 120.839517 -280.142438) (xy 120.816391 -280.094417)
			(xy 120.800681 -280.043487) (xy 120.792738 -279.990783) (xy 120.564158 -279.990783) (xy 120.556215 -280.043487)
			(xy 120.540505 -280.094417) (xy 120.517379 -280.142438) (xy 120.487355 -280.186475) (xy 120.451103 -280.225546)
			(xy 120.409432 -280.258777) (xy 120.363274 -280.285426) (xy 120.31366 -280.304898) (xy 120.261698 -280.316758)
			(xy 120.208548 -280.320742) (xy 120.155398 -280.316758) (xy 120.103436 -280.304898) (xy 120.053822 -280.285426)
			(xy 120.007664 -280.258777) (xy 119.965993 -280.225546) (xy 119.929741 -280.186475) (xy 119.899717 -280.142438)
			(xy 119.876591 -280.094417) (xy 119.860881 -280.043487) (xy 119.852938 -279.990783) (xy 119.624358 -279.990783)
			(xy 119.616415 -280.043487) (xy 119.600705 -280.094417) (xy 119.577579 -280.142438) (xy 119.547555 -280.186475)
			(xy 119.511303 -280.225546) (xy 119.469632 -280.258777) (xy 119.423474 -280.285426) (xy 119.37386 -280.304898)
			(xy 119.321898 -280.316758) (xy 119.268748 -280.320742) (xy 119.215598 -280.316758) (xy 119.163636 -280.304898)
			(xy 119.114022 -280.285426) (xy 119.067864 -280.258777) (xy 119.026193 -280.225546) (xy 118.989941 -280.186475)
			(xy 118.959917 -280.142438) (xy 118.936791 -280.094417) (xy 118.921081 -280.043487) (xy 118.913138 -279.990783)
			(xy 118.684304 -279.990783) (xy 118.676361 -280.043487) (xy 118.660651 -280.094417) (xy 118.637525 -280.142438)
			(xy 118.607501 -280.186475) (xy 118.571249 -280.225546) (xy 118.529578 -280.258777) (xy 118.48342 -280.285426)
			(xy 118.433806 -280.304898) (xy 118.381844 -280.316758) (xy 118.328694 -280.320742) (xy 118.275544 -280.316758)
			(xy 118.223582 -280.304898) (xy 118.173968 -280.285426) (xy 118.12781 -280.258777) (xy 118.086139 -280.225546)
			(xy 118.049887 -280.186475) (xy 118.019863 -280.142438) (xy 117.996737 -280.094417) (xy 117.981027 -280.043487)
			(xy 117.973084 -279.990783) (xy 117.744758 -279.990783) (xy 117.736815 -280.043487) (xy 117.721105 -280.094417)
			(xy 117.697979 -280.142438) (xy 117.667955 -280.186475) (xy 117.631703 -280.225546) (xy 117.590032 -280.258777)
			(xy 117.543874 -280.285426) (xy 117.49426 -280.304898) (xy 117.442298 -280.316758) (xy 117.389148 -280.320742)
			(xy 117.335998 -280.316758) (xy 117.284036 -280.304898) (xy 117.234422 -280.285426) (xy 117.188264 -280.258777)
			(xy 117.146593 -280.225546) (xy 117.110341 -280.186475) (xy 117.080317 -280.142438) (xy 117.057191 -280.094417)
			(xy 117.041481 -280.043487) (xy 117.033538 -279.990783) (xy 116.804958 -279.990783) (xy 116.797015 -280.043487)
			(xy 116.781305 -280.094417) (xy 116.758179 -280.142438) (xy 116.728155 -280.186475) (xy 116.691903 -280.225546)
			(xy 116.650232 -280.258777) (xy 116.604074 -280.285426) (xy 116.55446 -280.304898) (xy 116.502498 -280.316758)
			(xy 116.449348 -280.320742) (xy 116.396198 -280.316758) (xy 116.344236 -280.304898) (xy 116.294622 -280.285426)
			(xy 116.248464 -280.258777) (xy 116.206793 -280.225546) (xy 116.170541 -280.186475) (xy 116.140517 -280.142438)
			(xy 116.117391 -280.094417) (xy 116.101681 -280.043487) (xy 116.093738 -279.990783) (xy 113.985304 -279.990783)
			(xy 113.977361 -280.043487) (xy 113.961651 -280.094417) (xy 113.938525 -280.142438) (xy 113.908501 -280.186475)
			(xy 113.872249 -280.225546) (xy 113.830578 -280.258777) (xy 113.78442 -280.285426) (xy 113.734806 -280.304898)
			(xy 113.682844 -280.316758) (xy 113.629694 -280.320742) (xy 113.576544 -280.316758) (xy 113.524582 -280.304898)
			(xy 113.474968 -280.285426) (xy 113.42881 -280.258777) (xy 113.387139 -280.225546) (xy 113.350887 -280.186475)
			(xy 113.320863 -280.142438) (xy 113.297737 -280.094417) (xy 113.282027 -280.043487) (xy 113.274084 -279.990783)
			(xy 108.346504 -279.990783) (xy 108.338561 -280.043487) (xy 108.322851 -280.094417) (xy 108.299725 -280.142438)
			(xy 108.269701 -280.186475) (xy 108.233449 -280.225546) (xy 108.191778 -280.258777) (xy 108.14562 -280.285426)
			(xy 108.096006 -280.304898) (xy 108.044044 -280.316758) (xy 107.990894 -280.320742) (xy 107.937744 -280.316758)
			(xy 107.885782 -280.304898) (xy 107.836168 -280.285426) (xy 107.79001 -280.258777) (xy 107.748339 -280.225546)
			(xy 107.712087 -280.186475) (xy 107.682063 -280.142438) (xy 107.658937 -280.094417) (xy 107.643227 -280.043487)
			(xy 107.635284 -279.990783) (xy 107.406958 -279.990783) (xy 107.399015 -280.043487) (xy 107.383305 -280.094417)
			(xy 107.360179 -280.142438) (xy 107.330155 -280.186475) (xy 107.293903 -280.225546) (xy 107.252232 -280.258777)
			(xy 107.206074 -280.285426) (xy 107.15646 -280.304898) (xy 107.104498 -280.316758) (xy 107.051348 -280.320742)
			(xy 106.998198 -280.316758) (xy 106.946236 -280.304898) (xy 106.896622 -280.285426) (xy 106.850464 -280.258777)
			(xy 106.808793 -280.225546) (xy 106.772541 -280.186475) (xy 106.742517 -280.142438) (xy 106.719391 -280.094417)
			(xy 106.703681 -280.043487) (xy 106.695738 -279.990783) (xy 106.467158 -279.990783) (xy 106.459215 -280.043487)
			(xy 106.443505 -280.094417) (xy 106.420379 -280.142438) (xy 106.390355 -280.186475) (xy 106.354103 -280.225546)
			(xy 106.312432 -280.258777) (xy 106.266274 -280.285426) (xy 106.21666 -280.304898) (xy 106.164698 -280.316758)
			(xy 106.111548 -280.320742) (xy 106.058398 -280.316758) (xy 106.006436 -280.304898) (xy 105.956822 -280.285426)
			(xy 105.910664 -280.258777) (xy 105.868993 -280.225546) (xy 105.832741 -280.186475) (xy 105.802717 -280.142438)
			(xy 105.779591 -280.094417) (xy 105.763881 -280.043487) (xy 105.755938 -279.990783) (xy 105.526717 -279.990783)
			(xy 105.52323 -280.025821) (xy 105.510195 -280.077266) (xy 105.489669 -280.126207) (xy 105.462108 -280.171559)
			(xy 105.42812 -280.212318) (xy 105.38846 -280.247582) (xy 105.344005 -280.276569) (xy 105.29574 -280.298637)
			(xy 105.244735 -280.313298) (xy 105.218484 -280.317194) (xy 105.193846 -280.320496) (xy 105.08488 -280.508964)
			(xy 105.08488 -280.804107) (xy 105.31222 -280.804107) (xy 105.31222 -280.752293) (xy 105.320326 -280.701118)
			(xy 105.336337 -280.65184) (xy 105.359859 -280.605674) (xy 105.390314 -280.563756) (xy 105.426951 -280.527118)
			(xy 105.468869 -280.496662) (xy 105.515035 -280.473139) (xy 105.564312 -280.457127) (xy 105.615487 -280.449021)
			(xy 105.641394 -280.448512) (xy 105.666906 -280.448992) (xy 105.717321 -280.456852) (xy 105.765922 -280.472385)
			(xy 105.811551 -280.495221) (xy 105.853116 -280.524814) (xy 105.889626 -280.560457) (xy 105.9053 -280.580592)
			(xy 106.317288 -280.580592) (xy 106.332966 -280.560461) (xy 106.369475 -280.524817) (xy 106.41104 -280.495223)
			(xy 106.456667 -280.472386) (xy 106.505268 -280.456852) (xy 106.555682 -280.44899) (xy 106.581194 -280.448512)
			(xy 106.607104 -280.448985) (xy 106.658286 -280.457091) (xy 106.70757 -280.473103) (xy 106.753743 -280.496628)
			(xy 106.795666 -280.527087) (xy 106.832309 -280.563729) (xy 106.862768 -280.605652) (xy 106.886294 -280.651824)
			(xy 106.902308 -280.701108) (xy 106.910414 -280.75229) (xy 106.910414 -280.80411) (xy 106.910296 -280.804853)
			(xy 107.165384 -280.804853) (xy 107.165384 -280.751555) (xy 107.173327 -280.698851) (xy 107.189037 -280.647921)
			(xy 107.212163 -280.5999) (xy 107.242187 -280.555863) (xy 107.278439 -280.516792) (xy 107.32011 -280.483561)
			(xy 107.366268 -280.456912) (xy 107.415882 -280.43744) (xy 107.467844 -280.42558) (xy 107.520994 -280.421597)
			(xy 107.574144 -280.42558) (xy 107.626106 -280.43744) (xy 107.67572 -280.456912) (xy 107.721878 -280.483561)
			(xy 107.763549 -280.516792) (xy 107.799801 -280.555863) (xy 107.829825 -280.5999) (xy 107.852951 -280.647921)
			(xy 107.868661 -280.698851) (xy 107.876604 -280.751555) (xy 107.877102 -280.778204) (xy 107.876604 -280.804853)
			(xy 109.984784 -280.804853) (xy 109.984784 -280.751555) (xy 109.992727 -280.698851) (xy 110.008437 -280.647921)
			(xy 110.031563 -280.5999) (xy 110.061587 -280.555863) (xy 110.097839 -280.516792) (xy 110.13951 -280.483561)
			(xy 110.185668 -280.456912) (xy 110.235282 -280.43744) (xy 110.287244 -280.42558) (xy 110.340394 -280.421597)
			(xy 110.393544 -280.42558) (xy 110.445506 -280.43744) (xy 110.49512 -280.456912) (xy 110.541278 -280.483561)
			(xy 110.582949 -280.516792) (xy 110.619201 -280.555863) (xy 110.649225 -280.5999) (xy 110.672351 -280.647921)
			(xy 110.688061 -280.698851) (xy 110.696004 -280.751555) (xy 110.696502 -280.778204) (xy 110.696004 -280.804853)
			(xy 116.563638 -280.804853) (xy 116.563638 -280.751555) (xy 116.571581 -280.698851) (xy 116.587291 -280.647921)
			(xy 116.610417 -280.5999) (xy 116.640441 -280.555863) (xy 116.676693 -280.516792) (xy 116.718364 -280.483561)
			(xy 116.764522 -280.456912) (xy 116.814136 -280.43744) (xy 116.866098 -280.42558) (xy 116.919248 -280.421597)
			(xy 116.972398 -280.42558) (xy 117.02436 -280.43744) (xy 117.073974 -280.456912) (xy 117.120132 -280.483561)
			(xy 117.161803 -280.516792) (xy 117.198055 -280.555863) (xy 117.228079 -280.5999) (xy 117.251205 -280.647921)
			(xy 117.266915 -280.698851) (xy 117.274858 -280.751555) (xy 117.275356 -280.778204) (xy 117.274858 -280.804853)
			(xy 117.503438 -280.804853) (xy 117.503438 -280.751555) (xy 117.511381 -280.698851) (xy 117.527091 -280.647921)
			(xy 117.550217 -280.5999) (xy 117.580241 -280.555863) (xy 117.616493 -280.516792) (xy 117.658164 -280.483561)
			(xy 117.704322 -280.456912) (xy 117.753936 -280.43744) (xy 117.805898 -280.42558) (xy 117.859048 -280.421597)
			(xy 117.912198 -280.42558) (xy 117.96416 -280.43744) (xy 118.013774 -280.456912) (xy 118.059932 -280.483561)
			(xy 118.101603 -280.516792) (xy 118.137855 -280.555863) (xy 118.167879 -280.5999) (xy 118.191005 -280.647921)
			(xy 118.206715 -280.698851) (xy 118.214658 -280.751555) (xy 118.215156 -280.778204) (xy 118.214658 -280.804853)
			(xy 118.442984 -280.804853) (xy 118.442984 -280.751555) (xy 118.450927 -280.698851) (xy 118.466637 -280.647921)
			(xy 118.489763 -280.5999) (xy 118.519787 -280.555863) (xy 118.556039 -280.516792) (xy 118.59771 -280.483561)
			(xy 118.643868 -280.456912) (xy 118.693482 -280.43744) (xy 118.745444 -280.42558) (xy 118.798594 -280.421597)
			(xy 118.851744 -280.42558) (xy 118.903706 -280.43744) (xy 118.95332 -280.456912) (xy 118.999478 -280.483561)
			(xy 119.041149 -280.516792) (xy 119.077401 -280.555863) (xy 119.107425 -280.5999) (xy 119.130551 -280.647921)
			(xy 119.146261 -280.698851) (xy 119.154204 -280.751555) (xy 119.154702 -280.778204) (xy 119.154204 -280.804853)
			(xy 119.382784 -280.804853) (xy 119.382784 -280.751555) (xy 119.390727 -280.698851) (xy 119.406437 -280.647921)
			(xy 119.429563 -280.5999) (xy 119.459587 -280.555863) (xy 119.495839 -280.516792) (xy 119.53751 -280.483561)
			(xy 119.583668 -280.456912) (xy 119.633282 -280.43744) (xy 119.685244 -280.42558) (xy 119.738394 -280.421597)
			(xy 119.791544 -280.42558) (xy 119.843506 -280.43744) (xy 119.89312 -280.456912) (xy 119.939278 -280.483561)
			(xy 119.980949 -280.516792) (xy 120.017201 -280.555863) (xy 120.047225 -280.5999) (xy 120.070351 -280.647921)
			(xy 120.086061 -280.698851) (xy 120.094004 -280.751555) (xy 120.094502 -280.778204) (xy 120.094004 -280.804853)
			(xy 120.322584 -280.804853) (xy 120.322584 -280.751555) (xy 120.330527 -280.698851) (xy 120.346237 -280.647921)
			(xy 120.369363 -280.5999) (xy 120.399387 -280.555863) (xy 120.435639 -280.516792) (xy 120.47731 -280.483561)
			(xy 120.523468 -280.456912) (xy 120.573082 -280.43744) (xy 120.625044 -280.42558) (xy 120.678194 -280.421597)
			(xy 120.731344 -280.42558) (xy 120.783306 -280.43744) (xy 120.83292 -280.456912) (xy 120.879078 -280.483561)
			(xy 120.920749 -280.516792) (xy 120.957001 -280.555863) (xy 120.987025 -280.5999) (xy 121.010151 -280.647921)
			(xy 121.025861 -280.698851) (xy 121.033804 -280.751555) (xy 121.034302 -280.778204) (xy 121.033804 -280.804853)
			(xy 121.262384 -280.804853) (xy 121.262384 -280.751555) (xy 121.270327 -280.698851) (xy 121.286037 -280.647921)
			(xy 121.309163 -280.5999) (xy 121.339187 -280.555863) (xy 121.375439 -280.516792) (xy 121.41711 -280.483561)
			(xy 121.463268 -280.456912) (xy 121.512882 -280.43744) (xy 121.564844 -280.42558) (xy 121.617994 -280.421597)
			(xy 121.671144 -280.42558) (xy 121.723106 -280.43744) (xy 121.77272 -280.456912) (xy 121.818878 -280.483561)
			(xy 121.860549 -280.516792) (xy 121.896801 -280.555863) (xy 121.926825 -280.5999) (xy 121.949951 -280.647921)
			(xy 121.965661 -280.698851) (xy 121.973604 -280.751555) (xy 121.974102 -280.778204) (xy 121.973604 -280.804853)
			(xy 122.202184 -280.804853) (xy 122.202184 -280.751555) (xy 122.210127 -280.698851) (xy 122.225837 -280.647921)
			(xy 122.248963 -280.5999) (xy 122.278987 -280.555863) (xy 122.315239 -280.516792) (xy 122.35691 -280.483561)
			(xy 122.403068 -280.456912) (xy 122.452682 -280.43744) (xy 122.504644 -280.42558) (xy 122.557794 -280.421597)
			(xy 122.610944 -280.42558) (xy 122.662906 -280.43744) (xy 122.71252 -280.456912) (xy 122.758678 -280.483561)
			(xy 122.800349 -280.516792) (xy 122.836601 -280.555863) (xy 122.866625 -280.5999) (xy 122.889751 -280.647921)
			(xy 122.905461 -280.698851) (xy 122.913404 -280.751555) (xy 122.913902 -280.778204) (xy 122.913404 -280.804853)
			(xy 123.141984 -280.804853) (xy 123.141984 -280.751555) (xy 123.149927 -280.698851) (xy 123.165637 -280.647921)
			(xy 123.188763 -280.5999) (xy 123.218787 -280.555863) (xy 123.255039 -280.516792) (xy 123.29671 -280.483561)
			(xy 123.342868 -280.456912) (xy 123.392482 -280.43744) (xy 123.444444 -280.42558) (xy 123.497594 -280.421597)
			(xy 123.550744 -280.42558) (xy 123.602706 -280.43744) (xy 123.65232 -280.456912) (xy 123.698478 -280.483561)
			(xy 123.740149 -280.516792) (xy 123.776401 -280.555863) (xy 123.806425 -280.5999) (xy 123.829551 -280.647921)
			(xy 123.845261 -280.698851) (xy 123.853204 -280.751555) (xy 123.853702 -280.778204) (xy 123.853204 -280.804853)
			(xy 124.081784 -280.804853) (xy 124.081784 -280.751555) (xy 124.089727 -280.698851) (xy 124.105437 -280.647921)
			(xy 124.128563 -280.5999) (xy 124.158587 -280.555863) (xy 124.194839 -280.516792) (xy 124.23651 -280.483561)
			(xy 124.282668 -280.456912) (xy 124.332282 -280.43744) (xy 124.384244 -280.42558) (xy 124.437394 -280.421597)
			(xy 124.490544 -280.42558) (xy 124.542506 -280.43744) (xy 124.59212 -280.456912) (xy 124.638278 -280.483561)
			(xy 124.679949 -280.516792) (xy 124.716201 -280.555863) (xy 124.746225 -280.5999) (xy 124.769351 -280.647921)
			(xy 124.785061 -280.698851) (xy 124.793004 -280.751555) (xy 124.793502 -280.778204) (xy 124.793004 -280.804853)
			(xy 125.021584 -280.804853) (xy 125.021584 -280.751555) (xy 125.029527 -280.698851) (xy 125.045237 -280.647921)
			(xy 125.068363 -280.5999) (xy 125.098387 -280.555863) (xy 125.134639 -280.516792) (xy 125.17631 -280.483561)
			(xy 125.222468 -280.456912) (xy 125.272082 -280.43744) (xy 125.324044 -280.42558) (xy 125.377194 -280.421597)
			(xy 125.430344 -280.42558) (xy 125.482306 -280.43744) (xy 125.53192 -280.456912) (xy 125.578078 -280.483561)
			(xy 125.619749 -280.516792) (xy 125.656001 -280.555863) (xy 125.686025 -280.5999) (xy 125.709151 -280.647921)
			(xy 125.724861 -280.698851) (xy 125.732804 -280.751555) (xy 125.733302 -280.778204) (xy 125.732804 -280.804853)
			(xy 125.961638 -280.804853) (xy 125.961638 -280.751555) (xy 125.969581 -280.698851) (xy 125.985291 -280.647921)
			(xy 126.008417 -280.5999) (xy 126.038441 -280.555863) (xy 126.074693 -280.516792) (xy 126.116364 -280.483561)
			(xy 126.162522 -280.456912) (xy 126.212136 -280.43744) (xy 126.264098 -280.42558) (xy 126.317248 -280.421597)
			(xy 126.370398 -280.42558) (xy 126.42236 -280.43744) (xy 126.471974 -280.456912) (xy 126.518132 -280.483561)
			(xy 126.559803 -280.516792) (xy 126.596055 -280.555863) (xy 126.626079 -280.5999) (xy 126.649205 -280.647921)
			(xy 126.664915 -280.698851) (xy 126.672858 -280.751555) (xy 126.673356 -280.778204) (xy 126.672858 -280.804853)
			(xy 126.901438 -280.804853) (xy 126.901438 -280.751555) (xy 126.909381 -280.698851) (xy 126.925091 -280.647921)
			(xy 126.948217 -280.5999) (xy 126.978241 -280.555863) (xy 127.014493 -280.516792) (xy 127.056164 -280.483561)
			(xy 127.102322 -280.456912) (xy 127.151936 -280.43744) (xy 127.203898 -280.42558) (xy 127.257048 -280.421597)
			(xy 127.310198 -280.42558) (xy 127.36216 -280.43744) (xy 127.411774 -280.456912) (xy 127.457932 -280.483561)
			(xy 127.499603 -280.516792) (xy 127.535855 -280.555863) (xy 127.565879 -280.5999) (xy 127.589005 -280.647921)
			(xy 127.604715 -280.698851) (xy 127.612658 -280.751555) (xy 127.613156 -280.778204) (xy 127.612658 -280.804853)
			(xy 127.841238 -280.804853) (xy 127.841238 -280.751555) (xy 127.849181 -280.698851) (xy 127.864891 -280.647921)
			(xy 127.888017 -280.5999) (xy 127.918041 -280.555863) (xy 127.954293 -280.516792) (xy 127.995964 -280.483561)
			(xy 128.042122 -280.456912) (xy 128.091736 -280.43744) (xy 128.143698 -280.42558) (xy 128.196848 -280.421597)
			(xy 128.249998 -280.42558) (xy 128.30196 -280.43744) (xy 128.351574 -280.456912) (xy 128.397732 -280.483561)
			(xy 128.439403 -280.516792) (xy 128.475655 -280.555863) (xy 128.505679 -280.5999) (xy 128.528805 -280.647921)
			(xy 128.544515 -280.698851) (xy 128.552458 -280.751555) (xy 128.552956 -280.778204) (xy 128.552458 -280.804853)
			(xy 128.781038 -280.804853) (xy 128.781038 -280.751555) (xy 128.788981 -280.698851) (xy 128.804691 -280.647921)
			(xy 128.827817 -280.5999) (xy 128.857841 -280.555863) (xy 128.894093 -280.516792) (xy 128.935764 -280.483561)
			(xy 128.981922 -280.456912) (xy 129.031536 -280.43744) (xy 129.083498 -280.42558) (xy 129.136648 -280.421597)
			(xy 129.189798 -280.42558) (xy 129.24176 -280.43744) (xy 129.291374 -280.456912) (xy 129.337532 -280.483561)
			(xy 129.379203 -280.516792) (xy 129.415455 -280.555863) (xy 129.445479 -280.5999) (xy 129.468605 -280.647921)
			(xy 129.484315 -280.698851) (xy 129.492258 -280.751555) (xy 129.492756 -280.778204) (xy 129.492258 -280.804853)
			(xy 129.720838 -280.804853) (xy 129.720838 -280.751555) (xy 129.728781 -280.698851) (xy 129.744491 -280.647921)
			(xy 129.767617 -280.5999) (xy 129.797641 -280.555863) (xy 129.833893 -280.516792) (xy 129.875564 -280.483561)
			(xy 129.921722 -280.456912) (xy 129.971336 -280.43744) (xy 130.023298 -280.42558) (xy 130.076448 -280.421597)
			(xy 130.129598 -280.42558) (xy 130.18156 -280.43744) (xy 130.231174 -280.456912) (xy 130.277332 -280.483561)
			(xy 130.319003 -280.516792) (xy 130.355255 -280.555863) (xy 130.385279 -280.5999) (xy 130.408405 -280.647921)
			(xy 130.424115 -280.698851) (xy 130.432058 -280.751555) (xy 130.432556 -280.778204) (xy 130.432058 -280.804853)
			(xy 130.660384 -280.804853) (xy 130.660384 -280.751555) (xy 130.668327 -280.698851) (xy 130.684037 -280.647921)
			(xy 130.707163 -280.5999) (xy 130.737187 -280.555863) (xy 130.773439 -280.516792) (xy 130.81511 -280.483561)
			(xy 130.861268 -280.456912) (xy 130.910882 -280.43744) (xy 130.962844 -280.42558) (xy 131.015994 -280.421597)
			(xy 131.069144 -280.42558) (xy 131.121106 -280.43744) (xy 131.17072 -280.456912) (xy 131.216878 -280.483561)
			(xy 131.258549 -280.516792) (xy 131.294801 -280.555863) (xy 131.324825 -280.5999) (xy 131.347951 -280.647921)
			(xy 131.363661 -280.698851) (xy 131.371604 -280.751555) (xy 131.372102 -280.778204) (xy 131.371604 -280.804853)
			(xy 131.600184 -280.804853) (xy 131.600184 -280.751555) (xy 131.608127 -280.698851) (xy 131.623837 -280.647921)
			(xy 131.646963 -280.5999) (xy 131.676987 -280.555863) (xy 131.713239 -280.516792) (xy 131.75491 -280.483561)
			(xy 131.801068 -280.456912) (xy 131.850682 -280.43744) (xy 131.902644 -280.42558) (xy 131.955794 -280.421597)
			(xy 132.008944 -280.42558) (xy 132.060906 -280.43744) (xy 132.11052 -280.456912) (xy 132.156678 -280.483561)
			(xy 132.198349 -280.516792) (xy 132.234601 -280.555863) (xy 132.264625 -280.5999) (xy 132.287751 -280.647921)
			(xy 132.303461 -280.698851) (xy 132.311404 -280.751555) (xy 132.311902 -280.778204) (xy 132.311404 -280.804853)
			(xy 132.539984 -280.804853) (xy 132.539984 -280.751555) (xy 132.547927 -280.698851) (xy 132.563637 -280.647921)
			(xy 132.586763 -280.5999) (xy 132.616787 -280.555863) (xy 132.653039 -280.516792) (xy 132.69471 -280.483561)
			(xy 132.740868 -280.456912) (xy 132.790482 -280.43744) (xy 132.842444 -280.42558) (xy 132.895594 -280.421597)
			(xy 132.948744 -280.42558) (xy 133.000706 -280.43744) (xy 133.05032 -280.456912) (xy 133.096478 -280.483561)
			(xy 133.138149 -280.516792) (xy 133.174401 -280.555863) (xy 133.204425 -280.5999) (xy 133.227551 -280.647921)
			(xy 133.243261 -280.698851) (xy 133.251204 -280.751555) (xy 133.251702 -280.778204) (xy 133.251204 -280.804853)
			(xy 133.479784 -280.804853) (xy 133.479784 -280.751555) (xy 133.487727 -280.698851) (xy 133.503437 -280.647921)
			(xy 133.526563 -280.5999) (xy 133.556587 -280.555863) (xy 133.592839 -280.516792) (xy 133.63451 -280.483561)
			(xy 133.680668 -280.456912) (xy 133.730282 -280.43744) (xy 133.782244 -280.42558) (xy 133.835394 -280.421597)
			(xy 133.888544 -280.42558) (xy 133.940506 -280.43744) (xy 133.99012 -280.456912) (xy 134.036278 -280.483561)
			(xy 134.077949 -280.516792) (xy 134.114201 -280.555863) (xy 134.144225 -280.5999) (xy 134.167351 -280.647921)
			(xy 134.183061 -280.698851) (xy 134.191004 -280.751555) (xy 134.191502 -280.778204) (xy 134.191004 -280.804853)
			(xy 134.419584 -280.804853) (xy 134.419584 -280.751555) (xy 134.427527 -280.698851) (xy 134.443237 -280.647921)
			(xy 134.466363 -280.5999) (xy 134.496387 -280.555863) (xy 134.532639 -280.516792) (xy 134.57431 -280.483561)
			(xy 134.620468 -280.456912) (xy 134.670082 -280.43744) (xy 134.722044 -280.42558) (xy 134.775194 -280.421597)
			(xy 134.828344 -280.42558) (xy 134.880306 -280.43744) (xy 134.92992 -280.456912) (xy 134.976078 -280.483561)
			(xy 135.017749 -280.516792) (xy 135.054001 -280.555863) (xy 135.084025 -280.5999) (xy 135.107151 -280.647921)
			(xy 135.122861 -280.698851) (xy 135.130804 -280.751555) (xy 135.131302 -280.778204) (xy 135.130804 -280.804853)
			(xy 135.359384 -280.804853) (xy 135.359384 -280.751555) (xy 135.367327 -280.698851) (xy 135.383037 -280.647921)
			(xy 135.406163 -280.5999) (xy 135.436187 -280.555863) (xy 135.472439 -280.516792) (xy 135.51411 -280.483561)
			(xy 135.560268 -280.456912) (xy 135.609882 -280.43744) (xy 135.661844 -280.42558) (xy 135.714994 -280.421597)
			(xy 135.768144 -280.42558) (xy 135.820106 -280.43744) (xy 135.86972 -280.456912) (xy 135.915878 -280.483561)
			(xy 135.957549 -280.516792) (xy 135.993801 -280.555863) (xy 136.023825 -280.5999) (xy 136.046951 -280.647921)
			(xy 136.062661 -280.698851) (xy 136.070604 -280.751555) (xy 136.071102 -280.778204) (xy 136.070604 -280.804853)
			(xy 136.299184 -280.804853) (xy 136.299184 -280.751555) (xy 136.307127 -280.698851) (xy 136.322837 -280.647921)
			(xy 136.345963 -280.5999) (xy 136.375987 -280.555863) (xy 136.412239 -280.516792) (xy 136.45391 -280.483561)
			(xy 136.500068 -280.456912) (xy 136.549682 -280.43744) (xy 136.601644 -280.42558) (xy 136.654794 -280.421597)
			(xy 136.707944 -280.42558) (xy 136.759906 -280.43744) (xy 136.80952 -280.456912) (xy 136.855678 -280.483561)
			(xy 136.897349 -280.516792) (xy 136.933601 -280.555863) (xy 136.963625 -280.5999) (xy 136.986751 -280.647921)
			(xy 137.002461 -280.698851) (xy 137.010404 -280.751555) (xy 137.010902 -280.778204) (xy 137.010404 -280.804853)
			(xy 137.238984 -280.804853) (xy 137.238984 -280.751555) (xy 137.246927 -280.698851) (xy 137.262637 -280.647921)
			(xy 137.285763 -280.5999) (xy 137.315787 -280.555863) (xy 137.352039 -280.516792) (xy 137.39371 -280.483561)
			(xy 137.439868 -280.456912) (xy 137.489482 -280.43744) (xy 137.541444 -280.42558) (xy 137.594594 -280.421597)
			(xy 137.647744 -280.42558) (xy 137.699706 -280.43744) (xy 137.74932 -280.456912) (xy 137.795478 -280.483561)
			(xy 137.837149 -280.516792) (xy 137.873401 -280.555863) (xy 137.903425 -280.5999) (xy 137.926551 -280.647921)
			(xy 137.942261 -280.698851) (xy 137.950204 -280.751555) (xy 137.950702 -280.778204) (xy 137.950204 -280.804853)
			(xy 138.179038 -280.804853) (xy 138.179038 -280.751555) (xy 138.186981 -280.698851) (xy 138.202691 -280.647921)
			(xy 138.225817 -280.5999) (xy 138.255841 -280.555863) (xy 138.292093 -280.516792) (xy 138.333764 -280.483561)
			(xy 138.379922 -280.456912) (xy 138.429536 -280.43744) (xy 138.481498 -280.42558) (xy 138.534648 -280.421597)
			(xy 138.587798 -280.42558) (xy 138.63976 -280.43744) (xy 138.689374 -280.456912) (xy 138.735532 -280.483561)
			(xy 138.777203 -280.516792) (xy 138.813455 -280.555863) (xy 138.843479 -280.5999) (xy 138.866605 -280.647921)
			(xy 138.882315 -280.698851) (xy 138.890258 -280.751555) (xy 138.890756 -280.778204) (xy 138.890258 -280.804853)
			(xy 138.882315 -280.857557) (xy 138.866605 -280.908487) (xy 138.843479 -280.956508) (xy 138.813455 -281.000545)
			(xy 138.777203 -281.039616) (xy 138.735532 -281.072847) (xy 138.689374 -281.099496) (xy 138.63976 -281.118968)
			(xy 138.587798 -281.130828) (xy 138.534648 -281.134812) (xy 138.481498 -281.130828) (xy 138.429536 -281.118968)
			(xy 138.379922 -281.099496) (xy 138.333764 -281.072847) (xy 138.292093 -281.039616) (xy 138.255841 -281.000545)
			(xy 138.225817 -280.956508) (xy 138.202691 -280.908487) (xy 138.186981 -280.857557) (xy 138.179038 -280.804853)
			(xy 137.950204 -280.804853) (xy 137.942261 -280.857557) (xy 137.926551 -280.908487) (xy 137.903425 -280.956508)
			(xy 137.873401 -281.000545) (xy 137.837149 -281.039616) (xy 137.795478 -281.072847) (xy 137.74932 -281.099496)
			(xy 137.699706 -281.118968) (xy 137.647744 -281.130828) (xy 137.594594 -281.134812) (xy 137.541444 -281.130828)
			(xy 137.489482 -281.118968) (xy 137.439868 -281.099496) (xy 137.39371 -281.072847) (xy 137.352039 -281.039616)
			(xy 137.315787 -281.000545) (xy 137.285763 -280.956508) (xy 137.262637 -280.908487) (xy 137.246927 -280.857557)
			(xy 137.238984 -280.804853) (xy 137.010404 -280.804853) (xy 137.002461 -280.857557) (xy 136.986751 -280.908487)
			(xy 136.963625 -280.956508) (xy 136.933601 -281.000545) (xy 136.897349 -281.039616) (xy 136.855678 -281.072847)
			(xy 136.80952 -281.099496) (xy 136.759906 -281.118968) (xy 136.707944 -281.130828) (xy 136.654794 -281.134812)
			(xy 136.601644 -281.130828) (xy 136.549682 -281.118968) (xy 136.500068 -281.099496) (xy 136.45391 -281.072847)
			(xy 136.412239 -281.039616) (xy 136.375987 -281.000545) (xy 136.345963 -280.956508) (xy 136.322837 -280.908487)
			(xy 136.307127 -280.857557) (xy 136.299184 -280.804853) (xy 136.070604 -280.804853) (xy 136.062661 -280.857557)
			(xy 136.046951 -280.908487) (xy 136.023825 -280.956508) (xy 135.993801 -281.000545) (xy 135.957549 -281.039616)
			(xy 135.915878 -281.072847) (xy 135.86972 -281.099496) (xy 135.820106 -281.118968) (xy 135.768144 -281.130828)
			(xy 135.714994 -281.134812) (xy 135.661844 -281.130828) (xy 135.609882 -281.118968) (xy 135.560268 -281.099496)
			(xy 135.51411 -281.072847) (xy 135.472439 -281.039616) (xy 135.436187 -281.000545) (xy 135.406163 -280.956508)
			(xy 135.383037 -280.908487) (xy 135.367327 -280.857557) (xy 135.359384 -280.804853) (xy 135.130804 -280.804853)
			(xy 135.122861 -280.857557) (xy 135.107151 -280.908487) (xy 135.084025 -280.956508) (xy 135.054001 -281.000545)
			(xy 135.017749 -281.039616) (xy 134.976078 -281.072847) (xy 134.92992 -281.099496) (xy 134.880306 -281.118968)
			(xy 134.828344 -281.130828) (xy 134.775194 -281.134812) (xy 134.722044 -281.130828) (xy 134.670082 -281.118968)
			(xy 134.620468 -281.099496) (xy 134.57431 -281.072847) (xy 134.532639 -281.039616) (xy 134.496387 -281.000545)
			(xy 134.466363 -280.956508) (xy 134.443237 -280.908487) (xy 134.427527 -280.857557) (xy 134.419584 -280.804853)
			(xy 134.191004 -280.804853) (xy 134.183061 -280.857557) (xy 134.167351 -280.908487) (xy 134.144225 -280.956508)
			(xy 134.114201 -281.000545) (xy 134.077949 -281.039616) (xy 134.036278 -281.072847) (xy 133.99012 -281.099496)
			(xy 133.940506 -281.118968) (xy 133.888544 -281.130828) (xy 133.835394 -281.134812) (xy 133.782244 -281.130828)
			(xy 133.730282 -281.118968) (xy 133.680668 -281.099496) (xy 133.63451 -281.072847) (xy 133.592839 -281.039616)
			(xy 133.556587 -281.000545) (xy 133.526563 -280.956508) (xy 133.503437 -280.908487) (xy 133.487727 -280.857557)
			(xy 133.479784 -280.804853) (xy 133.251204 -280.804853) (xy 133.243261 -280.857557) (xy 133.227551 -280.908487)
			(xy 133.204425 -280.956508) (xy 133.174401 -281.000545) (xy 133.138149 -281.039616) (xy 133.096478 -281.072847)
			(xy 133.05032 -281.099496) (xy 133.000706 -281.118968) (xy 132.948744 -281.130828) (xy 132.895594 -281.134812)
			(xy 132.842444 -281.130828) (xy 132.790482 -281.118968) (xy 132.740868 -281.099496) (xy 132.69471 -281.072847)
			(xy 132.653039 -281.039616) (xy 132.616787 -281.000545) (xy 132.586763 -280.956508) (xy 132.563637 -280.908487)
			(xy 132.547927 -280.857557) (xy 132.539984 -280.804853) (xy 132.311404 -280.804853) (xy 132.303461 -280.857557)
			(xy 132.287751 -280.908487) (xy 132.264625 -280.956508) (xy 132.234601 -281.000545) (xy 132.198349 -281.039616)
			(xy 132.156678 -281.072847) (xy 132.11052 -281.099496) (xy 132.060906 -281.118968) (xy 132.008944 -281.130828)
			(xy 131.955794 -281.134812) (xy 131.902644 -281.130828) (xy 131.850682 -281.118968) (xy 131.801068 -281.099496)
			(xy 131.75491 -281.072847) (xy 131.713239 -281.039616) (xy 131.676987 -281.000545) (xy 131.646963 -280.956508)
			(xy 131.623837 -280.908487) (xy 131.608127 -280.857557) (xy 131.600184 -280.804853) (xy 131.371604 -280.804853)
			(xy 131.363661 -280.857557) (xy 131.347951 -280.908487) (xy 131.324825 -280.956508) (xy 131.294801 -281.000545)
			(xy 131.258549 -281.039616) (xy 131.216878 -281.072847) (xy 131.17072 -281.099496) (xy 131.121106 -281.118968)
			(xy 131.069144 -281.130828) (xy 131.015994 -281.134812) (xy 130.962844 -281.130828) (xy 130.910882 -281.118968)
			(xy 130.861268 -281.099496) (xy 130.81511 -281.072847) (xy 130.773439 -281.039616) (xy 130.737187 -281.000545)
			(xy 130.707163 -280.956508) (xy 130.684037 -280.908487) (xy 130.668327 -280.857557) (xy 130.660384 -280.804853)
			(xy 130.432058 -280.804853) (xy 130.424115 -280.857557) (xy 130.408405 -280.908487) (xy 130.385279 -280.956508)
			(xy 130.355255 -281.000545) (xy 130.319003 -281.039616) (xy 130.277332 -281.072847) (xy 130.231174 -281.099496)
			(xy 130.18156 -281.118968) (xy 130.129598 -281.130828) (xy 130.076448 -281.134812) (xy 130.023298 -281.130828)
			(xy 129.971336 -281.118968) (xy 129.921722 -281.099496) (xy 129.875564 -281.072847) (xy 129.833893 -281.039616)
			(xy 129.797641 -281.000545) (xy 129.767617 -280.956508) (xy 129.744491 -280.908487) (xy 129.728781 -280.857557)
			(xy 129.720838 -280.804853) (xy 129.492258 -280.804853) (xy 129.484315 -280.857557) (xy 129.468605 -280.908487)
			(xy 129.445479 -280.956508) (xy 129.415455 -281.000545) (xy 129.379203 -281.039616) (xy 129.337532 -281.072847)
			(xy 129.291374 -281.099496) (xy 129.24176 -281.118968) (xy 129.189798 -281.130828) (xy 129.136648 -281.134812)
			(xy 129.083498 -281.130828) (xy 129.031536 -281.118968) (xy 128.981922 -281.099496) (xy 128.935764 -281.072847)
			(xy 128.894093 -281.039616) (xy 128.857841 -281.000545) (xy 128.827817 -280.956508) (xy 128.804691 -280.908487)
			(xy 128.788981 -280.857557) (xy 128.781038 -280.804853) (xy 128.552458 -280.804853) (xy 128.544515 -280.857557)
			(xy 128.528805 -280.908487) (xy 128.505679 -280.956508) (xy 128.475655 -281.000545) (xy 128.439403 -281.039616)
			(xy 128.397732 -281.072847) (xy 128.351574 -281.099496) (xy 128.30196 -281.118968) (xy 128.249998 -281.130828)
			(xy 128.196848 -281.134812) (xy 128.143698 -281.130828) (xy 128.091736 -281.118968) (xy 128.042122 -281.099496)
			(xy 127.995964 -281.072847) (xy 127.954293 -281.039616) (xy 127.918041 -281.000545) (xy 127.888017 -280.956508)
			(xy 127.864891 -280.908487) (xy 127.849181 -280.857557) (xy 127.841238 -280.804853) (xy 127.612658 -280.804853)
			(xy 127.604715 -280.857557) (xy 127.589005 -280.908487) (xy 127.565879 -280.956508) (xy 127.535855 -281.000545)
			(xy 127.499603 -281.039616) (xy 127.457932 -281.072847) (xy 127.411774 -281.099496) (xy 127.36216 -281.118968)
			(xy 127.310198 -281.130828) (xy 127.257048 -281.134812) (xy 127.203898 -281.130828) (xy 127.151936 -281.118968)
			(xy 127.102322 -281.099496) (xy 127.056164 -281.072847) (xy 127.014493 -281.039616) (xy 126.978241 -281.000545)
			(xy 126.948217 -280.956508) (xy 126.925091 -280.908487) (xy 126.909381 -280.857557) (xy 126.901438 -280.804853)
			(xy 126.672858 -280.804853) (xy 126.664915 -280.857557) (xy 126.649205 -280.908487) (xy 126.626079 -280.956508)
			(xy 126.596055 -281.000545) (xy 126.559803 -281.039616) (xy 126.518132 -281.072847) (xy 126.471974 -281.099496)
			(xy 126.42236 -281.118968) (xy 126.370398 -281.130828) (xy 126.317248 -281.134812) (xy 126.264098 -281.130828)
			(xy 126.212136 -281.118968) (xy 126.162522 -281.099496) (xy 126.116364 -281.072847) (xy 126.074693 -281.039616)
			(xy 126.038441 -281.000545) (xy 126.008417 -280.956508) (xy 125.985291 -280.908487) (xy 125.969581 -280.857557)
			(xy 125.961638 -280.804853) (xy 125.732804 -280.804853) (xy 125.724861 -280.857557) (xy 125.709151 -280.908487)
			(xy 125.686025 -280.956508) (xy 125.656001 -281.000545) (xy 125.619749 -281.039616) (xy 125.578078 -281.072847)
			(xy 125.53192 -281.099496) (xy 125.482306 -281.118968) (xy 125.430344 -281.130828) (xy 125.377194 -281.134812)
			(xy 125.324044 -281.130828) (xy 125.272082 -281.118968) (xy 125.222468 -281.099496) (xy 125.17631 -281.072847)
			(xy 125.134639 -281.039616) (xy 125.098387 -281.000545) (xy 125.068363 -280.956508) (xy 125.045237 -280.908487)
			(xy 125.029527 -280.857557) (xy 125.021584 -280.804853) (xy 124.793004 -280.804853) (xy 124.785061 -280.857557)
			(xy 124.769351 -280.908487) (xy 124.746225 -280.956508) (xy 124.716201 -281.000545) (xy 124.679949 -281.039616)
			(xy 124.638278 -281.072847) (xy 124.59212 -281.099496) (xy 124.542506 -281.118968) (xy 124.490544 -281.130828)
			(xy 124.437394 -281.134812) (xy 124.384244 -281.130828) (xy 124.332282 -281.118968) (xy 124.282668 -281.099496)
			(xy 124.23651 -281.072847) (xy 124.194839 -281.039616) (xy 124.158587 -281.000545) (xy 124.128563 -280.956508)
			(xy 124.105437 -280.908487) (xy 124.089727 -280.857557) (xy 124.081784 -280.804853) (xy 123.853204 -280.804853)
			(xy 123.845261 -280.857557) (xy 123.829551 -280.908487) (xy 123.806425 -280.956508) (xy 123.776401 -281.000545)
			(xy 123.740149 -281.039616) (xy 123.698478 -281.072847) (xy 123.65232 -281.099496) (xy 123.602706 -281.118968)
			(xy 123.550744 -281.130828) (xy 123.497594 -281.134812) (xy 123.444444 -281.130828) (xy 123.392482 -281.118968)
			(xy 123.342868 -281.099496) (xy 123.29671 -281.072847) (xy 123.255039 -281.039616) (xy 123.218787 -281.000545)
			(xy 123.188763 -280.956508) (xy 123.165637 -280.908487) (xy 123.149927 -280.857557) (xy 123.141984 -280.804853)
			(xy 122.913404 -280.804853) (xy 122.905461 -280.857557) (xy 122.889751 -280.908487) (xy 122.866625 -280.956508)
			(xy 122.836601 -281.000545) (xy 122.800349 -281.039616) (xy 122.758678 -281.072847) (xy 122.71252 -281.099496)
			(xy 122.662906 -281.118968) (xy 122.610944 -281.130828) (xy 122.557794 -281.134812) (xy 122.504644 -281.130828)
			(xy 122.452682 -281.118968) (xy 122.403068 -281.099496) (xy 122.35691 -281.072847) (xy 122.315239 -281.039616)
			(xy 122.278987 -281.000545) (xy 122.248963 -280.956508) (xy 122.225837 -280.908487) (xy 122.210127 -280.857557)
			(xy 122.202184 -280.804853) (xy 121.973604 -280.804853) (xy 121.965661 -280.857557) (xy 121.949951 -280.908487)
			(xy 121.926825 -280.956508) (xy 121.896801 -281.000545) (xy 121.860549 -281.039616) (xy 121.818878 -281.072847)
			(xy 121.77272 -281.099496) (xy 121.723106 -281.118968) (xy 121.671144 -281.130828) (xy 121.617994 -281.134812)
			(xy 121.564844 -281.130828) (xy 121.512882 -281.118968) (xy 121.463268 -281.099496) (xy 121.41711 -281.072847)
			(xy 121.375439 -281.039616) (xy 121.339187 -281.000545) (xy 121.309163 -280.956508) (xy 121.286037 -280.908487)
			(xy 121.270327 -280.857557) (xy 121.262384 -280.804853) (xy 121.033804 -280.804853) (xy 121.025861 -280.857557)
			(xy 121.010151 -280.908487) (xy 120.987025 -280.956508) (xy 120.957001 -281.000545) (xy 120.920749 -281.039616)
			(xy 120.879078 -281.072847) (xy 120.83292 -281.099496) (xy 120.783306 -281.118968) (xy 120.731344 -281.130828)
			(xy 120.678194 -281.134812) (xy 120.625044 -281.130828) (xy 120.573082 -281.118968) (xy 120.523468 -281.099496)
			(xy 120.47731 -281.072847) (xy 120.435639 -281.039616) (xy 120.399387 -281.000545) (xy 120.369363 -280.956508)
			(xy 120.346237 -280.908487) (xy 120.330527 -280.857557) (xy 120.322584 -280.804853) (xy 120.094004 -280.804853)
			(xy 120.086061 -280.857557) (xy 120.070351 -280.908487) (xy 120.047225 -280.956508) (xy 120.017201 -281.000545)
			(xy 119.980949 -281.039616) (xy 119.939278 -281.072847) (xy 119.89312 -281.099496) (xy 119.843506 -281.118968)
			(xy 119.791544 -281.130828) (xy 119.738394 -281.134812) (xy 119.685244 -281.130828) (xy 119.633282 -281.118968)
			(xy 119.583668 -281.099496) (xy 119.53751 -281.072847) (xy 119.495839 -281.039616) (xy 119.459587 -281.000545)
			(xy 119.429563 -280.956508) (xy 119.406437 -280.908487) (xy 119.390727 -280.857557) (xy 119.382784 -280.804853)
			(xy 119.154204 -280.804853) (xy 119.146261 -280.857557) (xy 119.130551 -280.908487) (xy 119.107425 -280.956508)
			(xy 119.077401 -281.000545) (xy 119.041149 -281.039616) (xy 118.999478 -281.072847) (xy 118.95332 -281.099496)
			(xy 118.903706 -281.118968) (xy 118.851744 -281.130828) (xy 118.798594 -281.134812) (xy 118.745444 -281.130828)
			(xy 118.693482 -281.118968) (xy 118.643868 -281.099496) (xy 118.59771 -281.072847) (xy 118.556039 -281.039616)
			(xy 118.519787 -281.000545) (xy 118.489763 -280.956508) (xy 118.466637 -280.908487) (xy 118.450927 -280.857557)
			(xy 118.442984 -280.804853) (xy 118.214658 -280.804853) (xy 118.206715 -280.857557) (xy 118.191005 -280.908487)
			(xy 118.167879 -280.956508) (xy 118.137855 -281.000545) (xy 118.101603 -281.039616) (xy 118.059932 -281.072847)
			(xy 118.013774 -281.099496) (xy 117.96416 -281.118968) (xy 117.912198 -281.130828) (xy 117.859048 -281.134812)
			(xy 117.805898 -281.130828) (xy 117.753936 -281.118968) (xy 117.704322 -281.099496) (xy 117.658164 -281.072847)
			(xy 117.616493 -281.039616) (xy 117.580241 -281.000545) (xy 117.550217 -280.956508) (xy 117.527091 -280.908487)
			(xy 117.511381 -280.857557) (xy 117.503438 -280.804853) (xy 117.274858 -280.804853) (xy 117.266915 -280.857557)
			(xy 117.251205 -280.908487) (xy 117.228079 -280.956508) (xy 117.198055 -281.000545) (xy 117.161803 -281.039616)
			(xy 117.120132 -281.072847) (xy 117.073974 -281.099496) (xy 117.02436 -281.118968) (xy 116.972398 -281.130828)
			(xy 116.919248 -281.134812) (xy 116.866098 -281.130828) (xy 116.814136 -281.118968) (xy 116.764522 -281.099496)
			(xy 116.718364 -281.072847) (xy 116.676693 -281.039616) (xy 116.640441 -281.000545) (xy 116.610417 -280.956508)
			(xy 116.587291 -280.908487) (xy 116.571581 -280.857557) (xy 116.563638 -280.804853) (xy 110.696004 -280.804853)
			(xy 110.688061 -280.857557) (xy 110.672351 -280.908487) (xy 110.649225 -280.956508) (xy 110.619201 -281.000545)
			(xy 110.582949 -281.039616) (xy 110.541278 -281.072847) (xy 110.49512 -281.099496) (xy 110.445506 -281.118968)
			(xy 110.393544 -281.130828) (xy 110.340394 -281.134812) (xy 110.287244 -281.130828) (xy 110.235282 -281.118968)
			(xy 110.185668 -281.099496) (xy 110.13951 -281.072847) (xy 110.097839 -281.039616) (xy 110.061587 -281.000545)
			(xy 110.031563 -280.956508) (xy 110.008437 -280.908487) (xy 109.992727 -280.857557) (xy 109.984784 -280.804853)
			(xy 107.876604 -280.804853) (xy 107.868661 -280.857557) (xy 107.852951 -280.908487) (xy 107.829825 -280.956508)
			(xy 107.799801 -281.000545) (xy 107.763549 -281.039616) (xy 107.721878 -281.072847) (xy 107.67572 -281.099496)
			(xy 107.626106 -281.118968) (xy 107.574144 -281.130828) (xy 107.520994 -281.134812) (xy 107.467844 -281.130828)
			(xy 107.415882 -281.118968) (xy 107.366268 -281.099496) (xy 107.32011 -281.072847) (xy 107.278439 -281.039616)
			(xy 107.242187 -281.000545) (xy 107.212163 -280.956508) (xy 107.189037 -280.908487) (xy 107.173327 -280.857557)
			(xy 107.165384 -280.804853) (xy 106.910296 -280.804853) (xy 106.902308 -280.855292) (xy 106.886294 -280.904576)
			(xy 106.862768 -280.950748) (xy 106.832309 -280.992671) (xy 106.795666 -281.029313) (xy 106.753743 -281.059772)
			(xy 106.70757 -281.083297) (xy 106.658286 -281.099309) (xy 106.607104 -281.107415) (xy 106.581194 -281.107896)
			(xy 106.555682 -281.107421) (xy 106.505267 -281.09956) (xy 106.456665 -281.084025) (xy 106.411037 -281.061188)
			(xy 106.369472 -281.031595) (xy 106.332962 -280.995951) (xy 106.317288 -280.975816) (xy 105.9053 -280.975816)
			(xy 105.889631 -280.995955) (xy 105.85312 -281.031598) (xy 105.811553 -281.06119) (xy 105.765924 -281.084026)
			(xy 105.717322 -281.099559) (xy 105.666906 -281.107419) (xy 105.641394 -281.107896) (xy 105.615487 -281.107379)
			(xy 105.564312 -281.099273) (xy 105.515035 -281.083261) (xy 105.468869 -281.059738) (xy 105.426951 -281.029282)
			(xy 105.390314 -280.992644) (xy 105.359859 -280.950726) (xy 105.336337 -280.90456) (xy 105.320326 -280.855282)
			(xy 105.31222 -280.804107) (xy 105.08488 -280.804107) (xy 105.08488 -281.134566) (xy 105.085241 -281.143946)
			(xy 105.092026 -281.161435) (xy 105.098088 -281.168602) (xy 105.123742 -281.195272) (xy 105.14838 -281.220672)
			(xy 105.1553 -281.227257) (xy 105.172657 -281.235204) (xy 105.182162 -281.236166) (xy 105.183178 -281.236166)
			(xy 105.209246 -281.237465) (xy 105.260608 -281.246746) (xy 105.310064 -281.263427) (xy 105.356555 -281.287149)
			(xy 105.399084 -281.317406) (xy 105.436739 -281.353548) (xy 105.468714 -281.3948) (xy 105.494323 -281.440279)
			(xy 105.513018 -281.489009) (xy 105.524398 -281.539947) (xy 105.528218 -281.592001) (xy 105.528217 -281.59202)
			(xy 105.781856 -281.59202) (xy 105.782364 -281.566113) (xy 105.79047 -281.514936) (xy 105.806482 -281.465657)
			(xy 105.830005 -281.41949) (xy 105.860461 -281.377571) (xy 105.897099 -281.340933) (xy 105.939018 -281.310477)
			(xy 105.985185 -281.286954) (xy 106.034464 -281.270942) (xy 106.085641 -281.262836) (xy 106.137455 -281.262836)
			(xy 106.188632 -281.270942) (xy 106.237911 -281.286954) (xy 106.284078 -281.310477) (xy 106.325997 -281.340933)
			(xy 106.362635 -281.377571) (xy 106.393091 -281.41949) (xy 106.416614 -281.465657) (xy 106.432626 -281.514936)
			(xy 106.440732 -281.566113) (xy 106.44124 -281.59202) (xy 106.440693 -281.618669) (xy 106.695738 -281.618669)
			(xy 106.695738 -281.565371) (xy 106.703681 -281.512667) (xy 106.719391 -281.461737) (xy 106.742517 -281.413716)
			(xy 106.772541 -281.369679) (xy 106.808793 -281.330608) (xy 106.850464 -281.297377) (xy 106.896622 -281.270728)
			(xy 106.946236 -281.251256) (xy 106.998198 -281.239396) (xy 107.051348 -281.235413) (xy 107.104498 -281.239396)
			(xy 107.15646 -281.251256) (xy 107.206074 -281.270728) (xy 107.252232 -281.297377) (xy 107.293903 -281.330608)
			(xy 107.330155 -281.369679) (xy 107.360179 -281.413716) (xy 107.383305 -281.461737) (xy 107.399015 -281.512667)
			(xy 107.406958 -281.565371) (xy 107.407456 -281.59202) (xy 107.406958 -281.618669) (xy 113.274084 -281.618669)
			(xy 113.274084 -281.565371) (xy 113.282027 -281.512667) (xy 113.297737 -281.461737) (xy 113.320863 -281.413716)
			(xy 113.350887 -281.369679) (xy 113.387139 -281.330608) (xy 113.42881 -281.297377) (xy 113.474968 -281.270728)
			(xy 113.524582 -281.251256) (xy 113.576544 -281.239396) (xy 113.629694 -281.235413) (xy 113.682844 -281.239396)
			(xy 113.734806 -281.251256) (xy 113.78442 -281.270728) (xy 113.830578 -281.297377) (xy 113.872249 -281.330608)
			(xy 113.908501 -281.369679) (xy 113.938525 -281.413716) (xy 113.961651 -281.461737) (xy 113.977361 -281.512667)
			(xy 113.985304 -281.565371) (xy 113.985802 -281.59202) (xy 113.985304 -281.618669) (xy 117.033538 -281.618669)
			(xy 117.033538 -281.565371) (xy 117.041481 -281.512667) (xy 117.057191 -281.461737) (xy 117.080317 -281.413716)
			(xy 117.110341 -281.369679) (xy 117.146593 -281.330608) (xy 117.188264 -281.297377) (xy 117.234422 -281.270728)
			(xy 117.284036 -281.251256) (xy 117.335998 -281.239396) (xy 117.389148 -281.235413) (xy 117.442298 -281.239396)
			(xy 117.49426 -281.251256) (xy 117.543874 -281.270728) (xy 117.590032 -281.297377) (xy 117.631703 -281.330608)
			(xy 117.667955 -281.369679) (xy 117.697979 -281.413716) (xy 117.721105 -281.461737) (xy 117.736815 -281.512667)
			(xy 117.744758 -281.565371) (xy 117.745256 -281.59202) (xy 117.744758 -281.618669) (xy 117.973084 -281.618669)
			(xy 117.973084 -281.565371) (xy 117.981027 -281.512667) (xy 117.996737 -281.461737) (xy 118.019863 -281.413716)
			(xy 118.049887 -281.369679) (xy 118.086139 -281.330608) (xy 118.12781 -281.297377) (xy 118.173968 -281.270728)
			(xy 118.223582 -281.251256) (xy 118.275544 -281.239396) (xy 118.328694 -281.235413) (xy 118.381844 -281.239396)
			(xy 118.433806 -281.251256) (xy 118.48342 -281.270728) (xy 118.529578 -281.297377) (xy 118.571249 -281.330608)
			(xy 118.607501 -281.369679) (xy 118.637525 -281.413716) (xy 118.660651 -281.461737) (xy 118.676361 -281.512667)
			(xy 118.684304 -281.565371) (xy 118.684802 -281.59202) (xy 118.684304 -281.618669) (xy 118.913138 -281.618669)
			(xy 118.913138 -281.565371) (xy 118.921081 -281.512667) (xy 118.936791 -281.461737) (xy 118.959917 -281.413716)
			(xy 118.989941 -281.369679) (xy 119.026193 -281.330608) (xy 119.067864 -281.297377) (xy 119.114022 -281.270728)
			(xy 119.163636 -281.251256) (xy 119.215598 -281.239396) (xy 119.268748 -281.235413) (xy 119.321898 -281.239396)
			(xy 119.37386 -281.251256) (xy 119.423474 -281.270728) (xy 119.469632 -281.297377) (xy 119.511303 -281.330608)
			(xy 119.547555 -281.369679) (xy 119.577579 -281.413716) (xy 119.600705 -281.461737) (xy 119.616415 -281.512667)
			(xy 119.624358 -281.565371) (xy 119.624856 -281.59202) (xy 119.624358 -281.618669) (xy 119.852938 -281.618669)
			(xy 119.852938 -281.565371) (xy 119.860881 -281.512667) (xy 119.876591 -281.461737) (xy 119.899717 -281.413716)
			(xy 119.929741 -281.369679) (xy 119.965993 -281.330608) (xy 120.007664 -281.297377) (xy 120.053822 -281.270728)
			(xy 120.103436 -281.251256) (xy 120.155398 -281.239396) (xy 120.208548 -281.235413) (xy 120.261698 -281.239396)
			(xy 120.31366 -281.251256) (xy 120.363274 -281.270728) (xy 120.409432 -281.297377) (xy 120.451103 -281.330608)
			(xy 120.487355 -281.369679) (xy 120.517379 -281.413716) (xy 120.540505 -281.461737) (xy 120.556215 -281.512667)
			(xy 120.564158 -281.565371) (xy 120.564656 -281.59202) (xy 120.564158 -281.618669) (xy 120.792738 -281.618669)
			(xy 120.792738 -281.565371) (xy 120.800681 -281.512667) (xy 120.816391 -281.461737) (xy 120.839517 -281.413716)
			(xy 120.869541 -281.369679) (xy 120.905793 -281.330608) (xy 120.947464 -281.297377) (xy 120.993622 -281.270728)
			(xy 121.043236 -281.251256) (xy 121.095198 -281.239396) (xy 121.148348 -281.235413) (xy 121.201498 -281.239396)
			(xy 121.25346 -281.251256) (xy 121.303074 -281.270728) (xy 121.349232 -281.297377) (xy 121.390903 -281.330608)
			(xy 121.427155 -281.369679) (xy 121.457179 -281.413716) (xy 121.480305 -281.461737) (xy 121.496015 -281.512667)
			(xy 121.503958 -281.565371) (xy 121.504456 -281.59202) (xy 121.503958 -281.618669) (xy 121.732538 -281.618669)
			(xy 121.732538 -281.565371) (xy 121.740481 -281.512667) (xy 121.756191 -281.461737) (xy 121.779317 -281.413716)
			(xy 121.809341 -281.369679) (xy 121.845593 -281.330608) (xy 121.887264 -281.297377) (xy 121.933422 -281.270728)
			(xy 121.983036 -281.251256) (xy 122.034998 -281.239396) (xy 122.088148 -281.235413) (xy 122.141298 -281.239396)
			(xy 122.19326 -281.251256) (xy 122.242874 -281.270728) (xy 122.289032 -281.297377) (xy 122.330703 -281.330608)
			(xy 122.366955 -281.369679) (xy 122.396979 -281.413716) (xy 122.420105 -281.461737) (xy 122.435815 -281.512667)
			(xy 122.443758 -281.565371) (xy 122.444256 -281.59202) (xy 122.443758 -281.618669) (xy 122.672338 -281.618669)
			(xy 122.672338 -281.565371) (xy 122.680281 -281.512667) (xy 122.695991 -281.461737) (xy 122.719117 -281.413716)
			(xy 122.749141 -281.369679) (xy 122.785393 -281.330608) (xy 122.827064 -281.297377) (xy 122.873222 -281.270728)
			(xy 122.922836 -281.251256) (xy 122.974798 -281.239396) (xy 123.027948 -281.235413) (xy 123.081098 -281.239396)
			(xy 123.13306 -281.251256) (xy 123.182674 -281.270728) (xy 123.228832 -281.297377) (xy 123.270503 -281.330608)
			(xy 123.306755 -281.369679) (xy 123.336779 -281.413716) (xy 123.359905 -281.461737) (xy 123.375615 -281.512667)
			(xy 123.383558 -281.565371) (xy 123.384056 -281.59202) (xy 123.383558 -281.618669) (xy 123.612138 -281.618669)
			(xy 123.612138 -281.565371) (xy 123.620081 -281.512667) (xy 123.635791 -281.461737) (xy 123.658917 -281.413716)
			(xy 123.688941 -281.369679) (xy 123.725193 -281.330608) (xy 123.766864 -281.297377) (xy 123.813022 -281.270728)
			(xy 123.862636 -281.251256) (xy 123.914598 -281.239396) (xy 123.967748 -281.235413) (xy 124.020898 -281.239396)
			(xy 124.07286 -281.251256) (xy 124.122474 -281.270728) (xy 124.168632 -281.297377) (xy 124.210303 -281.330608)
			(xy 124.246555 -281.369679) (xy 124.276579 -281.413716) (xy 124.299705 -281.461737) (xy 124.315415 -281.512667)
			(xy 124.323358 -281.565371) (xy 124.323856 -281.59202) (xy 124.323358 -281.618669) (xy 124.551938 -281.618669)
			(xy 124.551938 -281.565371) (xy 124.559881 -281.512667) (xy 124.575591 -281.461737) (xy 124.598717 -281.413716)
			(xy 124.628741 -281.369679) (xy 124.664993 -281.330608) (xy 124.706664 -281.297377) (xy 124.752822 -281.270728)
			(xy 124.802436 -281.251256) (xy 124.854398 -281.239396) (xy 124.907548 -281.235413) (xy 124.960698 -281.239396)
			(xy 125.01266 -281.251256) (xy 125.062274 -281.270728) (xy 125.108432 -281.297377) (xy 125.150103 -281.330608)
			(xy 125.186355 -281.369679) (xy 125.216379 -281.413716) (xy 125.239505 -281.461737) (xy 125.255215 -281.512667)
			(xy 125.263158 -281.565371) (xy 125.263656 -281.59202) (xy 125.263158 -281.618669) (xy 125.491738 -281.618669)
			(xy 125.491738 -281.565371) (xy 125.499681 -281.512667) (xy 125.515391 -281.461737) (xy 125.538517 -281.413716)
			(xy 125.568541 -281.369679) (xy 125.604793 -281.330608) (xy 125.646464 -281.297377) (xy 125.692622 -281.270728)
			(xy 125.742236 -281.251256) (xy 125.794198 -281.239396) (xy 125.847348 -281.235413) (xy 125.900498 -281.239396)
			(xy 125.95246 -281.251256) (xy 126.002074 -281.270728) (xy 126.048232 -281.297377) (xy 126.089903 -281.330608)
			(xy 126.126155 -281.369679) (xy 126.156179 -281.413716) (xy 126.179305 -281.461737) (xy 126.195015 -281.512667)
			(xy 126.202958 -281.565371) (xy 126.203456 -281.59202) (xy 126.202958 -281.618669) (xy 126.431284 -281.618669)
			(xy 126.431284 -281.565371) (xy 126.439227 -281.512667) (xy 126.454937 -281.461737) (xy 126.478063 -281.413716)
			(xy 126.508087 -281.369679) (xy 126.544339 -281.330608) (xy 126.58601 -281.297377) (xy 126.632168 -281.270728)
			(xy 126.681782 -281.251256) (xy 126.733744 -281.239396) (xy 126.786894 -281.235413) (xy 126.840044 -281.239396)
			(xy 126.892006 -281.251256) (xy 126.94162 -281.270728) (xy 126.987778 -281.297377) (xy 127.029449 -281.330608)
			(xy 127.065701 -281.369679) (xy 127.095725 -281.413716) (xy 127.118851 -281.461737) (xy 127.134561 -281.512667)
			(xy 127.142504 -281.565371) (xy 127.143002 -281.59202) (xy 127.142509 -281.618415) (xy 127.371084 -281.618415)
			(xy 127.371084 -281.565117) (xy 127.379027 -281.512413) (xy 127.394737 -281.461483) (xy 127.417863 -281.413462)
			(xy 127.447887 -281.369425) (xy 127.484139 -281.330354) (xy 127.52581 -281.297123) (xy 127.571968 -281.270474)
			(xy 127.621582 -281.251002) (xy 127.673544 -281.239142) (xy 127.726694 -281.235159) (xy 127.779844 -281.239142)
			(xy 127.831806 -281.251002) (xy 127.88142 -281.270474) (xy 127.927578 -281.297123) (xy 127.969249 -281.330354)
			(xy 128.005501 -281.369425) (xy 128.035525 -281.413462) (xy 128.058651 -281.461483) (xy 128.074361 -281.512413)
			(xy 128.082304 -281.565117) (xy 128.082802 -281.591766) (xy 128.082304 -281.618415) (xy 128.082266 -281.618669)
			(xy 128.311138 -281.618669) (xy 128.311138 -281.565371) (xy 128.319081 -281.512667) (xy 128.334791 -281.461737)
			(xy 128.357917 -281.413716) (xy 128.387941 -281.369679) (xy 128.424193 -281.330608) (xy 128.465864 -281.297377)
			(xy 128.512022 -281.270728) (xy 128.561636 -281.251256) (xy 128.613598 -281.239396) (xy 128.666748 -281.235413)
			(xy 128.719898 -281.239396) (xy 128.77186 -281.251256) (xy 128.821474 -281.270728) (xy 128.867632 -281.297377)
			(xy 128.909303 -281.330608) (xy 128.945555 -281.369679) (xy 128.975579 -281.413716) (xy 128.998705 -281.461737)
			(xy 129.014415 -281.512667) (xy 129.022358 -281.565371) (xy 129.022856 -281.59202) (xy 129.022358 -281.618669)
			(xy 129.250684 -281.618669) (xy 129.250684 -281.565371) (xy 129.258627 -281.512667) (xy 129.274337 -281.461737)
			(xy 129.297463 -281.413716) (xy 129.327487 -281.369679) (xy 129.363739 -281.330608) (xy 129.40541 -281.297377)
			(xy 129.451568 -281.270728) (xy 129.501182 -281.251256) (xy 129.553144 -281.239396) (xy 129.606294 -281.235413)
			(xy 129.659444 -281.239396) (xy 129.711406 -281.251256) (xy 129.76102 -281.270728) (xy 129.807178 -281.297377)
			(xy 129.848849 -281.330608) (xy 129.885101 -281.369679) (xy 129.915125 -281.413716) (xy 129.938251 -281.461737)
			(xy 129.953961 -281.512667) (xy 129.961904 -281.565371) (xy 129.962402 -281.59202) (xy 129.961904 -281.618669)
			(xy 130.190738 -281.618669) (xy 130.190738 -281.565371) (xy 130.198681 -281.512667) (xy 130.214391 -281.461737)
			(xy 130.237517 -281.413716) (xy 130.267541 -281.369679) (xy 130.303793 -281.330608) (xy 130.345464 -281.297377)
			(xy 130.391622 -281.270728) (xy 130.441236 -281.251256) (xy 130.493198 -281.239396) (xy 130.546348 -281.235413)
			(xy 130.599498 -281.239396) (xy 130.65146 -281.251256) (xy 130.701074 -281.270728) (xy 130.747232 -281.297377)
			(xy 130.788903 -281.330608) (xy 130.825155 -281.369679) (xy 130.855179 -281.413716) (xy 130.878305 -281.461737)
			(xy 130.894015 -281.512667) (xy 130.901958 -281.565371) (xy 130.902456 -281.59202) (xy 130.901958 -281.618669)
			(xy 131.130538 -281.618669) (xy 131.130538 -281.565371) (xy 131.138481 -281.512667) (xy 131.154191 -281.461737)
			(xy 131.177317 -281.413716) (xy 131.207341 -281.369679) (xy 131.243593 -281.330608) (xy 131.285264 -281.297377)
			(xy 131.331422 -281.270728) (xy 131.381036 -281.251256) (xy 131.432998 -281.239396) (xy 131.486148 -281.235413)
			(xy 131.539298 -281.239396) (xy 131.59126 -281.251256) (xy 131.640874 -281.270728) (xy 131.687032 -281.297377)
			(xy 131.728703 -281.330608) (xy 131.764955 -281.369679) (xy 131.794979 -281.413716) (xy 131.818105 -281.461737)
			(xy 131.833815 -281.512667) (xy 131.841758 -281.565371) (xy 131.842256 -281.59202) (xy 131.841758 -281.618669)
			(xy 132.070338 -281.618669) (xy 132.070338 -281.565371) (xy 132.078281 -281.512667) (xy 132.093991 -281.461737)
			(xy 132.117117 -281.413716) (xy 132.147141 -281.369679) (xy 132.183393 -281.330608) (xy 132.225064 -281.297377)
			(xy 132.271222 -281.270728) (xy 132.320836 -281.251256) (xy 132.372798 -281.239396) (xy 132.425948 -281.235413)
			(xy 132.479098 -281.239396) (xy 132.53106 -281.251256) (xy 132.580674 -281.270728) (xy 132.626832 -281.297377)
			(xy 132.668503 -281.330608) (xy 132.704755 -281.369679) (xy 132.734779 -281.413716) (xy 132.757905 -281.461737)
			(xy 132.773615 -281.512667) (xy 132.781558 -281.565371) (xy 132.782056 -281.59202) (xy 132.781558 -281.618669)
			(xy 133.010138 -281.618669) (xy 133.010138 -281.565371) (xy 133.018081 -281.512667) (xy 133.033791 -281.461737)
			(xy 133.056917 -281.413716) (xy 133.086941 -281.369679) (xy 133.123193 -281.330608) (xy 133.164864 -281.297377)
			(xy 133.211022 -281.270728) (xy 133.260636 -281.251256) (xy 133.312598 -281.239396) (xy 133.365748 -281.235413)
			(xy 133.418898 -281.239396) (xy 133.47086 -281.251256) (xy 133.520474 -281.270728) (xy 133.566632 -281.297377)
			(xy 133.608303 -281.330608) (xy 133.644555 -281.369679) (xy 133.674579 -281.413716) (xy 133.697705 -281.461737)
			(xy 133.713415 -281.512667) (xy 133.721358 -281.565371) (xy 133.721856 -281.59202) (xy 133.721358 -281.618669)
			(xy 133.949938 -281.618669) (xy 133.949938 -281.565371) (xy 133.957881 -281.512667) (xy 133.973591 -281.461737)
			(xy 133.996717 -281.413716) (xy 134.026741 -281.369679) (xy 134.062993 -281.330608) (xy 134.104664 -281.297377)
			(xy 134.150822 -281.270728) (xy 134.200436 -281.251256) (xy 134.252398 -281.239396) (xy 134.305548 -281.235413)
			(xy 134.358698 -281.239396) (xy 134.41066 -281.251256) (xy 134.460274 -281.270728) (xy 134.506432 -281.297377)
			(xy 134.548103 -281.330608) (xy 134.584355 -281.369679) (xy 134.614379 -281.413716) (xy 134.637505 -281.461737)
			(xy 134.653215 -281.512667) (xy 134.661158 -281.565371) (xy 134.661656 -281.59202) (xy 134.661158 -281.618669)
			(xy 134.889484 -281.618669) (xy 134.889484 -281.565371) (xy 134.897427 -281.512667) (xy 134.913137 -281.461737)
			(xy 134.936263 -281.413716) (xy 134.966287 -281.369679) (xy 135.002539 -281.330608) (xy 135.04421 -281.297377)
			(xy 135.090368 -281.270728) (xy 135.139982 -281.251256) (xy 135.191944 -281.239396) (xy 135.245094 -281.235413)
			(xy 135.298244 -281.239396) (xy 135.350206 -281.251256) (xy 135.39982 -281.270728) (xy 135.445978 -281.297377)
			(xy 135.487649 -281.330608) (xy 135.523901 -281.369679) (xy 135.553925 -281.413716) (xy 135.577051 -281.461737)
			(xy 135.592761 -281.512667) (xy 135.600704 -281.565371) (xy 135.601202 -281.59202) (xy 135.600704 -281.618669)
			(xy 135.829284 -281.618669) (xy 135.829284 -281.565371) (xy 135.837227 -281.512667) (xy 135.852937 -281.461737)
			(xy 135.876063 -281.413716) (xy 135.906087 -281.369679) (xy 135.942339 -281.330608) (xy 135.98401 -281.297377)
			(xy 136.030168 -281.270728) (xy 136.079782 -281.251256) (xy 136.131744 -281.239396) (xy 136.184894 -281.235413)
			(xy 136.238044 -281.239396) (xy 136.290006 -281.251256) (xy 136.33962 -281.270728) (xy 136.385778 -281.297377)
			(xy 136.427449 -281.330608) (xy 136.463701 -281.369679) (xy 136.493725 -281.413716) (xy 136.516851 -281.461737)
			(xy 136.532561 -281.512667) (xy 136.540504 -281.565371) (xy 136.541002 -281.59202) (xy 136.540504 -281.618669)
			(xy 136.769084 -281.618669) (xy 136.769084 -281.565371) (xy 136.777027 -281.512667) (xy 136.792737 -281.461737)
			(xy 136.815863 -281.413716) (xy 136.845887 -281.369679) (xy 136.882139 -281.330608) (xy 136.92381 -281.297377)
			(xy 136.969968 -281.270728) (xy 137.019582 -281.251256) (xy 137.071544 -281.239396) (xy 137.124694 -281.235413)
			(xy 137.177844 -281.239396) (xy 137.229806 -281.251256) (xy 137.27942 -281.270728) (xy 137.325578 -281.297377)
			(xy 137.367249 -281.330608) (xy 137.403501 -281.369679) (xy 137.433525 -281.413716) (xy 137.456651 -281.461737)
			(xy 137.472361 -281.512667) (xy 137.480304 -281.565371) (xy 137.480802 -281.59202) (xy 137.480304 -281.618669)
			(xy 137.708884 -281.618669) (xy 137.708884 -281.565371) (xy 137.716827 -281.512667) (xy 137.732537 -281.461737)
			(xy 137.755663 -281.413716) (xy 137.785687 -281.369679) (xy 137.821939 -281.330608) (xy 137.86361 -281.297377)
			(xy 137.909768 -281.270728) (xy 137.959382 -281.251256) (xy 138.011344 -281.239396) (xy 138.064494 -281.235413)
			(xy 138.117644 -281.239396) (xy 138.169606 -281.251256) (xy 138.21922 -281.270728) (xy 138.265378 -281.297377)
			(xy 138.307049 -281.330608) (xy 138.343301 -281.369679) (xy 138.373325 -281.413716) (xy 138.396451 -281.461737)
			(xy 138.412161 -281.512667) (xy 138.420104 -281.565371) (xy 138.420602 -281.59202) (xy 138.420104 -281.618669)
			(xy 138.412161 -281.671373) (xy 138.396451 -281.722303) (xy 138.373325 -281.770324) (xy 138.343301 -281.814361)
			(xy 138.307049 -281.853432) (xy 138.265378 -281.886663) (xy 138.21922 -281.913312) (xy 138.169606 -281.932784)
			(xy 138.117644 -281.944644) (xy 138.064494 -281.948628) (xy 138.011344 -281.944644) (xy 137.959382 -281.932784)
			(xy 137.909768 -281.913312) (xy 137.86361 -281.886663) (xy 137.821939 -281.853432) (xy 137.785687 -281.814361)
			(xy 137.755663 -281.770324) (xy 137.732537 -281.722303) (xy 137.716827 -281.671373) (xy 137.708884 -281.618669)
			(xy 137.480304 -281.618669) (xy 137.472361 -281.671373) (xy 137.456651 -281.722303) (xy 137.433525 -281.770324)
			(xy 137.403501 -281.814361) (xy 137.367249 -281.853432) (xy 137.325578 -281.886663) (xy 137.27942 -281.913312)
			(xy 137.229806 -281.932784) (xy 137.177844 -281.944644) (xy 137.124694 -281.948628) (xy 137.071544 -281.944644)
			(xy 137.019582 -281.932784) (xy 136.969968 -281.913312) (xy 136.92381 -281.886663) (xy 136.882139 -281.853432)
			(xy 136.845887 -281.814361) (xy 136.815863 -281.770324) (xy 136.792737 -281.722303) (xy 136.777027 -281.671373)
			(xy 136.769084 -281.618669) (xy 136.540504 -281.618669) (xy 136.532561 -281.671373) (xy 136.516851 -281.722303)
			(xy 136.493725 -281.770324) (xy 136.463701 -281.814361) (xy 136.427449 -281.853432) (xy 136.385778 -281.886663)
			(xy 136.33962 -281.913312) (xy 136.290006 -281.932784) (xy 136.238044 -281.944644) (xy 136.184894 -281.948628)
			(xy 136.131744 -281.944644) (xy 136.079782 -281.932784) (xy 136.030168 -281.913312) (xy 135.98401 -281.886663)
			(xy 135.942339 -281.853432) (xy 135.906087 -281.814361) (xy 135.876063 -281.770324) (xy 135.852937 -281.722303)
			(xy 135.837227 -281.671373) (xy 135.829284 -281.618669) (xy 135.600704 -281.618669) (xy 135.592761 -281.671373)
			(xy 135.577051 -281.722303) (xy 135.553925 -281.770324) (xy 135.523901 -281.814361) (xy 135.487649 -281.853432)
			(xy 135.445978 -281.886663) (xy 135.39982 -281.913312) (xy 135.350206 -281.932784) (xy 135.298244 -281.944644)
			(xy 135.245094 -281.948628) (xy 135.191944 -281.944644) (xy 135.139982 -281.932784) (xy 135.090368 -281.913312)
			(xy 135.04421 -281.886663) (xy 135.002539 -281.853432) (xy 134.966287 -281.814361) (xy 134.936263 -281.770324)
			(xy 134.913137 -281.722303) (xy 134.897427 -281.671373) (xy 134.889484 -281.618669) (xy 134.661158 -281.618669)
			(xy 134.653215 -281.671373) (xy 134.637505 -281.722303) (xy 134.614379 -281.770324) (xy 134.584355 -281.814361)
			(xy 134.548103 -281.853432) (xy 134.506432 -281.886663) (xy 134.460274 -281.913312) (xy 134.41066 -281.932784)
			(xy 134.358698 -281.944644) (xy 134.305548 -281.948628) (xy 134.252398 -281.944644) (xy 134.200436 -281.932784)
			(xy 134.150822 -281.913312) (xy 134.104664 -281.886663) (xy 134.062993 -281.853432) (xy 134.026741 -281.814361)
			(xy 133.996717 -281.770324) (xy 133.973591 -281.722303) (xy 133.957881 -281.671373) (xy 133.949938 -281.618669)
			(xy 133.721358 -281.618669) (xy 133.713415 -281.671373) (xy 133.697705 -281.722303) (xy 133.674579 -281.770324)
			(xy 133.644555 -281.814361) (xy 133.608303 -281.853432) (xy 133.566632 -281.886663) (xy 133.520474 -281.913312)
			(xy 133.47086 -281.932784) (xy 133.418898 -281.944644) (xy 133.365748 -281.948628) (xy 133.312598 -281.944644)
			(xy 133.260636 -281.932784) (xy 133.211022 -281.913312) (xy 133.164864 -281.886663) (xy 133.123193 -281.853432)
			(xy 133.086941 -281.814361) (xy 133.056917 -281.770324) (xy 133.033791 -281.722303) (xy 133.018081 -281.671373)
			(xy 133.010138 -281.618669) (xy 132.781558 -281.618669) (xy 132.773615 -281.671373) (xy 132.757905 -281.722303)
			(xy 132.734779 -281.770324) (xy 132.704755 -281.814361) (xy 132.668503 -281.853432) (xy 132.626832 -281.886663)
			(xy 132.580674 -281.913312) (xy 132.53106 -281.932784) (xy 132.479098 -281.944644) (xy 132.425948 -281.948628)
			(xy 132.372798 -281.944644) (xy 132.320836 -281.932784) (xy 132.271222 -281.913312) (xy 132.225064 -281.886663)
			(xy 132.183393 -281.853432) (xy 132.147141 -281.814361) (xy 132.117117 -281.770324) (xy 132.093991 -281.722303)
			(xy 132.078281 -281.671373) (xy 132.070338 -281.618669) (xy 131.841758 -281.618669) (xy 131.833815 -281.671373)
			(xy 131.818105 -281.722303) (xy 131.794979 -281.770324) (xy 131.764955 -281.814361) (xy 131.728703 -281.853432)
			(xy 131.687032 -281.886663) (xy 131.640874 -281.913312) (xy 131.59126 -281.932784) (xy 131.539298 -281.944644)
			(xy 131.486148 -281.948628) (xy 131.432998 -281.944644) (xy 131.381036 -281.932784) (xy 131.331422 -281.913312)
			(xy 131.285264 -281.886663) (xy 131.243593 -281.853432) (xy 131.207341 -281.814361) (xy 131.177317 -281.770324)
			(xy 131.154191 -281.722303) (xy 131.138481 -281.671373) (xy 131.130538 -281.618669) (xy 130.901958 -281.618669)
			(xy 130.894015 -281.671373) (xy 130.878305 -281.722303) (xy 130.855179 -281.770324) (xy 130.825155 -281.814361)
			(xy 130.788903 -281.853432) (xy 130.747232 -281.886663) (xy 130.701074 -281.913312) (xy 130.65146 -281.932784)
			(xy 130.599498 -281.944644) (xy 130.546348 -281.948628) (xy 130.493198 -281.944644) (xy 130.441236 -281.932784)
			(xy 130.391622 -281.913312) (xy 130.345464 -281.886663) (xy 130.303793 -281.853432) (xy 130.267541 -281.814361)
			(xy 130.237517 -281.770324) (xy 130.214391 -281.722303) (xy 130.198681 -281.671373) (xy 130.190738 -281.618669)
			(xy 129.961904 -281.618669) (xy 129.953961 -281.671373) (xy 129.938251 -281.722303) (xy 129.915125 -281.770324)
			(xy 129.885101 -281.814361) (xy 129.848849 -281.853432) (xy 129.807178 -281.886663) (xy 129.76102 -281.913312)
			(xy 129.711406 -281.932784) (xy 129.659444 -281.944644) (xy 129.606294 -281.948628) (xy 129.553144 -281.944644)
			(xy 129.501182 -281.932784) (xy 129.451568 -281.913312) (xy 129.40541 -281.886663) (xy 129.363739 -281.853432)
			(xy 129.327487 -281.814361) (xy 129.297463 -281.770324) (xy 129.274337 -281.722303) (xy 129.258627 -281.671373)
			(xy 129.250684 -281.618669) (xy 129.022358 -281.618669) (xy 129.014415 -281.671373) (xy 128.998705 -281.722303)
			(xy 128.975579 -281.770324) (xy 128.945555 -281.814361) (xy 128.909303 -281.853432) (xy 128.867632 -281.886663)
			(xy 128.821474 -281.913312) (xy 128.77186 -281.932784) (xy 128.719898 -281.944644) (xy 128.666748 -281.948628)
			(xy 128.613598 -281.944644) (xy 128.561636 -281.932784) (xy 128.512022 -281.913312) (xy 128.465864 -281.886663)
			(xy 128.424193 -281.853432) (xy 128.387941 -281.814361) (xy 128.357917 -281.770324) (xy 128.334791 -281.722303)
			(xy 128.319081 -281.671373) (xy 128.311138 -281.618669) (xy 128.082266 -281.618669) (xy 128.074361 -281.671119)
			(xy 128.058651 -281.722049) (xy 128.035525 -281.77007) (xy 128.005501 -281.814107) (xy 127.969249 -281.853178)
			(xy 127.927578 -281.886409) (xy 127.88142 -281.913058) (xy 127.831806 -281.93253) (xy 127.779844 -281.94439)
			(xy 127.726694 -281.948374) (xy 127.673544 -281.94439) (xy 127.621582 -281.93253) (xy 127.571968 -281.913058)
			(xy 127.52581 -281.886409) (xy 127.484139 -281.853178) (xy 127.447887 -281.814107) (xy 127.417863 -281.77007)
			(xy 127.394737 -281.722049) (xy 127.379027 -281.671119) (xy 127.371084 -281.618415) (xy 127.142509 -281.618415)
			(xy 127.142504 -281.618669) (xy 127.134561 -281.671373) (xy 127.118851 -281.722303) (xy 127.095725 -281.770324)
			(xy 127.065701 -281.814361) (xy 127.029449 -281.853432) (xy 126.987778 -281.886663) (xy 126.94162 -281.913312)
			(xy 126.892006 -281.932784) (xy 126.840044 -281.944644) (xy 126.786894 -281.948628) (xy 126.733744 -281.944644)
			(xy 126.681782 -281.932784) (xy 126.632168 -281.913312) (xy 126.58601 -281.886663) (xy 126.544339 -281.853432)
			(xy 126.508087 -281.814361) (xy 126.478063 -281.770324) (xy 126.454937 -281.722303) (xy 126.439227 -281.671373)
			(xy 126.431284 -281.618669) (xy 126.202958 -281.618669) (xy 126.195015 -281.671373) (xy 126.179305 -281.722303)
			(xy 126.156179 -281.770324) (xy 126.126155 -281.814361) (xy 126.089903 -281.853432) (xy 126.048232 -281.886663)
			(xy 126.002074 -281.913312) (xy 125.95246 -281.932784) (xy 125.900498 -281.944644) (xy 125.847348 -281.948628)
			(xy 125.794198 -281.944644) (xy 125.742236 -281.932784) (xy 125.692622 -281.913312) (xy 125.646464 -281.886663)
			(xy 125.604793 -281.853432) (xy 125.568541 -281.814361) (xy 125.538517 -281.770324) (xy 125.515391 -281.722303)
			(xy 125.499681 -281.671373) (xy 125.491738 -281.618669) (xy 125.263158 -281.618669) (xy 125.255215 -281.671373)
			(xy 125.239505 -281.722303) (xy 125.216379 -281.770324) (xy 125.186355 -281.814361) (xy 125.150103 -281.853432)
			(xy 125.108432 -281.886663) (xy 125.062274 -281.913312) (xy 125.01266 -281.932784) (xy 124.960698 -281.944644)
			(xy 124.907548 -281.948628) (xy 124.854398 -281.944644) (xy 124.802436 -281.932784) (xy 124.752822 -281.913312)
			(xy 124.706664 -281.886663) (xy 124.664993 -281.853432) (xy 124.628741 -281.814361) (xy 124.598717 -281.770324)
			(xy 124.575591 -281.722303) (xy 124.559881 -281.671373) (xy 124.551938 -281.618669) (xy 124.323358 -281.618669)
			(xy 124.315415 -281.671373) (xy 124.299705 -281.722303) (xy 124.276579 -281.770324) (xy 124.246555 -281.814361)
			(xy 124.210303 -281.853432) (xy 124.168632 -281.886663) (xy 124.122474 -281.913312) (xy 124.07286 -281.932784)
			(xy 124.020898 -281.944644) (xy 123.967748 -281.948628) (xy 123.914598 -281.944644) (xy 123.862636 -281.932784)
			(xy 123.813022 -281.913312) (xy 123.766864 -281.886663) (xy 123.725193 -281.853432) (xy 123.688941 -281.814361)
			(xy 123.658917 -281.770324) (xy 123.635791 -281.722303) (xy 123.620081 -281.671373) (xy 123.612138 -281.618669)
			(xy 123.383558 -281.618669) (xy 123.375615 -281.671373) (xy 123.359905 -281.722303) (xy 123.336779 -281.770324)
			(xy 123.306755 -281.814361) (xy 123.270503 -281.853432) (xy 123.228832 -281.886663) (xy 123.182674 -281.913312)
			(xy 123.13306 -281.932784) (xy 123.081098 -281.944644) (xy 123.027948 -281.948628) (xy 122.974798 -281.944644)
			(xy 122.922836 -281.932784) (xy 122.873222 -281.913312) (xy 122.827064 -281.886663) (xy 122.785393 -281.853432)
			(xy 122.749141 -281.814361) (xy 122.719117 -281.770324) (xy 122.695991 -281.722303) (xy 122.680281 -281.671373)
			(xy 122.672338 -281.618669) (xy 122.443758 -281.618669) (xy 122.435815 -281.671373) (xy 122.420105 -281.722303)
			(xy 122.396979 -281.770324) (xy 122.366955 -281.814361) (xy 122.330703 -281.853432) (xy 122.289032 -281.886663)
			(xy 122.242874 -281.913312) (xy 122.19326 -281.932784) (xy 122.141298 -281.944644) (xy 122.088148 -281.948628)
			(xy 122.034998 -281.944644) (xy 121.983036 -281.932784) (xy 121.933422 -281.913312) (xy 121.887264 -281.886663)
			(xy 121.845593 -281.853432) (xy 121.809341 -281.814361) (xy 121.779317 -281.770324) (xy 121.756191 -281.722303)
			(xy 121.740481 -281.671373) (xy 121.732538 -281.618669) (xy 121.503958 -281.618669) (xy 121.496015 -281.671373)
			(xy 121.480305 -281.722303) (xy 121.457179 -281.770324) (xy 121.427155 -281.814361) (xy 121.390903 -281.853432)
			(xy 121.349232 -281.886663) (xy 121.303074 -281.913312) (xy 121.25346 -281.932784) (xy 121.201498 -281.944644)
			(xy 121.148348 -281.948628) (xy 121.095198 -281.944644) (xy 121.043236 -281.932784) (xy 120.993622 -281.913312)
			(xy 120.947464 -281.886663) (xy 120.905793 -281.853432) (xy 120.869541 -281.814361) (xy 120.839517 -281.770324)
			(xy 120.816391 -281.722303) (xy 120.800681 -281.671373) (xy 120.792738 -281.618669) (xy 120.564158 -281.618669)
			(xy 120.556215 -281.671373) (xy 120.540505 -281.722303) (xy 120.517379 -281.770324) (xy 120.487355 -281.814361)
			(xy 120.451103 -281.853432) (xy 120.409432 -281.886663) (xy 120.363274 -281.913312) (xy 120.31366 -281.932784)
			(xy 120.261698 -281.944644) (xy 120.208548 -281.948628) (xy 120.155398 -281.944644) (xy 120.103436 -281.932784)
			(xy 120.053822 -281.913312) (xy 120.007664 -281.886663) (xy 119.965993 -281.853432) (xy 119.929741 -281.814361)
			(xy 119.899717 -281.770324) (xy 119.876591 -281.722303) (xy 119.860881 -281.671373) (xy 119.852938 -281.618669)
			(xy 119.624358 -281.618669) (xy 119.616415 -281.671373) (xy 119.600705 -281.722303) (xy 119.577579 -281.770324)
			(xy 119.547555 -281.814361) (xy 119.511303 -281.853432) (xy 119.469632 -281.886663) (xy 119.423474 -281.913312)
			(xy 119.37386 -281.932784) (xy 119.321898 -281.944644) (xy 119.268748 -281.948628) (xy 119.215598 -281.944644)
			(xy 119.163636 -281.932784) (xy 119.114022 -281.913312) (xy 119.067864 -281.886663) (xy 119.026193 -281.853432)
			(xy 118.989941 -281.814361) (xy 118.959917 -281.770324) (xy 118.936791 -281.722303) (xy 118.921081 -281.671373)
			(xy 118.913138 -281.618669) (xy 118.684304 -281.618669) (xy 118.676361 -281.671373) (xy 118.660651 -281.722303)
			(xy 118.637525 -281.770324) (xy 118.607501 -281.814361) (xy 118.571249 -281.853432) (xy 118.529578 -281.886663)
			(xy 118.48342 -281.913312) (xy 118.433806 -281.932784) (xy 118.381844 -281.944644) (xy 118.328694 -281.948628)
			(xy 118.275544 -281.944644) (xy 118.223582 -281.932784) (xy 118.173968 -281.913312) (xy 118.12781 -281.886663)
			(xy 118.086139 -281.853432) (xy 118.049887 -281.814361) (xy 118.019863 -281.770324) (xy 117.996737 -281.722303)
			(xy 117.981027 -281.671373) (xy 117.973084 -281.618669) (xy 117.744758 -281.618669) (xy 117.736815 -281.671373)
			(xy 117.721105 -281.722303) (xy 117.697979 -281.770324) (xy 117.667955 -281.814361) (xy 117.631703 -281.853432)
			(xy 117.590032 -281.886663) (xy 117.543874 -281.913312) (xy 117.49426 -281.932784) (xy 117.442298 -281.944644)
			(xy 117.389148 -281.948628) (xy 117.335998 -281.944644) (xy 117.284036 -281.932784) (xy 117.234422 -281.913312)
			(xy 117.188264 -281.886663) (xy 117.146593 -281.853432) (xy 117.110341 -281.814361) (xy 117.080317 -281.770324)
			(xy 117.057191 -281.722303) (xy 117.041481 -281.671373) (xy 117.033538 -281.618669) (xy 113.985304 -281.618669)
			(xy 113.977361 -281.671373) (xy 113.961651 -281.722303) (xy 113.938525 -281.770324) (xy 113.908501 -281.814361)
			(xy 113.872249 -281.853432) (xy 113.830578 -281.886663) (xy 113.78442 -281.913312) (xy 113.734806 -281.932784)
			(xy 113.682844 -281.944644) (xy 113.629694 -281.948628) (xy 113.576544 -281.944644) (xy 113.524582 -281.932784)
			(xy 113.474968 -281.913312) (xy 113.42881 -281.886663) (xy 113.387139 -281.853432) (xy 113.350887 -281.814361)
			(xy 113.320863 -281.770324) (xy 113.297737 -281.722303) (xy 113.282027 -281.671373) (xy 113.274084 -281.618669)
			(xy 107.406958 -281.618669) (xy 107.399015 -281.671373) (xy 107.383305 -281.722303) (xy 107.360179 -281.770324)
			(xy 107.330155 -281.814361) (xy 107.293903 -281.853432) (xy 107.252232 -281.886663) (xy 107.206074 -281.913312)
			(xy 107.15646 -281.932784) (xy 107.104498 -281.944644) (xy 107.051348 -281.948628) (xy 106.998198 -281.944644)
			(xy 106.946236 -281.932784) (xy 106.896622 -281.913312) (xy 106.850464 -281.886663) (xy 106.808793 -281.853432)
			(xy 106.772541 -281.814361) (xy 106.742517 -281.770324) (xy 106.719391 -281.722303) (xy 106.703681 -281.671373)
			(xy 106.695738 -281.618669) (xy 106.440693 -281.618669) (xy 106.44067 -281.619802) (xy 106.431345 -281.674578)
			(xy 106.422698 -281.700986) (xy 106.414824 -281.72283) (xy 106.619802 -282.077668) (xy 106.642662 -282.081986)
			(xy 106.667464 -282.087182) (xy 106.715205 -282.104167) (xy 106.759784 -282.128258) (xy 106.800151 -282.158887)
			(xy 106.835356 -282.195333) (xy 106.864568 -282.236737) (xy 106.8871 -282.282123) (xy 106.902422 -282.330424)
			(xy 106.910171 -282.3805) (xy 106.910632 -282.405836) (xy 106.910124 -282.431723) (xy 106.910003 -282.432485)
			(xy 107.165384 -282.432485) (xy 107.165384 -282.379187) (xy 107.173327 -282.326483) (xy 107.189037 -282.275553)
			(xy 107.212163 -282.227532) (xy 107.242187 -282.183495) (xy 107.278439 -282.144424) (xy 107.32011 -282.111193)
			(xy 107.366268 -282.084544) (xy 107.415882 -282.065072) (xy 107.467844 -282.053212) (xy 107.520994 -282.049229)
			(xy 107.574144 -282.053212) (xy 107.626106 -282.065072) (xy 107.67572 -282.084544) (xy 107.721878 -282.111193)
			(xy 107.763549 -282.144424) (xy 107.799801 -282.183495) (xy 107.829825 -282.227532) (xy 107.852951 -282.275553)
			(xy 107.868661 -282.326483) (xy 107.876604 -282.379187) (xy 107.877102 -282.405836) (xy 107.876604 -282.432485)
			(xy 109.984784 -282.432485) (xy 109.984784 -282.379187) (xy 109.992727 -282.326483) (xy 110.008437 -282.275553)
			(xy 110.031563 -282.227532) (xy 110.061587 -282.183495) (xy 110.097839 -282.144424) (xy 110.13951 -282.111193)
			(xy 110.185668 -282.084544) (xy 110.235282 -282.065072) (xy 110.287244 -282.053212) (xy 110.340394 -282.049229)
			(xy 110.393544 -282.053212) (xy 110.445506 -282.065072) (xy 110.49512 -282.084544) (xy 110.541278 -282.111193)
			(xy 110.582949 -282.144424) (xy 110.619201 -282.183495) (xy 110.649225 -282.227532) (xy 110.672351 -282.275553)
			(xy 110.688061 -282.326483) (xy 110.696004 -282.379187) (xy 110.696502 -282.405836) (xy 110.696004 -282.432485)
			(xy 117.503438 -282.432485) (xy 117.503438 -282.379187) (xy 117.511381 -282.326483) (xy 117.527091 -282.275553)
			(xy 117.550217 -282.227532) (xy 117.580241 -282.183495) (xy 117.616493 -282.144424) (xy 117.658164 -282.111193)
			(xy 117.704322 -282.084544) (xy 117.753936 -282.065072) (xy 117.805898 -282.053212) (xy 117.859048 -282.049229)
			(xy 117.912198 -282.053212) (xy 117.96416 -282.065072) (xy 118.013774 -282.084544) (xy 118.059932 -282.111193)
			(xy 118.101603 -282.144424) (xy 118.137855 -282.183495) (xy 118.167879 -282.227532) (xy 118.191005 -282.275553)
			(xy 118.206715 -282.326483) (xy 118.214658 -282.379187) (xy 118.215156 -282.405836) (xy 118.214658 -282.432485)
			(xy 118.442984 -282.432485) (xy 118.442984 -282.379187) (xy 118.450927 -282.326483) (xy 118.466637 -282.275553)
			(xy 118.489763 -282.227532) (xy 118.519787 -282.183495) (xy 118.556039 -282.144424) (xy 118.59771 -282.111193)
			(xy 118.643868 -282.084544) (xy 118.693482 -282.065072) (xy 118.745444 -282.053212) (xy 118.798594 -282.049229)
			(xy 118.851744 -282.053212) (xy 118.903706 -282.065072) (xy 118.95332 -282.084544) (xy 118.999478 -282.111193)
			(xy 119.041149 -282.144424) (xy 119.077401 -282.183495) (xy 119.107425 -282.227532) (xy 119.130551 -282.275553)
			(xy 119.146261 -282.326483) (xy 119.154204 -282.379187) (xy 119.154702 -282.405836) (xy 119.154204 -282.432485)
			(xy 119.382784 -282.432485) (xy 119.382784 -282.379187) (xy 119.390727 -282.326483) (xy 119.406437 -282.275553)
			(xy 119.429563 -282.227532) (xy 119.459587 -282.183495) (xy 119.495839 -282.144424) (xy 119.53751 -282.111193)
			(xy 119.583668 -282.084544) (xy 119.633282 -282.065072) (xy 119.685244 -282.053212) (xy 119.738394 -282.049229)
			(xy 119.791544 -282.053212) (xy 119.843506 -282.065072) (xy 119.89312 -282.084544) (xy 119.939278 -282.111193)
			(xy 119.980949 -282.144424) (xy 120.017201 -282.183495) (xy 120.047225 -282.227532) (xy 120.070351 -282.275553)
			(xy 120.086061 -282.326483) (xy 120.094004 -282.379187) (xy 120.094502 -282.405836) (xy 120.094004 -282.432485)
			(xy 120.322584 -282.432485) (xy 120.322584 -282.379187) (xy 120.330527 -282.326483) (xy 120.346237 -282.275553)
			(xy 120.369363 -282.227532) (xy 120.399387 -282.183495) (xy 120.435639 -282.144424) (xy 120.47731 -282.111193)
			(xy 120.523468 -282.084544) (xy 120.573082 -282.065072) (xy 120.625044 -282.053212) (xy 120.678194 -282.049229)
			(xy 120.731344 -282.053212) (xy 120.783306 -282.065072) (xy 120.83292 -282.084544) (xy 120.879078 -282.111193)
			(xy 120.920749 -282.144424) (xy 120.957001 -282.183495) (xy 120.987025 -282.227532) (xy 121.010151 -282.275553)
			(xy 121.025861 -282.326483) (xy 121.033804 -282.379187) (xy 121.034302 -282.405836) (xy 121.033804 -282.432485)
			(xy 121.262384 -282.432485) (xy 121.262384 -282.379187) (xy 121.270327 -282.326483) (xy 121.286037 -282.275553)
			(xy 121.309163 -282.227532) (xy 121.339187 -282.183495) (xy 121.375439 -282.144424) (xy 121.41711 -282.111193)
			(xy 121.463268 -282.084544) (xy 121.512882 -282.065072) (xy 121.564844 -282.053212) (xy 121.617994 -282.049229)
			(xy 121.671144 -282.053212) (xy 121.723106 -282.065072) (xy 121.77272 -282.084544) (xy 121.818878 -282.111193)
			(xy 121.860549 -282.144424) (xy 121.896801 -282.183495) (xy 121.926825 -282.227532) (xy 121.949951 -282.275553)
			(xy 121.965661 -282.326483) (xy 121.973604 -282.379187) (xy 121.974102 -282.405836) (xy 121.973604 -282.432485)
			(xy 122.202184 -282.432485) (xy 122.202184 -282.379187) (xy 122.210127 -282.326483) (xy 122.225837 -282.275553)
			(xy 122.248963 -282.227532) (xy 122.278987 -282.183495) (xy 122.315239 -282.144424) (xy 122.35691 -282.111193)
			(xy 122.403068 -282.084544) (xy 122.452682 -282.065072) (xy 122.504644 -282.053212) (xy 122.557794 -282.049229)
			(xy 122.610944 -282.053212) (xy 122.662906 -282.065072) (xy 122.71252 -282.084544) (xy 122.758678 -282.111193)
			(xy 122.800349 -282.144424) (xy 122.836601 -282.183495) (xy 122.866625 -282.227532) (xy 122.889751 -282.275553)
			(xy 122.905461 -282.326483) (xy 122.913404 -282.379187) (xy 122.913902 -282.405836) (xy 122.913404 -282.432485)
			(xy 123.141984 -282.432485) (xy 123.141984 -282.379187) (xy 123.149927 -282.326483) (xy 123.165637 -282.275553)
			(xy 123.188763 -282.227532) (xy 123.218787 -282.183495) (xy 123.255039 -282.144424) (xy 123.29671 -282.111193)
			(xy 123.342868 -282.084544) (xy 123.392482 -282.065072) (xy 123.444444 -282.053212) (xy 123.497594 -282.049229)
			(xy 123.550744 -282.053212) (xy 123.602706 -282.065072) (xy 123.65232 -282.084544) (xy 123.698478 -282.111193)
			(xy 123.740149 -282.144424) (xy 123.776401 -282.183495) (xy 123.806425 -282.227532) (xy 123.829551 -282.275553)
			(xy 123.845261 -282.326483) (xy 123.853204 -282.379187) (xy 123.853702 -282.405836) (xy 123.853204 -282.432485)
			(xy 124.081784 -282.432485) (xy 124.081784 -282.379187) (xy 124.089727 -282.326483) (xy 124.105437 -282.275553)
			(xy 124.128563 -282.227532) (xy 124.158587 -282.183495) (xy 124.194839 -282.144424) (xy 124.23651 -282.111193)
			(xy 124.282668 -282.084544) (xy 124.332282 -282.065072) (xy 124.384244 -282.053212) (xy 124.437394 -282.049229)
			(xy 124.490544 -282.053212) (xy 124.542506 -282.065072) (xy 124.59212 -282.084544) (xy 124.638278 -282.111193)
			(xy 124.679949 -282.144424) (xy 124.716201 -282.183495) (xy 124.746225 -282.227532) (xy 124.769351 -282.275553)
			(xy 124.785061 -282.326483) (xy 124.793004 -282.379187) (xy 124.793502 -282.405836) (xy 124.793004 -282.432485)
			(xy 125.021584 -282.432485) (xy 125.021584 -282.379187) (xy 125.029527 -282.326483) (xy 125.045237 -282.275553)
			(xy 125.068363 -282.227532) (xy 125.098387 -282.183495) (xy 125.134639 -282.144424) (xy 125.17631 -282.111193)
			(xy 125.222468 -282.084544) (xy 125.272082 -282.065072) (xy 125.324044 -282.053212) (xy 125.377194 -282.049229)
			(xy 125.430344 -282.053212) (xy 125.482306 -282.065072) (xy 125.53192 -282.084544) (xy 125.578078 -282.111193)
			(xy 125.619749 -282.144424) (xy 125.656001 -282.183495) (xy 125.686025 -282.227532) (xy 125.709151 -282.275553)
			(xy 125.724861 -282.326483) (xy 125.732804 -282.379187) (xy 125.733302 -282.405836) (xy 125.732804 -282.432485)
			(xy 125.961638 -282.432485) (xy 125.961638 -282.379187) (xy 125.969581 -282.326483) (xy 125.985291 -282.275553)
			(xy 126.008417 -282.227532) (xy 126.038441 -282.183495) (xy 126.074693 -282.144424) (xy 126.116364 -282.111193)
			(xy 126.162522 -282.084544) (xy 126.212136 -282.065072) (xy 126.264098 -282.053212) (xy 126.317248 -282.049229)
			(xy 126.370398 -282.053212) (xy 126.42236 -282.065072) (xy 126.471974 -282.084544) (xy 126.518132 -282.111193)
			(xy 126.559803 -282.144424) (xy 126.596055 -282.183495) (xy 126.626079 -282.227532) (xy 126.649205 -282.275553)
			(xy 126.664915 -282.326483) (xy 126.672858 -282.379187) (xy 126.673356 -282.405836) (xy 126.672863 -282.432231)
			(xy 126.901438 -282.432231) (xy 126.901438 -282.378933) (xy 126.909381 -282.326229) (xy 126.925091 -282.275299)
			(xy 126.948217 -282.227278) (xy 126.978241 -282.183241) (xy 127.014493 -282.14417) (xy 127.056164 -282.110939)
			(xy 127.102322 -282.08429) (xy 127.151936 -282.064818) (xy 127.203898 -282.052958) (xy 127.257048 -282.048975)
			(xy 127.310198 -282.052958) (xy 127.36216 -282.064818) (xy 127.411774 -282.08429) (xy 127.457932 -282.110939)
			(xy 127.499603 -282.14417) (xy 127.535855 -282.183241) (xy 127.565879 -282.227278) (xy 127.589005 -282.275299)
			(xy 127.604715 -282.326229) (xy 127.612658 -282.378933) (xy 127.613156 -282.405582) (xy 127.612658 -282.432231)
			(xy 127.841238 -282.432231) (xy 127.841238 -282.378933) (xy 127.849181 -282.326229) (xy 127.864891 -282.275299)
			(xy 127.888017 -282.227278) (xy 127.918041 -282.183241) (xy 127.954293 -282.14417) (xy 127.995964 -282.110939)
			(xy 128.042122 -282.08429) (xy 128.091736 -282.064818) (xy 128.143698 -282.052958) (xy 128.196848 -282.048975)
			(xy 128.249998 -282.052958) (xy 128.30196 -282.064818) (xy 128.351574 -282.08429) (xy 128.397732 -282.110939)
			(xy 128.439403 -282.14417) (xy 128.475655 -282.183241) (xy 128.505679 -282.227278) (xy 128.528805 -282.275299)
			(xy 128.544515 -282.326229) (xy 128.552458 -282.378933) (xy 128.552956 -282.405582) (xy 128.552458 -282.432231)
			(xy 128.781038 -282.432231) (xy 128.781038 -282.378933) (xy 128.788981 -282.326229) (xy 128.804691 -282.275299)
			(xy 128.827817 -282.227278) (xy 128.857841 -282.183241) (xy 128.894093 -282.14417) (xy 128.935764 -282.110939)
			(xy 128.981922 -282.08429) (xy 129.031536 -282.064818) (xy 129.083498 -282.052958) (xy 129.136648 -282.048975)
			(xy 129.189798 -282.052958) (xy 129.24176 -282.064818) (xy 129.291374 -282.08429) (xy 129.337532 -282.110939)
			(xy 129.379203 -282.14417) (xy 129.415455 -282.183241) (xy 129.445479 -282.227278) (xy 129.468605 -282.275299)
			(xy 129.484315 -282.326229) (xy 129.492258 -282.378933) (xy 129.492756 -282.405582) (xy 129.492258 -282.432231)
			(xy 129.720838 -282.432231) (xy 129.720838 -282.378933) (xy 129.728781 -282.326229) (xy 129.744491 -282.275299)
			(xy 129.767617 -282.227278) (xy 129.797641 -282.183241) (xy 129.833893 -282.14417) (xy 129.875564 -282.110939)
			(xy 129.921722 -282.08429) (xy 129.971336 -282.064818) (xy 130.023298 -282.052958) (xy 130.076448 -282.048975)
			(xy 130.129598 -282.052958) (xy 130.18156 -282.064818) (xy 130.231174 -282.08429) (xy 130.277332 -282.110939)
			(xy 130.319003 -282.14417) (xy 130.355255 -282.183241) (xy 130.385279 -282.227278) (xy 130.408405 -282.275299)
			(xy 130.424115 -282.326229) (xy 130.432058 -282.378933) (xy 130.432556 -282.405582) (xy 130.432058 -282.432231)
			(xy 130.43202 -282.432485) (xy 130.660384 -282.432485) (xy 130.660384 -282.379187) (xy 130.668327 -282.326483)
			(xy 130.684037 -282.275553) (xy 130.707163 -282.227532) (xy 130.737187 -282.183495) (xy 130.773439 -282.144424)
			(xy 130.81511 -282.111193) (xy 130.861268 -282.084544) (xy 130.910882 -282.065072) (xy 130.962844 -282.053212)
			(xy 131.015994 -282.049229) (xy 131.069144 -282.053212) (xy 131.121106 -282.065072) (xy 131.17072 -282.084544)
			(xy 131.216878 -282.111193) (xy 131.258549 -282.144424) (xy 131.294801 -282.183495) (xy 131.324825 -282.227532)
			(xy 131.347951 -282.275553) (xy 131.363661 -282.326483) (xy 131.371604 -282.379187) (xy 131.372102 -282.405836)
			(xy 131.371604 -282.432485) (xy 131.600184 -282.432485) (xy 131.600184 -282.379187) (xy 131.608127 -282.326483)
			(xy 131.623837 -282.275553) (xy 131.646963 -282.227532) (xy 131.676987 -282.183495) (xy 131.713239 -282.144424)
			(xy 131.75491 -282.111193) (xy 131.801068 -282.084544) (xy 131.850682 -282.065072) (xy 131.902644 -282.053212)
			(xy 131.955794 -282.049229) (xy 132.008944 -282.053212) (xy 132.060906 -282.065072) (xy 132.11052 -282.084544)
			(xy 132.156678 -282.111193) (xy 132.198349 -282.144424) (xy 132.234601 -282.183495) (xy 132.264625 -282.227532)
			(xy 132.287751 -282.275553) (xy 132.303461 -282.326483) (xy 132.311404 -282.379187) (xy 132.311902 -282.405836)
			(xy 132.311404 -282.432485) (xy 132.539984 -282.432485) (xy 132.539984 -282.379187) (xy 132.547927 -282.326483)
			(xy 132.563637 -282.275553) (xy 132.586763 -282.227532) (xy 132.616787 -282.183495) (xy 132.653039 -282.144424)
			(xy 132.69471 -282.111193) (xy 132.740868 -282.084544) (xy 132.790482 -282.065072) (xy 132.842444 -282.053212)
			(xy 132.895594 -282.049229) (xy 132.948744 -282.053212) (xy 133.000706 -282.065072) (xy 133.05032 -282.084544)
			(xy 133.096478 -282.111193) (xy 133.138149 -282.144424) (xy 133.174401 -282.183495) (xy 133.204425 -282.227532)
			(xy 133.227551 -282.275553) (xy 133.243261 -282.326483) (xy 133.251204 -282.379187) (xy 133.251702 -282.405836)
			(xy 133.251204 -282.432485) (xy 133.479784 -282.432485) (xy 133.479784 -282.379187) (xy 133.487727 -282.326483)
			(xy 133.503437 -282.275553) (xy 133.526563 -282.227532) (xy 133.556587 -282.183495) (xy 133.592839 -282.144424)
			(xy 133.63451 -282.111193) (xy 133.680668 -282.084544) (xy 133.730282 -282.065072) (xy 133.782244 -282.053212)
			(xy 133.835394 -282.049229) (xy 133.888544 -282.053212) (xy 133.940506 -282.065072) (xy 133.99012 -282.084544)
			(xy 134.036278 -282.111193) (xy 134.077949 -282.144424) (xy 134.114201 -282.183495) (xy 134.144225 -282.227532)
			(xy 134.167351 -282.275553) (xy 134.183061 -282.326483) (xy 134.191004 -282.379187) (xy 134.191502 -282.405836)
			(xy 134.191004 -282.432485) (xy 134.419838 -282.432485) (xy 134.419838 -282.379187) (xy 134.427781 -282.326483)
			(xy 134.443491 -282.275553) (xy 134.466617 -282.227532) (xy 134.496641 -282.183495) (xy 134.532893 -282.144424)
			(xy 134.574564 -282.111193) (xy 134.620722 -282.084544) (xy 134.670336 -282.065072) (xy 134.722298 -282.053212)
			(xy 134.775448 -282.049229) (xy 134.828598 -282.053212) (xy 134.88056 -282.065072) (xy 134.930174 -282.084544)
			(xy 134.976332 -282.111193) (xy 135.018003 -282.144424) (xy 135.054255 -282.183495) (xy 135.084279 -282.227532)
			(xy 135.107405 -282.275553) (xy 135.123115 -282.326483) (xy 135.131058 -282.379187) (xy 135.131556 -282.405836)
			(xy 135.131058 -282.432485) (xy 135.359384 -282.432485) (xy 135.359384 -282.379187) (xy 135.367327 -282.326483)
			(xy 135.383037 -282.275553) (xy 135.406163 -282.227532) (xy 135.436187 -282.183495) (xy 135.472439 -282.144424)
			(xy 135.51411 -282.111193) (xy 135.560268 -282.084544) (xy 135.609882 -282.065072) (xy 135.661844 -282.053212)
			(xy 135.714994 -282.049229) (xy 135.768144 -282.053212) (xy 135.820106 -282.065072) (xy 135.86972 -282.084544)
			(xy 135.915878 -282.111193) (xy 135.957549 -282.144424) (xy 135.993801 -282.183495) (xy 136.023825 -282.227532)
			(xy 136.046951 -282.275553) (xy 136.062661 -282.326483) (xy 136.070604 -282.379187) (xy 136.071102 -282.405836)
			(xy 136.070604 -282.432485) (xy 136.299184 -282.432485) (xy 136.299184 -282.379187) (xy 136.307127 -282.326483)
			(xy 136.322837 -282.275553) (xy 136.345963 -282.227532) (xy 136.375987 -282.183495) (xy 136.412239 -282.144424)
			(xy 136.45391 -282.111193) (xy 136.500068 -282.084544) (xy 136.549682 -282.065072) (xy 136.601644 -282.053212)
			(xy 136.654794 -282.049229) (xy 136.707944 -282.053212) (xy 136.759906 -282.065072) (xy 136.80952 -282.084544)
			(xy 136.855678 -282.111193) (xy 136.897349 -282.144424) (xy 136.933601 -282.183495) (xy 136.963625 -282.227532)
			(xy 136.986751 -282.275553) (xy 137.002461 -282.326483) (xy 137.010404 -282.379187) (xy 137.010902 -282.405836)
			(xy 137.010404 -282.432485) (xy 137.238984 -282.432485) (xy 137.238984 -282.379187) (xy 137.246927 -282.326483)
			(xy 137.262637 -282.275553) (xy 137.285763 -282.227532) (xy 137.315787 -282.183495) (xy 137.352039 -282.144424)
			(xy 137.39371 -282.111193) (xy 137.439868 -282.084544) (xy 137.489482 -282.065072) (xy 137.541444 -282.053212)
			(xy 137.594594 -282.049229) (xy 137.647744 -282.053212) (xy 137.699706 -282.065072) (xy 137.74932 -282.084544)
			(xy 137.795478 -282.111193) (xy 137.837149 -282.144424) (xy 137.873401 -282.183495) (xy 137.903425 -282.227532)
			(xy 137.926551 -282.275553) (xy 137.942261 -282.326483) (xy 137.950204 -282.379187) (xy 137.950702 -282.405836)
			(xy 137.950204 -282.432485) (xy 138.178784 -282.432485) (xy 138.178784 -282.379187) (xy 138.186727 -282.326483)
			(xy 138.202437 -282.275553) (xy 138.225563 -282.227532) (xy 138.255587 -282.183495) (xy 138.291839 -282.144424)
			(xy 138.33351 -282.111193) (xy 138.379668 -282.084544) (xy 138.429282 -282.065072) (xy 138.481244 -282.053212)
			(xy 138.534394 -282.049229) (xy 138.587544 -282.053212) (xy 138.639506 -282.065072) (xy 138.68912 -282.084544)
			(xy 138.735278 -282.111193) (xy 138.776949 -282.144424) (xy 138.813201 -282.183495) (xy 138.843225 -282.227532)
			(xy 138.866351 -282.275553) (xy 138.882061 -282.326483) (xy 138.890004 -282.379187) (xy 138.890502 -282.405836)
			(xy 138.890004 -282.432485) (xy 138.882061 -282.485189) (xy 138.866351 -282.536119) (xy 138.843225 -282.58414)
			(xy 138.813201 -282.628177) (xy 138.776949 -282.667248) (xy 138.735278 -282.700479) (xy 138.68912 -282.727128)
			(xy 138.639506 -282.7466) (xy 138.587544 -282.75846) (xy 138.534394 -282.762444) (xy 138.481244 -282.75846)
			(xy 138.429282 -282.7466) (xy 138.379668 -282.727128) (xy 138.33351 -282.700479) (xy 138.291839 -282.667248)
			(xy 138.255587 -282.628177) (xy 138.225563 -282.58414) (xy 138.202437 -282.536119) (xy 138.186727 -282.485189)
			(xy 138.178784 -282.432485) (xy 137.950204 -282.432485) (xy 137.942261 -282.485189) (xy 137.926551 -282.536119)
			(xy 137.903425 -282.58414) (xy 137.873401 -282.628177) (xy 137.837149 -282.667248) (xy 137.795478 -282.700479)
			(xy 137.74932 -282.727128) (xy 137.699706 -282.7466) (xy 137.647744 -282.75846) (xy 137.594594 -282.762444)
			(xy 137.541444 -282.75846) (xy 137.489482 -282.7466) (xy 137.439868 -282.727128) (xy 137.39371 -282.700479)
			(xy 137.352039 -282.667248) (xy 137.315787 -282.628177) (xy 137.285763 -282.58414) (xy 137.262637 -282.536119)
			(xy 137.246927 -282.485189) (xy 137.238984 -282.432485) (xy 137.010404 -282.432485) (xy 137.002461 -282.485189)
			(xy 136.986751 -282.536119) (xy 136.963625 -282.58414) (xy 136.933601 -282.628177) (xy 136.897349 -282.667248)
			(xy 136.855678 -282.700479) (xy 136.80952 -282.727128) (xy 136.759906 -282.7466) (xy 136.707944 -282.75846)
			(xy 136.654794 -282.762444) (xy 136.601644 -282.75846) (xy 136.549682 -282.7466) (xy 136.500068 -282.727128)
			(xy 136.45391 -282.700479) (xy 136.412239 -282.667248) (xy 136.375987 -282.628177) (xy 136.345963 -282.58414)
			(xy 136.322837 -282.536119) (xy 136.307127 -282.485189) (xy 136.299184 -282.432485) (xy 136.070604 -282.432485)
			(xy 136.062661 -282.485189) (xy 136.046951 -282.536119) (xy 136.023825 -282.58414) (xy 135.993801 -282.628177)
			(xy 135.957549 -282.667248) (xy 135.915878 -282.700479) (xy 135.86972 -282.727128) (xy 135.820106 -282.7466)
			(xy 135.768144 -282.75846) (xy 135.714994 -282.762444) (xy 135.661844 -282.75846) (xy 135.609882 -282.7466)
			(xy 135.560268 -282.727128) (xy 135.51411 -282.700479) (xy 135.472439 -282.667248) (xy 135.436187 -282.628177)
			(xy 135.406163 -282.58414) (xy 135.383037 -282.536119) (xy 135.367327 -282.485189) (xy 135.359384 -282.432485)
			(xy 135.131058 -282.432485) (xy 135.123115 -282.485189) (xy 135.107405 -282.536119) (xy 135.084279 -282.58414)
			(xy 135.054255 -282.628177) (xy 135.018003 -282.667248) (xy 134.976332 -282.700479) (xy 134.930174 -282.727128)
			(xy 134.88056 -282.7466) (xy 134.828598 -282.75846) (xy 134.775448 -282.762444) (xy 134.722298 -282.75846)
			(xy 134.670336 -282.7466) (xy 134.620722 -282.727128) (xy 134.574564 -282.700479) (xy 134.532893 -282.667248)
			(xy 134.496641 -282.628177) (xy 134.466617 -282.58414) (xy 134.443491 -282.536119) (xy 134.427781 -282.485189)
			(xy 134.419838 -282.432485) (xy 134.191004 -282.432485) (xy 134.183061 -282.485189) (xy 134.167351 -282.536119)
			(xy 134.144225 -282.58414) (xy 134.114201 -282.628177) (xy 134.077949 -282.667248) (xy 134.036278 -282.700479)
			(xy 133.99012 -282.727128) (xy 133.940506 -282.7466) (xy 133.888544 -282.75846) (xy 133.835394 -282.762444)
			(xy 133.782244 -282.75846) (xy 133.730282 -282.7466) (xy 133.680668 -282.727128) (xy 133.63451 -282.700479)
			(xy 133.592839 -282.667248) (xy 133.556587 -282.628177) (xy 133.526563 -282.58414) (xy 133.503437 -282.536119)
			(xy 133.487727 -282.485189) (xy 133.479784 -282.432485) (xy 133.251204 -282.432485) (xy 133.243261 -282.485189)
			(xy 133.227551 -282.536119) (xy 133.204425 -282.58414) (xy 133.174401 -282.628177) (xy 133.138149 -282.667248)
			(xy 133.096478 -282.700479) (xy 133.05032 -282.727128) (xy 133.000706 -282.7466) (xy 132.948744 -282.75846)
			(xy 132.895594 -282.762444) (xy 132.842444 -282.75846) (xy 132.790482 -282.7466) (xy 132.740868 -282.727128)
			(xy 132.69471 -282.700479) (xy 132.653039 -282.667248) (xy 132.616787 -282.628177) (xy 132.586763 -282.58414)
			(xy 132.563637 -282.536119) (xy 132.547927 -282.485189) (xy 132.539984 -282.432485) (xy 132.311404 -282.432485)
			(xy 132.303461 -282.485189) (xy 132.287751 -282.536119) (xy 132.264625 -282.58414) (xy 132.234601 -282.628177)
			(xy 132.198349 -282.667248) (xy 132.156678 -282.700479) (xy 132.11052 -282.727128) (xy 132.060906 -282.7466)
			(xy 132.008944 -282.75846) (xy 131.955794 -282.762444) (xy 131.902644 -282.75846) (xy 131.850682 -282.7466)
			(xy 131.801068 -282.727128) (xy 131.75491 -282.700479) (xy 131.713239 -282.667248) (xy 131.676987 -282.628177)
			(xy 131.646963 -282.58414) (xy 131.623837 -282.536119) (xy 131.608127 -282.485189) (xy 131.600184 -282.432485)
			(xy 131.371604 -282.432485) (xy 131.363661 -282.485189) (xy 131.347951 -282.536119) (xy 131.324825 -282.58414)
			(xy 131.294801 -282.628177) (xy 131.258549 -282.667248) (xy 131.216878 -282.700479) (xy 131.17072 -282.727128)
			(xy 131.121106 -282.7466) (xy 131.069144 -282.75846) (xy 131.015994 -282.762444) (xy 130.962844 -282.75846)
			(xy 130.910882 -282.7466) (xy 130.861268 -282.727128) (xy 130.81511 -282.700479) (xy 130.773439 -282.667248)
			(xy 130.737187 -282.628177) (xy 130.707163 -282.58414) (xy 130.684037 -282.536119) (xy 130.668327 -282.485189)
			(xy 130.660384 -282.432485) (xy 130.43202 -282.432485) (xy 130.424115 -282.484935) (xy 130.408405 -282.535865)
			(xy 130.385279 -282.583886) (xy 130.355255 -282.627923) (xy 130.319003 -282.666994) (xy 130.277332 -282.700225)
			(xy 130.231174 -282.726874) (xy 130.18156 -282.746346) (xy 130.129598 -282.758206) (xy 130.076448 -282.76219)
			(xy 130.023298 -282.758206) (xy 129.971336 -282.746346) (xy 129.921722 -282.726874) (xy 129.875564 -282.700225)
			(xy 129.833893 -282.666994) (xy 129.797641 -282.627923) (xy 129.767617 -282.583886) (xy 129.744491 -282.535865)
			(xy 129.728781 -282.484935) (xy 129.720838 -282.432231) (xy 129.492258 -282.432231) (xy 129.484315 -282.484935)
			(xy 129.468605 -282.535865) (xy 129.445479 -282.583886) (xy 129.415455 -282.627923) (xy 129.379203 -282.666994)
			(xy 129.337532 -282.700225) (xy 129.291374 -282.726874) (xy 129.24176 -282.746346) (xy 129.189798 -282.758206)
			(xy 129.136648 -282.76219) (xy 129.083498 -282.758206) (xy 129.031536 -282.746346) (xy 128.981922 -282.726874)
			(xy 128.935764 -282.700225) (xy 128.894093 -282.666994) (xy 128.857841 -282.627923) (xy 128.827817 -282.583886)
			(xy 128.804691 -282.535865) (xy 128.788981 -282.484935) (xy 128.781038 -282.432231) (xy 128.552458 -282.432231)
			(xy 128.544515 -282.484935) (xy 128.528805 -282.535865) (xy 128.505679 -282.583886) (xy 128.475655 -282.627923)
			(xy 128.439403 -282.666994) (xy 128.397732 -282.700225) (xy 128.351574 -282.726874) (xy 128.30196 -282.746346)
			(xy 128.249998 -282.758206) (xy 128.196848 -282.76219) (xy 128.143698 -282.758206) (xy 128.091736 -282.746346)
			(xy 128.042122 -282.726874) (xy 127.995964 -282.700225) (xy 127.954293 -282.666994) (xy 127.918041 -282.627923)
			(xy 127.888017 -282.583886) (xy 127.864891 -282.535865) (xy 127.849181 -282.484935) (xy 127.841238 -282.432231)
			(xy 127.612658 -282.432231) (xy 127.604715 -282.484935) (xy 127.589005 -282.535865) (xy 127.565879 -282.583886)
			(xy 127.535855 -282.627923) (xy 127.499603 -282.666994) (xy 127.457932 -282.700225) (xy 127.411774 -282.726874)
			(xy 127.36216 -282.746346) (xy 127.310198 -282.758206) (xy 127.257048 -282.76219) (xy 127.203898 -282.758206)
			(xy 127.151936 -282.746346) (xy 127.102322 -282.726874) (xy 127.056164 -282.700225) (xy 127.014493 -282.666994)
			(xy 126.978241 -282.627923) (xy 126.948217 -282.583886) (xy 126.925091 -282.535865) (xy 126.909381 -282.484935)
			(xy 126.901438 -282.432231) (xy 126.672863 -282.432231) (xy 126.672858 -282.432485) (xy 126.664915 -282.485189)
			(xy 126.649205 -282.536119) (xy 126.626079 -282.58414) (xy 126.596055 -282.628177) (xy 126.559803 -282.667248)
			(xy 126.518132 -282.700479) (xy 126.471974 -282.727128) (xy 126.42236 -282.7466) (xy 126.370398 -282.75846)
			(xy 126.317248 -282.762444) (xy 126.264098 -282.75846) (xy 126.212136 -282.7466) (xy 126.162522 -282.727128)
			(xy 126.116364 -282.700479) (xy 126.074693 -282.667248) (xy 126.038441 -282.628177) (xy 126.008417 -282.58414)
			(xy 125.985291 -282.536119) (xy 125.969581 -282.485189) (xy 125.961638 -282.432485) (xy 125.732804 -282.432485)
			(xy 125.724861 -282.485189) (xy 125.709151 -282.536119) (xy 125.686025 -282.58414) (xy 125.656001 -282.628177)
			(xy 125.619749 -282.667248) (xy 125.578078 -282.700479) (xy 125.53192 -282.727128) (xy 125.482306 -282.7466)
			(xy 125.430344 -282.75846) (xy 125.377194 -282.762444) (xy 125.324044 -282.75846) (xy 125.272082 -282.7466)
			(xy 125.222468 -282.727128) (xy 125.17631 -282.700479) (xy 125.134639 -282.667248) (xy 125.098387 -282.628177)
			(xy 125.068363 -282.58414) (xy 125.045237 -282.536119) (xy 125.029527 -282.485189) (xy 125.021584 -282.432485)
			(xy 124.793004 -282.432485) (xy 124.785061 -282.485189) (xy 124.769351 -282.536119) (xy 124.746225 -282.58414)
			(xy 124.716201 -282.628177) (xy 124.679949 -282.667248) (xy 124.638278 -282.700479) (xy 124.59212 -282.727128)
			(xy 124.542506 -282.7466) (xy 124.490544 -282.75846) (xy 124.437394 -282.762444) (xy 124.384244 -282.75846)
			(xy 124.332282 -282.7466) (xy 124.282668 -282.727128) (xy 124.23651 -282.700479) (xy 124.194839 -282.667248)
			(xy 124.158587 -282.628177) (xy 124.128563 -282.58414) (xy 124.105437 -282.536119) (xy 124.089727 -282.485189)
			(xy 124.081784 -282.432485) (xy 123.853204 -282.432485) (xy 123.845261 -282.485189) (xy 123.829551 -282.536119)
			(xy 123.806425 -282.58414) (xy 123.776401 -282.628177) (xy 123.740149 -282.667248) (xy 123.698478 -282.700479)
			(xy 123.65232 -282.727128) (xy 123.602706 -282.7466) (xy 123.550744 -282.75846) (xy 123.497594 -282.762444)
			(xy 123.444444 -282.75846) (xy 123.392482 -282.7466) (xy 123.342868 -282.727128) (xy 123.29671 -282.700479)
			(xy 123.255039 -282.667248) (xy 123.218787 -282.628177) (xy 123.188763 -282.58414) (xy 123.165637 -282.536119)
			(xy 123.149927 -282.485189) (xy 123.141984 -282.432485) (xy 122.913404 -282.432485) (xy 122.905461 -282.485189)
			(xy 122.889751 -282.536119) (xy 122.866625 -282.58414) (xy 122.836601 -282.628177) (xy 122.800349 -282.667248)
			(xy 122.758678 -282.700479) (xy 122.71252 -282.727128) (xy 122.662906 -282.7466) (xy 122.610944 -282.75846)
			(xy 122.557794 -282.762444) (xy 122.504644 -282.75846) (xy 122.452682 -282.7466) (xy 122.403068 -282.727128)
			(xy 122.35691 -282.700479) (xy 122.315239 -282.667248) (xy 122.278987 -282.628177) (xy 122.248963 -282.58414)
			(xy 122.225837 -282.536119) (xy 122.210127 -282.485189) (xy 122.202184 -282.432485) (xy 121.973604 -282.432485)
			(xy 121.965661 -282.485189) (xy 121.949951 -282.536119) (xy 121.926825 -282.58414) (xy 121.896801 -282.628177)
			(xy 121.860549 -282.667248) (xy 121.818878 -282.700479) (xy 121.77272 -282.727128) (xy 121.723106 -282.7466)
			(xy 121.671144 -282.75846) (xy 121.617994 -282.762444) (xy 121.564844 -282.75846) (xy 121.512882 -282.7466)
			(xy 121.463268 -282.727128) (xy 121.41711 -282.700479) (xy 121.375439 -282.667248) (xy 121.339187 -282.628177)
			(xy 121.309163 -282.58414) (xy 121.286037 -282.536119) (xy 121.270327 -282.485189) (xy 121.262384 -282.432485)
			(xy 121.033804 -282.432485) (xy 121.025861 -282.485189) (xy 121.010151 -282.536119) (xy 120.987025 -282.58414)
			(xy 120.957001 -282.628177) (xy 120.920749 -282.667248) (xy 120.879078 -282.700479) (xy 120.83292 -282.727128)
			(xy 120.783306 -282.7466) (xy 120.731344 -282.75846) (xy 120.678194 -282.762444) (xy 120.625044 -282.75846)
			(xy 120.573082 -282.7466) (xy 120.523468 -282.727128) (xy 120.47731 -282.700479) (xy 120.435639 -282.667248)
			(xy 120.399387 -282.628177) (xy 120.369363 -282.58414) (xy 120.346237 -282.536119) (xy 120.330527 -282.485189)
			(xy 120.322584 -282.432485) (xy 120.094004 -282.432485) (xy 120.086061 -282.485189) (xy 120.070351 -282.536119)
			(xy 120.047225 -282.58414) (xy 120.017201 -282.628177) (xy 119.980949 -282.667248) (xy 119.939278 -282.700479)
			(xy 119.89312 -282.727128) (xy 119.843506 -282.7466) (xy 119.791544 -282.75846) (xy 119.738394 -282.762444)
			(xy 119.685244 -282.75846) (xy 119.633282 -282.7466) (xy 119.583668 -282.727128) (xy 119.53751 -282.700479)
			(xy 119.495839 -282.667248) (xy 119.459587 -282.628177) (xy 119.429563 -282.58414) (xy 119.406437 -282.536119)
			(xy 119.390727 -282.485189) (xy 119.382784 -282.432485) (xy 119.154204 -282.432485) (xy 119.146261 -282.485189)
			(xy 119.130551 -282.536119) (xy 119.107425 -282.58414) (xy 119.077401 -282.628177) (xy 119.041149 -282.667248)
			(xy 118.999478 -282.700479) (xy 118.95332 -282.727128) (xy 118.903706 -282.7466) (xy 118.851744 -282.75846)
			(xy 118.798594 -282.762444) (xy 118.745444 -282.75846) (xy 118.693482 -282.7466) (xy 118.643868 -282.727128)
			(xy 118.59771 -282.700479) (xy 118.556039 -282.667248) (xy 118.519787 -282.628177) (xy 118.489763 -282.58414)
			(xy 118.466637 -282.536119) (xy 118.450927 -282.485189) (xy 118.442984 -282.432485) (xy 118.214658 -282.432485)
			(xy 118.206715 -282.485189) (xy 118.191005 -282.536119) (xy 118.167879 -282.58414) (xy 118.137855 -282.628177)
			(xy 118.101603 -282.667248) (xy 118.059932 -282.700479) (xy 118.013774 -282.727128) (xy 117.96416 -282.7466)
			(xy 117.912198 -282.75846) (xy 117.859048 -282.762444) (xy 117.805898 -282.75846) (xy 117.753936 -282.7466)
			(xy 117.704322 -282.727128) (xy 117.658164 -282.700479) (xy 117.616493 -282.667248) (xy 117.580241 -282.628177)
			(xy 117.550217 -282.58414) (xy 117.527091 -282.536119) (xy 117.511381 -282.485189) (xy 117.503438 -282.432485)
			(xy 110.696004 -282.432485) (xy 110.688061 -282.485189) (xy 110.672351 -282.536119) (xy 110.649225 -282.58414)
			(xy 110.619201 -282.628177) (xy 110.582949 -282.667248) (xy 110.541278 -282.700479) (xy 110.49512 -282.727128)
			(xy 110.445506 -282.7466) (xy 110.393544 -282.75846) (xy 110.340394 -282.762444) (xy 110.287244 -282.75846)
			(xy 110.235282 -282.7466) (xy 110.185668 -282.727128) (xy 110.13951 -282.700479) (xy 110.097839 -282.667248)
			(xy 110.061587 -282.628177) (xy 110.031563 -282.58414) (xy 110.008437 -282.536119) (xy 109.992727 -282.485189)
			(xy 109.984784 -282.432485) (xy 107.876604 -282.432485) (xy 107.868661 -282.485189) (xy 107.852951 -282.536119)
			(xy 107.829825 -282.58414) (xy 107.799801 -282.628177) (xy 107.763549 -282.667248) (xy 107.721878 -282.700479)
			(xy 107.67572 -282.727128) (xy 107.626106 -282.7466) (xy 107.574144 -282.75846) (xy 107.520994 -282.762444)
			(xy 107.467844 -282.75846) (xy 107.415882 -282.7466) (xy 107.366268 -282.727128) (xy 107.32011 -282.700479)
			(xy 107.278439 -282.667248) (xy 107.242187 -282.628177) (xy 107.212163 -282.58414) (xy 107.189037 -282.536119)
			(xy 107.173327 -282.485189) (xy 107.165384 -282.432485) (xy 106.910003 -282.432485) (xy 106.902025 -282.482861)
			(xy 106.886026 -282.532101) (xy 106.86252 -282.578233) (xy 106.832088 -282.62012) (xy 106.795478 -282.65673)
			(xy 106.753591 -282.687162) (xy 106.707459 -282.710668) (xy 106.658219 -282.726667) (xy 106.607081 -282.734766)
			(xy 106.555307 -282.734766) (xy 106.504169 -282.726667) (xy 106.454929 -282.710668) (xy 106.408797 -282.687162)
			(xy 106.36691 -282.65673) (xy 106.3303 -282.62012) (xy 106.299868 -282.578233) (xy 106.276362 -282.532101)
			(xy 106.260363 -282.482861) (xy 106.252264 -282.431723) (xy 106.251756 -282.405836) (xy 106.252296 -282.378128)
			(xy 106.261484 -282.323482) (xy 106.270044 -282.297124) (xy 106.277918 -282.275026) (xy 106.07294 -281.920188)
			(xy 106.05008 -281.91587) (xy 106.025256 -281.910713) (xy 105.977474 -281.893761) (xy 105.932853 -281.86969)
			(xy 105.892445 -281.839069) (xy 105.857203 -281.802621) (xy 105.827959 -281.761205) (xy 105.805403 -281.715799)
			(xy 105.790068 -281.667474) (xy 105.782315 -281.61737) (xy 105.781856 -281.59202) (xy 105.528217 -281.59202)
			(xy 105.524397 -281.644054) (xy 105.513018 -281.694992) (xy 105.494323 -281.743722) (xy 105.468713 -281.789201)
			(xy 105.436738 -281.830453) (xy 105.399083 -281.866595) (xy 105.356554 -281.896851) (xy 105.310063 -281.920574)
			(xy 105.260607 -281.937255) (xy 105.209245 -281.946536) (xy 105.183178 -281.947874) (xy 105.182162 -281.947874)
			(xy 105.172648 -281.948795) (xy 105.155287 -281.95676) (xy 105.14838 -281.963368) (xy 105.123742 -281.988768)
			(xy 105.098088 -282.015438) (xy 105.092134 -282.022668) (xy 105.085377 -282.04012) (xy 105.08488 -282.049474)
			(xy 105.08488 -282.762706) (xy 105.08536 -282.77206) (xy 105.09214 -282.789505) (xy 105.098088 -282.796742)
			(xy 105.10774 -282.806648) (xy 105.11456 -282.813192) (xy 105.131695 -282.821136) (xy 105.150544 -282.82233)
			(xy 105.168544 -282.81661) (xy 105.183247 -282.804754) (xy 105.188258 -282.796742) (xy 105.338118 -282.5369)
			(xy 105.330498 -282.514802) (xy 105.32185 -282.488394) (xy 105.312523 -282.433618) (xy 105.311956 -282.405836)
			(xy 105.312464 -282.379949) (xy 105.320563 -282.328811) (xy 105.336562 -282.279571) (xy 105.360068 -282.233439)
			(xy 105.3905 -282.191552) (xy 105.42711 -282.154942) (xy 105.468997 -282.12451) (xy 105.515129 -282.101004)
			(xy 105.564369 -282.085005) (xy 105.615507 -282.076906) (xy 105.667281 -282.076906) (xy 105.718419 -282.085005)
			(xy 105.767659 -282.101004) (xy 105.813791 -282.12451) (xy 105.855678 -282.154942) (xy 105.892288 -282.191552)
			(xy 105.92272 -282.233439) (xy 105.946226 -282.279571) (xy 105.962225 -282.328811) (xy 105.970324 -282.379949)
			(xy 105.970832 -282.405836) (xy 105.970367 -282.431157) (xy 105.962618 -282.481203) (xy 105.947309 -282.529476)
			(xy 105.924799 -282.574841) (xy 105.895617 -282.61623) (xy 105.86045 -282.652671) (xy 105.820125 -282.683307)
			(xy 105.775589 -282.707416) (xy 105.727891 -282.724433) (xy 105.703116 -282.729686) (xy 105.680256 -282.734004)
			(xy 105.49128 -283.060902) (xy 105.500932 -283.084016) (xy 105.510581 -283.108646) (xy 105.523315 -283.159987)
			(xy 105.528312 -283.212647) (xy 105.526482 -283.246555) (xy 105.755684 -283.246555) (xy 105.755684 -283.193257)
			(xy 105.763627 -283.140553) (xy 105.779337 -283.089623) (xy 105.802463 -283.041602) (xy 105.832487 -282.997565)
			(xy 105.868739 -282.958494) (xy 105.91041 -282.925263) (xy 105.956568 -282.898614) (xy 106.006182 -282.879142)
			(xy 106.058144 -282.867282) (xy 106.111294 -282.863299) (xy 106.164444 -282.867282) (xy 106.216406 -282.879142)
			(xy 106.26602 -282.898614) (xy 106.312178 -282.925263) (xy 106.353849 -282.958494) (xy 106.390101 -282.997565)
			(xy 106.420125 -283.041602) (xy 106.443251 -283.089623) (xy 106.458961 -283.140553) (xy 106.466904 -283.193257)
			(xy 106.467402 -283.219906) (xy 106.466904 -283.246555) (xy 106.695738 -283.246555) (xy 106.695738 -283.193257)
			(xy 106.703681 -283.140553) (xy 106.719391 -283.089623) (xy 106.742517 -283.041602) (xy 106.772541 -282.997565)
			(xy 106.808793 -282.958494) (xy 106.850464 -282.925263) (xy 106.896622 -282.898614) (xy 106.946236 -282.879142)
			(xy 106.998198 -282.867282) (xy 107.051348 -282.863299) (xy 107.104498 -282.867282) (xy 107.15646 -282.879142)
			(xy 107.206074 -282.898614) (xy 107.252232 -282.925263) (xy 107.293903 -282.958494) (xy 107.330155 -282.997565)
			(xy 107.360179 -283.041602) (xy 107.383305 -283.089623) (xy 107.399015 -283.140553) (xy 107.406958 -283.193257)
			(xy 107.407456 -283.219906) (xy 107.406958 -283.246555) (xy 113.274084 -283.246555) (xy 113.274084 -283.193257)
			(xy 113.282027 -283.140553) (xy 113.297737 -283.089623) (xy 113.320863 -283.041602) (xy 113.350887 -282.997565)
			(xy 113.387139 -282.958494) (xy 113.42881 -282.925263) (xy 113.474968 -282.898614) (xy 113.524582 -282.879142)
			(xy 113.576544 -282.867282) (xy 113.629694 -282.863299) (xy 113.682844 -282.867282) (xy 113.734806 -282.879142)
			(xy 113.78442 -282.898614) (xy 113.830578 -282.925263) (xy 113.872249 -282.958494) (xy 113.908501 -282.997565)
			(xy 113.938525 -283.041602) (xy 113.961651 -283.089623) (xy 113.977361 -283.140553) (xy 113.985304 -283.193257)
			(xy 113.985802 -283.219906) (xy 113.985304 -283.246555) (xy 116.093738 -283.246555) (xy 116.093738 -283.193257)
			(xy 116.101681 -283.140553) (xy 116.117391 -283.089623) (xy 116.140517 -283.041602) (xy 116.170541 -282.997565)
			(xy 116.206793 -282.958494) (xy 116.248464 -282.925263) (xy 116.294622 -282.898614) (xy 116.344236 -282.879142)
			(xy 116.396198 -282.867282) (xy 116.449348 -282.863299) (xy 116.502498 -282.867282) (xy 116.55446 -282.879142)
			(xy 116.604074 -282.898614) (xy 116.650232 -282.925263) (xy 116.691903 -282.958494) (xy 116.728155 -282.997565)
			(xy 116.758179 -283.041602) (xy 116.781305 -283.089623) (xy 116.797015 -283.140553) (xy 116.804958 -283.193257)
			(xy 116.805456 -283.219906) (xy 116.804958 -283.246555) (xy 117.973338 -283.246555) (xy 117.973338 -283.193257)
			(xy 117.981281 -283.140553) (xy 117.996991 -283.089623) (xy 118.020117 -283.041602) (xy 118.050141 -282.997565)
			(xy 118.086393 -282.958494) (xy 118.128064 -282.925263) (xy 118.174222 -282.898614) (xy 118.223836 -282.879142)
			(xy 118.275798 -282.867282) (xy 118.328948 -282.863299) (xy 118.382098 -282.867282) (xy 118.43406 -282.879142)
			(xy 118.483674 -282.898614) (xy 118.529832 -282.925263) (xy 118.571503 -282.958494) (xy 118.607755 -282.997565)
			(xy 118.637779 -283.041602) (xy 118.660905 -283.089623) (xy 118.676615 -283.140553) (xy 118.684558 -283.193257)
			(xy 118.685056 -283.219906) (xy 118.684558 -283.246555) (xy 118.912884 -283.246555) (xy 118.912884 -283.193257)
			(xy 118.920827 -283.140553) (xy 118.936537 -283.089623) (xy 118.959663 -283.041602) (xy 118.989687 -282.997565)
			(xy 119.025939 -282.958494) (xy 119.06761 -282.925263) (xy 119.113768 -282.898614) (xy 119.163382 -282.879142)
			(xy 119.215344 -282.867282) (xy 119.268494 -282.863299) (xy 119.321644 -282.867282) (xy 119.373606 -282.879142)
			(xy 119.42322 -282.898614) (xy 119.469378 -282.925263) (xy 119.511049 -282.958494) (xy 119.547301 -282.997565)
			(xy 119.577325 -283.041602) (xy 119.600451 -283.089623) (xy 119.616161 -283.140553) (xy 119.624104 -283.193257)
			(xy 119.624602 -283.219906) (xy 119.624104 -283.246555) (xy 119.852938 -283.246555) (xy 119.852938 -283.193257)
			(xy 119.860881 -283.140553) (xy 119.876591 -283.089623) (xy 119.899717 -283.041602) (xy 119.929741 -282.997565)
			(xy 119.965993 -282.958494) (xy 120.007664 -282.925263) (xy 120.053822 -282.898614) (xy 120.103436 -282.879142)
			(xy 120.155398 -282.867282) (xy 120.208548 -282.863299) (xy 120.261698 -282.867282) (xy 120.31366 -282.879142)
			(xy 120.363274 -282.898614) (xy 120.409432 -282.925263) (xy 120.451103 -282.958494) (xy 120.487355 -282.997565)
			(xy 120.517379 -283.041602) (xy 120.540505 -283.089623) (xy 120.556215 -283.140553) (xy 120.564158 -283.193257)
			(xy 120.564656 -283.219906) (xy 120.564158 -283.246555) (xy 120.792484 -283.246555) (xy 120.792484 -283.193257)
			(xy 120.800427 -283.140553) (xy 120.816137 -283.089623) (xy 120.839263 -283.041602) (xy 120.869287 -282.997565)
			(xy 120.905539 -282.958494) (xy 120.94721 -282.925263) (xy 120.993368 -282.898614) (xy 121.042982 -282.879142)
			(xy 121.094944 -282.867282) (xy 121.148094 -282.863299) (xy 121.201244 -282.867282) (xy 121.253206 -282.879142)
			(xy 121.30282 -282.898614) (xy 121.348978 -282.925263) (xy 121.390649 -282.958494) (xy 121.426901 -282.997565)
			(xy 121.456925 -283.041602) (xy 121.480051 -283.089623) (xy 121.495761 -283.140553) (xy 121.503704 -283.193257)
			(xy 121.504202 -283.219906) (xy 121.503704 -283.246555) (xy 121.732284 -283.246555) (xy 121.732284 -283.193257)
			(xy 121.740227 -283.140553) (xy 121.755937 -283.089623) (xy 121.779063 -283.041602) (xy 121.809087 -282.997565)
			(xy 121.845339 -282.958494) (xy 121.88701 -282.925263) (xy 121.933168 -282.898614) (xy 121.982782 -282.879142)
			(xy 122.034744 -282.867282) (xy 122.087894 -282.863299) (xy 122.141044 -282.867282) (xy 122.193006 -282.879142)
			(xy 122.24262 -282.898614) (xy 122.288778 -282.925263) (xy 122.330449 -282.958494) (xy 122.366701 -282.997565)
			(xy 122.396725 -283.041602) (xy 122.419851 -283.089623) (xy 122.435561 -283.140553) (xy 122.443504 -283.193257)
			(xy 122.444002 -283.219906) (xy 122.443504 -283.246555) (xy 122.672338 -283.246555) (xy 122.672338 -283.193257)
			(xy 122.680281 -283.140553) (xy 122.695991 -283.089623) (xy 122.719117 -283.041602) (xy 122.749141 -282.997565)
			(xy 122.785393 -282.958494) (xy 122.827064 -282.925263) (xy 122.873222 -282.898614) (xy 122.922836 -282.879142)
			(xy 122.974798 -282.867282) (xy 123.027948 -282.863299) (xy 123.081098 -282.867282) (xy 123.13306 -282.879142)
			(xy 123.182674 -282.898614) (xy 123.228832 -282.925263) (xy 123.270503 -282.958494) (xy 123.306755 -282.997565)
			(xy 123.336779 -283.041602) (xy 123.359905 -283.089623) (xy 123.375615 -283.140553) (xy 123.383558 -283.193257)
			(xy 123.384056 -283.219906) (xy 123.383558 -283.246555) (xy 123.612138 -283.246555) (xy 123.612138 -283.193257)
			(xy 123.620081 -283.140553) (xy 123.635791 -283.089623) (xy 123.658917 -283.041602) (xy 123.688941 -282.997565)
			(xy 123.725193 -282.958494) (xy 123.766864 -282.925263) (xy 123.813022 -282.898614) (xy 123.862636 -282.879142)
			(xy 123.914598 -282.867282) (xy 123.967748 -282.863299) (xy 124.020898 -282.867282) (xy 124.07286 -282.879142)
			(xy 124.122474 -282.898614) (xy 124.168632 -282.925263) (xy 124.210303 -282.958494) (xy 124.246555 -282.997565)
			(xy 124.276579 -283.041602) (xy 124.299705 -283.089623) (xy 124.315415 -283.140553) (xy 124.323358 -283.193257)
			(xy 124.323856 -283.219906) (xy 124.323358 -283.246555) (xy 124.551938 -283.246555) (xy 124.551938 -283.193257)
			(xy 124.559881 -283.140553) (xy 124.575591 -283.089623) (xy 124.598717 -283.041602) (xy 124.628741 -282.997565)
			(xy 124.664993 -282.958494) (xy 124.706664 -282.925263) (xy 124.752822 -282.898614) (xy 124.802436 -282.879142)
			(xy 124.854398 -282.867282) (xy 124.907548 -282.863299) (xy 124.960698 -282.867282) (xy 125.01266 -282.879142)
			(xy 125.062274 -282.898614) (xy 125.108432 -282.925263) (xy 125.150103 -282.958494) (xy 125.186355 -282.997565)
			(xy 125.216379 -283.041602) (xy 125.239505 -283.089623) (xy 125.255215 -283.140553) (xy 125.263158 -283.193257)
			(xy 125.263656 -283.219906) (xy 125.263158 -283.246555) (xy 125.491738 -283.246555) (xy 125.491738 -283.193257)
			(xy 125.499681 -283.140553) (xy 125.515391 -283.089623) (xy 125.538517 -283.041602) (xy 125.568541 -282.997565)
			(xy 125.604793 -282.958494) (xy 125.646464 -282.925263) (xy 125.692622 -282.898614) (xy 125.742236 -282.879142)
			(xy 125.794198 -282.867282) (xy 125.847348 -282.863299) (xy 125.900498 -282.867282) (xy 125.95246 -282.879142)
			(xy 126.002074 -282.898614) (xy 126.048232 -282.925263) (xy 126.089903 -282.958494) (xy 126.126155 -282.997565)
			(xy 126.156179 -283.041602) (xy 126.179305 -283.089623) (xy 126.195015 -283.140553) (xy 126.202958 -283.193257)
			(xy 126.203456 -283.219906) (xy 126.202958 -283.246555) (xy 126.431284 -283.246555) (xy 126.431284 -283.193257)
			(xy 126.439227 -283.140553) (xy 126.454937 -283.089623) (xy 126.478063 -283.041602) (xy 126.508087 -282.997565)
			(xy 126.544339 -282.958494) (xy 126.58601 -282.925263) (xy 126.632168 -282.898614) (xy 126.681782 -282.879142)
			(xy 126.733744 -282.867282) (xy 126.786894 -282.863299) (xy 126.840044 -282.867282) (xy 126.892006 -282.879142)
			(xy 126.94162 -282.898614) (xy 126.987778 -282.925263) (xy 127.029449 -282.958494) (xy 127.065701 -282.997565)
			(xy 127.095725 -283.041602) (xy 127.118851 -283.089623) (xy 127.134561 -283.140553) (xy 127.142504 -283.193257)
			(xy 127.143002 -283.219906) (xy 127.142504 -283.246555) (xy 127.371338 -283.246555) (xy 127.371338 -283.193257)
			(xy 127.379281 -283.140553) (xy 127.394991 -283.089623) (xy 127.418117 -283.041602) (xy 127.448141 -282.997565)
			(xy 127.484393 -282.958494) (xy 127.526064 -282.925263) (xy 127.572222 -282.898614) (xy 127.621836 -282.879142)
			(xy 127.673798 -282.867282) (xy 127.726948 -282.863299) (xy 127.780098 -282.867282) (xy 127.83206 -282.879142)
			(xy 127.881674 -282.898614) (xy 127.927832 -282.925263) (xy 127.969503 -282.958494) (xy 128.005755 -282.997565)
			(xy 128.035779 -283.041602) (xy 128.058905 -283.089623) (xy 128.074615 -283.140553) (xy 128.082558 -283.193257)
			(xy 128.083056 -283.219906) (xy 128.082563 -283.246301) (xy 128.310884 -283.246301) (xy 128.310884 -283.193003)
			(xy 128.318827 -283.140299) (xy 128.334537 -283.089369) (xy 128.357663 -283.041348) (xy 128.387687 -282.997311)
			(xy 128.423939 -282.95824) (xy 128.46561 -282.925009) (xy 128.511768 -282.89836) (xy 128.561382 -282.878888)
			(xy 128.613344 -282.867028) (xy 128.666494 -282.863045) (xy 128.719644 -282.867028) (xy 128.771606 -282.878888)
			(xy 128.82122 -282.89836) (xy 128.867378 -282.925009) (xy 128.909049 -282.95824) (xy 128.945301 -282.997311)
			(xy 128.975325 -283.041348) (xy 128.998451 -283.089369) (xy 129.014161 -283.140299) (xy 129.022104 -283.193003)
			(xy 129.022602 -283.219652) (xy 129.022104 -283.246301) (xy 129.022066 -283.246555) (xy 129.250684 -283.246555)
			(xy 129.250684 -283.193257) (xy 129.258627 -283.140553) (xy 129.274337 -283.089623) (xy 129.297463 -283.041602)
			(xy 129.327487 -282.997565) (xy 129.363739 -282.958494) (xy 129.40541 -282.925263) (xy 129.451568 -282.898614)
			(xy 129.501182 -282.879142) (xy 129.553144 -282.867282) (xy 129.606294 -282.863299) (xy 129.659444 -282.867282)
			(xy 129.711406 -282.879142) (xy 129.76102 -282.898614) (xy 129.807178 -282.925263) (xy 129.848849 -282.958494)
			(xy 129.885101 -282.997565) (xy 129.915125 -283.041602) (xy 129.938251 -283.089623) (xy 129.953961 -283.140553)
			(xy 129.961904 -283.193257) (xy 129.962402 -283.219906) (xy 129.961904 -283.246555) (xy 130.190484 -283.246555)
			(xy 130.190484 -283.193257) (xy 130.198427 -283.140553) (xy 130.214137 -283.089623) (xy 130.237263 -283.041602)
			(xy 130.267287 -282.997565) (xy 130.303539 -282.958494) (xy 130.34521 -282.925263) (xy 130.391368 -282.898614)
			(xy 130.440982 -282.879142) (xy 130.492944 -282.867282) (xy 130.546094 -282.863299) (xy 130.599244 -282.867282)
			(xy 130.651206 -282.879142) (xy 130.70082 -282.898614) (xy 130.746978 -282.925263) (xy 130.788649 -282.958494)
			(xy 130.824901 -282.997565) (xy 130.854925 -283.041602) (xy 130.878051 -283.089623) (xy 130.893761 -283.140553)
			(xy 130.901704 -283.193257) (xy 130.902202 -283.219906) (xy 130.901704 -283.246555) (xy 131.130538 -283.246555)
			(xy 131.130538 -283.193257) (xy 131.138481 -283.140553) (xy 131.154191 -283.089623) (xy 131.177317 -283.041602)
			(xy 131.207341 -282.997565) (xy 131.243593 -282.958494) (xy 131.285264 -282.925263) (xy 131.331422 -282.898614)
			(xy 131.381036 -282.879142) (xy 131.432998 -282.867282) (xy 131.486148 -282.863299) (xy 131.539298 -282.867282)
			(xy 131.59126 -282.879142) (xy 131.640874 -282.898614) (xy 131.687032 -282.925263) (xy 131.728703 -282.958494)
			(xy 131.764955 -282.997565) (xy 131.794979 -283.041602) (xy 131.818105 -283.089623) (xy 131.833815 -283.140553)
			(xy 131.841758 -283.193257) (xy 131.842256 -283.219906) (xy 131.841758 -283.246555) (xy 132.070084 -283.246555)
			(xy 132.070084 -283.193257) (xy 132.078027 -283.140553) (xy 132.093737 -283.089623) (xy 132.116863 -283.041602)
			(xy 132.146887 -282.997565) (xy 132.183139 -282.958494) (xy 132.22481 -282.925263) (xy 132.270968 -282.898614)
			(xy 132.320582 -282.879142) (xy 132.372544 -282.867282) (xy 132.425694 -282.863299) (xy 132.478844 -282.867282)
			(xy 132.530806 -282.879142) (xy 132.58042 -282.898614) (xy 132.626578 -282.925263) (xy 132.668249 -282.958494)
			(xy 132.704501 -282.997565) (xy 132.734525 -283.041602) (xy 132.757651 -283.089623) (xy 132.773361 -283.140553)
			(xy 132.781304 -283.193257) (xy 132.781802 -283.219906) (xy 132.781304 -283.246555) (xy 133.010138 -283.246555)
			(xy 133.010138 -283.193257) (xy 133.018081 -283.140553) (xy 133.033791 -283.089623) (xy 133.056917 -283.041602)
			(xy 133.086941 -282.997565) (xy 133.123193 -282.958494) (xy 133.164864 -282.925263) (xy 133.211022 -282.898614)
			(xy 133.260636 -282.879142) (xy 133.312598 -282.867282) (xy 133.365748 -282.863299) (xy 133.418898 -282.867282)
			(xy 133.47086 -282.879142) (xy 133.520474 -282.898614) (xy 133.566632 -282.925263) (xy 133.608303 -282.958494)
			(xy 133.644555 -282.997565) (xy 133.674579 -283.041602) (xy 133.697705 -283.089623) (xy 133.713415 -283.140553)
			(xy 133.721358 -283.193257) (xy 133.721856 -283.219906) (xy 133.721358 -283.246555) (xy 133.949938 -283.246555)
			(xy 133.949938 -283.193257) (xy 133.957881 -283.140553) (xy 133.973591 -283.089623) (xy 133.996717 -283.041602)
			(xy 134.026741 -282.997565) (xy 134.062993 -282.958494) (xy 134.104664 -282.925263) (xy 134.150822 -282.898614)
			(xy 134.200436 -282.879142) (xy 134.252398 -282.867282) (xy 134.305548 -282.863299) (xy 134.358698 -282.867282)
			(xy 134.41066 -282.879142) (xy 134.460274 -282.898614) (xy 134.506432 -282.925263) (xy 134.548103 -282.958494)
			(xy 134.584355 -282.997565) (xy 134.614379 -283.041602) (xy 134.637505 -283.089623) (xy 134.653215 -283.140553)
			(xy 134.661158 -283.193257) (xy 134.661656 -283.219906) (xy 134.661158 -283.246555) (xy 134.889484 -283.246555)
			(xy 134.889484 -283.193257) (xy 134.897427 -283.140553) (xy 134.913137 -283.089623) (xy 134.936263 -283.041602)
			(xy 134.966287 -282.997565) (xy 135.002539 -282.958494) (xy 135.04421 -282.925263) (xy 135.090368 -282.898614)
			(xy 135.139982 -282.879142) (xy 135.191944 -282.867282) (xy 135.245094 -282.863299) (xy 135.298244 -282.867282)
			(xy 135.350206 -282.879142) (xy 135.39982 -282.898614) (xy 135.445978 -282.925263) (xy 135.487649 -282.958494)
			(xy 135.523901 -282.997565) (xy 135.553925 -283.041602) (xy 135.577051 -283.089623) (xy 135.592761 -283.140553)
			(xy 135.600704 -283.193257) (xy 135.601202 -283.219906) (xy 135.600704 -283.246555) (xy 135.829284 -283.246555)
			(xy 135.829284 -283.193257) (xy 135.837227 -283.140553) (xy 135.852937 -283.089623) (xy 135.876063 -283.041602)
			(xy 135.906087 -282.997565) (xy 135.942339 -282.958494) (xy 135.98401 -282.925263) (xy 136.030168 -282.898614)
			(xy 136.079782 -282.879142) (xy 136.131744 -282.867282) (xy 136.184894 -282.863299) (xy 136.238044 -282.867282)
			(xy 136.290006 -282.879142) (xy 136.33962 -282.898614) (xy 136.385778 -282.925263) (xy 136.427449 -282.958494)
			(xy 136.463701 -282.997565) (xy 136.493725 -283.041602) (xy 136.516851 -283.089623) (xy 136.532561 -283.140553)
			(xy 136.540504 -283.193257) (xy 136.541002 -283.219906) (xy 136.540504 -283.246555) (xy 136.769338 -283.246555)
			(xy 136.769338 -283.193257) (xy 136.777281 -283.140553) (xy 136.792991 -283.089623) (xy 136.816117 -283.041602)
			(xy 136.846141 -282.997565) (xy 136.882393 -282.958494) (xy 136.924064 -282.925263) (xy 136.970222 -282.898614)
			(xy 137.019836 -282.879142) (xy 137.071798 -282.867282) (xy 137.124948 -282.863299) (xy 137.178098 -282.867282)
			(xy 137.23006 -282.879142) (xy 137.279674 -282.898614) (xy 137.325832 -282.925263) (xy 137.367503 -282.958494)
			(xy 137.403755 -282.997565) (xy 137.433779 -283.041602) (xy 137.456905 -283.089623) (xy 137.472615 -283.140553)
			(xy 137.480558 -283.193257) (xy 137.481056 -283.219906) (xy 137.480558 -283.246555) (xy 137.709138 -283.246555)
			(xy 137.709138 -283.193257) (xy 137.717081 -283.140553) (xy 137.732791 -283.089623) (xy 137.755917 -283.041602)
			(xy 137.785941 -282.997565) (xy 137.822193 -282.958494) (xy 137.863864 -282.925263) (xy 137.910022 -282.898614)
			(xy 137.959636 -282.879142) (xy 138.011598 -282.867282) (xy 138.064748 -282.863299) (xy 138.117898 -282.867282)
			(xy 138.16986 -282.879142) (xy 138.219474 -282.898614) (xy 138.265632 -282.925263) (xy 138.307303 -282.958494)
			(xy 138.343555 -282.997565) (xy 138.373579 -283.041602) (xy 138.396705 -283.089623) (xy 138.412415 -283.140553)
			(xy 138.420358 -283.193257) (xy 138.420856 -283.219906) (xy 138.420358 -283.246555) (xy 138.412415 -283.299259)
			(xy 138.396705 -283.350189) (xy 138.373579 -283.39821) (xy 138.343555 -283.442247) (xy 138.307303 -283.481318)
			(xy 138.265632 -283.514549) (xy 138.219474 -283.541198) (xy 138.16986 -283.56067) (xy 138.117898 -283.57253)
			(xy 138.064748 -283.576514) (xy 138.011598 -283.57253) (xy 137.959636 -283.56067) (xy 137.910022 -283.541198)
			(xy 137.863864 -283.514549) (xy 137.822193 -283.481318) (xy 137.785941 -283.442247) (xy 137.755917 -283.39821)
			(xy 137.732791 -283.350189) (xy 137.717081 -283.299259) (xy 137.709138 -283.246555) (xy 137.480558 -283.246555)
			(xy 137.472615 -283.299259) (xy 137.456905 -283.350189) (xy 137.433779 -283.39821) (xy 137.403755 -283.442247)
			(xy 137.367503 -283.481318) (xy 137.325832 -283.514549) (xy 137.279674 -283.541198) (xy 137.23006 -283.56067)
			(xy 137.178098 -283.57253) (xy 137.124948 -283.576514) (xy 137.071798 -283.57253) (xy 137.019836 -283.56067)
			(xy 136.970222 -283.541198) (xy 136.924064 -283.514549) (xy 136.882393 -283.481318) (xy 136.846141 -283.442247)
			(xy 136.816117 -283.39821) (xy 136.792991 -283.350189) (xy 136.777281 -283.299259) (xy 136.769338 -283.246555)
			(xy 136.540504 -283.246555) (xy 136.532561 -283.299259) (xy 136.516851 -283.350189) (xy 136.493725 -283.39821)
			(xy 136.463701 -283.442247) (xy 136.427449 -283.481318) (xy 136.385778 -283.514549) (xy 136.33962 -283.541198)
			(xy 136.290006 -283.56067) (xy 136.238044 -283.57253) (xy 136.184894 -283.576514) (xy 136.131744 -283.57253)
			(xy 136.079782 -283.56067) (xy 136.030168 -283.541198) (xy 135.98401 -283.514549) (xy 135.942339 -283.481318)
			(xy 135.906087 -283.442247) (xy 135.876063 -283.39821) (xy 135.852937 -283.350189) (xy 135.837227 -283.299259)
			(xy 135.829284 -283.246555) (xy 135.600704 -283.246555) (xy 135.592761 -283.299259) (xy 135.577051 -283.350189)
			(xy 135.553925 -283.39821) (xy 135.523901 -283.442247) (xy 135.487649 -283.481318) (xy 135.445978 -283.514549)
			(xy 135.39982 -283.541198) (xy 135.350206 -283.56067) (xy 135.298244 -283.57253) (xy 135.245094 -283.576514)
			(xy 135.191944 -283.57253) (xy 135.139982 -283.56067) (xy 135.090368 -283.541198) (xy 135.04421 -283.514549)
			(xy 135.002539 -283.481318) (xy 134.966287 -283.442247) (xy 134.936263 -283.39821) (xy 134.913137 -283.350189)
			(xy 134.897427 -283.299259) (xy 134.889484 -283.246555) (xy 134.661158 -283.246555) (xy 134.653215 -283.299259)
			(xy 134.637505 -283.350189) (xy 134.614379 -283.39821) (xy 134.584355 -283.442247) (xy 134.548103 -283.481318)
			(xy 134.506432 -283.514549) (xy 134.460274 -283.541198) (xy 134.41066 -283.56067) (xy 134.358698 -283.57253)
			(xy 134.305548 -283.576514) (xy 134.252398 -283.57253) (xy 134.200436 -283.56067) (xy 134.150822 -283.541198)
			(xy 134.104664 -283.514549) (xy 134.062993 -283.481318) (xy 134.026741 -283.442247) (xy 133.996717 -283.39821)
			(xy 133.973591 -283.350189) (xy 133.957881 -283.299259) (xy 133.949938 -283.246555) (xy 133.721358 -283.246555)
			(xy 133.713415 -283.299259) (xy 133.697705 -283.350189) (xy 133.674579 -283.39821) (xy 133.644555 -283.442247)
			(xy 133.608303 -283.481318) (xy 133.566632 -283.514549) (xy 133.520474 -283.541198) (xy 133.47086 -283.56067)
			(xy 133.418898 -283.57253) (xy 133.365748 -283.576514) (xy 133.312598 -283.57253) (xy 133.260636 -283.56067)
			(xy 133.211022 -283.541198) (xy 133.164864 -283.514549) (xy 133.123193 -283.481318) (xy 133.086941 -283.442247)
			(xy 133.056917 -283.39821) (xy 133.033791 -283.350189) (xy 133.018081 -283.299259) (xy 133.010138 -283.246555)
			(xy 132.781304 -283.246555) (xy 132.773361 -283.299259) (xy 132.757651 -283.350189) (xy 132.734525 -283.39821)
			(xy 132.704501 -283.442247) (xy 132.668249 -283.481318) (xy 132.626578 -283.514549) (xy 132.58042 -283.541198)
			(xy 132.530806 -283.56067) (xy 132.478844 -283.57253) (xy 132.425694 -283.576514) (xy 132.372544 -283.57253)
			(xy 132.320582 -283.56067) (xy 132.270968 -283.541198) (xy 132.22481 -283.514549) (xy 132.183139 -283.481318)
			(xy 132.146887 -283.442247) (xy 132.116863 -283.39821) (xy 132.093737 -283.350189) (xy 132.078027 -283.299259)
			(xy 132.070084 -283.246555) (xy 131.841758 -283.246555) (xy 131.833815 -283.299259) (xy 131.818105 -283.350189)
			(xy 131.794979 -283.39821) (xy 131.764955 -283.442247) (xy 131.728703 -283.481318) (xy 131.687032 -283.514549)
			(xy 131.640874 -283.541198) (xy 131.59126 -283.56067) (xy 131.539298 -283.57253) (xy 131.486148 -283.576514)
			(xy 131.432998 -283.57253) (xy 131.381036 -283.56067) (xy 131.331422 -283.541198) (xy 131.285264 -283.514549)
			(xy 131.243593 -283.481318) (xy 131.207341 -283.442247) (xy 131.177317 -283.39821) (xy 131.154191 -283.350189)
			(xy 131.138481 -283.299259) (xy 131.130538 -283.246555) (xy 130.901704 -283.246555) (xy 130.893761 -283.299259)
			(xy 130.878051 -283.350189) (xy 130.854925 -283.39821) (xy 130.824901 -283.442247) (xy 130.788649 -283.481318)
			(xy 130.746978 -283.514549) (xy 130.70082 -283.541198) (xy 130.651206 -283.56067) (xy 130.599244 -283.57253)
			(xy 130.546094 -283.576514) (xy 130.492944 -283.57253) (xy 130.440982 -283.56067) (xy 130.391368 -283.541198)
			(xy 130.34521 -283.514549) (xy 130.303539 -283.481318) (xy 130.267287 -283.442247) (xy 130.237263 -283.39821)
			(xy 130.214137 -283.350189) (xy 130.198427 -283.299259) (xy 130.190484 -283.246555) (xy 129.961904 -283.246555)
			(xy 129.953961 -283.299259) (xy 129.938251 -283.350189) (xy 129.915125 -283.39821) (xy 129.885101 -283.442247)
			(xy 129.848849 -283.481318) (xy 129.807178 -283.514549) (xy 129.76102 -283.541198) (xy 129.711406 -283.56067)
			(xy 129.659444 -283.57253) (xy 129.606294 -283.576514) (xy 129.553144 -283.57253) (xy 129.501182 -283.56067)
			(xy 129.451568 -283.541198) (xy 129.40541 -283.514549) (xy 129.363739 -283.481318) (xy 129.327487 -283.442247)
			(xy 129.297463 -283.39821) (xy 129.274337 -283.350189) (xy 129.258627 -283.299259) (xy 129.250684 -283.246555)
			(xy 129.022066 -283.246555) (xy 129.014161 -283.299005) (xy 128.998451 -283.349935) (xy 128.975325 -283.397956)
			(xy 128.945301 -283.441993) (xy 128.909049 -283.481064) (xy 128.867378 -283.514295) (xy 128.82122 -283.540944)
			(xy 128.771606 -283.560416) (xy 128.719644 -283.572276) (xy 128.666494 -283.57626) (xy 128.613344 -283.572276)
			(xy 128.561382 -283.560416) (xy 128.511768 -283.540944) (xy 128.46561 -283.514295) (xy 128.423939 -283.481064)
			(xy 128.387687 -283.441993) (xy 128.357663 -283.397956) (xy 128.334537 -283.349935) (xy 128.318827 -283.299005)
			(xy 128.310884 -283.246301) (xy 128.082563 -283.246301) (xy 128.082558 -283.246555) (xy 128.074615 -283.299259)
			(xy 128.058905 -283.350189) (xy 128.035779 -283.39821) (xy 128.005755 -283.442247) (xy 127.969503 -283.481318)
			(xy 127.927832 -283.514549) (xy 127.881674 -283.541198) (xy 127.83206 -283.56067) (xy 127.780098 -283.57253)
			(xy 127.726948 -283.576514) (xy 127.673798 -283.57253) (xy 127.621836 -283.56067) (xy 127.572222 -283.541198)
			(xy 127.526064 -283.514549) (xy 127.484393 -283.481318) (xy 127.448141 -283.442247) (xy 127.418117 -283.39821)
			(xy 127.394991 -283.350189) (xy 127.379281 -283.299259) (xy 127.371338 -283.246555) (xy 127.142504 -283.246555)
			(xy 127.134561 -283.299259) (xy 127.118851 -283.350189) (xy 127.095725 -283.39821) (xy 127.065701 -283.442247)
			(xy 127.029449 -283.481318) (xy 126.987778 -283.514549) (xy 126.94162 -283.541198) (xy 126.892006 -283.56067)
			(xy 126.840044 -283.57253) (xy 126.786894 -283.576514) (xy 126.733744 -283.57253) (xy 126.681782 -283.56067)
			(xy 126.632168 -283.541198) (xy 126.58601 -283.514549) (xy 126.544339 -283.481318) (xy 126.508087 -283.442247)
			(xy 126.478063 -283.39821) (xy 126.454937 -283.350189) (xy 126.439227 -283.299259) (xy 126.431284 -283.246555)
			(xy 126.202958 -283.246555) (xy 126.195015 -283.299259) (xy 126.179305 -283.350189) (xy 126.156179 -283.39821)
			(xy 126.126155 -283.442247) (xy 126.089903 -283.481318) (xy 126.048232 -283.514549) (xy 126.002074 -283.541198)
			(xy 125.95246 -283.56067) (xy 125.900498 -283.57253) (xy 125.847348 -283.576514) (xy 125.794198 -283.57253)
			(xy 125.742236 -283.56067) (xy 125.692622 -283.541198) (xy 125.646464 -283.514549) (xy 125.604793 -283.481318)
			(xy 125.568541 -283.442247) (xy 125.538517 -283.39821) (xy 125.515391 -283.350189) (xy 125.499681 -283.299259)
			(xy 125.491738 -283.246555) (xy 125.263158 -283.246555) (xy 125.255215 -283.299259) (xy 125.239505 -283.350189)
			(xy 125.216379 -283.39821) (xy 125.186355 -283.442247) (xy 125.150103 -283.481318) (xy 125.108432 -283.514549)
			(xy 125.062274 -283.541198) (xy 125.01266 -283.56067) (xy 124.960698 -283.57253) (xy 124.907548 -283.576514)
			(xy 124.854398 -283.57253) (xy 124.802436 -283.56067) (xy 124.752822 -283.541198) (xy 124.706664 -283.514549)
			(xy 124.664993 -283.481318) (xy 124.628741 -283.442247) (xy 124.598717 -283.39821) (xy 124.575591 -283.350189)
			(xy 124.559881 -283.299259) (xy 124.551938 -283.246555) (xy 124.323358 -283.246555) (xy 124.315415 -283.299259)
			(xy 124.299705 -283.350189) (xy 124.276579 -283.39821) (xy 124.246555 -283.442247) (xy 124.210303 -283.481318)
			(xy 124.168632 -283.514549) (xy 124.122474 -283.541198) (xy 124.07286 -283.56067) (xy 124.020898 -283.57253)
			(xy 123.967748 -283.576514) (xy 123.914598 -283.57253) (xy 123.862636 -283.56067) (xy 123.813022 -283.541198)
			(xy 123.766864 -283.514549) (xy 123.725193 -283.481318) (xy 123.688941 -283.442247) (xy 123.658917 -283.39821)
			(xy 123.635791 -283.350189) (xy 123.620081 -283.299259) (xy 123.612138 -283.246555) (xy 123.383558 -283.246555)
			(xy 123.375615 -283.299259) (xy 123.359905 -283.350189) (xy 123.336779 -283.39821) (xy 123.306755 -283.442247)
			(xy 123.270503 -283.481318) (xy 123.228832 -283.514549) (xy 123.182674 -283.541198) (xy 123.13306 -283.56067)
			(xy 123.081098 -283.57253) (xy 123.027948 -283.576514) (xy 122.974798 -283.57253) (xy 122.922836 -283.56067)
			(xy 122.873222 -283.541198) (xy 122.827064 -283.514549) (xy 122.785393 -283.481318) (xy 122.749141 -283.442247)
			(xy 122.719117 -283.39821) (xy 122.695991 -283.350189) (xy 122.680281 -283.299259) (xy 122.672338 -283.246555)
			(xy 122.443504 -283.246555) (xy 122.435561 -283.299259) (xy 122.419851 -283.350189) (xy 122.396725 -283.39821)
			(xy 122.366701 -283.442247) (xy 122.330449 -283.481318) (xy 122.288778 -283.514549) (xy 122.24262 -283.541198)
			(xy 122.193006 -283.56067) (xy 122.141044 -283.57253) (xy 122.087894 -283.576514) (xy 122.034744 -283.57253)
			(xy 121.982782 -283.56067) (xy 121.933168 -283.541198) (xy 121.88701 -283.514549) (xy 121.845339 -283.481318)
			(xy 121.809087 -283.442247) (xy 121.779063 -283.39821) (xy 121.755937 -283.350189) (xy 121.740227 -283.299259)
			(xy 121.732284 -283.246555) (xy 121.503704 -283.246555) (xy 121.495761 -283.299259) (xy 121.480051 -283.350189)
			(xy 121.456925 -283.39821) (xy 121.426901 -283.442247) (xy 121.390649 -283.481318) (xy 121.348978 -283.514549)
			(xy 121.30282 -283.541198) (xy 121.253206 -283.56067) (xy 121.201244 -283.57253) (xy 121.148094 -283.576514)
			(xy 121.094944 -283.57253) (xy 121.042982 -283.56067) (xy 120.993368 -283.541198) (xy 120.94721 -283.514549)
			(xy 120.905539 -283.481318) (xy 120.869287 -283.442247) (xy 120.839263 -283.39821) (xy 120.816137 -283.350189)
			(xy 120.800427 -283.299259) (xy 120.792484 -283.246555) (xy 120.564158 -283.246555) (xy 120.556215 -283.299259)
			(xy 120.540505 -283.350189) (xy 120.517379 -283.39821) (xy 120.487355 -283.442247) (xy 120.451103 -283.481318)
			(xy 120.409432 -283.514549) (xy 120.363274 -283.541198) (xy 120.31366 -283.56067) (xy 120.261698 -283.57253)
			(xy 120.208548 -283.576514) (xy 120.155398 -283.57253) (xy 120.103436 -283.56067) (xy 120.053822 -283.541198)
			(xy 120.007664 -283.514549) (xy 119.965993 -283.481318) (xy 119.929741 -283.442247) (xy 119.899717 -283.39821)
			(xy 119.876591 -283.350189) (xy 119.860881 -283.299259) (xy 119.852938 -283.246555) (xy 119.624104 -283.246555)
			(xy 119.616161 -283.299259) (xy 119.600451 -283.350189) (xy 119.577325 -283.39821) (xy 119.547301 -283.442247)
			(xy 119.511049 -283.481318) (xy 119.469378 -283.514549) (xy 119.42322 -283.541198) (xy 119.373606 -283.56067)
			(xy 119.321644 -283.57253) (xy 119.268494 -283.576514) (xy 119.215344 -283.57253) (xy 119.163382 -283.56067)
			(xy 119.113768 -283.541198) (xy 119.06761 -283.514549) (xy 119.025939 -283.481318) (xy 118.989687 -283.442247)
			(xy 118.959663 -283.39821) (xy 118.936537 -283.350189) (xy 118.920827 -283.299259) (xy 118.912884 -283.246555)
			(xy 118.684558 -283.246555) (xy 118.676615 -283.299259) (xy 118.660905 -283.350189) (xy 118.637779 -283.39821)
			(xy 118.607755 -283.442247) (xy 118.571503 -283.481318) (xy 118.529832 -283.514549) (xy 118.483674 -283.541198)
			(xy 118.43406 -283.56067) (xy 118.382098 -283.57253) (xy 118.328948 -283.576514) (xy 118.275798 -283.57253)
			(xy 118.223836 -283.56067) (xy 118.174222 -283.541198) (xy 118.128064 -283.514549) (xy 118.086393 -283.481318)
			(xy 118.050141 -283.442247) (xy 118.020117 -283.39821) (xy 117.996991 -283.350189) (xy 117.981281 -283.299259)
			(xy 117.973338 -283.246555) (xy 116.804958 -283.246555) (xy 116.797015 -283.299259) (xy 116.781305 -283.350189)
			(xy 116.758179 -283.39821) (xy 116.728155 -283.442247) (xy 116.691903 -283.481318) (xy 116.650232 -283.514549)
			(xy 116.604074 -283.541198) (xy 116.55446 -283.56067) (xy 116.502498 -283.57253) (xy 116.449348 -283.576514)
			(xy 116.396198 -283.57253) (xy 116.344236 -283.56067) (xy 116.294622 -283.541198) (xy 116.248464 -283.514549)
			(xy 116.206793 -283.481318) (xy 116.170541 -283.442247) (xy 116.140517 -283.39821) (xy 116.117391 -283.350189)
			(xy 116.101681 -283.299259) (xy 116.093738 -283.246555) (xy 113.985304 -283.246555) (xy 113.977361 -283.299259)
			(xy 113.961651 -283.350189) (xy 113.938525 -283.39821) (xy 113.908501 -283.442247) (xy 113.872249 -283.481318)
			(xy 113.830578 -283.514549) (xy 113.78442 -283.541198) (xy 113.734806 -283.56067) (xy 113.682844 -283.57253)
			(xy 113.629694 -283.576514) (xy 113.576544 -283.57253) (xy 113.524582 -283.56067) (xy 113.474968 -283.541198)
			(xy 113.42881 -283.514549) (xy 113.387139 -283.481318) (xy 113.350887 -283.442247) (xy 113.320863 -283.39821)
			(xy 113.297737 -283.350189) (xy 113.282027 -283.299259) (xy 113.274084 -283.246555) (xy 107.406958 -283.246555)
			(xy 107.399015 -283.299259) (xy 107.383305 -283.350189) (xy 107.360179 -283.39821) (xy 107.330155 -283.442247)
			(xy 107.293903 -283.481318) (xy 107.252232 -283.514549) (xy 107.206074 -283.541198) (xy 107.15646 -283.56067)
			(xy 107.104498 -283.57253) (xy 107.051348 -283.576514) (xy 106.998198 -283.57253) (xy 106.946236 -283.56067)
			(xy 106.896622 -283.541198) (xy 106.850464 -283.514549) (xy 106.808793 -283.481318) (xy 106.772541 -283.442247)
			(xy 106.742517 -283.39821) (xy 106.719391 -283.350189) (xy 106.703681 -283.299259) (xy 106.695738 -283.246555)
			(xy 106.466904 -283.246555) (xy 106.458961 -283.299259) (xy 106.443251 -283.350189) (xy 106.420125 -283.39821)
			(xy 106.390101 -283.442247) (xy 106.353849 -283.481318) (xy 106.312178 -283.514549) (xy 106.26602 -283.541198)
			(xy 106.216406 -283.56067) (xy 106.164444 -283.57253) (xy 106.111294 -283.576514) (xy 106.058144 -283.57253)
			(xy 106.006182 -283.56067) (xy 105.956568 -283.541198) (xy 105.91041 -283.514549) (xy 105.868739 -283.481318)
			(xy 105.832487 -283.442247) (xy 105.802463 -283.39821) (xy 105.779337 -283.350189) (xy 105.763627 -283.299259)
			(xy 105.755684 -283.246555) (xy 105.526482 -283.246555) (xy 105.525461 -283.265467) (xy 105.514826 -283.317284)
			(xy 105.496641 -283.366956) (xy 105.471305 -283.41339) (xy 105.439377 -283.455565) (xy 105.40156 -283.49255)
			(xy 105.358687 -283.523533) (xy 105.311701 -283.54783) (xy 105.261636 -283.564906) (xy 105.209596 -283.574387)
			(xy 105.183178 -283.57576) (xy 105.182162 -283.57576) (xy 105.17355 -283.576575) (xy 105.157578 -283.583192)
			(xy 105.15092 -283.588714) (xy 105.09758 -283.643832) (xy 105.0918 -283.650987) (xy 105.085275 -283.668171)
			(xy 105.08488 -283.67736) (xy 105.08488 -284.060371) (xy 105.285784 -284.060371) (xy 105.285784 -284.007073)
			(xy 105.293727 -283.954369) (xy 105.309437 -283.903439) (xy 105.332563 -283.855418) (xy 105.362587 -283.811381)
			(xy 105.398839 -283.77231) (xy 105.44051 -283.739079) (xy 105.486668 -283.71243) (xy 105.536282 -283.692958)
			(xy 105.588244 -283.681098) (xy 105.641394 -283.677115) (xy 105.694544 -283.681098) (xy 105.746506 -283.692958)
			(xy 105.79612 -283.71243) (xy 105.842278 -283.739079) (xy 105.883949 -283.77231) (xy 105.920201 -283.811381)
			(xy 105.950225 -283.855418) (xy 105.973351 -283.903439) (xy 105.989061 -283.954369) (xy 105.997004 -284.007073)
			(xy 105.997502 -284.033722) (xy 105.997004 -284.060371) (xy 107.165384 -284.060371) (xy 107.165384 -284.007073)
			(xy 107.173327 -283.954369) (xy 107.189037 -283.903439) (xy 107.212163 -283.855418) (xy 107.242187 -283.811381)
			(xy 107.278439 -283.77231) (xy 107.32011 -283.739079) (xy 107.366268 -283.71243) (xy 107.415882 -283.692958)
			(xy 107.467844 -283.681098) (xy 107.520994 -283.677115) (xy 107.574144 -283.681098) (xy 107.626106 -283.692958)
			(xy 107.67572 -283.71243) (xy 107.721878 -283.739079) (xy 107.763549 -283.77231) (xy 107.799801 -283.811381)
			(xy 107.829825 -283.855418) (xy 107.852951 -283.903439) (xy 107.868661 -283.954369) (xy 107.876604 -284.007073)
			(xy 107.877102 -284.033722) (xy 107.876604 -284.060371) (xy 109.984784 -284.060371) (xy 109.984784 -284.007073)
			(xy 109.992727 -283.954369) (xy 110.008437 -283.903439) (xy 110.031563 -283.855418) (xy 110.061587 -283.811381)
			(xy 110.097839 -283.77231) (xy 110.13951 -283.739079) (xy 110.185668 -283.71243) (xy 110.235282 -283.692958)
			(xy 110.287244 -283.681098) (xy 110.340394 -283.677115) (xy 110.393544 -283.681098) (xy 110.445506 -283.692958)
			(xy 110.49512 -283.71243) (xy 110.541278 -283.739079) (xy 110.582949 -283.77231) (xy 110.619201 -283.811381)
			(xy 110.649225 -283.855418) (xy 110.672351 -283.903439) (xy 110.688061 -283.954369) (xy 110.696004 -284.007073)
			(xy 110.696502 -284.033722) (xy 110.696004 -284.060371) (xy 118.442984 -284.060371) (xy 118.442984 -284.007073)
			(xy 118.450927 -283.954369) (xy 118.466637 -283.903439) (xy 118.489763 -283.855418) (xy 118.519787 -283.811381)
			(xy 118.556039 -283.77231) (xy 118.59771 -283.739079) (xy 118.643868 -283.71243) (xy 118.693482 -283.692958)
			(xy 118.745444 -283.681098) (xy 118.798594 -283.677115) (xy 118.851744 -283.681098) (xy 118.903706 -283.692958)
			(xy 118.95332 -283.71243) (xy 118.999478 -283.739079) (xy 119.041149 -283.77231) (xy 119.077401 -283.811381)
			(xy 119.107425 -283.855418) (xy 119.130551 -283.903439) (xy 119.146261 -283.954369) (xy 119.154204 -284.007073)
			(xy 119.154702 -284.033722) (xy 119.154204 -284.060371) (xy 119.382784 -284.060371) (xy 119.382784 -284.007073)
			(xy 119.390727 -283.954369) (xy 119.406437 -283.903439) (xy 119.429563 -283.855418) (xy 119.459587 -283.811381)
			(xy 119.495839 -283.77231) (xy 119.53751 -283.739079) (xy 119.583668 -283.71243) (xy 119.633282 -283.692958)
			(xy 119.685244 -283.681098) (xy 119.738394 -283.677115) (xy 119.791544 -283.681098) (xy 119.843506 -283.692958)
			(xy 119.89312 -283.71243) (xy 119.939278 -283.739079) (xy 119.980949 -283.77231) (xy 120.017201 -283.811381)
			(xy 120.047225 -283.855418) (xy 120.070351 -283.903439) (xy 120.086061 -283.954369) (xy 120.094004 -284.007073)
			(xy 120.094502 -284.033722) (xy 120.094004 -284.060371) (xy 120.322584 -284.060371) (xy 120.322584 -284.007073)
			(xy 120.330527 -283.954369) (xy 120.346237 -283.903439) (xy 120.369363 -283.855418) (xy 120.399387 -283.811381)
			(xy 120.435639 -283.77231) (xy 120.47731 -283.739079) (xy 120.523468 -283.71243) (xy 120.573082 -283.692958)
			(xy 120.625044 -283.681098) (xy 120.678194 -283.677115) (xy 120.731344 -283.681098) (xy 120.783306 -283.692958)
			(xy 120.83292 -283.71243) (xy 120.879078 -283.739079) (xy 120.920749 -283.77231) (xy 120.957001 -283.811381)
			(xy 120.987025 -283.855418) (xy 121.010151 -283.903439) (xy 121.025861 -283.954369) (xy 121.033804 -284.007073)
			(xy 121.034302 -284.033722) (xy 121.033804 -284.060371) (xy 121.262384 -284.060371) (xy 121.262384 -284.007073)
			(xy 121.270327 -283.954369) (xy 121.286037 -283.903439) (xy 121.309163 -283.855418) (xy 121.339187 -283.811381)
			(xy 121.375439 -283.77231) (xy 121.41711 -283.739079) (xy 121.463268 -283.71243) (xy 121.512882 -283.692958)
			(xy 121.564844 -283.681098) (xy 121.617994 -283.677115) (xy 121.671144 -283.681098) (xy 121.723106 -283.692958)
			(xy 121.77272 -283.71243) (xy 121.818878 -283.739079) (xy 121.860549 -283.77231) (xy 121.896801 -283.811381)
			(xy 121.926825 -283.855418) (xy 121.949951 -283.903439) (xy 121.965661 -283.954369) (xy 121.973604 -284.007073)
			(xy 121.974102 -284.033722) (xy 121.973604 -284.060371) (xy 122.202184 -284.060371) (xy 122.202184 -284.007073)
			(xy 122.210127 -283.954369) (xy 122.225837 -283.903439) (xy 122.248963 -283.855418) (xy 122.278987 -283.811381)
			(xy 122.315239 -283.77231) (xy 122.35691 -283.739079) (xy 122.403068 -283.71243) (xy 122.452682 -283.692958)
			(xy 122.504644 -283.681098) (xy 122.557794 -283.677115) (xy 122.610944 -283.681098) (xy 122.662906 -283.692958)
			(xy 122.71252 -283.71243) (xy 122.758678 -283.739079) (xy 122.800349 -283.77231) (xy 122.836601 -283.811381)
			(xy 122.866625 -283.855418) (xy 122.889751 -283.903439) (xy 122.905461 -283.954369) (xy 122.913404 -284.007073)
			(xy 122.913902 -284.033722) (xy 122.913404 -284.060371) (xy 123.141984 -284.060371) (xy 123.141984 -284.007073)
			(xy 123.149927 -283.954369) (xy 123.165637 -283.903439) (xy 123.188763 -283.855418) (xy 123.218787 -283.811381)
			(xy 123.255039 -283.77231) (xy 123.29671 -283.739079) (xy 123.342868 -283.71243) (xy 123.392482 -283.692958)
			(xy 123.444444 -283.681098) (xy 123.497594 -283.677115) (xy 123.550744 -283.681098) (xy 123.602706 -283.692958)
			(xy 123.65232 -283.71243) (xy 123.698478 -283.739079) (xy 123.740149 -283.77231) (xy 123.776401 -283.811381)
			(xy 123.806425 -283.855418) (xy 123.829551 -283.903439) (xy 123.845261 -283.954369) (xy 123.853204 -284.007073)
			(xy 123.853702 -284.033722) (xy 123.853204 -284.060371) (xy 124.081784 -284.060371) (xy 124.081784 -284.007073)
			(xy 124.089727 -283.954369) (xy 124.105437 -283.903439) (xy 124.128563 -283.855418) (xy 124.158587 -283.811381)
			(xy 124.194839 -283.77231) (xy 124.23651 -283.739079) (xy 124.282668 -283.71243) (xy 124.332282 -283.692958)
			(xy 124.384244 -283.681098) (xy 124.437394 -283.677115) (xy 124.490544 -283.681098) (xy 124.542506 -283.692958)
			(xy 124.59212 -283.71243) (xy 124.638278 -283.739079) (xy 124.679949 -283.77231) (xy 124.716201 -283.811381)
			(xy 124.746225 -283.855418) (xy 124.769351 -283.903439) (xy 124.785061 -283.954369) (xy 124.793004 -284.007073)
			(xy 124.793502 -284.033722) (xy 124.793004 -284.060371) (xy 125.021838 -284.060371) (xy 125.021838 -284.007073)
			(xy 125.029781 -283.954369) (xy 125.045491 -283.903439) (xy 125.068617 -283.855418) (xy 125.098641 -283.811381)
			(xy 125.134893 -283.77231) (xy 125.176564 -283.739079) (xy 125.222722 -283.71243) (xy 125.272336 -283.692958)
			(xy 125.324298 -283.681098) (xy 125.377448 -283.677115) (xy 125.430598 -283.681098) (xy 125.48256 -283.692958)
			(xy 125.532174 -283.71243) (xy 125.578332 -283.739079) (xy 125.620003 -283.77231) (xy 125.656255 -283.811381)
			(xy 125.686279 -283.855418) (xy 125.709405 -283.903439) (xy 125.725115 -283.954369) (xy 125.733058 -284.007073)
			(xy 125.733556 -284.033722) (xy 125.733058 -284.060371) (xy 125.961384 -284.060371) (xy 125.961384 -284.007073)
			(xy 125.969327 -283.954369) (xy 125.985037 -283.903439) (xy 126.008163 -283.855418) (xy 126.038187 -283.811381)
			(xy 126.074439 -283.77231) (xy 126.11611 -283.739079) (xy 126.162268 -283.71243) (xy 126.211882 -283.692958)
			(xy 126.263844 -283.681098) (xy 126.316994 -283.677115) (xy 126.370144 -283.681098) (xy 126.422106 -283.692958)
			(xy 126.47172 -283.71243) (xy 126.517878 -283.739079) (xy 126.559549 -283.77231) (xy 126.595801 -283.811381)
			(xy 126.625825 -283.855418) (xy 126.648951 -283.903439) (xy 126.664661 -283.954369) (xy 126.672604 -284.007073)
			(xy 126.673102 -284.033722) (xy 126.672604 -284.060371) (xy 126.901184 -284.060371) (xy 126.901184 -284.007073)
			(xy 126.909127 -283.954369) (xy 126.924837 -283.903439) (xy 126.947963 -283.855418) (xy 126.977987 -283.811381)
			(xy 127.014239 -283.77231) (xy 127.05591 -283.739079) (xy 127.102068 -283.71243) (xy 127.151682 -283.692958)
			(xy 127.203644 -283.681098) (xy 127.256794 -283.677115) (xy 127.309944 -283.681098) (xy 127.361906 -283.692958)
			(xy 127.41152 -283.71243) (xy 127.457678 -283.739079) (xy 127.499349 -283.77231) (xy 127.535601 -283.811381)
			(xy 127.565625 -283.855418) (xy 127.588751 -283.903439) (xy 127.604461 -283.954369) (xy 127.612404 -284.007073)
			(xy 127.612902 -284.033722) (xy 127.612404 -284.060371) (xy 127.840984 -284.060371) (xy 127.840984 -284.007073)
			(xy 127.848927 -283.954369) (xy 127.864637 -283.903439) (xy 127.887763 -283.855418) (xy 127.917787 -283.811381)
			(xy 127.954039 -283.77231) (xy 127.99571 -283.739079) (xy 128.041868 -283.71243) (xy 128.091482 -283.692958)
			(xy 128.143444 -283.681098) (xy 128.196594 -283.677115) (xy 128.249744 -283.681098) (xy 128.301706 -283.692958)
			(xy 128.35132 -283.71243) (xy 128.397478 -283.739079) (xy 128.439149 -283.77231) (xy 128.475401 -283.811381)
			(xy 128.505425 -283.855418) (xy 128.528551 -283.903439) (xy 128.544261 -283.954369) (xy 128.552204 -284.007073)
			(xy 128.552702 -284.033722) (xy 128.552204 -284.060371) (xy 128.780784 -284.060371) (xy 128.780784 -284.007073)
			(xy 128.788727 -283.954369) (xy 128.804437 -283.903439) (xy 128.827563 -283.855418) (xy 128.857587 -283.811381)
			(xy 128.893839 -283.77231) (xy 128.93551 -283.739079) (xy 128.981668 -283.71243) (xy 129.031282 -283.692958)
			(xy 129.083244 -283.681098) (xy 129.136394 -283.677115) (xy 129.189544 -283.681098) (xy 129.241506 -283.692958)
			(xy 129.29112 -283.71243) (xy 129.337278 -283.739079) (xy 129.378949 -283.77231) (xy 129.415201 -283.811381)
			(xy 129.445225 -283.855418) (xy 129.468351 -283.903439) (xy 129.484061 -283.954369) (xy 129.492004 -284.007073)
			(xy 129.492502 -284.033722) (xy 129.492004 -284.060371) (xy 129.720584 -284.060371) (xy 129.720584 -284.007073)
			(xy 129.728527 -283.954369) (xy 129.744237 -283.903439) (xy 129.767363 -283.855418) (xy 129.797387 -283.811381)
			(xy 129.833639 -283.77231) (xy 129.87531 -283.739079) (xy 129.921468 -283.71243) (xy 129.971082 -283.692958)
			(xy 130.023044 -283.681098) (xy 130.076194 -283.677115) (xy 130.129344 -283.681098) (xy 130.181306 -283.692958)
			(xy 130.23092 -283.71243) (xy 130.277078 -283.739079) (xy 130.318749 -283.77231) (xy 130.355001 -283.811381)
			(xy 130.385025 -283.855418) (xy 130.408151 -283.903439) (xy 130.423861 -283.954369) (xy 130.431804 -284.007073)
			(xy 130.432302 -284.033722) (xy 130.431804 -284.060371) (xy 130.660384 -284.060371) (xy 130.660384 -284.007073)
			(xy 130.668327 -283.954369) (xy 130.684037 -283.903439) (xy 130.707163 -283.855418) (xy 130.737187 -283.811381)
			(xy 130.773439 -283.77231) (xy 130.81511 -283.739079) (xy 130.861268 -283.71243) (xy 130.910882 -283.692958)
			(xy 130.962844 -283.681098) (xy 131.015994 -283.677115) (xy 131.069144 -283.681098) (xy 131.121106 -283.692958)
			(xy 131.17072 -283.71243) (xy 131.216878 -283.739079) (xy 131.258549 -283.77231) (xy 131.294801 -283.811381)
			(xy 131.324825 -283.855418) (xy 131.347951 -283.903439) (xy 131.363661 -283.954369) (xy 131.371604 -284.007073)
			(xy 131.372102 -284.033722) (xy 131.371604 -284.060371) (xy 131.600184 -284.060371) (xy 131.600184 -284.007073)
			(xy 131.608127 -283.954369) (xy 131.623837 -283.903439) (xy 131.646963 -283.855418) (xy 131.676987 -283.811381)
			(xy 131.713239 -283.77231) (xy 131.75491 -283.739079) (xy 131.801068 -283.71243) (xy 131.850682 -283.692958)
			(xy 131.902644 -283.681098) (xy 131.955794 -283.677115) (xy 132.008944 -283.681098) (xy 132.060906 -283.692958)
			(xy 132.11052 -283.71243) (xy 132.156678 -283.739079) (xy 132.198349 -283.77231) (xy 132.234601 -283.811381)
			(xy 132.264625 -283.855418) (xy 132.287751 -283.903439) (xy 132.303461 -283.954369) (xy 132.311404 -284.007073)
			(xy 132.311902 -284.033722) (xy 132.311404 -284.060371) (xy 132.539984 -284.060371) (xy 132.539984 -284.007073)
			(xy 132.547927 -283.954369) (xy 132.563637 -283.903439) (xy 132.586763 -283.855418) (xy 132.616787 -283.811381)
			(xy 132.653039 -283.77231) (xy 132.69471 -283.739079) (xy 132.740868 -283.71243) (xy 132.790482 -283.692958)
			(xy 132.842444 -283.681098) (xy 132.895594 -283.677115) (xy 132.948744 -283.681098) (xy 133.000706 -283.692958)
			(xy 133.05032 -283.71243) (xy 133.096478 -283.739079) (xy 133.138149 -283.77231) (xy 133.174401 -283.811381)
			(xy 133.204425 -283.855418) (xy 133.227551 -283.903439) (xy 133.243261 -283.954369) (xy 133.251204 -284.007073)
			(xy 133.251702 -284.033722) (xy 133.251204 -284.060371) (xy 133.479784 -284.060371) (xy 133.479784 -284.007073)
			(xy 133.487727 -283.954369) (xy 133.503437 -283.903439) (xy 133.526563 -283.855418) (xy 133.556587 -283.811381)
			(xy 133.592839 -283.77231) (xy 133.63451 -283.739079) (xy 133.680668 -283.71243) (xy 133.730282 -283.692958)
			(xy 133.782244 -283.681098) (xy 133.835394 -283.677115) (xy 133.888544 -283.681098) (xy 133.940506 -283.692958)
			(xy 133.99012 -283.71243) (xy 134.036278 -283.739079) (xy 134.077949 -283.77231) (xy 134.114201 -283.811381)
			(xy 134.144225 -283.855418) (xy 134.167351 -283.903439) (xy 134.183061 -283.954369) (xy 134.191004 -284.007073)
			(xy 134.191502 -284.033722) (xy 134.191004 -284.060371) (xy 134.419584 -284.060371) (xy 134.419584 -284.007073)
			(xy 134.427527 -283.954369) (xy 134.443237 -283.903439) (xy 134.466363 -283.855418) (xy 134.496387 -283.811381)
			(xy 134.532639 -283.77231) (xy 134.57431 -283.739079) (xy 134.620468 -283.71243) (xy 134.670082 -283.692958)
			(xy 134.722044 -283.681098) (xy 134.775194 -283.677115) (xy 134.828344 -283.681098) (xy 134.880306 -283.692958)
			(xy 134.92992 -283.71243) (xy 134.976078 -283.739079) (xy 135.017749 -283.77231) (xy 135.054001 -283.811381)
			(xy 135.084025 -283.855418) (xy 135.107151 -283.903439) (xy 135.122861 -283.954369) (xy 135.130804 -284.007073)
			(xy 135.131302 -284.033722) (xy 135.130804 -284.060371) (xy 135.359384 -284.060371) (xy 135.359384 -284.007073)
			(xy 135.367327 -283.954369) (xy 135.383037 -283.903439) (xy 135.406163 -283.855418) (xy 135.436187 -283.811381)
			(xy 135.472439 -283.77231) (xy 135.51411 -283.739079) (xy 135.560268 -283.71243) (xy 135.609882 -283.692958)
			(xy 135.661844 -283.681098) (xy 135.714994 -283.677115) (xy 135.768144 -283.681098) (xy 135.820106 -283.692958)
			(xy 135.86972 -283.71243) (xy 135.915878 -283.739079) (xy 135.957549 -283.77231) (xy 135.993801 -283.811381)
			(xy 136.023825 -283.855418) (xy 136.046951 -283.903439) (xy 136.062661 -283.954369) (xy 136.070604 -284.007073)
			(xy 136.071102 -284.033722) (xy 136.070609 -284.060117) (xy 136.29893 -284.060117) (xy 136.29893 -284.006819)
			(xy 136.306873 -283.954115) (xy 136.322583 -283.903185) (xy 136.345709 -283.855164) (xy 136.375733 -283.811127)
			(xy 136.411985 -283.772056) (xy 136.453656 -283.738825) (xy 136.499814 -283.712176) (xy 136.549428 -283.692704)
			(xy 136.60139 -283.680844) (xy 136.65454 -283.676861) (xy 136.70769 -283.680844) (xy 136.759652 -283.692704)
			(xy 136.809266 -283.712176) (xy 136.855424 -283.738825) (xy 136.897095 -283.772056) (xy 136.933347 -283.811127)
			(xy 136.963371 -283.855164) (xy 136.986497 -283.903185) (xy 137.002207 -283.954115) (xy 137.01015 -284.006819)
			(xy 137.010648 -284.033468) (xy 137.01015 -284.060117) (xy 137.010112 -284.060371) (xy 137.238984 -284.060371)
			(xy 137.238984 -284.007073) (xy 137.246927 -283.954369) (xy 137.262637 -283.903439) (xy 137.285763 -283.855418)
			(xy 137.315787 -283.811381) (xy 137.352039 -283.77231) (xy 137.39371 -283.739079) (xy 137.439868 -283.71243)
			(xy 137.489482 -283.692958) (xy 137.541444 -283.681098) (xy 137.594594 -283.677115) (xy 137.647744 -283.681098)
			(xy 137.699706 -283.692958) (xy 137.74932 -283.71243) (xy 137.795478 -283.739079) (xy 137.837149 -283.77231)
			(xy 137.873401 -283.811381) (xy 137.903425 -283.855418) (xy 137.926551 -283.903439) (xy 137.942261 -283.954369)
			(xy 137.950204 -284.007073) (xy 137.950702 -284.033722) (xy 137.950204 -284.060371) (xy 138.178784 -284.060371)
			(xy 138.178784 -284.007073) (xy 138.186727 -283.954369) (xy 138.202437 -283.903439) (xy 138.225563 -283.855418)
			(xy 138.255587 -283.811381) (xy 138.291839 -283.77231) (xy 138.33351 -283.739079) (xy 138.379668 -283.71243)
			(xy 138.429282 -283.692958) (xy 138.481244 -283.681098) (xy 138.534394 -283.677115) (xy 138.587544 -283.681098)
			(xy 138.639506 -283.692958) (xy 138.68912 -283.71243) (xy 138.735278 -283.739079) (xy 138.776949 -283.77231)
			(xy 138.813201 -283.811381) (xy 138.843225 -283.855418) (xy 138.866351 -283.903439) (xy 138.882061 -283.954369)
			(xy 138.890004 -284.007073) (xy 138.890502 -284.033722) (xy 138.890004 -284.060371) (xy 138.882061 -284.113075)
			(xy 138.866351 -284.164005) (xy 138.843225 -284.212026) (xy 138.813201 -284.256063) (xy 138.776949 -284.295134)
			(xy 138.735278 -284.328365) (xy 138.68912 -284.355014) (xy 138.639506 -284.374486) (xy 138.587544 -284.386346)
			(xy 138.534394 -284.39033) (xy 138.481244 -284.386346) (xy 138.429282 -284.374486) (xy 138.379668 -284.355014)
			(xy 138.33351 -284.328365) (xy 138.291839 -284.295134) (xy 138.255587 -284.256063) (xy 138.225563 -284.212026)
			(xy 138.202437 -284.164005) (xy 138.186727 -284.113075) (xy 138.178784 -284.060371) (xy 137.950204 -284.060371)
			(xy 137.942261 -284.113075) (xy 137.926551 -284.164005) (xy 137.903425 -284.212026) (xy 137.873401 -284.256063)
			(xy 137.837149 -284.295134) (xy 137.795478 -284.328365) (xy 137.74932 -284.355014) (xy 137.699706 -284.374486)
			(xy 137.647744 -284.386346) (xy 137.594594 -284.39033) (xy 137.541444 -284.386346) (xy 137.489482 -284.374486)
			(xy 137.439868 -284.355014) (xy 137.39371 -284.328365) (xy 137.352039 -284.295134) (xy 137.315787 -284.256063)
			(xy 137.285763 -284.212026) (xy 137.262637 -284.164005) (xy 137.246927 -284.113075) (xy 137.238984 -284.060371)
			(xy 137.010112 -284.060371) (xy 137.002207 -284.112821) (xy 136.986497 -284.163751) (xy 136.963371 -284.211772)
			(xy 136.933347 -284.255809) (xy 136.897095 -284.29488) (xy 136.855424 -284.328111) (xy 136.809266 -284.35476)
			(xy 136.759652 -284.374232) (xy 136.70769 -284.386092) (xy 136.65454 -284.390076) (xy 136.60139 -284.386092)
			(xy 136.549428 -284.374232) (xy 136.499814 -284.35476) (xy 136.453656 -284.328111) (xy 136.411985 -284.29488)
			(xy 136.375733 -284.255809) (xy 136.345709 -284.211772) (xy 136.322583 -284.163751) (xy 136.306873 -284.112821)
			(xy 136.29893 -284.060117) (xy 136.070609 -284.060117) (xy 136.070604 -284.060371) (xy 136.062661 -284.113075)
			(xy 136.046951 -284.164005) (xy 136.023825 -284.212026) (xy 135.993801 -284.256063) (xy 135.957549 -284.295134)
			(xy 135.915878 -284.328365) (xy 135.86972 -284.355014) (xy 135.820106 -284.374486) (xy 135.768144 -284.386346)
			(xy 135.714994 -284.39033) (xy 135.661844 -284.386346) (xy 135.609882 -284.374486) (xy 135.560268 -284.355014)
			(xy 135.51411 -284.328365) (xy 135.472439 -284.295134) (xy 135.436187 -284.256063) (xy 135.406163 -284.212026)
			(xy 135.383037 -284.164005) (xy 135.367327 -284.113075) (xy 135.359384 -284.060371) (xy 135.130804 -284.060371)
			(xy 135.122861 -284.113075) (xy 135.107151 -284.164005) (xy 135.084025 -284.212026) (xy 135.054001 -284.256063)
			(xy 135.017749 -284.295134) (xy 134.976078 -284.328365) (xy 134.92992 -284.355014) (xy 134.880306 -284.374486)
			(xy 134.828344 -284.386346) (xy 134.775194 -284.39033) (xy 134.722044 -284.386346) (xy 134.670082 -284.374486)
			(xy 134.620468 -284.355014) (xy 134.57431 -284.328365) (xy 134.532639 -284.295134) (xy 134.496387 -284.256063)
			(xy 134.466363 -284.212026) (xy 134.443237 -284.164005) (xy 134.427527 -284.113075) (xy 134.419584 -284.060371)
			(xy 134.191004 -284.060371) (xy 134.183061 -284.113075) (xy 134.167351 -284.164005) (xy 134.144225 -284.212026)
			(xy 134.114201 -284.256063) (xy 134.077949 -284.295134) (xy 134.036278 -284.328365) (xy 133.99012 -284.355014)
			(xy 133.940506 -284.374486) (xy 133.888544 -284.386346) (xy 133.835394 -284.39033) (xy 133.782244 -284.386346)
			(xy 133.730282 -284.374486) (xy 133.680668 -284.355014) (xy 133.63451 -284.328365) (xy 133.592839 -284.295134)
			(xy 133.556587 -284.256063) (xy 133.526563 -284.212026) (xy 133.503437 -284.164005) (xy 133.487727 -284.113075)
			(xy 133.479784 -284.060371) (xy 133.251204 -284.060371) (xy 133.243261 -284.113075) (xy 133.227551 -284.164005)
			(xy 133.204425 -284.212026) (xy 133.174401 -284.256063) (xy 133.138149 -284.295134) (xy 133.096478 -284.328365)
			(xy 133.05032 -284.355014) (xy 133.000706 -284.374486) (xy 132.948744 -284.386346) (xy 132.895594 -284.39033)
			(xy 132.842444 -284.386346) (xy 132.790482 -284.374486) (xy 132.740868 -284.355014) (xy 132.69471 -284.328365)
			(xy 132.653039 -284.295134) (xy 132.616787 -284.256063) (xy 132.586763 -284.212026) (xy 132.563637 -284.164005)
			(xy 132.547927 -284.113075) (xy 132.539984 -284.060371) (xy 132.311404 -284.060371) (xy 132.303461 -284.113075)
			(xy 132.287751 -284.164005) (xy 132.264625 -284.212026) (xy 132.234601 -284.256063) (xy 132.198349 -284.295134)
			(xy 132.156678 -284.328365) (xy 132.11052 -284.355014) (xy 132.060906 -284.374486) (xy 132.008944 -284.386346)
			(xy 131.955794 -284.39033) (xy 131.902644 -284.386346) (xy 131.850682 -284.374486) (xy 131.801068 -284.355014)
			(xy 131.75491 -284.328365) (xy 131.713239 -284.295134) (xy 131.676987 -284.256063) (xy 131.646963 -284.212026)
			(xy 131.623837 -284.164005) (xy 131.608127 -284.113075) (xy 131.600184 -284.060371) (xy 131.371604 -284.060371)
			(xy 131.363661 -284.113075) (xy 131.347951 -284.164005) (xy 131.324825 -284.212026) (xy 131.294801 -284.256063)
			(xy 131.258549 -284.295134) (xy 131.216878 -284.328365) (xy 131.17072 -284.355014) (xy 131.121106 -284.374486)
			(xy 131.069144 -284.386346) (xy 131.015994 -284.39033) (xy 130.962844 -284.386346) (xy 130.910882 -284.374486)
			(xy 130.861268 -284.355014) (xy 130.81511 -284.328365) (xy 130.773439 -284.295134) (xy 130.737187 -284.256063)
			(xy 130.707163 -284.212026) (xy 130.684037 -284.164005) (xy 130.668327 -284.113075) (xy 130.660384 -284.060371)
			(xy 130.431804 -284.060371) (xy 130.423861 -284.113075) (xy 130.408151 -284.164005) (xy 130.385025 -284.212026)
			(xy 130.355001 -284.256063) (xy 130.318749 -284.295134) (xy 130.277078 -284.328365) (xy 130.23092 -284.355014)
			(xy 130.181306 -284.374486) (xy 130.129344 -284.386346) (xy 130.076194 -284.39033) (xy 130.023044 -284.386346)
			(xy 129.971082 -284.374486) (xy 129.921468 -284.355014) (xy 129.87531 -284.328365) (xy 129.833639 -284.295134)
			(xy 129.797387 -284.256063) (xy 129.767363 -284.212026) (xy 129.744237 -284.164005) (xy 129.728527 -284.113075)
			(xy 129.720584 -284.060371) (xy 129.492004 -284.060371) (xy 129.484061 -284.113075) (xy 129.468351 -284.164005)
			(xy 129.445225 -284.212026) (xy 129.415201 -284.256063) (xy 129.378949 -284.295134) (xy 129.337278 -284.328365)
			(xy 129.29112 -284.355014) (xy 129.241506 -284.374486) (xy 129.189544 -284.386346) (xy 129.136394 -284.39033)
			(xy 129.083244 -284.386346) (xy 129.031282 -284.374486) (xy 128.981668 -284.355014) (xy 128.93551 -284.328365)
			(xy 128.893839 -284.295134) (xy 128.857587 -284.256063) (xy 128.827563 -284.212026) (xy 128.804437 -284.164005)
			(xy 128.788727 -284.113075) (xy 128.780784 -284.060371) (xy 128.552204 -284.060371) (xy 128.544261 -284.113075)
			(xy 128.528551 -284.164005) (xy 128.505425 -284.212026) (xy 128.475401 -284.256063) (xy 128.439149 -284.295134)
			(xy 128.397478 -284.328365) (xy 128.35132 -284.355014) (xy 128.301706 -284.374486) (xy 128.249744 -284.386346)
			(xy 128.196594 -284.39033) (xy 128.143444 -284.386346) (xy 128.091482 -284.374486) (xy 128.041868 -284.355014)
			(xy 127.99571 -284.328365) (xy 127.954039 -284.295134) (xy 127.917787 -284.256063) (xy 127.887763 -284.212026)
			(xy 127.864637 -284.164005) (xy 127.848927 -284.113075) (xy 127.840984 -284.060371) (xy 127.612404 -284.060371)
			(xy 127.604461 -284.113075) (xy 127.588751 -284.164005) (xy 127.565625 -284.212026) (xy 127.535601 -284.256063)
			(xy 127.499349 -284.295134) (xy 127.457678 -284.328365) (xy 127.41152 -284.355014) (xy 127.361906 -284.374486)
			(xy 127.309944 -284.386346) (xy 127.256794 -284.39033) (xy 127.203644 -284.386346) (xy 127.151682 -284.374486)
			(xy 127.102068 -284.355014) (xy 127.05591 -284.328365) (xy 127.014239 -284.295134) (xy 126.977987 -284.256063)
			(xy 126.947963 -284.212026) (xy 126.924837 -284.164005) (xy 126.909127 -284.113075) (xy 126.901184 -284.060371)
			(xy 126.672604 -284.060371) (xy 126.664661 -284.113075) (xy 126.648951 -284.164005) (xy 126.625825 -284.212026)
			(xy 126.595801 -284.256063) (xy 126.559549 -284.295134) (xy 126.517878 -284.328365) (xy 126.47172 -284.355014)
			(xy 126.422106 -284.374486) (xy 126.370144 -284.386346) (xy 126.316994 -284.39033) (xy 126.263844 -284.386346)
			(xy 126.211882 -284.374486) (xy 126.162268 -284.355014) (xy 126.11611 -284.328365) (xy 126.074439 -284.295134)
			(xy 126.038187 -284.256063) (xy 126.008163 -284.212026) (xy 125.985037 -284.164005) (xy 125.969327 -284.113075)
			(xy 125.961384 -284.060371) (xy 125.733058 -284.060371) (xy 125.725115 -284.113075) (xy 125.709405 -284.164005)
			(xy 125.686279 -284.212026) (xy 125.656255 -284.256063) (xy 125.620003 -284.295134) (xy 125.578332 -284.328365)
			(xy 125.532174 -284.355014) (xy 125.48256 -284.374486) (xy 125.430598 -284.386346) (xy 125.377448 -284.39033)
			(xy 125.324298 -284.386346) (xy 125.272336 -284.374486) (xy 125.222722 -284.355014) (xy 125.176564 -284.328365)
			(xy 125.134893 -284.295134) (xy 125.098641 -284.256063) (xy 125.068617 -284.212026) (xy 125.045491 -284.164005)
			(xy 125.029781 -284.113075) (xy 125.021838 -284.060371) (xy 124.793004 -284.060371) (xy 124.785061 -284.113075)
			(xy 124.769351 -284.164005) (xy 124.746225 -284.212026) (xy 124.716201 -284.256063) (xy 124.679949 -284.295134)
			(xy 124.638278 -284.328365) (xy 124.59212 -284.355014) (xy 124.542506 -284.374486) (xy 124.490544 -284.386346)
			(xy 124.437394 -284.39033) (xy 124.384244 -284.386346) (xy 124.332282 -284.374486) (xy 124.282668 -284.355014)
			(xy 124.23651 -284.328365) (xy 124.194839 -284.295134) (xy 124.158587 -284.256063) (xy 124.128563 -284.212026)
			(xy 124.105437 -284.164005) (xy 124.089727 -284.113075) (xy 124.081784 -284.060371) (xy 123.853204 -284.060371)
			(xy 123.845261 -284.113075) (xy 123.829551 -284.164005) (xy 123.806425 -284.212026) (xy 123.776401 -284.256063)
			(xy 123.740149 -284.295134) (xy 123.698478 -284.328365) (xy 123.65232 -284.355014) (xy 123.602706 -284.374486)
			(xy 123.550744 -284.386346) (xy 123.497594 -284.39033) (xy 123.444444 -284.386346) (xy 123.392482 -284.374486)
			(xy 123.342868 -284.355014) (xy 123.29671 -284.328365) (xy 123.255039 -284.295134) (xy 123.218787 -284.256063)
			(xy 123.188763 -284.212026) (xy 123.165637 -284.164005) (xy 123.149927 -284.113075) (xy 123.141984 -284.060371)
			(xy 122.913404 -284.060371) (xy 122.905461 -284.113075) (xy 122.889751 -284.164005) (xy 122.866625 -284.212026)
			(xy 122.836601 -284.256063) (xy 122.800349 -284.295134) (xy 122.758678 -284.328365) (xy 122.71252 -284.355014)
			(xy 122.662906 -284.374486) (xy 122.610944 -284.386346) (xy 122.557794 -284.39033) (xy 122.504644 -284.386346)
			(xy 122.452682 -284.374486) (xy 122.403068 -284.355014) (xy 122.35691 -284.328365) (xy 122.315239 -284.295134)
			(xy 122.278987 -284.256063) (xy 122.248963 -284.212026) (xy 122.225837 -284.164005) (xy 122.210127 -284.113075)
			(xy 122.202184 -284.060371) (xy 121.973604 -284.060371) (xy 121.965661 -284.113075) (xy 121.949951 -284.164005)
			(xy 121.926825 -284.212026) (xy 121.896801 -284.256063) (xy 121.860549 -284.295134) (xy 121.818878 -284.328365)
			(xy 121.77272 -284.355014) (xy 121.723106 -284.374486) (xy 121.671144 -284.386346) (xy 121.617994 -284.39033)
			(xy 121.564844 -284.386346) (xy 121.512882 -284.374486) (xy 121.463268 -284.355014) (xy 121.41711 -284.328365)
			(xy 121.375439 -284.295134) (xy 121.339187 -284.256063) (xy 121.309163 -284.212026) (xy 121.286037 -284.164005)
			(xy 121.270327 -284.113075) (xy 121.262384 -284.060371) (xy 121.033804 -284.060371) (xy 121.025861 -284.113075)
			(xy 121.010151 -284.164005) (xy 120.987025 -284.212026) (xy 120.957001 -284.256063) (xy 120.920749 -284.295134)
			(xy 120.879078 -284.328365) (xy 120.83292 -284.355014) (xy 120.783306 -284.374486) (xy 120.731344 -284.386346)
			(xy 120.678194 -284.39033) (xy 120.625044 -284.386346) (xy 120.573082 -284.374486) (xy 120.523468 -284.355014)
			(xy 120.47731 -284.328365) (xy 120.435639 -284.295134) (xy 120.399387 -284.256063) (xy 120.369363 -284.212026)
			(xy 120.346237 -284.164005) (xy 120.330527 -284.113075) (xy 120.322584 -284.060371) (xy 120.094004 -284.060371)
			(xy 120.086061 -284.113075) (xy 120.070351 -284.164005) (xy 120.047225 -284.212026) (xy 120.017201 -284.256063)
			(xy 119.980949 -284.295134) (xy 119.939278 -284.328365) (xy 119.89312 -284.355014) (xy 119.843506 -284.374486)
			(xy 119.791544 -284.386346) (xy 119.738394 -284.39033) (xy 119.685244 -284.386346) (xy 119.633282 -284.374486)
			(xy 119.583668 -284.355014) (xy 119.53751 -284.328365) (xy 119.495839 -284.295134) (xy 119.459587 -284.256063)
			(xy 119.429563 -284.212026) (xy 119.406437 -284.164005) (xy 119.390727 -284.113075) (xy 119.382784 -284.060371)
			(xy 119.154204 -284.060371) (xy 119.146261 -284.113075) (xy 119.130551 -284.164005) (xy 119.107425 -284.212026)
			(xy 119.077401 -284.256063) (xy 119.041149 -284.295134) (xy 118.999478 -284.328365) (xy 118.95332 -284.355014)
			(xy 118.903706 -284.374486) (xy 118.851744 -284.386346) (xy 118.798594 -284.39033) (xy 118.745444 -284.386346)
			(xy 118.693482 -284.374486) (xy 118.643868 -284.355014) (xy 118.59771 -284.328365) (xy 118.556039 -284.295134)
			(xy 118.519787 -284.256063) (xy 118.489763 -284.212026) (xy 118.466637 -284.164005) (xy 118.450927 -284.113075)
			(xy 118.442984 -284.060371) (xy 110.696004 -284.060371) (xy 110.688061 -284.113075) (xy 110.672351 -284.164005)
			(xy 110.649225 -284.212026) (xy 110.619201 -284.256063) (xy 110.582949 -284.295134) (xy 110.541278 -284.328365)
			(xy 110.49512 -284.355014) (xy 110.445506 -284.374486) (xy 110.393544 -284.386346) (xy 110.340394 -284.39033)
			(xy 110.287244 -284.386346) (xy 110.235282 -284.374486) (xy 110.185668 -284.355014) (xy 110.13951 -284.328365)
			(xy 110.097839 -284.295134) (xy 110.061587 -284.256063) (xy 110.031563 -284.212026) (xy 110.008437 -284.164005)
			(xy 109.992727 -284.113075) (xy 109.984784 -284.060371) (xy 107.876604 -284.060371) (xy 107.868661 -284.113075)
			(xy 107.852951 -284.164005) (xy 107.829825 -284.212026) (xy 107.799801 -284.256063) (xy 107.763549 -284.295134)
			(xy 107.721878 -284.328365) (xy 107.67572 -284.355014) (xy 107.626106 -284.374486) (xy 107.574144 -284.386346)
			(xy 107.520994 -284.39033) (xy 107.467844 -284.386346) (xy 107.415882 -284.374486) (xy 107.366268 -284.355014)
			(xy 107.32011 -284.328365) (xy 107.278439 -284.295134) (xy 107.242187 -284.256063) (xy 107.212163 -284.212026)
			(xy 107.189037 -284.164005) (xy 107.173327 -284.113075) (xy 107.165384 -284.060371) (xy 105.997004 -284.060371)
			(xy 105.989061 -284.113075) (xy 105.973351 -284.164005) (xy 105.950225 -284.212026) (xy 105.920201 -284.256063)
			(xy 105.883949 -284.295134) (xy 105.842278 -284.328365) (xy 105.79612 -284.355014) (xy 105.746506 -284.374486)
			(xy 105.694544 -284.386346) (xy 105.641394 -284.39033) (xy 105.588244 -284.386346) (xy 105.536282 -284.374486)
			(xy 105.486668 -284.355014) (xy 105.44051 -284.328365) (xy 105.398839 -284.295134) (xy 105.362587 -284.256063)
			(xy 105.332563 -284.212026) (xy 105.309437 -284.164005) (xy 105.293727 -284.113075) (xy 105.285784 -284.060371)
			(xy 105.08488 -284.060371) (xy 105.08488 -284.390084) (xy 105.085244 -284.399463) (xy 105.092034 -284.416947)
			(xy 105.098088 -284.42412) (xy 105.123742 -284.45079) (xy 105.14838 -284.47619) (xy 105.155301 -284.482773)
			(xy 105.172658 -284.490717) (xy 105.182162 -284.491684) (xy 105.183178 -284.491684) (xy 105.209235 -284.492996)
			(xy 105.260572 -284.5023) (xy 105.310001 -284.518997) (xy 105.356463 -284.542729) (xy 105.398965 -284.572988)
			(xy 105.436595 -284.609127) (xy 105.468547 -284.65037) (xy 105.494138 -284.695836) (xy 105.512818 -284.74455)
			(xy 105.524189 -284.795468) (xy 105.528007 -284.847501) (xy 105.526049 -284.874187) (xy 113.274084 -284.874187)
			(xy 113.274084 -284.820889) (xy 113.282027 -284.768185) (xy 113.297737 -284.717255) (xy 113.320863 -284.669234)
			(xy 113.350887 -284.625197) (xy 113.387139 -284.586126) (xy 113.42881 -284.552895) (xy 113.474968 -284.526246)
			(xy 113.524582 -284.506774) (xy 113.576544 -284.494914) (xy 113.629694 -284.490931) (xy 113.682844 -284.494914)
			(xy 113.734806 -284.506774) (xy 113.78442 -284.526246) (xy 113.830578 -284.552895) (xy 113.872249 -284.586126)
			(xy 113.908501 -284.625197) (xy 113.938525 -284.669234) (xy 113.961651 -284.717255) (xy 113.977361 -284.768185)
			(xy 113.985304 -284.820889) (xy 113.985802 -284.847538) (xy 113.985304 -284.874187) (xy 116.093738 -284.874187)
			(xy 116.093738 -284.820889) (xy 116.101681 -284.768185) (xy 116.117391 -284.717255) (xy 116.140517 -284.669234)
			(xy 116.170541 -284.625197) (xy 116.206793 -284.586126) (xy 116.248464 -284.552895) (xy 116.294622 -284.526246)
			(xy 116.344236 -284.506774) (xy 116.396198 -284.494914) (xy 116.449348 -284.490931) (xy 116.502498 -284.494914)
			(xy 116.55446 -284.506774) (xy 116.604074 -284.526246) (xy 116.650232 -284.552895) (xy 116.691903 -284.586126)
			(xy 116.728155 -284.625197) (xy 116.758179 -284.669234) (xy 116.781305 -284.717255) (xy 116.797015 -284.768185)
			(xy 116.804958 -284.820889) (xy 116.805456 -284.847538) (xy 116.804958 -284.874187) (xy 117.973338 -284.874187)
			(xy 117.973338 -284.820889) (xy 117.981281 -284.768185) (xy 117.996991 -284.717255) (xy 118.020117 -284.669234)
			(xy 118.050141 -284.625197) (xy 118.086393 -284.586126) (xy 118.128064 -284.552895) (xy 118.174222 -284.526246)
			(xy 118.223836 -284.506774) (xy 118.275798 -284.494914) (xy 118.328948 -284.490931) (xy 118.382098 -284.494914)
			(xy 118.43406 -284.506774) (xy 118.483674 -284.526246) (xy 118.529832 -284.552895) (xy 118.571503 -284.586126)
			(xy 118.607755 -284.625197) (xy 118.637779 -284.669234) (xy 118.660905 -284.717255) (xy 118.676615 -284.768185)
			(xy 118.684558 -284.820889) (xy 118.685056 -284.847538) (xy 118.939056 -284.847538) (xy 118.939564 -284.821631)
			(xy 118.94767 -284.770454) (xy 118.963682 -284.721175) (xy 118.987205 -284.675008) (xy 119.017661 -284.633089)
			(xy 119.054299 -284.596451) (xy 119.096218 -284.565995) (xy 119.142385 -284.542472) (xy 119.191664 -284.52646)
			(xy 119.242841 -284.518354) (xy 119.294655 -284.518354) (xy 119.345832 -284.52646) (xy 119.395111 -284.542472)
			(xy 119.441278 -284.565995) (xy 119.483197 -284.596451) (xy 119.519835 -284.633089) (xy 119.550291 -284.675008)
			(xy 119.573814 -284.721175) (xy 119.589826 -284.770454) (xy 119.597932 -284.821631) (xy 119.59844 -284.847538)
			(xy 119.597857 -284.874187) (xy 119.852938 -284.874187) (xy 119.852938 -284.820889) (xy 119.860881 -284.768185)
			(xy 119.876591 -284.717255) (xy 119.899717 -284.669234) (xy 119.929741 -284.625197) (xy 119.965993 -284.586126)
			(xy 120.007664 -284.552895) (xy 120.053822 -284.526246) (xy 120.103436 -284.506774) (xy 120.155398 -284.494914)
			(xy 120.208548 -284.490931) (xy 120.261698 -284.494914) (xy 120.31366 -284.506774) (xy 120.363274 -284.526246)
			(xy 120.409432 -284.552895) (xy 120.451103 -284.586126) (xy 120.487355 -284.625197) (xy 120.517379 -284.669234)
			(xy 120.540505 -284.717255) (xy 120.556215 -284.768185) (xy 120.564158 -284.820889) (xy 120.564656 -284.847538)
			(xy 120.818656 -284.847538) (xy 120.819164 -284.821631) (xy 120.82727 -284.770454) (xy 120.843282 -284.721175)
			(xy 120.866805 -284.675008) (xy 120.897261 -284.633089) (xy 120.933899 -284.596451) (xy 120.975818 -284.565995)
			(xy 121.021985 -284.542472) (xy 121.071264 -284.52646) (xy 121.122441 -284.518354) (xy 121.174255 -284.518354)
			(xy 121.225432 -284.52646) (xy 121.274711 -284.542472) (xy 121.320878 -284.565995) (xy 121.362797 -284.596451)
			(xy 121.399435 -284.633089) (xy 121.429891 -284.675008) (xy 121.453414 -284.721175) (xy 121.469426 -284.770454)
			(xy 121.477532 -284.821631) (xy 121.47804 -284.847538) (xy 121.477457 -284.874187) (xy 121.732538 -284.874187)
			(xy 121.732538 -284.820889) (xy 121.740481 -284.768185) (xy 121.756191 -284.717255) (xy 121.779317 -284.669234)
			(xy 121.809341 -284.625197) (xy 121.845593 -284.586126) (xy 121.887264 -284.552895) (xy 121.933422 -284.526246)
			(xy 121.983036 -284.506774) (xy 122.034998 -284.494914) (xy 122.088148 -284.490931) (xy 122.141298 -284.494914)
			(xy 122.19326 -284.506774) (xy 122.242874 -284.526246) (xy 122.289032 -284.552895) (xy 122.330703 -284.586126)
			(xy 122.366955 -284.625197) (xy 122.396979 -284.669234) (xy 122.420105 -284.717255) (xy 122.435815 -284.768185)
			(xy 122.443758 -284.820889) (xy 122.444256 -284.847538) (xy 122.698256 -284.847538) (xy 122.698764 -284.821631)
			(xy 122.70687 -284.770454) (xy 122.722882 -284.721175) (xy 122.746405 -284.675008) (xy 122.776861 -284.633089)
			(xy 122.813499 -284.596451) (xy 122.855418 -284.565995) (xy 122.901585 -284.542472) (xy 122.950864 -284.52646)
			(xy 123.002041 -284.518354) (xy 123.053855 -284.518354) (xy 123.105032 -284.52646) (xy 123.154311 -284.542472)
			(xy 123.200478 -284.565995) (xy 123.242397 -284.596451) (xy 123.279035 -284.633089) (xy 123.309491 -284.675008)
			(xy 123.333014 -284.721175) (xy 123.349026 -284.770454) (xy 123.357132 -284.821631) (xy 123.35764 -284.847538)
			(xy 123.357057 -284.874187) (xy 123.612138 -284.874187) (xy 123.612138 -284.820889) (xy 123.620081 -284.768185)
			(xy 123.635791 -284.717255) (xy 123.658917 -284.669234) (xy 123.688941 -284.625197) (xy 123.725193 -284.586126)
			(xy 123.766864 -284.552895) (xy 123.813022 -284.526246) (xy 123.862636 -284.506774) (xy 123.914598 -284.494914)
			(xy 123.967748 -284.490931) (xy 124.020898 -284.494914) (xy 124.07286 -284.506774) (xy 124.122474 -284.526246)
			(xy 124.168632 -284.552895) (xy 124.210303 -284.586126) (xy 124.246555 -284.625197) (xy 124.276579 -284.669234)
			(xy 124.299705 -284.717255) (xy 124.315415 -284.768185) (xy 124.323358 -284.820889) (xy 124.323856 -284.847538)
			(xy 124.577856 -284.847538) (xy 124.578364 -284.821631) (xy 124.58647 -284.770454) (xy 124.602482 -284.721175)
			(xy 124.626005 -284.675008) (xy 124.656461 -284.633089) (xy 124.693099 -284.596451) (xy 124.735018 -284.565995)
			(xy 124.781185 -284.542472) (xy 124.830464 -284.52646) (xy 124.881641 -284.518354) (xy 124.933455 -284.518354)
			(xy 124.984632 -284.52646) (xy 125.033911 -284.542472) (xy 125.080078 -284.565995) (xy 125.121997 -284.596451)
			(xy 125.158635 -284.633089) (xy 125.189091 -284.675008) (xy 125.212614 -284.721175) (xy 125.228626 -284.770454)
			(xy 125.236732 -284.821631) (xy 125.23724 -284.847538) (xy 125.236657 -284.874187) (xy 125.491738 -284.874187)
			(xy 125.491738 -284.820889) (xy 125.499681 -284.768185) (xy 125.515391 -284.717255) (xy 125.538517 -284.669234)
			(xy 125.568541 -284.625197) (xy 125.604793 -284.586126) (xy 125.646464 -284.552895) (xy 125.692622 -284.526246)
			(xy 125.742236 -284.506774) (xy 125.794198 -284.494914) (xy 125.847348 -284.490931) (xy 125.900498 -284.494914)
			(xy 125.95246 -284.506774) (xy 126.002074 -284.526246) (xy 126.048232 -284.552895) (xy 126.089903 -284.586126)
			(xy 126.126155 -284.625197) (xy 126.156179 -284.669234) (xy 126.179305 -284.717255) (xy 126.195015 -284.768185)
			(xy 126.202958 -284.820889) (xy 126.203456 -284.847538) (xy 126.457456 -284.847538) (xy 126.457964 -284.821631)
			(xy 126.46607 -284.770454) (xy 126.482082 -284.721175) (xy 126.505605 -284.675008) (xy 126.536061 -284.633089)
			(xy 126.572699 -284.596451) (xy 126.614618 -284.565995) (xy 126.660785 -284.542472) (xy 126.710064 -284.52646)
			(xy 126.761241 -284.518354) (xy 126.813055 -284.518354) (xy 126.864232 -284.52646) (xy 126.913511 -284.542472)
			(xy 126.959678 -284.565995) (xy 127.001597 -284.596451) (xy 127.038235 -284.633089) (xy 127.068691 -284.675008)
			(xy 127.092214 -284.721175) (xy 127.108226 -284.770454) (xy 127.116332 -284.821631) (xy 127.11684 -284.847538)
			(xy 127.116257 -284.874187) (xy 127.371338 -284.874187) (xy 127.371338 -284.820889) (xy 127.379281 -284.768185)
			(xy 127.394991 -284.717255) (xy 127.418117 -284.669234) (xy 127.448141 -284.625197) (xy 127.484393 -284.586126)
			(xy 127.526064 -284.552895) (xy 127.572222 -284.526246) (xy 127.621836 -284.506774) (xy 127.673798 -284.494914)
			(xy 127.726948 -284.490931) (xy 127.780098 -284.494914) (xy 127.83206 -284.506774) (xy 127.881674 -284.526246)
			(xy 127.927832 -284.552895) (xy 127.969503 -284.586126) (xy 128.005755 -284.625197) (xy 128.035779 -284.669234)
			(xy 128.058905 -284.717255) (xy 128.074615 -284.768185) (xy 128.082558 -284.820889) (xy 128.083056 -284.847538)
			(xy 128.337056 -284.847538) (xy 128.337564 -284.821631) (xy 128.34567 -284.770454) (xy 128.361682 -284.721175)
			(xy 128.385205 -284.675008) (xy 128.415661 -284.633089) (xy 128.452299 -284.596451) (xy 128.494218 -284.565995)
			(xy 128.540385 -284.542472) (xy 128.589664 -284.52646) (xy 128.640841 -284.518354) (xy 128.692655 -284.518354)
			(xy 128.743832 -284.52646) (xy 128.793111 -284.542472) (xy 128.839278 -284.565995) (xy 128.881197 -284.596451)
			(xy 128.917835 -284.633089) (xy 128.948291 -284.675008) (xy 128.971814 -284.721175) (xy 128.987826 -284.770454)
			(xy 128.995932 -284.821631) (xy 128.99644 -284.847538) (xy 128.995857 -284.874187) (xy 129.250938 -284.874187)
			(xy 129.250938 -284.820889) (xy 129.258881 -284.768185) (xy 129.274591 -284.717255) (xy 129.297717 -284.669234)
			(xy 129.327741 -284.625197) (xy 129.363993 -284.586126) (xy 129.405664 -284.552895) (xy 129.451822 -284.526246)
			(xy 129.501436 -284.506774) (xy 129.553398 -284.494914) (xy 129.606548 -284.490931) (xy 129.659698 -284.494914)
			(xy 129.71166 -284.506774) (xy 129.761274 -284.526246) (xy 129.807432 -284.552895) (xy 129.849103 -284.586126)
			(xy 129.885355 -284.625197) (xy 129.915379 -284.669234) (xy 129.938505 -284.717255) (xy 129.954215 -284.768185)
			(xy 129.962158 -284.820889) (xy 129.962656 -284.847538) (xy 130.216656 -284.847538) (xy 130.217164 -284.821631)
			(xy 130.22527 -284.770454) (xy 130.241282 -284.721175) (xy 130.264805 -284.675008) (xy 130.295261 -284.633089)
			(xy 130.331899 -284.596451) (xy 130.373818 -284.565995) (xy 130.419985 -284.542472) (xy 130.469264 -284.52646)
			(xy 130.520441 -284.518354) (xy 130.572255 -284.518354) (xy 130.623432 -284.52646) (xy 130.672711 -284.542472)
			(xy 130.718878 -284.565995) (xy 130.760797 -284.596451) (xy 130.797435 -284.633089) (xy 130.827891 -284.675008)
			(xy 130.851414 -284.721175) (xy 130.867426 -284.770454) (xy 130.875532 -284.821631) (xy 130.87604 -284.847538)
			(xy 130.875457 -284.874187) (xy 131.130538 -284.874187) (xy 131.130538 -284.820889) (xy 131.138481 -284.768185)
			(xy 131.154191 -284.717255) (xy 131.177317 -284.669234) (xy 131.207341 -284.625197) (xy 131.243593 -284.586126)
			(xy 131.285264 -284.552895) (xy 131.331422 -284.526246) (xy 131.381036 -284.506774) (xy 131.432998 -284.494914)
			(xy 131.486148 -284.490931) (xy 131.539298 -284.494914) (xy 131.59126 -284.506774) (xy 131.640874 -284.526246)
			(xy 131.687032 -284.552895) (xy 131.728703 -284.586126) (xy 131.764955 -284.625197) (xy 131.794979 -284.669234)
			(xy 131.818105 -284.717255) (xy 131.833815 -284.768185) (xy 131.841758 -284.820889) (xy 131.842256 -284.847538)
			(xy 132.096256 -284.847538) (xy 132.096764 -284.821631) (xy 132.10487 -284.770454) (xy 132.120882 -284.721175)
			(xy 132.144405 -284.675008) (xy 132.174861 -284.633089) (xy 132.211499 -284.596451) (xy 132.253418 -284.565995)
			(xy 132.299585 -284.542472) (xy 132.348864 -284.52646) (xy 132.400041 -284.518354) (xy 132.451855 -284.518354)
			(xy 132.503032 -284.52646) (xy 132.552311 -284.542472) (xy 132.598478 -284.565995) (xy 132.640397 -284.596451)
			(xy 132.677035 -284.633089) (xy 132.707491 -284.675008) (xy 132.731014 -284.721175) (xy 132.747026 -284.770454)
			(xy 132.755132 -284.821631) (xy 132.75564 -284.847538) (xy 132.755057 -284.874187) (xy 133.010138 -284.874187)
			(xy 133.010138 -284.820889) (xy 133.018081 -284.768185) (xy 133.033791 -284.717255) (xy 133.056917 -284.669234)
			(xy 133.086941 -284.625197) (xy 133.123193 -284.586126) (xy 133.164864 -284.552895) (xy 133.211022 -284.526246)
			(xy 133.260636 -284.506774) (xy 133.312598 -284.494914) (xy 133.365748 -284.490931) (xy 133.418898 -284.494914)
			(xy 133.47086 -284.506774) (xy 133.520474 -284.526246) (xy 133.566632 -284.552895) (xy 133.608303 -284.586126)
			(xy 133.644555 -284.625197) (xy 133.674579 -284.669234) (xy 133.697705 -284.717255) (xy 133.713415 -284.768185)
			(xy 133.721358 -284.820889) (xy 133.721856 -284.847538) (xy 133.721358 -284.874187) (xy 133.949938 -284.874187)
			(xy 133.949938 -284.820889) (xy 133.957881 -284.768185) (xy 133.973591 -284.717255) (xy 133.996717 -284.669234)
			(xy 134.026741 -284.625197) (xy 134.062993 -284.586126) (xy 134.104664 -284.552895) (xy 134.150822 -284.526246)
			(xy 134.200436 -284.506774) (xy 134.252398 -284.494914) (xy 134.305548 -284.490931) (xy 134.358698 -284.494914)
			(xy 134.41066 -284.506774) (xy 134.460274 -284.526246) (xy 134.506432 -284.552895) (xy 134.548103 -284.586126)
			(xy 134.584355 -284.625197) (xy 134.614379 -284.669234) (xy 134.637505 -284.717255) (xy 134.653215 -284.768185)
			(xy 134.661158 -284.820889) (xy 134.661656 -284.847538) (xy 134.661163 -284.873933) (xy 134.889484 -284.873933)
			(xy 134.889484 -284.820635) (xy 134.897427 -284.767931) (xy 134.913137 -284.717001) (xy 134.936263 -284.66898)
			(xy 134.966287 -284.624943) (xy 135.002539 -284.585872) (xy 135.04421 -284.552641) (xy 135.090368 -284.525992)
			(xy 135.139982 -284.50652) (xy 135.191944 -284.49466) (xy 135.245094 -284.490677) (xy 135.298244 -284.49466)
			(xy 135.350206 -284.50652) (xy 135.39982 -284.525992) (xy 135.445978 -284.552641) (xy 135.487649 -284.585872)
			(xy 135.523901 -284.624943) (xy 135.553925 -284.66898) (xy 135.577051 -284.717001) (xy 135.592761 -284.767931)
			(xy 135.600704 -284.820635) (xy 135.601202 -284.847284) (xy 135.600704 -284.873933) (xy 135.829284 -284.873933)
			(xy 135.829284 -284.820635) (xy 135.837227 -284.767931) (xy 135.852937 -284.717001) (xy 135.876063 -284.66898)
			(xy 135.906087 -284.624943) (xy 135.942339 -284.585872) (xy 135.98401 -284.552641) (xy 136.030168 -284.525992)
			(xy 136.079782 -284.50652) (xy 136.131744 -284.49466) (xy 136.184894 -284.490677) (xy 136.238044 -284.49466)
			(xy 136.290006 -284.50652) (xy 136.33962 -284.525992) (xy 136.385778 -284.552641) (xy 136.427449 -284.585872)
			(xy 136.463701 -284.624943) (xy 136.493725 -284.66898) (xy 136.516851 -284.717001) (xy 136.532561 -284.767931)
			(xy 136.540504 -284.820635) (xy 136.541002 -284.847284) (xy 136.540504 -284.873933) (xy 136.769084 -284.873933)
			(xy 136.769084 -284.820635) (xy 136.777027 -284.767931) (xy 136.792737 -284.717001) (xy 136.815863 -284.66898)
			(xy 136.845887 -284.624943) (xy 136.882139 -284.585872) (xy 136.92381 -284.552641) (xy 136.969968 -284.525992)
			(xy 137.019582 -284.50652) (xy 137.071544 -284.49466) (xy 137.124694 -284.490677) (xy 137.177844 -284.49466)
			(xy 137.229806 -284.50652) (xy 137.27942 -284.525992) (xy 137.325578 -284.552641) (xy 137.367249 -284.585872)
			(xy 137.403501 -284.624943) (xy 137.433525 -284.66898) (xy 137.456651 -284.717001) (xy 137.472361 -284.767931)
			(xy 137.480304 -284.820635) (xy 137.480802 -284.847284) (xy 137.480304 -284.873933) (xy 137.708884 -284.873933)
			(xy 137.708884 -284.820635) (xy 137.716827 -284.767931) (xy 137.732537 -284.717001) (xy 137.755663 -284.66898)
			(xy 137.785687 -284.624943) (xy 137.821939 -284.585872) (xy 137.86361 -284.552641) (xy 137.909768 -284.525992)
			(xy 137.959382 -284.50652) (xy 138.011344 -284.49466) (xy 138.064494 -284.490677) (xy 138.117644 -284.49466)
			(xy 138.169606 -284.50652) (xy 138.21922 -284.525992) (xy 138.265378 -284.552641) (xy 138.307049 -284.585872)
			(xy 138.343301 -284.624943) (xy 138.373325 -284.66898) (xy 138.396451 -284.717001) (xy 138.412161 -284.767931)
			(xy 138.420104 -284.820635) (xy 138.420602 -284.847284) (xy 138.420104 -284.873933) (xy 138.412161 -284.926637)
			(xy 138.396451 -284.977567) (xy 138.373325 -285.025588) (xy 138.343301 -285.069625) (xy 138.307049 -285.108696)
			(xy 138.265378 -285.141927) (xy 138.21922 -285.168576) (xy 138.169606 -285.188048) (xy 138.117644 -285.199908)
			(xy 138.064494 -285.203892) (xy 138.011344 -285.199908) (xy 137.959382 -285.188048) (xy 137.909768 -285.168576)
			(xy 137.86361 -285.141927) (xy 137.821939 -285.108696) (xy 137.785687 -285.069625) (xy 137.755663 -285.025588)
			(xy 137.732537 -284.977567) (xy 137.716827 -284.926637) (xy 137.708884 -284.873933) (xy 137.480304 -284.873933)
			(xy 137.472361 -284.926637) (xy 137.456651 -284.977567) (xy 137.433525 -285.025588) (xy 137.403501 -285.069625)
			(xy 137.367249 -285.108696) (xy 137.325578 -285.141927) (xy 137.27942 -285.168576) (xy 137.229806 -285.188048)
			(xy 137.177844 -285.199908) (xy 137.124694 -285.203892) (xy 137.071544 -285.199908) (xy 137.019582 -285.188048)
			(xy 136.969968 -285.168576) (xy 136.92381 -285.141927) (xy 136.882139 -285.108696) (xy 136.845887 -285.069625)
			(xy 136.815863 -285.025588) (xy 136.792737 -284.977567) (xy 136.777027 -284.926637) (xy 136.769084 -284.873933)
			(xy 136.540504 -284.873933) (xy 136.532561 -284.926637) (xy 136.516851 -284.977567) (xy 136.493725 -285.025588)
			(xy 136.463701 -285.069625) (xy 136.427449 -285.108696) (xy 136.385778 -285.141927) (xy 136.33962 -285.168576)
			(xy 136.290006 -285.188048) (xy 136.238044 -285.199908) (xy 136.184894 -285.203892) (xy 136.131744 -285.199908)
			(xy 136.079782 -285.188048) (xy 136.030168 -285.168576) (xy 135.98401 -285.141927) (xy 135.942339 -285.108696)
			(xy 135.906087 -285.069625) (xy 135.876063 -285.025588) (xy 135.852937 -284.977567) (xy 135.837227 -284.926637)
			(xy 135.829284 -284.873933) (xy 135.600704 -284.873933) (xy 135.592761 -284.926637) (xy 135.577051 -284.977567)
			(xy 135.553925 -285.025588) (xy 135.523901 -285.069625) (xy 135.487649 -285.108696) (xy 135.445978 -285.141927)
			(xy 135.39982 -285.168576) (xy 135.350206 -285.188048) (xy 135.298244 -285.199908) (xy 135.245094 -285.203892)
			(xy 135.191944 -285.199908) (xy 135.139982 -285.188048) (xy 135.090368 -285.168576) (xy 135.04421 -285.141927)
			(xy 135.002539 -285.108696) (xy 134.966287 -285.069625) (xy 134.936263 -285.025588) (xy 134.913137 -284.977567)
			(xy 134.897427 -284.926637) (xy 134.889484 -284.873933) (xy 134.661163 -284.873933) (xy 134.661158 -284.874187)
			(xy 134.653215 -284.926891) (xy 134.637505 -284.977821) (xy 134.614379 -285.025842) (xy 134.584355 -285.069879)
			(xy 134.548103 -285.10895) (xy 134.506432 -285.142181) (xy 134.460274 -285.16883) (xy 134.41066 -285.188302)
			(xy 134.358698 -285.200162) (xy 134.305548 -285.204146) (xy 134.252398 -285.200162) (xy 134.200436 -285.188302)
			(xy 134.150822 -285.16883) (xy 134.104664 -285.142181) (xy 134.062993 -285.10895) (xy 134.026741 -285.069879)
			(xy 133.996717 -285.025842) (xy 133.973591 -284.977821) (xy 133.957881 -284.926891) (xy 133.949938 -284.874187)
			(xy 133.721358 -284.874187) (xy 133.713415 -284.926891) (xy 133.697705 -284.977821) (xy 133.674579 -285.025842)
			(xy 133.644555 -285.069879) (xy 133.608303 -285.10895) (xy 133.566632 -285.142181) (xy 133.520474 -285.16883)
			(xy 133.47086 -285.188302) (xy 133.418898 -285.200162) (xy 133.365748 -285.204146) (xy 133.312598 -285.200162)
			(xy 133.260636 -285.188302) (xy 133.211022 -285.16883) (xy 133.164864 -285.142181) (xy 133.123193 -285.10895)
			(xy 133.086941 -285.069879) (xy 133.056917 -285.025842) (xy 133.033791 -284.977821) (xy 133.018081 -284.926891)
			(xy 133.010138 -284.874187) (xy 132.755057 -284.874187) (xy 132.755034 -284.875255) (xy 132.745719 -284.929901)
			(xy 132.737098 -284.95625) (xy 132.729224 -284.978348) (xy 132.934202 -285.333186) (xy 132.957062 -285.337504)
			(xy 132.981868 -285.342683) (xy 133.02961 -285.359669) (xy 133.07419 -285.383762) (xy 133.114558 -285.414393)
			(xy 133.149763 -285.450841) (xy 133.178975 -285.492247) (xy 133.201506 -285.537636) (xy 133.216825 -285.585939)
			(xy 133.224572 -285.636017) (xy 133.225032 -285.661354) (xy 133.224524 -285.687241) (xy 133.216425 -285.738379)
			(xy 133.200426 -285.787619) (xy 133.17692 -285.833751) (xy 133.146488 -285.875638) (xy 133.109878 -285.912248)
			(xy 133.067991 -285.94268) (xy 133.021859 -285.966186) (xy 132.972619 -285.982185) (xy 132.921481 -285.990284)
			(xy 132.869707 -285.990284) (xy 132.818569 -285.982185) (xy 132.769329 -285.966186) (xy 132.723197 -285.94268)
			(xy 132.68131 -285.912248) (xy 132.6447 -285.875638) (xy 132.614268 -285.833751) (xy 132.590762 -285.787619)
			(xy 132.574763 -285.738379) (xy 132.566664 -285.687241) (xy 132.566156 -285.661354) (xy 132.566701 -285.633647)
			(xy 132.575886 -285.579) (xy 132.584444 -285.552642) (xy 132.592318 -285.530544) (xy 132.38734 -285.175706)
			(xy 132.36448 -285.171388) (xy 132.33966 -285.166215) (xy 132.29188 -285.149263) (xy 132.247259 -285.125194)
			(xy 132.206851 -285.094575) (xy 132.171609 -285.058129) (xy 132.142365 -285.016715) (xy 132.119809 -284.971312)
			(xy 132.104472 -284.922989) (xy 132.096717 -284.872887) (xy 132.096256 -284.847538) (xy 131.842256 -284.847538)
			(xy 131.841758 -284.874187) (xy 131.833815 -284.926891) (xy 131.818105 -284.977821) (xy 131.794979 -285.025842)
			(xy 131.764955 -285.069879) (xy 131.728703 -285.10895) (xy 131.687032 -285.142181) (xy 131.640874 -285.16883)
			(xy 131.59126 -285.188302) (xy 131.539298 -285.200162) (xy 131.486148 -285.204146) (xy 131.432998 -285.200162)
			(xy 131.381036 -285.188302) (xy 131.331422 -285.16883) (xy 131.285264 -285.142181) (xy 131.243593 -285.10895)
			(xy 131.207341 -285.069879) (xy 131.177317 -285.025842) (xy 131.154191 -284.977821) (xy 131.138481 -284.926891)
			(xy 131.130538 -284.874187) (xy 130.875457 -284.874187) (xy 130.875434 -284.875255) (xy 130.866119 -284.929901)
			(xy 130.857498 -284.95625) (xy 130.849624 -284.978348) (xy 131.054602 -285.333186) (xy 131.077462 -285.337504)
			(xy 131.102268 -285.342683) (xy 131.15001 -285.359669) (xy 131.19459 -285.383762) (xy 131.234958 -285.414393)
			(xy 131.270163 -285.450841) (xy 131.299375 -285.492247) (xy 131.321906 -285.537636) (xy 131.337225 -285.585939)
			(xy 131.344972 -285.636017) (xy 131.345432 -285.661354) (xy 131.344924 -285.687241) (xy 131.336825 -285.738379)
			(xy 131.320826 -285.787619) (xy 131.29732 -285.833751) (xy 131.266888 -285.875638) (xy 131.230278 -285.912248)
			(xy 131.188391 -285.94268) (xy 131.142259 -285.966186) (xy 131.093019 -285.982185) (xy 131.041881 -285.990284)
			(xy 130.990107 -285.990284) (xy 130.938969 -285.982185) (xy 130.889729 -285.966186) (xy 130.843597 -285.94268)
			(xy 130.80171 -285.912248) (xy 130.7651 -285.875638) (xy 130.734668 -285.833751) (xy 130.711162 -285.787619)
			(xy 130.695163 -285.738379) (xy 130.687064 -285.687241) (xy 130.686556 -285.661354) (xy 130.687101 -285.633647)
			(xy 130.696286 -285.579) (xy 130.704844 -285.552642) (xy 130.712718 -285.530544) (xy 130.50774 -285.175706)
			(xy 130.48488 -285.171388) (xy 130.46006 -285.166215) (xy 130.41228 -285.149263) (xy 130.367659 -285.125194)
			(xy 130.327251 -285.094575) (xy 130.292009 -285.058129) (xy 130.262765 -285.016715) (xy 130.240209 -284.971312)
			(xy 130.224872 -284.922989) (xy 130.217117 -284.872887) (xy 130.216656 -284.847538) (xy 129.962656 -284.847538)
			(xy 129.962158 -284.874187) (xy 129.954215 -284.926891) (xy 129.938505 -284.977821) (xy 129.915379 -285.025842)
			(xy 129.885355 -285.069879) (xy 129.849103 -285.10895) (xy 129.807432 -285.142181) (xy 129.761274 -285.16883)
			(xy 129.71166 -285.188302) (xy 129.659698 -285.200162) (xy 129.606548 -285.204146) (xy 129.553398 -285.200162)
			(xy 129.501436 -285.188302) (xy 129.451822 -285.16883) (xy 129.405664 -285.142181) (xy 129.363993 -285.10895)
			(xy 129.327741 -285.069879) (xy 129.297717 -285.025842) (xy 129.274591 -284.977821) (xy 129.258881 -284.926891)
			(xy 129.250938 -284.874187) (xy 128.995857 -284.874187) (xy 128.995834 -284.875255) (xy 128.986519 -284.929901)
			(xy 128.977898 -284.95625) (xy 128.970024 -284.978348) (xy 129.175002 -285.333186) (xy 129.197862 -285.337504)
			(xy 129.222668 -285.342683) (xy 129.27041 -285.359669) (xy 129.31499 -285.383762) (xy 129.355358 -285.414393)
			(xy 129.390563 -285.450841) (xy 129.419775 -285.492247) (xy 129.442306 -285.537636) (xy 129.457625 -285.585939)
			(xy 129.465372 -285.636017) (xy 129.465832 -285.661354) (xy 129.465324 -285.687241) (xy 129.457225 -285.738379)
			(xy 129.441226 -285.787619) (xy 129.41772 -285.833751) (xy 129.387288 -285.875638) (xy 129.350678 -285.912248)
			(xy 129.308791 -285.94268) (xy 129.262659 -285.966186) (xy 129.213419 -285.982185) (xy 129.162281 -285.990284)
			(xy 129.110507 -285.990284) (xy 129.059369 -285.982185) (xy 129.010129 -285.966186) (xy 128.963997 -285.94268)
			(xy 128.92211 -285.912248) (xy 128.8855 -285.875638) (xy 128.855068 -285.833751) (xy 128.831562 -285.787619)
			(xy 128.815563 -285.738379) (xy 128.807464 -285.687241) (xy 128.806956 -285.661354) (xy 128.807501 -285.633647)
			(xy 128.816686 -285.579) (xy 128.825244 -285.552642) (xy 128.833118 -285.530544) (xy 128.62814 -285.175706)
			(xy 128.60528 -285.171388) (xy 128.58046 -285.166215) (xy 128.53268 -285.149263) (xy 128.488059 -285.125194)
			(xy 128.447651 -285.094575) (xy 128.412409 -285.058129) (xy 128.383165 -285.016715) (xy 128.360609 -284.971312)
			(xy 128.345272 -284.922989) (xy 128.337517 -284.872887) (xy 128.337056 -284.847538) (xy 128.083056 -284.847538)
			(xy 128.082558 -284.874187) (xy 128.074615 -284.926891) (xy 128.058905 -284.977821) (xy 128.035779 -285.025842)
			(xy 128.005755 -285.069879) (xy 127.969503 -285.10895) (xy 127.927832 -285.142181) (xy 127.881674 -285.16883)
			(xy 127.83206 -285.188302) (xy 127.780098 -285.200162) (xy 127.726948 -285.204146) (xy 127.673798 -285.200162)
			(xy 127.621836 -285.188302) (xy 127.572222 -285.16883) (xy 127.526064 -285.142181) (xy 127.484393 -285.10895)
			(xy 127.448141 -285.069879) (xy 127.418117 -285.025842) (xy 127.394991 -284.977821) (xy 127.379281 -284.926891)
			(xy 127.371338 -284.874187) (xy 127.116257 -284.874187) (xy 127.116234 -284.875255) (xy 127.106919 -284.929901)
			(xy 127.098298 -284.95625) (xy 127.090424 -284.978348) (xy 127.295402 -285.333186) (xy 127.318262 -285.337504)
			(xy 127.343068 -285.342683) (xy 127.39081 -285.359669) (xy 127.43539 -285.383762) (xy 127.475758 -285.414393)
			(xy 127.510963 -285.450841) (xy 127.540175 -285.492247) (xy 127.562706 -285.537636) (xy 127.578025 -285.585939)
			(xy 127.585772 -285.636017) (xy 127.586232 -285.661354) (xy 127.585724 -285.687241) (xy 127.577625 -285.738379)
			(xy 127.561626 -285.787619) (xy 127.53812 -285.833751) (xy 127.507688 -285.875638) (xy 127.471078 -285.912248)
			(xy 127.429191 -285.94268) (xy 127.383059 -285.966186) (xy 127.333819 -285.982185) (xy 127.282681 -285.990284)
			(xy 127.230907 -285.990284) (xy 127.179769 -285.982185) (xy 127.130529 -285.966186) (xy 127.084397 -285.94268)
			(xy 127.04251 -285.912248) (xy 127.0059 -285.875638) (xy 126.975468 -285.833751) (xy 126.951962 -285.787619)
			(xy 126.935963 -285.738379) (xy 126.927864 -285.687241) (xy 126.927356 -285.661354) (xy 126.927901 -285.633647)
			(xy 126.937086 -285.579) (xy 126.945644 -285.552642) (xy 126.953518 -285.530544) (xy 126.74854 -285.175706)
			(xy 126.72568 -285.171388) (xy 126.70086 -285.166215) (xy 126.65308 -285.149263) (xy 126.608459 -285.125194)
			(xy 126.568051 -285.094575) (xy 126.532809 -285.058129) (xy 126.503565 -285.016715) (xy 126.481009 -284.971312)
			(xy 126.465672 -284.922989) (xy 126.457917 -284.872887) (xy 126.457456 -284.847538) (xy 126.203456 -284.847538)
			(xy 126.202958 -284.874187) (xy 126.195015 -284.926891) (xy 126.179305 -284.977821) (xy 126.156179 -285.025842)
			(xy 126.126155 -285.069879) (xy 126.089903 -285.10895) (xy 126.048232 -285.142181) (xy 126.002074 -285.16883)
			(xy 125.95246 -285.188302) (xy 125.900498 -285.200162) (xy 125.847348 -285.204146) (xy 125.794198 -285.200162)
			(xy 125.742236 -285.188302) (xy 125.692622 -285.16883) (xy 125.646464 -285.142181) (xy 125.604793 -285.10895)
			(xy 125.568541 -285.069879) (xy 125.538517 -285.025842) (xy 125.515391 -284.977821) (xy 125.499681 -284.926891)
			(xy 125.491738 -284.874187) (xy 125.236657 -284.874187) (xy 125.236634 -284.875255) (xy 125.227319 -284.929901)
			(xy 125.218698 -284.95625) (xy 125.210824 -284.978348) (xy 125.415802 -285.333186) (xy 125.438662 -285.337504)
			(xy 125.463468 -285.342683) (xy 125.51121 -285.359669) (xy 125.55579 -285.383762) (xy 125.596158 -285.414393)
			(xy 125.631363 -285.450841) (xy 125.660575 -285.492247) (xy 125.683106 -285.537636) (xy 125.698425 -285.585939)
			(xy 125.706172 -285.636017) (xy 125.706632 -285.661354) (xy 125.706124 -285.687241) (xy 125.698025 -285.738379)
			(xy 125.682026 -285.787619) (xy 125.65852 -285.833751) (xy 125.628088 -285.875638) (xy 125.591478 -285.912248)
			(xy 125.549591 -285.94268) (xy 125.503459 -285.966186) (xy 125.454219 -285.982185) (xy 125.403081 -285.990284)
			(xy 125.351307 -285.990284) (xy 125.300169 -285.982185) (xy 125.250929 -285.966186) (xy 125.204797 -285.94268)
			(xy 125.16291 -285.912248) (xy 125.1263 -285.875638) (xy 125.095868 -285.833751) (xy 125.072362 -285.787619)
			(xy 125.056363 -285.738379) (xy 125.048264 -285.687241) (xy 125.047756 -285.661354) (xy 125.048301 -285.633647)
			(xy 125.057486 -285.579) (xy 125.066044 -285.552642) (xy 125.073918 -285.530544) (xy 124.86894 -285.175706)
			(xy 124.84608 -285.171388) (xy 124.82126 -285.166215) (xy 124.77348 -285.149263) (xy 124.728859 -285.125194)
			(xy 124.688451 -285.094575) (xy 124.653209 -285.058129) (xy 124.623965 -285.016715) (xy 124.601409 -284.971312)
			(xy 124.586072 -284.922989) (xy 124.578317 -284.872887) (xy 124.577856 -284.847538) (xy 124.323856 -284.847538)
			(xy 124.323358 -284.874187) (xy 124.315415 -284.926891) (xy 124.299705 -284.977821) (xy 124.276579 -285.025842)
			(xy 124.246555 -285.069879) (xy 124.210303 -285.10895) (xy 124.168632 -285.142181) (xy 124.122474 -285.16883)
			(xy 124.07286 -285.188302) (xy 124.020898 -285.200162) (xy 123.967748 -285.204146) (xy 123.914598 -285.200162)
			(xy 123.862636 -285.188302) (xy 123.813022 -285.16883) (xy 123.766864 -285.142181) (xy 123.725193 -285.10895)
			(xy 123.688941 -285.069879) (xy 123.658917 -285.025842) (xy 123.635791 -284.977821) (xy 123.620081 -284.926891)
			(xy 123.612138 -284.874187) (xy 123.357057 -284.874187) (xy 123.357034 -284.875255) (xy 123.347719 -284.929901)
			(xy 123.339098 -284.95625) (xy 123.331224 -284.978348) (xy 123.536202 -285.333186) (xy 123.559062 -285.337504)
			(xy 123.583868 -285.342683) (xy 123.63161 -285.359669) (xy 123.67619 -285.383762) (xy 123.716558 -285.414393)
			(xy 123.751763 -285.450841) (xy 123.780975 -285.492247) (xy 123.803506 -285.537636) (xy 123.818825 -285.585939)
			(xy 123.826572 -285.636017) (xy 123.827032 -285.661354) (xy 123.826524 -285.687241) (xy 123.818425 -285.738379)
			(xy 123.802426 -285.787619) (xy 123.77892 -285.833751) (xy 123.748488 -285.875638) (xy 123.711878 -285.912248)
			(xy 123.669991 -285.94268) (xy 123.623859 -285.966186) (xy 123.574619 -285.982185) (xy 123.523481 -285.990284)
			(xy 123.471707 -285.990284) (xy 123.420569 -285.982185) (xy 123.371329 -285.966186) (xy 123.325197 -285.94268)
			(xy 123.28331 -285.912248) (xy 123.2467 -285.875638) (xy 123.216268 -285.833751) (xy 123.192762 -285.787619)
			(xy 123.176763 -285.738379) (xy 123.168664 -285.687241) (xy 123.168156 -285.661354) (xy 123.168701 -285.633647)
			(xy 123.177886 -285.579) (xy 123.186444 -285.552642) (xy 123.194318 -285.530544) (xy 122.98934 -285.175706)
			(xy 122.96648 -285.171388) (xy 122.94166 -285.166215) (xy 122.89388 -285.149263) (xy 122.849259 -285.125194)
			(xy 122.808851 -285.094575) (xy 122.773609 -285.058129) (xy 122.744365 -285.016715) (xy 122.721809 -284.971312)
			(xy 122.706472 -284.922989) (xy 122.698717 -284.872887) (xy 122.698256 -284.847538) (xy 122.444256 -284.847538)
			(xy 122.443758 -284.874187) (xy 122.435815 -284.926891) (xy 122.420105 -284.977821) (xy 122.396979 -285.025842)
			(xy 122.366955 -285.069879) (xy 122.330703 -285.10895) (xy 122.289032 -285.142181) (xy 122.242874 -285.16883)
			(xy 122.19326 -285.188302) (xy 122.141298 -285.200162) (xy 122.088148 -285.204146) (xy 122.034998 -285.200162)
			(xy 121.983036 -285.188302) (xy 121.933422 -285.16883) (xy 121.887264 -285.142181) (xy 121.845593 -285.10895)
			(xy 121.809341 -285.069879) (xy 121.779317 -285.025842) (xy 121.756191 -284.977821) (xy 121.740481 -284.926891)
			(xy 121.732538 -284.874187) (xy 121.477457 -284.874187) (xy 121.477434 -284.875255) (xy 121.468119 -284.929901)
			(xy 121.459498 -284.95625) (xy 121.451624 -284.978348) (xy 121.656602 -285.333186) (xy 121.679462 -285.337504)
			(xy 121.704268 -285.342683) (xy 121.75201 -285.359669) (xy 121.79659 -285.383762) (xy 121.836958 -285.414393)
			(xy 121.872163 -285.450841) (xy 121.901375 -285.492247) (xy 121.923906 -285.537636) (xy 121.939225 -285.585939)
			(xy 121.946972 -285.636017) (xy 121.947432 -285.661354) (xy 121.946924 -285.687241) (xy 121.938825 -285.738379)
			(xy 121.922826 -285.787619) (xy 121.89932 -285.833751) (xy 121.868888 -285.875638) (xy 121.832278 -285.912248)
			(xy 121.790391 -285.94268) (xy 121.744259 -285.966186) (xy 121.695019 -285.982185) (xy 121.643881 -285.990284)
			(xy 121.592107 -285.990284) (xy 121.540969 -285.982185) (xy 121.491729 -285.966186) (xy 121.445597 -285.94268)
			(xy 121.40371 -285.912248) (xy 121.3671 -285.875638) (xy 121.336668 -285.833751) (xy 121.313162 -285.787619)
			(xy 121.297163 -285.738379) (xy 121.289064 -285.687241) (xy 121.288556 -285.661354) (xy 121.289101 -285.633647)
			(xy 121.298286 -285.579) (xy 121.306844 -285.552642) (xy 121.314718 -285.530544) (xy 121.10974 -285.175706)
			(xy 121.08688 -285.171388) (xy 121.06206 -285.166215) (xy 121.01428 -285.149263) (xy 120.969659 -285.125194)
			(xy 120.929251 -285.094575) (xy 120.894009 -285.058129) (xy 120.864765 -285.016715) (xy 120.842209 -284.971312)
			(xy 120.826872 -284.922989) (xy 120.819117 -284.872887) (xy 120.818656 -284.847538) (xy 120.564656 -284.847538)
			(xy 120.564158 -284.874187) (xy 120.556215 -284.926891) (xy 120.540505 -284.977821) (xy 120.517379 -285.025842)
			(xy 120.487355 -285.069879) (xy 120.451103 -285.10895) (xy 120.409432 -285.142181) (xy 120.363274 -285.16883)
			(xy 120.31366 -285.188302) (xy 120.261698 -285.200162) (xy 120.208548 -285.204146) (xy 120.155398 -285.200162)
			(xy 120.103436 -285.188302) (xy 120.053822 -285.16883) (xy 120.007664 -285.142181) (xy 119.965993 -285.10895)
			(xy 119.929741 -285.069879) (xy 119.899717 -285.025842) (xy 119.876591 -284.977821) (xy 119.860881 -284.926891)
			(xy 119.852938 -284.874187) (xy 119.597857 -284.874187) (xy 119.597834 -284.875255) (xy 119.588519 -284.929901)
			(xy 119.579898 -284.95625) (xy 119.572024 -284.978348) (xy 119.777002 -285.333186) (xy 119.799862 -285.337504)
			(xy 119.824668 -285.342683) (xy 119.87241 -285.359669) (xy 119.91699 -285.383762) (xy 119.957358 -285.414393)
			(xy 119.992563 -285.450841) (xy 120.021775 -285.492247) (xy 120.044306 -285.537636) (xy 120.059625 -285.585939)
			(xy 120.067372 -285.636017) (xy 120.067832 -285.661354) (xy 120.067324 -285.687241) (xy 120.059225 -285.738379)
			(xy 120.043226 -285.787619) (xy 120.01972 -285.833751) (xy 119.989288 -285.875638) (xy 119.952678 -285.912248)
			(xy 119.910791 -285.94268) (xy 119.864659 -285.966186) (xy 119.815419 -285.982185) (xy 119.764281 -285.990284)
			(xy 119.712507 -285.990284) (xy 119.661369 -285.982185) (xy 119.612129 -285.966186) (xy 119.565997 -285.94268)
			(xy 119.52411 -285.912248) (xy 119.4875 -285.875638) (xy 119.457068 -285.833751) (xy 119.433562 -285.787619)
			(xy 119.417563 -285.738379) (xy 119.409464 -285.687241) (xy 119.408956 -285.661354) (xy 119.409501 -285.633647)
			(xy 119.418686 -285.579) (xy 119.427244 -285.552642) (xy 119.435118 -285.530544) (xy 119.23014 -285.175706)
			(xy 119.20728 -285.171388) (xy 119.18246 -285.166215) (xy 119.13468 -285.149263) (xy 119.090059 -285.125194)
			(xy 119.049651 -285.094575) (xy 119.014409 -285.058129) (xy 118.985165 -285.016715) (xy 118.962609 -284.971312)
			(xy 118.947272 -284.922989) (xy 118.939517 -284.872887) (xy 118.939056 -284.847538) (xy 118.685056 -284.847538)
			(xy 118.684558 -284.874187) (xy 118.676615 -284.926891) (xy 118.660905 -284.977821) (xy 118.637779 -285.025842)
			(xy 118.607755 -285.069879) (xy 118.571503 -285.10895) (xy 118.529832 -285.142181) (xy 118.483674 -285.16883)
			(xy 118.43406 -285.188302) (xy 118.382098 -285.200162) (xy 118.328948 -285.204146) (xy 118.275798 -285.200162)
			(xy 118.223836 -285.188302) (xy 118.174222 -285.16883) (xy 118.128064 -285.142181) (xy 118.086393 -285.10895)
			(xy 118.050141 -285.069879) (xy 118.020117 -285.025842) (xy 117.996991 -284.977821) (xy 117.981281 -284.926891)
			(xy 117.973338 -284.874187) (xy 116.804958 -284.874187) (xy 116.797015 -284.926891) (xy 116.781305 -284.977821)
			(xy 116.758179 -285.025842) (xy 116.728155 -285.069879) (xy 116.691903 -285.10895) (xy 116.650232 -285.142181)
			(xy 116.604074 -285.16883) (xy 116.55446 -285.188302) (xy 116.502498 -285.200162) (xy 116.449348 -285.204146)
			(xy 116.396198 -285.200162) (xy 116.344236 -285.188302) (xy 116.294622 -285.16883) (xy 116.248464 -285.142181)
			(xy 116.206793 -285.10895) (xy 116.170541 -285.069879) (xy 116.140517 -285.025842) (xy 116.117391 -284.977821)
			(xy 116.101681 -284.926891) (xy 116.093738 -284.874187) (xy 113.985304 -284.874187) (xy 113.977361 -284.926891)
			(xy 113.961651 -284.977821) (xy 113.938525 -285.025842) (xy 113.908501 -285.069879) (xy 113.872249 -285.10895)
			(xy 113.830578 -285.142181) (xy 113.78442 -285.16883) (xy 113.734806 -285.188302) (xy 113.682844 -285.200162)
			(xy 113.629694 -285.204146) (xy 113.576544 -285.200162) (xy 113.524582 -285.188302) (xy 113.474968 -285.16883)
			(xy 113.42881 -285.142181) (xy 113.387139 -285.10895) (xy 113.350887 -285.069879) (xy 113.320863 -285.025842)
			(xy 113.297737 -284.977821) (xy 113.282027 -284.926891) (xy 113.274084 -284.874187) (xy 105.526049 -284.874187)
			(xy 105.524189 -284.899534) (xy 105.512818 -284.950453) (xy 105.494136 -284.999166) (xy 105.468546 -285.044632)
			(xy 105.436593 -285.085875) (xy 105.398963 -285.122013) (xy 105.356461 -285.152272) (xy 105.309998 -285.176004)
			(xy 105.260569 -285.192701) (xy 105.209233 -285.202004) (xy 105.183178 -285.203392) (xy 105.182162 -285.203392)
			(xy 105.172648 -285.204314) (xy 105.15529 -285.212281) (xy 105.14838 -285.218886) (xy 105.123742 -285.244286)
			(xy 105.098088 -285.270956) (xy 105.092121 -285.278182) (xy 105.085337 -285.295633) (xy 105.08488 -285.304992)
			(xy 105.08488 -285.688003) (xy 107.165384 -285.688003) (xy 107.165384 -285.634705) (xy 107.173327 -285.582001)
			(xy 107.189037 -285.531071) (xy 107.212163 -285.48305) (xy 107.242187 -285.439013) (xy 107.278439 -285.399942)
			(xy 107.32011 -285.366711) (xy 107.366268 -285.340062) (xy 107.415882 -285.32059) (xy 107.467844 -285.30873)
			(xy 107.520994 -285.304747) (xy 107.574144 -285.30873) (xy 107.626106 -285.32059) (xy 107.67572 -285.340062)
			(xy 107.721878 -285.366711) (xy 107.763549 -285.399942) (xy 107.799801 -285.439013) (xy 107.829825 -285.48305)
			(xy 107.852951 -285.531071) (xy 107.868661 -285.582001) (xy 107.876604 -285.634705) (xy 107.877102 -285.661354)
			(xy 107.876604 -285.688003) (xy 109.984784 -285.688003) (xy 109.984784 -285.634705) (xy 109.992727 -285.582001)
			(xy 110.008437 -285.531071) (xy 110.031563 -285.48305) (xy 110.061587 -285.439013) (xy 110.097839 -285.399942)
			(xy 110.13951 -285.366711) (xy 110.185668 -285.340062) (xy 110.235282 -285.32059) (xy 110.287244 -285.30873)
			(xy 110.340394 -285.304747) (xy 110.393544 -285.30873) (xy 110.445506 -285.32059) (xy 110.49512 -285.340062)
			(xy 110.541278 -285.366711) (xy 110.582949 -285.399942) (xy 110.619201 -285.439013) (xy 110.649225 -285.48305)
			(xy 110.672351 -285.531071) (xy 110.688061 -285.582001) (xy 110.696004 -285.634705) (xy 110.696502 -285.661354)
			(xy 110.696004 -285.688003) (xy 118.443238 -285.688003) (xy 118.443238 -285.634705) (xy 118.451181 -285.582001)
			(xy 118.466891 -285.531071) (xy 118.490017 -285.48305) (xy 118.520041 -285.439013) (xy 118.556293 -285.399942)
			(xy 118.597964 -285.366711) (xy 118.644122 -285.340062) (xy 118.693736 -285.32059) (xy 118.745698 -285.30873)
			(xy 118.798848 -285.304747) (xy 118.851998 -285.30873) (xy 118.90396 -285.32059) (xy 118.953574 -285.340062)
			(xy 118.999732 -285.366711) (xy 119.041403 -285.399942) (xy 119.077655 -285.439013) (xy 119.107679 -285.48305)
			(xy 119.130805 -285.531071) (xy 119.146515 -285.582001) (xy 119.154458 -285.634705) (xy 119.154956 -285.661354)
			(xy 119.154458 -285.688003) (xy 119.146515 -285.740707) (xy 119.130805 -285.791637) (xy 119.107679 -285.839658)
			(xy 119.077655 -285.883695) (xy 119.041403 -285.922766) (xy 118.999732 -285.955997) (xy 118.953574 -285.982646)
			(xy 118.90396 -286.002118) (xy 118.851998 -286.013978) (xy 118.798848 -286.017962) (xy 118.745698 -286.013978)
			(xy 118.693736 -286.002118) (xy 118.644122 -285.982646) (xy 118.597964 -285.955997) (xy 118.556293 -285.922766)
			(xy 118.520041 -285.883695) (xy 118.490017 -285.839658) (xy 118.466891 -285.791637) (xy 118.451181 -285.740707)
			(xy 118.443238 -285.688003) (xy 110.696004 -285.688003) (xy 110.688061 -285.740707) (xy 110.672351 -285.791637)
			(xy 110.649225 -285.839658) (xy 110.619201 -285.883695) (xy 110.582949 -285.922766) (xy 110.541278 -285.955997)
			(xy 110.49512 -285.982646) (xy 110.445506 -286.002118) (xy 110.393544 -286.013978) (xy 110.340394 -286.017962)
			(xy 110.287244 -286.013978) (xy 110.235282 -286.002118) (xy 110.185668 -285.982646) (xy 110.13951 -285.955997)
			(xy 110.097839 -285.922766) (xy 110.061587 -285.883695) (xy 110.031563 -285.839658) (xy 110.008437 -285.791637)
			(xy 109.992727 -285.740707) (xy 109.984784 -285.688003) (xy 107.876604 -285.688003) (xy 107.868661 -285.740707)
			(xy 107.852951 -285.791637) (xy 107.829825 -285.839658) (xy 107.799801 -285.883695) (xy 107.763549 -285.922766)
			(xy 107.721878 -285.955997) (xy 107.67572 -285.982646) (xy 107.626106 -286.002118) (xy 107.574144 -286.013978)
			(xy 107.520994 -286.017962) (xy 107.467844 -286.013978) (xy 107.415882 -286.002118) (xy 107.366268 -285.982646)
			(xy 107.32011 -285.955997) (xy 107.278439 -285.922766) (xy 107.242187 -285.883695) (xy 107.212163 -285.839658)
			(xy 107.189037 -285.791637) (xy 107.173327 -285.740707) (xy 107.165384 -285.688003) (xy 105.08488 -285.688003)
			(xy 105.08488 -285.73857) (xy 105.085349 -285.748443) (xy 105.092803 -285.766731) (xy 105.099358 -285.77413)
			(xy 105.12425 -285.79953) (xy 105.150158 -285.825946) (xy 105.157117 -285.832096) (xy 105.174178 -285.839389)
			(xy 105.183432 -285.84017) (xy 105.184448 -285.84017) (xy 105.219641 -285.84133) (xy 105.289461 -285.850478)
			(xy 105.357841 -285.867292) (xy 105.423942 -285.891567) (xy 105.486952 -285.923004) (xy 105.546098 -285.961218)
			(xy 105.600654 -286.00574) (xy 105.649951 -286.056022) (xy 105.693384 -286.111449) (xy 105.73042 -286.17134)
			(xy 105.760603 -286.23496) (xy 105.783565 -286.301528) (xy 105.799023 -286.370228) (xy 105.806787 -286.440215)
			(xy 105.807256 -286.475424) (xy 105.807256 -286.502073) (xy 113.274084 -286.502073) (xy 113.274084 -286.448775)
			(xy 113.282027 -286.396071) (xy 113.297737 -286.345141) (xy 113.320863 -286.29712) (xy 113.350887 -286.253083)
			(xy 113.387139 -286.214012) (xy 113.42881 -286.180781) (xy 113.474968 -286.154132) (xy 113.524582 -286.13466)
			(xy 113.576544 -286.1228) (xy 113.629694 -286.118817) (xy 113.682844 -286.1228) (xy 113.734806 -286.13466)
			(xy 113.78442 -286.154132) (xy 113.830578 -286.180781) (xy 113.872249 -286.214012) (xy 113.908501 -286.253083)
			(xy 113.938525 -286.29712) (xy 113.961651 -286.345141) (xy 113.977361 -286.396071) (xy 113.985304 -286.448775)
			(xy 113.985802 -286.475424) (xy 113.985304 -286.502073) (xy 116.093738 -286.502073) (xy 116.093738 -286.448775)
			(xy 116.101681 -286.396071) (xy 116.117391 -286.345141) (xy 116.140517 -286.29712) (xy 116.170541 -286.253083)
			(xy 116.206793 -286.214012) (xy 116.248464 -286.180781) (xy 116.294622 -286.154132) (xy 116.344236 -286.13466)
			(xy 116.396198 -286.1228) (xy 116.449348 -286.118817) (xy 116.502498 -286.1228) (xy 116.55446 -286.13466)
			(xy 116.604074 -286.154132) (xy 116.650232 -286.180781) (xy 116.691903 -286.214012) (xy 116.728155 -286.253083)
			(xy 116.758179 -286.29712) (xy 116.781305 -286.345141) (xy 116.797015 -286.396071) (xy 116.804958 -286.448775)
			(xy 116.805456 -286.475424) (xy 116.804958 -286.502073) (xy 118.913138 -286.502073) (xy 118.913138 -286.448775)
			(xy 118.921081 -286.396071) (xy 118.936791 -286.345141) (xy 118.959917 -286.29712) (xy 118.989941 -286.253083)
			(xy 119.026193 -286.214012) (xy 119.067864 -286.180781) (xy 119.114022 -286.154132) (xy 119.163636 -286.13466)
			(xy 119.215598 -286.1228) (xy 119.268748 -286.118817) (xy 119.321898 -286.1228) (xy 119.37386 -286.13466)
			(xy 119.423474 -286.154132) (xy 119.469632 -286.180781) (xy 119.511303 -286.214012) (xy 119.547555 -286.253083)
			(xy 119.577579 -286.29712) (xy 119.600705 -286.345141) (xy 119.616415 -286.396071) (xy 119.624358 -286.448775)
			(xy 119.624856 -286.475424) (xy 119.878856 -286.475424) (xy 119.879354 -286.450079) (xy 119.887123 -286.399987)
			(xy 119.902468 -286.351675) (xy 119.925026 -286.306281) (xy 119.954266 -286.264873) (xy 119.989499 -286.228429)
			(xy 120.029894 -286.197807) (xy 120.0745 -286.173728) (xy 120.122266 -286.156759) (xy 120.14708 -286.151574)
			(xy 120.16994 -286.147256) (xy 120.374918 -285.792164) (xy 120.367044 -285.77032) (xy 120.358471 -285.743899)
			(xy 120.34927 -285.689126) (xy 120.348756 -285.661354) (xy 120.349264 -285.635467) (xy 120.357363 -285.584329)
			(xy 120.373362 -285.535089) (xy 120.396868 -285.488957) (xy 120.4273 -285.44707) (xy 120.46391 -285.41046)
			(xy 120.505797 -285.380028) (xy 120.551929 -285.356522) (xy 120.601169 -285.340523) (xy 120.652307 -285.332424)
			(xy 120.704081 -285.332424) (xy 120.755219 -285.340523) (xy 120.804459 -285.356522) (xy 120.850591 -285.380028)
			(xy 120.892478 -285.41046) (xy 120.929088 -285.44707) (xy 120.95952 -285.488957) (xy 120.983026 -285.535089)
			(xy 120.999025 -285.584329) (xy 121.007124 -285.635467) (xy 121.007632 -285.661354) (xy 121.007172 -285.686689)
			(xy 120.999413 -285.736761) (xy 120.984085 -285.785057) (xy 120.961549 -285.830439) (xy 120.932336 -285.87184)
			(xy 120.897134 -285.908285) (xy 120.856771 -285.938915) (xy 120.812197 -285.963011) (xy 120.764462 -285.980004)
			(xy 120.739662 -285.985204) (xy 120.716802 -285.989522) (xy 120.511824 -286.344614) (xy 120.519698 -286.366458)
			(xy 120.528349 -286.392865) (xy 120.537666 -286.447642) (xy 120.53824 -286.475424) (xy 120.537732 -286.501331)
			(xy 120.537614 -286.502073) (xy 120.792484 -286.502073) (xy 120.792484 -286.448775) (xy 120.800427 -286.396071)
			(xy 120.816137 -286.345141) (xy 120.839263 -286.29712) (xy 120.869287 -286.253083) (xy 120.905539 -286.214012)
			(xy 120.94721 -286.180781) (xy 120.993368 -286.154132) (xy 121.042982 -286.13466) (xy 121.094944 -286.1228)
			(xy 121.148094 -286.118817) (xy 121.201244 -286.1228) (xy 121.253206 -286.13466) (xy 121.30282 -286.154132)
			(xy 121.348978 -286.180781) (xy 121.390649 -286.214012) (xy 121.426901 -286.253083) (xy 121.456925 -286.29712)
			(xy 121.480051 -286.345141) (xy 121.495761 -286.396071) (xy 121.503704 -286.448775) (xy 121.504202 -286.475424)
			(xy 121.758456 -286.475424) (xy 121.758954 -286.450079) (xy 121.766723 -286.399987) (xy 121.782068 -286.351675)
			(xy 121.804626 -286.306281) (xy 121.833866 -286.264873) (xy 121.869099 -286.228429) (xy 121.909494 -286.197807)
			(xy 121.9541 -286.173728) (xy 122.001866 -286.156759) (xy 122.02668 -286.151574) (xy 122.04954 -286.147256)
			(xy 122.254518 -285.792164) (xy 122.246644 -285.77032) (xy 122.238071 -285.743899) (xy 122.22887 -285.689126)
			(xy 122.228356 -285.661354) (xy 122.228864 -285.635467) (xy 122.236963 -285.584329) (xy 122.252962 -285.535089)
			(xy 122.276468 -285.488957) (xy 122.3069 -285.44707) (xy 122.34351 -285.41046) (xy 122.385397 -285.380028)
			(xy 122.431529 -285.356522) (xy 122.480769 -285.340523) (xy 122.531907 -285.332424) (xy 122.583681 -285.332424)
			(xy 122.634819 -285.340523) (xy 122.684059 -285.356522) (xy 122.730191 -285.380028) (xy 122.772078 -285.41046)
			(xy 122.808688 -285.44707) (xy 122.83912 -285.488957) (xy 122.862626 -285.535089) (xy 122.878625 -285.584329)
			(xy 122.886724 -285.635467) (xy 122.887232 -285.661354) (xy 122.886772 -285.686689) (xy 122.879013 -285.736761)
			(xy 122.863685 -285.785057) (xy 122.841149 -285.830439) (xy 122.811936 -285.87184) (xy 122.776734 -285.908285)
			(xy 122.736371 -285.938915) (xy 122.691797 -285.963011) (xy 122.644062 -285.980004) (xy 122.619262 -285.985204)
			(xy 122.596402 -285.989522) (xy 122.391424 -286.344614) (xy 122.399298 -286.366458) (xy 122.407949 -286.392865)
			(xy 122.417266 -286.447642) (xy 122.41784 -286.475424) (xy 122.417332 -286.501331) (xy 122.417214 -286.502073)
			(xy 122.672084 -286.502073) (xy 122.672084 -286.448775) (xy 122.680027 -286.396071) (xy 122.695737 -286.345141)
			(xy 122.718863 -286.29712) (xy 122.748887 -286.253083) (xy 122.785139 -286.214012) (xy 122.82681 -286.180781)
			(xy 122.872968 -286.154132) (xy 122.922582 -286.13466) (xy 122.974544 -286.1228) (xy 123.027694 -286.118817)
			(xy 123.080844 -286.1228) (xy 123.132806 -286.13466) (xy 123.18242 -286.154132) (xy 123.228578 -286.180781)
			(xy 123.270249 -286.214012) (xy 123.306501 -286.253083) (xy 123.336525 -286.29712) (xy 123.359651 -286.345141)
			(xy 123.375361 -286.396071) (xy 123.383304 -286.448775) (xy 123.383802 -286.475424) (xy 123.638056 -286.475424)
			(xy 123.638554 -286.450079) (xy 123.646323 -286.399987) (xy 123.661668 -286.351675) (xy 123.684226 -286.306281)
			(xy 123.713466 -286.264873) (xy 123.748699 -286.228429) (xy 123.789094 -286.197807) (xy 123.8337 -286.173728)
			(xy 123.881466 -286.156759) (xy 123.90628 -286.151574) (xy 123.92914 -286.147256) (xy 124.134118 -285.792164)
			(xy 124.126244 -285.77032) (xy 124.117671 -285.743899) (xy 124.10847 -285.689126) (xy 124.107956 -285.661354)
			(xy 124.108464 -285.635467) (xy 124.116563 -285.584329) (xy 124.132562 -285.535089) (xy 124.156068 -285.488957)
			(xy 124.1865 -285.44707) (xy 124.22311 -285.41046) (xy 124.264997 -285.380028) (xy 124.311129 -285.356522)
			(xy 124.360369 -285.340523) (xy 124.411507 -285.332424) (xy 124.463281 -285.332424) (xy 124.514419 -285.340523)
			(xy 124.563659 -285.356522) (xy 124.609791 -285.380028) (xy 124.651678 -285.41046) (xy 124.688288 -285.44707)
			(xy 124.71872 -285.488957) (xy 124.742226 -285.535089) (xy 124.758225 -285.584329) (xy 124.766324 -285.635467)
			(xy 124.766832 -285.661354) (xy 124.766372 -285.686689) (xy 124.758613 -285.736761) (xy 124.743285 -285.785057)
			(xy 124.720749 -285.830439) (xy 124.691536 -285.87184) (xy 124.656334 -285.908285) (xy 124.615971 -285.938915)
			(xy 124.571397 -285.963011) (xy 124.523662 -285.980004) (xy 124.498862 -285.985204) (xy 124.476002 -285.989522)
			(xy 124.271024 -286.344614) (xy 124.278898 -286.366458) (xy 124.287549 -286.392865) (xy 124.296866 -286.447642)
			(xy 124.29744 -286.475424) (xy 124.296932 -286.501331) (xy 124.296814 -286.502073) (xy 124.551684 -286.502073)
			(xy 124.551684 -286.448775) (xy 124.559627 -286.396071) (xy 124.575337 -286.345141) (xy 124.598463 -286.29712)
			(xy 124.628487 -286.253083) (xy 124.664739 -286.214012) (xy 124.70641 -286.180781) (xy 124.752568 -286.154132)
			(xy 124.802182 -286.13466) (xy 124.854144 -286.1228) (xy 124.907294 -286.118817) (xy 124.960444 -286.1228)
			(xy 125.012406 -286.13466) (xy 125.06202 -286.154132) (xy 125.108178 -286.180781) (xy 125.149849 -286.214012)
			(xy 125.186101 -286.253083) (xy 125.216125 -286.29712) (xy 125.239251 -286.345141) (xy 125.254961 -286.396071)
			(xy 125.262904 -286.448775) (xy 125.263402 -286.475424) (xy 125.517656 -286.475424) (xy 125.518154 -286.450079)
			(xy 125.525923 -286.399987) (xy 125.541268 -286.351675) (xy 125.563826 -286.306281) (xy 125.593066 -286.264873)
			(xy 125.628299 -286.228429) (xy 125.668694 -286.197807) (xy 125.7133 -286.173728) (xy 125.761066 -286.156759)
			(xy 125.78588 -286.151574) (xy 125.80874 -286.147256) (xy 126.013718 -285.792164) (xy 126.005844 -285.77032)
			(xy 125.997271 -285.743899) (xy 125.98807 -285.689126) (xy 125.987556 -285.661354) (xy 125.988064 -285.635467)
			(xy 125.996163 -285.584329) (xy 126.012162 -285.535089) (xy 126.035668 -285.488957) (xy 126.0661 -285.44707)
			(xy 126.10271 -285.41046) (xy 126.144597 -285.380028) (xy 126.190729 -285.356522) (xy 126.239969 -285.340523)
			(xy 126.291107 -285.332424) (xy 126.342881 -285.332424) (xy 126.394019 -285.340523) (xy 126.443259 -285.356522)
			(xy 126.489391 -285.380028) (xy 126.531278 -285.41046) (xy 126.567888 -285.44707) (xy 126.59832 -285.488957)
			(xy 126.621826 -285.535089) (xy 126.637825 -285.584329) (xy 126.645924 -285.635467) (xy 126.646432 -285.661354)
			(xy 126.645972 -285.686689) (xy 126.638213 -285.736761) (xy 126.622885 -285.785057) (xy 126.600349 -285.830439)
			(xy 126.571136 -285.87184) (xy 126.535934 -285.908285) (xy 126.495571 -285.938915) (xy 126.450997 -285.963011)
			(xy 126.403262 -285.980004) (xy 126.378462 -285.985204) (xy 126.355602 -285.989522) (xy 126.150624 -286.344614)
			(xy 126.158498 -286.366458) (xy 126.167149 -286.392865) (xy 126.176466 -286.447642) (xy 126.17704 -286.475424)
			(xy 126.176532 -286.501331) (xy 126.176414 -286.502073) (xy 126.431284 -286.502073) (xy 126.431284 -286.448775)
			(xy 126.439227 -286.396071) (xy 126.454937 -286.345141) (xy 126.478063 -286.29712) (xy 126.508087 -286.253083)
			(xy 126.544339 -286.214012) (xy 126.58601 -286.180781) (xy 126.632168 -286.154132) (xy 126.681782 -286.13466)
			(xy 126.733744 -286.1228) (xy 126.786894 -286.118817) (xy 126.840044 -286.1228) (xy 126.892006 -286.13466)
			(xy 126.94162 -286.154132) (xy 126.987778 -286.180781) (xy 127.029449 -286.214012) (xy 127.065701 -286.253083)
			(xy 127.095725 -286.29712) (xy 127.118851 -286.345141) (xy 127.134561 -286.396071) (xy 127.142504 -286.448775)
			(xy 127.143002 -286.475424) (xy 127.397256 -286.475424) (xy 127.397754 -286.450079) (xy 127.405523 -286.399987)
			(xy 127.420868 -286.351675) (xy 127.443426 -286.306281) (xy 127.472666 -286.264873) (xy 127.507899 -286.228429)
			(xy 127.548294 -286.197807) (xy 127.5929 -286.173728) (xy 127.640666 -286.156759) (xy 127.66548 -286.151574)
			(xy 127.68834 -286.147256) (xy 127.893318 -285.792164) (xy 127.885444 -285.77032) (xy 127.876871 -285.743899)
			(xy 127.86767 -285.689126) (xy 127.867156 -285.661354) (xy 127.867664 -285.635467) (xy 127.875763 -285.584329)
			(xy 127.891762 -285.535089) (xy 127.915268 -285.488957) (xy 127.9457 -285.44707) (xy 127.98231 -285.41046)
			(xy 128.024197 -285.380028) (xy 128.070329 -285.356522) (xy 128.119569 -285.340523) (xy 128.170707 -285.332424)
			(xy 128.222481 -285.332424) (xy 128.273619 -285.340523) (xy 128.322859 -285.356522) (xy 128.368991 -285.380028)
			(xy 128.410878 -285.41046) (xy 128.447488 -285.44707) (xy 128.47792 -285.488957) (xy 128.501426 -285.535089)
			(xy 128.517425 -285.584329) (xy 128.525524 -285.635467) (xy 128.526032 -285.661354) (xy 128.525572 -285.686689)
			(xy 128.517813 -285.736761) (xy 128.502485 -285.785057) (xy 128.479949 -285.830439) (xy 128.450736 -285.87184)
			(xy 128.415534 -285.908285) (xy 128.375171 -285.938915) (xy 128.330597 -285.963011) (xy 128.282862 -285.980004)
			(xy 128.258062 -285.985204) (xy 128.235202 -285.989522) (xy 128.030224 -286.344614) (xy 128.038098 -286.366458)
			(xy 128.046749 -286.392865) (xy 128.056066 -286.447642) (xy 128.05664 -286.475424) (xy 128.056132 -286.501331)
			(xy 128.056014 -286.502073) (xy 128.310884 -286.502073) (xy 128.310884 -286.448775) (xy 128.318827 -286.396071)
			(xy 128.334537 -286.345141) (xy 128.357663 -286.29712) (xy 128.387687 -286.253083) (xy 128.423939 -286.214012)
			(xy 128.46561 -286.180781) (xy 128.511768 -286.154132) (xy 128.561382 -286.13466) (xy 128.613344 -286.1228)
			(xy 128.666494 -286.118817) (xy 128.719644 -286.1228) (xy 128.771606 -286.13466) (xy 128.82122 -286.154132)
			(xy 128.867378 -286.180781) (xy 128.909049 -286.214012) (xy 128.945301 -286.253083) (xy 128.975325 -286.29712)
			(xy 128.998451 -286.345141) (xy 129.014161 -286.396071) (xy 129.022104 -286.448775) (xy 129.022602 -286.475424)
			(xy 129.276856 -286.475424) (xy 129.277354 -286.450079) (xy 129.285123 -286.399987) (xy 129.300468 -286.351675)
			(xy 129.323026 -286.306281) (xy 129.352266 -286.264873) (xy 129.387499 -286.228429) (xy 129.427894 -286.197807)
			(xy 129.4725 -286.173728) (xy 129.520266 -286.156759) (xy 129.54508 -286.151574) (xy 129.56794 -286.147256)
			(xy 129.772918 -285.792164) (xy 129.765044 -285.77032) (xy 129.756471 -285.743899) (xy 129.74727 -285.689126)
			(xy 129.746756 -285.661354) (xy 129.747264 -285.635467) (xy 129.755363 -285.584329) (xy 129.771362 -285.535089)
			(xy 129.794868 -285.488957) (xy 129.8253 -285.44707) (xy 129.86191 -285.41046) (xy 129.903797 -285.380028)
			(xy 129.949929 -285.356522) (xy 129.999169 -285.340523) (xy 130.050307 -285.332424) (xy 130.102081 -285.332424)
			(xy 130.153219 -285.340523) (xy 130.202459 -285.356522) (xy 130.248591 -285.380028) (xy 130.290478 -285.41046)
			(xy 130.327088 -285.44707) (xy 130.35752 -285.488957) (xy 130.381026 -285.535089) (xy 130.397025 -285.584329)
			(xy 130.405124 -285.635467) (xy 130.405632 -285.661354) (xy 130.405172 -285.686689) (xy 130.397413 -285.736761)
			(xy 130.382085 -285.785057) (xy 130.359549 -285.830439) (xy 130.330336 -285.87184) (xy 130.295134 -285.908285)
			(xy 130.254771 -285.938915) (xy 130.210197 -285.963011) (xy 130.162462 -285.980004) (xy 130.137662 -285.985204)
			(xy 130.114802 -285.989522) (xy 129.909824 -286.344614) (xy 129.917698 -286.366458) (xy 129.926349 -286.392865)
			(xy 129.935666 -286.447642) (xy 129.93624 -286.475424) (xy 129.935732 -286.501331) (xy 129.935614 -286.502073)
			(xy 130.190484 -286.502073) (xy 130.190484 -286.448775) (xy 130.198427 -286.396071) (xy 130.214137 -286.345141)
			(xy 130.237263 -286.29712) (xy 130.267287 -286.253083) (xy 130.303539 -286.214012) (xy 130.34521 -286.180781)
			(xy 130.391368 -286.154132) (xy 130.440982 -286.13466) (xy 130.492944 -286.1228) (xy 130.546094 -286.118817)
			(xy 130.599244 -286.1228) (xy 130.651206 -286.13466) (xy 130.70082 -286.154132) (xy 130.746978 -286.180781)
			(xy 130.788649 -286.214012) (xy 130.824901 -286.253083) (xy 130.854925 -286.29712) (xy 130.878051 -286.345141)
			(xy 130.893761 -286.396071) (xy 130.901704 -286.448775) (xy 130.902202 -286.475424) (xy 131.156456 -286.475424)
			(xy 131.156954 -286.450079) (xy 131.164723 -286.399987) (xy 131.180068 -286.351675) (xy 131.202626 -286.306281)
			(xy 131.231866 -286.264873) (xy 131.267099 -286.228429) (xy 131.307494 -286.197807) (xy 131.3521 -286.173728)
			(xy 131.399866 -286.156759) (xy 131.42468 -286.151574) (xy 131.44754 -286.147256) (xy 131.652518 -285.792164)
			(xy 131.644644 -285.77032) (xy 131.636071 -285.743899) (xy 131.62687 -285.689126) (xy 131.626356 -285.661354)
			(xy 131.626864 -285.635467) (xy 131.634963 -285.584329) (xy 131.650962 -285.535089) (xy 131.674468 -285.488957)
			(xy 131.7049 -285.44707) (xy 131.74151 -285.41046) (xy 131.783397 -285.380028) (xy 131.829529 -285.356522)
			(xy 131.878769 -285.340523) (xy 131.929907 -285.332424) (xy 131.981681 -285.332424) (xy 132.032819 -285.340523)
			(xy 132.082059 -285.356522) (xy 132.128191 -285.380028) (xy 132.170078 -285.41046) (xy 132.206688 -285.44707)
			(xy 132.23712 -285.488957) (xy 132.260626 -285.535089) (xy 132.276625 -285.584329) (xy 132.284724 -285.635467)
			(xy 132.285232 -285.661354) (xy 132.284772 -285.686689) (xy 132.277013 -285.736761) (xy 132.261685 -285.785057)
			(xy 132.239149 -285.830439) (xy 132.209936 -285.87184) (xy 132.174734 -285.908285) (xy 132.134371 -285.938915)
			(xy 132.089797 -285.963011) (xy 132.042062 -285.980004) (xy 132.017262 -285.985204) (xy 131.994402 -285.989522)
			(xy 131.789424 -286.344614) (xy 131.797298 -286.366458) (xy 131.805949 -286.392865) (xy 131.815266 -286.447642)
			(xy 131.81584 -286.475424) (xy 131.815332 -286.501331) (xy 131.815214 -286.502073) (xy 132.070084 -286.502073)
			(xy 132.070084 -286.448775) (xy 132.078027 -286.396071) (xy 132.093737 -286.345141) (xy 132.116863 -286.29712)
			(xy 132.146887 -286.253083) (xy 132.183139 -286.214012) (xy 132.22481 -286.180781) (xy 132.270968 -286.154132)
			(xy 132.320582 -286.13466) (xy 132.372544 -286.1228) (xy 132.425694 -286.118817) (xy 132.478844 -286.1228)
			(xy 132.530806 -286.13466) (xy 132.58042 -286.154132) (xy 132.626578 -286.180781) (xy 132.668249 -286.214012)
			(xy 132.704501 -286.253083) (xy 132.734525 -286.29712) (xy 132.757651 -286.345141) (xy 132.773361 -286.396071)
			(xy 132.781304 -286.448775) (xy 132.781802 -286.475424) (xy 133.036056 -286.475424) (xy 133.036554 -286.450079)
			(xy 133.044323 -286.399987) (xy 133.059668 -286.351675) (xy 133.082226 -286.306281) (xy 133.111466 -286.264873)
			(xy 133.146699 -286.228429) (xy 133.187094 -286.197807) (xy 133.2317 -286.173728) (xy 133.279466 -286.156759)
			(xy 133.30428 -286.151574) (xy 133.32714 -286.147256) (xy 133.532118 -285.792164) (xy 133.524244 -285.77032)
			(xy 133.515671 -285.743899) (xy 133.50647 -285.689126) (xy 133.505956 -285.661354) (xy 133.506464 -285.635467)
			(xy 133.514563 -285.584329) (xy 133.530562 -285.535089) (xy 133.554068 -285.488957) (xy 133.5845 -285.44707)
			(xy 133.62111 -285.41046) (xy 133.662997 -285.380028) (xy 133.709129 -285.356522) (xy 133.758369 -285.340523)
			(xy 133.809507 -285.332424) (xy 133.861281 -285.332424) (xy 133.912419 -285.340523) (xy 133.961659 -285.356522)
			(xy 134.007791 -285.380028) (xy 134.049678 -285.41046) (xy 134.086288 -285.44707) (xy 134.11672 -285.488957)
			(xy 134.140226 -285.535089) (xy 134.156225 -285.584329) (xy 134.164324 -285.635467) (xy 134.164832 -285.661354)
			(xy 134.164372 -285.686689) (xy 134.164168 -285.688003) (xy 134.419584 -285.688003) (xy 134.419584 -285.634705)
			(xy 134.427527 -285.582001) (xy 134.443237 -285.531071) (xy 134.466363 -285.48305) (xy 134.496387 -285.439013)
			(xy 134.532639 -285.399942) (xy 134.57431 -285.366711) (xy 134.620468 -285.340062) (xy 134.670082 -285.32059)
			(xy 134.722044 -285.30873) (xy 134.775194 -285.304747) (xy 134.828344 -285.30873) (xy 134.880306 -285.32059)
			(xy 134.92992 -285.340062) (xy 134.976078 -285.366711) (xy 135.017749 -285.399942) (xy 135.054001 -285.439013)
			(xy 135.084025 -285.48305) (xy 135.107151 -285.531071) (xy 135.122861 -285.582001) (xy 135.130804 -285.634705)
			(xy 135.131302 -285.661354) (xy 135.130809 -285.687749) (xy 135.359384 -285.687749) (xy 135.359384 -285.634451)
			(xy 135.367327 -285.581747) (xy 135.383037 -285.530817) (xy 135.406163 -285.482796) (xy 135.436187 -285.438759)
			(xy 135.472439 -285.399688) (xy 135.51411 -285.366457) (xy 135.560268 -285.339808) (xy 135.609882 -285.320336)
			(xy 135.661844 -285.308476) (xy 135.714994 -285.304493) (xy 135.768144 -285.308476) (xy 135.820106 -285.320336)
			(xy 135.86972 -285.339808) (xy 135.915878 -285.366457) (xy 135.957549 -285.399688) (xy 135.993801 -285.438759)
			(xy 136.023825 -285.482796) (xy 136.046951 -285.530817) (xy 136.062661 -285.581747) (xy 136.070604 -285.634451)
			(xy 136.071102 -285.6611) (xy 136.070604 -285.687749) (xy 136.070566 -285.688003) (xy 136.299184 -285.688003)
			(xy 136.299184 -285.634705) (xy 136.307127 -285.582001) (xy 136.322837 -285.531071) (xy 136.345963 -285.48305)
			(xy 136.375987 -285.439013) (xy 136.412239 -285.399942) (xy 136.45391 -285.366711) (xy 136.500068 -285.340062)
			(xy 136.549682 -285.32059) (xy 136.601644 -285.30873) (xy 136.654794 -285.304747) (xy 136.707944 -285.30873)
			(xy 136.759906 -285.32059) (xy 136.80952 -285.340062) (xy 136.855678 -285.366711) (xy 136.897349 -285.399942)
			(xy 136.933601 -285.439013) (xy 136.963625 -285.48305) (xy 136.986751 -285.531071) (xy 137.002461 -285.582001)
			(xy 137.010404 -285.634705) (xy 137.010902 -285.661354) (xy 137.010409 -285.687749) (xy 137.238984 -285.687749)
			(xy 137.238984 -285.634451) (xy 137.246927 -285.581747) (xy 137.262637 -285.530817) (xy 137.285763 -285.482796)
			(xy 137.315787 -285.438759) (xy 137.352039 -285.399688) (xy 137.39371 -285.366457) (xy 137.439868 -285.339808)
			(xy 137.489482 -285.320336) (xy 137.541444 -285.308476) (xy 137.594594 -285.304493) (xy 137.647744 -285.308476)
			(xy 137.699706 -285.320336) (xy 137.74932 -285.339808) (xy 137.795478 -285.366457) (xy 137.837149 -285.399688)
			(xy 137.873401 -285.438759) (xy 137.903425 -285.482796) (xy 137.926551 -285.530817) (xy 137.942261 -285.581747)
			(xy 137.950204 -285.634451) (xy 137.950702 -285.6611) (xy 137.950204 -285.687749) (xy 137.950166 -285.688003)
			(xy 138.178784 -285.688003) (xy 138.178784 -285.634705) (xy 138.186727 -285.582001) (xy 138.202437 -285.531071)
			(xy 138.225563 -285.48305) (xy 138.255587 -285.439013) (xy 138.291839 -285.399942) (xy 138.33351 -285.366711)
			(xy 138.379668 -285.340062) (xy 138.429282 -285.32059) (xy 138.481244 -285.30873) (xy 138.534394 -285.304747)
			(xy 138.587544 -285.30873) (xy 138.639506 -285.32059) (xy 138.68912 -285.340062) (xy 138.735278 -285.366711)
			(xy 138.776949 -285.399942) (xy 138.813201 -285.439013) (xy 138.843225 -285.48305) (xy 138.866351 -285.531071)
			(xy 138.882061 -285.582001) (xy 138.890004 -285.634705) (xy 138.890502 -285.661354) (xy 138.890004 -285.688003)
			(xy 138.882061 -285.740707) (xy 138.866351 -285.791637) (xy 138.843225 -285.839658) (xy 138.813201 -285.883695)
			(xy 138.776949 -285.922766) (xy 138.735278 -285.955997) (xy 138.68912 -285.982646) (xy 138.639506 -286.002118)
			(xy 138.587544 -286.013978) (xy 138.534394 -286.017962) (xy 138.481244 -286.013978) (xy 138.429282 -286.002118)
			(xy 138.379668 -285.982646) (xy 138.33351 -285.955997) (xy 138.291839 -285.922766) (xy 138.255587 -285.883695)
			(xy 138.225563 -285.839658) (xy 138.202437 -285.791637) (xy 138.186727 -285.740707) (xy 138.178784 -285.688003)
			(xy 137.950166 -285.688003) (xy 137.942261 -285.740453) (xy 137.926551 -285.791383) (xy 137.903425 -285.839404)
			(xy 137.873401 -285.883441) (xy 137.837149 -285.922512) (xy 137.795478 -285.955743) (xy 137.74932 -285.982392)
			(xy 137.699706 -286.001864) (xy 137.647744 -286.013724) (xy 137.594594 -286.017708) (xy 137.541444 -286.013724)
			(xy 137.489482 -286.001864) (xy 137.439868 -285.982392) (xy 137.39371 -285.955743) (xy 137.352039 -285.922512)
			(xy 137.315787 -285.883441) (xy 137.285763 -285.839404) (xy 137.262637 -285.791383) (xy 137.246927 -285.740453)
			(xy 137.238984 -285.687749) (xy 137.010409 -285.687749) (xy 137.010404 -285.688003) (xy 137.002461 -285.740707)
			(xy 136.986751 -285.791637) (xy 136.963625 -285.839658) (xy 136.933601 -285.883695) (xy 136.897349 -285.922766)
			(xy 136.855678 -285.955997) (xy 136.80952 -285.982646) (xy 136.759906 -286.002118) (xy 136.707944 -286.013978)
			(xy 136.654794 -286.017962) (xy 136.601644 -286.013978) (xy 136.549682 -286.002118) (xy 136.500068 -285.982646)
			(xy 136.45391 -285.955997) (xy 136.412239 -285.922766) (xy 136.375987 -285.883695) (xy 136.345963 -285.839658)
			(xy 136.322837 -285.791637) (xy 136.307127 -285.740707) (xy 136.299184 -285.688003) (xy 136.070566 -285.688003)
			(xy 136.062661 -285.740453) (xy 136.046951 -285.791383) (xy 136.023825 -285.839404) (xy 135.993801 -285.883441)
			(xy 135.957549 -285.922512) (xy 135.915878 -285.955743) (xy 135.86972 -285.982392) (xy 135.820106 -286.001864)
			(xy 135.768144 -286.013724) (xy 135.714994 -286.017708) (xy 135.661844 -286.013724) (xy 135.609882 -286.001864)
			(xy 135.560268 -285.982392) (xy 135.51411 -285.955743) (xy 135.472439 -285.922512) (xy 135.436187 -285.883441)
			(xy 135.406163 -285.839404) (xy 135.383037 -285.791383) (xy 135.367327 -285.740453) (xy 135.359384 -285.687749)
			(xy 135.130809 -285.687749) (xy 135.130804 -285.688003) (xy 135.122861 -285.740707) (xy 135.107151 -285.791637)
			(xy 135.084025 -285.839658) (xy 135.054001 -285.883695) (xy 135.017749 -285.922766) (xy 134.976078 -285.955997)
			(xy 134.92992 -285.982646) (xy 134.880306 -286.002118) (xy 134.828344 -286.013978) (xy 134.775194 -286.017962)
			(xy 134.722044 -286.013978) (xy 134.670082 -286.002118) (xy 134.620468 -285.982646) (xy 134.57431 -285.955997)
			(xy 134.532639 -285.922766) (xy 134.496387 -285.883695) (xy 134.466363 -285.839658) (xy 134.443237 -285.791637)
			(xy 134.427527 -285.740707) (xy 134.419584 -285.688003) (xy 134.164168 -285.688003) (xy 134.156613 -285.736761)
			(xy 134.141285 -285.785057) (xy 134.118749 -285.830439) (xy 134.089536 -285.87184) (xy 134.054334 -285.908285)
			(xy 134.013971 -285.938915) (xy 133.969397 -285.963011) (xy 133.921662 -285.980004) (xy 133.896862 -285.985204)
			(xy 133.874002 -285.989522) (xy 133.669024 -286.344614) (xy 133.676898 -286.366458) (xy 133.685549 -286.392865)
			(xy 133.694866 -286.447642) (xy 133.69544 -286.475424) (xy 133.694932 -286.501331) (xy 133.694814 -286.502073)
			(xy 133.949684 -286.502073) (xy 133.949684 -286.448775) (xy 133.957627 -286.396071) (xy 133.973337 -286.345141)
			(xy 133.996463 -286.29712) (xy 134.026487 -286.253083) (xy 134.062739 -286.214012) (xy 134.10441 -286.180781)
			(xy 134.150568 -286.154132) (xy 134.200182 -286.13466) (xy 134.252144 -286.1228) (xy 134.305294 -286.118817)
			(xy 134.358444 -286.1228) (xy 134.410406 -286.13466) (xy 134.46002 -286.154132) (xy 134.506178 -286.180781)
			(xy 134.547849 -286.214012) (xy 134.584101 -286.253083) (xy 134.614125 -286.29712) (xy 134.637251 -286.345141)
			(xy 134.652961 -286.396071) (xy 134.660904 -286.448775) (xy 134.661402 -286.475424) (xy 134.660909 -286.501819)
			(xy 134.889484 -286.501819) (xy 134.889484 -286.448521) (xy 134.897427 -286.395817) (xy 134.913137 -286.344887)
			(xy 134.936263 -286.296866) (xy 134.966287 -286.252829) (xy 135.002539 -286.213758) (xy 135.04421 -286.180527)
			(xy 135.090368 -286.153878) (xy 135.139982 -286.134406) (xy 135.191944 -286.122546) (xy 135.245094 -286.118563)
			(xy 135.298244 -286.122546) (xy 135.350206 -286.134406) (xy 135.39982 -286.153878) (xy 135.445978 -286.180527)
			(xy 135.487649 -286.213758) (xy 135.523901 -286.252829) (xy 135.553925 -286.296866) (xy 135.577051 -286.344887)
			(xy 135.592761 -286.395817) (xy 135.600704 -286.448521) (xy 135.601202 -286.47517) (xy 135.600704 -286.501819)
			(xy 135.829284 -286.501819) (xy 135.829284 -286.448521) (xy 135.837227 -286.395817) (xy 135.852937 -286.344887)
			(xy 135.876063 -286.296866) (xy 135.906087 -286.252829) (xy 135.942339 -286.213758) (xy 135.98401 -286.180527)
			(xy 136.030168 -286.153878) (xy 136.079782 -286.134406) (xy 136.131744 -286.122546) (xy 136.184894 -286.118563)
			(xy 136.238044 -286.122546) (xy 136.290006 -286.134406) (xy 136.33962 -286.153878) (xy 136.385778 -286.180527)
			(xy 136.427449 -286.213758) (xy 136.463701 -286.252829) (xy 136.493725 -286.296866) (xy 136.516851 -286.344887)
			(xy 136.532561 -286.395817) (xy 136.540504 -286.448521) (xy 136.541002 -286.47517) (xy 136.540504 -286.501819)
			(xy 136.769084 -286.501819) (xy 136.769084 -286.448521) (xy 136.777027 -286.395817) (xy 136.792737 -286.344887)
			(xy 136.815863 -286.296866) (xy 136.845887 -286.252829) (xy 136.882139 -286.213758) (xy 136.92381 -286.180527)
			(xy 136.969968 -286.153878) (xy 137.019582 -286.134406) (xy 137.071544 -286.122546) (xy 137.124694 -286.118563)
			(xy 137.177844 -286.122546) (xy 137.229806 -286.134406) (xy 137.27942 -286.153878) (xy 137.325578 -286.180527)
			(xy 137.367249 -286.213758) (xy 137.403501 -286.252829) (xy 137.433525 -286.296866) (xy 137.456651 -286.344887)
			(xy 137.472361 -286.395817) (xy 137.480304 -286.448521) (xy 137.480802 -286.47517) (xy 137.480304 -286.501819)
			(xy 137.708884 -286.501819) (xy 137.708884 -286.448521) (xy 137.716827 -286.395817) (xy 137.732537 -286.344887)
			(xy 137.755663 -286.296866) (xy 137.785687 -286.252829) (xy 137.821939 -286.213758) (xy 137.86361 -286.180527)
			(xy 137.909768 -286.153878) (xy 137.959382 -286.134406) (xy 138.011344 -286.122546) (xy 138.064494 -286.118563)
			(xy 138.117644 -286.122546) (xy 138.169606 -286.134406) (xy 138.21922 -286.153878) (xy 138.265378 -286.180527)
			(xy 138.307049 -286.213758) (xy 138.343301 -286.252829) (xy 138.373325 -286.296866) (xy 138.396451 -286.344887)
			(xy 138.412161 -286.395817) (xy 138.420104 -286.448521) (xy 138.420602 -286.47517) (xy 138.420104 -286.501819)
			(xy 138.412161 -286.554523) (xy 138.396451 -286.605453) (xy 138.373325 -286.653474) (xy 138.343301 -286.697511)
			(xy 138.307049 -286.736582) (xy 138.265378 -286.769813) (xy 138.21922 -286.796462) (xy 138.169606 -286.815934)
			(xy 138.117644 -286.827794) (xy 138.064494 -286.831778) (xy 138.011344 -286.827794) (xy 137.959382 -286.815934)
			(xy 137.909768 -286.796462) (xy 137.86361 -286.769813) (xy 137.821939 -286.736582) (xy 137.785687 -286.697511)
			(xy 137.755663 -286.653474) (xy 137.732537 -286.605453) (xy 137.716827 -286.554523) (xy 137.708884 -286.501819)
			(xy 137.480304 -286.501819) (xy 137.472361 -286.554523) (xy 137.456651 -286.605453) (xy 137.433525 -286.653474)
			(xy 137.403501 -286.697511) (xy 137.367249 -286.736582) (xy 137.325578 -286.769813) (xy 137.27942 -286.796462)
			(xy 137.229806 -286.815934) (xy 137.177844 -286.827794) (xy 137.124694 -286.831778) (xy 137.071544 -286.827794)
			(xy 137.019582 -286.815934) (xy 136.969968 -286.796462) (xy 136.92381 -286.769813) (xy 136.882139 -286.736582)
			(xy 136.845887 -286.697511) (xy 136.815863 -286.653474) (xy 136.792737 -286.605453) (xy 136.777027 -286.554523)
			(xy 136.769084 -286.501819) (xy 136.540504 -286.501819) (xy 136.532561 -286.554523) (xy 136.516851 -286.605453)
			(xy 136.493725 -286.653474) (xy 136.463701 -286.697511) (xy 136.427449 -286.736582) (xy 136.385778 -286.769813)
			(xy 136.33962 -286.796462) (xy 136.290006 -286.815934) (xy 136.238044 -286.827794) (xy 136.184894 -286.831778)
			(xy 136.131744 -286.827794) (xy 136.079782 -286.815934) (xy 136.030168 -286.796462) (xy 135.98401 -286.769813)
			(xy 135.942339 -286.736582) (xy 135.906087 -286.697511) (xy 135.876063 -286.653474) (xy 135.852937 -286.605453)
			(xy 135.837227 -286.554523) (xy 135.829284 -286.501819) (xy 135.600704 -286.501819) (xy 135.592761 -286.554523)
			(xy 135.577051 -286.605453) (xy 135.553925 -286.653474) (xy 135.523901 -286.697511) (xy 135.487649 -286.736582)
			(xy 135.445978 -286.769813) (xy 135.39982 -286.796462) (xy 135.350206 -286.815934) (xy 135.298244 -286.827794)
			(xy 135.245094 -286.831778) (xy 135.191944 -286.827794) (xy 135.139982 -286.815934) (xy 135.090368 -286.796462)
			(xy 135.04421 -286.769813) (xy 135.002539 -286.736582) (xy 134.966287 -286.697511) (xy 134.936263 -286.653474)
			(xy 134.913137 -286.605453) (xy 134.897427 -286.554523) (xy 134.889484 -286.501819) (xy 134.660909 -286.501819)
			(xy 134.660904 -286.502073) (xy 134.652961 -286.554777) (xy 134.637251 -286.605707) (xy 134.614125 -286.653728)
			(xy 134.584101 -286.697765) (xy 134.547849 -286.736836) (xy 134.506178 -286.770067) (xy 134.46002 -286.796716)
			(xy 134.410406 -286.816188) (xy 134.358444 -286.828048) (xy 134.305294 -286.832032) (xy 134.252144 -286.828048)
			(xy 134.200182 -286.816188) (xy 134.150568 -286.796716) (xy 134.10441 -286.770067) (xy 134.062739 -286.736836)
			(xy 134.026487 -286.697765) (xy 133.996463 -286.653728) (xy 133.973337 -286.605707) (xy 133.957627 -286.554777)
			(xy 133.949684 -286.502073) (xy 133.694814 -286.502073) (xy 133.686826 -286.552508) (xy 133.670814 -286.601787)
			(xy 133.647291 -286.647954) (xy 133.616835 -286.689873) (xy 133.580197 -286.726511) (xy 133.538278 -286.756967)
			(xy 133.492111 -286.78049) (xy 133.442832 -286.796502) (xy 133.391655 -286.804608) (xy 133.339841 -286.804608)
			(xy 133.288664 -286.796502) (xy 133.239385 -286.78049) (xy 133.193218 -286.756967) (xy 133.151299 -286.726511)
			(xy 133.114661 -286.689873) (xy 133.084205 -286.647954) (xy 133.060682 -286.601787) (xy 133.04467 -286.552508)
			(xy 133.036564 -286.501331) (xy 133.036056 -286.475424) (xy 132.781802 -286.475424) (xy 132.781304 -286.502073)
			(xy 132.773361 -286.554777) (xy 132.757651 -286.605707) (xy 132.734525 -286.653728) (xy 132.704501 -286.697765)
			(xy 132.668249 -286.736836) (xy 132.626578 -286.770067) (xy 132.58042 -286.796716) (xy 132.530806 -286.816188)
			(xy 132.478844 -286.828048) (xy 132.425694 -286.832032) (xy 132.372544 -286.828048) (xy 132.320582 -286.816188)
			(xy 132.270968 -286.796716) (xy 132.22481 -286.770067) (xy 132.183139 -286.736836) (xy 132.146887 -286.697765)
			(xy 132.116863 -286.653728) (xy 132.093737 -286.605707) (xy 132.078027 -286.554777) (xy 132.070084 -286.502073)
			(xy 131.815214 -286.502073) (xy 131.807226 -286.552508) (xy 131.791214 -286.601787) (xy 131.767691 -286.647954)
			(xy 131.737235 -286.689873) (xy 131.700597 -286.726511) (xy 131.658678 -286.756967) (xy 131.612511 -286.78049)
			(xy 131.563232 -286.796502) (xy 131.512055 -286.804608) (xy 131.460241 -286.804608) (xy 131.409064 -286.796502)
			(xy 131.359785 -286.78049) (xy 131.313618 -286.756967) (xy 131.271699 -286.726511) (xy 131.235061 -286.689873)
			(xy 131.204605 -286.647954) (xy 131.181082 -286.601787) (xy 131.16507 -286.552508) (xy 131.156964 -286.501331)
			(xy 131.156456 -286.475424) (xy 130.902202 -286.475424) (xy 130.901704 -286.502073) (xy 130.893761 -286.554777)
			(xy 130.878051 -286.605707) (xy 130.854925 -286.653728) (xy 130.824901 -286.697765) (xy 130.788649 -286.736836)
			(xy 130.746978 -286.770067) (xy 130.70082 -286.796716) (xy 130.651206 -286.816188) (xy 130.599244 -286.828048)
			(xy 130.546094 -286.832032) (xy 130.492944 -286.828048) (xy 130.440982 -286.816188) (xy 130.391368 -286.796716)
			(xy 130.34521 -286.770067) (xy 130.303539 -286.736836) (xy 130.267287 -286.697765) (xy 130.237263 -286.653728)
			(xy 130.214137 -286.605707) (xy 130.198427 -286.554777) (xy 130.190484 -286.502073) (xy 129.935614 -286.502073)
			(xy 129.927626 -286.552508) (xy 129.911614 -286.601787) (xy 129.888091 -286.647954) (xy 129.857635 -286.689873)
			(xy 129.820997 -286.726511) (xy 129.779078 -286.756967) (xy 129.732911 -286.78049) (xy 129.683632 -286.796502)
			(xy 129.632455 -286.804608) (xy 129.580641 -286.804608) (xy 129.529464 -286.796502) (xy 129.480185 -286.78049)
			(xy 129.434018 -286.756967) (xy 129.392099 -286.726511) (xy 129.355461 -286.689873) (xy 129.325005 -286.647954)
			(xy 129.301482 -286.601787) (xy 129.28547 -286.552508) (xy 129.277364 -286.501331) (xy 129.276856 -286.475424)
			(xy 129.022602 -286.475424) (xy 129.022104 -286.502073) (xy 129.014161 -286.554777) (xy 128.998451 -286.605707)
			(xy 128.975325 -286.653728) (xy 128.945301 -286.697765) (xy 128.909049 -286.736836) (xy 128.867378 -286.770067)
			(xy 128.82122 -286.796716) (xy 128.771606 -286.816188) (xy 128.719644 -286.828048) (xy 128.666494 -286.832032)
			(xy 128.613344 -286.828048) (xy 128.561382 -286.816188) (xy 128.511768 -286.796716) (xy 128.46561 -286.770067)
			(xy 128.423939 -286.736836) (xy 128.387687 -286.697765) (xy 128.357663 -286.653728) (xy 128.334537 -286.605707)
			(xy 128.318827 -286.554777) (xy 128.310884 -286.502073) (xy 128.056014 -286.502073) (xy 128.048026 -286.552508)
			(xy 128.032014 -286.601787) (xy 128.008491 -286.647954) (xy 127.978035 -286.689873) (xy 127.941397 -286.726511)
			(xy 127.899478 -286.756967) (xy 127.853311 -286.78049) (xy 127.804032 -286.796502) (xy 127.752855 -286.804608)
			(xy 127.701041 -286.804608) (xy 127.649864 -286.796502) (xy 127.600585 -286.78049) (xy 127.554418 -286.756967)
			(xy 127.512499 -286.726511) (xy 127.475861 -286.689873) (xy 127.445405 -286.647954) (xy 127.421882 -286.601787)
			(xy 127.40587 -286.552508) (xy 127.397764 -286.501331) (xy 127.397256 -286.475424) (xy 127.143002 -286.475424)
			(xy 127.142504 -286.502073) (xy 127.134561 -286.554777) (xy 127.118851 -286.605707) (xy 127.095725 -286.653728)
			(xy 127.065701 -286.697765) (xy 127.029449 -286.736836) (xy 126.987778 -286.770067) (xy 126.94162 -286.796716)
			(xy 126.892006 -286.816188) (xy 126.840044 -286.828048) (xy 126.786894 -286.832032) (xy 126.733744 -286.828048)
			(xy 126.681782 -286.816188) (xy 126.632168 -286.796716) (xy 126.58601 -286.770067) (xy 126.544339 -286.736836)
			(xy 126.508087 -286.697765) (xy 126.478063 -286.653728) (xy 126.454937 -286.605707) (xy 126.439227 -286.554777)
			(xy 126.431284 -286.502073) (xy 126.176414 -286.502073) (xy 126.168426 -286.552508) (xy 126.152414 -286.601787)
			(xy 126.128891 -286.647954) (xy 126.098435 -286.689873) (xy 126.061797 -286.726511) (xy 126.019878 -286.756967)
			(xy 125.973711 -286.78049) (xy 125.924432 -286.796502) (xy 125.873255 -286.804608) (xy 125.821441 -286.804608)
			(xy 125.770264 -286.796502) (xy 125.720985 -286.78049) (xy 125.674818 -286.756967) (xy 125.632899 -286.726511)
			(xy 125.596261 -286.689873) (xy 125.565805 -286.647954) (xy 125.542282 -286.601787) (xy 125.52627 -286.552508)
			(xy 125.518164 -286.501331) (xy 125.517656 -286.475424) (xy 125.263402 -286.475424) (xy 125.262904 -286.502073)
			(xy 125.254961 -286.554777) (xy 125.239251 -286.605707) (xy 125.216125 -286.653728) (xy 125.186101 -286.697765)
			(xy 125.149849 -286.736836) (xy 125.108178 -286.770067) (xy 125.06202 -286.796716) (xy 125.012406 -286.816188)
			(xy 124.960444 -286.828048) (xy 124.907294 -286.832032) (xy 124.854144 -286.828048) (xy 124.802182 -286.816188)
			(xy 124.752568 -286.796716) (xy 124.70641 -286.770067) (xy 124.664739 -286.736836) (xy 124.628487 -286.697765)
			(xy 124.598463 -286.653728) (xy 124.575337 -286.605707) (xy 124.559627 -286.554777) (xy 124.551684 -286.502073)
			(xy 124.296814 -286.502073) (xy 124.288826 -286.552508) (xy 124.272814 -286.601787) (xy 124.249291 -286.647954)
			(xy 124.218835 -286.689873) (xy 124.182197 -286.726511) (xy 124.140278 -286.756967) (xy 124.094111 -286.78049)
			(xy 124.044832 -286.796502) (xy 123.993655 -286.804608) (xy 123.941841 -286.804608) (xy 123.890664 -286.796502)
			(xy 123.841385 -286.78049) (xy 123.795218 -286.756967) (xy 123.753299 -286.726511) (xy 123.716661 -286.689873)
			(xy 123.686205 -286.647954) (xy 123.662682 -286.601787) (xy 123.64667 -286.552508) (xy 123.638564 -286.501331)
			(xy 123.638056 -286.475424) (xy 123.383802 -286.475424) (xy 123.383304 -286.502073) (xy 123.375361 -286.554777)
			(xy 123.359651 -286.605707) (xy 123.336525 -286.653728) (xy 123.306501 -286.697765) (xy 123.270249 -286.736836)
			(xy 123.228578 -286.770067) (xy 123.18242 -286.796716) (xy 123.132806 -286.816188) (xy 123.080844 -286.828048)
			(xy 123.027694 -286.832032) (xy 122.974544 -286.828048) (xy 122.922582 -286.816188) (xy 122.872968 -286.796716)
			(xy 122.82681 -286.770067) (xy 122.785139 -286.736836) (xy 122.748887 -286.697765) (xy 122.718863 -286.653728)
			(xy 122.695737 -286.605707) (xy 122.680027 -286.554777) (xy 122.672084 -286.502073) (xy 122.417214 -286.502073)
			(xy 122.409226 -286.552508) (xy 122.393214 -286.601787) (xy 122.369691 -286.647954) (xy 122.339235 -286.689873)
			(xy 122.302597 -286.726511) (xy 122.260678 -286.756967) (xy 122.214511 -286.78049) (xy 122.165232 -286.796502)
			(xy 122.114055 -286.804608) (xy 122.062241 -286.804608) (xy 122.011064 -286.796502) (xy 121.961785 -286.78049)
			(xy 121.915618 -286.756967) (xy 121.873699 -286.726511) (xy 121.837061 -286.689873) (xy 121.806605 -286.647954)
			(xy 121.783082 -286.601787) (xy 121.76707 -286.552508) (xy 121.758964 -286.501331) (xy 121.758456 -286.475424)
			(xy 121.504202 -286.475424) (xy 121.503704 -286.502073) (xy 121.495761 -286.554777) (xy 121.480051 -286.605707)
			(xy 121.456925 -286.653728) (xy 121.426901 -286.697765) (xy 121.390649 -286.736836) (xy 121.348978 -286.770067)
			(xy 121.30282 -286.796716) (xy 121.253206 -286.816188) (xy 121.201244 -286.828048) (xy 121.148094 -286.832032)
			(xy 121.094944 -286.828048) (xy 121.042982 -286.816188) (xy 120.993368 -286.796716) (xy 120.94721 -286.770067)
			(xy 120.905539 -286.736836) (xy 120.869287 -286.697765) (xy 120.839263 -286.653728) (xy 120.816137 -286.605707)
			(xy 120.800427 -286.554777) (xy 120.792484 -286.502073) (xy 120.537614 -286.502073) (xy 120.529626 -286.552508)
			(xy 120.513614 -286.601787) (xy 120.490091 -286.647954) (xy 120.459635 -286.689873) (xy 120.422997 -286.726511)
			(xy 120.381078 -286.756967) (xy 120.334911 -286.78049) (xy 120.285632 -286.796502) (xy 120.234455 -286.804608)
			(xy 120.182641 -286.804608) (xy 120.131464 -286.796502) (xy 120.082185 -286.78049) (xy 120.036018 -286.756967)
			(xy 119.994099 -286.726511) (xy 119.957461 -286.689873) (xy 119.927005 -286.647954) (xy 119.903482 -286.601787)
			(xy 119.88747 -286.552508) (xy 119.879364 -286.501331) (xy 119.878856 -286.475424) (xy 119.624856 -286.475424)
			(xy 119.624358 -286.502073) (xy 119.616415 -286.554777) (xy 119.600705 -286.605707) (xy 119.577579 -286.653728)
			(xy 119.547555 -286.697765) (xy 119.511303 -286.736836) (xy 119.469632 -286.770067) (xy 119.423474 -286.796716)
			(xy 119.37386 -286.816188) (xy 119.321898 -286.828048) (xy 119.268748 -286.832032) (xy 119.215598 -286.828048)
			(xy 119.163636 -286.816188) (xy 119.114022 -286.796716) (xy 119.067864 -286.770067) (xy 119.026193 -286.736836)
			(xy 118.989941 -286.697765) (xy 118.959917 -286.653728) (xy 118.936791 -286.605707) (xy 118.921081 -286.554777)
			(xy 118.913138 -286.502073) (xy 116.804958 -286.502073) (xy 116.797015 -286.554777) (xy 116.781305 -286.605707)
			(xy 116.758179 -286.653728) (xy 116.728155 -286.697765) (xy 116.691903 -286.736836) (xy 116.650232 -286.770067)
			(xy 116.604074 -286.796716) (xy 116.55446 -286.816188) (xy 116.502498 -286.828048) (xy 116.449348 -286.832032)
			(xy 116.396198 -286.828048) (xy 116.344236 -286.816188) (xy 116.294622 -286.796716) (xy 116.248464 -286.770067)
			(xy 116.206793 -286.736836) (xy 116.170541 -286.697765) (xy 116.140517 -286.653728) (xy 116.117391 -286.605707)
			(xy 116.101681 -286.554777) (xy 116.093738 -286.502073) (xy 113.985304 -286.502073) (xy 113.977361 -286.554777)
			(xy 113.961651 -286.605707) (xy 113.938525 -286.653728) (xy 113.908501 -286.697765) (xy 113.872249 -286.736836)
			(xy 113.830578 -286.770067) (xy 113.78442 -286.796716) (xy 113.734806 -286.816188) (xy 113.682844 -286.828048)
			(xy 113.629694 -286.832032) (xy 113.576544 -286.828048) (xy 113.524582 -286.816188) (xy 113.474968 -286.796716)
			(xy 113.42881 -286.770067) (xy 113.387139 -286.736836) (xy 113.350887 -286.697765) (xy 113.320863 -286.653728)
			(xy 113.297737 -286.605707) (xy 113.282027 -286.554777) (xy 113.274084 -286.502073) (xy 105.807256 -286.502073)
			(xy 105.807256 -286.975042) (xy 105.829354 -287.016952) (xy 105.850943 -287.032478) (xy 105.889331 -287.069273)
			(xy 105.921335 -287.111737) (xy 105.946131 -287.158775) (xy 105.96308 -287.209176) (xy 105.971745 -287.261639)
			(xy 105.972356 -287.288224) (xy 105.986946 -287.315889) (xy 107.165384 -287.315889) (xy 107.165384 -287.262591)
			(xy 107.173327 -287.209887) (xy 107.189037 -287.158957) (xy 107.212163 -287.110936) (xy 107.242187 -287.066899)
			(xy 107.278439 -287.027828) (xy 107.32011 -286.994597) (xy 107.366268 -286.967948) (xy 107.415882 -286.948476)
			(xy 107.467844 -286.936616) (xy 107.520994 -286.932633) (xy 107.574144 -286.936616) (xy 107.626106 -286.948476)
			(xy 107.67572 -286.967948) (xy 107.721878 -286.994597) (xy 107.763549 -287.027828) (xy 107.799801 -287.066899)
			(xy 107.829825 -287.110936) (xy 107.852951 -287.158957) (xy 107.868661 -287.209887) (xy 107.876604 -287.262591)
			(xy 107.877102 -287.28924) (xy 107.876604 -287.315889) (xy 109.984784 -287.315889) (xy 109.984784 -287.262591)
			(xy 109.992727 -287.209887) (xy 110.008437 -287.158957) (xy 110.031563 -287.110936) (xy 110.061587 -287.066899)
			(xy 110.097839 -287.027828) (xy 110.13951 -286.994597) (xy 110.185668 -286.967948) (xy 110.235282 -286.948476)
			(xy 110.287244 -286.936616) (xy 110.340394 -286.932633) (xy 110.393544 -286.936616) (xy 110.445506 -286.948476)
			(xy 110.49512 -286.967948) (xy 110.541278 -286.994597) (xy 110.582949 -287.027828) (xy 110.619201 -287.066899)
			(xy 110.649225 -287.110936) (xy 110.672351 -287.158957) (xy 110.688061 -287.209887) (xy 110.696004 -287.262591)
			(xy 110.696502 -287.28924) (xy 110.696004 -287.315889) (xy 119.383038 -287.315889) (xy 119.383038 -287.262591)
			(xy 119.390981 -287.209887) (xy 119.406691 -287.158957) (xy 119.429817 -287.110936) (xy 119.459841 -287.066899)
			(xy 119.496093 -287.027828) (xy 119.537764 -286.994597) (xy 119.583922 -286.967948) (xy 119.633536 -286.948476)
			(xy 119.685498 -286.936616) (xy 119.738648 -286.932633) (xy 119.791798 -286.936616) (xy 119.84376 -286.948476)
			(xy 119.893374 -286.967948) (xy 119.939532 -286.994597) (xy 119.981203 -287.027828) (xy 120.017455 -287.066899)
			(xy 120.047479 -287.110936) (xy 120.070605 -287.158957) (xy 120.086315 -287.209887) (xy 120.094258 -287.262591)
			(xy 120.094756 -287.28924) (xy 120.094258 -287.315889) (xy 120.322584 -287.315889) (xy 120.322584 -287.262591)
			(xy 120.330527 -287.209887) (xy 120.346237 -287.158957) (xy 120.369363 -287.110936) (xy 120.399387 -287.066899)
			(xy 120.435639 -287.027828) (xy 120.47731 -286.994597) (xy 120.523468 -286.967948) (xy 120.573082 -286.948476)
			(xy 120.625044 -286.936616) (xy 120.678194 -286.932633) (xy 120.731344 -286.936616) (xy 120.783306 -286.948476)
			(xy 120.83292 -286.967948) (xy 120.879078 -286.994597) (xy 120.920749 -287.027828) (xy 120.957001 -287.066899)
			(xy 120.987025 -287.110936) (xy 121.010151 -287.158957) (xy 121.025861 -287.209887) (xy 121.033804 -287.262591)
			(xy 121.034302 -287.28924) (xy 121.033804 -287.315889) (xy 121.262384 -287.315889) (xy 121.262384 -287.262591)
			(xy 121.270327 -287.209887) (xy 121.286037 -287.158957) (xy 121.309163 -287.110936) (xy 121.339187 -287.066899)
			(xy 121.375439 -287.027828) (xy 121.41711 -286.994597) (xy 121.463268 -286.967948) (xy 121.512882 -286.948476)
			(xy 121.564844 -286.936616) (xy 121.617994 -286.932633) (xy 121.671144 -286.936616) (xy 121.723106 -286.948476)
			(xy 121.77272 -286.967948) (xy 121.818878 -286.994597) (xy 121.860549 -287.027828) (xy 121.896801 -287.066899)
			(xy 121.926825 -287.110936) (xy 121.949951 -287.158957) (xy 121.965661 -287.209887) (xy 121.973604 -287.262591)
			(xy 121.974102 -287.28924) (xy 121.973604 -287.315889) (xy 122.202184 -287.315889) (xy 122.202184 -287.262591)
			(xy 122.210127 -287.209887) (xy 122.225837 -287.158957) (xy 122.248963 -287.110936) (xy 122.278987 -287.066899)
			(xy 122.315239 -287.027828) (xy 122.35691 -286.994597) (xy 122.403068 -286.967948) (xy 122.452682 -286.948476)
			(xy 122.504644 -286.936616) (xy 122.557794 -286.932633) (xy 122.610944 -286.936616) (xy 122.662906 -286.948476)
			(xy 122.71252 -286.967948) (xy 122.758678 -286.994597) (xy 122.800349 -287.027828) (xy 122.836601 -287.066899)
			(xy 122.866625 -287.110936) (xy 122.889751 -287.158957) (xy 122.905461 -287.209887) (xy 122.913404 -287.262591)
			(xy 122.913902 -287.28924) (xy 122.913404 -287.315889) (xy 123.141984 -287.315889) (xy 123.141984 -287.262591)
			(xy 123.149927 -287.209887) (xy 123.165637 -287.158957) (xy 123.188763 -287.110936) (xy 123.218787 -287.066899)
			(xy 123.255039 -287.027828) (xy 123.29671 -286.994597) (xy 123.342868 -286.967948) (xy 123.392482 -286.948476)
			(xy 123.444444 -286.936616) (xy 123.497594 -286.932633) (xy 123.550744 -286.936616) (xy 123.602706 -286.948476)
			(xy 123.65232 -286.967948) (xy 123.698478 -286.994597) (xy 123.740149 -287.027828) (xy 123.776401 -287.066899)
			(xy 123.806425 -287.110936) (xy 123.829551 -287.158957) (xy 123.845261 -287.209887) (xy 123.853204 -287.262591)
			(xy 123.853702 -287.28924) (xy 123.853204 -287.315889) (xy 124.081784 -287.315889) (xy 124.081784 -287.262591)
			(xy 124.089727 -287.209887) (xy 124.105437 -287.158957) (xy 124.128563 -287.110936) (xy 124.158587 -287.066899)
			(xy 124.194839 -287.027828) (xy 124.23651 -286.994597) (xy 124.282668 -286.967948) (xy 124.332282 -286.948476)
			(xy 124.384244 -286.936616) (xy 124.437394 -286.932633) (xy 124.490544 -286.936616) (xy 124.542506 -286.948476)
			(xy 124.59212 -286.967948) (xy 124.638278 -286.994597) (xy 124.679949 -287.027828) (xy 124.716201 -287.066899)
			(xy 124.746225 -287.110936) (xy 124.769351 -287.158957) (xy 124.785061 -287.209887) (xy 124.793004 -287.262591)
			(xy 124.793502 -287.28924) (xy 124.793004 -287.315889) (xy 125.021584 -287.315889) (xy 125.021584 -287.262591)
			(xy 125.029527 -287.209887) (xy 125.045237 -287.158957) (xy 125.068363 -287.110936) (xy 125.098387 -287.066899)
			(xy 125.134639 -287.027828) (xy 125.17631 -286.994597) (xy 125.222468 -286.967948) (xy 125.272082 -286.948476)
			(xy 125.324044 -286.936616) (xy 125.377194 -286.932633) (xy 125.430344 -286.936616) (xy 125.482306 -286.948476)
			(xy 125.53192 -286.967948) (xy 125.578078 -286.994597) (xy 125.619749 -287.027828) (xy 125.656001 -287.066899)
			(xy 125.686025 -287.110936) (xy 125.709151 -287.158957) (xy 125.724861 -287.209887) (xy 125.732804 -287.262591)
			(xy 125.733302 -287.28924) (xy 125.732804 -287.315889) (xy 125.961384 -287.315889) (xy 125.961384 -287.262591)
			(xy 125.969327 -287.209887) (xy 125.985037 -287.158957) (xy 126.008163 -287.110936) (xy 126.038187 -287.066899)
			(xy 126.074439 -287.027828) (xy 126.11611 -286.994597) (xy 126.162268 -286.967948) (xy 126.211882 -286.948476)
			(xy 126.263844 -286.936616) (xy 126.316994 -286.932633) (xy 126.370144 -286.936616) (xy 126.422106 -286.948476)
			(xy 126.47172 -286.967948) (xy 126.517878 -286.994597) (xy 126.559549 -287.027828) (xy 126.595801 -287.066899)
			(xy 126.625825 -287.110936) (xy 126.648951 -287.158957) (xy 126.664661 -287.209887) (xy 126.672604 -287.262591)
			(xy 126.673102 -287.28924) (xy 126.672604 -287.315889) (xy 126.901184 -287.315889) (xy 126.901184 -287.262591)
			(xy 126.909127 -287.209887) (xy 126.924837 -287.158957) (xy 126.947963 -287.110936) (xy 126.977987 -287.066899)
			(xy 127.014239 -287.027828) (xy 127.05591 -286.994597) (xy 127.102068 -286.967948) (xy 127.151682 -286.948476)
			(xy 127.203644 -286.936616) (xy 127.256794 -286.932633) (xy 127.309944 -286.936616) (xy 127.361906 -286.948476)
			(xy 127.41152 -286.967948) (xy 127.457678 -286.994597) (xy 127.499349 -287.027828) (xy 127.535601 -287.066899)
			(xy 127.565625 -287.110936) (xy 127.588751 -287.158957) (xy 127.604461 -287.209887) (xy 127.612404 -287.262591)
			(xy 127.612902 -287.28924) (xy 127.612404 -287.315889) (xy 127.840984 -287.315889) (xy 127.840984 -287.262591)
			(xy 127.848927 -287.209887) (xy 127.864637 -287.158957) (xy 127.887763 -287.110936) (xy 127.917787 -287.066899)
			(xy 127.954039 -287.027828) (xy 127.99571 -286.994597) (xy 128.041868 -286.967948) (xy 128.091482 -286.948476)
			(xy 128.143444 -286.936616) (xy 128.196594 -286.932633) (xy 128.249744 -286.936616) (xy 128.301706 -286.948476)
			(xy 128.35132 -286.967948) (xy 128.397478 -286.994597) (xy 128.439149 -287.027828) (xy 128.475401 -287.066899)
			(xy 128.505425 -287.110936) (xy 128.528551 -287.158957) (xy 128.544261 -287.209887) (xy 128.552204 -287.262591)
			(xy 128.552702 -287.28924) (xy 128.552204 -287.315889) (xy 128.780784 -287.315889) (xy 128.780784 -287.262591)
			(xy 128.788727 -287.209887) (xy 128.804437 -287.158957) (xy 128.827563 -287.110936) (xy 128.857587 -287.066899)
			(xy 128.893839 -287.027828) (xy 128.93551 -286.994597) (xy 128.981668 -286.967948) (xy 129.031282 -286.948476)
			(xy 129.083244 -286.936616) (xy 129.136394 -286.932633) (xy 129.189544 -286.936616) (xy 129.241506 -286.948476)
			(xy 129.29112 -286.967948) (xy 129.337278 -286.994597) (xy 129.378949 -287.027828) (xy 129.415201 -287.066899)
			(xy 129.445225 -287.110936) (xy 129.468351 -287.158957) (xy 129.484061 -287.209887) (xy 129.492004 -287.262591)
			(xy 129.492502 -287.28924) (xy 129.492004 -287.315889) (xy 129.720584 -287.315889) (xy 129.720584 -287.262591)
			(xy 129.728527 -287.209887) (xy 129.744237 -287.158957) (xy 129.767363 -287.110936) (xy 129.797387 -287.066899)
			(xy 129.833639 -287.027828) (xy 129.87531 -286.994597) (xy 129.921468 -286.967948) (xy 129.971082 -286.948476)
			(xy 130.023044 -286.936616) (xy 130.076194 -286.932633) (xy 130.129344 -286.936616) (xy 130.181306 -286.948476)
			(xy 130.23092 -286.967948) (xy 130.277078 -286.994597) (xy 130.318749 -287.027828) (xy 130.355001 -287.066899)
			(xy 130.385025 -287.110936) (xy 130.408151 -287.158957) (xy 130.423861 -287.209887) (xy 130.431804 -287.262591)
			(xy 130.432302 -287.28924) (xy 130.431804 -287.315889) (xy 130.660384 -287.315889) (xy 130.660384 -287.262591)
			(xy 130.668327 -287.209887) (xy 130.684037 -287.158957) (xy 130.707163 -287.110936) (xy 130.737187 -287.066899)
			(xy 130.773439 -287.027828) (xy 130.81511 -286.994597) (xy 130.861268 -286.967948) (xy 130.910882 -286.948476)
			(xy 130.962844 -286.936616) (xy 131.015994 -286.932633) (xy 131.069144 -286.936616) (xy 131.121106 -286.948476)
			(xy 131.17072 -286.967948) (xy 131.216878 -286.994597) (xy 131.258549 -287.027828) (xy 131.294801 -287.066899)
			(xy 131.324825 -287.110936) (xy 131.347951 -287.158957) (xy 131.363661 -287.209887) (xy 131.371604 -287.262591)
			(xy 131.372102 -287.28924) (xy 131.371604 -287.315889) (xy 131.600184 -287.315889) (xy 131.600184 -287.262591)
			(xy 131.608127 -287.209887) (xy 131.623837 -287.158957) (xy 131.646963 -287.110936) (xy 131.676987 -287.066899)
			(xy 131.713239 -287.027828) (xy 131.75491 -286.994597) (xy 131.801068 -286.967948) (xy 131.850682 -286.948476)
			(xy 131.902644 -286.936616) (xy 131.955794 -286.932633) (xy 132.008944 -286.936616) (xy 132.060906 -286.948476)
			(xy 132.11052 -286.967948) (xy 132.156678 -286.994597) (xy 132.198349 -287.027828) (xy 132.234601 -287.066899)
			(xy 132.264625 -287.110936) (xy 132.287751 -287.158957) (xy 132.303461 -287.209887) (xy 132.311404 -287.262591)
			(xy 132.311902 -287.28924) (xy 132.311404 -287.315889) (xy 132.539984 -287.315889) (xy 132.539984 -287.262591)
			(xy 132.547927 -287.209887) (xy 132.563637 -287.158957) (xy 132.586763 -287.110936) (xy 132.616787 -287.066899)
			(xy 132.653039 -287.027828) (xy 132.69471 -286.994597) (xy 132.740868 -286.967948) (xy 132.790482 -286.948476)
			(xy 132.842444 -286.936616) (xy 132.895594 -286.932633) (xy 132.948744 -286.936616) (xy 133.000706 -286.948476)
			(xy 133.05032 -286.967948) (xy 133.096478 -286.994597) (xy 133.138149 -287.027828) (xy 133.174401 -287.066899)
			(xy 133.204425 -287.110936) (xy 133.227551 -287.158957) (xy 133.243261 -287.209887) (xy 133.251204 -287.262591)
			(xy 133.251702 -287.28924) (xy 133.251204 -287.315889) (xy 133.480038 -287.315889) (xy 133.480038 -287.262591)
			(xy 133.487981 -287.209887) (xy 133.503691 -287.158957) (xy 133.526817 -287.110936) (xy 133.556841 -287.066899)
			(xy 133.593093 -287.027828) (xy 133.634764 -286.994597) (xy 133.680922 -286.967948) (xy 133.730536 -286.948476)
			(xy 133.782498 -286.936616) (xy 133.835648 -286.932633) (xy 133.888798 -286.936616) (xy 133.94076 -286.948476)
			(xy 133.990374 -286.967948) (xy 134.036532 -286.994597) (xy 134.078203 -287.027828) (xy 134.114455 -287.066899)
			(xy 134.144479 -287.110936) (xy 134.167605 -287.158957) (xy 134.183315 -287.209887) (xy 134.191258 -287.262591)
			(xy 134.191756 -287.28924) (xy 134.191258 -287.315889) (xy 134.419838 -287.315889) (xy 134.419838 -287.262591)
			(xy 134.427781 -287.209887) (xy 134.443491 -287.158957) (xy 134.466617 -287.110936) (xy 134.496641 -287.066899)
			(xy 134.532893 -287.027828) (xy 134.574564 -286.994597) (xy 134.620722 -286.967948) (xy 134.670336 -286.948476)
			(xy 134.722298 -286.936616) (xy 134.775448 -286.932633) (xy 134.828598 -286.936616) (xy 134.88056 -286.948476)
			(xy 134.930174 -286.967948) (xy 134.976332 -286.994597) (xy 135.018003 -287.027828) (xy 135.054255 -287.066899)
			(xy 135.084279 -287.110936) (xy 135.107405 -287.158957) (xy 135.123115 -287.209887) (xy 135.131058 -287.262591)
			(xy 135.131556 -287.28924) (xy 135.131058 -287.315889) (xy 135.359384 -287.315889) (xy 135.359384 -287.262591)
			(xy 135.367327 -287.209887) (xy 135.383037 -287.158957) (xy 135.406163 -287.110936) (xy 135.436187 -287.066899)
			(xy 135.472439 -287.027828) (xy 135.51411 -286.994597) (xy 135.560268 -286.967948) (xy 135.609882 -286.948476)
			(xy 135.661844 -286.936616) (xy 135.714994 -286.932633) (xy 135.768144 -286.936616) (xy 135.820106 -286.948476)
			(xy 135.86972 -286.967948) (xy 135.915878 -286.994597) (xy 135.957549 -287.027828) (xy 135.993801 -287.066899)
			(xy 136.023825 -287.110936) (xy 136.046951 -287.158957) (xy 136.062661 -287.209887) (xy 136.070604 -287.262591)
			(xy 136.071102 -287.28924) (xy 136.070609 -287.315635) (xy 136.299438 -287.315635) (xy 136.299438 -287.262337)
			(xy 136.307381 -287.209633) (xy 136.323091 -287.158703) (xy 136.346217 -287.110682) (xy 136.376241 -287.066645)
			(xy 136.412493 -287.027574) (xy 136.454164 -286.994343) (xy 136.500322 -286.967694) (xy 136.549936 -286.948222)
			(xy 136.601898 -286.936362) (xy 136.655048 -286.932379) (xy 136.708198 -286.936362) (xy 136.76016 -286.948222)
			(xy 136.809774 -286.967694) (xy 136.855932 -286.994343) (xy 136.897603 -287.027574) (xy 136.933855 -287.066645)
			(xy 136.963879 -287.110682) (xy 136.987005 -287.158703) (xy 137.002715 -287.209633) (xy 137.010658 -287.262337)
			(xy 137.011156 -287.288986) (xy 137.010658 -287.315635) (xy 137.01062 -287.315889) (xy 137.238984 -287.315889)
			(xy 137.238984 -287.262591) (xy 137.246927 -287.209887) (xy 137.262637 -287.158957) (xy 137.285763 -287.110936)
			(xy 137.315787 -287.066899) (xy 137.352039 -287.027828) (xy 137.39371 -286.994597) (xy 137.439868 -286.967948)
			(xy 137.489482 -286.948476) (xy 137.541444 -286.936616) (xy 137.594594 -286.932633) (xy 137.647744 -286.936616)
			(xy 137.699706 -286.948476) (xy 137.74932 -286.967948) (xy 137.795478 -286.994597) (xy 137.837149 -287.027828)
			(xy 137.873401 -287.066899) (xy 137.903425 -287.110936) (xy 137.926551 -287.158957) (xy 137.942261 -287.209887)
			(xy 137.950204 -287.262591) (xy 137.950702 -287.28924) (xy 137.950204 -287.315889) (xy 137.942261 -287.368593)
			(xy 137.926551 -287.419523) (xy 137.903425 -287.467544) (xy 137.873401 -287.511581) (xy 137.837149 -287.550652)
			(xy 137.795478 -287.583883) (xy 137.74932 -287.610532) (xy 137.699706 -287.630004) (xy 137.647744 -287.641864)
			(xy 137.594594 -287.645848) (xy 137.541444 -287.641864) (xy 137.489482 -287.630004) (xy 137.439868 -287.610532)
			(xy 137.39371 -287.583883) (xy 137.352039 -287.550652) (xy 137.315787 -287.511581) (xy 137.285763 -287.467544)
			(xy 137.262637 -287.419523) (xy 137.246927 -287.368593) (xy 137.238984 -287.315889) (xy 137.01062 -287.315889)
			(xy 137.002715 -287.368339) (xy 136.987005 -287.419269) (xy 136.963879 -287.46729) (xy 136.933855 -287.511327)
			(xy 136.897603 -287.550398) (xy 136.855932 -287.583629) (xy 136.809774 -287.610278) (xy 136.76016 -287.62975)
			(xy 136.708198 -287.64161) (xy 136.655048 -287.645594) (xy 136.601898 -287.64161) (xy 136.549936 -287.62975)
			(xy 136.500322 -287.610278) (xy 136.454164 -287.583629) (xy 136.412493 -287.550398) (xy 136.376241 -287.511327)
			(xy 136.346217 -287.46729) (xy 136.323091 -287.419269) (xy 136.307381 -287.368339) (xy 136.299438 -287.315635)
			(xy 136.070609 -287.315635) (xy 136.070604 -287.315889) (xy 136.062661 -287.368593) (xy 136.046951 -287.419523)
			(xy 136.023825 -287.467544) (xy 135.993801 -287.511581) (xy 135.957549 -287.550652) (xy 135.915878 -287.583883)
			(xy 135.86972 -287.610532) (xy 135.820106 -287.630004) (xy 135.768144 -287.641864) (xy 135.714994 -287.645848)
			(xy 135.661844 -287.641864) (xy 135.609882 -287.630004) (xy 135.560268 -287.610532) (xy 135.51411 -287.583883)
			(xy 135.472439 -287.550652) (xy 135.436187 -287.511581) (xy 135.406163 -287.467544) (xy 135.383037 -287.419523)
			(xy 135.367327 -287.368593) (xy 135.359384 -287.315889) (xy 135.131058 -287.315889) (xy 135.123115 -287.368593)
			(xy 135.107405 -287.419523) (xy 135.084279 -287.467544) (xy 135.054255 -287.511581) (xy 135.018003 -287.550652)
			(xy 134.976332 -287.583883) (xy 134.930174 -287.610532) (xy 134.88056 -287.630004) (xy 134.828598 -287.641864)
			(xy 134.775448 -287.645848) (xy 134.722298 -287.641864) (xy 134.670336 -287.630004) (xy 134.620722 -287.610532)
			(xy 134.574564 -287.583883) (xy 134.532893 -287.550652) (xy 134.496641 -287.511581) (xy 134.466617 -287.467544)
			(xy 134.443491 -287.419523) (xy 134.427781 -287.368593) (xy 134.419838 -287.315889) (xy 134.191258 -287.315889)
			(xy 134.183315 -287.368593) (xy 134.167605 -287.419523) (xy 134.144479 -287.467544) (xy 134.114455 -287.511581)
			(xy 134.078203 -287.550652) (xy 134.036532 -287.583883) (xy 133.990374 -287.610532) (xy 133.94076 -287.630004)
			(xy 133.888798 -287.641864) (xy 133.835648 -287.645848) (xy 133.782498 -287.641864) (xy 133.730536 -287.630004)
			(xy 133.680922 -287.610532) (xy 133.634764 -287.583883) (xy 133.593093 -287.550652) (xy 133.556841 -287.511581)
			(xy 133.526817 -287.467544) (xy 133.503691 -287.419523) (xy 133.487981 -287.368593) (xy 133.480038 -287.315889)
			(xy 133.251204 -287.315889) (xy 133.243261 -287.368593) (xy 133.227551 -287.419523) (xy 133.204425 -287.467544)
			(xy 133.174401 -287.511581) (xy 133.138149 -287.550652) (xy 133.096478 -287.583883) (xy 133.05032 -287.610532)
			(xy 133.000706 -287.630004) (xy 132.948744 -287.641864) (xy 132.895594 -287.645848) (xy 132.842444 -287.641864)
			(xy 132.790482 -287.630004) (xy 132.740868 -287.610532) (xy 132.69471 -287.583883) (xy 132.653039 -287.550652)
			(xy 132.616787 -287.511581) (xy 132.586763 -287.467544) (xy 132.563637 -287.419523) (xy 132.547927 -287.368593)
			(xy 132.539984 -287.315889) (xy 132.311404 -287.315889) (xy 132.303461 -287.368593) (xy 132.287751 -287.419523)
			(xy 132.264625 -287.467544) (xy 132.234601 -287.511581) (xy 132.198349 -287.550652) (xy 132.156678 -287.583883)
			(xy 132.11052 -287.610532) (xy 132.060906 -287.630004) (xy 132.008944 -287.641864) (xy 131.955794 -287.645848)
			(xy 131.902644 -287.641864) (xy 131.850682 -287.630004) (xy 131.801068 -287.610532) (xy 131.75491 -287.583883)
			(xy 131.713239 -287.550652) (xy 131.676987 -287.511581) (xy 131.646963 -287.467544) (xy 131.623837 -287.419523)
			(xy 131.608127 -287.368593) (xy 131.600184 -287.315889) (xy 131.371604 -287.315889) (xy 131.363661 -287.368593)
			(xy 131.347951 -287.419523) (xy 131.324825 -287.467544) (xy 131.294801 -287.511581) (xy 131.258549 -287.550652)
			(xy 131.216878 -287.583883) (xy 131.17072 -287.610532) (xy 131.121106 -287.630004) (xy 131.069144 -287.641864)
			(xy 131.015994 -287.645848) (xy 130.962844 -287.641864) (xy 130.910882 -287.630004) (xy 130.861268 -287.610532)
			(xy 130.81511 -287.583883) (xy 130.773439 -287.550652) (xy 130.737187 -287.511581) (xy 130.707163 -287.467544)
			(xy 130.684037 -287.419523) (xy 130.668327 -287.368593) (xy 130.660384 -287.315889) (xy 130.431804 -287.315889)
			(xy 130.423861 -287.368593) (xy 130.408151 -287.419523) (xy 130.385025 -287.467544) (xy 130.355001 -287.511581)
			(xy 130.318749 -287.550652) (xy 130.277078 -287.583883) (xy 130.23092 -287.610532) (xy 130.181306 -287.630004)
			(xy 130.129344 -287.641864) (xy 130.076194 -287.645848) (xy 130.023044 -287.641864) (xy 129.971082 -287.630004)
			(xy 129.921468 -287.610532) (xy 129.87531 -287.583883) (xy 129.833639 -287.550652) (xy 129.797387 -287.511581)
			(xy 129.767363 -287.467544) (xy 129.744237 -287.419523) (xy 129.728527 -287.368593) (xy 129.720584 -287.315889)
			(xy 129.492004 -287.315889) (xy 129.484061 -287.368593) (xy 129.468351 -287.419523) (xy 129.445225 -287.467544)
			(xy 129.415201 -287.511581) (xy 129.378949 -287.550652) (xy 129.337278 -287.583883) (xy 129.29112 -287.610532)
			(xy 129.241506 -287.630004) (xy 129.189544 -287.641864) (xy 129.136394 -287.645848) (xy 129.083244 -287.641864)
			(xy 129.031282 -287.630004) (xy 128.981668 -287.610532) (xy 128.93551 -287.583883) (xy 128.893839 -287.550652)
			(xy 128.857587 -287.511581) (xy 128.827563 -287.467544) (xy 128.804437 -287.419523) (xy 128.788727 -287.368593)
			(xy 128.780784 -287.315889) (xy 128.552204 -287.315889) (xy 128.544261 -287.368593) (xy 128.528551 -287.419523)
			(xy 128.505425 -287.467544) (xy 128.475401 -287.511581) (xy 128.439149 -287.550652) (xy 128.397478 -287.583883)
			(xy 128.35132 -287.610532) (xy 128.301706 -287.630004) (xy 128.249744 -287.641864) (xy 128.196594 -287.645848)
			(xy 128.143444 -287.641864) (xy 128.091482 -287.630004) (xy 128.041868 -287.610532) (xy 127.99571 -287.583883)
			(xy 127.954039 -287.550652) (xy 127.917787 -287.511581) (xy 127.887763 -287.467544) (xy 127.864637 -287.419523)
			(xy 127.848927 -287.368593) (xy 127.840984 -287.315889) (xy 127.612404 -287.315889) (xy 127.604461 -287.368593)
			(xy 127.588751 -287.419523) (xy 127.565625 -287.467544) (xy 127.535601 -287.511581) (xy 127.499349 -287.550652)
			(xy 127.457678 -287.583883) (xy 127.41152 -287.610532) (xy 127.361906 -287.630004) (xy 127.309944 -287.641864)
			(xy 127.256794 -287.645848) (xy 127.203644 -287.641864) (xy 127.151682 -287.630004) (xy 127.102068 -287.610532)
			(xy 127.05591 -287.583883) (xy 127.014239 -287.550652) (xy 126.977987 -287.511581) (xy 126.947963 -287.467544)
			(xy 126.924837 -287.419523) (xy 126.909127 -287.368593) (xy 126.901184 -287.315889) (xy 126.672604 -287.315889)
			(xy 126.664661 -287.368593) (xy 126.648951 -287.419523) (xy 126.625825 -287.467544) (xy 126.595801 -287.511581)
			(xy 126.559549 -287.550652) (xy 126.517878 -287.583883) (xy 126.47172 -287.610532) (xy 126.422106 -287.630004)
			(xy 126.370144 -287.641864) (xy 126.316994 -287.645848) (xy 126.263844 -287.641864) (xy 126.211882 -287.630004)
			(xy 126.162268 -287.610532) (xy 126.11611 -287.583883) (xy 126.074439 -287.550652) (xy 126.038187 -287.511581)
			(xy 126.008163 -287.467544) (xy 125.985037 -287.419523) (xy 125.969327 -287.368593) (xy 125.961384 -287.315889)
			(xy 125.732804 -287.315889) (xy 125.724861 -287.368593) (xy 125.709151 -287.419523) (xy 125.686025 -287.467544)
			(xy 125.656001 -287.511581) (xy 125.619749 -287.550652) (xy 125.578078 -287.583883) (xy 125.53192 -287.610532)
			(xy 125.482306 -287.630004) (xy 125.430344 -287.641864) (xy 125.377194 -287.645848) (xy 125.324044 -287.641864)
			(xy 125.272082 -287.630004) (xy 125.222468 -287.610532) (xy 125.17631 -287.583883) (xy 125.134639 -287.550652)
			(xy 125.098387 -287.511581) (xy 125.068363 -287.467544) (xy 125.045237 -287.419523) (xy 125.029527 -287.368593)
			(xy 125.021584 -287.315889) (xy 124.793004 -287.315889) (xy 124.785061 -287.368593) (xy 124.769351 -287.419523)
			(xy 124.746225 -287.467544) (xy 124.716201 -287.511581) (xy 124.679949 -287.550652) (xy 124.638278 -287.583883)
			(xy 124.59212 -287.610532) (xy 124.542506 -287.630004) (xy 124.490544 -287.641864) (xy 124.437394 -287.645848)
			(xy 124.384244 -287.641864) (xy 124.332282 -287.630004) (xy 124.282668 -287.610532) (xy 124.23651 -287.583883)
			(xy 124.194839 -287.550652) (xy 124.158587 -287.511581) (xy 124.128563 -287.467544) (xy 124.105437 -287.419523)
			(xy 124.089727 -287.368593) (xy 124.081784 -287.315889) (xy 123.853204 -287.315889) (xy 123.845261 -287.368593)
			(xy 123.829551 -287.419523) (xy 123.806425 -287.467544) (xy 123.776401 -287.511581) (xy 123.740149 -287.550652)
			(xy 123.698478 -287.583883) (xy 123.65232 -287.610532) (xy 123.602706 -287.630004) (xy 123.550744 -287.641864)
			(xy 123.497594 -287.645848) (xy 123.444444 -287.641864) (xy 123.392482 -287.630004) (xy 123.342868 -287.610532)
			(xy 123.29671 -287.583883) (xy 123.255039 -287.550652) (xy 123.218787 -287.511581) (xy 123.188763 -287.467544)
			(xy 123.165637 -287.419523) (xy 123.149927 -287.368593) (xy 123.141984 -287.315889) (xy 122.913404 -287.315889)
			(xy 122.905461 -287.368593) (xy 122.889751 -287.419523) (xy 122.866625 -287.467544) (xy 122.836601 -287.511581)
			(xy 122.800349 -287.550652) (xy 122.758678 -287.583883) (xy 122.71252 -287.610532) (xy 122.662906 -287.630004)
			(xy 122.610944 -287.641864) (xy 122.557794 -287.645848) (xy 122.504644 -287.641864) (xy 122.452682 -287.630004)
			(xy 122.403068 -287.610532) (xy 122.35691 -287.583883) (xy 122.315239 -287.550652) (xy 122.278987 -287.511581)
			(xy 122.248963 -287.467544) (xy 122.225837 -287.419523) (xy 122.210127 -287.368593) (xy 122.202184 -287.315889)
			(xy 121.973604 -287.315889) (xy 121.965661 -287.368593) (xy 121.949951 -287.419523) (xy 121.926825 -287.467544)
			(xy 121.896801 -287.511581) (xy 121.860549 -287.550652) (xy 121.818878 -287.583883) (xy 121.77272 -287.610532)
			(xy 121.723106 -287.630004) (xy 121.671144 -287.641864) (xy 121.617994 -287.645848) (xy 121.564844 -287.641864)
			(xy 121.512882 -287.630004) (xy 121.463268 -287.610532) (xy 121.41711 -287.583883) (xy 121.375439 -287.550652)
			(xy 121.339187 -287.511581) (xy 121.309163 -287.467544) (xy 121.286037 -287.419523) (xy 121.270327 -287.368593)
			(xy 121.262384 -287.315889) (xy 121.033804 -287.315889) (xy 121.025861 -287.368593) (xy 121.010151 -287.419523)
			(xy 120.987025 -287.467544) (xy 120.957001 -287.511581) (xy 120.920749 -287.550652) (xy 120.879078 -287.583883)
			(xy 120.83292 -287.610532) (xy 120.783306 -287.630004) (xy 120.731344 -287.641864) (xy 120.678194 -287.645848)
			(xy 120.625044 -287.641864) (xy 120.573082 -287.630004) (xy 120.523468 -287.610532) (xy 120.47731 -287.583883)
			(xy 120.435639 -287.550652) (xy 120.399387 -287.511581) (xy 120.369363 -287.467544) (xy 120.346237 -287.419523)
			(xy 120.330527 -287.368593) (xy 120.322584 -287.315889) (xy 120.094258 -287.315889) (xy 120.086315 -287.368593)
			(xy 120.070605 -287.419523) (xy 120.047479 -287.467544) (xy 120.017455 -287.511581) (xy 119.981203 -287.550652)
			(xy 119.939532 -287.583883) (xy 119.893374 -287.610532) (xy 119.84376 -287.630004) (xy 119.791798 -287.641864)
			(xy 119.738648 -287.645848) (xy 119.685498 -287.641864) (xy 119.633536 -287.630004) (xy 119.583922 -287.610532)
			(xy 119.537764 -287.583883) (xy 119.496093 -287.550652) (xy 119.459841 -287.511581) (xy 119.429817 -287.467544)
			(xy 119.406691 -287.419523) (xy 119.390981 -287.368593) (xy 119.383038 -287.315889) (xy 110.696004 -287.315889)
			(xy 110.688061 -287.368593) (xy 110.672351 -287.419523) (xy 110.649225 -287.467544) (xy 110.619201 -287.511581)
			(xy 110.582949 -287.550652) (xy 110.541278 -287.583883) (xy 110.49512 -287.610532) (xy 110.445506 -287.630004)
			(xy 110.393544 -287.641864) (xy 110.340394 -287.645848) (xy 110.287244 -287.641864) (xy 110.235282 -287.630004)
			(xy 110.185668 -287.610532) (xy 110.13951 -287.583883) (xy 110.097839 -287.550652) (xy 110.061587 -287.511581)
			(xy 110.031563 -287.467544) (xy 110.008437 -287.419523) (xy 109.992727 -287.368593) (xy 109.984784 -287.315889)
			(xy 107.876604 -287.315889) (xy 107.868661 -287.368593) (xy 107.852951 -287.419523) (xy 107.829825 -287.467544)
			(xy 107.799801 -287.511581) (xy 107.763549 -287.550652) (xy 107.721878 -287.583883) (xy 107.67572 -287.610532)
			(xy 107.626106 -287.630004) (xy 107.574144 -287.641864) (xy 107.520994 -287.645848) (xy 107.467844 -287.641864)
			(xy 107.415882 -287.630004) (xy 107.366268 -287.610532) (xy 107.32011 -287.583883) (xy 107.278439 -287.550652)
			(xy 107.242187 -287.511581) (xy 107.212163 -287.467544) (xy 107.189037 -287.419523) (xy 107.173327 -287.368593)
			(xy 107.165384 -287.315889) (xy 105.986946 -287.315889) (xy 105.99928 -287.339278) (xy 105.95737 -287.387538)
			(xy 105.948717 -287.413443) (xy 105.924139 -287.462213) (xy 105.891891 -287.506288) (xy 105.852845 -287.544472)
			(xy 105.808062 -287.57573) (xy 105.783634 -287.587944) (xy 105.756964 -287.618678) (xy 105.742927 -287.66205)
			(xy 105.70867 -287.746538) (xy 105.667574 -287.827919) (xy 105.619917 -287.90564) (xy 105.566024 -287.979174)
			(xy 105.536492 -288.013902) (xy 105.529773 -288.022428) (xy 105.523604 -288.043219) (xy 105.524554 -288.054034)
			(xy 105.526128 -288.066228) (xy 105.527782 -288.090761) (xy 105.527856 -288.103056) (xy 105.527372 -288.129575)
			(xy 105.527353 -288.129705) (xy 113.274084 -288.129705) (xy 113.274084 -288.076407) (xy 113.282027 -288.023703)
			(xy 113.297737 -287.972773) (xy 113.320863 -287.924752) (xy 113.350887 -287.880715) (xy 113.387139 -287.841644)
			(xy 113.42881 -287.808413) (xy 113.474968 -287.781764) (xy 113.524582 -287.762292) (xy 113.576544 -287.750432)
			(xy 113.629694 -287.746449) (xy 113.682844 -287.750432) (xy 113.734806 -287.762292) (xy 113.78442 -287.781764)
			(xy 113.830578 -287.808413) (xy 113.872249 -287.841644) (xy 113.908501 -287.880715) (xy 113.938525 -287.924752)
			(xy 113.961651 -287.972773) (xy 113.977361 -288.023703) (xy 113.985304 -288.076407) (xy 113.985802 -288.103056)
			(xy 113.985304 -288.129705) (xy 116.093738 -288.129705) (xy 116.093738 -288.076407) (xy 116.101681 -288.023703)
			(xy 116.117391 -287.972773) (xy 116.140517 -287.924752) (xy 116.170541 -287.880715) (xy 116.206793 -287.841644)
			(xy 116.248464 -287.808413) (xy 116.294622 -287.781764) (xy 116.344236 -287.762292) (xy 116.396198 -287.750432)
			(xy 116.449348 -287.746449) (xy 116.502498 -287.750432) (xy 116.55446 -287.762292) (xy 116.604074 -287.781764)
			(xy 116.650232 -287.808413) (xy 116.691903 -287.841644) (xy 116.728155 -287.880715) (xy 116.758179 -287.924752)
			(xy 116.781305 -287.972773) (xy 116.797015 -288.023703) (xy 116.804958 -288.076407) (xy 116.805456 -288.103056)
			(xy 116.804958 -288.129705) (xy 119.852684 -288.129705) (xy 119.852684 -288.076407) (xy 119.860627 -288.023703)
			(xy 119.876337 -287.972773) (xy 119.899463 -287.924752) (xy 119.929487 -287.880715) (xy 119.965739 -287.841644)
			(xy 120.00741 -287.808413) (xy 120.053568 -287.781764) (xy 120.103182 -287.762292) (xy 120.155144 -287.750432)
			(xy 120.208294 -287.746449) (xy 120.261444 -287.750432) (xy 120.313406 -287.762292) (xy 120.36302 -287.781764)
			(xy 120.409178 -287.808413) (xy 120.450849 -287.841644) (xy 120.487101 -287.880715) (xy 120.517125 -287.924752)
			(xy 120.540251 -287.972773) (xy 120.555961 -288.023703) (xy 120.563904 -288.076407) (xy 120.564402 -288.103056)
			(xy 120.818656 -288.103056) (xy 120.819164 -288.077149) (xy 120.82727 -288.025972) (xy 120.843282 -287.976693)
			(xy 120.866805 -287.930526) (xy 120.897261 -287.888607) (xy 120.933899 -287.851969) (xy 120.975818 -287.821513)
			(xy 121.021985 -287.79799) (xy 121.071264 -287.781978) (xy 121.122441 -287.773872) (xy 121.174255 -287.773872)
			(xy 121.225432 -287.781978) (xy 121.274711 -287.79799) (xy 121.320878 -287.821513) (xy 121.362797 -287.851969)
			(xy 121.399435 -287.888607) (xy 121.429891 -287.930526) (xy 121.453414 -287.976693) (xy 121.469426 -288.025972)
			(xy 121.477532 -288.077149) (xy 121.47804 -288.103056) (xy 121.477461 -288.129705) (xy 121.732538 -288.129705)
			(xy 121.732538 -288.076407) (xy 121.740481 -288.023703) (xy 121.756191 -287.972773) (xy 121.779317 -287.924752)
			(xy 121.809341 -287.880715) (xy 121.845593 -287.841644) (xy 121.887264 -287.808413) (xy 121.933422 -287.781764)
			(xy 121.983036 -287.762292) (xy 122.034998 -287.750432) (xy 122.088148 -287.746449) (xy 122.141298 -287.750432)
			(xy 122.19326 -287.762292) (xy 122.242874 -287.781764) (xy 122.289032 -287.808413) (xy 122.330703 -287.841644)
			(xy 122.366955 -287.880715) (xy 122.396979 -287.924752) (xy 122.420105 -287.972773) (xy 122.435815 -288.023703)
			(xy 122.443758 -288.076407) (xy 122.444256 -288.103056) (xy 122.698256 -288.103056) (xy 122.698764 -288.077149)
			(xy 122.70687 -288.025972) (xy 122.722882 -287.976693) (xy 122.746405 -287.930526) (xy 122.776861 -287.888607)
			(xy 122.813499 -287.851969) (xy 122.855418 -287.821513) (xy 122.901585 -287.79799) (xy 122.950864 -287.781978)
			(xy 123.002041 -287.773872) (xy 123.053855 -287.773872) (xy 123.105032 -287.781978) (xy 123.154311 -287.79799)
			(xy 123.200478 -287.821513) (xy 123.242397 -287.851969) (xy 123.279035 -287.888607) (xy 123.309491 -287.930526)
			(xy 123.333014 -287.976693) (xy 123.349026 -288.025972) (xy 123.357132 -288.077149) (xy 123.35764 -288.103056)
			(xy 123.357061 -288.129705) (xy 123.612138 -288.129705) (xy 123.612138 -288.076407) (xy 123.620081 -288.023703)
			(xy 123.635791 -287.972773) (xy 123.658917 -287.924752) (xy 123.688941 -287.880715) (xy 123.725193 -287.841644)
			(xy 123.766864 -287.808413) (xy 123.813022 -287.781764) (xy 123.862636 -287.762292) (xy 123.914598 -287.750432)
			(xy 123.967748 -287.746449) (xy 124.020898 -287.750432) (xy 124.07286 -287.762292) (xy 124.122474 -287.781764)
			(xy 124.168632 -287.808413) (xy 124.210303 -287.841644) (xy 124.246555 -287.880715) (xy 124.276579 -287.924752)
			(xy 124.299705 -287.972773) (xy 124.315415 -288.023703) (xy 124.323358 -288.076407) (xy 124.323856 -288.103056)
			(xy 124.577856 -288.103056) (xy 124.578364 -288.077149) (xy 124.58647 -288.025972) (xy 124.602482 -287.976693)
			(xy 124.626005 -287.930526) (xy 124.656461 -287.888607) (xy 124.693099 -287.851969) (xy 124.735018 -287.821513)
			(xy 124.781185 -287.79799) (xy 124.830464 -287.781978) (xy 124.881641 -287.773872) (xy 124.933455 -287.773872)
			(xy 124.984632 -287.781978) (xy 125.033911 -287.79799) (xy 125.080078 -287.821513) (xy 125.121997 -287.851969)
			(xy 125.158635 -287.888607) (xy 125.189091 -287.930526) (xy 125.212614 -287.976693) (xy 125.228626 -288.025972)
			(xy 125.236732 -288.077149) (xy 125.23724 -288.103056) (xy 125.236661 -288.129705) (xy 125.491738 -288.129705)
			(xy 125.491738 -288.076407) (xy 125.499681 -288.023703) (xy 125.515391 -287.972773) (xy 125.538517 -287.924752)
			(xy 125.568541 -287.880715) (xy 125.604793 -287.841644) (xy 125.646464 -287.808413) (xy 125.692622 -287.781764)
			(xy 125.742236 -287.762292) (xy 125.794198 -287.750432) (xy 125.847348 -287.746449) (xy 125.900498 -287.750432)
			(xy 125.95246 -287.762292) (xy 126.002074 -287.781764) (xy 126.048232 -287.808413) (xy 126.089903 -287.841644)
			(xy 126.126155 -287.880715) (xy 126.156179 -287.924752) (xy 126.179305 -287.972773) (xy 126.195015 -288.023703)
			(xy 126.202958 -288.076407) (xy 126.203456 -288.103056) (xy 126.457456 -288.103056) (xy 126.457964 -288.077149)
			(xy 126.46607 -288.025972) (xy 126.482082 -287.976693) (xy 126.505605 -287.930526) (xy 126.536061 -287.888607)
			(xy 126.572699 -287.851969) (xy 126.614618 -287.821513) (xy 126.660785 -287.79799) (xy 126.710064 -287.781978)
			(xy 126.761241 -287.773872) (xy 126.813055 -287.773872) (xy 126.864232 -287.781978) (xy 126.913511 -287.79799)
			(xy 126.959678 -287.821513) (xy 127.001597 -287.851969) (xy 127.038235 -287.888607) (xy 127.068691 -287.930526)
			(xy 127.092214 -287.976693) (xy 127.108226 -288.025972) (xy 127.116332 -288.077149) (xy 127.11684 -288.103056)
			(xy 127.116261 -288.129705) (xy 127.371338 -288.129705) (xy 127.371338 -288.076407) (xy 127.379281 -288.023703)
			(xy 127.394991 -287.972773) (xy 127.418117 -287.924752) (xy 127.448141 -287.880715) (xy 127.484393 -287.841644)
			(xy 127.526064 -287.808413) (xy 127.572222 -287.781764) (xy 127.621836 -287.762292) (xy 127.673798 -287.750432)
			(xy 127.726948 -287.746449) (xy 127.780098 -287.750432) (xy 127.83206 -287.762292) (xy 127.881674 -287.781764)
			(xy 127.927832 -287.808413) (xy 127.969503 -287.841644) (xy 128.005755 -287.880715) (xy 128.035779 -287.924752)
			(xy 128.058905 -287.972773) (xy 128.074615 -288.023703) (xy 128.082558 -288.076407) (xy 128.083056 -288.103056)
			(xy 128.337056 -288.103056) (xy 128.337564 -288.077149) (xy 128.34567 -288.025972) (xy 128.361682 -287.976693)
			(xy 128.385205 -287.930526) (xy 128.415661 -287.888607) (xy 128.452299 -287.851969) (xy 128.494218 -287.821513)
			(xy 128.540385 -287.79799) (xy 128.589664 -287.781978) (xy 128.640841 -287.773872) (xy 128.692655 -287.773872)
			(xy 128.743832 -287.781978) (xy 128.793111 -287.79799) (xy 128.839278 -287.821513) (xy 128.881197 -287.851969)
			(xy 128.917835 -287.888607) (xy 128.948291 -287.930526) (xy 128.971814 -287.976693) (xy 128.987826 -288.025972)
			(xy 128.995932 -288.077149) (xy 128.99644 -288.103056) (xy 128.995861 -288.129705) (xy 129.250938 -288.129705)
			(xy 129.250938 -288.076407) (xy 129.258881 -288.023703) (xy 129.274591 -287.972773) (xy 129.297717 -287.924752)
			(xy 129.327741 -287.880715) (xy 129.363993 -287.841644) (xy 129.405664 -287.808413) (xy 129.451822 -287.781764)
			(xy 129.501436 -287.762292) (xy 129.553398 -287.750432) (xy 129.606548 -287.746449) (xy 129.659698 -287.750432)
			(xy 129.71166 -287.762292) (xy 129.761274 -287.781764) (xy 129.807432 -287.808413) (xy 129.849103 -287.841644)
			(xy 129.885355 -287.880715) (xy 129.915379 -287.924752) (xy 129.938505 -287.972773) (xy 129.954215 -288.023703)
			(xy 129.962158 -288.076407) (xy 129.962656 -288.103056) (xy 130.216656 -288.103056) (xy 130.217164 -288.077149)
			(xy 130.22527 -288.025972) (xy 130.241282 -287.976693) (xy 130.264805 -287.930526) (xy 130.295261 -287.888607)
			(xy 130.331899 -287.851969) (xy 130.373818 -287.821513) (xy 130.419985 -287.79799) (xy 130.469264 -287.781978)
			(xy 130.520441 -287.773872) (xy 130.572255 -287.773872) (xy 130.623432 -287.781978) (xy 130.672711 -287.79799)
			(xy 130.718878 -287.821513) (xy 130.760797 -287.851969) (xy 130.797435 -287.888607) (xy 130.827891 -287.930526)
			(xy 130.851414 -287.976693) (xy 130.867426 -288.025972) (xy 130.875532 -288.077149) (xy 130.87604 -288.103056)
			(xy 130.875461 -288.129705) (xy 131.130538 -288.129705) (xy 131.130538 -288.076407) (xy 131.138481 -288.023703)
			(xy 131.154191 -287.972773) (xy 131.177317 -287.924752) (xy 131.207341 -287.880715) (xy 131.243593 -287.841644)
			(xy 131.285264 -287.808413) (xy 131.331422 -287.781764) (xy 131.381036 -287.762292) (xy 131.432998 -287.750432)
			(xy 131.486148 -287.746449) (xy 131.539298 -287.750432) (xy 131.59126 -287.762292) (xy 131.640874 -287.781764)
			(xy 131.687032 -287.808413) (xy 131.728703 -287.841644) (xy 131.764955 -287.880715) (xy 131.794979 -287.924752)
			(xy 131.818105 -287.972773) (xy 131.833815 -288.023703) (xy 131.841758 -288.076407) (xy 131.842256 -288.103056)
			(xy 132.096256 -288.103056) (xy 132.096764 -288.077149) (xy 132.10487 -288.025972) (xy 132.120882 -287.976693)
			(xy 132.144405 -287.930526) (xy 132.174861 -287.888607) (xy 132.211499 -287.851969) (xy 132.253418 -287.821513)
			(xy 132.299585 -287.79799) (xy 132.348864 -287.781978) (xy 132.400041 -287.773872) (xy 132.451855 -287.773872)
			(xy 132.503032 -287.781978) (xy 132.552311 -287.79799) (xy 132.598478 -287.821513) (xy 132.640397 -287.851969)
			(xy 132.677035 -287.888607) (xy 132.707491 -287.930526) (xy 132.731014 -287.976693) (xy 132.747026 -288.025972)
			(xy 132.755132 -288.077149) (xy 132.75564 -288.103056) (xy 132.755061 -288.129705) (xy 133.010138 -288.129705)
			(xy 133.010138 -288.076407) (xy 133.018081 -288.023703) (xy 133.033791 -287.972773) (xy 133.056917 -287.924752)
			(xy 133.086941 -287.880715) (xy 133.123193 -287.841644) (xy 133.164864 -287.808413) (xy 133.211022 -287.781764)
			(xy 133.260636 -287.762292) (xy 133.312598 -287.750432) (xy 133.365748 -287.746449) (xy 133.418898 -287.750432)
			(xy 133.47086 -287.762292) (xy 133.520474 -287.781764) (xy 133.566632 -287.808413) (xy 133.608303 -287.841644)
			(xy 133.644555 -287.880715) (xy 133.674579 -287.924752) (xy 133.697705 -287.972773) (xy 133.713415 -288.023703)
			(xy 133.721358 -288.076407) (xy 133.721856 -288.103056) (xy 133.721358 -288.129705) (xy 133.949684 -288.129705)
			(xy 133.949684 -288.076407) (xy 133.957627 -288.023703) (xy 133.973337 -287.972773) (xy 133.996463 -287.924752)
			(xy 134.026487 -287.880715) (xy 134.062739 -287.841644) (xy 134.10441 -287.808413) (xy 134.150568 -287.781764)
			(xy 134.200182 -287.762292) (xy 134.252144 -287.750432) (xy 134.305294 -287.746449) (xy 134.358444 -287.750432)
			(xy 134.410406 -287.762292) (xy 134.46002 -287.781764) (xy 134.506178 -287.808413) (xy 134.547849 -287.841644)
			(xy 134.584101 -287.880715) (xy 134.614125 -287.924752) (xy 134.637251 -287.972773) (xy 134.652961 -288.023703)
			(xy 134.660904 -288.076407) (xy 134.661402 -288.103056) (xy 134.915656 -288.103056) (xy 134.916164 -288.077149)
			(xy 134.92427 -288.025972) (xy 134.940282 -287.976693) (xy 134.963805 -287.930526) (xy 134.994261 -287.888607)
			(xy 135.030899 -287.851969) (xy 135.072818 -287.821513) (xy 135.118985 -287.79799) (xy 135.168264 -287.781978)
			(xy 135.219441 -287.773872) (xy 135.271255 -287.773872) (xy 135.322432 -287.781978) (xy 135.371711 -287.79799)
			(xy 135.417878 -287.821513) (xy 135.459797 -287.851969) (xy 135.496435 -287.888607) (xy 135.526891 -287.930526)
			(xy 135.550414 -287.976693) (xy 135.566426 -288.025972) (xy 135.574532 -288.077149) (xy 135.57504 -288.103056)
			(xy 135.574461 -288.129705) (xy 135.829538 -288.129705) (xy 135.829538 -288.076407) (xy 135.837481 -288.023703)
			(xy 135.853191 -287.972773) (xy 135.876317 -287.924752) (xy 135.906341 -287.880715) (xy 135.942593 -287.841644)
			(xy 135.984264 -287.808413) (xy 136.030422 -287.781764) (xy 136.080036 -287.762292) (xy 136.131998 -287.750432)
			(xy 136.185148 -287.746449) (xy 136.238298 -287.750432) (xy 136.29026 -287.762292) (xy 136.339874 -287.781764)
			(xy 136.386032 -287.808413) (xy 136.427703 -287.841644) (xy 136.463955 -287.880715) (xy 136.493979 -287.924752)
			(xy 136.517105 -287.972773) (xy 136.532815 -288.023703) (xy 136.540758 -288.076407) (xy 136.541256 -288.103056)
			(xy 136.540758 -288.129705) (xy 136.532815 -288.182409) (xy 136.517105 -288.233339) (xy 136.493979 -288.28136)
			(xy 136.463955 -288.325397) (xy 136.427703 -288.364468) (xy 136.386032 -288.397699) (xy 136.339874 -288.424348)
			(xy 136.29026 -288.44382) (xy 136.238298 -288.45568) (xy 136.185148 -288.459664) (xy 136.131998 -288.45568)
			(xy 136.080036 -288.44382) (xy 136.030422 -288.424348) (xy 135.984264 -288.397699) (xy 135.942593 -288.364468)
			(xy 135.906341 -288.325397) (xy 135.876317 -288.28136) (xy 135.853191 -288.233339) (xy 135.837481 -288.182409)
			(xy 135.829538 -288.129705) (xy 135.574461 -288.129705) (xy 135.574438 -288.130773) (xy 135.56512 -288.18542)
			(xy 135.556498 -288.211768) (xy 135.548624 -288.233866) (xy 135.753856 -288.588958) (xy 135.776716 -288.593276)
			(xy 135.801527 -288.598486) (xy 135.849305 -288.615434) (xy 135.893924 -288.6395) (xy 135.934331 -288.670114)
			(xy 135.969573 -288.706556) (xy 135.998818 -288.747964) (xy 136.021377 -288.793363) (xy 136.036717 -288.841681)
			(xy 136.044477 -288.891779) (xy 136.04494 -288.917126) (xy 136.044432 -288.943033) (xy 136.036326 -288.99421)
			(xy 136.020314 -289.043489) (xy 135.996791 -289.089656) (xy 135.966335 -289.131575) (xy 135.929697 -289.168213)
			(xy 135.887778 -289.198669) (xy 135.841611 -289.222192) (xy 135.792332 -289.238204) (xy 135.741155 -289.24631)
			(xy 135.689341 -289.24631) (xy 135.638164 -289.238204) (xy 135.588885 -289.222192) (xy 135.542718 -289.198669)
			(xy 135.500799 -289.168213) (xy 135.464161 -289.131575) (xy 135.433705 -289.089656) (xy 135.410182 -289.043489)
			(xy 135.39417 -288.99421) (xy 135.386064 -288.943033) (xy 135.385556 -288.917126) (xy 135.386153 -288.889409)
			(xy 135.395474 -288.834762) (xy 135.404098 -288.808414) (xy 135.411972 -288.786316) (xy 135.20674 -288.431224)
			(xy 135.18388 -288.426906) (xy 135.159064 -288.421716) (xy 135.111285 -288.404766) (xy 135.066665 -288.380698)
			(xy 135.026258 -288.350081) (xy 134.991016 -288.313637) (xy 134.961772 -288.272226) (xy 134.939214 -288.226825)
			(xy 134.923875 -288.178504) (xy 134.916118 -288.128404) (xy 134.915656 -288.103056) (xy 134.661402 -288.103056)
			(xy 134.660904 -288.129705) (xy 134.652961 -288.182409) (xy 134.637251 -288.233339) (xy 134.614125 -288.28136)
			(xy 134.584101 -288.325397) (xy 134.547849 -288.364468) (xy 134.506178 -288.397699) (xy 134.46002 -288.424348)
			(xy 134.410406 -288.44382) (xy 134.358444 -288.45568) (xy 134.305294 -288.459664) (xy 134.252144 -288.45568)
			(xy 134.200182 -288.44382) (xy 134.150568 -288.424348) (xy 134.10441 -288.397699) (xy 134.062739 -288.364468)
			(xy 134.026487 -288.325397) (xy 133.996463 -288.28136) (xy 133.973337 -288.233339) (xy 133.957627 -288.182409)
			(xy 133.949684 -288.129705) (xy 133.721358 -288.129705) (xy 133.713415 -288.182409) (xy 133.697705 -288.233339)
			(xy 133.674579 -288.28136) (xy 133.644555 -288.325397) (xy 133.608303 -288.364468) (xy 133.566632 -288.397699)
			(xy 133.520474 -288.424348) (xy 133.47086 -288.44382) (xy 133.418898 -288.45568) (xy 133.365748 -288.459664)
			(xy 133.312598 -288.45568) (xy 133.260636 -288.44382) (xy 133.211022 -288.424348) (xy 133.164864 -288.397699)
			(xy 133.123193 -288.364468) (xy 133.086941 -288.325397) (xy 133.056917 -288.28136) (xy 133.033791 -288.233339)
			(xy 133.018081 -288.182409) (xy 133.010138 -288.129705) (xy 132.755061 -288.129705) (xy 132.755038 -288.130773)
			(xy 132.74572 -288.18542) (xy 132.737098 -288.211768) (xy 132.729478 -288.233866) (xy 132.934456 -288.588958)
			(xy 132.957316 -288.593276) (xy 132.982127 -288.598486) (xy 133.029905 -288.615434) (xy 133.074524 -288.6395)
			(xy 133.114931 -288.670114) (xy 133.150173 -288.706556) (xy 133.179418 -288.747964) (xy 133.201977 -288.793363)
			(xy 133.217317 -288.841681) (xy 133.225077 -288.891779) (xy 133.22554 -288.917126) (xy 133.225032 -288.943033)
			(xy 133.216926 -288.99421) (xy 133.200914 -289.043489) (xy 133.177391 -289.089656) (xy 133.146935 -289.131575)
			(xy 133.110297 -289.168213) (xy 133.068378 -289.198669) (xy 133.022211 -289.222192) (xy 132.972932 -289.238204)
			(xy 132.921755 -289.24631) (xy 132.869941 -289.24631) (xy 132.818764 -289.238204) (xy 132.769485 -289.222192)
			(xy 132.723318 -289.198669) (xy 132.681399 -289.168213) (xy 132.644761 -289.131575) (xy 132.614305 -289.089656)
			(xy 132.590782 -289.043489) (xy 132.57477 -288.99421) (xy 132.566664 -288.943033) (xy 132.566156 -288.917126)
			(xy 132.566753 -288.889409) (xy 132.576074 -288.834762) (xy 132.584698 -288.808414) (xy 132.592572 -288.786316)
			(xy 132.387594 -288.431224) (xy 132.364734 -288.426906) (xy 132.339899 -288.421756) (xy 132.292089 -288.404821)
			(xy 132.247438 -288.380764) (xy 132.206999 -288.350151) (xy 132.171726 -288.313705) (xy 132.142451 -288.272287)
			(xy 132.119866 -288.226873) (xy 132.104504 -288.178536) (xy 132.096726 -288.128416) (xy 132.096256 -288.103056)
			(xy 131.842256 -288.103056) (xy 131.841758 -288.129705) (xy 131.833815 -288.182409) (xy 131.818105 -288.233339)
			(xy 131.794979 -288.28136) (xy 131.764955 -288.325397) (xy 131.728703 -288.364468) (xy 131.687032 -288.397699)
			(xy 131.640874 -288.424348) (xy 131.59126 -288.44382) (xy 131.539298 -288.45568) (xy 131.486148 -288.459664)
			(xy 131.432998 -288.45568) (xy 131.381036 -288.44382) (xy 131.331422 -288.424348) (xy 131.285264 -288.397699)
			(xy 131.243593 -288.364468) (xy 131.207341 -288.325397) (xy 131.177317 -288.28136) (xy 131.154191 -288.233339)
			(xy 131.138481 -288.182409) (xy 131.130538 -288.129705) (xy 130.875461 -288.129705) (xy 130.875438 -288.130773)
			(xy 130.86612 -288.18542) (xy 130.857498 -288.211768) (xy 130.849878 -288.233866) (xy 131.054856 -288.588958)
			(xy 131.077716 -288.593276) (xy 131.102527 -288.598486) (xy 131.150305 -288.615434) (xy 131.194924 -288.6395)
			(xy 131.235331 -288.670114) (xy 131.270573 -288.706556) (xy 131.299818 -288.747964) (xy 131.322377 -288.793363)
			(xy 131.337717 -288.841681) (xy 131.345477 -288.891779) (xy 131.34594 -288.917126) (xy 131.345432 -288.943033)
			(xy 131.337326 -288.99421) (xy 131.321314 -289.043489) (xy 131.297791 -289.089656) (xy 131.267335 -289.131575)
			(xy 131.230697 -289.168213) (xy 131.188778 -289.198669) (xy 131.142611 -289.222192) (xy 131.093332 -289.238204)
			(xy 131.042155 -289.24631) (xy 130.990341 -289.24631) (xy 130.939164 -289.238204) (xy 130.889885 -289.222192)
			(xy 130.843718 -289.198669) (xy 130.801799 -289.168213) (xy 130.765161 -289.131575) (xy 130.734705 -289.089656)
			(xy 130.711182 -289.043489) (xy 130.69517 -288.99421) (xy 130.687064 -288.943033) (xy 130.686556 -288.917126)
			(xy 130.687153 -288.889409) (xy 130.696474 -288.834762) (xy 130.705098 -288.808414) (xy 130.712972 -288.786316)
			(xy 130.507994 -288.431224) (xy 130.485134 -288.426906) (xy 130.460299 -288.421756) (xy 130.412489 -288.404821)
			(xy 130.367838 -288.380764) (xy 130.327399 -288.350151) (xy 130.292126 -288.313705) (xy 130.262851 -288.272287)
			(xy 130.240266 -288.226873) (xy 130.224904 -288.178536) (xy 130.217126 -288.128416) (xy 130.216656 -288.103056)
			(xy 129.962656 -288.103056) (xy 129.962158 -288.129705) (xy 129.954215 -288.182409) (xy 129.938505 -288.233339)
			(xy 129.915379 -288.28136) (xy 129.885355 -288.325397) (xy 129.849103 -288.364468) (xy 129.807432 -288.397699)
			(xy 129.761274 -288.424348) (xy 129.71166 -288.44382) (xy 129.659698 -288.45568) (xy 129.606548 -288.459664)
			(xy 129.553398 -288.45568) (xy 129.501436 -288.44382) (xy 129.451822 -288.424348) (xy 129.405664 -288.397699)
			(xy 129.363993 -288.364468) (xy 129.327741 -288.325397) (xy 129.297717 -288.28136) (xy 129.274591 -288.233339)
			(xy 129.258881 -288.182409) (xy 129.250938 -288.129705) (xy 128.995861 -288.129705) (xy 128.995838 -288.130773)
			(xy 128.98652 -288.18542) (xy 128.977898 -288.211768) (xy 128.970278 -288.233866) (xy 129.175256 -288.588958)
			(xy 129.198116 -288.593276) (xy 129.222927 -288.598486) (xy 129.270705 -288.615434) (xy 129.315324 -288.6395)
			(xy 129.355731 -288.670114) (xy 129.390973 -288.706556) (xy 129.420218 -288.747964) (xy 129.442777 -288.793363)
			(xy 129.458117 -288.841681) (xy 129.465877 -288.891779) (xy 129.46634 -288.917126) (xy 129.465832 -288.943033)
			(xy 129.457726 -288.99421) (xy 129.441714 -289.043489) (xy 129.418191 -289.089656) (xy 129.387735 -289.131575)
			(xy 129.351097 -289.168213) (xy 129.309178 -289.198669) (xy 129.263011 -289.222192) (xy 129.213732 -289.238204)
			(xy 129.162555 -289.24631) (xy 129.110741 -289.24631) (xy 129.059564 -289.238204) (xy 129.010285 -289.222192)
			(xy 128.964118 -289.198669) (xy 128.922199 -289.168213) (xy 128.885561 -289.131575) (xy 128.855105 -289.089656)
			(xy 128.831582 -289.043489) (xy 128.81557 -288.99421) (xy 128.807464 -288.943033) (xy 128.806956 -288.917126)
			(xy 128.807553 -288.889409) (xy 128.816874 -288.834762) (xy 128.825498 -288.808414) (xy 128.833372 -288.786316)
			(xy 128.628394 -288.431224) (xy 128.605534 -288.426906) (xy 128.580699 -288.421756) (xy 128.532889 -288.404821)
			(xy 128.488238 -288.380764) (xy 128.447799 -288.350151) (xy 128.412526 -288.313705) (xy 128.383251 -288.272287)
			(xy 128.360666 -288.226873) (xy 128.345304 -288.178536) (xy 128.337526 -288.128416) (xy 128.337056 -288.103056)
			(xy 128.083056 -288.103056) (xy 128.082558 -288.129705) (xy 128.074615 -288.182409) (xy 128.058905 -288.233339)
			(xy 128.035779 -288.28136) (xy 128.005755 -288.325397) (xy 127.969503 -288.364468) (xy 127.927832 -288.397699)
			(xy 127.881674 -288.424348) (xy 127.83206 -288.44382) (xy 127.780098 -288.45568) (xy 127.726948 -288.459664)
			(xy 127.673798 -288.45568) (xy 127.621836 -288.44382) (xy 127.572222 -288.424348) (xy 127.526064 -288.397699)
			(xy 127.484393 -288.364468) (xy 127.448141 -288.325397) (xy 127.418117 -288.28136) (xy 127.394991 -288.233339)
			(xy 127.379281 -288.182409) (xy 127.371338 -288.129705) (xy 127.116261 -288.129705) (xy 127.116238 -288.130773)
			(xy 127.10692 -288.18542) (xy 127.098298 -288.211768) (xy 127.090678 -288.233866) (xy 127.295656 -288.588958)
			(xy 127.318516 -288.593276) (xy 127.343327 -288.598486) (xy 127.391105 -288.615434) (xy 127.435724 -288.6395)
			(xy 127.476131 -288.670114) (xy 127.511373 -288.706556) (xy 127.540618 -288.747964) (xy 127.563177 -288.793363)
			(xy 127.578517 -288.841681) (xy 127.586277 -288.891779) (xy 127.58674 -288.917126) (xy 127.586232 -288.943033)
			(xy 127.578126 -288.99421) (xy 127.562114 -289.043489) (xy 127.538591 -289.089656) (xy 127.508135 -289.131575)
			(xy 127.471497 -289.168213) (xy 127.429578 -289.198669) (xy 127.383411 -289.222192) (xy 127.334132 -289.238204)
			(xy 127.282955 -289.24631) (xy 127.231141 -289.24631) (xy 127.179964 -289.238204) (xy 127.130685 -289.222192)
			(xy 127.084518 -289.198669) (xy 127.042599 -289.168213) (xy 127.005961 -289.131575) (xy 126.975505 -289.089656)
			(xy 126.951982 -289.043489) (xy 126.93597 -288.99421) (xy 126.927864 -288.943033) (xy 126.927356 -288.917126)
			(xy 126.927953 -288.889409) (xy 126.937274 -288.834762) (xy 126.945898 -288.808414) (xy 126.953772 -288.786316)
			(xy 126.748794 -288.431224) (xy 126.725934 -288.426906) (xy 126.701099 -288.421756) (xy 126.653289 -288.404821)
			(xy 126.608638 -288.380764) (xy 126.568199 -288.350151) (xy 126.532926 -288.313705) (xy 126.503651 -288.272287)
			(xy 126.481066 -288.226873) (xy 126.465704 -288.178536) (xy 126.457926 -288.128416) (xy 126.457456 -288.103056)
			(xy 126.203456 -288.103056) (xy 126.202958 -288.129705) (xy 126.195015 -288.182409) (xy 126.179305 -288.233339)
			(xy 126.156179 -288.28136) (xy 126.126155 -288.325397) (xy 126.089903 -288.364468) (xy 126.048232 -288.397699)
			(xy 126.002074 -288.424348) (xy 125.95246 -288.44382) (xy 125.900498 -288.45568) (xy 125.847348 -288.459664)
			(xy 125.794198 -288.45568) (xy 125.742236 -288.44382) (xy 125.692622 -288.424348) (xy 125.646464 -288.397699)
			(xy 125.604793 -288.364468) (xy 125.568541 -288.325397) (xy 125.538517 -288.28136) (xy 125.515391 -288.233339)
			(xy 125.499681 -288.182409) (xy 125.491738 -288.129705) (xy 125.236661 -288.129705) (xy 125.236638 -288.130773)
			(xy 125.22732 -288.18542) (xy 125.218698 -288.211768) (xy 125.211078 -288.233866) (xy 125.416056 -288.588958)
			(xy 125.438916 -288.593276) (xy 125.463727 -288.598486) (xy 125.511505 -288.615434) (xy 125.556124 -288.6395)
			(xy 125.596531 -288.670114) (xy 125.631773 -288.706556) (xy 125.661018 -288.747964) (xy 125.683577 -288.793363)
			(xy 125.698917 -288.841681) (xy 125.706677 -288.891779) (xy 125.70714 -288.917126) (xy 125.706632 -288.943033)
			(xy 125.698526 -288.99421) (xy 125.682514 -289.043489) (xy 125.658991 -289.089656) (xy 125.628535 -289.131575)
			(xy 125.591897 -289.168213) (xy 125.549978 -289.198669) (xy 125.503811 -289.222192) (xy 125.454532 -289.238204)
			(xy 125.403355 -289.24631) (xy 125.351541 -289.24631) (xy 125.300364 -289.238204) (xy 125.251085 -289.222192)
			(xy 125.204918 -289.198669) (xy 125.162999 -289.168213) (xy 125.126361 -289.131575) (xy 125.095905 -289.089656)
			(xy 125.072382 -289.043489) (xy 125.05637 -288.99421) (xy 125.048264 -288.943033) (xy 125.047756 -288.917126)
			(xy 125.048353 -288.889409) (xy 125.057674 -288.834762) (xy 125.066298 -288.808414) (xy 125.074172 -288.786316)
			(xy 124.869194 -288.431224) (xy 124.846334 -288.426906) (xy 124.821499 -288.421756) (xy 124.773689 -288.404821)
			(xy 124.729038 -288.380764) (xy 124.688599 -288.350151) (xy 124.653326 -288.313705) (xy 124.624051 -288.272287)
			(xy 124.601466 -288.226873) (xy 124.586104 -288.178536) (xy 124.578326 -288.128416) (xy 124.577856 -288.103056)
			(xy 124.323856 -288.103056) (xy 124.323358 -288.129705) (xy 124.315415 -288.182409) (xy 124.299705 -288.233339)
			(xy 124.276579 -288.28136) (xy 124.246555 -288.325397) (xy 124.210303 -288.364468) (xy 124.168632 -288.397699)
			(xy 124.122474 -288.424348) (xy 124.07286 -288.44382) (xy 124.020898 -288.45568) (xy 123.967748 -288.459664)
			(xy 123.914598 -288.45568) (xy 123.862636 -288.44382) (xy 123.813022 -288.424348) (xy 123.766864 -288.397699)
			(xy 123.725193 -288.364468) (xy 123.688941 -288.325397) (xy 123.658917 -288.28136) (xy 123.635791 -288.233339)
			(xy 123.620081 -288.182409) (xy 123.612138 -288.129705) (xy 123.357061 -288.129705) (xy 123.357038 -288.130773)
			(xy 123.34772 -288.18542) (xy 123.339098 -288.211768) (xy 123.331478 -288.233866) (xy 123.536456 -288.588958)
			(xy 123.559316 -288.593276) (xy 123.584127 -288.598486) (xy 123.631905 -288.615434) (xy 123.676524 -288.6395)
			(xy 123.716931 -288.670114) (xy 123.752173 -288.706556) (xy 123.781418 -288.747964) (xy 123.803977 -288.793363)
			(xy 123.819317 -288.841681) (xy 123.827077 -288.891779) (xy 123.82754 -288.917126) (xy 123.827032 -288.943033)
			(xy 123.818926 -288.99421) (xy 123.802914 -289.043489) (xy 123.779391 -289.089656) (xy 123.748935 -289.131575)
			(xy 123.712297 -289.168213) (xy 123.670378 -289.198669) (xy 123.624211 -289.222192) (xy 123.574932 -289.238204)
			(xy 123.523755 -289.24631) (xy 123.471941 -289.24631) (xy 123.420764 -289.238204) (xy 123.371485 -289.222192)
			(xy 123.325318 -289.198669) (xy 123.283399 -289.168213) (xy 123.246761 -289.131575) (xy 123.216305 -289.089656)
			(xy 123.192782 -289.043489) (xy 123.17677 -288.99421) (xy 123.168664 -288.943033) (xy 123.168156 -288.917126)
			(xy 123.168753 -288.889409) (xy 123.178074 -288.834762) (xy 123.186698 -288.808414) (xy 123.194572 -288.786316)
			(xy 122.989594 -288.431224) (xy 122.966734 -288.426906) (xy 122.941899 -288.421756) (xy 122.894089 -288.404821)
			(xy 122.849438 -288.380764) (xy 122.808999 -288.350151) (xy 122.773726 -288.313705) (xy 122.744451 -288.272287)
			(xy 122.721866 -288.226873) (xy 122.706504 -288.178536) (xy 122.698726 -288.128416) (xy 122.698256 -288.103056)
			(xy 122.444256 -288.103056) (xy 122.443758 -288.129705) (xy 122.435815 -288.182409) (xy 122.420105 -288.233339)
			(xy 122.396979 -288.28136) (xy 122.366955 -288.325397) (xy 122.330703 -288.364468) (xy 122.289032 -288.397699)
			(xy 122.242874 -288.424348) (xy 122.19326 -288.44382) (xy 122.141298 -288.45568) (xy 122.088148 -288.459664)
			(xy 122.034998 -288.45568) (xy 121.983036 -288.44382) (xy 121.933422 -288.424348) (xy 121.887264 -288.397699)
			(xy 121.845593 -288.364468) (xy 121.809341 -288.325397) (xy 121.779317 -288.28136) (xy 121.756191 -288.233339)
			(xy 121.740481 -288.182409) (xy 121.732538 -288.129705) (xy 121.477461 -288.129705) (xy 121.477438 -288.130773)
			(xy 121.46812 -288.18542) (xy 121.459498 -288.211768) (xy 121.451624 -288.233866) (xy 121.656856 -288.588958)
			(xy 121.679716 -288.593276) (xy 121.704527 -288.598486) (xy 121.752305 -288.615434) (xy 121.796924 -288.6395)
			(xy 121.837331 -288.670114) (xy 121.872573 -288.706556) (xy 121.901818 -288.747964) (xy 121.924377 -288.793363)
			(xy 121.939717 -288.841681) (xy 121.947477 -288.891779) (xy 121.94794 -288.917126) (xy 121.947432 -288.943033)
			(xy 121.939326 -288.99421) (xy 121.923314 -289.043489) (xy 121.899791 -289.089656) (xy 121.869335 -289.131575)
			(xy 121.832697 -289.168213) (xy 121.790778 -289.198669) (xy 121.744611 -289.222192) (xy 121.695332 -289.238204)
			(xy 121.644155 -289.24631) (xy 121.592341 -289.24631) (xy 121.541164 -289.238204) (xy 121.491885 -289.222192)
			(xy 121.445718 -289.198669) (xy 121.403799 -289.168213) (xy 121.367161 -289.131575) (xy 121.336705 -289.089656)
			(xy 121.313182 -289.043489) (xy 121.29717 -288.99421) (xy 121.289064 -288.943033) (xy 121.288556 -288.917126)
			(xy 121.289153 -288.889409) (xy 121.298474 -288.834762) (xy 121.307098 -288.808414) (xy 121.314972 -288.786316)
			(xy 121.10974 -288.431224) (xy 121.08688 -288.426906) (xy 121.062064 -288.421716) (xy 121.014285 -288.404766)
			(xy 120.969665 -288.380698) (xy 120.929258 -288.350081) (xy 120.894016 -288.313637) (xy 120.864772 -288.272226)
			(xy 120.842214 -288.226825) (xy 120.826875 -288.178504) (xy 120.819118 -288.128404) (xy 120.818656 -288.103056)
			(xy 120.564402 -288.103056) (xy 120.563904 -288.129705) (xy 120.555961 -288.182409) (xy 120.540251 -288.233339)
			(xy 120.517125 -288.28136) (xy 120.487101 -288.325397) (xy 120.450849 -288.364468) (xy 120.409178 -288.397699)
			(xy 120.36302 -288.424348) (xy 120.313406 -288.44382) (xy 120.261444 -288.45568) (xy 120.208294 -288.459664)
			(xy 120.155144 -288.45568) (xy 120.103182 -288.44382) (xy 120.053568 -288.424348) (xy 120.00741 -288.397699)
			(xy 119.965739 -288.364468) (xy 119.929487 -288.325397) (xy 119.899463 -288.28136) (xy 119.876337 -288.233339)
			(xy 119.860627 -288.182409) (xy 119.852684 -288.129705) (xy 116.804958 -288.129705) (xy 116.797015 -288.182409)
			(xy 116.781305 -288.233339) (xy 116.758179 -288.28136) (xy 116.728155 -288.325397) (xy 116.691903 -288.364468)
			(xy 116.650232 -288.397699) (xy 116.604074 -288.424348) (xy 116.55446 -288.44382) (xy 116.502498 -288.45568)
			(xy 116.449348 -288.459664) (xy 116.396198 -288.45568) (xy 116.344236 -288.44382) (xy 116.294622 -288.424348)
			(xy 116.248464 -288.397699) (xy 116.206793 -288.364468) (xy 116.170541 -288.325397) (xy 116.140517 -288.28136)
			(xy 116.117391 -288.233339) (xy 116.101681 -288.182409) (xy 116.093738 -288.129705) (xy 113.985304 -288.129705)
			(xy 113.977361 -288.182409) (xy 113.961651 -288.233339) (xy 113.938525 -288.28136) (xy 113.908501 -288.325397)
			(xy 113.872249 -288.364468) (xy 113.830578 -288.397699) (xy 113.78442 -288.424348) (xy 113.734806 -288.44382)
			(xy 113.682844 -288.45568) (xy 113.629694 -288.459664) (xy 113.576544 -288.45568) (xy 113.524582 -288.44382)
			(xy 113.474968 -288.424348) (xy 113.42881 -288.397699) (xy 113.387139 -288.364468) (xy 113.350887 -288.325397)
			(xy 113.320863 -288.28136) (xy 113.297737 -288.233339) (xy 113.282027 -288.182409) (xy 113.274084 -288.129705)
			(xy 105.527353 -288.129705) (xy 105.519513 -288.182027) (xy 105.503962 -288.232735) (xy 105.481064 -288.280575)
			(xy 105.451324 -288.32449) (xy 105.4154 -288.36351) (xy 105.374088 -288.396771) (xy 105.328299 -288.423537)
			(xy 105.303828 -288.433764) (xy 105.303066 -288.434018) (xy 105.294501 -288.438499) (xy 105.281303 -288.452602)
			(xy 105.277412 -288.46145) (xy 105.257854 -288.514536) (xy 105.244138 -288.547302) (xy 105.24042 -288.558319)
			(xy 105.242261 -288.581474) (xy 105.247694 -288.591752) (xy 105.2648 -288.621334) (xy 105.293291 -288.683448)
			(xy 105.31496 -288.748258) (xy 105.329556 -288.815018) (xy 105.336911 -288.882958) (xy 105.337356 -288.917126)
			(xy 105.337356 -288.943775) (xy 107.165638 -288.943775) (xy 107.165638 -288.890477) (xy 107.173581 -288.837773)
			(xy 107.189291 -288.786843) (xy 107.212417 -288.738822) (xy 107.242441 -288.694785) (xy 107.278693 -288.655714)
			(xy 107.320364 -288.622483) (xy 107.366522 -288.595834) (xy 107.416136 -288.576362) (xy 107.468098 -288.564502)
			(xy 107.521248 -288.560519) (xy 107.574398 -288.564502) (xy 107.62636 -288.576362) (xy 107.675974 -288.595834)
			(xy 107.722132 -288.622483) (xy 107.763803 -288.655714) (xy 107.800055 -288.694785) (xy 107.830079 -288.738822)
			(xy 107.853205 -288.786843) (xy 107.868915 -288.837773) (xy 107.876858 -288.890477) (xy 107.877356 -288.917126)
			(xy 107.876858 -288.943775) (xy 107.868915 -288.996479) (xy 107.861667 -289.019975) (xy 109.985038 -289.019975)
			(xy 109.985038 -288.966677) (xy 109.992981 -288.913973) (xy 110.008691 -288.863043) (xy 110.031817 -288.815022)
			(xy 110.061841 -288.770985) (xy 110.098093 -288.731914) (xy 110.139764 -288.698683) (xy 110.185922 -288.672034)
			(xy 110.235536 -288.652562) (xy 110.287498 -288.640702) (xy 110.340648 -288.636719) (xy 110.393798 -288.640702)
			(xy 110.44576 -288.652562) (xy 110.495374 -288.672034) (xy 110.541532 -288.698683) (xy 110.583203 -288.731914)
			(xy 110.619455 -288.770985) (xy 110.649479 -288.815022) (xy 110.672605 -288.863043) (xy 110.688315 -288.913973)
			(xy 110.692806 -288.943775) (xy 119.383038 -288.943775) (xy 119.383038 -288.890477) (xy 119.390981 -288.837773)
			(xy 119.406691 -288.786843) (xy 119.429817 -288.738822) (xy 119.459841 -288.694785) (xy 119.496093 -288.655714)
			(xy 119.537764 -288.622483) (xy 119.583922 -288.595834) (xy 119.633536 -288.576362) (xy 119.685498 -288.564502)
			(xy 119.738648 -288.560519) (xy 119.791798 -288.564502) (xy 119.84376 -288.576362) (xy 119.893374 -288.595834)
			(xy 119.939532 -288.622483) (xy 119.981203 -288.655714) (xy 120.017455 -288.694785) (xy 120.047479 -288.738822)
			(xy 120.070605 -288.786843) (xy 120.086315 -288.837773) (xy 120.094258 -288.890477) (xy 120.094756 -288.917126)
			(xy 120.094258 -288.943775) (xy 120.086315 -288.996479) (xy 120.070605 -289.047409) (xy 120.047479 -289.09543)
			(xy 120.017455 -289.139467) (xy 119.981203 -289.178538) (xy 119.939532 -289.211769) (xy 119.893374 -289.238418)
			(xy 119.84376 -289.25789) (xy 119.791798 -289.26975) (xy 119.738648 -289.273734) (xy 119.685498 -289.26975)
			(xy 119.633536 -289.25789) (xy 119.583922 -289.238418) (xy 119.537764 -289.211769) (xy 119.496093 -289.178538)
			(xy 119.459841 -289.139467) (xy 119.429817 -289.09543) (xy 119.406691 -289.047409) (xy 119.390981 -288.996479)
			(xy 119.383038 -288.943775) (xy 110.692806 -288.943775) (xy 110.696258 -288.966677) (xy 110.696756 -288.993326)
			(xy 110.696258 -289.019975) (xy 110.688315 -289.072679) (xy 110.672605 -289.123609) (xy 110.649479 -289.17163)
			(xy 110.619455 -289.215667) (xy 110.583203 -289.254738) (xy 110.541532 -289.287969) (xy 110.495374 -289.314618)
			(xy 110.44576 -289.33409) (xy 110.393798 -289.34595) (xy 110.340648 -289.349934) (xy 110.287498 -289.34595)
			(xy 110.235536 -289.33409) (xy 110.185922 -289.314618) (xy 110.139764 -289.287969) (xy 110.098093 -289.254738)
			(xy 110.061841 -289.215667) (xy 110.031817 -289.17163) (xy 110.008691 -289.123609) (xy 109.992981 -289.072679)
			(xy 109.985038 -289.019975) (xy 107.861667 -289.019975) (xy 107.853205 -289.047409) (xy 107.830079 -289.09543)
			(xy 107.800055 -289.139467) (xy 107.763803 -289.178538) (xy 107.722132 -289.211769) (xy 107.675974 -289.238418)
			(xy 107.62636 -289.25789) (xy 107.574398 -289.26975) (xy 107.521248 -289.273734) (xy 107.468098 -289.26975)
			(xy 107.416136 -289.25789) (xy 107.366522 -289.238418) (xy 107.320364 -289.211769) (xy 107.278693 -289.178538)
			(xy 107.242441 -289.139467) (xy 107.212417 -289.09543) (xy 107.189291 -289.047409) (xy 107.173581 -288.996479)
			(xy 107.165638 -288.943775) (xy 105.337356 -288.943775) (xy 105.337356 -289.493452) (xy 105.337911 -289.50498)
			(xy 105.347974 -289.525726) (xy 105.35666 -289.53333) (xy 105.378666 -289.548833) (xy 105.4178 -289.585789)
			(xy 105.450431 -289.628597) (xy 105.475697 -289.676125) (xy 105.492929 -289.727118) (xy 105.501674 -289.780229)
			(xy 105.502202 -289.807142) (xy 105.50169 -289.833791) (xy 118.912884 -289.833791) (xy 118.912884 -289.780493)
			(xy 118.920827 -289.727789) (xy 118.936537 -289.676859) (xy 118.959663 -289.628838) (xy 118.989687 -289.584801)
			(xy 119.025939 -289.54573) (xy 119.06761 -289.512499) (xy 119.113768 -289.48585) (xy 119.163382 -289.466378)
			(xy 119.215344 -289.454518) (xy 119.268494 -289.450535) (xy 119.321644 -289.454518) (xy 119.373606 -289.466378)
			(xy 119.42322 -289.48585) (xy 119.469378 -289.512499) (xy 119.511049 -289.54573) (xy 119.547301 -289.584801)
			(xy 119.577325 -289.628838) (xy 119.600451 -289.676859) (xy 119.616161 -289.727789) (xy 119.624104 -289.780493)
			(xy 119.624602 -289.807142) (xy 119.878856 -289.807142) (xy 119.879399 -289.781715) (xy 119.887229 -289.731468)
			(xy 119.90268 -289.683018) (xy 119.925386 -289.637514) (xy 119.954808 -289.596036) (xy 119.990248 -289.559565)
			(xy 120.030867 -289.528967) (xy 120.075701 -289.504967) (xy 120.123688 -289.488134) (xy 120.148604 -289.483038)
			(xy 120.172734 -289.478466) (xy 120.38711 -289.073082) (xy 120.377204 -289.050476) (xy 120.368243 -289.029398)
			(xy 120.355596 -288.985377) (xy 120.349182 -288.940026) (xy 120.348756 -288.917126) (xy 120.349264 -288.891219)
			(xy 120.35737 -288.840042) (xy 120.373382 -288.790763) (xy 120.396905 -288.744596) (xy 120.427361 -288.702677)
			(xy 120.463999 -288.666039) (xy 120.505918 -288.635583) (xy 120.552085 -288.61206) (xy 120.601364 -288.596048)
			(xy 120.652541 -288.587942) (xy 120.704355 -288.587942) (xy 120.755532 -288.596048) (xy 120.804811 -288.61206)
			(xy 120.850978 -288.635583) (xy 120.892897 -288.666039) (xy 120.929535 -288.702677) (xy 120.959991 -288.744596)
			(xy 120.983514 -288.790763) (xy 120.999526 -288.840042) (xy 121.007632 -288.891219) (xy 121.00814 -288.917126)
			(xy 121.007659 -288.942574) (xy 120.999856 -288.992867) (xy 120.984408 -289.041361) (xy 120.961683 -289.086901)
			(xy 120.932222 -289.128403) (xy 120.896727 -289.164878) (xy 120.856043 -289.195458) (xy 120.811139 -289.219415)
			(xy 120.763084 -289.236178) (xy 120.738138 -289.24123) (xy 120.714008 -289.245802) (xy 120.499632 -289.651186)
			(xy 120.509538 -289.673792) (xy 120.518456 -289.694878) (xy 120.531008 -289.738907) (xy 120.537342 -289.78425)
			(xy 120.537732 -289.807142) (xy 120.537224 -289.833029) (xy 120.537103 -289.833791) (xy 120.792484 -289.833791)
			(xy 120.792484 -289.780493) (xy 120.800427 -289.727789) (xy 120.816137 -289.676859) (xy 120.839263 -289.628838)
			(xy 120.869287 -289.584801) (xy 120.905539 -289.54573) (xy 120.94721 -289.512499) (xy 120.993368 -289.48585)
			(xy 121.042982 -289.466378) (xy 121.094944 -289.454518) (xy 121.148094 -289.450535) (xy 121.201244 -289.454518)
			(xy 121.253206 -289.466378) (xy 121.30282 -289.48585) (xy 121.348978 -289.512499) (xy 121.390649 -289.54573)
			(xy 121.426901 -289.584801) (xy 121.456925 -289.628838) (xy 121.480051 -289.676859) (xy 121.495761 -289.727789)
			(xy 121.503704 -289.780493) (xy 121.504202 -289.807142) (xy 121.758456 -289.807142) (xy 121.758999 -289.781715)
			(xy 121.766829 -289.731468) (xy 121.78228 -289.683018) (xy 121.804986 -289.637514) (xy 121.834408 -289.596036)
			(xy 121.869848 -289.559565) (xy 121.910467 -289.528967) (xy 121.955301 -289.504967) (xy 122.003288 -289.488134)
			(xy 122.028204 -289.483038) (xy 122.052334 -289.478466) (xy 122.26671 -289.073082) (xy 122.256804 -289.050476)
			(xy 122.247843 -289.029398) (xy 122.235196 -288.985377) (xy 122.228782 -288.940026) (xy 122.228356 -288.917126)
			(xy 122.228864 -288.891219) (xy 122.23697 -288.840042) (xy 122.252982 -288.790763) (xy 122.276505 -288.744596)
			(xy 122.306961 -288.702677) (xy 122.343599 -288.666039) (xy 122.385518 -288.635583) (xy 122.431685 -288.61206)
			(xy 122.480964 -288.596048) (xy 122.532141 -288.587942) (xy 122.583955 -288.587942) (xy 122.635132 -288.596048)
			(xy 122.684411 -288.61206) (xy 122.730578 -288.635583) (xy 122.772497 -288.666039) (xy 122.809135 -288.702677)
			(xy 122.839591 -288.744596) (xy 122.863114 -288.790763) (xy 122.879126 -288.840042) (xy 122.887232 -288.891219)
			(xy 122.88774 -288.917126) (xy 122.887259 -288.942574) (xy 122.879456 -288.992867) (xy 122.864008 -289.041361)
			(xy 122.841283 -289.086901) (xy 122.811822 -289.128403) (xy 122.776327 -289.164878) (xy 122.735643 -289.195458)
			(xy 122.690739 -289.219415) (xy 122.642684 -289.236178) (xy 122.617738 -289.24123) (xy 122.593608 -289.245802)
			(xy 122.379232 -289.651186) (xy 122.389138 -289.673792) (xy 122.398056 -289.694878) (xy 122.410608 -289.738907)
			(xy 122.416942 -289.78425) (xy 122.417332 -289.807142) (xy 122.416824 -289.833029) (xy 122.416703 -289.833791)
			(xy 122.672084 -289.833791) (xy 122.672084 -289.780493) (xy 122.680027 -289.727789) (xy 122.695737 -289.676859)
			(xy 122.718863 -289.628838) (xy 122.748887 -289.584801) (xy 122.785139 -289.54573) (xy 122.82681 -289.512499)
			(xy 122.872968 -289.48585) (xy 122.922582 -289.466378) (xy 122.974544 -289.454518) (xy 123.027694 -289.450535)
			(xy 123.080844 -289.454518) (xy 123.132806 -289.466378) (xy 123.18242 -289.48585) (xy 123.228578 -289.512499)
			(xy 123.270249 -289.54573) (xy 123.306501 -289.584801) (xy 123.336525 -289.628838) (xy 123.359651 -289.676859)
			(xy 123.375361 -289.727789) (xy 123.383304 -289.780493) (xy 123.383802 -289.807142) (xy 123.638056 -289.807142)
			(xy 123.638599 -289.781715) (xy 123.646429 -289.731468) (xy 123.66188 -289.683018) (xy 123.684586 -289.637514)
			(xy 123.714008 -289.596036) (xy 123.749448 -289.559565) (xy 123.790067 -289.528967) (xy 123.834901 -289.504967)
			(xy 123.882888 -289.488134) (xy 123.907804 -289.483038) (xy 123.931934 -289.478466) (xy 124.14631 -289.073082)
			(xy 124.136404 -289.050476) (xy 124.127443 -289.029398) (xy 124.114796 -288.985377) (xy 124.108382 -288.940026)
			(xy 124.107956 -288.917126) (xy 124.108464 -288.891219) (xy 124.11657 -288.840042) (xy 124.132582 -288.790763)
			(xy 124.156105 -288.744596) (xy 124.186561 -288.702677) (xy 124.223199 -288.666039) (xy 124.265118 -288.635583)
			(xy 124.311285 -288.61206) (xy 124.360564 -288.596048) (xy 124.411741 -288.587942) (xy 124.463555 -288.587942)
			(xy 124.514732 -288.596048) (xy 124.564011 -288.61206) (xy 124.610178 -288.635583) (xy 124.652097 -288.666039)
			(xy 124.688735 -288.702677) (xy 124.719191 -288.744596) (xy 124.742714 -288.790763) (xy 124.758726 -288.840042)
			(xy 124.766832 -288.891219) (xy 124.76734 -288.917126) (xy 124.766859 -288.942574) (xy 124.759056 -288.992867)
			(xy 124.743608 -289.041361) (xy 124.720883 -289.086901) (xy 124.691422 -289.128403) (xy 124.655927 -289.164878)
			(xy 124.615243 -289.195458) (xy 124.570339 -289.219415) (xy 124.522284 -289.236178) (xy 124.497338 -289.24123)
			(xy 124.473208 -289.245802) (xy 124.258832 -289.651186) (xy 124.268738 -289.673792) (xy 124.277656 -289.694878)
			(xy 124.290208 -289.738907) (xy 124.296542 -289.78425) (xy 124.296932 -289.807142) (xy 124.296424 -289.833029)
			(xy 124.296303 -289.833791) (xy 124.551684 -289.833791) (xy 124.551684 -289.780493) (xy 124.559627 -289.727789)
			(xy 124.575337 -289.676859) (xy 124.598463 -289.628838) (xy 124.628487 -289.584801) (xy 124.664739 -289.54573)
			(xy 124.70641 -289.512499) (xy 124.752568 -289.48585) (xy 124.802182 -289.466378) (xy 124.854144 -289.454518)
			(xy 124.907294 -289.450535) (xy 124.960444 -289.454518) (xy 125.012406 -289.466378) (xy 125.06202 -289.48585)
			(xy 125.108178 -289.512499) (xy 125.149849 -289.54573) (xy 125.186101 -289.584801) (xy 125.216125 -289.628838)
			(xy 125.239251 -289.676859) (xy 125.254961 -289.727789) (xy 125.262904 -289.780493) (xy 125.263402 -289.807142)
			(xy 125.517656 -289.807142) (xy 125.518199 -289.781715) (xy 125.526029 -289.731468) (xy 125.54148 -289.683018)
			(xy 125.564186 -289.637514) (xy 125.593608 -289.596036) (xy 125.629048 -289.559565) (xy 125.669667 -289.528967)
			(xy 125.714501 -289.504967) (xy 125.762488 -289.488134) (xy 125.787404 -289.483038) (xy 125.811534 -289.478466)
			(xy 126.02591 -289.073082) (xy 126.016004 -289.050476) (xy 126.007043 -289.029398) (xy 125.994396 -288.985377)
			(xy 125.987982 -288.940026) (xy 125.987556 -288.917126) (xy 125.988064 -288.891219) (xy 125.99617 -288.840042)
			(xy 126.012182 -288.790763) (xy 126.035705 -288.744596) (xy 126.066161 -288.702677) (xy 126.102799 -288.666039)
			(xy 126.144718 -288.635583) (xy 126.190885 -288.61206) (xy 126.240164 -288.596048) (xy 126.291341 -288.587942)
			(xy 126.343155 -288.587942) (xy 126.394332 -288.596048) (xy 126.443611 -288.61206) (xy 126.489778 -288.635583)
			(xy 126.531697 -288.666039) (xy 126.568335 -288.702677) (xy 126.598791 -288.744596) (xy 126.622314 -288.790763)
			(xy 126.638326 -288.840042) (xy 126.646432 -288.891219) (xy 126.64694 -288.917126) (xy 126.646459 -288.942574)
			(xy 126.638656 -288.992867) (xy 126.623208 -289.041361) (xy 126.600483 -289.086901) (xy 126.571022 -289.128403)
			(xy 126.535527 -289.164878) (xy 126.494843 -289.195458) (xy 126.449939 -289.219415) (xy 126.401884 -289.236178)
			(xy 126.376938 -289.24123) (xy 126.352808 -289.245802) (xy 126.138432 -289.651186) (xy 126.148338 -289.673792)
			(xy 126.157256 -289.694878) (xy 126.169808 -289.738907) (xy 126.176142 -289.78425) (xy 126.176532 -289.807142)
			(xy 126.176024 -289.833029) (xy 126.175903 -289.833791) (xy 126.431284 -289.833791) (xy 126.431284 -289.780493)
			(xy 126.439227 -289.727789) (xy 126.454937 -289.676859) (xy 126.478063 -289.628838) (xy 126.508087 -289.584801)
			(xy 126.544339 -289.54573) (xy 126.58601 -289.512499) (xy 126.632168 -289.48585) (xy 126.681782 -289.466378)
			(xy 126.733744 -289.454518) (xy 126.786894 -289.450535) (xy 126.840044 -289.454518) (xy 126.892006 -289.466378)
			(xy 126.94162 -289.48585) (xy 126.987778 -289.512499) (xy 127.029449 -289.54573) (xy 127.065701 -289.584801)
			(xy 127.095725 -289.628838) (xy 127.118851 -289.676859) (xy 127.134561 -289.727789) (xy 127.142504 -289.780493)
			(xy 127.143002 -289.807142) (xy 127.397256 -289.807142) (xy 127.397799 -289.781715) (xy 127.405629 -289.731468)
			(xy 127.42108 -289.683018) (xy 127.443786 -289.637514) (xy 127.473208 -289.596036) (xy 127.508648 -289.559565)
			(xy 127.549267 -289.528967) (xy 127.594101 -289.504967) (xy 127.642088 -289.488134) (xy 127.667004 -289.483038)
			(xy 127.691134 -289.478466) (xy 127.90551 -289.073082) (xy 127.895604 -289.050476) (xy 127.886643 -289.029398)
			(xy 127.873996 -288.985377) (xy 127.867582 -288.940026) (xy 127.867156 -288.917126) (xy 127.867664 -288.891219)
			(xy 127.87577 -288.840042) (xy 127.891782 -288.790763) (xy 127.915305 -288.744596) (xy 127.945761 -288.702677)
			(xy 127.982399 -288.666039) (xy 128.024318 -288.635583) (xy 128.070485 -288.61206) (xy 128.119764 -288.596048)
			(xy 128.170941 -288.587942) (xy 128.222755 -288.587942) (xy 128.273932 -288.596048) (xy 128.323211 -288.61206)
			(xy 128.369378 -288.635583) (xy 128.411297 -288.666039) (xy 128.447935 -288.702677) (xy 128.478391 -288.744596)
			(xy 128.501914 -288.790763) (xy 128.517926 -288.840042) (xy 128.526032 -288.891219) (xy 128.52654 -288.917126)
			(xy 128.526059 -288.942574) (xy 128.518256 -288.992867) (xy 128.502808 -289.041361) (xy 128.480083 -289.086901)
			(xy 128.450622 -289.128403) (xy 128.415127 -289.164878) (xy 128.374443 -289.195458) (xy 128.329539 -289.219415)
			(xy 128.281484 -289.236178) (xy 128.256538 -289.24123) (xy 128.232408 -289.245802) (xy 128.018032 -289.651186)
			(xy 128.027938 -289.673792) (xy 128.036856 -289.694878) (xy 128.049408 -289.738907) (xy 128.055742 -289.78425)
			(xy 128.056132 -289.807142) (xy 128.055624 -289.833029) (xy 128.055503 -289.833791) (xy 128.310884 -289.833791)
			(xy 128.310884 -289.780493) (xy 128.318827 -289.727789) (xy 128.334537 -289.676859) (xy 128.357663 -289.628838)
			(xy 128.387687 -289.584801) (xy 128.423939 -289.54573) (xy 128.46561 -289.512499) (xy 128.511768 -289.48585)
			(xy 128.561382 -289.466378) (xy 128.613344 -289.454518) (xy 128.666494 -289.450535) (xy 128.719644 -289.454518)
			(xy 128.771606 -289.466378) (xy 128.82122 -289.48585) (xy 128.867378 -289.512499) (xy 128.909049 -289.54573)
			(xy 128.945301 -289.584801) (xy 128.975325 -289.628838) (xy 128.998451 -289.676859) (xy 129.014161 -289.727789)
			(xy 129.022104 -289.780493) (xy 129.022602 -289.807142) (xy 129.276856 -289.807142) (xy 129.277399 -289.781715)
			(xy 129.285229 -289.731468) (xy 129.30068 -289.683018) (xy 129.323386 -289.637514) (xy 129.352808 -289.596036)
			(xy 129.388248 -289.559565) (xy 129.428867 -289.528967) (xy 129.473701 -289.504967) (xy 129.521688 -289.488134)
			(xy 129.546604 -289.483038) (xy 129.570734 -289.478466) (xy 129.78511 -289.073082) (xy 129.775204 -289.050476)
			(xy 129.766243 -289.029398) (xy 129.753596 -288.985377) (xy 129.747182 -288.940026) (xy 129.746756 -288.917126)
			(xy 129.747264 -288.891219) (xy 129.75537 -288.840042) (xy 129.771382 -288.790763) (xy 129.794905 -288.744596)
			(xy 129.825361 -288.702677) (xy 129.861999 -288.666039) (xy 129.903918 -288.635583) (xy 129.950085 -288.61206)
			(xy 129.999364 -288.596048) (xy 130.050541 -288.587942) (xy 130.102355 -288.587942) (xy 130.153532 -288.596048)
			(xy 130.202811 -288.61206) (xy 130.248978 -288.635583) (xy 130.290897 -288.666039) (xy 130.327535 -288.702677)
			(xy 130.357991 -288.744596) (xy 130.381514 -288.790763) (xy 130.397526 -288.840042) (xy 130.405632 -288.891219)
			(xy 130.40614 -288.917126) (xy 130.405659 -288.942574) (xy 130.397856 -288.992867) (xy 130.382408 -289.041361)
			(xy 130.359683 -289.086901) (xy 130.330222 -289.128403) (xy 130.294727 -289.164878) (xy 130.254043 -289.195458)
			(xy 130.209139 -289.219415) (xy 130.161084 -289.236178) (xy 130.136138 -289.24123) (xy 130.112008 -289.245802)
			(xy 129.897632 -289.651186) (xy 129.907538 -289.673792) (xy 129.916456 -289.694878) (xy 129.929008 -289.738907)
			(xy 129.935342 -289.78425) (xy 129.935732 -289.807142) (xy 129.935224 -289.833029) (xy 129.935103 -289.833791)
			(xy 130.190484 -289.833791) (xy 130.190484 -289.780493) (xy 130.198427 -289.727789) (xy 130.214137 -289.676859)
			(xy 130.237263 -289.628838) (xy 130.267287 -289.584801) (xy 130.303539 -289.54573) (xy 130.34521 -289.512499)
			(xy 130.391368 -289.48585) (xy 130.440982 -289.466378) (xy 130.492944 -289.454518) (xy 130.546094 -289.450535)
			(xy 130.599244 -289.454518) (xy 130.651206 -289.466378) (xy 130.70082 -289.48585) (xy 130.746978 -289.512499)
			(xy 130.788649 -289.54573) (xy 130.824901 -289.584801) (xy 130.854925 -289.628838) (xy 130.878051 -289.676859)
			(xy 130.893761 -289.727789) (xy 130.901704 -289.780493) (xy 130.902202 -289.807142) (xy 131.156456 -289.807142)
			(xy 131.156999 -289.781715) (xy 131.164829 -289.731468) (xy 131.18028 -289.683018) (xy 131.202986 -289.637514)
			(xy 131.232408 -289.596036) (xy 131.267848 -289.559565) (xy 131.308467 -289.528967) (xy 131.353301 -289.504967)
			(xy 131.401288 -289.488134) (xy 131.426204 -289.483038) (xy 131.450334 -289.478466) (xy 131.66471 -289.073082)
			(xy 131.654804 -289.050476) (xy 131.645843 -289.029398) (xy 131.633196 -288.985377) (xy 131.626782 -288.940026)
			(xy 131.626356 -288.917126) (xy 131.626864 -288.891219) (xy 131.63497 -288.840042) (xy 131.650982 -288.790763)
			(xy 131.674505 -288.744596) (xy 131.704961 -288.702677) (xy 131.741599 -288.666039) (xy 131.783518 -288.635583)
			(xy 131.829685 -288.61206) (xy 131.878964 -288.596048) (xy 131.930141 -288.587942) (xy 131.981955 -288.587942)
			(xy 132.033132 -288.596048) (xy 132.082411 -288.61206) (xy 132.128578 -288.635583) (xy 132.170497 -288.666039)
			(xy 132.207135 -288.702677) (xy 132.237591 -288.744596) (xy 132.261114 -288.790763) (xy 132.277126 -288.840042)
			(xy 132.285232 -288.891219) (xy 132.28574 -288.917126) (xy 132.285259 -288.942574) (xy 132.277456 -288.992867)
			(xy 132.262008 -289.041361) (xy 132.239283 -289.086901) (xy 132.209822 -289.128403) (xy 132.174327 -289.164878)
			(xy 132.133643 -289.195458) (xy 132.088739 -289.219415) (xy 132.040684 -289.236178) (xy 132.015738 -289.24123)
			(xy 131.991608 -289.245802) (xy 131.777232 -289.651186) (xy 131.787138 -289.673792) (xy 131.796056 -289.694878)
			(xy 131.808608 -289.738907) (xy 131.814942 -289.78425) (xy 131.815332 -289.807142) (xy 131.814824 -289.833029)
			(xy 131.814703 -289.833791) (xy 132.070084 -289.833791) (xy 132.070084 -289.780493) (xy 132.078027 -289.727789)
			(xy 132.093737 -289.676859) (xy 132.116863 -289.628838) (xy 132.146887 -289.584801) (xy 132.183139 -289.54573)
			(xy 132.22481 -289.512499) (xy 132.270968 -289.48585) (xy 132.320582 -289.466378) (xy 132.372544 -289.454518)
			(xy 132.425694 -289.450535) (xy 132.478844 -289.454518) (xy 132.530806 -289.466378) (xy 132.58042 -289.48585)
			(xy 132.626578 -289.512499) (xy 132.668249 -289.54573) (xy 132.704501 -289.584801) (xy 132.734525 -289.628838)
			(xy 132.757651 -289.676859) (xy 132.773361 -289.727789) (xy 132.781304 -289.780493) (xy 132.781802 -289.807142)
			(xy 133.036056 -289.807142) (xy 133.036599 -289.781715) (xy 133.044429 -289.731468) (xy 133.05988 -289.683018)
			(xy 133.082586 -289.637514) (xy 133.112008 -289.596036) (xy 133.147448 -289.559565) (xy 133.188067 -289.528967)
			(xy 133.232901 -289.504967) (xy 133.280888 -289.488134) (xy 133.305804 -289.483038) (xy 133.329934 -289.478466)
			(xy 133.54431 -289.073082) (xy 133.534404 -289.050476) (xy 133.525443 -289.029398) (xy 133.512796 -288.985377)
			(xy 133.506382 -288.940026) (xy 133.505956 -288.917126) (xy 133.506464 -288.891219) (xy 133.51457 -288.840042)
			(xy 133.530582 -288.790763) (xy 133.554105 -288.744596) (xy 133.584561 -288.702677) (xy 133.621199 -288.666039)
			(xy 133.663118 -288.635583) (xy 133.709285 -288.61206) (xy 133.758564 -288.596048) (xy 133.809741 -288.587942)
			(xy 133.861555 -288.587942) (xy 133.912732 -288.596048) (xy 133.962011 -288.61206) (xy 134.008178 -288.635583)
			(xy 134.050097 -288.666039) (xy 134.086735 -288.702677) (xy 134.117191 -288.744596) (xy 134.140714 -288.790763)
			(xy 134.156726 -288.840042) (xy 134.164832 -288.891219) (xy 134.16534 -288.917126) (xy 134.164859 -288.942574)
			(xy 134.164673 -288.943775) (xy 134.419838 -288.943775) (xy 134.419838 -288.890477) (xy 134.427781 -288.837773)
			(xy 134.443491 -288.786843) (xy 134.466617 -288.738822) (xy 134.496641 -288.694785) (xy 134.532893 -288.655714)
			(xy 134.574564 -288.622483) (xy 134.620722 -288.595834) (xy 134.670336 -288.576362) (xy 134.722298 -288.564502)
			(xy 134.775448 -288.560519) (xy 134.828598 -288.564502) (xy 134.88056 -288.576362) (xy 134.930174 -288.595834)
			(xy 134.976332 -288.622483) (xy 135.018003 -288.655714) (xy 135.054255 -288.694785) (xy 135.084279 -288.738822)
			(xy 135.107405 -288.786843) (xy 135.123115 -288.837773) (xy 135.131058 -288.890477) (xy 135.131556 -288.917126)
			(xy 135.131058 -288.943775) (xy 135.123115 -288.996479) (xy 135.107405 -289.047409) (xy 135.084279 -289.09543)
			(xy 135.054255 -289.139467) (xy 135.018003 -289.178538) (xy 134.976332 -289.211769) (xy 134.930174 -289.238418)
			(xy 134.88056 -289.25789) (xy 134.828598 -289.26975) (xy 134.775448 -289.273734) (xy 134.722298 -289.26975)
			(xy 134.670336 -289.25789) (xy 134.620722 -289.238418) (xy 134.574564 -289.211769) (xy 134.532893 -289.178538)
			(xy 134.496641 -289.139467) (xy 134.466617 -289.09543) (xy 134.443491 -289.047409) (xy 134.427781 -288.996479)
			(xy 134.419838 -288.943775) (xy 134.164673 -288.943775) (xy 134.157056 -288.992867) (xy 134.141608 -289.041361)
			(xy 134.118883 -289.086901) (xy 134.089422 -289.128403) (xy 134.053927 -289.164878) (xy 134.013243 -289.195458)
			(xy 133.968339 -289.219415) (xy 133.920284 -289.236178) (xy 133.895338 -289.24123) (xy 133.871208 -289.245802)
			(xy 133.656832 -289.651186) (xy 133.666738 -289.673792) (xy 133.675656 -289.694878) (xy 133.688208 -289.738907)
			(xy 133.694542 -289.78425) (xy 133.694932 -289.807142) (xy 133.694424 -289.833029) (xy 133.686325 -289.884167)
			(xy 133.670326 -289.933407) (xy 133.64682 -289.979539) (xy 133.616388 -290.021426) (xy 133.579778 -290.058036)
			(xy 133.537891 -290.088468) (xy 133.491759 -290.111974) (xy 133.442519 -290.127973) (xy 133.391381 -290.136072)
			(xy 133.339607 -290.136072) (xy 133.288469 -290.127973) (xy 133.239229 -290.111974) (xy 133.193097 -290.088468)
			(xy 133.15121 -290.058036) (xy 133.1146 -290.021426) (xy 133.084168 -289.979539) (xy 133.060662 -289.933407)
			(xy 133.044663 -289.884167) (xy 133.036564 -289.833029) (xy 133.036056 -289.807142) (xy 132.781802 -289.807142)
			(xy 132.781304 -289.833791) (xy 132.773361 -289.886495) (xy 132.757651 -289.937425) (xy 132.734525 -289.985446)
			(xy 132.704501 -290.029483) (xy 132.668249 -290.068554) (xy 132.626578 -290.101785) (xy 132.58042 -290.128434)
			(xy 132.530806 -290.147906) (xy 132.478844 -290.159766) (xy 132.425694 -290.16375) (xy 132.372544 -290.159766)
			(xy 132.320582 -290.147906) (xy 132.270968 -290.128434) (xy 132.22481 -290.101785) (xy 132.183139 -290.068554)
			(xy 132.146887 -290.029483) (xy 132.116863 -289.985446) (xy 132.093737 -289.937425) (xy 132.078027 -289.886495)
			(xy 132.070084 -289.833791) (xy 131.814703 -289.833791) (xy 131.806725 -289.884167) (xy 131.790726 -289.933407)
			(xy 131.76722 -289.979539) (xy 131.736788 -290.021426) (xy 131.700178 -290.058036) (xy 131.658291 -290.088468)
			(xy 131.612159 -290.111974) (xy 131.562919 -290.127973) (xy 131.511781 -290.136072) (xy 131.460007 -290.136072)
			(xy 131.408869 -290.127973) (xy 131.359629 -290.111974) (xy 131.313497 -290.088468) (xy 131.27161 -290.058036)
			(xy 131.235 -290.021426) (xy 131.204568 -289.979539) (xy 131.181062 -289.933407) (xy 131.165063 -289.884167)
			(xy 131.156964 -289.833029) (xy 131.156456 -289.807142) (xy 130.902202 -289.807142) (xy 130.901704 -289.833791)
			(xy 130.893761 -289.886495) (xy 130.878051 -289.937425) (xy 130.854925 -289.985446) (xy 130.824901 -290.029483)
			(xy 130.788649 -290.068554) (xy 130.746978 -290.101785) (xy 130.70082 -290.128434) (xy 130.651206 -290.147906)
			(xy 130.599244 -290.159766) (xy 130.546094 -290.16375) (xy 130.492944 -290.159766) (xy 130.440982 -290.147906)
			(xy 130.391368 -290.128434) (xy 130.34521 -290.101785) (xy 130.303539 -290.068554) (xy 130.267287 -290.029483)
			(xy 130.237263 -289.985446) (xy 130.214137 -289.937425) (xy 130.198427 -289.886495) (xy 130.190484 -289.833791)
			(xy 129.935103 -289.833791) (xy 129.927125 -289.884167) (xy 129.911126 -289.933407) (xy 129.88762 -289.979539)
			(xy 129.857188 -290.021426) (xy 129.820578 -290.058036) (xy 129.778691 -290.088468) (xy 129.732559 -290.111974)
			(xy 129.683319 -290.127973) (xy 129.632181 -290.136072) (xy 129.580407 -290.136072) (xy 129.529269 -290.127973)
			(xy 129.480029 -290.111974) (xy 129.433897 -290.088468) (xy 129.39201 -290.058036) (xy 129.3554 -290.021426)
			(xy 129.324968 -289.979539) (xy 129.301462 -289.933407) (xy 129.285463 -289.884167) (xy 129.277364 -289.833029)
			(xy 129.276856 -289.807142) (xy 129.022602 -289.807142) (xy 129.022104 -289.833791) (xy 129.014161 -289.886495)
			(xy 128.998451 -289.937425) (xy 128.975325 -289.985446) (xy 128.945301 -290.029483) (xy 128.909049 -290.068554)
			(xy 128.867378 -290.101785) (xy 128.82122 -290.128434) (xy 128.771606 -290.147906) (xy 128.719644 -290.159766)
			(xy 128.666494 -290.16375) (xy 128.613344 -290.159766) (xy 128.561382 -290.147906) (xy 128.511768 -290.128434)
			(xy 128.46561 -290.101785) (xy 128.423939 -290.068554) (xy 128.387687 -290.029483) (xy 128.357663 -289.985446)
			(xy 128.334537 -289.937425) (xy 128.318827 -289.886495) (xy 128.310884 -289.833791) (xy 128.055503 -289.833791)
			(xy 128.047525 -289.884167) (xy 128.031526 -289.933407) (xy 128.00802 -289.979539) (xy 127.977588 -290.021426)
			(xy 127.940978 -290.058036) (xy 127.899091 -290.088468) (xy 127.852959 -290.111974) (xy 127.803719 -290.127973)
			(xy 127.752581 -290.136072) (xy 127.700807 -290.136072) (xy 127.649669 -290.127973) (xy 127.600429 -290.111974)
			(xy 127.554297 -290.088468) (xy 127.51241 -290.058036) (xy 127.4758 -290.021426) (xy 127.445368 -289.979539)
			(xy 127.421862 -289.933407) (xy 127.405863 -289.884167) (xy 127.397764 -289.833029) (xy 127.397256 -289.807142)
			(xy 127.143002 -289.807142) (xy 127.142504 -289.833791) (xy 127.134561 -289.886495) (xy 127.118851 -289.937425)
			(xy 127.095725 -289.985446) (xy 127.065701 -290.029483) (xy 127.029449 -290.068554) (xy 126.987778 -290.101785)
			(xy 126.94162 -290.128434) (xy 126.892006 -290.147906) (xy 126.840044 -290.159766) (xy 126.786894 -290.16375)
			(xy 126.733744 -290.159766) (xy 126.681782 -290.147906) (xy 126.632168 -290.128434) (xy 126.58601 -290.101785)
			(xy 126.544339 -290.068554) (xy 126.508087 -290.029483) (xy 126.478063 -289.985446) (xy 126.454937 -289.937425)
			(xy 126.439227 -289.886495) (xy 126.431284 -289.833791) (xy 126.175903 -289.833791) (xy 126.167925 -289.884167)
			(xy 126.151926 -289.933407) (xy 126.12842 -289.979539) (xy 126.097988 -290.021426) (xy 126.061378 -290.058036)
			(xy 126.019491 -290.088468) (xy 125.973359 -290.111974) (xy 125.924119 -290.127973) (xy 125.872981 -290.136072)
			(xy 125.821207 -290.136072) (xy 125.770069 -290.127973) (xy 125.720829 -290.111974) (xy 125.674697 -290.088468)
			(xy 125.63281 -290.058036) (xy 125.5962 -290.021426) (xy 125.565768 -289.979539) (xy 125.542262 -289.933407)
			(xy 125.526263 -289.884167) (xy 125.518164 -289.833029) (xy 125.517656 -289.807142) (xy 125.263402 -289.807142)
			(xy 125.262904 -289.833791) (xy 125.254961 -289.886495) (xy 125.239251 -289.937425) (xy 125.216125 -289.985446)
			(xy 125.186101 -290.029483) (xy 125.149849 -290.068554) (xy 125.108178 -290.101785) (xy 125.06202 -290.128434)
			(xy 125.012406 -290.147906) (xy 124.960444 -290.159766) (xy 124.907294 -290.16375) (xy 124.854144 -290.159766)
			(xy 124.802182 -290.147906) (xy 124.752568 -290.128434) (xy 124.70641 -290.101785) (xy 124.664739 -290.068554)
			(xy 124.628487 -290.029483) (xy 124.598463 -289.985446) (xy 124.575337 -289.937425) (xy 124.559627 -289.886495)
			(xy 124.551684 -289.833791) (xy 124.296303 -289.833791) (xy 124.288325 -289.884167) (xy 124.272326 -289.933407)
			(xy 124.24882 -289.979539) (xy 124.218388 -290.021426) (xy 124.181778 -290.058036) (xy 124.139891 -290.088468)
			(xy 124.093759 -290.111974) (xy 124.044519 -290.127973) (xy 123.993381 -290.136072) (xy 123.941607 -290.136072)
			(xy 123.890469 -290.127973) (xy 123.841229 -290.111974) (xy 123.795097 -290.088468) (xy 123.75321 -290.058036)
			(xy 123.7166 -290.021426) (xy 123.686168 -289.979539) (xy 123.662662 -289.933407) (xy 123.646663 -289.884167)
			(xy 123.638564 -289.833029) (xy 123.638056 -289.807142) (xy 123.383802 -289.807142) (xy 123.383304 -289.833791)
			(xy 123.375361 -289.886495) (xy 123.359651 -289.937425) (xy 123.336525 -289.985446) (xy 123.306501 -290.029483)
			(xy 123.270249 -290.068554) (xy 123.228578 -290.101785) (xy 123.18242 -290.128434) (xy 123.132806 -290.147906)
			(xy 123.080844 -290.159766) (xy 123.027694 -290.16375) (xy 122.974544 -290.159766) (xy 122.922582 -290.147906)
			(xy 122.872968 -290.128434) (xy 122.82681 -290.101785) (xy 122.785139 -290.068554) (xy 122.748887 -290.029483)
			(xy 122.718863 -289.985446) (xy 122.695737 -289.937425) (xy 122.680027 -289.886495) (xy 122.672084 -289.833791)
			(xy 122.416703 -289.833791) (xy 122.408725 -289.884167) (xy 122.392726 -289.933407) (xy 122.36922 -289.979539)
			(xy 122.338788 -290.021426) (xy 122.302178 -290.058036) (xy 122.260291 -290.088468) (xy 122.214159 -290.111974)
			(xy 122.164919 -290.127973) (xy 122.113781 -290.136072) (xy 122.062007 -290.136072) (xy 122.010869 -290.127973)
			(xy 121.961629 -290.111974) (xy 121.915497 -290.088468) (xy 121.87361 -290.058036) (xy 121.837 -290.021426)
			(xy 121.806568 -289.979539) (xy 121.783062 -289.933407) (xy 121.767063 -289.884167) (xy 121.758964 -289.833029)
			(xy 121.758456 -289.807142) (xy 121.504202 -289.807142) (xy 121.503704 -289.833791) (xy 121.495761 -289.886495)
			(xy 121.480051 -289.937425) (xy 121.456925 -289.985446) (xy 121.426901 -290.029483) (xy 121.390649 -290.068554)
			(xy 121.348978 -290.101785) (xy 121.30282 -290.128434) (xy 121.253206 -290.147906) (xy 121.201244 -290.159766)
			(xy 121.148094 -290.16375) (xy 121.094944 -290.159766) (xy 121.042982 -290.147906) (xy 120.993368 -290.128434)
			(xy 120.94721 -290.101785) (xy 120.905539 -290.068554) (xy 120.869287 -290.029483) (xy 120.839263 -289.985446)
			(xy 120.816137 -289.937425) (xy 120.800427 -289.886495) (xy 120.792484 -289.833791) (xy 120.537103 -289.833791)
			(xy 120.529125 -289.884167) (xy 120.513126 -289.933407) (xy 120.48962 -289.979539) (xy 120.459188 -290.021426)
			(xy 120.422578 -290.058036) (xy 120.380691 -290.088468) (xy 120.334559 -290.111974) (xy 120.285319 -290.127973)
			(xy 120.234181 -290.136072) (xy 120.182407 -290.136072) (xy 120.131269 -290.127973) (xy 120.082029 -290.111974)
			(xy 120.035897 -290.088468) (xy 119.99401 -290.058036) (xy 119.9574 -290.021426) (xy 119.926968 -289.979539)
			(xy 119.903462 -289.933407) (xy 119.887463 -289.884167) (xy 119.879364 -289.833029) (xy 119.878856 -289.807142)
			(xy 119.624602 -289.807142) (xy 119.624104 -289.833791) (xy 119.616161 -289.886495) (xy 119.600451 -289.937425)
			(xy 119.577325 -289.985446) (xy 119.547301 -290.029483) (xy 119.511049 -290.068554) (xy 119.469378 -290.101785)
			(xy 119.42322 -290.128434) (xy 119.373606 -290.147906) (xy 119.321644 -290.159766) (xy 119.268494 -290.16375)
			(xy 119.215344 -290.159766) (xy 119.163382 -290.147906) (xy 119.113768 -290.128434) (xy 119.06761 -290.101785)
			(xy 119.025939 -290.068554) (xy 118.989687 -290.029483) (xy 118.959663 -289.985446) (xy 118.936537 -289.937425)
			(xy 118.920827 -289.886495) (xy 118.912884 -289.833791) (xy 105.50169 -289.833791) (xy 105.50169 -289.833815)
			(xy 105.493124 -289.886468) (xy 105.476219 -289.937064) (xy 105.451415 -289.984292) (xy 105.419354 -290.026928)
			(xy 105.380867 -290.063866) (xy 105.3592 -290.07943) (xy 105.355644 -290.081716) (xy 105.347399 -290.089324)
			(xy 105.33792 -290.109626) (xy 105.337356 -290.120832) (xy 105.337356 -290.218368) (xy 105.336876 -290.25403)
			(xy 105.328892 -290.324906) (xy 105.313021 -290.394442) (xy 105.289462 -290.461763) (xy 105.258512 -290.526023)
			(xy 105.22056 -290.586411) (xy 105.176084 -290.64217) (xy 105.151174 -290.667694) (xy 103.800148 -292.01872)
			(xy 103.774606 -292.043548) (xy 103.718907 -292.087956) (xy 103.65859 -292.125853) (xy 103.594411 -292.156764)
			(xy 103.527177 -292.180299) (xy 103.457732 -292.196165) (xy 103.386947 -292.20416) (xy 103.35133 -292.204648)
			(xy 101.444044 -292.204648) (xy 101.434082 -292.205134) (xy 101.41566 -292.212724) (xy 101.40823 -292.21938)
			(xy 101.084888 -292.542976) (xy 101.059344 -292.5678) (xy 101.003643 -292.612198) (xy 100.943324 -292.650086)
			(xy 100.879144 -292.680988) (xy 100.811911 -292.704515) (xy 100.742467 -292.720373) (xy 100.671685 -292.728361)
			(xy 100.63607 -292.728904) (xy 80.887824 -292.728904) (xy 80.87776 -292.729341) (xy 80.859176 -292.737075)
			(xy 80.851756 -292.74389) (xy 79.086964 -294.508682) (xy 79.080281 -294.516092) (xy 79.072698 -294.534528)
			(xy 79.072232 -294.544496) (xy 79.072232 -297.515026) (xy 88.21548 -297.515026) (xy 88.219461 -297.382006)
			(xy 88.23139 -297.249461) (xy 88.251225 -297.117868) (xy 88.278894 -296.987696) (xy 88.314298 -296.859411)
			(xy 88.357311 -296.733474) (xy 88.407778 -296.610335) (xy 88.465519 -296.490434) (xy 88.530328 -296.374201)
			(xy 88.601972 -296.262051) (xy 88.680194 -296.154387) (xy 88.764715 -296.051594) (xy 88.855233 -295.954039)
			(xy 88.951422 -295.862073) (xy 89.05294 -295.776023) (xy 89.159421 -295.696199) (xy 89.270486 -295.622886)
			(xy 89.385737 -295.556346) (xy 89.504761 -295.496817) (xy 89.627132 -295.444513) (xy 89.752411 -295.399621)
			(xy 89.880152 -295.362302) (xy 90.009895 -295.332689) (xy 90.141177 -295.310888) (xy 90.273528 -295.296978)
			(xy 90.406474 -295.291007) (xy 90.539539 -295.292998) (xy 90.672247 -295.302943) (xy 90.804123 -295.320807)
			(xy 90.934694 -295.346525) (xy 91.063494 -295.380006) (xy 91.19006 -295.42113) (xy 91.313941 -295.46975)
			(xy 91.434692 -295.525691) (xy 91.551882 -295.588753) (xy 91.665091 -295.658711) (xy 91.773913 -295.735315)
			(xy 91.877959 -295.818289) (xy 91.976857 -295.907337) (xy 92.070252 -296.00214) (xy 92.15781 -296.102358)
			(xy 92.239219 -296.207634) (xy 92.314185 -296.31759) (xy 92.382442 -296.431832) (xy 92.443744 -296.549952)
			(xy 92.497873 -296.671527) (xy 92.544634 -296.796121) (xy 92.58386 -296.923289) (xy 92.61541 -297.052575)
			(xy 92.639173 -297.183516) (xy 92.652434 -297.293792) (xy 102.67696 -297.293792) (xy 102.67696 -292.764972)
			(xy 103.123238 -292.318948) (xy 105.158286 -292.318948) (xy 105.507028 -292.667182) (xy 105.507028 -297.320462)
			(xy 105.498905 -297.32859) (xy 109.013752 -297.32859) (xy 109.013752 -292.720522) (xy 109.415326 -292.318948)
			(xy 111.450628 -292.318948) (xy 111.843312 -292.711378) (xy 111.843312 -297.313858) (xy 111.826558 -297.330622)
			(xy 115.373912 -297.330622) (xy 115.373912 -292.693598) (xy 115.733576 -292.33368) (xy 117.808756 -292.33368)
			(xy 118.20652 -292.731698) (xy 118.20652 -297.335956) (xy 117.962426 -297.58005) (xy 121.723912 -297.58005)
			(xy 121.723912 -292.690804) (xy 122.027696 -292.38702) (xy 122.995436 -292.38702) (xy 123.28144 -292.673024)
			(xy 123.28144 -297.515026) (xy 131.195582 -297.515026) (xy 131.199563 -297.382006) (xy 131.211492 -297.249461)
			(xy 131.231327 -297.117868) (xy 131.258996 -296.987696) (xy 131.2944 -296.859411) (xy 131.337413 -296.733474)
			(xy 131.38788 -296.610335) (xy 131.445621 -296.490434) (xy 131.51043 -296.374201) (xy 131.582074 -296.262051)
			(xy 131.660296 -296.154387) (xy 131.744817 -296.051594) (xy 131.835335 -295.954039) (xy 131.931524 -295.862073)
			(xy 132.033042 -295.776023) (xy 132.139523 -295.696199) (xy 132.250588 -295.622886) (xy 132.365839 -295.556346)
			(xy 132.484863 -295.496817) (xy 132.607234 -295.444513) (xy 132.732513 -295.399621) (xy 132.860254 -295.362302)
			(xy 132.989997 -295.332689) (xy 133.121279 -295.310888) (xy 133.25363 -295.296978) (xy 133.386576 -295.291007)
			(xy 133.519641 -295.292998) (xy 133.652349 -295.302943) (xy 133.784225 -295.320807) (xy 133.914796 -295.346525)
			(xy 134.043596 -295.380006) (xy 134.170162 -295.42113) (xy 134.294043 -295.46975) (xy 134.414794 -295.525691)
			(xy 134.531984 -295.588753) (xy 134.645193 -295.658711) (xy 134.754015 -295.735315) (xy 134.858061 -295.818289)
			(xy 134.956959 -295.907337) (xy 135.050354 -296.00214) (xy 135.137912 -296.102358) (xy 135.219321 -296.207634)
			(xy 135.294287 -296.31759) (xy 135.362544 -296.431832) (xy 135.423846 -296.549952) (xy 135.477975 -296.671527)
			(xy 135.524736 -296.796121) (xy 135.563962 -296.923289) (xy 135.595512 -297.052575) (xy 135.619275 -297.183516)
			(xy 135.635164 -297.315644) (xy 135.643122 -297.448486) (xy 135.64362 -297.515026) (xy 135.643122 -297.581566)
			(xy 135.635164 -297.714408) (xy 135.619275 -297.846536) (xy 135.595512 -297.977477) (xy 135.563962 -298.106763)
			(xy 135.524736 -298.233931) (xy 135.477975 -298.358525) (xy 135.423846 -298.4801) (xy 135.362544 -298.59822)
			(xy 135.294287 -298.712462) (xy 135.219321 -298.822418) (xy 135.137912 -298.927694) (xy 135.050354 -299.027912)
			(xy 134.956959 -299.122715) (xy 134.858061 -299.211763) (xy 134.754015 -299.294737) (xy 134.645193 -299.371341)
			(xy 134.531984 -299.441299) (xy 134.414794 -299.504361) (xy 134.294043 -299.560302) (xy 134.170162 -299.608922)
			(xy 134.043596 -299.650046) (xy 133.914796 -299.683527) (xy 133.784225 -299.709245) (xy 133.652349 -299.727109)
			(xy 133.519641 -299.737054) (xy 133.386576 -299.739045) (xy 133.25363 -299.733074) (xy 133.121279 -299.719164)
			(xy 132.989997 -299.697363) (xy 132.860254 -299.66775) (xy 132.732513 -299.630431) (xy 132.607234 -299.585539)
			(xy 132.484863 -299.533235) (xy 132.365839 -299.473706) (xy 132.250588 -299.407166) (xy 132.139523 -299.333853)
			(xy 132.033042 -299.254029) (xy 131.931524 -299.167979) (xy 131.835335 -299.076013) (xy 131.744817 -298.978458)
			(xy 131.660296 -298.875665) (xy 131.582074 -298.768001) (xy 131.51043 -298.655851) (xy 131.445621 -298.539618)
			(xy 131.38788 -298.419717) (xy 131.337413 -298.296578) (xy 131.2944 -298.170641) (xy 131.258996 -298.042356)
			(xy 131.231327 -297.912184) (xy 131.211492 -297.780591) (xy 131.199563 -297.648046) (xy 131.195582 -297.515026)
			(xy 123.28144 -297.515026) (xy 123.28144 -297.58767) (xy 122.992642 -297.876468) (xy 122.02033 -297.876468)
			(xy 121.723912 -297.58005) (xy 117.962426 -297.58005) (xy 117.790976 -297.7515) (xy 115.79479 -297.7515)
			(xy 115.373912 -297.330622) (xy 111.826558 -297.330622) (xy 111.420656 -297.736768) (xy 109.421676 -297.736768)
			(xy 109.013752 -297.32859) (xy 105.498905 -297.32859) (xy 105.090976 -297.736768) (xy 103.119936 -297.736768)
			(xy 102.67696 -297.293792) (xy 92.652434 -297.293792) (xy 92.655062 -297.315644) (xy 92.66302 -297.448486)
			(xy 92.663518 -297.515026) (xy 92.66302 -297.581566) (xy 92.655062 -297.714408) (xy 92.639173 -297.846536)
			(xy 92.61541 -297.977477) (xy 92.58386 -298.106763) (xy 92.544634 -298.233931) (xy 92.497873 -298.358525)
			(xy 92.443744 -298.4801) (xy 92.382442 -298.59822) (xy 92.314185 -298.712462) (xy 92.239219 -298.822418)
			(xy 92.15781 -298.927694) (xy 92.070252 -299.027912) (xy 91.976857 -299.122715) (xy 91.877959 -299.211763)
			(xy 91.773913 -299.294737) (xy 91.665091 -299.371341) (xy 91.551882 -299.441299) (xy 91.434692 -299.504361)
			(xy 91.313941 -299.560302) (xy 91.19006 -299.608922) (xy 91.063494 -299.650046) (xy 90.934694 -299.683527)
			(xy 90.804123 -299.709245) (xy 90.672247 -299.727109) (xy 90.539539 -299.737054) (xy 90.406474 -299.739045)
			(xy 90.273528 -299.733074) (xy 90.141177 -299.719164) (xy 90.009895 -299.697363) (xy 89.880152 -299.66775)
			(xy 89.752411 -299.630431) (xy 89.627132 -299.585539) (xy 89.504761 -299.533235) (xy 89.385737 -299.473706)
			(xy 89.270486 -299.407166) (xy 89.159421 -299.333853) (xy 89.05294 -299.254029) (xy 88.951422 -299.167979)
			(xy 88.855233 -299.076013) (xy 88.764715 -298.978458) (xy 88.680194 -298.875665) (xy 88.601972 -298.768001)
			(xy 88.530328 -298.655851) (xy 88.465519 -298.539618) (xy 88.407778 -298.419717) (xy 88.357311 -298.296578)
			(xy 88.314298 -298.170641) (xy 88.278894 -298.042356) (xy 88.251225 -297.912184) (xy 88.23139 -297.780591)
			(xy 88.219461 -297.648046) (xy 88.21548 -297.515026) (xy 79.072232 -297.515026) (xy 79.072232 -316.45479)
			(xy 97.636584 -316.45479) (xy 97.636584 -314.87999) (xy 97.636934 -314.866629) (xy 97.643854 -314.840819)
			(xy 97.657219 -314.81768) (xy 97.676119 -314.79879) (xy 97.699264 -314.785435) (xy 97.725077 -314.778528)
			(xy 97.738438 -314.778136) (xy 99.313238 -314.778136) (xy 99.326591 -314.778548) (xy 99.352385 -314.785468)
			(xy 99.37551 -314.798826) (xy 99.394391 -314.817713) (xy 99.407743 -314.840841) (xy 99.414655 -314.866637)
			(xy 99.415092 -314.87999) (xy 99.415092 -315.66739) (xy 99.610423 -315.66739) (xy 99.614445 -315.58167)
			(xy 99.626476 -315.496702) (xy 99.646412 -315.413235) (xy 99.674075 -315.332001) (xy 99.709224 -315.253715)
			(xy 99.75155 -315.179064) (xy 99.800679 -315.108705) (xy 99.856182 -315.043255) (xy 99.917569 -314.983291)
			(xy 99.984302 -314.929338) (xy 100.055794 -314.881871) (xy 100.131416 -314.841307) (xy 100.210505 -314.808003)
			(xy 100.292365 -314.782251) (xy 100.376276 -314.764278) (xy 100.461502 -314.754242) (xy 100.547294 -314.75223)
			(xy 100.632896 -314.758261) (xy 100.717558 -314.772281) (xy 100.800535 -314.794167) (xy 100.881098 -314.823728)
			(xy 100.958538 -314.860702) (xy 101.032177 -314.904766) (xy 101.101365 -314.955532) (xy 101.165496 -315.012553)
			(xy 101.224005 -315.075329) (xy 101.276378 -315.143309) (xy 101.322156 -315.215894) (xy 101.360936 -315.292446)
			(xy 101.392377 -315.372294) (xy 101.416203 -315.454735) (xy 101.432204 -315.539045) (xy 101.440239 -315.624483)
			(xy 101.440742 -315.66739) (xy 101.440239 -315.710297) (xy 101.432204 -315.795735) (xy 101.416203 -315.880045)
			(xy 101.392377 -315.962486) (xy 101.360936 -316.042334) (xy 101.322156 -316.118886) (xy 101.276378 -316.191471)
			(xy 101.224005 -316.259451) (xy 101.165496 -316.322227) (xy 101.101365 -316.379248) (xy 101.032177 -316.430014)
			(xy 100.990772 -316.45479) (xy 103.834184 -316.45479) (xy 103.834184 -314.87999) (xy 103.834534 -314.866629)
			(xy 103.841454 -314.840819) (xy 103.854819 -314.81768) (xy 103.873719 -314.79879) (xy 103.896864 -314.785435)
			(xy 103.922677 -314.778528) (xy 103.936038 -314.778136) (xy 105.510838 -314.778136) (xy 105.524191 -314.778548)
			(xy 105.549985 -314.785468) (xy 105.57311 -314.798826) (xy 105.591991 -314.817713) (xy 105.605343 -314.840841)
			(xy 105.612255 -314.866637) (xy 105.612692 -314.87999) (xy 105.612692 -315.66739) (xy 105.808023 -315.66739)
			(xy 105.812045 -315.58167) (xy 105.824076 -315.496702) (xy 105.844012 -315.413235) (xy 105.871675 -315.332001)
			(xy 105.906824 -315.253715) (xy 105.94915 -315.179064) (xy 105.998279 -315.108705) (xy 106.053782 -315.043255)
			(xy 106.115169 -314.983291) (xy 106.181902 -314.929338) (xy 106.253394 -314.881871) (xy 106.329016 -314.841307)
			(xy 106.408105 -314.808003) (xy 106.489965 -314.782251) (xy 106.573876 -314.764278) (xy 106.659102 -314.754242)
			(xy 106.744894 -314.75223) (xy 106.830496 -314.758261) (xy 106.915158 -314.772281) (xy 106.998135 -314.794167)
			(xy 107.078698 -314.823728) (xy 107.156138 -314.860702) (xy 107.229777 -314.904766) (xy 107.298965 -314.955532)
			(xy 107.363096 -315.012553) (xy 107.421605 -315.075329) (xy 107.473978 -315.143309) (xy 107.519756 -315.215894)
			(xy 107.558536 -315.292446) (xy 107.589977 -315.372294) (xy 107.613803 -315.454735) (xy 107.629804 -315.539045)
			(xy 107.637839 -315.624483) (xy 107.638342 -315.66739) (xy 107.637839 -315.710297) (xy 107.629804 -315.795735)
			(xy 107.613803 -315.880045) (xy 107.589977 -315.962486) (xy 107.558536 -316.042334) (xy 107.519756 -316.118886)
			(xy 107.473978 -316.191471) (xy 107.421605 -316.259451) (xy 107.363096 -316.322227) (xy 107.298965 -316.379248)
			(xy 107.229777 -316.430014) (xy 107.188372 -316.45479) (xy 110.011972 -316.45479) (xy 110.011972 -314.87999)
			(xy 110.012334 -314.86663) (xy 110.019253 -314.840822) (xy 110.032616 -314.817684) (xy 110.051513 -314.798794)
			(xy 110.074655 -314.785439) (xy 110.100466 -314.778529) (xy 110.113826 -314.778136) (xy 111.688626 -314.778136)
			(xy 111.701978 -314.778559) (xy 111.727772 -314.785476) (xy 111.750897 -314.798831) (xy 111.769779 -314.817716)
			(xy 111.783131 -314.840843) (xy 111.790043 -314.866638) (xy 111.79048 -314.87999) (xy 111.79048 -315.66739)
			(xy 111.985811 -315.66739) (xy 111.989833 -315.58167) (xy 112.001864 -315.496702) (xy 112.0218 -315.413235)
			(xy 112.049463 -315.332001) (xy 112.084612 -315.253715) (xy 112.126938 -315.179064) (xy 112.176067 -315.108705)
			(xy 112.23157 -315.043255) (xy 112.292957 -314.983291) (xy 112.35969 -314.929338) (xy 112.431182 -314.881871)
			(xy 112.506804 -314.841307) (xy 112.585893 -314.808003) (xy 112.667753 -314.782251) (xy 112.751664 -314.764278)
			(xy 112.83689 -314.754242) (xy 112.922682 -314.75223) (xy 113.008284 -314.758261) (xy 113.092946 -314.772281)
			(xy 113.175923 -314.794167) (xy 113.256486 -314.823728) (xy 113.333926 -314.860702) (xy 113.407565 -314.904766)
			(xy 113.476753 -314.955532) (xy 113.540884 -315.012553) (xy 113.599393 -315.075329) (xy 113.651766 -315.143309)
			(xy 113.697544 -315.215894) (xy 113.736324 -315.292446) (xy 113.767765 -315.372294) (xy 113.791591 -315.454735)
			(xy 113.807592 -315.539045) (xy 113.815627 -315.624483) (xy 113.81613 -315.66739) (xy 113.815627 -315.710297)
			(xy 113.807592 -315.795735) (xy 113.791591 -315.880045) (xy 113.767765 -315.962486) (xy 113.736324 -316.042334)
			(xy 113.697544 -316.118886) (xy 113.651766 -316.191471) (xy 113.599393 -316.259451) (xy 113.540884 -316.322227)
			(xy 113.476753 -316.379248) (xy 113.407565 -316.430014) (xy 113.36616 -316.45479) (xy 116.209572 -316.45479)
			(xy 116.209572 -314.87999) (xy 116.209934 -314.86663) (xy 116.216853 -314.840822) (xy 116.230216 -314.817684)
			(xy 116.249113 -314.798794) (xy 116.272255 -314.785439) (xy 116.298066 -314.778529) (xy 116.311426 -314.778136)
			(xy 117.886226 -314.778136) (xy 117.899578 -314.778559) (xy 117.925372 -314.785476) (xy 117.948497 -314.798831)
			(xy 117.967379 -314.817716) (xy 117.980731 -314.840843) (xy 117.987643 -314.866638) (xy 117.98808 -314.87999)
			(xy 117.98808 -315.66739) (xy 118.183411 -315.66739) (xy 118.187433 -315.58167) (xy 118.199464 -315.496702)
			(xy 118.2194 -315.413235) (xy 118.247063 -315.332001) (xy 118.282212 -315.253715) (xy 118.324538 -315.179064)
			(xy 118.373667 -315.108705) (xy 118.42917 -315.043255) (xy 118.490557 -314.983291) (xy 118.55729 -314.929338)
			(xy 118.628782 -314.881871) (xy 118.704404 -314.841307) (xy 118.783493 -314.808003) (xy 118.865353 -314.782251)
			(xy 118.949264 -314.764278) (xy 119.03449 -314.754242) (xy 119.120282 -314.75223) (xy 119.205884 -314.758261)
			(xy 119.290546 -314.772281) (xy 119.373523 -314.794167) (xy 119.454086 -314.823728) (xy 119.531526 -314.860702)
			(xy 119.605165 -314.904766) (xy 119.674353 -314.955532) (xy 119.738484 -315.012553) (xy 119.796993 -315.075329)
			(xy 119.849366 -315.143309) (xy 119.895144 -315.215894) (xy 119.933924 -315.292446) (xy 119.965365 -315.372294)
			(xy 119.989191 -315.454735) (xy 120.005192 -315.539045) (xy 120.013227 -315.624483) (xy 120.01373 -315.66739)
			(xy 120.013227 -315.710297) (xy 120.005192 -315.795735) (xy 119.989191 -315.880045) (xy 119.965365 -315.962486)
			(xy 119.933924 -316.042334) (xy 119.895144 -316.118886) (xy 119.849366 -316.191471) (xy 119.796993 -316.259451)
			(xy 119.738484 -316.322227) (xy 119.674353 -316.379248) (xy 119.605165 -316.430014) (xy 119.56376 -316.45479)
			(xy 122.407172 -316.45479) (xy 122.407172 -314.87999) (xy 122.407534 -314.86663) (xy 122.414453 -314.840822)
			(xy 122.427816 -314.817684) (xy 122.446713 -314.798794) (xy 122.469855 -314.785439) (xy 122.495666 -314.778529)
			(xy 122.509026 -314.778136) (xy 124.083826 -314.778136) (xy 124.097178 -314.778559) (xy 124.122972 -314.785476)
			(xy 124.146097 -314.798831) (xy 124.164979 -314.817716) (xy 124.178331 -314.840843) (xy 124.185243 -314.866638)
			(xy 124.18568 -314.87999) (xy 124.18568 -315.66739) (xy 124.381011 -315.66739) (xy 124.385033 -315.58167)
			(xy 124.397064 -315.496702) (xy 124.417 -315.413235) (xy 124.444663 -315.332001) (xy 124.479812 -315.253715)
			(xy 124.522138 -315.179064) (xy 124.571267 -315.108705) (xy 124.62677 -315.043255) (xy 124.688157 -314.983291)
			(xy 124.75489 -314.929338) (xy 124.826382 -314.881871) (xy 124.902004 -314.841307) (xy 124.981093 -314.808003)
			(xy 125.062953 -314.782251) (xy 125.146864 -314.764278) (xy 125.23209 -314.754242) (xy 125.317882 -314.75223)
			(xy 125.403484 -314.758261) (xy 125.488146 -314.772281) (xy 125.571123 -314.794167) (xy 125.651686 -314.823728)
			(xy 125.729126 -314.860702) (xy 125.802765 -314.904766) (xy 125.871953 -314.955532) (xy 125.936084 -315.012553)
			(xy 125.994593 -315.075329) (xy 126.046966 -315.143309) (xy 126.092744 -315.215894) (xy 126.131524 -315.292446)
			(xy 126.162965 -315.372294) (xy 126.186791 -315.454735) (xy 126.202792 -315.539045) (xy 126.210827 -315.624483)
			(xy 126.21133 -315.66739) (xy 126.210827 -315.710297) (xy 126.202792 -315.795735) (xy 126.186791 -315.880045)
			(xy 126.162965 -315.962486) (xy 126.131524 -316.042334) (xy 126.092744 -316.118886) (xy 126.046966 -316.191471)
			(xy 125.994593 -316.259451) (xy 125.936084 -316.322227) (xy 125.871953 -316.379248) (xy 125.802765 -316.430014)
			(xy 125.729126 -316.474078) (xy 125.651686 -316.511052) (xy 125.571123 -316.540613) (xy 125.488146 -316.562499)
			(xy 125.403484 -316.576519) (xy 125.317882 -316.58255) (xy 125.23209 -316.580538) (xy 125.146864 -316.570502)
			(xy 125.062953 -316.552529) (xy 124.981093 -316.526777) (xy 124.902004 -316.493473) (xy 124.826382 -316.452909)
			(xy 124.75489 -316.405442) (xy 124.688157 -316.351489) (xy 124.62677 -316.291525) (xy 124.571267 -316.226075)
			(xy 124.522138 -316.155716) (xy 124.479812 -316.081065) (xy 124.444663 -316.002779) (xy 124.417 -315.921545)
			(xy 124.397064 -315.838078) (xy 124.385033 -315.75311) (xy 124.381011 -315.66739) (xy 124.18568 -315.66739)
			(xy 124.18568 -316.45479) (xy 124.18521 -316.468139) (xy 124.178303 -316.493929) (xy 124.164957 -316.517053)
			(xy 124.146082 -316.535935) (xy 124.122963 -316.549289) (xy 124.097175 -316.556205) (xy 124.083826 -316.556644)
			(xy 122.509026 -316.556644) (xy 122.495669 -316.556234) (xy 122.469865 -316.549325) (xy 122.446729 -316.535972)
			(xy 122.427838 -316.517084) (xy 122.414481 -316.49395) (xy 122.407568 -316.468147) (xy 122.407172 -316.45479)
			(xy 119.56376 -316.45479) (xy 119.531526 -316.474078) (xy 119.454086 -316.511052) (xy 119.373523 -316.540613)
			(xy 119.290546 -316.562499) (xy 119.205884 -316.576519) (xy 119.120282 -316.58255) (xy 119.03449 -316.580538)
			(xy 118.949264 -316.570502) (xy 118.865353 -316.552529) (xy 118.783493 -316.526777) (xy 118.704404 -316.493473)
			(xy 118.628782 -316.452909) (xy 118.55729 -316.405442) (xy 118.490557 -316.351489) (xy 118.42917 -316.291525)
			(xy 118.373667 -316.226075) (xy 118.324538 -316.155716) (xy 118.282212 -316.081065) (xy 118.247063 -316.002779)
			(xy 118.2194 -315.921545) (xy 118.199464 -315.838078) (xy 118.187433 -315.75311) (xy 118.183411 -315.66739)
			(xy 117.98808 -315.66739) (xy 117.98808 -316.45479) (xy 117.98761 -316.468139) (xy 117.980703 -316.493929)
			(xy 117.967357 -316.517053) (xy 117.948482 -316.535935) (xy 117.925363 -316.549289) (xy 117.899575 -316.556205)
			(xy 117.886226 -316.556644) (xy 116.311426 -316.556644) (xy 116.298069 -316.556234) (xy 116.272265 -316.549325)
			(xy 116.249129 -316.535972) (xy 116.230238 -316.517084) (xy 116.216881 -316.49395) (xy 116.209968 -316.468147)
			(xy 116.209572 -316.45479) (xy 113.36616 -316.45479) (xy 113.333926 -316.474078) (xy 113.256486 -316.511052)
			(xy 113.175923 -316.540613) (xy 113.092946 -316.562499) (xy 113.008284 -316.576519) (xy 112.922682 -316.58255)
			(xy 112.83689 -316.580538) (xy 112.751664 -316.570502) (xy 112.667753 -316.552529) (xy 112.585893 -316.526777)
			(xy 112.506804 -316.493473) (xy 112.431182 -316.452909) (xy 112.35969 -316.405442) (xy 112.292957 -316.351489)
			(xy 112.23157 -316.291525) (xy 112.176067 -316.226075) (xy 112.126938 -316.155716) (xy 112.084612 -316.081065)
			(xy 112.049463 -316.002779) (xy 112.0218 -315.921545) (xy 112.001864 -315.838078) (xy 111.989833 -315.75311)
			(xy 111.985811 -315.66739) (xy 111.79048 -315.66739) (xy 111.79048 -316.45479) (xy 111.79001 -316.468139)
			(xy 111.783103 -316.493929) (xy 111.769757 -316.517053) (xy 111.750882 -316.535935) (xy 111.727763 -316.549289)
			(xy 111.701975 -316.556205) (xy 111.688626 -316.556644) (xy 110.113826 -316.556644) (xy 110.100469 -316.556234)
			(xy 110.074665 -316.549325) (xy 110.051529 -316.535972) (xy 110.032638 -316.517084) (xy 110.019281 -316.49395)
			(xy 110.012368 -316.468147) (xy 110.011972 -316.45479) (xy 107.188372 -316.45479) (xy 107.156138 -316.474078)
			(xy 107.078698 -316.511052) (xy 106.998135 -316.540613) (xy 106.915158 -316.562499) (xy 106.830496 -316.576519)
			(xy 106.744894 -316.58255) (xy 106.659102 -316.580538) (xy 106.573876 -316.570502) (xy 106.489965 -316.552529)
			(xy 106.408105 -316.526777) (xy 106.329016 -316.493473) (xy 106.253394 -316.452909) (xy 106.181902 -316.405442)
			(xy 106.115169 -316.351489) (xy 106.053782 -316.291525) (xy 105.998279 -316.226075) (xy 105.94915 -316.155716)
			(xy 105.906824 -316.081065) (xy 105.871675 -316.002779) (xy 105.844012 -315.921545) (xy 105.824076 -315.838078)
			(xy 105.812045 -315.75311) (xy 105.808023 -315.66739) (xy 105.612692 -315.66739) (xy 105.612692 -316.45479)
			(xy 105.61221 -316.468138) (xy 105.605304 -316.493926) (xy 105.59196 -316.517049) (xy 105.573087 -316.535931)
			(xy 105.549971 -316.549286) (xy 105.524186 -316.556204) (xy 105.510838 -316.556644) (xy 103.936038 -316.556644)
			(xy 103.922682 -316.556224) (xy 103.896878 -316.549318) (xy 103.873741 -316.535967) (xy 103.85485 -316.517081)
			(xy 103.841493 -316.493948) (xy 103.83458 -316.468146) (xy 103.834184 -316.45479) (xy 100.990772 -316.45479)
			(xy 100.958538 -316.474078) (xy 100.881098 -316.511052) (xy 100.800535 -316.540613) (xy 100.717558 -316.562499)
			(xy 100.632896 -316.576519) (xy 100.547294 -316.58255) (xy 100.461502 -316.580538) (xy 100.376276 -316.570502)
			(xy 100.292365 -316.552529) (xy 100.210505 -316.526777) (xy 100.131416 -316.493473) (xy 100.055794 -316.452909)
			(xy 99.984302 -316.405442) (xy 99.917569 -316.351489) (xy 99.856182 -316.291525) (xy 99.800679 -316.226075)
			(xy 99.75155 -316.155716) (xy 99.709224 -316.081065) (xy 99.674075 -316.002779) (xy 99.646412 -315.921545)
			(xy 99.626476 -315.838078) (xy 99.614445 -315.75311) (xy 99.610423 -315.66739) (xy 99.415092 -315.66739)
			(xy 99.415092 -316.45479) (xy 99.41461 -316.468138) (xy 99.407704 -316.493926) (xy 99.39436 -316.517049)
			(xy 99.375487 -316.535931) (xy 99.352371 -316.549286) (xy 99.326586 -316.556204) (xy 99.313238 -316.556644)
			(xy 97.738438 -316.556644) (xy 97.725082 -316.556224) (xy 97.699278 -316.549318) (xy 97.676141 -316.535967)
			(xy 97.65725 -316.517081) (xy 97.643893 -316.493948) (xy 97.63698 -316.468146) (xy 97.636584 -316.45479)
			(xy 79.072232 -316.45479) (xy 79.072232 -331.13218) (xy 79.27848 -331.338428) (xy 82.92338 -331.338428)
			(xy 83.278726 -331.69352) (xy 84.180934 -331.69352) (xy 84.347812 -331.526896) (xy 84.347812 -328.622152)
			(xy 84.348244 -328.612086) (xy 84.355972 -328.593495) (xy 84.362798 -328.586084) (xy 84.560664 -328.388218)
			(xy 84.568065 -328.38138) (xy 84.586664 -328.373666) (xy 84.596732 -328.373232) (xy 93.292168 -328.373232)
			(xy 93.302131 -328.372746) (xy 93.320558 -328.365162) (xy 93.327982 -328.3585) (xy 94.093538 -327.592944)
			(xy 94.100904 -327.583292) (xy 94.103849 -327.578075) (xy 94.107438 -327.566649) (xy 94.108016 -327.560686)
			(xy 94.108016 -325.52894) (xy 94.10827 -325.52132) (xy 94.10827 -325.423784) (xy 94.108695 -325.413714)
			(xy 94.11641 -325.395111) (xy 94.123256 -325.387716) (xy 94.193614 -325.317358) (xy 94.197678 -325.31304)
			(xy 94.448884 -325.061834) (xy 94.453202 -325.05777) (xy 94.523814 -324.987158) (xy 94.53121 -324.980307)
			(xy 94.549809 -324.972569) (xy 94.559882 -324.972172) (xy 125.150372 -324.972172) (xy 125.160423 -324.972676)
			(xy 125.178986 -324.980395) (xy 125.18644 -324.987158) (xy 125.257052 -325.05777) (xy 125.26137 -325.061834)
			(xy 125.400054 -325.200772) (xy 125.453648 -325.254366) (xy 125.46049 -325.261766) (xy 125.468208 -325.280364)
			(xy 125.468634 -325.290434) (xy 125.468634 -325.38797) (xy 125.468888 -325.39559) (xy 125.468888 -328.213974)
			(xy 125.469929 -328.221642) (xy 125.475998 -328.235868) (xy 125.480826 -328.241914) (xy 125.6284 -328.389742)
			(xy 125.635719 -328.396129) (xy 125.653746 -328.403323) (xy 125.663452 -328.403712) (xy 133.863842 -328.403712)
			(xy 133.873909 -328.404143) (xy 133.892501 -328.41187) (xy 133.89991 -328.418698) (xy 134.215378 -328.734166)
			(xy 134.222216 -328.741567) (xy 134.22993 -328.760166) (xy 134.230364 -328.770234) (xy 134.230364 -331.317346)
			(xy 134.235698 -331.32268) (xy 134.235698 -333.332582) (xy 134.23617 -333.342454) (xy 134.243629 -333.360736)
			(xy 134.250176 -333.368142) (xy 134.516368 -333.634334) (xy 134.523749 -333.640916) (xy 134.542048 -333.648364)
			(xy 134.551928 -333.648812)
		)
		(stroke
			(width 0)
			(type solid)
		)
		(fill yes)
		(layer "B.Cu")
		(net "PVCCIN_CPU1")
	)
	(gr_line
		(start 70.177152 -419.62197)
		(end 70.182232 -419.62197)
		(stroke
			(width 0.06604)
			(type default)
		)
		(layer "B.Cu")
	)
	(gr_line
		(start 70.178422 -419.36162)
		(end 70.6501 -418.889942)
		(stroke
			(width 0.06604)
			(type default)
		)
		(layer "B.Cu")
	)
	(gr_line
		(start 70.182232 -419.62197)
		(end 70.6501 -420.089838)
		(stroke
			(width 0.06604)
			(type default)
		)
		(layer "B.Cu")
	)
	(gr_line
		(start 70.6501 -423.68978)
		(end 70.6501 -423.689526)
		(stroke
			(width 0.06604)
			(type default)
		)
		(layer "B.Cu")
	)
	(gr_line
		(start 70.6501 -423.689526)
		(end 71.120254 -423.219372)
		(stroke
			(width 0.06604)
			(type default)
		)
		(layer "B.Cu")
	)
	(gr_line
		(start 70.6501 -422.489884)
		(end 71.117968 -422.957752)
		(stroke
			(width 0.06604)
			(type default)
		)
		(layer "B.Cu")
	)
	(gr_line
		(start 70.663562 -416.13963)
		(end 70.492874 -416.13963)
		(stroke
			(width 0.06604)
			(type default)
		)
		(layer "B.Cu")
	)
	(gr_line
		(start 70.749922 -415.514282)
		(end 70.307962 -415.956496)
		(stroke
			(width 0.06604)
			(type default)
		)
		(layer "B.Cu")
	)
	(gr_line
		(start 70.93331 -415.869882)
		(end 70.663562 -416.13963)
		(stroke
			(width 0.06604)
			(type default)
		)
		(layer "B.Cu")
	)
	(gr_line
		(start 70.93331 -415.699194)
		(end 70.93331 -415.869882)
		(stroke
			(width 0.06604)
			(type default)
		)
		(layer "B.Cu")
	)
	(gr_line
		(start 71.117968 -422.957752)
		(end 71.304404 -422.957752)
		(stroke
			(width 0.06604)
			(type default)
		)
		(layer "B.Cu")
	)
	(gr_line
		(start 71.120254 -423.219372)
		(end 71.411084 -423.219372)
		(stroke
			(width 0.06604)
			(type default)
		)
		(layer "B.Cu")
	)
	(gr_line
		(start 71.411084 -423.219372)
		(end 71.48957 -423.14114)
		(stroke
			(width 0.06604)
			(type default)
		)
		(layer "B.Cu")
	)
	(gr_line
		(start 71.66991 -414.594548)
		(end 71.638668 -414.625536)
		(stroke
			(width 0.06604)
			(type default)
		)
		(layer "B.Cu")
	)
	(gr_line
		(start 71.66991 -414.594548)
		(end 71.66991 -414.594294)
		(stroke
			(width 0.06604)
			(type default)
		)
		(layer "B.Cu")
	)
	(gr_line
		(start 71.709534 -414.575244)
		(end 71.66991 -414.594294)
		(stroke
			(width 0.06604)
			(type default)
		)
		(layer "B.Cu")
	)
	(gr_line
		(start 72.338946 -414.27273)
		(end 72.299068 -414.292034)
		(stroke
			(width 0.06604)
			(type default)
		)
		(layer "B.Cu")
	)
	(gr_line
		(start 72.338946 -414.27273)
		(end 72.338692 -414.27273)
		(stroke
			(width 0.06604)
			(type default)
		)
		(layer "B.Cu")
	)
	(gr_line
		(start 72.382634 -414.267904)
		(end 72.338692 -414.27273)
		(stroke
			(width 0.06604)
			(type default)
		)
		(layer "B.Cu")
	)
	(gr_line
		(start 73.49236 -414.528)
		(end 73.358756 -414.42132)
		(stroke
			(width 0.06604)
			(type default)
		)
		(layer "B.Cu")
	)
	(gr_line
		(start 73.871328 -414.485836)
		(end 73.49236 -414.528)
		(stroke
			(width 0.06604)
			(type default)
		)
		(layer "B.Cu")
	)
	(gr_line
		(start 73.950576 -414.093406)
		(end 73.329038 -414.162494)
		(stroke
			(width 0.06604)
			(type default)
		)
		(layer "B.Cu")
	)
	(gr_line
		(start 73.978008 -414.352232)
		(end 73.871328 -414.485836)
		(stroke
			(width 0.06604)
			(type default)
		)
		(layer "B.Cu")
	)
	(gr_line
		(start 74.492104 -414.416748)
		(end 74.358754 -414.310068)
		(stroke
			(width 0.06604)
			(type default)
		)
		(layer "B.Cu")
	)
	(gr_line
		(start 74.871072 -414.374584)
		(end 74.492104 -414.416748)
		(stroke
			(width 0.06604)
			(type default)
		)
		(layer "B.Cu")
	)
	(gr_line
		(start 74.950066 -413.982154)
		(end 74.329036 -414.051242)
		(stroke
			(width 0.06604)
			(type default)
		)
		(layer "B.Cu")
	)
	(gr_line
		(start 74.977752 -414.241234)
		(end 74.871072 -414.374584)
		(stroke
			(width 0.06604)
			(type default)
		)
		(layer "B.Cu")
	)
	(gr_line
		(start 77.836522 -413.661098)
		(end 74.950066 -413.982154)
		(stroke
			(width 0.06604)
			(type default)
		)
		(layer "B.Cu")
	)
	(gr_line
		(start 77.865224 -413.918654)
		(end 74.978768 -414.23971)
		(stroke
			(width 0.06604)
			(type default)
		)
		(layer "B.Cu")
	)
	(gr_line
		(start 98.511868 -404.753318)
		(end 98.82124 -405.06269)
		(stroke
			(width 0.06604)
			(type default)
		)
		(layer "B.Cu")
	)
	(gr_line
		(start 98.53422 -402.62937)
		(end 98.84283 -402.93798)
		(stroke
			(width 0.06604)
			(type default)
		)
		(layer "B.Cu")
	)
	(gr_line
		(start 98.82124 -405.06269)
		(end 98.82124 -405.092916)
		(stroke
			(width 0.06604)
			(type default)
		)
		(layer "B.Cu")
	)
	(gr_line
		(start 98.84283 -403.888956)
		(end 98.511868 -404.219918)
		(stroke
			(width 0.06604)
			(type default)
		)
		(layer "B.Cu")
	)
	(gr_line
		(start 99.10318 -403.90318)
		(end 99.419918 -404.219918)
		(stroke
			(width 0.06604)
			(type default)
		)
		(layer "B.Cu")
	)
	(gr_line
		(start 99.10318 -403.887686)
		(end 99.10318 -403.90318)
		(stroke
			(width 0.06604)
			(type default)
		)
		(layer "B.Cu")
	)
	(gr_line
		(start 99.10318 -402.92401)
		(end 99.10318 -402.93925)
		(stroke
			(width 0.06604)
			(type default)
		)
		(layer "B.Cu")
	)
	(gr_line
		(start 99.39782 -402.62937)
		(end 99.10318 -402.92401)
		(stroke
			(width 0.06604)
			(type default)
		)
		(layer "B.Cu")
	)
	(gr_line
		(start 99.419918 -404.753318)
		(end 99.08159 -405.091646)
		(stroke
			(width 0.06604)
			(type default)
		)
		(layer "B.Cu")
	)
	(gr_line
		(start 99.628198 -408.154886)
		(end 99.959668 -407.022554)
		(stroke
			(width 0.06604)
			(type default)
		)
		(layer "B.Cu")
	)
	(gr_line
		(start 99.876864 -408.227784)
		(end 100.208334 -407.095452)
		(stroke
			(width 0.06604)
			(type default)
		)
		(layer "B.Cu")
	)
	(gr_line
		(start 99.959668 -407.022554)
		(end 100.13823 -406.413462)
		(stroke
			(width 0.06604)
			(type default)
		)
		(layer "B.Cu")
	)
	(gr_line
		(start 100.13823 -406.413462)
		(end 100.138484 -406.4127)
		(stroke
			(width 0.06604)
			(type default)
		)
		(layer "B.Cu")
	)
	(gr_line
		(start 100.210112 -407.094436)
		(end 100.359972 -407.012902)
		(stroke
			(width 0.06604)
			(type default)
		)
		(layer "B.Cu")
	)
	(gr_line
		(start 100.359972 -407.012902)
		(end 100.469954 -406.637236)
		(stroke
			(width 0.06604)
			(type default)
		)
		(layer "B.Cu")
	)
	(gr_line
		(start 100.387404 -406.48636)
		(end 100.38715 -406.485852)
		(stroke
			(width 0.06604)
			(type default)
		)
		(layer "B.Cu")
	)
	(gr_line
		(start 100.469954 -406.637236)
		(end 100.387912 -406.487122)
		(stroke
			(width 0.06604)
			(type default)
		)
		(layer "B.Cu")
	)
	(gr_line
		(start 102.31628 -404.66264)
		(end 102.32644 -404.66264)
		(stroke
			(width 0.06604)
			(type default)
		)
		(layer "B.Cu")
	)
	(gr_line
		(start 102.31755 -404.92299)
		(end 102.62362 -405.22906)
		(stroke
			(width 0.06604)
			(type default)
		)
		(layer "B.Cu")
	)
	(gr_line
		(start 102.32644 -404.66264)
		(end 102.62362 -404.36546)
		(stroke
			(width 0.06604)
			(type default)
		)
		(layer "B.Cu")
	)
	(gr_poly
		(pts
			(arc
				(start 278.10841 -405.924766)
				(mid 278.127045 -405.923069)
				(end 278.145748 -405.92248)
			)
			(xy 280.90622 -405.92248) (xy 281.051508 -405.777192) (xy 281.051508 -397.72844) (xy 280.706068 -397.383)
			(xy 275.6408 -397.383) (xy 275.3868 -397.637) (xy 275.3868 -405.8285) (xy 275.48332 -405.92502) (xy 278.105616 -405.92502)
		)
		(stroke
			(width 0)
			(type solid)
		)
		(fill yes)
		(layer "In1.Cu")
		(net "P12V_MAIN_R_0")
	)
	(gr_poly
		(pts
			(arc
				(start 273.791172 -406.781)
				(mid 273.810393 -406.777119)
				(end 273.826732 -406.766268)
			)
			(xy 274.30476 -406.28824) (xy 274.32 -406.274016) (xy 274.32 -397.635984) (xy 274.30476 -397.62176)
			(xy 274.083018 -397.400018) (xy 274.067016 -397.383) (xy 240.155984 -397.383) (xy 240.14176 -397.39824)
			(xy 239.666018 -397.873982) (xy 239.665764 -397.874236) (xy 239.649 -397.889984) (xy 239.649 -406.528016)
			(xy 239.66424 -406.54224) (xy 239.88776 -406.76576) (xy 239.901984 -406.781)
		)
		(stroke
			(width 0)
			(type solid)
		)
		(fill yes)
		(layer "In1.Cu")
		(net "P12V_MAIN_R")
	)
	(gr_poly
		(pts
			(xy 230.38054 -434.93182)
			(arc
				(start 230.38054 -423.45102)
				(mid 230.404693 -423.329504)
				(end 230.473504 -423.226484)
			)
			(arc
				(start 232.965244 -420.734744)
				(mid 233.068276 -420.665963)
				(end 233.18978 -420.64178)
			)
			(xy 270.34998 -420.64178)
			(arc
				(start 275.456396 -415.535364)
				(mid 275.559428 -415.466583)
				(end 275.680932 -415.4424)
			)
			(xy 279.79624 -415.4424) (xy 280.19756 -415.04108) (xy 280.19756 -408.29992) (xy 279.96896 -408.07132)
			(arc
				(start 239.699292 -408.07132)
				(mid 239.577776 -408.047167)
				(end 239.474756 -407.978356)
			)
			(xy 237.61446 -406.11806)
			(arc
				(start 235.520992 -406.11806)
				(mid 235.399476 -406.093907)
				(end 235.296456 -406.025096)
			)
			(arc
				(start 233.973624 -404.702264)
				(mid 233.904843 -404.599232)
				(end 233.88066 -404.477728)
			)
			(xy 233.88066 -401.03298) (xy 233.86542 -401.01774) (xy 230.47706 -401.01774) (xy 230.46182 -401.03298)
			(arc
				(start 230.46182 -404.473156)
				(mid 230.437667 -404.594672)
				(end 230.368856 -404.697692)
			)
			(xy 230.256588 -404.80996)
			(arc
				(start 230.256588 -407.3906)
				(mid 230.232435 -407.512116)
				(end 230.163624 -407.615136)
			)
			(arc
				(start 228.159564 -409.619196)
				(mid 228.056532 -409.687977)
				(end 227.935028 -409.71216)
			)
			(arc
				(start 225.70694 -409.71216)
				(mid 225.585424 -409.688007)
				(end 225.482404 -409.619196)
			)
			(arc
				(start 223.491552 -407.628344)
				(mid 223.422771 -407.525312)
				(end 223.398588 -407.403808)
			)
			(xy 223.398588 -404.79218)
			(arc
				(start 223.310704 -404.704296)
				(mid 223.241923 -404.601264)
				(end 223.21774 -404.47976)
			)
			(xy 223.21774 -401.04568) (xy 223.19234 -401.02028) (xy 219.81414 -401.02028) (xy 219.79636 -401.03806)
			(arc
				(start 219.79636 -404.490936)
				(mid 219.772207 -404.612452)
				(end 219.703396 -404.715472)
			)
			(xy 219.613988 -404.80488)
			(arc
				(start 219.613988 -407.259028)
				(mid 219.589835 -407.380544)
				(end 219.521024 -407.483564)
			)
			(arc
				(start 217.497152 -409.507436)
				(mid 217.39412 -409.576217)
				(end 217.272616 -409.6004)
			)
			(arc
				(start 214.794592 -409.6004)
				(mid 214.673076 -409.576247)
				(end 214.570056 -409.507436)
			)
			(arc
				(start 212.812884 -407.750264)
				(mid 212.744103 -407.647232)
				(end 212.71992 -407.525728)
			)
			(xy 212.71992 -404.79472)
			(arc
				(start 212.635084 -404.709884)
				(mid 212.566303 -404.606852)
				(end 212.54212 -404.485348)
			)
			(xy 212.54212 -401.02536) (xy 212.53704 -401.02028) (xy 209.14106 -401.02028) (xy 209.13598 -401.02536)
			(arc
				(start 209.13598 -404.452836)
				(mid 209.111827 -404.574352)
				(end 209.043016 -404.677372)
			)
			(xy 208.945988 -404.7744)
			(arc
				(start 208.945988 -407.30424)
				(mid 208.921835 -407.425756)
				(end 208.853024 -407.528776)
			)
			(arc
				(start 206.770224 -409.611576)
				(mid 206.667192 -409.680357)
				(end 206.545688 -409.70454)
			)
			(arc
				(start 204.16012 -409.70454)
				(mid 204.038604 -409.680387)
				(end 203.935584 -409.611576)
			)
			(arc
				(start 202.155552 -407.831544)
				(mid 202.086771 -407.728512)
				(end 202.062588 -407.607008)
			)
			(xy 202.062588 -404.779988)
			(arc
				(start 201.969624 -404.687024)
				(mid 201.900843 -404.583992)
				(end 201.87666 -404.462488)
			)
			(xy 201.87666 -401.03298) (xy 201.86396 -401.02028) (xy 198.47306 -401.02028) (xy 198.46798 -401.02536)
			(arc
				(start 198.46798 -404.487888)
				(mid 198.443827 -404.609404)
				(end 198.375016 -404.712424)
			)
			(arc
				(start 197.194424 -405.893016)
				(mid 197.091392 -405.961797)
				(end 196.969888 -405.98598)
			)
			(arc
				(start 190.870332 -405.98598)
				(mid 190.748816 -405.961827)
				(end 190.645796 -405.893016)
			)
			(arc
				(start 189.455552 -404.702518)
				(mid 189.386771 -404.599486)
				(end 189.362588 -404.477982)
			)
			(xy 189.362588 -404.177754) (xy 189.337188 -404.152354)
			(arc
				(start 189.11316 -404.152354)
				(mid 188.991644 -404.128201)
				(end 188.888624 -404.05939)
			)
			(arc
				(start 188.710824 -403.88159)
				(mid 188.642043 -403.778558)
				(end 188.61786 -403.657054)
			)
			(xy 188.61786 -401.02028) (xy 188.600588 -401.002754) (xy 185.196988 -401.002754) (xy 185.196988 -406.489154)
			(arc
				(start 185.434224 -406.72639)
				(mid 185.480227 -406.78458)
				(end 185.51144 -406.851866)
			)
			(arc
				(start 185.51144 -406.851866)
				(mid 185.548193 -406.942536)
				(end 185.560716 -407.039572)
			)
			(arc
				(start 185.560716 -407.039572)
				(mid 185.553298 -407.114694)
				(end 185.531252 -407.186892)
			)
			(xy 185.527188 -407.19629)
			(arc
				(start 185.527188 -408.287982)
				(mid 185.503035 -408.409498)
				(end 185.434224 -408.512518)
			)
			(xy 185.323988 -408.622754) (xy 185.323988 -413.065976) (xy 192.869312 -420.6113)
			(arc
				(start 197.416928 -420.6113)
				(mid 197.538444 -420.635453)
				(end 197.641464 -420.704264)
			)
			(arc
				(start 206.398876 -429.461676)
				(mid 206.467657 -429.564708)
				(end 206.49184 -429.686212)
			)
			(xy 206.49184 -435.39156) (xy 207.63484 -436.53456) (xy 228.7778 -436.53456)
		)
		(stroke
			(width 0)
			(type solid)
		)
		(fill yes)
		(layer "In1.Cu")
		(net "P12V_PSU")
	)
	(gr_poly
		(pts
			(xy 531.7998 -462.520284) (xy 531.855607 -462.519775) (xy 531.96691 -462.511434) (xy 532.077278 -462.494798)
			(xy 532.186094 -462.469962) (xy 532.29275 -462.437062) (xy 532.396649 -462.396285) (xy 532.49721 -462.347857)
			(xy 532.593871 -462.292049) (xy 532.686092 -462.229174) (xy 532.773355 -462.159583) (xy 532.855174 -462.083666)
			(xy 532.931091 -462.001846) (xy 533.000681 -461.914582) (xy 533.063556 -461.822361) (xy 533.119362 -461.7257)
			(xy 533.16779 -461.625138) (xy 533.208566 -461.521239) (xy 533.241465 -461.414583) (xy 533.266301 -461.305766)
			(xy 533.282935 -461.195398) (xy 533.291275 -461.084095) (xy 533.291796 -461.028288) (xy 533.291796 -455.0283)
			(xy 533.291274 -454.972493) (xy 533.282933 -454.861191) (xy 533.266298 -454.750824) (xy 533.241462 -454.642008)
			(xy 533.208563 -454.535353) (xy 533.167786 -454.431454) (xy 533.119358 -454.330893) (xy 533.063551 -454.234233)
			(xy 533.000677 -454.142013) (xy 532.931086 -454.054749) (xy 532.85517 -453.97293) (xy 532.773351 -453.897014)
			(xy 532.686087 -453.827423) (xy 532.593867 -453.764549) (xy 532.497207 -453.708742) (xy 532.396646 -453.660314)
			(xy 532.292747 -453.619537) (xy 532.186092 -453.586638) (xy 532.077276 -453.561802) (xy 531.966909 -453.545167)
			(xy 531.855607 -453.536826) (xy 531.7998 -453.536304) (xy 516.019796 -453.536304) (xy 515.949442 -453.535811)
			(xy 515.808956 -453.527921) (xy 515.669133 -453.512166) (xy 515.530414 -453.488597) (xy 515.393234 -453.457286)
			(xy 515.258026 -453.418334) (xy 515.125215 -453.371861) (xy 514.995218 -453.318014) (xy 514.868445 -453.256963)
			(xy 514.745294 -453.188901) (xy 514.626154 -453.11404) (xy 514.511398 -453.032616) (xy 514.401389 -452.944887)
			(xy 514.296471 -452.851127) (xy 514.196976 -452.751632) (xy 514.103216 -452.646714) (xy 514.015486 -452.536705)
			(xy 513.934063 -452.421949) (xy 513.859201 -452.302809) (xy 513.791138 -452.179659) (xy 513.730087 -452.052886)
			(xy 513.676241 -451.922889) (xy 513.629768 -451.790078) (xy 513.590815 -451.65487) (xy 513.559504 -451.51769)
			(xy 513.535934 -451.378971) (xy 513.520179 -451.239148) (xy 513.512289 -451.098662) (xy 513.5118 -451.028308)
			(xy 513.5118 -312.408316) (xy 513.512284 -312.337962) (xy 513.520173 -312.197474) (xy 513.535926 -312.05765)
			(xy 513.559495 -311.91893) (xy 513.590805 -311.781749) (xy 513.629757 -311.646539) (xy 513.676229 -311.513726)
			(xy 513.730076 -311.383728) (xy 513.791126 -311.256954) (xy 513.859189 -311.133802) (xy 513.93405 -311.01466)
			(xy 514.015474 -310.899903) (xy 514.103203 -310.789893) (xy 514.196964 -310.684974) (xy 514.296459 -310.585477)
			(xy 514.401377 -310.491716) (xy 514.511387 -310.403986) (xy 514.626144 -310.322561) (xy 514.745285 -310.247699)
			(xy 514.868436 -310.179635) (xy 514.99521 -310.118584) (xy 515.125208 -310.064737) (xy 515.25802 -310.018263)
			(xy 515.393229 -309.97931) (xy 515.53041 -309.947999) (xy 515.669131 -309.924429) (xy 515.808954 -309.908674)
			(xy 515.949442 -309.900784) (xy 516.019796 -309.90032) (xy 531.7998 -309.90032) (xy 531.855607 -309.899798)
			(xy 531.96691 -309.891457) (xy 532.077278 -309.874822) (xy 532.186094 -309.849986) (xy 532.292751 -309.817087)
			(xy 532.39665 -309.77631) (xy 532.497211 -309.727883) (xy 532.593873 -309.672076) (xy 532.686094 -309.609202)
			(xy 532.773358 -309.539612) (xy 532.855178 -309.463695) (xy 532.931096 -309.381876) (xy 533.000687 -309.294613)
			(xy 533.063563 -309.202393) (xy 533.119372 -309.105733) (xy 533.167801 -309.005172) (xy 533.208579 -308.901273)
			(xy 533.24148 -308.794618) (xy 533.266318 -308.685802) (xy 533.282955 -308.575434) (xy 533.291297 -308.464131)
			(xy 533.291796 -308.408324) (xy 533.291796 10.40003) (xy 533.291273 10.455836) (xy 533.28293 10.567137)
			(xy 533.266293 10.677502) (xy 533.241455 10.786316) (xy 533.208555 10.89297) (xy 533.167777 10.996866)
			(xy 533.119348 11.097425) (xy 533.063541 11.194084) (xy 533.000666 11.286302) (xy 532.931076 11.373563)
			(xy 532.855159 11.45538) (xy 532.77334 11.531295) (xy 532.686078 11.600884) (xy 532.593858 11.663757)
			(xy 532.497199 11.719562) (xy 532.396639 11.767989) (xy 532.292741 11.808765) (xy 532.186087 11.841663)
			(xy 532.077273 11.866499) (xy 531.966907 11.883134) (xy 531.855606 11.891474) (xy 531.7998 11.892026)
			(xy 475.799912 11.892026) (xy 475.744104 11.891505) (xy 475.632801 11.883165) (xy 475.522432 11.86653)
			(xy 475.413615 11.841695) (xy 475.306958 11.808796) (xy 475.203057 11.76802) (xy 475.102495 11.719593)
			(xy 475.005832 11.663786) (xy 474.91361 11.600912) (xy 474.826345 11.531322) (xy 474.744524 11.455406)
			(xy 474.668605 11.373587) (xy 474.599013 11.286323) (xy 474.536136 11.194103) (xy 474.480327 11.097442)
			(xy 474.431897 10.996881) (xy 474.391117 10.892982) (xy 474.358216 10.786326) (xy 474.333378 10.677509)
			(xy 474.31674 10.567141) (xy 474.308397 10.455838) (xy 474.307916 10.40003) (xy 474.307916 7.335466)
			(xy 526.704041 7.335466) (xy 526.704041 7.464606) (xy 526.711991 7.593501) (xy 526.727861 7.721661)
			(xy 526.75159 7.848602) (xy 526.783089 7.973841) (xy 526.822238 8.096904) (xy 526.868889 8.217323)
			(xy 526.922864 8.334642) (xy 526.983959 8.448416) (xy 527.051942 8.558213) (xy 527.126556 8.663616)
			(xy 527.207517 8.764226) (xy 527.294517 8.859661) (xy 527.387228 8.94956) (xy 527.485298 9.033581)
			(xy 527.588353 9.111405) (xy 527.696004 9.182737) (xy 527.807843 9.247307) (xy 527.923444 9.304869)
			(xy 528.042369 9.355206) (xy 528.164168 9.398126) (xy 528.288378 9.433467) (xy 528.414527 9.461094)
			(xy 528.542139 9.480903) (xy 528.670728 9.492819) (xy 528.799806 9.496796) (xy 528.928884 9.492819)
			(xy 529.057473 9.480903) (xy 529.185085 9.461094) (xy 529.311234 9.433467) (xy 529.435444 9.398126)
			(xy 529.557243 9.355206) (xy 529.676168 9.304869) (xy 529.791769 9.247307) (xy 529.903608 9.182737)
			(xy 530.011259 9.111405) (xy 530.114314 9.033581) (xy 530.212384 8.94956) (xy 530.305095 8.859661)
			(xy 530.392095 8.764226) (xy 530.473056 8.663616) (xy 530.54767 8.558213) (xy 530.615653 8.448416)
			(xy 530.676748 8.334642) (xy 530.730723 8.217323) (xy 530.777374 8.096904) (xy 530.816523 7.973841)
			(xy 530.848022 7.848602) (xy 530.871751 7.721661) (xy 530.887621 7.593501) (xy 530.895571 7.464606)
			(xy 530.896068 7.400036) (xy 530.895571 7.335466) (xy 530.887621 7.206571) (xy 530.871751 7.078411)
			(xy 530.848022 6.95147) (xy 530.816523 6.826231) (xy 530.777374 6.703168) (xy 530.730723 6.582749)
			(xy 530.676748 6.46543) (xy 530.615653 6.351656) (xy 530.54767 6.241859) (xy 530.473056 6.136456)
			(xy 530.392095 6.035846) (xy 530.305095 5.940411) (xy 530.212384 5.850512) (xy 530.114314 5.766491)
			(xy 530.011259 5.688667) (xy 529.903608 5.617335) (xy 529.791769 5.552765) (xy 529.676168 5.495203)
			(xy 529.557243 5.444866) (xy 529.435444 5.401946) (xy 529.311234 5.366605) (xy 529.185085 5.338978)
			(xy 529.057473 5.319169) (xy 528.928884 5.307253) (xy 528.799806 5.303277) (xy 528.670728 5.307253)
			(xy 528.542139 5.319169) (xy 528.414527 5.338978) (xy 528.288378 5.366605) (xy 528.164168 5.401946)
			(xy 528.042369 5.444866) (xy 527.923444 5.495203) (xy 527.807843 5.552765) (xy 527.696004 5.617335)
			(xy 527.588353 5.688667) (xy 527.485298 5.766491) (xy 527.387228 5.850512) (xy 527.294517 5.940411)
			(xy 527.207517 6.035846) (xy 527.126556 6.136456) (xy 527.051942 6.241859) (xy 526.983959 6.351656)
			(xy 526.922864 6.46543) (xy 526.868889 6.582749) (xy 526.822238 6.703168) (xy 526.783089 6.826231)
			(xy 526.75159 6.95147) (xy 526.727861 7.078411) (xy 526.711991 7.206571) (xy 526.704041 7.335466)
			(xy 474.307916 7.335466) (xy 474.307916 -77.67193) (xy 474.307428 -77.765094) (xy 474.299715 -77.951262)
			(xy 474.284317 -78.136953) (xy 474.261258 -78.321849) (xy 474.23058 -78.505634) (xy 474.192333 -78.687994)
			(xy 474.146584 -78.868619) (xy 474.093411 -79.047199) (xy 474.032904 -79.223429) (xy 473.965167 -79.397008)
			(xy 473.890315 -79.56764) (xy 473.808477 -79.735034) (xy 473.719792 -79.898903) (xy 473.624411 -80.058968)
			(xy 473.522498 -80.214955) (xy 473.414227 -80.366597) (xy 473.299782 -80.513637) (xy 473.17936 -80.655821)
			(xy 473.053165 -80.792909) (xy 472.987624 -80.859122) (xy 471.245184 -82.601562) (xy 471.207836 -82.63956)
			(xy 471.138049 -82.720082) (xy 471.074185 -82.805378) (xy 471.01657 -82.895014) (xy 470.965496 -82.988531)
			(xy 470.921226 -83.085455) (xy 470.883983 -83.18529) (xy 470.853958 -83.287527) (xy 470.831304 -83.391646)
			(xy 470.816136 -83.497117) (xy 470.808532 -83.6034) (xy 470.80805 -83.656678) (xy 470.80805 -404.871936)
			(xy 470.807562 -404.9651) (xy 470.799849 -405.151268) (xy 470.78445 -405.336959) (xy 470.761392 -405.521855)
			(xy 470.730713 -405.70564) (xy 470.692467 -405.888001) (xy 470.646718 -406.068625) (xy 470.593544 -406.247205)
			(xy 470.533038 -406.423435) (xy 470.465301 -406.597015) (xy 470.39045 -406.767647) (xy 470.308612 -406.935041)
			(xy 470.219927 -407.098911) (xy 470.124547 -407.258976) (xy 470.022634 -407.414963) (xy 469.914363 -407.566606)
			(xy 469.799919 -407.713645) (xy 469.679497 -407.855831) (xy 469.553302 -407.992919) (xy 469.487758 -408.059128)
			(xy 468.244936 -409.30195) (xy 468.207612 -409.339964) (xy 468.137859 -409.4205) (xy 468.074028 -409.505805)
			(xy 468.016443 -409.595446) (xy 467.965398 -409.688966) (xy 467.921153 -409.785888) (xy 467.883933 -409.885719)
			(xy 467.853928 -409.98795) (xy 467.831291 -410.092061) (xy 467.816137 -410.197522) (xy 467.808543 -410.303794)
			(xy 467.808056 -410.357066) (xy 467.808056 -439.989976) (xy 467.808577 -440.045784) (xy 467.816916 -440.157089)
			(xy 467.83355 -440.267459) (xy 467.858385 -440.376277) (xy 467.891282 -440.482936) (xy 467.932058 -440.586837)
			(xy 467.980485 -440.687401) (xy 468.036291 -440.784065) (xy 468.099165 -440.876289) (xy 468.168754 -440.963556)
			(xy 468.244671 -441.045378) (xy 468.32649 -441.121299) (xy 468.413753 -441.190893) (xy 468.505974 -441.253771)
			(xy 468.602635 -441.309582) (xy 468.703197 -441.358013) (xy 468.807096 -441.398794) (xy 468.913753 -441.431697)
			(xy 469.02257 -441.456537) (xy 469.13294 -441.473176) (xy 469.244244 -441.48152) (xy 469.300052 -441.481972)
			(xy 471.79992 -441.481972) (xy 471.870274 -441.482466) (xy 472.01076 -441.490356) (xy 472.150582 -441.506112)
			(xy 472.289302 -441.529682) (xy 472.426481 -441.560993) (xy 472.561689 -441.599946) (xy 472.6945 -441.646419)
			(xy 472.824497 -441.700266) (xy 472.95127 -441.761317) (xy 473.07442 -441.82938) (xy 473.19356 -441.904241)
			(xy 473.308316 -441.985664) (xy 473.418325 -442.073394) (xy 473.523243 -442.167153) (xy 473.622738 -442.266648)
			(xy 473.716499 -442.371565) (xy 473.804229 -442.481575) (xy 473.885652 -442.59633) (xy 473.960514 -442.71547)
			(xy 474.028578 -442.83862) (xy 474.089629 -442.965392) (xy 474.143476 -443.095389) (xy 474.18995 -443.2282)
			(xy 474.228904 -443.363407) (xy 474.260216 -443.500587) (xy 474.283787 -443.639306) (xy 474.299543 -443.779128)
			(xy 474.307434 -443.919614) (xy 474.307916 -443.989968) (xy 474.307916 -458.092864) (xy 526.704041 -458.092864)
			(xy 526.704041 -457.963724) (xy 526.711991 -457.834829) (xy 526.727861 -457.706669) (xy 526.75159 -457.579728)
			(xy 526.783089 -457.454489) (xy 526.822238 -457.331426) (xy 526.868889 -457.211007) (xy 526.922864 -457.093688)
			(xy 526.983959 -456.979914) (xy 527.051942 -456.870117) (xy 527.126556 -456.764714) (xy 527.207517 -456.664104)
			(xy 527.294517 -456.568669) (xy 527.387228 -456.47877) (xy 527.485298 -456.394749) (xy 527.588353 -456.316925)
			(xy 527.696004 -456.245593) (xy 527.807843 -456.181023) (xy 527.923444 -456.123461) (xy 528.042369 -456.073124)
			(xy 528.164168 -456.030204) (xy 528.288378 -455.994863) (xy 528.414527 -455.967236) (xy 528.542139 -455.947427)
			(xy 528.670728 -455.935511) (xy 528.799806 -455.931535) (xy 528.928884 -455.935511) (xy 529.057473 -455.947427)
			(xy 529.185085 -455.967236) (xy 529.311234 -455.994863) (xy 529.435444 -456.030204) (xy 529.557243 -456.073124)
			(xy 529.676168 -456.123461) (xy 529.791769 -456.181023) (xy 529.903608 -456.245593) (xy 530.011259 -456.316925)
			(xy 530.114314 -456.394749) (xy 530.212384 -456.47877) (xy 530.305095 -456.568669) (xy 530.392095 -456.664104)
			(xy 530.473056 -456.764714) (xy 530.54767 -456.870117) (xy 530.615653 -456.979914) (xy 530.676748 -457.093688)
			(xy 530.730723 -457.211007) (xy 530.777374 -457.331426) (xy 530.816523 -457.454489) (xy 530.848022 -457.579728)
			(xy 530.871751 -457.706669) (xy 530.887621 -457.834829) (xy 530.895571 -457.963724) (xy 530.896068 -458.028294)
			(xy 530.895571 -458.092864) (xy 530.887621 -458.221759) (xy 530.871751 -458.349919) (xy 530.848022 -458.47686)
			(xy 530.816523 -458.602099) (xy 530.777374 -458.725162) (xy 530.730723 -458.845581) (xy 530.676748 -458.9629)
			(xy 530.615653 -459.076674) (xy 530.54767 -459.186471) (xy 530.473056 -459.291874) (xy 530.392095 -459.392484)
			(xy 530.305095 -459.487919) (xy 530.212384 -459.577818) (xy 530.114314 -459.661839) (xy 530.011259 -459.739663)
			(xy 529.903608 -459.810995) (xy 529.791769 -459.875565) (xy 529.676168 -459.933127) (xy 529.557243 -459.983464)
			(xy 529.435444 -460.026384) (xy 529.311234 -460.061725) (xy 529.185085 -460.089352) (xy 529.057473 -460.109161)
			(xy 528.928884 -460.121077) (xy 528.799806 -460.125054) (xy 528.670728 -460.121077) (xy 528.542139 -460.109161)
			(xy 528.414527 -460.089352) (xy 528.288378 -460.061725) (xy 528.164168 -460.026384) (xy 528.042369 -459.983464)
			(xy 527.923444 -459.933127) (xy 527.807843 -459.875565) (xy 527.696004 -459.810995) (xy 527.588353 -459.739663)
			(xy 527.485298 -459.661839) (xy 527.387228 -459.577818) (xy 527.294517 -459.487919) (xy 527.207517 -459.392484)
			(xy 527.126556 -459.291874) (xy 527.051942 -459.186471) (xy 526.983959 -459.076674) (xy 526.922864 -458.9629)
			(xy 526.868889 -458.845581) (xy 526.822238 -458.725162) (xy 526.783089 -458.602099) (xy 526.75159 -458.47686)
			(xy 526.727861 -458.349919) (xy 526.711991 -458.221759) (xy 526.704041 -458.092864) (xy 474.307916 -458.092864)
			(xy 474.307916 -461.028288) (xy 474.308425 -461.084096) (xy 474.316765 -461.195399) (xy 474.3334 -461.305768)
			(xy 474.358236 -461.414584) (xy 474.391134 -461.521241) (xy 474.431912 -461.625141) (xy 474.480339 -461.725703)
			(xy 474.536147 -461.822365) (xy 474.599022 -461.914586) (xy 474.668612 -462.00185) (xy 474.74453 -462.08367)
			(xy 474.82635 -462.159588) (xy 474.913614 -462.229178) (xy 475.005835 -462.292053) (xy 475.102497 -462.347861)
			(xy 475.203059 -462.396288) (xy 475.306959 -462.437066) (xy 475.413616 -462.469964) (xy 475.522432 -462.4948)
			(xy 475.632801 -462.511435) (xy 475.744104 -462.519775) (xy 475.799912 -462.520284)
		)
		(stroke
			(width 0)
			(type solid)
		)
		(fill yes)
		(layer "In1.Cu")
		(net "T1_GND")
	)
	(gr_poly
		(pts
			(xy 256.292096 -31.120588) (xy 256.292096 -11.780012) (xy 256.29258 -11.709658) (xy 256.300469 -11.56917)
			(xy 256.316223 -11.429347) (xy 256.339792 -11.290626) (xy 256.371101 -11.153445) (xy 256.410054 -11.018236)
			(xy 256.456527 -10.885423) (xy 256.510373 -10.755425) (xy 256.571423 -10.628651) (xy 256.639486 -10.505499)
			(xy 256.714347 -10.386357) (xy 256.795771 -10.2716) (xy 256.883501 -10.16159) (xy 256.977261 -10.056671)
			(xy 257.076757 -9.957175) (xy 257.181674 -9.863414) (xy 257.291684 -9.775683) (xy 257.406441 -9.694258)
			(xy 257.525582 -9.619396) (xy 257.648733 -9.551333) (xy 257.775507 -9.490281) (xy 257.905504 -9.436434)
			(xy 258.038317 -9.38996) (xy 258.173526 -9.351006) (xy 258.310706 -9.319695) (xy 258.449427 -9.296125)
			(xy 258.589251 -9.280371) (xy 258.729738 -9.272481) (xy 258.800092 -9.272016) (xy 383.601976 -9.272016)
			(xy 383.657784 -9.271508) (xy 383.769089 -9.263168) (xy 383.879459 -9.246534) (xy 383.988278 -9.221699)
			(xy 384.094936 -9.188801) (xy 384.198838 -9.148025) (xy 384.299402 -9.099598) (xy 384.396066 -9.043791)
			(xy 384.488289 -8.980916) (xy 384.575555 -8.911326) (xy 384.657377 -8.835408) (xy 384.733297 -8.753588)
			(xy 384.80289 -8.666324) (xy 384.865767 -8.574103) (xy 384.921577 -8.477441) (xy 384.970007 -8.376878)
			(xy 385.010787 -8.272978) (xy 385.043688 -8.16632) (xy 385.068526 -8.057503) (xy 385.085163 -7.947133)
			(xy 385.093506 -7.835828) (xy 385.093972 -7.78002) (xy 385.093972 0.999998) (xy 385.094465 1.070352)
			(xy 385.102355 1.210839) (xy 385.118109 1.350662) (xy 385.141678 1.489383) (xy 385.172988 1.626563)
			(xy 385.211941 1.761772) (xy 385.258413 1.894584) (xy 385.312259 2.024582) (xy 385.37331 2.151356)
			(xy 385.441373 2.274507) (xy 385.516233 2.393649) (xy 385.597656 2.508405) (xy 385.685386 2.618416)
			(xy 385.779146 2.723335) (xy 385.878641 2.822831) (xy 385.983558 2.916592) (xy 386.093567 3.004323)
			(xy 386.208323 3.085748) (xy 386.327463 3.16061) (xy 386.450614 3.228674) (xy 386.577387 3.289727)
			(xy 386.707384 3.343575) (xy 386.840195 3.390049) (xy 386.975404 3.429003) (xy 387.112584 3.460315)
			(xy 387.251304 3.483887) (xy 387.391127 3.499643) (xy 387.531614 3.507534) (xy 387.601968 3.507994)
			(xy 456.202034 3.507994) (xy 456.272387 3.5075) (xy 456.412872 3.499608) (xy 456.552693 3.483853)
			(xy 456.691411 3.460282) (xy 456.828589 3.42897) (xy 456.963796 3.390016) (xy 457.096605 3.343542)
			(xy 457.226601 3.289695) (xy 457.353372 3.228644) (xy 457.476521 3.16058) (xy 457.595659 3.085719)
			(xy 457.710413 3.004295) (xy 457.820421 2.916565) (xy 457.925337 2.822806) (xy 458.02483 2.723311)
			(xy 458.118589 2.618393) (xy 458.206317 2.508384) (xy 458.287739 2.393629) (xy 458.362598 2.27449)
			(xy 458.43066 2.15134) (xy 458.49171 2.024568) (xy 458.545555 1.894572) (xy 458.592027 1.761761)
			(xy 458.630979 1.626554) (xy 458.662289 1.489376) (xy 458.685858 1.350658) (xy 458.701612 1.210836)
			(xy 458.709501 1.070351) (xy 458.71003 0.999998) (xy 458.71003 -7.78002) (xy 458.71054 -7.835827)
			(xy 458.718882 -7.947128) (xy 458.735519 -8.057494) (xy 458.760357 -8.166309) (xy 458.793257 -8.272963)
			(xy 458.834035 -8.37686) (xy 458.882464 -8.47742) (xy 458.938272 -8.574079) (xy 459.001148 -8.666297)
			(xy 459.070739 -8.753559) (xy 459.146656 -8.835376) (xy 459.228476 -8.911291) (xy 459.31574 -8.98088)
			(xy 459.40796 -9.043752) (xy 459.504621 -9.099557) (xy 459.605182 -9.147983) (xy 459.70908 -9.188758)
			(xy 459.815736 -9.221655) (xy 459.924551 -9.24649) (xy 460.034918 -9.263123) (xy 460.146219 -9.271462)
			(xy 460.202026 -9.272016) (xy 464.327748 -9.272016) (xy 464.332574 -9.271) (xy 464.357024 -9.266474)
			(xy 464.406516 -9.261643) (xy 464.43138 -9.261348) (xy 464.456244 -9.26164) (xy 464.505735 -9.266479)
			(xy 464.530186 -9.271) (xy 464.535012 -9.272016) (xy 469.799924 -9.272016) (xy 469.855731 -9.271493)
			(xy 469.967032 -9.263151) (xy 470.077399 -9.246514) (xy 470.186213 -9.221677) (xy 470.292868 -9.188777)
			(xy 470.396765 -9.147999) (xy 470.497325 -9.099571) (xy 470.593985 -9.043764) (xy 470.686204 -8.980889)
			(xy 470.773467 -8.911299) (xy 470.855285 -8.835382) (xy 470.931202 -8.753564) (xy 471.000791 -8.666301)
			(xy 471.063666 -8.574082) (xy 471.119473 -8.477422) (xy 471.167901 -8.376862) (xy 471.208678 -8.272964)
			(xy 471.241578 -8.166309) (xy 471.266415 -8.057495) (xy 471.283051 -7.947128) (xy 471.291394 -7.835827)
			(xy 471.29192 -7.78002) (xy 471.29192 10.40003) (xy 471.291397 10.455837) (xy 471.283054 10.567138)
			(xy 471.266417 10.677504) (xy 471.241579 10.786319) (xy 471.208679 10.892973) (xy 471.167901 10.99687)
			(xy 471.119473 11.09743) (xy 471.063666 11.194089) (xy 471.000791 11.286308) (xy 470.931201 11.373571)
			(xy 470.855284 11.455389) (xy 470.773466 11.531305) (xy 470.686203 11.600895) (xy 470.593984 11.663769)
			(xy 470.497324 11.719576) (xy 470.396765 11.768004) (xy 470.292867 11.808781) (xy 470.186213 11.841681)
			(xy 470.077398 11.866518) (xy 469.967032 11.883155) (xy 469.855731 11.891497) (xy 469.799924 11.892026)
			(xy 1.999996 11.892026) (xy 1.944189 11.891504) (xy 1.832887 11.883163) (xy 1.72252 11.866527) (xy 1.613705 11.841691)
			(xy 1.50705 11.808792) (xy 1.403151 11.768014) (xy 1.302591 11.719587) (xy 1.20593 11.66378) (xy 1.113711 11.600905)
			(xy 1.026448 11.531315) (xy 0.944629 11.455398) (xy 0.868712 11.373579) (xy 0.799122 11.286316) (xy 0.736248 11.194096)
			(xy 0.680441 11.097436) (xy 0.632014 10.996875) (xy 0.591237 10.892977) (xy 0.558338 10.786321) (xy 0.533502 10.677506)
			(xy 0.516867 10.567139) (xy 0.508526 10.455837) (xy 0.508 10.40003) (xy 0.508 7.335466) (xy 2.904225 7.335466)
			(xy 2.904225 7.464606) (xy 2.912175 7.593501) (xy 2.928045 7.721661) (xy 2.951774 7.848602) (xy 2.983273 7.973841)
			(xy 3.022422 8.096904) (xy 3.069073 8.217323) (xy 3.123048 8.334642) (xy 3.184143 8.448416) (xy 3.252126 8.558213)
			(xy 3.32674 8.663616) (xy 3.407701 8.764226) (xy 3.494701 8.859661) (xy 3.587412 8.94956) (xy 3.685482 9.033581)
			(xy 3.788537 9.111405) (xy 3.896188 9.182737) (xy 4.008027 9.247307) (xy 4.123628 9.304869) (xy 4.242553 9.355206)
			(xy 4.364352 9.398126) (xy 4.488562 9.433467) (xy 4.614711 9.461094) (xy 4.742323 9.480903) (xy 4.870912 9.492819)
			(xy 4.99999 9.496796) (xy 5.129068 9.492819) (xy 5.257657 9.480903) (xy 5.385269 9.461094) (xy 5.511418 9.433467)
			(xy 5.635628 9.398126) (xy 5.757427 9.355206) (xy 5.876352 9.304869) (xy 5.991953 9.247307) (xy 6.020338 9.230919)
			(xy 256.921241 9.230919) (xy 256.921241 9.316669) (xy 256.929153 9.402052) (xy 256.944909 9.486342)
			(xy 256.968376 9.568818) (xy 256.999352 9.648777) (xy 257.037574 9.725537) (xy 257.082715 9.798443)
			(xy 257.134391 9.866872) (xy 257.19216 9.930242) (xy 257.25553 9.988011) (xy 257.323959 10.039687)
			(xy 257.396865 10.084828) (xy 257.473625 10.12305) (xy 257.553584 10.154026) (xy 257.63606 10.177493)
			(xy 257.72035 10.193249) (xy 257.805733 10.201161) (xy 257.891483 10.201161) (xy 257.976866 10.193249)
			(xy 258.061156 10.177493) (xy 258.143632 10.154026) (xy 258.223591 10.12305) (xy 258.300351 10.084828)
			(xy 258.373257 10.039687) (xy 258.441686 9.988011) (xy 258.505056 9.930242) (xy 258.562825 9.866872)
			(xy 258.614501 9.798443) (xy 258.659642 9.725537) (xy 258.697864 9.648777) (xy 258.72884 9.568818)
			(xy 258.752307 9.486342) (xy 258.768063 9.402052) (xy 258.775975 9.316669) (xy 258.77647 9.273794)
			(xy 258.775975 9.230919) (xy 263.271241 9.230919) (xy 263.271241 9.316669) (xy 263.279153 9.402052)
			(xy 263.294909 9.486342) (xy 263.318376 9.568818) (xy 263.349352 9.648777) (xy 263.387574 9.725537)
			(xy 263.432715 9.798443) (xy 263.484391 9.866872) (xy 263.54216 9.930242) (xy 263.60553 9.988011)
			(xy 263.673959 10.039687) (xy 263.746865 10.084828) (xy 263.823625 10.12305) (xy 263.903584 10.154026)
			(xy 263.98606 10.177493) (xy 264.07035 10.193249) (xy 264.155733 10.201161) (xy 264.241483 10.201161)
			(xy 264.326866 10.193249) (xy 264.411156 10.177493) (xy 264.493632 10.154026) (xy 264.573591 10.12305)
			(xy 264.650351 10.084828) (xy 264.723257 10.039687) (xy 264.791686 9.988011) (xy 264.855056 9.930242)
			(xy 264.912825 9.866872) (xy 264.964501 9.798443) (xy 265.009642 9.725537) (xy 265.047864 9.648777)
			(xy 265.07884 9.568818) (xy 265.102307 9.486342) (xy 265.118063 9.402052) (xy 265.125975 9.316669)
			(xy 265.12647 9.273794) (xy 265.125975 9.230919) (xy 324.845921 9.230919) (xy 324.845921 9.316669)
			(xy 324.853833 9.402052) (xy 324.869589 9.486342) (xy 324.893056 9.568818) (xy 324.924032 9.648777)
			(xy 324.962254 9.725537) (xy 325.007395 9.798443) (xy 325.059071 9.866872) (xy 325.11684 9.930242)
			(xy 325.18021 9.988011) (xy 325.248639 10.039687) (xy 325.321545 10.084828) (xy 325.398305 10.12305)
			(xy 325.478264 10.154026) (xy 325.56074 10.177493) (xy 325.64503 10.193249) (xy 325.730413 10.201161)
			(xy 325.816163 10.201161) (xy 325.901546 10.193249) (xy 325.985836 10.177493) (xy 326.068312 10.154026)
			(xy 326.148271 10.12305) (xy 326.225031 10.084828) (xy 326.297937 10.039687) (xy 326.366366 9.988011)
			(xy 326.429736 9.930242) (xy 326.487505 9.866872) (xy 326.539181 9.798443) (xy 326.584322 9.725537)
			(xy 326.622544 9.648777) (xy 326.65352 9.568818) (xy 326.676987 9.486342) (xy 326.692743 9.402052)
			(xy 326.700655 9.316669) (xy 326.70115 9.273794) (xy 326.700655 9.230919) (xy 331.195921 9.230919)
			(xy 331.195921 9.316669) (xy 331.203833 9.402052) (xy 331.219589 9.486342) (xy 331.243056 9.568818)
			(xy 331.274032 9.648777) (xy 331.312254 9.725537) (xy 331.357395 9.798443) (xy 331.409071 9.866872)
			(xy 331.46684 9.930242) (xy 331.53021 9.988011) (xy 331.598639 10.039687) (xy 331.671545 10.084828)
			(xy 331.748305 10.12305) (xy 331.828264 10.154026) (xy 331.91074 10.177493) (xy 331.99503 10.193249)
			(xy 332.080413 10.201161) (xy 332.166163 10.201161) (xy 332.251546 10.193249) (xy 332.335836 10.177493)
			(xy 332.418312 10.154026) (xy 332.498271 10.12305) (xy 332.575031 10.084828) (xy 332.647937 10.039687)
			(xy 332.716366 9.988011) (xy 332.779736 9.930242) (xy 332.837505 9.866872) (xy 332.889181 9.798443)
			(xy 332.934322 9.725537) (xy 332.972544 9.648777) (xy 333.00352 9.568818) (xy 333.026987 9.486342)
			(xy 333.042743 9.402052) (xy 333.050655 9.316669) (xy 333.05115 9.273794) (xy 333.050655 9.230919)
			(xy 335.488267 9.230919) (xy 335.488267 9.316669) (xy 335.496179 9.402052) (xy 335.511935 9.486342)
			(xy 335.535402 9.568818) (xy 335.566378 9.648777) (xy 335.6046 9.725537) (xy 335.649741 9.798443)
			(xy 335.701417 9.866872) (xy 335.759186 9.930242) (xy 335.822556 9.988011) (xy 335.890985 10.039687)
			(xy 335.963891 10.084828) (xy 336.040651 10.12305) (xy 336.12061 10.154026) (xy 336.203086 10.177493)
			(xy 336.287376 10.193249) (xy 336.372759 10.201161) (xy 336.458509 10.201161) (xy 336.543892 10.193249)
			(xy 336.628182 10.177493) (xy 336.710658 10.154026) (xy 336.790617 10.12305) (xy 336.867377 10.084828)
			(xy 336.940283 10.039687) (xy 337.008712 9.988011) (xy 337.072082 9.930242) (xy 337.129851 9.866872)
			(xy 337.181527 9.798443) (xy 337.226668 9.725537) (xy 337.26489 9.648777) (xy 337.295866 9.568818)
			(xy 337.319333 9.486342) (xy 337.335089 9.402052) (xy 337.343001 9.316669) (xy 337.343496 9.273794)
			(xy 337.343001 9.230919) (xy 341.838267 9.230919) (xy 341.838267 9.316669) (xy 341.846179 9.402052)
			(xy 341.861935 9.486342) (xy 341.885402 9.568818) (xy 341.916378 9.648777) (xy 341.9546 9.725537)
			(xy 341.999741 9.798443) (xy 342.051417 9.866872) (xy 342.109186 9.930242) (xy 342.172556 9.988011)
			(xy 342.240985 10.039687) (xy 342.313891 10.084828) (xy 342.390651 10.12305) (xy 342.47061 10.154026)
			(xy 342.553086 10.177493) (xy 342.637376 10.193249) (xy 342.722759 10.201161) (xy 342.808509 10.201161)
			(xy 342.893892 10.193249) (xy 342.978182 10.177493) (xy 343.060658 10.154026) (xy 343.140617 10.12305)
			(xy 343.217377 10.084828) (xy 343.290283 10.039687) (xy 343.358712 9.988011) (xy 343.422082 9.930242)
			(xy 343.479851 9.866872) (xy 343.531527 9.798443) (xy 343.576668 9.725537) (xy 343.61489 9.648777)
			(xy 343.645866 9.568818) (xy 343.669333 9.486342) (xy 343.685089 9.402052) (xy 343.693001 9.316669)
			(xy 343.693496 9.273794) (xy 343.693001 9.230919) (xy 373.705107 9.230919) (xy 373.705107 9.316669)
			(xy 373.713019 9.402052) (xy 373.728775 9.486342) (xy 373.752242 9.568818) (xy 373.783218 9.648777)
			(xy 373.82144 9.725537) (xy 373.866581 9.798443) (xy 373.918257 9.866872) (xy 373.976026 9.930242)
			(xy 374.039396 9.988011) (xy 374.107825 10.039687) (xy 374.180731 10.084828) (xy 374.257491 10.12305)
			(xy 374.33745 10.154026) (xy 374.419926 10.177493) (xy 374.504216 10.193249) (xy 374.589599 10.201161)
			(xy 374.675349 10.201161) (xy 374.760732 10.193249) (xy 374.845022 10.177493) (xy 374.927498 10.154026)
			(xy 375.007457 10.12305) (xy 375.084217 10.084828) (xy 375.157123 10.039687) (xy 375.225552 9.988011)
			(xy 375.288922 9.930242) (xy 375.346691 9.866872) (xy 375.398367 9.798443) (xy 375.443508 9.725537)
			(xy 375.48173 9.648777) (xy 375.512706 9.568818) (xy 375.536173 9.486342) (xy 375.551929 9.402052)
			(xy 375.559841 9.316669) (xy 375.560336 9.273794) (xy 375.559841 9.230919) (xy 380.055107 9.230919)
			(xy 380.055107 9.316669) (xy 380.063019 9.402052) (xy 380.078775 9.486342) (xy 380.102242 9.568818)
			(xy 380.133218 9.648777) (xy 380.17144 9.725537) (xy 380.216581 9.798443) (xy 380.268257 9.866872)
			(xy 380.326026 9.930242) (xy 380.389396 9.988011) (xy 380.457825 10.039687) (xy 380.530731 10.084828)
			(xy 380.607491 10.12305) (xy 380.68745 10.154026) (xy 380.769926 10.177493) (xy 380.854216 10.193249)
			(xy 380.939599 10.201161) (xy 381.025349 10.201161) (xy 381.110732 10.193249) (xy 381.195022 10.177493)
			(xy 381.277498 10.154026) (xy 381.357457 10.12305) (xy 381.434217 10.084828) (xy 381.507123 10.039687)
			(xy 381.575552 9.988011) (xy 381.638922 9.930242) (xy 381.696691 9.866872) (xy 381.748367 9.798443)
			(xy 381.793508 9.725537) (xy 381.83173 9.648777) (xy 381.862706 9.568818) (xy 381.886173 9.486342)
			(xy 381.901929 9.402052) (xy 381.909841 9.316669) (xy 381.910336 9.273794) (xy 381.909841 9.230919)
			(xy 381.901929 9.145536) (xy 381.886173 9.061246) (xy 381.862706 8.97877) (xy 381.83173 8.898811)
			(xy 381.793508 8.822051) (xy 381.748367 8.749145) (xy 381.696691 8.680716) (xy 381.638922 8.617346)
			(xy 381.575552 8.559577) (xy 381.507123 8.507901) (xy 381.434217 8.46276) (xy 381.357457 8.424538)
			(xy 381.277498 8.393562) (xy 381.195022 8.370095) (xy 381.110732 8.354339) (xy 381.025349 8.346427)
			(xy 380.939599 8.346427) (xy 380.854216 8.354339) (xy 380.769926 8.370095) (xy 380.68745 8.393562)
			(xy 380.607491 8.424538) (xy 380.530731 8.46276) (xy 380.457825 8.507901) (xy 380.389396 8.559577)
			(xy 380.326026 8.617346) (xy 380.268257 8.680716) (xy 380.216581 8.749145) (xy 380.17144 8.822051)
			(xy 380.133218 8.898811) (xy 380.102242 8.97877) (xy 380.078775 9.061246) (xy 380.063019 9.145536)
			(xy 380.055107 9.230919) (xy 375.559841 9.230919) (xy 375.551929 9.145536) (xy 375.536173 9.061246)
			(xy 375.512706 8.97877) (xy 375.48173 8.898811) (xy 375.443508 8.822051) (xy 375.398367 8.749145)
			(xy 375.346691 8.680716) (xy 375.288922 8.617346) (xy 375.225552 8.559577) (xy 375.157123 8.507901)
			(xy 375.084217 8.46276) (xy 375.007457 8.424538) (xy 374.927498 8.393562) (xy 374.845022 8.370095)
			(xy 374.760732 8.354339) (xy 374.675349 8.346427) (xy 374.589599 8.346427) (xy 374.504216 8.354339)
			(xy 374.419926 8.370095) (xy 374.33745 8.393562) (xy 374.257491 8.424538) (xy 374.180731 8.46276)
			(xy 374.107825 8.507901) (xy 374.039396 8.559577) (xy 373.976026 8.617346) (xy 373.918257 8.680716)
			(xy 373.866581 8.749145) (xy 373.82144 8.822051) (xy 373.783218 8.898811) (xy 373.752242 8.97877)
			(xy 373.728775 9.061246) (xy 373.713019 9.145536) (xy 373.705107 9.230919) (xy 343.693001 9.230919)
			(xy 343.685089 9.145536) (xy 343.669333 9.061246) (xy 343.645866 8.97877) (xy 343.61489 8.898811)
			(xy 343.576668 8.822051) (xy 343.531527 8.749145) (xy 343.479851 8.680716) (xy 343.422082 8.617346)
			(xy 343.358712 8.559577) (xy 343.290283 8.507901) (xy 343.217377 8.46276) (xy 343.140617 8.424538)
			(xy 343.060658 8.393562) (xy 342.978182 8.370095) (xy 342.893892 8.354339) (xy 342.808509 8.346427)
			(xy 342.722759 8.346427) (xy 342.637376 8.354339) (xy 342.553086 8.370095) (xy 342.47061 8.393562)
			(xy 342.390651 8.424538) (xy 342.313891 8.46276) (xy 342.240985 8.507901) (xy 342.172556 8.559577)
			(xy 342.109186 8.617346) (xy 342.051417 8.680716) (xy 341.999741 8.749145) (xy 341.9546 8.822051)
			(xy 341.916378 8.898811) (xy 341.885402 8.97877) (xy 341.861935 9.061246) (xy 341.846179 9.145536)
			(xy 341.838267 9.230919) (xy 337.343001 9.230919) (xy 337.335089 9.145536) (xy 337.319333 9.061246)
			(xy 337.295866 8.97877) (xy 337.26489 8.898811) (xy 337.226668 8.822051) (xy 337.181527 8.749145)
			(xy 337.129851 8.680716) (xy 337.072082 8.617346) (xy 337.008712 8.559577) (xy 336.940283 8.507901)
			(xy 336.867377 8.46276) (xy 336.790617 8.424538) (xy 336.710658 8.393562) (xy 336.628182 8.370095)
			(xy 336.543892 8.354339) (xy 336.458509 8.346427) (xy 336.372759 8.346427) (xy 336.287376 8.354339)
			(xy 336.203086 8.370095) (xy 336.12061 8.393562) (xy 336.040651 8.424538) (xy 335.963891 8.46276)
			(xy 335.890985 8.507901) (xy 335.822556 8.559577) (xy 335.759186 8.617346) (xy 335.701417 8.680716)
			(xy 335.649741 8.749145) (xy 335.6046 8.822051) (xy 335.566378 8.898811) (xy 335.535402 8.97877)
			(xy 335.511935 9.061246) (xy 335.496179 9.145536) (xy 335.488267 9.230919) (xy 333.050655 9.230919)
			(xy 333.042743 9.145536) (xy 333.026987 9.061246) (xy 333.00352 8.97877) (xy 332.972544 8.898811)
			(xy 332.934322 8.822051) (xy 332.889181 8.749145) (xy 332.837505 8.680716) (xy 332.779736 8.617346)
			(xy 332.716366 8.559577) (xy 332.647937 8.507901) (xy 332.575031 8.46276) (xy 332.498271 8.424538)
			(xy 332.418312 8.393562) (xy 332.335836 8.370095) (xy 332.251546 8.354339) (xy 332.166163 8.346427)
			(xy 332.080413 8.346427) (xy 331.99503 8.354339) (xy 331.91074 8.370095) (xy 331.828264 8.393562)
			(xy 331.748305 8.424538) (xy 331.671545 8.46276) (xy 331.598639 8.507901) (xy 331.53021 8.559577)
			(xy 331.46684 8.617346) (xy 331.409071 8.680716) (xy 331.357395 8.749145) (xy 331.312254 8.822051)
			(xy 331.274032 8.898811) (xy 331.243056 8.97877) (xy 331.219589 9.061246) (xy 331.203833 9.145536)
			(xy 331.195921 9.230919) (xy 326.700655 9.230919) (xy 326.692743 9.145536) (xy 326.676987 9.061246)
			(xy 326.65352 8.97877) (xy 326.622544 8.898811) (xy 326.584322 8.822051) (xy 326.539181 8.749145)
			(xy 326.487505 8.680716) (xy 326.429736 8.617346) (xy 326.366366 8.559577) (xy 326.297937 8.507901)
			(xy 326.225031 8.46276) (xy 326.148271 8.424538) (xy 326.068312 8.393562) (xy 325.985836 8.370095)
			(xy 325.901546 8.354339) (xy 325.816163 8.346427) (xy 325.730413 8.346427) (xy 325.64503 8.354339)
			(xy 325.56074 8.370095) (xy 325.478264 8.393562) (xy 325.398305 8.424538) (xy 325.321545 8.46276)
			(xy 325.248639 8.507901) (xy 325.18021 8.559577) (xy 325.11684 8.617346) (xy 325.059071 8.680716)
			(xy 325.007395 8.749145) (xy 324.962254 8.822051) (xy 324.924032 8.898811) (xy 324.893056 8.97877)
			(xy 324.869589 9.061246) (xy 324.853833 9.145536) (xy 324.845921 9.230919) (xy 265.125975 9.230919)
			(xy 265.118063 9.145536) (xy 265.102307 9.061246) (xy 265.07884 8.97877) (xy 265.047864 8.898811)
			(xy 265.009642 8.822051) (xy 264.964501 8.749145) (xy 264.912825 8.680716) (xy 264.855056 8.617346)
			(xy 264.791686 8.559577) (xy 264.723257 8.507901) (xy 264.650351 8.46276) (xy 264.573591 8.424538)
			(xy 264.493632 8.393562) (xy 264.411156 8.370095) (xy 264.326866 8.354339) (xy 264.241483 8.346427)
			(xy 264.155733 8.346427) (xy 264.07035 8.354339) (xy 263.98606 8.370095) (xy 263.903584 8.393562)
			(xy 263.823625 8.424538) (xy 263.746865 8.46276) (xy 263.673959 8.507901) (xy 263.60553 8.559577)
			(xy 263.54216 8.617346) (xy 263.484391 8.680716) (xy 263.432715 8.749145) (xy 263.387574 8.822051)
			(xy 263.349352 8.898811) (xy 263.318376 8.97877) (xy 263.294909 9.061246) (xy 263.279153 9.145536)
			(xy 263.271241 9.230919) (xy 258.775975 9.230919) (xy 258.768063 9.145536) (xy 258.752307 9.061246)
			(xy 258.72884 8.97877) (xy 258.697864 8.898811) (xy 258.659642 8.822051) (xy 258.614501 8.749145)
			(xy 258.562825 8.680716) (xy 258.505056 8.617346) (xy 258.441686 8.559577) (xy 258.373257 8.507901)
			(xy 258.300351 8.46276) (xy 258.223591 8.424538) (xy 258.143632 8.393562) (xy 258.061156 8.370095)
			(xy 257.976866 8.354339) (xy 257.891483 8.346427) (xy 257.805733 8.346427) (xy 257.72035 8.354339)
			(xy 257.63606 8.370095) (xy 257.553584 8.393562) (xy 257.473625 8.424538) (xy 257.396865 8.46276)
			(xy 257.323959 8.507901) (xy 257.25553 8.559577) (xy 257.19216 8.617346) (xy 257.134391 8.680716)
			(xy 257.082715 8.749145) (xy 257.037574 8.822051) (xy 256.999352 8.898811) (xy 256.968376 8.97877)
			(xy 256.944909 9.061246) (xy 256.929153 9.145536) (xy 256.921241 9.230919) (xy 6.020338 9.230919)
			(xy 6.103792 9.182737) (xy 6.211443 9.111405) (xy 6.314498 9.033581) (xy 6.412568 8.94956) (xy 6.505279 8.859661)
			(xy 6.592279 8.764226) (xy 6.67324 8.663616) (xy 6.747854 8.558213) (xy 6.815837 8.448416) (xy 6.876932 8.334642)
			(xy 6.930907 8.217323) (xy 6.977558 8.096904) (xy 7.016707 7.973841) (xy 7.048206 7.848602) (xy 7.071935 7.721661)
			(xy 7.087805 7.593501) (xy 7.095755 7.464606) (xy 7.096252 7.400036) (xy 7.095755 7.335466) (xy 7.087805 7.206571)
			(xy 7.071935 7.078411) (xy 7.048206 6.95147) (xy 7.016707 6.826231) (xy 6.977558 6.703168) (xy 6.97173 6.688125)
			(xy 178.335673 6.688125) (xy 178.335673 6.773875) (xy 178.343585 6.859258) (xy 178.359341 6.943548)
			(xy 178.382808 7.026024) (xy 178.413784 7.105983) (xy 178.452006 7.182743) (xy 178.497147 7.255649)
			(xy 178.548823 7.324078) (xy 178.606592 7.387448) (xy 178.669962 7.445217) (xy 178.738391 7.496893)
			(xy 178.811297 7.542034) (xy 178.888057 7.580256) (xy 178.968016 7.611232) (xy 179.050492 7.634699)
			(xy 179.134782 7.650455) (xy 179.220165 7.658367) (xy 179.305915 7.658367) (xy 179.391298 7.650455)
			(xy 179.475588 7.634699) (xy 179.558064 7.611232) (xy 179.638023 7.580256) (xy 179.714783 7.542034)
			(xy 179.787689 7.496893) (xy 179.856118 7.445217) (xy 179.919488 7.387448) (xy 179.977257 7.324078)
			(xy 180.028933 7.255649) (xy 180.074074 7.182743) (xy 180.112296 7.105983) (xy 180.143272 7.026024)
			(xy 180.166739 6.943548) (xy 180.182495 6.859258) (xy 180.190407 6.773875) (xy 180.190902 6.731)
			(xy 180.190407 6.688125) (xy 184.685673 6.688125) (xy 184.685673 6.773875) (xy 184.693585 6.859258)
			(xy 184.709341 6.943548) (xy 184.732808 7.026024) (xy 184.763784 7.105983) (xy 184.802006 7.182743)
			(xy 184.847147 7.255649) (xy 184.898823 7.324078) (xy 184.956592 7.387448) (xy 185.019962 7.445217)
			(xy 185.088391 7.496893) (xy 185.161297 7.542034) (xy 185.238057 7.580256) (xy 185.318016 7.611232)
			(xy 185.400492 7.634699) (xy 185.484782 7.650455) (xy 185.570165 7.658367) (xy 185.655915 7.658367)
			(xy 185.741298 7.650455) (xy 185.825588 7.634699) (xy 185.908064 7.611232) (xy 185.988023 7.580256)
			(xy 186.064783 7.542034) (xy 186.137689 7.496893) (xy 186.206118 7.445217) (xy 186.269488 7.387448)
			(xy 186.327257 7.324078) (xy 186.378933 7.255649) (xy 186.424074 7.182743) (xy 186.462296 7.105983)
			(xy 186.493272 7.026024) (xy 186.516739 6.943548) (xy 186.532495 6.859258) (xy 186.540407 6.773875)
			(xy 186.540902 6.731) (xy 186.540407 6.688125) (xy 246.260353 6.688125) (xy 246.260353 6.773875)
			(xy 246.268265 6.859258) (xy 246.284021 6.943548) (xy 246.307488 7.026024) (xy 246.338464 7.105983)
			(xy 246.376686 7.182743) (xy 246.421827 7.255649) (xy 246.473503 7.324078) (xy 246.531272 7.387448)
			(xy 246.594642 7.445217) (xy 246.663071 7.496893) (xy 246.735977 7.542034) (xy 246.812737 7.580256)
			(xy 246.892696 7.611232) (xy 246.975172 7.634699) (xy 247.059462 7.650455) (xy 247.144845 7.658367)
			(xy 247.230595 7.658367) (xy 247.315978 7.650455) (xy 247.400268 7.634699) (xy 247.482744 7.611232)
			(xy 247.562703 7.580256) (xy 247.639463 7.542034) (xy 247.712369 7.496893) (xy 247.780798 7.445217)
			(xy 247.844168 7.387448) (xy 247.901937 7.324078) (xy 247.953613 7.255649) (xy 247.998754 7.182743)
			(xy 248.036976 7.105983) (xy 248.067952 7.026024) (xy 248.091419 6.943548) (xy 248.107175 6.859258)
			(xy 248.115087 6.773875) (xy 248.115582 6.731) (xy 248.115087 6.688125) (xy 252.610353 6.688125)
			(xy 252.610353 6.773875) (xy 252.618265 6.859258) (xy 252.634021 6.943548) (xy 252.657488 7.026024)
			(xy 252.688464 7.105983) (xy 252.726686 7.182743) (xy 252.771827 7.255649) (xy 252.823503 7.324078)
			(xy 252.881272 7.387448) (xy 252.944642 7.445217) (xy 253.013071 7.496893) (xy 253.085977 7.542034)
			(xy 253.162737 7.580256) (xy 253.242696 7.611232) (xy 253.325172 7.634699) (xy 253.409462 7.650455)
			(xy 253.494845 7.658367) (xy 253.580595 7.658367) (xy 253.665978 7.650455) (xy 253.750268 7.634699)
			(xy 253.832744 7.611232) (xy 253.912703 7.580256) (xy 253.989463 7.542034) (xy 254.062369 7.496893)
			(xy 254.130798 7.445217) (xy 254.194168 7.387448) (xy 254.251937 7.324078) (xy 254.303613 7.255649)
			(xy 254.348754 7.182743) (xy 254.386976 7.105983) (xy 254.417952 7.026024) (xy 254.441419 6.943548)
			(xy 254.457175 6.859258) (xy 254.465087 6.773875) (xy 254.465582 6.731) (xy 254.465119 6.690919)
			(xy 256.921241 6.690919) (xy 256.921241 6.776669) (xy 256.929153 6.862052) (xy 256.944909 6.946342)
			(xy 256.968376 7.028818) (xy 256.999352 7.108777) (xy 257.037574 7.185537) (xy 257.082715 7.258443)
			(xy 257.134391 7.326872) (xy 257.19216 7.390242) (xy 257.25553 7.448011) (xy 257.323959 7.499687)
			(xy 257.396865 7.544828) (xy 257.473625 7.58305) (xy 257.553584 7.614026) (xy 257.63606 7.637493)
			(xy 257.72035 7.653249) (xy 257.805733 7.661161) (xy 257.891483 7.661161) (xy 257.976866 7.653249)
			(xy 258.061156 7.637493) (xy 258.143632 7.614026) (xy 258.223591 7.58305) (xy 258.245794 7.571994)
			(xy 261.85622 7.571994) (xy 261.85622 8.435594) (xy 261.856706 8.462863) (xy 261.864468 8.516847)
			(xy 261.879833 8.569177) (xy 261.90249 8.618787) (xy 261.931976 8.664668) (xy 261.967691 8.705885)
			(xy 262.008908 8.7416) (xy 262.054789 8.771086) (xy 262.104399 8.793743) (xy 262.156729 8.809108)
			(xy 262.210713 8.81687) (xy 262.265251 8.81687) (xy 262.319235 8.809108) (xy 262.371565 8.793743)
			(xy 262.421175 8.771086) (xy 262.467056 8.7416) (xy 262.508273 8.705885) (xy 262.543988 8.664668)
			(xy 262.573474 8.618787) (xy 262.596131 8.569177) (xy 262.611496 8.516847) (xy 262.619258 8.462863)
			(xy 262.619744 8.435594) (xy 262.619744 7.571994) (xy 262.619258 7.544725) (xy 262.611496 7.490741)
			(xy 262.596131 7.438411) (xy 262.573474 7.388801) (xy 262.543988 7.34292) (xy 262.508273 7.301703)
			(xy 262.467056 7.265988) (xy 262.421175 7.236502) (xy 262.371565 7.213845) (xy 262.319235 7.19848)
			(xy 262.265251 7.190718) (xy 262.210713 7.190718) (xy 262.156729 7.19848) (xy 262.104399 7.213845)
			(xy 262.054789 7.236502) (xy 262.008908 7.265988) (xy 261.967691 7.301703) (xy 261.931976 7.34292)
			(xy 261.90249 7.388801) (xy 261.879833 7.438411) (xy 261.864468 7.490741) (xy 261.856706 7.544725)
			(xy 261.85622 7.571994) (xy 258.245794 7.571994) (xy 258.300351 7.544828) (xy 258.373257 7.499687)
			(xy 258.441686 7.448011) (xy 258.505056 7.390242) (xy 258.562825 7.326872) (xy 258.614501 7.258443)
			(xy 258.659642 7.185537) (xy 258.697864 7.108777) (xy 258.72884 7.028818) (xy 258.752307 6.946342)
			(xy 258.768063 6.862052) (xy 258.775975 6.776669) (xy 258.77647 6.733794) (xy 258.775975 6.690919)
			(xy 263.271241 6.690919) (xy 263.271241 6.776669) (xy 263.279153 6.862052) (xy 263.294909 6.946342)
			(xy 263.318376 7.028818) (xy 263.349352 7.108777) (xy 263.387574 7.185537) (xy 263.432715 7.258443)
			(xy 263.484391 7.326872) (xy 263.54216 7.390242) (xy 263.60553 7.448011) (xy 263.673959 7.499687)
			(xy 263.746865 7.544828) (xy 263.823625 7.58305) (xy 263.903584 7.614026) (xy 263.98606 7.637493)
			(xy 264.07035 7.653249) (xy 264.155733 7.661161) (xy 264.241483 7.661161) (xy 264.326866 7.653249)
			(xy 264.411156 7.637493) (xy 264.493632 7.614026) (xy 264.573591 7.58305) (xy 264.650351 7.544828)
			(xy 264.723257 7.499687) (xy 264.791686 7.448011) (xy 264.855056 7.390242) (xy 264.912825 7.326872)
			(xy 264.964501 7.258443) (xy 265.009642 7.185537) (xy 265.047864 7.108777) (xy 265.07884 7.028818)
			(xy 265.102307 6.946342) (xy 265.118063 6.862052) (xy 265.125975 6.776669) (xy 265.12647 6.733794)
			(xy 265.125975 6.690919) (xy 324.845921 6.690919) (xy 324.845921 6.776669) (xy 324.853833 6.862052)
			(xy 324.869589 6.946342) (xy 324.893056 7.028818) (xy 324.924032 7.108777) (xy 324.962254 7.185537)
			(xy 325.007395 7.258443) (xy 325.059071 7.326872) (xy 325.11684 7.390242) (xy 325.18021 7.448011)
			(xy 325.248639 7.499687) (xy 325.321545 7.544828) (xy 325.398305 7.58305) (xy 325.478264 7.614026)
			(xy 325.56074 7.637493) (xy 325.64503 7.653249) (xy 325.730413 7.661161) (xy 325.816163 7.661161)
			(xy 325.901546 7.653249) (xy 325.985836 7.637493) (xy 326.068312 7.614026) (xy 326.148271 7.58305)
			(xy 326.170474 7.571994) (xy 327.352152 7.571994) (xy 327.352152 8.435594) (xy 327.352638 8.462863)
			(xy 327.3604 8.516847) (xy 327.375765 8.569177) (xy 327.398422 8.618787) (xy 327.427908 8.664668)
			(xy 327.463623 8.705885) (xy 327.50484 8.7416) (xy 327.550721 8.771086) (xy 327.600331 8.793743)
			(xy 327.652661 8.809108) (xy 327.706645 8.81687) (xy 327.761183 8.81687) (xy 327.815167 8.809108)
			(xy 327.867497 8.793743) (xy 327.917107 8.771086) (xy 327.962988 8.7416) (xy 328.004205 8.705885)
			(xy 328.03992 8.664668) (xy 328.069406 8.618787) (xy 328.092063 8.569177) (xy 328.107428 8.516847)
			(xy 328.11519 8.462863) (xy 328.115676 8.435594) (xy 328.115676 7.571994) (xy 328.11519 7.544725)
			(xy 328.107428 7.490741) (xy 328.092063 7.438411) (xy 328.069406 7.388801) (xy 328.03992 7.34292)
			(xy 328.004205 7.301703) (xy 327.962988 7.265988) (xy 327.917107 7.236502) (xy 327.867497 7.213845)
			(xy 327.815167 7.19848) (xy 327.761183 7.190718) (xy 327.706645 7.190718) (xy 327.652661 7.19848)
			(xy 327.600331 7.213845) (xy 327.550721 7.236502) (xy 327.50484 7.265988) (xy 327.463623 7.301703)
			(xy 327.427908 7.34292) (xy 327.398422 7.388801) (xy 327.375765 7.438411) (xy 327.3604 7.490741)
			(xy 327.352638 7.544725) (xy 327.352152 7.571994) (xy 326.170474 7.571994) (xy 326.225031 7.544828)
			(xy 326.297937 7.499687) (xy 326.366366 7.448011) (xy 326.429736 7.390242) (xy 326.487505 7.326872)
			(xy 326.539181 7.258443) (xy 326.584322 7.185537) (xy 326.622544 7.108777) (xy 326.65352 7.028818)
			(xy 326.676987 6.946342) (xy 326.692743 6.862052) (xy 326.700655 6.776669) (xy 326.70115 6.733794)
			(xy 326.700655 6.690919) (xy 331.195921 6.690919) (xy 331.195921 6.776669) (xy 331.203833 6.862052)
			(xy 331.219589 6.946342) (xy 331.243056 7.028818) (xy 331.274032 7.108777) (xy 331.312254 7.185537)
			(xy 331.357395 7.258443) (xy 331.409071 7.326872) (xy 331.46684 7.390242) (xy 331.53021 7.448011)
			(xy 331.598639 7.499687) (xy 331.671545 7.544828) (xy 331.748305 7.58305) (xy 331.828264 7.614026)
			(xy 331.91074 7.637493) (xy 331.99503 7.653249) (xy 332.080413 7.661161) (xy 332.166163 7.661161)
			(xy 332.251546 7.653249) (xy 332.335836 7.637493) (xy 332.418312 7.614026) (xy 332.498271 7.58305)
			(xy 332.575031 7.544828) (xy 332.647937 7.499687) (xy 332.716366 7.448011) (xy 332.779736 7.390242)
			(xy 332.837505 7.326872) (xy 332.889181 7.258443) (xy 332.934322 7.185537) (xy 332.972544 7.108777)
			(xy 333.00352 7.028818) (xy 333.026987 6.946342) (xy 333.042743 6.862052) (xy 333.050655 6.776669)
			(xy 333.05115 6.733794) (xy 333.050655 6.690919) (xy 335.488267 6.690919) (xy 335.488267 6.776669)
			(xy 335.496179 6.862052) (xy 335.511935 6.946342) (xy 335.535402 7.028818) (xy 335.566378 7.108777)
			(xy 335.6046 7.185537) (xy 335.649741 7.258443) (xy 335.701417 7.326872) (xy 335.759186 7.390242)
			(xy 335.822556 7.448011) (xy 335.890985 7.499687) (xy 335.963891 7.544828) (xy 336.040651 7.58305)
			(xy 336.12061 7.614026) (xy 336.203086 7.637493) (xy 336.287376 7.653249) (xy 336.372759 7.661161)
			(xy 336.458509 7.661161) (xy 336.543892 7.653249) (xy 336.628182 7.637493) (xy 336.710658 7.614026)
			(xy 336.790617 7.58305) (xy 336.81282 7.571994) (xy 340.4235 7.571994) (xy 340.4235 8.435594) (xy 340.423986 8.462845)
			(xy 340.431742 8.516793) (xy 340.447097 8.569088) (xy 340.469739 8.618665) (xy 340.499205 8.664515)
			(xy 340.534896 8.705706) (xy 340.576087 8.741397) (xy 340.621937 8.770863) (xy 340.671514 8.793505)
			(xy 340.723809 8.80886) (xy 340.777757 8.816616) (xy 340.832259 8.816616) (xy 340.886207 8.80886)
			(xy 340.938502 8.793505) (xy 340.988079 8.770863) (xy 341.033929 8.741397) (xy 341.07512 8.705706)
			(xy 341.110811 8.664515) (xy 341.140277 8.618665) (xy 341.162919 8.569088) (xy 341.178274 8.516793)
			(xy 341.18603 8.462845) (xy 341.186516 8.435594) (xy 341.186516 7.571994) (xy 341.18603 7.544743)
			(xy 341.178274 7.490795) (xy 341.162919 7.4385) (xy 341.140277 7.388923) (xy 341.110811 7.343073)
			(xy 341.07512 7.301882) (xy 341.033929 7.266191) (xy 340.988079 7.236725) (xy 340.938502 7.214083)
			(xy 340.886207 7.198728) (xy 340.832259 7.190972) (xy 340.777757 7.190972) (xy 340.723809 7.198728)
			(xy 340.671514 7.214083) (xy 340.621937 7.236725) (xy 340.576087 7.266191) (xy 340.534896 7.301882)
			(xy 340.499205 7.343073) (xy 340.469739 7.388923) (xy 340.447097 7.4385) (xy 340.431742 7.490795)
			(xy 340.423986 7.544743) (xy 340.4235 7.571994) (xy 336.81282 7.571994) (xy 336.867377 7.544828)
			(xy 336.940283 7.499687) (xy 337.008712 7.448011) (xy 337.072082 7.390242) (xy 337.129851 7.326872)
			(xy 337.181527 7.258443) (xy 337.226668 7.185537) (xy 337.26489 7.108777) (xy 337.295866 7.028818)
			(xy 337.319333 6.946342) (xy 337.335089 6.862052) (xy 337.343001 6.776669) (xy 337.343496 6.733794)
			(xy 337.343001 6.690919) (xy 341.838267 6.690919) (xy 341.838267 6.776669) (xy 341.846179 6.862052)
			(xy 341.861935 6.946342) (xy 341.885402 7.028818) (xy 341.916378 7.108777) (xy 341.9546 7.185537)
			(xy 341.999741 7.258443) (xy 342.051417 7.326872) (xy 342.109186 7.390242) (xy 342.172556 7.448011)
			(xy 342.240985 7.499687) (xy 342.313891 7.544828) (xy 342.390651 7.58305) (xy 342.47061 7.614026)
			(xy 342.553086 7.637493) (xy 342.637376 7.653249) (xy 342.722759 7.661161) (xy 342.808509 7.661161)
			(xy 342.893892 7.653249) (xy 342.978182 7.637493) (xy 343.060658 7.614026) (xy 343.140617 7.58305)
			(xy 343.217377 7.544828) (xy 343.290283 7.499687) (xy 343.358712 7.448011) (xy 343.422082 7.390242)
			(xy 343.479851 7.326872) (xy 343.531527 7.258443) (xy 343.576668 7.185537) (xy 343.61489 7.108777)
			(xy 343.645866 7.028818) (xy 343.669333 6.946342) (xy 343.685089 6.862052) (xy 343.693001 6.776669)
			(xy 343.693496 6.733794) (xy 343.693001 6.690919) (xy 373.705107 6.690919) (xy 373.705107 6.776669)
			(xy 373.713019 6.862052) (xy 373.728775 6.946342) (xy 373.752242 7.028818) (xy 373.783218 7.108777)
			(xy 373.82144 7.185537) (xy 373.866581 7.258443) (xy 373.918257 7.326872) (xy 373.976026 7.390242)
			(xy 374.039396 7.448011) (xy 374.107825 7.499687) (xy 374.180731 7.544828) (xy 374.257491 7.58305)
			(xy 374.33745 7.614026) (xy 374.419926 7.637493) (xy 374.504216 7.653249) (xy 374.589599 7.661161)
			(xy 374.675349 7.661161) (xy 374.760732 7.653249) (xy 374.845022 7.637493) (xy 374.927498 7.614026)
			(xy 375.007457 7.58305) (xy 375.02966 7.571994) (xy 376.211592 7.571994) (xy 376.211592 8.435594)
			(xy 376.212078 8.462845) (xy 376.219834 8.516793) (xy 376.235189 8.569088) (xy 376.257831 8.618665)
			(xy 376.287297 8.664515) (xy 376.322988 8.705706) (xy 376.364179 8.741397) (xy 376.410029 8.770863)
			(xy 376.459606 8.793505) (xy 376.511901 8.80886) (xy 376.565849 8.816616) (xy 376.620351 8.816616)
			(xy 376.674299 8.80886) (xy 376.726594 8.793505) (xy 376.776171 8.770863) (xy 376.822021 8.741397)
			(xy 376.863212 8.705706) (xy 376.898903 8.664515) (xy 376.928369 8.618665) (xy 376.951011 8.569088)
			(xy 376.966366 8.516793) (xy 376.974122 8.462845) (xy 376.974608 8.435594) (xy 376.974608 7.571994)
			(xy 376.974122 7.544743) (xy 376.966366 7.490795) (xy 376.951011 7.4385) (xy 376.928369 7.388923)
			(xy 376.898903 7.343073) (xy 376.863212 7.301882) (xy 376.822021 7.266191) (xy 376.776171 7.236725)
			(xy 376.726594 7.214083) (xy 376.674299 7.198728) (xy 376.620351 7.190972) (xy 376.565849 7.190972)
			(xy 376.511901 7.198728) (xy 376.459606 7.214083) (xy 376.410029 7.236725) (xy 376.364179 7.266191)
			(xy 376.322988 7.301882) (xy 376.287297 7.343073) (xy 376.257831 7.388923) (xy 376.235189 7.4385)
			(xy 376.219834 7.490795) (xy 376.212078 7.544743) (xy 376.211592 7.571994) (xy 375.02966 7.571994)
			(xy 375.084217 7.544828) (xy 375.157123 7.499687) (xy 375.225552 7.448011) (xy 375.288922 7.390242)
			(xy 375.346691 7.326872) (xy 375.398367 7.258443) (xy 375.443508 7.185537) (xy 375.48173 7.108777)
			(xy 375.512706 7.028818) (xy 375.536173 6.946342) (xy 375.551929 6.862052) (xy 375.559841 6.776669)
			(xy 375.560336 6.733794) (xy 375.559841 6.690919) (xy 380.055107 6.690919) (xy 380.055107 6.776669)
			(xy 380.063019 6.862052) (xy 380.078775 6.946342) (xy 380.102242 7.028818) (xy 380.133218 7.108777)
			(xy 380.17144 7.185537) (xy 380.216581 7.258443) (xy 380.268257 7.326872) (xy 380.326026 7.390242)
			(xy 380.389396 7.448011) (xy 380.457825 7.499687) (xy 380.530731 7.544828) (xy 380.607491 7.58305)
			(xy 380.68745 7.614026) (xy 380.769926 7.637493) (xy 380.854216 7.653249) (xy 380.939599 7.661161)
			(xy 381.025349 7.661161) (xy 381.110732 7.653249) (xy 381.195022 7.637493) (xy 381.277498 7.614026)
			(xy 381.357457 7.58305) (xy 381.434217 7.544828) (xy 381.507123 7.499687) (xy 381.575552 7.448011)
			(xy 381.638922 7.390242) (xy 381.688857 7.335466) (xy 464.704165 7.335466) (xy 464.704165 7.464606)
			(xy 464.712115 7.593501) (xy 464.727985 7.721661) (xy 464.751714 7.848602) (xy 464.783213 7.973841)
			(xy 464.822362 8.096904) (xy 464.869013 8.217323) (xy 464.922988 8.334642) (xy 464.984083 8.448416)
			(xy 465.052066 8.558213) (xy 465.12668 8.663616) (xy 465.207641 8.764226) (xy 465.294641 8.859661)
			(xy 465.387352 8.94956) (xy 465.485422 9.033581) (xy 465.588477 9.111405) (xy 465.696128 9.182737)
			(xy 465.807967 9.247307) (xy 465.923568 9.304869) (xy 466.042493 9.355206) (xy 466.164292 9.398126)
			(xy 466.288502 9.433467) (xy 466.414651 9.461094) (xy 466.542263 9.480903) (xy 466.670852 9.492819)
			(xy 466.79993 9.496796) (xy 466.929008 9.492819) (xy 467.057597 9.480903) (xy 467.185209 9.461094)
			(xy 467.311358 9.433467) (xy 467.435568 9.398126) (xy 467.557367 9.355206) (xy 467.676292 9.304869)
			(xy 467.791893 9.247307) (xy 467.903732 9.182737) (xy 468.011383 9.111405) (xy 468.114438 9.033581)
			(xy 468.212508 8.94956) (xy 468.305219 8.859661) (xy 468.392219 8.764226) (xy 468.47318 8.663616)
			(xy 468.547794 8.558213) (xy 468.615777 8.448416) (xy 468.676872 8.334642) (xy 468.730847 8.217323)
			(xy 468.777498 8.096904) (xy 468.816647 7.973841) (xy 468.848146 7.848602) (xy 468.871875 7.721661)
			(xy 468.887745 7.593501) (xy 468.895695 7.464606) (xy 468.896192 7.400036) (xy 468.895695 7.335466)
			(xy 468.887745 7.206571) (xy 468.871875 7.078411) (xy 468.848146 6.95147) (xy 468.816647 6.826231)
			(xy 468.777498 6.703168) (xy 468.730847 6.582749) (xy 468.676872 6.46543) (xy 468.615777 6.351656)
			(xy 468.547794 6.241859) (xy 468.47318 6.136456) (xy 468.392219 6.035846) (xy 468.305219 5.940411)
			(xy 468.212508 5.850512) (xy 468.114438 5.766491) (xy 468.011383 5.688667) (xy 467.903732 5.617335)
			(xy 467.791893 5.552765) (xy 467.676292 5.495203) (xy 467.557367 5.444866) (xy 467.435568 5.401946)
			(xy 467.311358 5.366605) (xy 467.185209 5.338978) (xy 467.057597 5.319169) (xy 466.929008 5.307253)
			(xy 466.79993 5.303277) (xy 466.670852 5.307253) (xy 466.542263 5.319169) (xy 466.414651 5.338978)
			(xy 466.288502 5.366605) (xy 466.164292 5.401946) (xy 466.042493 5.444866) (xy 465.923568 5.495203)
			(xy 465.807967 5.552765) (xy 465.696128 5.617335) (xy 465.588477 5.688667) (xy 465.485422 5.766491)
			(xy 465.387352 5.850512) (xy 465.294641 5.940411) (xy 465.207641 6.035846) (xy 465.12668 6.136456)
			(xy 465.052066 6.241859) (xy 464.984083 6.351656) (xy 464.922988 6.46543) (xy 464.869013 6.582749)
			(xy 464.822362 6.703168) (xy 464.783213 6.826231) (xy 464.751714 6.95147) (xy 464.727985 7.078411)
			(xy 464.712115 7.206571) (xy 464.704165 7.335466) (xy 381.688857 7.335466) (xy 381.696691 7.326872)
			(xy 381.748367 7.258443) (xy 381.793508 7.185537) (xy 381.83173 7.108777) (xy 381.862706 7.028818)
			(xy 381.886173 6.946342) (xy 381.901929 6.862052) (xy 381.909841 6.776669) (xy 381.910336 6.733794)
			(xy 381.909841 6.690919) (xy 381.901929 6.605536) (xy 381.886173 6.521246) (xy 381.862706 6.43877)
			(xy 381.83173 6.358811) (xy 381.793508 6.282051) (xy 381.748367 6.209145) (xy 381.696691 6.140716)
			(xy 381.638922 6.077346) (xy 381.575552 6.019577) (xy 381.507123 5.967901) (xy 381.434217 5.92276)
			(xy 381.357457 5.884538) (xy 381.277498 5.853562) (xy 381.195022 5.830095) (xy 381.110732 5.814339)
			(xy 381.025349 5.806427) (xy 380.939599 5.806427) (xy 380.854216 5.814339) (xy 380.769926 5.830095)
			(xy 380.68745 5.853562) (xy 380.607491 5.884538) (xy 380.530731 5.92276) (xy 380.457825 5.967901)
			(xy 380.389396 6.019577) (xy 380.326026 6.077346) (xy 380.268257 6.140716) (xy 380.216581 6.209145)
			(xy 380.17144 6.282051) (xy 380.133218 6.358811) (xy 380.102242 6.43877) (xy 380.078775 6.521246)
			(xy 380.063019 6.605536) (xy 380.055107 6.690919) (xy 375.559841 6.690919) (xy 375.551929 6.605536)
			(xy 375.536173 6.521246) (xy 375.512706 6.43877) (xy 375.48173 6.358811) (xy 375.443508 6.282051)
			(xy 375.398367 6.209145) (xy 375.346691 6.140716) (xy 375.288922 6.077346) (xy 375.225552 6.019577)
			(xy 375.157123 5.967901) (xy 375.084217 5.92276) (xy 375.007457 5.884538) (xy 374.927498 5.853562)
			(xy 374.845022 5.830095) (xy 374.760732 5.814339) (xy 374.675349 5.806427) (xy 374.589599 5.806427)
			(xy 374.504216 5.814339) (xy 374.419926 5.830095) (xy 374.33745 5.853562) (xy 374.257491 5.884538)
			(xy 374.180731 5.92276) (xy 374.107825 5.967901) (xy 374.039396 6.019577) (xy 373.976026 6.077346)
			(xy 373.918257 6.140716) (xy 373.866581 6.209145) (xy 373.82144 6.282051) (xy 373.783218 6.358811)
			(xy 373.752242 6.43877) (xy 373.728775 6.521246) (xy 373.713019 6.605536) (xy 373.705107 6.690919)
			(xy 343.693001 6.690919) (xy 343.685089 6.605536) (xy 343.669333 6.521246) (xy 343.645866 6.43877)
			(xy 343.61489 6.358811) (xy 343.576668 6.282051) (xy 343.531527 6.209145) (xy 343.479851 6.140716)
			(xy 343.422082 6.077346) (xy 343.358712 6.019577) (xy 343.290283 5.967901) (xy 343.217377 5.92276)
			(xy 343.140617 5.884538) (xy 343.060658 5.853562) (xy 342.978182 5.830095) (xy 342.893892 5.814339)
			(xy 342.808509 5.806427) (xy 342.722759 5.806427) (xy 342.637376 5.814339) (xy 342.553086 5.830095)
			(xy 342.47061 5.853562) (xy 342.390651 5.884538) (xy 342.313891 5.92276) (xy 342.240985 5.967901)
			(xy 342.172556 6.019577) (xy 342.109186 6.077346) (xy 342.051417 6.140716) (xy 341.999741 6.209145)
			(xy 341.9546 6.282051) (xy 341.916378 6.358811) (xy 341.885402 6.43877) (xy 341.861935 6.521246)
			(xy 341.846179 6.605536) (xy 341.838267 6.690919) (xy 337.343001 6.690919) (xy 337.335089 6.605536)
			(xy 337.319333 6.521246) (xy 337.295866 6.43877) (xy 337.26489 6.358811) (xy 337.226668 6.282051)
			(xy 337.181527 6.209145) (xy 337.129851 6.140716) (xy 337.072082 6.077346) (xy 337.008712 6.019577)
			(xy 336.940283 5.967901) (xy 336.867377 5.92276) (xy 336.790617 5.884538) (xy 336.710658 5.853562)
			(xy 336.628182 5.830095) (xy 336.543892 5.814339) (xy 336.458509 5.806427) (xy 336.372759 5.806427)
			(xy 336.287376 5.814339) (xy 336.203086 5.830095) (xy 336.12061 5.853562) (xy 336.040651 5.884538)
			(xy 335.963891 5.92276) (xy 335.890985 5.967901) (xy 335.822556 6.019577) (xy 335.759186 6.077346)
			(xy 335.701417 6.140716) (xy 335.649741 6.209145) (xy 335.6046 6.282051) (xy 335.566378 6.358811)
			(xy 335.535402 6.43877) (xy 335.511935 6.521246) (xy 335.496179 6.605536) (xy 335.488267 6.690919)
			(xy 333.050655 6.690919) (xy 333.042743 6.605536) (xy 333.026987 6.521246) (xy 333.00352 6.43877)
			(xy 332.972544 6.358811) (xy 332.934322 6.282051) (xy 332.889181 6.209145) (xy 332.837505 6.140716)
			(xy 332.779736 6.077346) (xy 332.716366 6.019577) (xy 332.647937 5.967901) (xy 332.575031 5.92276)
			(xy 332.498271 5.884538) (xy 332.418312 5.853562) (xy 332.335836 5.830095) (xy 332.251546 5.814339)
			(xy 332.166163 5.806427) (xy 332.080413 5.806427) (xy 331.99503 5.814339) (xy 331.91074 5.830095)
			(xy 331.828264 5.853562) (xy 331.748305 5.884538) (xy 331.671545 5.92276) (xy 331.598639 5.967901)
			(xy 331.53021 6.019577) (xy 331.46684 6.077346) (xy 331.409071 6.140716) (xy 331.357395 6.209145)
			(xy 331.312254 6.282051) (xy 331.274032 6.358811) (xy 331.243056 6.43877) (xy 331.219589 6.521246)
			(xy 331.203833 6.605536) (xy 331.195921 6.690919) (xy 326.700655 6.690919) (xy 326.692743 6.605536)
			(xy 326.676987 6.521246) (xy 326.65352 6.43877) (xy 326.622544 6.358811) (xy 326.584322 6.282051)
			(xy 326.539181 6.209145) (xy 326.487505 6.140716) (xy 326.429736 6.077346) (xy 326.366366 6.019577)
			(xy 326.297937 5.967901) (xy 326.225031 5.92276) (xy 326.148271 5.884538) (xy 326.068312 5.853562)
			(xy 325.985836 5.830095) (xy 325.901546 5.814339) (xy 325.816163 5.806427) (xy 325.730413 5.806427)
			(xy 325.64503 5.814339) (xy 325.56074 5.830095) (xy 325.478264 5.853562) (xy 325.398305 5.884538)
			(xy 325.321545 5.92276) (xy 325.248639 5.967901) (xy 325.18021 6.019577) (xy 325.11684 6.077346)
			(xy 325.059071 6.140716) (xy 325.007395 6.209145) (xy 324.962254 6.282051) (xy 324.924032 6.358811)
			(xy 324.893056 6.43877) (xy 324.869589 6.521246) (xy 324.853833 6.605536) (xy 324.845921 6.690919)
			(xy 265.125975 6.690919) (xy 265.118063 6.605536) (xy 265.102307 6.521246) (xy 265.07884 6.43877)
			(xy 265.047864 6.358811) (xy 265.009642 6.282051) (xy 264.964501 6.209145) (xy 264.912825 6.140716)
			(xy 264.855056 6.077346) (xy 264.791686 6.019577) (xy 264.723257 5.967901) (xy 264.650351 5.92276)
			(xy 264.573591 5.884538) (xy 264.493632 5.853562) (xy 264.411156 5.830095) (xy 264.326866 5.814339)
			(xy 264.241483 5.806427) (xy 264.155733 5.806427) (xy 264.07035 5.814339) (xy 263.98606 5.830095)
			(xy 263.903584 5.853562) (xy 263.823625 5.884538) (xy 263.746865 5.92276) (xy 263.673959 5.967901)
			(xy 263.60553 6.019577) (xy 263.54216 6.077346) (xy 263.484391 6.140716) (xy 263.432715 6.209145)
			(xy 263.387574 6.282051) (xy 263.349352 6.358811) (xy 263.318376 6.43877) (xy 263.294909 6.521246)
			(xy 263.279153 6.605536) (xy 263.271241 6.690919) (xy 258.775975 6.690919) (xy 258.768063 6.605536)
			(xy 258.752307 6.521246) (xy 258.72884 6.43877) (xy 258.697864 6.358811) (xy 258.659642 6.282051)
			(xy 258.614501 6.209145) (xy 258.562825 6.140716) (xy 258.505056 6.077346) (xy 258.441686 6.019577)
			(xy 258.373257 5.967901) (xy 258.300351 5.92276) (xy 258.223591 5.884538) (xy 258.143632 5.853562)
			(xy 258.061156 5.830095) (xy 257.976866 5.814339) (xy 257.891483 5.806427) (xy 257.805733 5.806427)
			(xy 257.72035 5.814339) (xy 257.63606 5.830095) (xy 257.553584 5.853562) (xy 257.473625 5.884538)
			(xy 257.396865 5.92276) (xy 257.323959 5.967901) (xy 257.25553 6.019577) (xy 257.19216 6.077346)
			(xy 257.134391 6.140716) (xy 257.082715 6.209145) (xy 257.037574 6.282051) (xy 256.999352 6.358811)
			(xy 256.968376 6.43877) (xy 256.944909 6.521246) (xy 256.929153 6.605536) (xy 256.921241 6.690919)
			(xy 254.465119 6.690919) (xy 254.465087 6.688125) (xy 254.457175 6.602742) (xy 254.441419 6.518452)
			(xy 254.417952 6.435976) (xy 254.386976 6.356017) (xy 254.348754 6.279257) (xy 254.303613 6.206351)
			(xy 254.251937 6.137922) (xy 254.194168 6.074552) (xy 254.130798 6.016783) (xy 254.062369 5.965107)
			(xy 253.989463 5.919966) (xy 253.912703 5.881744) (xy 253.832744 5.850768) (xy 253.750268 5.827301)
			(xy 253.665978 5.811545) (xy 253.580595 5.803633) (xy 253.494845 5.803633) (xy 253.409462 5.811545)
			(xy 253.325172 5.827301) (xy 253.242696 5.850768) (xy 253.162737 5.881744) (xy 253.085977 5.919966)
			(xy 253.013071 5.965107) (xy 252.944642 6.016783) (xy 252.881272 6.074552) (xy 252.823503 6.137922)
			(xy 252.771827 6.206351) (xy 252.726686 6.279257) (xy 252.688464 6.356017) (xy 252.657488 6.435976)
			(xy 252.634021 6.518452) (xy 252.618265 6.602742) (xy 252.610353 6.688125) (xy 248.115087 6.688125)
			(xy 248.107175 6.602742) (xy 248.091419 6.518452) (xy 248.067952 6.435976) (xy 248.036976 6.356017)
			(xy 247.998754 6.279257) (xy 247.953613 6.206351) (xy 247.901937 6.137922) (xy 247.844168 6.074552)
			(xy 247.780798 6.016783) (xy 247.712369 5.965107) (xy 247.639463 5.919966) (xy 247.562703 5.881744)
			(xy 247.482744 5.850768) (xy 247.400268 5.827301) (xy 247.315978 5.811545) (xy 247.230595 5.803633)
			(xy 247.144845 5.803633) (xy 247.059462 5.811545) (xy 246.975172 5.827301) (xy 246.892696 5.850768)
			(xy 246.812737 5.881744) (xy 246.735977 5.919966) (xy 246.663071 5.965107) (xy 246.594642 6.016783)
			(xy 246.531272 6.074552) (xy 246.473503 6.137922) (xy 246.421827 6.206351) (xy 246.376686 6.279257)
			(xy 246.338464 6.356017) (xy 246.307488 6.435976) (xy 246.284021 6.518452) (xy 246.268265 6.602742)
			(xy 246.260353 6.688125) (xy 186.540407 6.688125) (xy 186.532495 6.602742) (xy 186.516739 6.518452)
			(xy 186.493272 6.435976) (xy 186.462296 6.356017) (xy 186.424074 6.279257) (xy 186.378933 6.206351)
			(xy 186.327257 6.137922) (xy 186.269488 6.074552) (xy 186.206118 6.016783) (xy 186.137689 5.965107)
			(xy 186.064783 5.919966) (xy 185.988023 5.881744) (xy 185.908064 5.850768) (xy 185.825588 5.827301)
			(xy 185.741298 5.811545) (xy 185.655915 5.803633) (xy 185.570165 5.803633) (xy 185.484782 5.811545)
			(xy 185.400492 5.827301) (xy 185.318016 5.850768) (xy 185.238057 5.881744) (xy 185.161297 5.919966)
			(xy 185.088391 5.965107) (xy 185.019962 6.016783) (xy 184.956592 6.074552) (xy 184.898823 6.137922)
			(xy 184.847147 6.206351) (xy 184.802006 6.279257) (xy 184.763784 6.356017) (xy 184.732808 6.435976)
			(xy 184.709341 6.518452) (xy 184.693585 6.602742) (xy 184.685673 6.688125) (xy 180.190407 6.688125)
			(xy 180.182495 6.602742) (xy 180.166739 6.518452) (xy 180.143272 6.435976) (xy 180.112296 6.356017)
			(xy 180.074074 6.279257) (xy 180.028933 6.206351) (xy 179.977257 6.137922) (xy 179.919488 6.074552)
			(xy 179.856118 6.016783) (xy 179.787689 5.965107) (xy 179.714783 5.919966) (xy 179.638023 5.881744)
			(xy 179.558064 5.850768) (xy 179.475588 5.827301) (xy 179.391298 5.811545) (xy 179.305915 5.803633)
			(xy 179.220165 5.803633) (xy 179.134782 5.811545) (xy 179.050492 5.827301) (xy 178.968016 5.850768)
			(xy 178.888057 5.881744) (xy 178.811297 5.919966) (xy 178.738391 5.965107) (xy 178.669962 6.016783)
			(xy 178.606592 6.074552) (xy 178.548823 6.137922) (xy 178.497147 6.206351) (xy 178.452006 6.279257)
			(xy 178.413784 6.356017) (xy 178.382808 6.435976) (xy 178.359341 6.518452) (xy 178.343585 6.602742)
			(xy 178.335673 6.688125) (xy 6.97173 6.688125) (xy 6.930907 6.582749) (xy 6.876932 6.46543) (xy 6.815837 6.351656)
			(xy 6.747854 6.241859) (xy 6.67324 6.136456) (xy 6.592279 6.035846) (xy 6.505279 5.940411) (xy 6.412568 5.850512)
			(xy 6.314498 5.766491) (xy 6.211443 5.688667) (xy 6.103792 5.617335) (xy 5.991953 5.552765) (xy 5.876352 5.495203)
			(xy 5.757427 5.444866) (xy 5.635628 5.401946) (xy 5.511418 5.366605) (xy 5.385269 5.338978) (xy 5.257657 5.319169)
			(xy 5.129068 5.307253) (xy 4.99999 5.303277) (xy 4.870912 5.307253) (xy 4.742323 5.319169) (xy 4.614711 5.338978)
			(xy 4.488562 5.366605) (xy 4.364352 5.401946) (xy 4.242553 5.444866) (xy 4.123628 5.495203) (xy 4.008027 5.552765)
			(xy 3.896188 5.617335) (xy 3.788537 5.688667) (xy 3.685482 5.766491) (xy 3.587412 5.850512) (xy 3.494701 5.940411)
			(xy 3.407701 6.035846) (xy 3.32674 6.136456) (xy 3.252126 6.241859) (xy 3.184143 6.351656) (xy 3.123048 6.46543)
			(xy 3.069073 6.582749) (xy 3.022422 6.703168) (xy 2.983273 6.826231) (xy 2.951774 6.95147) (xy 2.928045 7.078411)
			(xy 2.912175 7.206571) (xy 2.904225 7.335466) (xy 0.508 7.335466) (xy 0.508 4.148125) (xy 178.335673 4.148125)
			(xy 178.335673 4.233875) (xy 178.343585 4.319258) (xy 178.359341 4.403548) (xy 178.382808 4.486024)
			(xy 178.413784 4.565983) (xy 178.452006 4.642743) (xy 178.497147 4.715649) (xy 178.548823 4.784078)
			(xy 178.606592 4.847448) (xy 178.669962 4.905217) (xy 178.738391 4.956893) (xy 178.811297 5.002034)
			(xy 178.888057 5.040256) (xy 178.968016 5.071232) (xy 179.050492 5.094699) (xy 179.134782 5.110455)
			(xy 179.220165 5.118367) (xy 179.305915 5.118367) (xy 179.391298 5.110455) (xy 179.475588 5.094699)
			(xy 179.558064 5.071232) (xy 179.638023 5.040256) (xy 179.660226 5.0292) (xy 183.270652 5.0292) (xy 183.270652 5.8928)
			(xy 183.271138 5.920069) (xy 183.2789 5.974053) (xy 183.294265 6.026383) (xy 183.316922 6.075993)
			(xy 183.346408 6.121874) (xy 183.382123 6.163091) (xy 183.42334 6.198806) (xy 183.469221 6.228292)
			(xy 183.518831 6.250949) (xy 183.571161 6.266314) (xy 183.625145 6.274076) (xy 183.679683 6.274076)
			(xy 183.733667 6.266314) (xy 183.785997 6.250949) (xy 183.835607 6.228292) (xy 183.881488 6.198806)
			(xy 183.922705 6.163091) (xy 183.95842 6.121874) (xy 183.987906 6.075993) (xy 184.010563 6.026383)
			(xy 184.025928 5.974053) (xy 184.03369 5.920069) (xy 184.034176 5.8928) (xy 184.034176 5.0292) (xy 184.03369 5.001931)
			(xy 184.025928 4.947947) (xy 184.010563 4.895617) (xy 183.987906 4.846007) (xy 183.95842 4.800126)
			(xy 183.922705 4.758909) (xy 183.881488 4.723194) (xy 183.835607 4.693708) (xy 183.785997 4.671051)
			(xy 183.733667 4.655686) (xy 183.679683 4.647924) (xy 183.625145 4.647924) (xy 183.571161 4.655686)
			(xy 183.518831 4.671051) (xy 183.469221 4.693708) (xy 183.42334 4.723194) (xy 183.382123 4.758909)
			(xy 183.346408 4.800126) (xy 183.316922 4.846007) (xy 183.294265 4.895617) (xy 183.2789 4.947947)
			(xy 183.271138 5.001931) (xy 183.270652 5.0292) (xy 179.660226 5.0292) (xy 179.714783 5.002034) (xy 179.787689 4.956893)
			(xy 179.856118 4.905217) (xy 179.919488 4.847448) (xy 179.977257 4.784078) (xy 180.028933 4.715649)
			(xy 180.074074 4.642743) (xy 180.112296 4.565983) (xy 180.143272 4.486024) (xy 180.166739 4.403548)
			(xy 180.182495 4.319258) (xy 180.190407 4.233875) (xy 180.190902 4.191) (xy 180.190407 4.148125)
			(xy 184.685673 4.148125) (xy 184.685673 4.233875) (xy 184.693585 4.319258) (xy 184.709341 4.403548)
			(xy 184.732808 4.486024) (xy 184.763784 4.565983) (xy 184.802006 4.642743) (xy 184.847147 4.715649)
			(xy 184.898823 4.784078) (xy 184.956592 4.847448) (xy 185.019962 4.905217) (xy 185.088391 4.956893)
			(xy 185.161297 5.002034) (xy 185.238057 5.040256) (xy 185.318016 5.071232) (xy 185.400492 5.094699)
			(xy 185.484782 5.110455) (xy 185.570165 5.118367) (xy 185.655915 5.118367) (xy 185.741298 5.110455)
			(xy 185.825588 5.094699) (xy 185.908064 5.071232) (xy 185.988023 5.040256) (xy 186.064783 5.002034)
			(xy 186.137689 4.956893) (xy 186.206118 4.905217) (xy 186.269488 4.847448) (xy 186.327257 4.784078)
			(xy 186.378933 4.715649) (xy 186.424074 4.642743) (xy 186.462296 4.565983) (xy 186.493272 4.486024)
			(xy 186.516739 4.403548) (xy 186.532495 4.319258) (xy 186.540407 4.233875) (xy 186.540902 4.191)
			(xy 186.540407 4.148125) (xy 246.260353 4.148125) (xy 246.260353 4.233875) (xy 246.268265 4.319258)
			(xy 246.284021 4.403548) (xy 246.307488 4.486024) (xy 246.338464 4.565983) (xy 246.376686 4.642743)
			(xy 246.421827 4.715649) (xy 246.473503 4.784078) (xy 246.531272 4.847448) (xy 246.594642 4.905217)
			(xy 246.663071 4.956893) (xy 246.735977 5.002034) (xy 246.812737 5.040256) (xy 246.892696 5.071232)
			(xy 246.975172 5.094699) (xy 247.059462 5.110455) (xy 247.144845 5.118367) (xy 247.230595 5.118367)
			(xy 247.315978 5.110455) (xy 247.400268 5.094699) (xy 247.482744 5.071232) (xy 247.562703 5.040256)
			(xy 247.584906 5.0292) (xy 248.766584 5.0292) (xy 248.766584 5.8928) (xy 248.76707 5.920069) (xy 248.774832 5.974053)
			(xy 248.790197 6.026383) (xy 248.812854 6.075993) (xy 248.84234 6.121874) (xy 248.878055 6.163091)
			(xy 248.919272 6.198806) (xy 248.965153 6.228292) (xy 249.014763 6.250949) (xy 249.067093 6.266314)
			(xy 249.121077 6.274076) (xy 249.175615 6.274076) (xy 249.229599 6.266314) (xy 249.281929 6.250949)
			(xy 249.331539 6.228292) (xy 249.37742 6.198806) (xy 249.418637 6.163091) (xy 249.454352 6.121874)
			(xy 249.483838 6.075993) (xy 249.506495 6.026383) (xy 249.52186 5.974053) (xy 249.529622 5.920069)
			(xy 249.530108 5.8928) (xy 249.530108 5.0292) (xy 249.529622 5.001931) (xy 249.52186 4.947947) (xy 249.506495 4.895617)
			(xy 249.483838 4.846007) (xy 249.454352 4.800126) (xy 249.418637 4.758909) (xy 249.37742 4.723194)
			(xy 249.331539 4.693708) (xy 249.281929 4.671051) (xy 249.229599 4.655686) (xy 249.175615 4.647924)
			(xy 249.121077 4.647924) (xy 249.067093 4.655686) (xy 249.014763 4.671051) (xy 248.965153 4.693708)
			(xy 248.919272 4.723194) (xy 248.878055 4.758909) (xy 248.84234 4.800126) (xy 248.812854 4.846007)
			(xy 248.790197 4.895617) (xy 248.774832 4.947947) (xy 248.76707 5.001931) (xy 248.766584 5.0292)
			(xy 247.584906 5.0292) (xy 247.639463 5.002034) (xy 247.712369 4.956893) (xy 247.780798 4.905217)
			(xy 247.844168 4.847448) (xy 247.901937 4.784078) (xy 247.953613 4.715649) (xy 247.998754 4.642743)
			(xy 248.036976 4.565983) (xy 248.067952 4.486024) (xy 248.091419 4.403548) (xy 248.107175 4.319258)
			(xy 248.115087 4.233875) (xy 248.115582 4.191) (xy 248.115087 4.148125) (xy 252.610353 4.148125)
			(xy 252.610353 4.233875) (xy 252.618265 4.319258) (xy 252.634021 4.403548) (xy 252.657488 4.486024)
			(xy 252.688464 4.565983) (xy 252.726686 4.642743) (xy 252.771827 4.715649) (xy 252.823503 4.784078)
			(xy 252.881272 4.847448) (xy 252.944642 4.905217) (xy 253.013071 4.956893) (xy 253.085977 5.002034)
			(xy 253.162737 5.040256) (xy 253.242696 5.071232) (xy 253.325172 5.094699) (xy 253.409462 5.110455)
			(xy 253.494845 5.118367) (xy 253.580595 5.118367) (xy 253.665978 5.110455) (xy 253.750268 5.094699)
			(xy 253.832744 5.071232) (xy 253.912703 5.040256) (xy 253.989463 5.002034) (xy 254.062369 4.956893)
			(xy 254.130798 4.905217) (xy 254.194168 4.847448) (xy 254.251937 4.784078) (xy 254.303613 4.715649)
			(xy 254.348754 4.642743) (xy 254.386976 4.565983) (xy 254.417952 4.486024) (xy 254.441419 4.403548)
			(xy 254.457175 4.319258) (xy 254.465087 4.233875) (xy 254.465582 4.191) (xy 254.465119 4.150919)
			(xy 256.921241 4.150919) (xy 256.921241 4.236669) (xy 256.929153 4.322052) (xy 256.944909 4.406342)
			(xy 256.968376 4.488818) (xy 256.999352 4.568777) (xy 257.037574 4.645537) (xy 257.082715 4.718443)
			(xy 257.134391 4.786872) (xy 257.19216 4.850242) (xy 257.25553 4.908011) (xy 257.323959 4.959687)
			(xy 257.396865 5.004828) (xy 257.473625 5.04305) (xy 257.553584 5.074026) (xy 257.63606 5.097493)
			(xy 257.72035 5.113249) (xy 257.805733 5.121161) (xy 257.891483 5.121161) (xy 257.976866 5.113249)
			(xy 258.061156 5.097493) (xy 258.143632 5.074026) (xy 258.223591 5.04305) (xy 258.300351 5.004828)
			(xy 258.373257 4.959687) (xy 258.428864 4.917694) (xy 261.079996 4.917694) (xy 261.079996 6.014974)
			(xy 261.080529 6.027058) (xy 261.087973 6.05005) (xy 261.102144 6.069627) (xy 261.121661 6.08388)
			(xy 261.144622 6.09142) (xy 261.156704 6.091936) (xy 261.768844 6.091936) (xy 261.777315 6.091685)
			(xy 261.793848 6.087973) (xy 261.80161 6.08457) (xy 261.814596 6.078995) (xy 261.842475 6.07445)
			(xy 261.870532 6.077721) (xy 261.896619 6.088555) (xy 261.918738 6.106125) (xy 261.92734 6.117336)
			(xy 261.942756 6.138198) (xy 261.978318 6.175962) (xy 262.018669 6.208561) (xy 262.063063 6.235392)
			(xy 262.110683 6.255961) (xy 262.160651 6.269889) (xy 262.212046 6.276919) (xy 262.237982 6.277356)
			(xy 262.265253 6.276882) (xy 262.31924 6.269122) (xy 262.371572 6.253758) (xy 262.421186 6.231102)
			(xy 262.46707 6.201615) (xy 262.508291 6.165899) (xy 262.544008 6.12468) (xy 262.573496 6.078797)
			(xy 262.596153 6.029184) (xy 262.611519 5.976851) (xy 262.619281 5.922865) (xy 262.619744 5.895594)
			(xy 262.619744 5.031994) (xy 262.619304 5.004722) (xy 262.611541 4.950733) (xy 262.596173 4.898399)
			(xy 262.573513 4.848785) (xy 262.544023 4.8029) (xy 262.508303 4.76168) (xy 262.46708 4.725962) (xy 262.421194 4.696475)
			(xy 262.371578 4.673819) (xy 262.319243 4.658454) (xy 262.265254 4.650694) (xy 262.237982 4.650232)
			(xy 262.211789 4.6507) (xy 262.159897 4.657893) (xy 262.109477 4.672115) (xy 262.061475 4.693097)
			(xy 262.016793 4.720446) (xy 261.976271 4.753648) (xy 261.940669 4.792079) (xy 261.925308 4.8133)
			(xy 261.916825 4.824535) (xy 261.894967 4.84226) (xy 261.86911 4.853366) (xy 261.841207 4.857016)
			(xy 261.813364 4.852935) (xy 261.80034 4.84759) (xy 261.792854 4.84442) (xy 261.776971 4.840961)
			(xy 261.768844 4.840732) (xy 261.156704 4.840732) (xy 261.144592 4.84112) (xy 261.121559 4.848622)
			(xy 261.101983 4.86289) (xy 261.08779 4.88252) (xy 261.080375 4.905581) (xy 261.079996 4.917694)
			(xy 258.428864 4.917694) (xy 258.441686 4.908011) (xy 258.505056 4.850242) (xy 258.562825 4.786872)
			(xy 258.614501 4.718443) (xy 258.659642 4.645537) (xy 258.697864 4.568777) (xy 258.72884 4.488818)
			(xy 258.752307 4.406342) (xy 258.768063 4.322052) (xy 258.775975 4.236669) (xy 258.77647 4.193794)
			(xy 258.775975 4.150919) (xy 263.271241 4.150919) (xy 263.271241 4.236669) (xy 263.279153 4.322052)
			(xy 263.294909 4.406342) (xy 263.318376 4.488818) (xy 263.349352 4.568777) (xy 263.387574 4.645537)
			(xy 263.432715 4.718443) (xy 263.484391 4.786872) (xy 263.54216 4.850242) (xy 263.60553 4.908011)
			(xy 263.673959 4.959687) (xy 263.746865 5.004828) (xy 263.823625 5.04305) (xy 263.903584 5.074026)
			(xy 263.98606 5.097493) (xy 264.07035 5.113249) (xy 264.155733 5.121161) (xy 264.241483 5.121161)
			(xy 264.326866 5.113249) (xy 264.411156 5.097493) (xy 264.493632 5.074026) (xy 264.573591 5.04305)
			(xy 264.650351 5.004828) (xy 264.723257 4.959687) (xy 264.791686 4.908011) (xy 264.855056 4.850242)
			(xy 264.912825 4.786872) (xy 264.964501 4.718443) (xy 265.009642 4.645537) (xy 265.047864 4.568777)
			(xy 265.07884 4.488818) (xy 265.102307 4.406342) (xy 265.118063 4.322052) (xy 265.125975 4.236669)
			(xy 265.12647 4.193794) (xy 265.125975 4.150919) (xy 324.845921 4.150919) (xy 324.845921 4.236669)
			(xy 324.853833 4.322052) (xy 324.869589 4.406342) (xy 324.893056 4.488818) (xy 324.924032 4.568777)
			(xy 324.962254 4.645537) (xy 325.007395 4.718443) (xy 325.059071 4.786872) (xy 325.11684 4.850242)
			(xy 325.18021 4.908011) (xy 325.248639 4.959687) (xy 325.321545 5.004828) (xy 325.398305 5.04305)
			(xy 325.478264 5.074026) (xy 325.56074 5.097493) (xy 325.64503 5.113249) (xy 325.730413 5.121161)
			(xy 325.816163 5.121161) (xy 325.901546 5.113249) (xy 325.985836 5.097493) (xy 326.068312 5.074026)
			(xy 326.148271 5.04305) (xy 326.170474 5.031994) (xy 327.352152 5.031994) (xy 327.352152 5.895594)
			(xy 327.352607 5.922865) (xy 327.360369 5.976853) (xy 327.375735 6.029187) (xy 327.398393 6.078801)
			(xy 327.427881 6.124686) (xy 327.4636 6.165906) (xy 327.504821 6.201624) (xy 327.550706 6.231111)
			(xy 327.60032 6.253768) (xy 327.652654 6.269133) (xy 327.706642 6.276893) (xy 327.733914 6.277356)
			(xy 327.760108 6.27689) (xy 327.811999 6.269697) (xy 327.86242 6.255476) (xy 327.910422 6.234493)
			(xy 327.955104 6.207144) (xy 327.995626 6.173942) (xy 328.031228 6.13551) (xy 328.046588 6.114288)
			(xy 328.055072 6.103054) (xy 328.07693 6.085331) (xy 328.102787 6.074225) (xy 328.130689 6.070574)
			(xy 328.158532 6.074654) (xy 328.171556 6.079998) (xy 328.179043 6.083167) (xy 328.194925 6.086627)
			(xy 328.203052 6.086856) (xy 328.815192 6.086856) (xy 328.827295 6.086378) (xy 328.850312 6.078887)
			(xy 328.869881 6.06464) (xy 328.884078 6.045035) (xy 328.891509 6.021998) (xy 328.8919 6.009894)
			(xy 328.8919 4.912614) (xy 328.891381 4.900529) (xy 328.883933 4.877536) (xy 328.869759 4.857959)
			(xy 328.850238 4.843707) (xy 328.827275 4.836167) (xy 328.815192 4.835652) (xy 328.203052 4.835652)
			(xy 328.194581 4.835903) (xy 328.178048 4.839615) (xy 328.170286 4.843018) (xy 328.157303 4.848601)
			(xy 328.129422 4.853146) (xy 328.101363 4.849874) (xy 328.075276 4.839037) (xy 328.053157 4.821465)
			(xy 328.044556 4.810252) (xy 328.029145 4.789385) (xy 327.993582 4.751622) (xy 327.953231 4.719024)
			(xy 327.908835 4.692194) (xy 327.861214 4.671625) (xy 327.811245 4.657698) (xy 327.759851 4.650668)
			(xy 327.733914 4.650232) (xy 327.706644 4.650714) (xy 327.652658 4.658475) (xy 327.600326 4.673839)
			(xy 327.550713 4.696494) (xy 327.50483 4.72598) (xy 327.46361 4.761695) (xy 327.427892 4.802914)
			(xy 327.398404 4.848795) (xy 327.375746 4.898407) (xy 327.360379 4.950738) (xy 327.352616 5.004724)
			(xy 327.352152 5.031994) (xy 326.170474 5.031994) (xy 326.225031 5.004828) (xy 326.297937 4.959687)
			(xy 326.366366 4.908011) (xy 326.429736 4.850242) (xy 326.487505 4.786872) (xy 326.539181 4.718443)
			(xy 326.584322 4.645537) (xy 326.622544 4.568777) (xy 326.65352 4.488818) (xy 326.676987 4.406342)
			(xy 326.692743 4.322052) (xy 326.700655 4.236669) (xy 326.70115 4.193794) (xy 326.700655 4.150919)
			(xy 331.195921 4.150919) (xy 331.195921 4.236669) (xy 331.203833 4.322052) (xy 331.219589 4.406342)
			(xy 331.243056 4.488818) (xy 331.274032 4.568777) (xy 331.312254 4.645537) (xy 331.357395 4.718443)
			(xy 331.409071 4.786872) (xy 331.46684 4.850242) (xy 331.53021 4.908011) (xy 331.598639 4.959687)
			(xy 331.671545 5.004828) (xy 331.748305 5.04305) (xy 331.828264 5.074026) (xy 331.91074 5.097493)
			(xy 331.99503 5.113249) (xy 332.080413 5.121161) (xy 332.166163 5.121161) (xy 332.251546 5.113249)
			(xy 332.335836 5.097493) (xy 332.418312 5.074026) (xy 332.498271 5.04305) (xy 332.575031 5.004828)
			(xy 332.647937 4.959687) (xy 332.716366 4.908011) (xy 332.779736 4.850242) (xy 332.837505 4.786872)
			(xy 332.889181 4.718443) (xy 332.934322 4.645537) (xy 332.972544 4.568777) (xy 333.00352 4.488818)
			(xy 333.026987 4.406342) (xy 333.042743 4.322052) (xy 333.050655 4.236669) (xy 333.05115 4.193794)
			(xy 333.050655 4.150919) (xy 335.488267 4.150919) (xy 335.488267 4.236669) (xy 335.496179 4.322052)
			(xy 335.511935 4.406342) (xy 335.535402 4.488818) (xy 335.566378 4.568777) (xy 335.6046 4.645537)
			(xy 335.649741 4.718443) (xy 335.701417 4.786872) (xy 335.759186 4.850242) (xy 335.822556 4.908011)
			(xy 335.890985 4.959687) (xy 335.963891 5.004828) (xy 336.040651 5.04305) (xy 336.12061 5.074026)
			(xy 336.203086 5.097493) (xy 336.287376 5.113249) (xy 336.372759 5.121161) (xy 336.458509 5.121161)
			(xy 336.543892 5.113249) (xy 336.628182 5.097493) (xy 336.710658 5.074026) (xy 336.790617 5.04305)
			(xy 336.867377 5.004828) (xy 336.940283 4.959687) (xy 336.99589 4.917694) (xy 339.646768 4.917694)
			(xy 339.646768 6.014974) (xy 339.647183 6.027098) (xy 339.654671 6.050161) (xy 339.668923 6.06978)
			(xy 339.688542 6.084031) (xy 339.711606 6.091518) (xy 339.72373 6.091936) (xy 340.33587 6.091936)
			(xy 340.344342 6.091693) (xy 340.360875 6.087975) (xy 340.368636 6.08457) (xy 340.381611 6.078968)
			(xy 340.409496 6.074428) (xy 340.437557 6.077705) (xy 340.463646 6.088546) (xy 340.485765 6.106121)
			(xy 340.494366 6.117336) (xy 340.509767 6.13821) (xy 340.545331 6.175974) (xy 340.585684 6.208572)
			(xy 340.630081 6.235401) (xy 340.677704 6.255968) (xy 340.727675 6.269894) (xy 340.779071 6.276921)
			(xy 340.805008 6.277356) (xy 340.83227 6.276851) (xy 340.88624 6.269088) (xy 340.938554 6.253721)
			(xy 340.988148 6.231062) (xy 341.034011 6.201574) (xy 341.075209 6.165857) (xy 341.110903 6.124639)
			(xy 341.140365 6.07876) (xy 341.162996 6.029153) (xy 341.178334 5.97683) (xy 341.186067 5.922857)
			(xy 341.186516 5.895594) (xy 341.186516 5.031994) (xy 341.186082 5.004734) (xy 341.178325 4.950768)
			(xy 341.162969 4.898455) (xy 341.140327 4.848859) (xy 341.11086 4.802988) (xy 341.075167 4.761776)
			(xy 341.033974 4.726061) (xy 340.988119 4.696569) (xy 340.938534 4.673902) (xy 340.886229 4.658518)
			(xy 340.832268 4.650733) (xy 340.805008 4.650232) (xy 340.778815 4.65072) (xy 340.726925 4.657909)
			(xy 340.676505 4.672127) (xy 340.628503 4.693106) (xy 340.583821 4.720452) (xy 340.543298 4.753651)
			(xy 340.507695 4.79208) (xy 340.492334 4.8133) (xy 340.483828 4.824517) (xy 340.461977 4.842242)
			(xy 340.436126 4.853351) (xy 340.408228 4.857006) (xy 340.380389 4.852931) (xy 340.367366 4.84759)
			(xy 340.359877 4.844427) (xy 340.343996 4.840964) (xy 340.33587 4.840732) (xy 339.72373 4.840732)
			(xy 339.711609 4.841185) (xy 339.688553 4.848669) (xy 339.668937 4.862912) (xy 339.654685 4.88252)
			(xy 339.647191 4.905574) (xy 339.646768 4.917694) (xy 336.99589 4.917694) (xy 337.008712 4.908011)
			(xy 337.072082 4.850242) (xy 337.129851 4.786872) (xy 337.181527 4.718443) (xy 337.226668 4.645537)
			(xy 337.26489 4.568777) (xy 337.295866 4.488818) (xy 337.319333 4.406342) (xy 337.335089 4.322052)
			(xy 337.343001 4.236669) (xy 337.343496 4.193794) (xy 337.343001 4.150919) (xy 341.838267 4.150919)
			(xy 341.838267 4.236669) (xy 341.846179 4.322052) (xy 341.861935 4.406342) (xy 341.885402 4.488818)
			(xy 341.916378 4.568777) (xy 341.9546 4.645537) (xy 341.999741 4.718443) (xy 342.051417 4.786872)
			(xy 342.109186 4.850242) (xy 342.172556 4.908011) (xy 342.240985 4.959687) (xy 342.313891 5.004828)
			(xy 342.390651 5.04305) (xy 342.47061 5.074026) (xy 342.553086 5.097493) (xy 342.637376 5.113249)
			(xy 342.722759 5.121161) (xy 342.808509 5.121161) (xy 342.893892 5.113249) (xy 342.978182 5.097493)
			(xy 343.060658 5.074026) (xy 343.140617 5.04305) (xy 343.217377 5.004828) (xy 343.290283 4.959687)
			(xy 343.358712 4.908011) (xy 343.422082 4.850242) (xy 343.479851 4.786872) (xy 343.531527 4.718443)
			(xy 343.576668 4.645537) (xy 343.61489 4.568777) (xy 343.645866 4.488818) (xy 343.669333 4.406342)
			(xy 343.685089 4.322052) (xy 343.693001 4.236669) (xy 343.693496 4.193794) (xy 343.693001 4.150919)
			(xy 373.705107 4.150919) (xy 373.705107 4.236669) (xy 373.713019 4.322052) (xy 373.728775 4.406342)
			(xy 373.752242 4.488818) (xy 373.783218 4.568777) (xy 373.82144 4.645537) (xy 373.866581 4.718443)
			(xy 373.918257 4.786872) (xy 373.976026 4.850242) (xy 374.039396 4.908011) (xy 374.107825 4.959687)
			(xy 374.180731 5.004828) (xy 374.257491 5.04305) (xy 374.33745 5.074026) (xy 374.419926 5.097493)
			(xy 374.504216 5.113249) (xy 374.589599 5.121161) (xy 374.675349 5.121161) (xy 374.760732 5.113249)
			(xy 374.845022 5.097493) (xy 374.927498 5.074026) (xy 375.007457 5.04305) (xy 375.02966 5.031994)
			(xy 376.211592 5.031994) (xy 376.211592 5.895594) (xy 376.212129 5.92285) (xy 376.219882 5.976807)
			(xy 376.235231 6.029112) (xy 376.257865 6.078702) (xy 376.287322 6.124569) (xy 376.323005 6.165779)
			(xy 376.364186 6.201494) (xy 376.410029 6.230988) (xy 376.459601 6.253661) (xy 376.511894 6.269053)
			(xy 376.565845 6.276849) (xy 376.5931 6.277356) (xy 376.619293 6.276879) (xy 376.671184 6.269688)
			(xy 376.721605 6.255469) (xy 376.769607 6.234488) (xy 376.814289 6.207141) (xy 376.854812 6.17394)
			(xy 376.890413 6.135509) (xy 376.905774 6.114288) (xy 376.91427 6.103064) (xy 376.936125 6.085341)
			(xy 376.961978 6.074233) (xy 376.989878 6.07058) (xy 377.017719 6.074656) (xy 377.030742 6.079998)
			(xy 377.038231 6.083163) (xy 377.054112 6.086625) (xy 377.062238 6.086856) (xy 377.674378 6.086856)
			(xy 377.6865 6.086421) (xy 377.709559 6.078934) (xy 377.729175 6.064687) (xy 377.743427 6.045074)
			(xy 377.750919 6.022016) (xy 377.75134 6.009894) (xy 377.75134 4.912614) (xy 377.750928 4.90049)
			(xy 377.743437 4.877428) (xy 377.729184 4.857811) (xy 377.709565 4.84356) (xy 377.686502 4.836071)
			(xy 377.674378 4.835652) (xy 377.062238 4.835652) (xy 377.053766 4.835898) (xy 377.037234 4.839614)
			(xy 377.029472 4.843018) (xy 377.016495 4.848616) (xy 376.988611 4.853158) (xy 376.96055 4.849883)
			(xy 376.934462 4.839042) (xy 376.912343 4.821467) (xy 376.903742 4.810252) (xy 376.88834 4.789379)
			(xy 376.852775 4.751615) (xy 376.812422 4.719018) (xy 376.768025 4.692189) (xy 376.720403 4.671621)
			(xy 376.670433 4.657695) (xy 376.619037 4.650668) (xy 376.5931 4.650232) (xy 376.565834 4.650656)
			(xy 376.511857 4.658421) (xy 376.459536 4.673792) (xy 376.409936 4.696456) (xy 376.364069 4.725951)
			(xy 376.322868 4.761677) (xy 376.287175 4.802904) (xy 376.257715 4.848794) (xy 376.235089 4.898412)
			(xy 376.219758 4.950745) (xy 376.212035 5.004727) (xy 376.211592 5.031994) (xy 375.02966 5.031994)
			(xy 375.084217 5.004828) (xy 375.157123 4.959687) (xy 375.225552 4.908011) (xy 375.288922 4.850242)
			(xy 375.346691 4.786872) (xy 375.398367 4.718443) (xy 375.443508 4.645537) (xy 375.48173 4.568777)
			(xy 375.512706 4.488818) (xy 375.536173 4.406342) (xy 375.551929 4.322052) (xy 375.559841 4.236669)
			(xy 375.560336 4.193794) (xy 375.559841 4.150919) (xy 380.055107 4.150919) (xy 380.055107 4.236669)
			(xy 380.063019 4.322052) (xy 380.078775 4.406342) (xy 380.102242 4.488818) (xy 380.133218 4.568777)
			(xy 380.17144 4.645537) (xy 380.216581 4.718443) (xy 380.268257 4.786872) (xy 380.326026 4.850242)
			(xy 380.389396 4.908011) (xy 380.457825 4.959687) (xy 380.530731 5.004828) (xy 380.607491 5.04305)
			(xy 380.68745 5.074026) (xy 380.769926 5.097493) (xy 380.854216 5.113249) (xy 380.939599 5.121161)
			(xy 381.025349 5.121161) (xy 381.110732 5.113249) (xy 381.195022 5.097493) (xy 381.277498 5.074026)
			(xy 381.357457 5.04305) (xy 381.434217 5.004828) (xy 381.507123 4.959687) (xy 381.575552 4.908011)
			(xy 381.638922 4.850242) (xy 381.696691 4.786872) (xy 381.748367 4.718443) (xy 381.793508 4.645537)
			(xy 381.83173 4.568777) (xy 381.862706 4.488818) (xy 381.886173 4.406342) (xy 381.901929 4.322052)
			(xy 381.909841 4.236669) (xy 381.910336 4.193794) (xy 381.909841 4.150919) (xy 381.901929 4.065536)
			(xy 381.886173 3.981246) (xy 381.862706 3.89877) (xy 381.83173 3.818811) (xy 381.793508 3.742051)
			(xy 381.748367 3.669145) (xy 381.696691 3.600716) (xy 381.638922 3.537346) (xy 381.575552 3.479577)
			(xy 381.507123 3.427901) (xy 381.434217 3.38276) (xy 381.357457 3.344538) (xy 381.277498 3.313562)
			(xy 381.195022 3.290095) (xy 381.110732 3.274339) (xy 381.025349 3.266427) (xy 380.939599 3.266427)
			(xy 380.854216 3.274339) (xy 380.769926 3.290095) (xy 380.68745 3.313562) (xy 380.607491 3.344538)
			(xy 380.530731 3.38276) (xy 380.457825 3.427901) (xy 380.389396 3.479577) (xy 380.326026 3.537346)
			(xy 380.268257 3.600716) (xy 380.216581 3.669145) (xy 380.17144 3.742051) (xy 380.133218 3.818811)
			(xy 380.102242 3.89877) (xy 380.078775 3.981246) (xy 380.063019 4.065536) (xy 380.055107 4.150919)
			(xy 375.559841 4.150919) (xy 375.551929 4.065536) (xy 375.536173 3.981246) (xy 375.512706 3.89877)
			(xy 375.48173 3.818811) (xy 375.443508 3.742051) (xy 375.398367 3.669145) (xy 375.346691 3.600716)
			(xy 375.288922 3.537346) (xy 375.225552 3.479577) (xy 375.157123 3.427901) (xy 375.084217 3.38276)
			(xy 375.007457 3.344538) (xy 374.927498 3.313562) (xy 374.845022 3.290095) (xy 374.760732 3.274339)
			(xy 374.675349 3.266427) (xy 374.589599 3.266427) (xy 374.504216 3.274339) (xy 374.419926 3.290095)
			(xy 374.33745 3.313562) (xy 374.257491 3.344538) (xy 374.180731 3.38276) (xy 374.107825 3.427901)
			(xy 374.039396 3.479577) (xy 373.976026 3.537346) (xy 373.918257 3.600716) (xy 373.866581 3.669145)
			(xy 373.82144 3.742051) (xy 373.783218 3.818811) (xy 373.752242 3.89877) (xy 373.728775 3.981246)
			(xy 373.713019 4.065536) (xy 373.705107 4.150919) (xy 343.693001 4.150919) (xy 343.685089 4.065536)
			(xy 343.669333 3.981246) (xy 343.645866 3.89877) (xy 343.61489 3.818811) (xy 343.576668 3.742051)
			(xy 343.531527 3.669145) (xy 343.479851 3.600716) (xy 343.422082 3.537346) (xy 343.358712 3.479577)
			(xy 343.290283 3.427901) (xy 343.217377 3.38276) (xy 343.140617 3.344538) (xy 343.060658 3.313562)
			(xy 342.978182 3.290095) (xy 342.893892 3.274339) (xy 342.808509 3.266427) (xy 342.722759 3.266427)
			(xy 342.637376 3.274339) (xy 342.553086 3.290095) (xy 342.47061 3.313562) (xy 342.390651 3.344538)
			(xy 342.313891 3.38276) (xy 342.240985 3.427901) (xy 342.172556 3.479577) (xy 342.109186 3.537346)
			(xy 342.051417 3.600716) (xy 341.999741 3.669145) (xy 341.9546 3.742051) (xy 341.916378 3.818811)
			(xy 341.885402 3.89877) (xy 341.861935 3.981246) (xy 341.846179 4.065536) (xy 341.838267 4.150919)
			(xy 337.343001 4.150919) (xy 337.335089 4.065536) (xy 337.319333 3.981246) (xy 337.295866 3.89877)
			(xy 337.26489 3.818811) (xy 337.226668 3.742051) (xy 337.181527 3.669145) (xy 337.129851 3.600716)
			(xy 337.072082 3.537346) (xy 337.008712 3.479577) (xy 336.940283 3.427901) (xy 336.867377 3.38276)
			(xy 336.790617 3.344538) (xy 336.710658 3.313562) (xy 336.628182 3.290095) (xy 336.543892 3.274339)
			(xy 336.458509 3.266427) (xy 336.372759 3.266427) (xy 336.287376 3.274339) (xy 336.203086 3.290095)
			(xy 336.12061 3.313562) (xy 336.040651 3.344538) (xy 335.963891 3.38276) (xy 335.890985 3.427901)
			(xy 335.822556 3.479577) (xy 335.759186 3.537346) (xy 335.701417 3.600716) (xy 335.649741 3.669145)
			(xy 335.6046 3.742051) (xy 335.566378 3.818811) (xy 335.535402 3.89877) (xy 335.511935 3.981246)
			(xy 335.496179 4.065536) (xy 335.488267 4.150919) (xy 333.050655 4.150919) (xy 333.042743 4.065536)
			(xy 333.026987 3.981246) (xy 333.00352 3.89877) (xy 332.972544 3.818811) (xy 332.934322 3.742051)
			(xy 332.889181 3.669145) (xy 332.837505 3.600716) (xy 332.779736 3.537346) (xy 332.716366 3.479577)
			(xy 332.647937 3.427901) (xy 332.575031 3.38276) (xy 332.498271 3.344538) (xy 332.418312 3.313562)
			(xy 332.335836 3.290095) (xy 332.251546 3.274339) (xy 332.166163 3.266427) (xy 332.080413 3.266427)
			(xy 331.99503 3.274339) (xy 331.91074 3.290095) (xy 331.828264 3.313562) (xy 331.748305 3.344538)
			(xy 331.671545 3.38276) (xy 331.598639 3.427901) (xy 331.53021 3.479577) (xy 331.46684 3.537346)
			(xy 331.409071 3.600716) (xy 331.357395 3.669145) (xy 331.312254 3.742051) (xy 331.274032 3.818811)
			(xy 331.243056 3.89877) (xy 331.219589 3.981246) (xy 331.203833 4.065536) (xy 331.195921 4.150919)
			(xy 326.700655 4.150919) (xy 326.692743 4.065536) (xy 326.676987 3.981246) (xy 326.65352 3.89877)
			(xy 326.622544 3.818811) (xy 326.584322 3.742051) (xy 326.539181 3.669145) (xy 326.487505 3.600716)
			(xy 326.429736 3.537346) (xy 326.366366 3.479577) (xy 326.297937 3.427901) (xy 326.225031 3.38276)
			(xy 326.148271 3.344538) (xy 326.068312 3.313562) (xy 325.985836 3.290095) (xy 325.901546 3.274339)
			(xy 325.816163 3.266427) (xy 325.730413 3.266427) (xy 325.64503 3.274339) (xy 325.56074 3.290095)
			(xy 325.478264 3.313562) (xy 325.398305 3.344538) (xy 325.321545 3.38276) (xy 325.248639 3.427901)
			(xy 325.18021 3.479577) (xy 325.11684 3.537346) (xy 325.059071 3.600716) (xy 325.007395 3.669145)
			(xy 324.962254 3.742051) (xy 324.924032 3.818811) (xy 324.893056 3.89877) (xy 324.869589 3.981246)
			(xy 324.853833 4.065536) (xy 324.845921 4.150919) (xy 265.125975 4.150919) (xy 265.118063 4.065536)
			(xy 265.102307 3.981246) (xy 265.07884 3.89877) (xy 265.047864 3.818811) (xy 265.009642 3.742051)
			(xy 264.964501 3.669145) (xy 264.912825 3.600716) (xy 264.855056 3.537346) (xy 264.791686 3.479577)
			(xy 264.723257 3.427901) (xy 264.650351 3.38276) (xy 264.573591 3.344538) (xy 264.493632 3.313562)
			(xy 264.411156 3.290095) (xy 264.326866 3.274339) (xy 264.241483 3.266427) (xy 264.155733 3.266427)
			(xy 264.07035 3.274339) (xy 263.98606 3.290095) (xy 263.903584 3.313562) (xy 263.823625 3.344538)
			(xy 263.746865 3.38276) (xy 263.673959 3.427901) (xy 263.60553 3.479577) (xy 263.54216 3.537346)
			(xy 263.484391 3.600716) (xy 263.432715 3.669145) (xy 263.387574 3.742051) (xy 263.349352 3.818811)
			(xy 263.318376 3.89877) (xy 263.294909 3.981246) (xy 263.279153 4.065536) (xy 263.271241 4.150919)
			(xy 258.775975 4.150919) (xy 258.768063 4.065536) (xy 258.752307 3.981246) (xy 258.72884 3.89877)
			(xy 258.697864 3.818811) (xy 258.659642 3.742051) (xy 258.614501 3.669145) (xy 258.562825 3.600716)
			(xy 258.505056 3.537346) (xy 258.441686 3.479577) (xy 258.373257 3.427901) (xy 258.300351 3.38276)
			(xy 258.223591 3.344538) (xy 258.143632 3.313562) (xy 258.061156 3.290095) (xy 257.976866 3.274339)
			(xy 257.891483 3.266427) (xy 257.805733 3.266427) (xy 257.72035 3.274339) (xy 257.63606 3.290095)
			(xy 257.553584 3.313562) (xy 257.473625 3.344538) (xy 257.396865 3.38276) (xy 257.323959 3.427901)
			(xy 257.25553 3.479577) (xy 257.19216 3.537346) (xy 257.134391 3.600716) (xy 257.082715 3.669145)
			(xy 257.037574 3.742051) (xy 256.999352 3.818811) (xy 256.968376 3.89877) (xy 256.944909 3.981246)
			(xy 256.929153 4.065536) (xy 256.921241 4.150919) (xy 254.465119 4.150919) (xy 254.465087 4.148125)
			(xy 254.457175 4.062742) (xy 254.441419 3.978452) (xy 254.417952 3.895976) (xy 254.386976 3.816017)
			(xy 254.348754 3.739257) (xy 254.303613 3.666351) (xy 254.251937 3.597922) (xy 254.194168 3.534552)
			(xy 254.130798 3.476783) (xy 254.062369 3.425107) (xy 253.989463 3.379966) (xy 253.912703 3.341744)
			(xy 253.832744 3.310768) (xy 253.750268 3.287301) (xy 253.665978 3.271545) (xy 253.580595 3.263633)
			(xy 253.494845 3.263633) (xy 253.409462 3.271545) (xy 253.325172 3.287301) (xy 253.242696 3.310768)
			(xy 253.162737 3.341744) (xy 253.085977 3.379966) (xy 253.013071 3.425107) (xy 252.944642 3.476783)
			(xy 252.881272 3.534552) (xy 252.823503 3.597922) (xy 252.771827 3.666351) (xy 252.726686 3.739257)
			(xy 252.688464 3.816017) (xy 252.657488 3.895976) (xy 252.634021 3.978452) (xy 252.618265 4.062742)
			(xy 252.610353 4.148125) (xy 248.115087 4.148125) (xy 248.107175 4.062742) (xy 248.091419 3.978452)
			(xy 248.067952 3.895976) (xy 248.036976 3.816017) (xy 247.998754 3.739257) (xy 247.953613 3.666351)
			(xy 247.901937 3.597922) (xy 247.844168 3.534552) (xy 247.780798 3.476783) (xy 247.712369 3.425107)
			(xy 247.639463 3.379966) (xy 247.562703 3.341744) (xy 247.482744 3.310768) (xy 247.400268 3.287301)
			(xy 247.315978 3.271545) (xy 247.230595 3.263633) (xy 247.144845 3.263633) (xy 247.059462 3.271545)
			(xy 246.975172 3.287301) (xy 246.892696 3.310768) (xy 246.812737 3.341744) (xy 246.735977 3.379966)
			(xy 246.663071 3.425107) (xy 246.594642 3.476783) (xy 246.531272 3.534552) (xy 246.473503 3.597922)
			(xy 246.421827 3.666351) (xy 246.376686 3.739257) (xy 246.338464 3.816017) (xy 246.307488 3.895976)
			(xy 246.284021 3.978452) (xy 246.268265 4.062742) (xy 246.260353 4.148125) (xy 186.540407 4.148125)
			(xy 186.532495 4.062742) (xy 186.516739 3.978452) (xy 186.493272 3.895976) (xy 186.462296 3.816017)
			(xy 186.424074 3.739257) (xy 186.378933 3.666351) (xy 186.327257 3.597922) (xy 186.269488 3.534552)
			(xy 186.206118 3.476783) (xy 186.137689 3.425107) (xy 186.064783 3.379966) (xy 185.988023 3.341744)
			(xy 185.908064 3.310768) (xy 185.825588 3.287301) (xy 185.741298 3.271545) (xy 185.655915 3.263633)
			(xy 185.570165 3.263633) (xy 185.484782 3.271545) (xy 185.400492 3.287301) (xy 185.318016 3.310768)
			(xy 185.238057 3.341744) (xy 185.161297 3.379966) (xy 185.088391 3.425107) (xy 185.019962 3.476783)
			(xy 184.956592 3.534552) (xy 184.898823 3.597922) (xy 184.847147 3.666351) (xy 184.802006 3.739257)
			(xy 184.763784 3.816017) (xy 184.732808 3.895976) (xy 184.709341 3.978452) (xy 184.693585 4.062742)
			(xy 184.685673 4.148125) (xy 180.190407 4.148125) (xy 180.182495 4.062742) (xy 180.166739 3.978452)
			(xy 180.143272 3.895976) (xy 180.112296 3.816017) (xy 180.074074 3.739257) (xy 180.028933 3.666351)
			(xy 179.977257 3.597922) (xy 179.919488 3.534552) (xy 179.856118 3.476783) (xy 179.787689 3.425107)
			(xy 179.714783 3.379966) (xy 179.638023 3.341744) (xy 179.558064 3.310768) (xy 179.475588 3.287301)
			(xy 179.391298 3.271545) (xy 179.305915 3.263633) (xy 179.220165 3.263633) (xy 179.134782 3.271545)
			(xy 179.050492 3.287301) (xy 178.968016 3.310768) (xy 178.888057 3.341744) (xy 178.811297 3.379966)
			(xy 178.738391 3.425107) (xy 178.669962 3.476783) (xy 178.606592 3.534552) (xy 178.548823 3.597922)
			(xy 178.497147 3.666351) (xy 178.452006 3.739257) (xy 178.413784 3.816017) (xy 178.382808 3.895976)
			(xy 178.359341 3.978452) (xy 178.343585 4.062742) (xy 178.335673 4.148125) (xy 0.508 4.148125) (xy 0.508 -7.78002)
			(xy 0.508522 -7.835827) (xy 0.516863 -7.947129) (xy 0.533498 -8.057497) (xy 0.558334 -8.166312) (xy 0.591233 -8.272968)
			(xy 0.63201 -8.376867) (xy 0.680438 -8.477428) (xy 0.736245 -8.574088) (xy 0.799119 -8.666308) (xy 0.868709 -8.753572)
			(xy 0.944626 -8.835391) (xy 1.026445 -8.911308) (xy 1.113708 -8.980898) (xy 1.205928 -9.043773) (xy 1.302589 -9.09958)
			(xy 1.40315 -9.148008) (xy 1.507048 -9.188786) (xy 1.613704 -9.221685) (xy 1.722519 -9.246521) (xy 1.832887 -9.263157)
			(xy 1.944189 -9.271498) (xy 1.999996 -9.272016) (xy 9.10209 -9.272016) (xy 9.157898 -9.271495) (xy 9.269201 -9.263154)
			(xy 9.379569 -9.24652) (xy 9.488386 -9.221684) (xy 9.595043 -9.188786) (xy 9.698942 -9.148009) (xy 9.799505 -9.099582)
			(xy 9.896167 -9.043775) (xy 9.988388 -8.980901) (xy 10.075653 -8.911311) (xy 10.157473 -8.835394)
			(xy 10.233392 -8.753575) (xy 10.302983 -8.666312) (xy 10.365859 -8.574092) (xy 10.421668 -8.477431)
			(xy 10.470097 -8.37687) (xy 10.510876 -8.272971) (xy 10.543776 -8.166315) (xy 10.568614 -8.057499)
			(xy 10.585251 -7.94713) (xy 10.593594 -7.835828) (xy 10.594086 -7.78002) (xy 10.594086 0.999998)
			(xy 10.59457 1.070352) (xy 10.60246 1.210839) (xy 10.618214 1.350662) (xy 10.641783 1.489382) (xy 10.673094 1.626562)
			(xy 10.712047 1.761771) (xy 10.758519 1.894583) (xy 10.812366 2.02458) (xy 10.873417 2.151354) (xy 10.94148 2.274505)
			(xy 11.016341 2.393646) (xy 11.097765 2.508402) (xy 11.185495 2.618411) (xy 11.279255 2.723329) (xy 11.378751 2.822825)
			(xy 11.483669 2.916585) (xy 11.593678 3.004315) (xy 11.708434 3.085739) (xy 11.827575 3.1606) (xy 11.950726 3.228663)
			(xy 12.0775 3.289714) (xy 12.207497 3.343561) (xy 12.340309 3.390033) (xy 12.475518 3.428986) (xy 12.612698 3.460297)
			(xy 12.751418 3.483866) (xy 12.891241 3.49962) (xy 13.031728 3.50751) (xy 13.102082 3.507994) (xy 81.701894 3.507994)
			(xy 81.772248 3.50751) (xy 81.912735 3.499621) (xy 82.052558 3.483867) (xy 82.191278 3.460297) (xy 82.328459 3.428987)
			(xy 82.463668 3.390034) (xy 82.59648 3.343562) (xy 82.726477 3.289715) (xy 82.853251 3.228664) (xy 82.976402 3.160601)
			(xy 83.095543 3.08574) (xy 83.2103 3.004317) (xy 83.32031 2.916587) (xy 83.425228 2.822826) (xy 83.524724 2.723331)
			(xy 83.618484 2.618413) (xy 83.706214 2.508403) (xy 83.787638 2.393647) (xy 83.862499 2.274506) (xy 83.930563 2.151355)
			(xy 83.991614 2.024581) (xy 84.04546 1.894584) (xy 84.091933 1.761772) (xy 84.130886 1.626563) (xy 84.135094 1.608125)
			(xy 178.335673 1.608125) (xy 178.335673 1.693875) (xy 178.343585 1.779258) (xy 178.359341 1.863548)
			(xy 178.382808 1.946024) (xy 178.413784 2.025983) (xy 178.452006 2.102743) (xy 178.497147 2.175649)
			(xy 178.548823 2.244078) (xy 178.606592 2.307448) (xy 178.669962 2.365217) (xy 178.738391 2.416893)
			(xy 178.811297 2.462034) (xy 178.888057 2.500256) (xy 178.968016 2.531232) (xy 179.050492 2.554699)
			(xy 179.134782 2.570455) (xy 179.220165 2.578367) (xy 179.305915 2.578367) (xy 179.391298 2.570455)
			(xy 179.475588 2.554699) (xy 179.558064 2.531232) (xy 179.638023 2.500256) (xy 179.714783 2.462034)
			(xy 179.787689 2.416893) (xy 179.843296 2.3749) (xy 182.494428 2.3749) (xy 182.494428 3.47218) (xy 182.49483 3.484265)
			(xy 182.502297 3.507253) (xy 182.516504 3.526807) (xy 182.536061 3.541011) (xy 182.559051 3.548472)
			(xy 182.571136 3.548888) (xy 183.183276 3.548888) (xy 183.191737 3.548707) (xy 183.208271 3.545126)
			(xy 183.216042 3.541776) (xy 183.229014 3.536165) (xy 183.2569 3.531627) (xy 183.284963 3.534905)
			(xy 183.311052 3.545748) (xy 183.333171 3.563326) (xy 183.341772 3.574542) (xy 183.35718 3.595401)
			(xy 183.392753 3.633134) (xy 183.433113 3.665698) (xy 183.477513 3.692492) (xy 183.525134 3.713022)
			(xy 183.575099 3.726907) (xy 183.626485 3.733893) (xy 183.652414 3.734308) (xy 183.67967 3.73379)
			(xy 183.733628 3.726034) (xy 183.785934 3.710682) (xy 183.835524 3.688046) (xy 183.88139 3.658586)
			(xy 183.9226 3.622902) (xy 183.958315 3.58172) (xy 183.987809 3.535875) (xy 184.010482 3.486302)
			(xy 184.025873 3.434008) (xy 184.033669 3.380056) (xy 184.034176 3.3528) (xy 184.034176 2.4892) (xy 184.033744 2.461934)
			(xy 184.025979 2.407958) (xy 184.010609 2.355637) (xy 183.987946 2.306038) (xy 183.958451 2.260171)
			(xy 183.922726 2.218971) (xy 183.881499 2.183277) (xy 183.83561 2.153817) (xy 183.785994 2.131191)
			(xy 183.733662 2.11586) (xy 183.67968 2.108136) (xy 183.652414 2.107692) (xy 183.626229 2.108097)
			(xy 183.574353 2.115277) (xy 183.523944 2.129478) (xy 183.475948 2.150433) (xy 183.431266 2.177749)
			(xy 183.390734 2.210913) (xy 183.355114 2.249304) (xy 183.33974 2.270506) (xy 183.33123 2.281719)
			(xy 183.30938 2.299443) (xy 183.28353 2.310553) (xy 183.255634 2.314209) (xy 183.227795 2.310136)
			(xy 183.214772 2.304796) (xy 183.207261 2.301727) (xy 183.191387 2.298389) (xy 183.183276 2.298192)
			(xy 182.571136 2.298192) (xy 182.559055 2.298643) (xy 182.536074 2.306101) (xy 182.516523 2.320297)
			(xy 182.502317 2.339841) (xy 182.494849 2.362819) (xy 182.494428 2.3749) (xy 179.843296 2.3749) (xy 179.856118 2.365217)
			(xy 179.919488 2.307448) (xy 179.977257 2.244078) (xy 180.028933 2.175649) (xy 180.074074 2.102743)
			(xy 180.112296 2.025983) (xy 180.143272 1.946024) (xy 180.166739 1.863548) (xy 180.182495 1.779258)
			(xy 180.190407 1.693875) (xy 180.190902 1.651) (xy 180.190407 1.608125) (xy 184.685673 1.608125)
			(xy 184.685673 1.693875) (xy 184.693585 1.779258) (xy 184.709341 1.863548) (xy 184.732808 1.946024)
			(xy 184.763784 2.025983) (xy 184.802006 2.102743) (xy 184.847147 2.175649) (xy 184.898823 2.244078)
			(xy 184.956592 2.307448) (xy 185.019962 2.365217) (xy 185.088391 2.416893) (xy 185.161297 2.462034)
			(xy 185.238057 2.500256) (xy 185.318016 2.531232) (xy 185.400492 2.554699) (xy 185.484782 2.570455)
			(xy 185.570165 2.578367) (xy 185.655915 2.578367) (xy 185.741298 2.570455) (xy 185.825588 2.554699)
			(xy 185.908064 2.531232) (xy 185.988023 2.500256) (xy 186.064783 2.462034) (xy 186.137689 2.416893)
			(xy 186.206118 2.365217) (xy 186.269488 2.307448) (xy 186.327257 2.244078) (xy 186.378933 2.175649)
			(xy 186.424074 2.102743) (xy 186.462296 2.025983) (xy 186.493272 1.946024) (xy 186.516739 1.863548)
			(xy 186.532495 1.779258) (xy 186.540407 1.693875) (xy 186.540902 1.651) (xy 186.540407 1.608125)
			(xy 246.260353 1.608125) (xy 246.260353 1.693875) (xy 246.268265 1.779258) (xy 246.284021 1.863548)
			(xy 246.307488 1.946024) (xy 246.338464 2.025983) (xy 246.376686 2.102743) (xy 246.421827 2.175649)
			(xy 246.473503 2.244078) (xy 246.531272 2.307448) (xy 246.594642 2.365217) (xy 246.663071 2.416893)
			(xy 246.735977 2.462034) (xy 246.812737 2.500256) (xy 246.892696 2.531232) (xy 246.975172 2.554699)
			(xy 247.059462 2.570455) (xy 247.144845 2.578367) (xy 247.230595 2.578367) (xy 247.315978 2.570455)
			(xy 247.400268 2.554699) (xy 247.482744 2.531232) (xy 247.562703 2.500256) (xy 247.584906 2.4892)
			(xy 248.766584 2.4892) (xy 248.766584 3.3528) (xy 248.767056 3.380064) (xy 248.774819 3.434037) (xy 248.790188 3.486354)
			(xy 248.812848 3.535951) (xy 248.842339 3.581816) (xy 248.87806 3.623015) (xy 248.919282 3.658708)
			(xy 248.965166 3.68817) (xy 249.014777 3.710798) (xy 249.067104 3.726133) (xy 249.121082 3.733861)
			(xy 249.148346 3.734308) (xy 249.17453 3.733873) (xy 249.226405 3.726698) (xy 249.276813 3.712502)
			(xy 249.324809 3.691553) (xy 249.369492 3.664241) (xy 249.410024 3.631081) (xy 249.445646 3.592694)
			(xy 249.46102 3.571494) (xy 249.469477 3.560237) (xy 249.491343 3.542514) (xy 249.517206 3.531412)
			(xy 249.545116 3.527767) (xy 249.572963 3.531855) (xy 249.585988 3.537204) (xy 249.593492 3.540291)
			(xy 249.609372 3.543617) (xy 249.617484 3.543808) (xy 250.229624 3.543808) (xy 250.2417 3.543356)
			(xy 250.264668 3.535887) (xy 250.284204 3.521687) (xy 250.298398 3.502146) (xy 250.30586 3.479176)
			(xy 250.306332 3.4671) (xy 250.306332 2.36982) (xy 250.305819 2.357749) (xy 250.298365 2.334786)
			(xy 250.28418 2.315251) (xy 250.264653 2.301055) (xy 250.241695 2.293588) (xy 250.229624 2.293112)
			(xy 249.617484 2.293112) (xy 249.609023 2.29328) (xy 249.592488 2.29687) (xy 249.584718 2.300224)
			(xy 249.571762 2.305876) (xy 249.543868 2.310406) (xy 249.5158 2.307119) (xy 249.489708 2.296266)
			(xy 249.467588 2.278678) (xy 249.458988 2.267458) (xy 249.443604 2.24658) (xy 249.408027 2.208847)
			(xy 249.367664 2.176285) (xy 249.323259 2.149493) (xy 249.275634 2.128967) (xy 249.225665 2.115085)
			(xy 249.174277 2.108104) (xy 249.148346 2.107692) (xy 249.121091 2.108266) (xy 249.067136 2.116014)
			(xy 249.014831 2.131358) (xy 248.965241 2.153987) (xy 248.919374 2.18344) (xy 248.878164 2.219119)
			(xy 248.842448 2.260297) (xy 248.812953 2.306137) (xy 248.790279 2.355706) (xy 248.774888 2.407997)
			(xy 248.767091 2.461946) (xy 248.766584 2.4892) (xy 247.584906 2.4892) (xy 247.639463 2.462034) (xy 247.712369 2.416893)
			(xy 247.780798 2.365217) (xy 247.844168 2.307448) (xy 247.901937 2.244078) (xy 247.953613 2.175649)
			(xy 247.998754 2.102743) (xy 248.036976 2.025983) (xy 248.067952 1.946024) (xy 248.091419 1.863548)
			(xy 248.107175 1.779258) (xy 248.115087 1.693875) (xy 248.115582 1.651) (xy 248.115087 1.608125)
			(xy 252.610353 1.608125) (xy 252.610353 1.693875) (xy 252.618265 1.779258) (xy 252.634021 1.863548)
			(xy 252.657488 1.946024) (xy 252.688464 2.025983) (xy 252.726686 2.102743) (xy 252.771827 2.175649)
			(xy 252.823503 2.244078) (xy 252.881272 2.307448) (xy 252.944642 2.365217) (xy 253.013071 2.416893)
			(xy 253.085977 2.462034) (xy 253.162737 2.500256) (xy 253.242696 2.531232) (xy 253.325172 2.554699)
			(xy 253.409462 2.570455) (xy 253.494845 2.578367) (xy 253.580595 2.578367) (xy 253.665978 2.570455)
			(xy 253.750268 2.554699) (xy 253.832744 2.531232) (xy 253.912703 2.500256) (xy 253.989463 2.462034)
			(xy 254.062369 2.416893) (xy 254.130798 2.365217) (xy 254.194168 2.307448) (xy 254.251937 2.244078)
			(xy 254.303613 2.175649) (xy 254.348754 2.102743) (xy 254.386976 2.025983) (xy 254.417952 1.946024)
			(xy 254.441419 1.863548) (xy 254.457175 1.779258) (xy 254.465087 1.693875) (xy 254.465582 1.651)
			(xy 254.465119 1.610919) (xy 256.921241 1.610919) (xy 256.921241 1.696669) (xy 256.929153 1.782052)
			(xy 256.944909 1.866342) (xy 256.968376 1.948818) (xy 256.999352 2.028777) (xy 257.037574 2.105537)
			(xy 257.082715 2.178443) (xy 257.134391 2.246872) (xy 257.19216 2.310242) (xy 257.25553 2.368011)
			(xy 257.323959 2.419687) (xy 257.396865 2.464828) (xy 257.473625 2.50305) (xy 257.553584 2.534026)
			(xy 257.63606 2.557493) (xy 257.72035 2.573249) (xy 257.805733 2.581161) (xy 257.891483 2.581161)
			(xy 257.976866 2.573249) (xy 258.061156 2.557493) (xy 258.143632 2.534026) (xy 258.223591 2.50305)
			(xy 258.245794 2.491994) (xy 261.85622 2.491994) (xy 261.85622 3.355594) (xy 261.856706 3.382863)
			(xy 261.864468 3.436847) (xy 261.879833 3.489177) (xy 261.90249 3.538787) (xy 261.931976 3.584668)
			(xy 261.967691 3.625885) (xy 262.008908 3.6616) (xy 262.054789 3.691086) (xy 262.104399 3.713743)
			(xy 262.156729 3.729108) (xy 262.210713 3.73687) (xy 262.265251 3.73687) (xy 262.319235 3.729108)
			(xy 262.371565 3.713743) (xy 262.421175 3.691086) (xy 262.467056 3.6616) (xy 262.508273 3.625885)
			(xy 262.543988 3.584668) (xy 262.573474 3.538787) (xy 262.596131 3.489177) (xy 262.611496 3.436847)
			(xy 262.619258 3.382863) (xy 262.619744 3.355594) (xy 262.619744 2.491994) (xy 262.619258 2.464725)
			(xy 262.611496 2.410741) (xy 262.596131 2.358411) (xy 262.573474 2.308801) (xy 262.543988 2.26292)
			(xy 262.508273 2.221703) (xy 262.467056 2.185988) (xy 262.421175 2.156502) (xy 262.371565 2.133845)
			(xy 262.319235 2.11848) (xy 262.265251 2.110718) (xy 262.210713 2.110718) (xy 262.156729 2.11848)
			(xy 262.104399 2.133845) (xy 262.054789 2.156502) (xy 262.008908 2.185988) (xy 261.967691 2.221703)
			(xy 261.931976 2.26292) (xy 261.90249 2.308801) (xy 261.879833 2.358411) (xy 261.864468 2.410741)
			(xy 261.856706 2.464725) (xy 261.85622 2.491994) (xy 258.245794 2.491994) (xy 258.300351 2.464828)
			(xy 258.373257 2.419687) (xy 258.441686 2.368011) (xy 258.505056 2.310242) (xy 258.562825 2.246872)
			(xy 258.614501 2.178443) (xy 258.659642 2.105537) (xy 258.697864 2.028777) (xy 258.72884 1.948818)
			(xy 258.752307 1.866342) (xy 258.768063 1.782052) (xy 258.775975 1.696669) (xy 258.77647 1.653794)
			(xy 258.775975 1.610919) (xy 263.271241 1.610919) (xy 263.271241 1.696669) (xy 263.279153 1.782052)
			(xy 263.294909 1.866342) (xy 263.318376 1.948818) (xy 263.349352 2.028777) (xy 263.387574 2.105537)
			(xy 263.432715 2.178443) (xy 263.484391 2.246872) (xy 263.54216 2.310242) (xy 263.60553 2.368011)
			(xy 263.673959 2.419687) (xy 263.746865 2.464828) (xy 263.823625 2.50305) (xy 263.903584 2.534026)
			(xy 263.98606 2.557493) (xy 264.07035 2.573249) (xy 264.155733 2.581161) (xy 264.241483 2.581161)
			(xy 264.326866 2.573249) (xy 264.411156 2.557493) (xy 264.493632 2.534026) (xy 264.573591 2.50305)
			(xy 264.650351 2.464828) (xy 264.723257 2.419687) (xy 264.791686 2.368011) (xy 264.855056 2.310242)
			(xy 264.912825 2.246872) (xy 264.964501 2.178443) (xy 265.009642 2.105537) (xy 265.047864 2.028777)
			(xy 265.07884 1.948818) (xy 265.102307 1.866342) (xy 265.118063 1.782052) (xy 265.125975 1.696669)
			(xy 265.12647 1.653794) (xy 265.125975 1.610919) (xy 324.845921 1.610919) (xy 324.845921 1.696669)
			(xy 324.853833 1.782052) (xy 324.869589 1.866342) (xy 324.893056 1.948818) (xy 324.924032 2.028777)
			(xy 324.962254 2.105537) (xy 325.007395 2.178443) (xy 325.059071 2.246872) (xy 325.11684 2.310242)
			(xy 325.18021 2.368011) (xy 325.248639 2.419687) (xy 325.321545 2.464828) (xy 325.398305 2.50305)
			(xy 325.478264 2.534026) (xy 325.56074 2.557493) (xy 325.64503 2.573249) (xy 325.730413 2.581161)
			(xy 325.816163 2.581161) (xy 325.901546 2.573249) (xy 325.985836 2.557493) (xy 326.068312 2.534026)
			(xy 326.148271 2.50305) (xy 326.170474 2.491994) (xy 327.352152 2.491994) (xy 327.352152 3.355594)
			(xy 327.352638 3.382863) (xy 327.3604 3.436847) (xy 327.375765 3.489177) (xy 327.398422 3.538787)
			(xy 327.427908 3.584668) (xy 327.463623 3.625885) (xy 327.50484 3.6616) (xy 327.550721 3.691086)
			(xy 327.600331 3.713743) (xy 327.652661 3.729108) (xy 327.706645 3.73687) (xy 327.761183 3.73687)
			(xy 327.815167 3.729108) (xy 327.867497 3.713743) (xy 327.917107 3.691086) (xy 327.962988 3.6616)
			(xy 328.004205 3.625885) (xy 328.03992 3.584668) (xy 328.069406 3.538787) (xy 328.092063 3.489177)
			(xy 328.107428 3.436847) (xy 328.11519 3.382863) (xy 328.115676 3.355594) (xy 328.115676 2.491994)
			(xy 328.11519 2.464725) (xy 328.107428 2.410741) (xy 328.092063 2.358411) (xy 328.069406 2.308801)
			(xy 328.03992 2.26292) (xy 328.004205 2.221703) (xy 327.962988 2.185988) (xy 327.917107 2.156502)
			(xy 327.867497 2.133845) (xy 327.815167 2.11848) (xy 327.761183 2.110718) (xy 327.706645 2.110718)
			(xy 327.652661 2.11848) (xy 327.600331 2.133845) (xy 327.550721 2.156502) (xy 327.50484 2.185988)
			(xy 327.463623 2.221703) (xy 327.427908 2.26292) (xy 327.398422 2.308801) (xy 327.375765 2.358411)
			(xy 327.3604 2.410741) (xy 327.352638 2.464725) (xy 327.352152 2.491994) (xy 326.170474 2.491994)
			(xy 326.225031 2.464828) (xy 326.297937 2.419687) (xy 326.366366 2.368011) (xy 326.429736 2.310242)
			(xy 326.487505 2.246872) (xy 326.539181 2.178443) (xy 326.584322 2.105537) (xy 326.622544 2.028777)
			(xy 326.65352 1.948818) (xy 326.676987 1.866342) (xy 326.692743 1.782052) (xy 326.700655 1.696669)
			(xy 326.70115 1.653794) (xy 326.700655 1.610919) (xy 331.195921 1.610919) (xy 331.195921 1.696669)
			(xy 331.203833 1.782052) (xy 331.219589 1.866342) (xy 331.243056 1.948818) (xy 331.274032 2.028777)
			(xy 331.312254 2.105537) (xy 331.357395 2.178443) (xy 331.409071 2.246872) (xy 331.46684 2.310242)
			(xy 331.53021 2.368011) (xy 331.598639 2.419687) (xy 331.671545 2.464828) (xy 331.748305 2.50305)
			(xy 331.828264 2.534026) (xy 331.91074 2.557493) (xy 331.99503 2.573249) (xy 332.080413 2.581161)
			(xy 332.166163 2.581161) (xy 332.251546 2.573249) (xy 332.335836 2.557493) (xy 332.418312 2.534026)
			(xy 332.498271 2.50305) (xy 332.575031 2.464828) (xy 332.647937 2.419687) (xy 332.716366 2.368011)
			(xy 332.779736 2.310242) (xy 332.837505 2.246872) (xy 332.889181 2.178443) (xy 332.934322 2.105537)
			(xy 332.972544 2.028777) (xy 333.00352 1.948818) (xy 333.026987 1.866342) (xy 333.042743 1.782052)
			(xy 333.050655 1.696669) (xy 333.05115 1.653794) (xy 333.050655 1.610919) (xy 335.488267 1.610919)
			(xy 335.488267 1.696669) (xy 335.496179 1.782052) (xy 335.511935 1.866342) (xy 335.535402 1.948818)
			(xy 335.566378 2.028777) (xy 335.6046 2.105537) (xy 335.649741 2.178443) (xy 335.701417 2.246872)
			(xy 335.759186 2.310242) (xy 335.822556 2.368011) (xy 335.890985 2.419687) (xy 335.963891 2.464828)
			(xy 336.040651 2.50305) (xy 336.12061 2.534026) (xy 336.203086 2.557493) (xy 336.287376 2.573249)
			(xy 336.372759 2.581161) (xy 336.458509 2.581161) (xy 336.543892 2.573249) (xy 336.628182 2.557493)
			(xy 336.710658 2.534026) (xy 336.790617 2.50305) (xy 336.81282 2.491994) (xy 340.4235 2.491994) (xy 340.4235 3.355594)
			(xy 340.423986 3.382845) (xy 340.431742 3.436793) (xy 340.447097 3.489088) (xy 340.469739 3.538665)
			(xy 340.499205 3.584515) (xy 340.534896 3.625706) (xy 340.576087 3.661397) (xy 340.621937 3.690863)
			(xy 340.671514 3.713505) (xy 340.723809 3.72886) (xy 340.777757 3.736616) (xy 340.832259 3.736616)
			(xy 340.886207 3.72886) (xy 340.938502 3.713505) (xy 340.988079 3.690863) (xy 341.033929 3.661397)
			(xy 341.07512 3.625706) (xy 341.110811 3.584515) (xy 341.140277 3.538665) (xy 341.162919 3.489088)
			(xy 341.178274 3.436793) (xy 341.18603 3.382845) (xy 341.186516 3.355594) (xy 341.186516 2.491994)
			(xy 341.18603 2.464743) (xy 341.178274 2.410795) (xy 341.162919 2.3585) (xy 341.140277 2.308923)
			(xy 341.110811 2.263073) (xy 341.07512 2.221882) (xy 341.033929 2.186191) (xy 340.988079 2.156725)
			(xy 340.938502 2.134083) (xy 340.886207 2.118728) (xy 340.832259 2.110972) (xy 340.777757 2.110972)
			(xy 340.723809 2.118728) (xy 340.671514 2.134083) (xy 340.621937 2.156725) (xy 340.576087 2.186191)
			(xy 340.534896 2.221882) (xy 340.499205 2.263073) (xy 340.469739 2.308923) (xy 340.447097 2.3585)
			(xy 340.431742 2.410795) (xy 340.423986 2.464743) (xy 340.4235 2.491994) (xy 336.81282 2.491994)
			(xy 336.867377 2.464828) (xy 336.940283 2.419687) (xy 337.008712 2.368011) (xy 337.072082 2.310242)
			(xy 337.129851 2.246872) (xy 337.181527 2.178443) (xy 337.226668 2.105537) (xy 337.26489 2.028777)
			(xy 337.295866 1.948818) (xy 337.319333 1.866342) (xy 337.335089 1.782052) (xy 337.343001 1.696669)
			(xy 337.343496 1.653794) (xy 337.343001 1.610919) (xy 341.838267 1.610919) (xy 341.838267 1.696669)
			(xy 341.846179 1.782052) (xy 341.861935 1.866342) (xy 341.885402 1.948818) (xy 341.916378 2.028777)
			(xy 341.9546 2.105537) (xy 341.999741 2.178443) (xy 342.051417 2.246872) (xy 342.109186 2.310242)
			(xy 342.172556 2.368011) (xy 342.240985 2.419687) (xy 342.313891 2.464828) (xy 342.390651 2.50305)
			(xy 342.47061 2.534026) (xy 342.553086 2.557493) (xy 342.637376 2.573249) (xy 342.722759 2.581161)
			(xy 342.808509 2.581161) (xy 342.893892 2.573249) (xy 342.978182 2.557493) (xy 343.060658 2.534026)
			(xy 343.140617 2.50305) (xy 343.217377 2.464828) (xy 343.290283 2.419687) (xy 343.358712 2.368011)
			(xy 343.422082 2.310242) (xy 343.479851 2.246872) (xy 343.531527 2.178443) (xy 343.576668 2.105537)
			(xy 343.61489 2.028777) (xy 343.645866 1.948818) (xy 343.669333 1.866342) (xy 343.685089 1.782052)
			(xy 343.693001 1.696669) (xy 343.693496 1.653794) (xy 343.693001 1.610919) (xy 373.705107 1.610919)
			(xy 373.705107 1.696669) (xy 373.713019 1.782052) (xy 373.728775 1.866342) (xy 373.752242 1.948818)
			(xy 373.783218 2.028777) (xy 373.82144 2.105537) (xy 373.866581 2.178443) (xy 373.918257 2.246872)
			(xy 373.976026 2.310242) (xy 374.039396 2.368011) (xy 374.107825 2.419687) (xy 374.180731 2.464828)
			(xy 374.257491 2.50305) (xy 374.33745 2.534026) (xy 374.419926 2.557493) (xy 374.504216 2.573249)
			(xy 374.589599 2.581161) (xy 374.675349 2.581161) (xy 374.760732 2.573249) (xy 374.845022 2.557493)
			(xy 374.927498 2.534026) (xy 375.007457 2.50305) (xy 375.02966 2.491994) (xy 376.211592 2.491994)
			(xy 376.211592 3.355594) (xy 376.212078 3.382845) (xy 376.219834 3.436793) (xy 376.235189 3.489088)
			(xy 376.257831 3.538665) (xy 376.287297 3.584515) (xy 376.322988 3.625706) (xy 376.364179 3.661397)
			(xy 376.410029 3.690863) (xy 376.459606 3.713505) (xy 376.511901 3.72886) (xy 376.565849 3.736616)
			(xy 376.620351 3.736616) (xy 376.674299 3.72886) (xy 376.726594 3.713505) (xy 376.776171 3.690863)
			(xy 376.822021 3.661397) (xy 376.863212 3.625706) (xy 376.898903 3.584515) (xy 376.928369 3.538665)
			(xy 376.951011 3.489088) (xy 376.966366 3.436793) (xy 376.974122 3.382845) (xy 376.974608 3.355594)
			(xy 376.974608 2.491994) (xy 376.974122 2.464743) (xy 376.966366 2.410795) (xy 376.951011 2.3585)
			(xy 376.928369 2.308923) (xy 376.898903 2.263073) (xy 376.863212 2.221882) (xy 376.822021 2.186191)
			(xy 376.776171 2.156725) (xy 376.726594 2.134083) (xy 376.674299 2.118728) (xy 376.620351 2.110972)
			(xy 376.565849 2.110972) (xy 376.511901 2.118728) (xy 376.459606 2.134083) (xy 376.410029 2.156725)
			(xy 376.364179 2.186191) (xy 376.322988 2.221882) (xy 376.287297 2.263073) (xy 376.257831 2.308923)
			(xy 376.235189 2.3585) (xy 376.219834 2.410795) (xy 376.212078 2.464743) (xy 376.211592 2.491994)
			(xy 375.02966 2.491994) (xy 375.084217 2.464828) (xy 375.157123 2.419687) (xy 375.225552 2.368011)
			(xy 375.288922 2.310242) (xy 375.346691 2.246872) (xy 375.398367 2.178443) (xy 375.443508 2.105537)
			(xy 375.48173 2.028777) (xy 375.512706 1.948818) (xy 375.536173 1.866342) (xy 375.551929 1.782052)
			(xy 375.559841 1.696669) (xy 375.560336 1.653794) (xy 375.559841 1.610919) (xy 380.055107 1.610919)
			(xy 380.055107 1.696669) (xy 380.063019 1.782052) (xy 380.078775 1.866342) (xy 380.102242 1.948818)
			(xy 380.133218 2.028777) (xy 380.17144 2.105537) (xy 380.216581 2.178443) (xy 380.268257 2.246872)
			(xy 380.326026 2.310242) (xy 380.389396 2.368011) (xy 380.457825 2.419687) (xy 380.530731 2.464828)
			(xy 380.607491 2.50305) (xy 380.68745 2.534026) (xy 380.769926 2.557493) (xy 380.854216 2.573249)
			(xy 380.939599 2.581161) (xy 381.025349 2.581161) (xy 381.110732 2.573249) (xy 381.195022 2.557493)
			(xy 381.277498 2.534026) (xy 381.357457 2.50305) (xy 381.434217 2.464828) (xy 381.507123 2.419687)
			(xy 381.575552 2.368011) (xy 381.638922 2.310242) (xy 381.696691 2.246872) (xy 381.748367 2.178443)
			(xy 381.793508 2.105537) (xy 381.83173 2.028777) (xy 381.862706 1.948818) (xy 381.886173 1.866342)
			(xy 381.901929 1.782052) (xy 381.909841 1.696669) (xy 381.910336 1.653794) (xy 381.909841 1.610919)
			(xy 381.901929 1.525536) (xy 381.886173 1.441246) (xy 381.862706 1.35877) (xy 381.83173 1.278811)
			(xy 381.793508 1.202051) (xy 381.748367 1.129145) (xy 381.696691 1.060716) (xy 381.638922 0.997346)
			(xy 381.575552 0.939577) (xy 381.507123 0.887901) (xy 381.434217 0.84276) (xy 381.357457 0.804538)
			(xy 381.277498 0.773562) (xy 381.195022 0.750095) (xy 381.110732 0.734339) (xy 381.025349 0.726427)
			(xy 380.939599 0.726427) (xy 380.854216 0.734339) (xy 380.769926 0.750095) (xy 380.68745 0.773562)
			(xy 380.607491 0.804538) (xy 380.530731 0.84276) (xy 380.457825 0.887901) (xy 380.389396 0.939577)
			(xy 380.326026 0.997346) (xy 380.268257 1.060716) (xy 380.216581 1.129145) (xy 380.17144 1.202051)
			(xy 380.133218 1.278811) (xy 380.102242 1.35877) (xy 380.078775 1.441246) (xy 380.063019 1.525536)
			(xy 380.055107 1.610919) (xy 375.559841 1.610919) (xy 375.551929 1.525536) (xy 375.536173 1.441246)
			(xy 375.512706 1.35877) (xy 375.48173 1.278811) (xy 375.443508 1.202051) (xy 375.398367 1.129145)
			(xy 375.346691 1.060716) (xy 375.288922 0.997346) (xy 375.225552 0.939577) (xy 375.157123 0.887901)
			(xy 375.084217 0.84276) (xy 375.007457 0.804538) (xy 374.927498 0.773562) (xy 374.845022 0.750095)
			(xy 374.760732 0.734339) (xy 374.675349 0.726427) (xy 374.589599 0.726427) (xy 374.504216 0.734339)
			(xy 374.419926 0.750095) (xy 374.33745 0.773562) (xy 374.257491 0.804538) (xy 374.180731 0.84276)
			(xy 374.107825 0.887901) (xy 374.039396 0.939577) (xy 373.976026 0.997346) (xy 373.918257 1.060716)
			(xy 373.866581 1.129145) (xy 373.82144 1.202051) (xy 373.783218 1.278811) (xy 373.752242 1.35877)
			(xy 373.728775 1.441246) (xy 373.713019 1.525536) (xy 373.705107 1.610919) (xy 343.693001 1.610919)
			(xy 343.685089 1.525536) (xy 343.669333 1.441246) (xy 343.645866 1.35877) (xy 343.61489 1.278811)
			(xy 343.576668 1.202051) (xy 343.531527 1.129145) (xy 343.479851 1.060716) (xy 343.422082 0.997346)
			(xy 343.358712 0.939577) (xy 343.290283 0.887901) (xy 343.217377 0.84276) (xy 343.140617 0.804538)
			(xy 343.060658 0.773562) (xy 342.978182 0.750095) (xy 342.893892 0.734339) (xy 342.808509 0.726427)
			(xy 342.722759 0.726427) (xy 342.637376 0.734339) (xy 342.553086 0.750095) (xy 342.47061 0.773562)
			(xy 342.390651 0.804538) (xy 342.313891 0.84276) (xy 342.240985 0.887901) (xy 342.172556 0.939577)
			(xy 342.109186 0.997346) (xy 342.051417 1.060716) (xy 341.999741 1.129145) (xy 341.9546 1.202051)
			(xy 341.916378 1.278811) (xy 341.885402 1.35877) (xy 341.861935 1.441246) (xy 341.846179 1.525536)
			(xy 341.838267 1.610919) (xy 337.343001 1.610919) (xy 337.335089 1.525536) (xy 337.319333 1.441246)
			(xy 337.295866 1.35877) (xy 337.26489 1.278811) (xy 337.226668 1.202051) (xy 337.181527 1.129145)
			(xy 337.129851 1.060716) (xy 337.072082 0.997346) (xy 337.008712 0.939577) (xy 336.940283 0.887901)
			(xy 336.867377 0.84276) (xy 336.790617 0.804538) (xy 336.710658 0.773562) (xy 336.628182 0.750095)
			(xy 336.543892 0.734339) (xy 336.458509 0.726427) (xy 336.372759 0.726427) (xy 336.287376 0.734339)
			(xy 336.203086 0.750095) (xy 336.12061 0.773562) (xy 336.040651 0.804538) (xy 335.963891 0.84276)
			(xy 335.890985 0.887901) (xy 335.822556 0.939577) (xy 335.759186 0.997346) (xy 335.701417 1.060716)
			(xy 335.649741 1.129145) (xy 335.6046 1.202051) (xy 335.566378 1.278811) (xy 335.535402 1.35877)
			(xy 335.511935 1.441246) (xy 335.496179 1.525536) (xy 335.488267 1.610919) (xy 333.050655 1.610919)
			(xy 333.042743 1.525536) (xy 333.026987 1.441246) (xy 333.00352 1.35877) (xy 332.972544 1.278811)
			(xy 332.934322 1.202051) (xy 332.889181 1.129145) (xy 332.837505 1.060716) (xy 332.779736 0.997346)
			(xy 332.716366 0.939577) (xy 332.647937 0.887901) (xy 332.575031 0.84276) (xy 332.498271 0.804538)
			(xy 332.418312 0.773562) (xy 332.335836 0.750095) (xy 332.251546 0.734339) (xy 332.166163 0.726427)
			(xy 332.080413 0.726427) (xy 331.99503 0.734339) (xy 331.91074 0.750095) (xy 331.828264 0.773562)
			(xy 331.748305 0.804538) (xy 331.671545 0.84276) (xy 331.598639 0.887901) (xy 331.53021 0.939577)
			(xy 331.46684 0.997346) (xy 331.409071 1.060716) (xy 331.357395 1.129145) (xy 331.312254 1.202051)
			(xy 331.274032 1.278811) (xy 331.243056 1.35877) (xy 331.219589 1.441246) (xy 331.203833 1.525536)
			(xy 331.195921 1.610919) (xy 326.700655 1.610919) (xy 326.692743 1.525536) (xy 326.676987 1.441246)
			(xy 326.65352 1.35877) (xy 326.622544 1.278811) (xy 326.584322 1.202051) (xy 326.539181 1.129145)
			(xy 326.487505 1.060716) (xy 326.429736 0.997346) (xy 326.366366 0.939577) (xy 326.297937 0.887901)
			(xy 326.225031 0.84276) (xy 326.148271 0.804538) (xy 326.068312 0.773562) (xy 325.985836 0.750095)
			(xy 325.901546 0.734339) (xy 325.816163 0.726427) (xy 325.730413 0.726427) (xy 325.64503 0.734339)
			(xy 325.56074 0.750095) (xy 325.478264 0.773562) (xy 325.398305 0.804538) (xy 325.321545 0.84276)
			(xy 325.248639 0.887901) (xy 325.18021 0.939577) (xy 325.11684 0.997346) (xy 325.059071 1.060716)
			(xy 325.007395 1.129145) (xy 324.962254 1.202051) (xy 324.924032 1.278811) (xy 324.893056 1.35877)
			(xy 324.869589 1.441246) (xy 324.853833 1.525536) (xy 324.845921 1.610919) (xy 265.125975 1.610919)
			(xy 265.118063 1.525536) (xy 265.102307 1.441246) (xy 265.07884 1.35877) (xy 265.047864 1.278811)
			(xy 265.009642 1.202051) (xy 264.964501 1.129145) (xy 264.912825 1.060716) (xy 264.855056 0.997346)
			(xy 264.791686 0.939577) (xy 264.723257 0.887901) (xy 264.650351 0.84276) (xy 264.573591 0.804538)
			(xy 264.493632 0.773562) (xy 264.411156 0.750095) (xy 264.326866 0.734339) (xy 264.241483 0.726427)
			(xy 264.155733 0.726427) (xy 264.07035 0.734339) (xy 263.98606 0.750095) (xy 263.903584 0.773562)
			(xy 263.823625 0.804538) (xy 263.746865 0.84276) (xy 263.673959 0.887901) (xy 263.60553 0.939577)
			(xy 263.54216 0.997346) (xy 263.484391 1.060716) (xy 263.432715 1.129145) (xy 263.387574 1.202051)
			(xy 263.349352 1.278811) (xy 263.318376 1.35877) (xy 263.294909 1.441246) (xy 263.279153 1.525536)
			(xy 263.271241 1.610919) (xy 258.775975 1.610919) (xy 258.768063 1.525536) (xy 258.752307 1.441246)
			(xy 258.72884 1.35877) (xy 258.697864 1.278811) (xy 258.659642 1.202051) (xy 258.614501 1.129145)
			(xy 258.562825 1.060716) (xy 258.505056 0.997346) (xy 258.441686 0.939577) (xy 258.373257 0.887901)
			(xy 258.300351 0.84276) (xy 258.223591 0.804538) (xy 258.143632 0.773562) (xy 258.061156 0.750095)
			(xy 257.976866 0.734339) (xy 257.891483 0.726427) (xy 257.805733 0.726427) (xy 257.72035 0.734339)
			(xy 257.63606 0.750095) (xy 257.553584 0.773562) (xy 257.473625 0.804538) (xy 257.396865 0.84276)
			(xy 257.323959 0.887901) (xy 257.25553 0.939577) (xy 257.19216 0.997346) (xy 257.134391 1.060716)
			(xy 257.082715 1.129145) (xy 257.037574 1.202051) (xy 256.999352 1.278811) (xy 256.968376 1.35877)
			(xy 256.944909 1.441246) (xy 256.929153 1.525536) (xy 256.921241 1.610919) (xy 254.465119 1.610919)
			(xy 254.465087 1.608125) (xy 254.457175 1.522742) (xy 254.441419 1.438452) (xy 254.417952 1.355976)
			(xy 254.386976 1.276017) (xy 254.348754 1.199257) (xy 254.303613 1.126351) (xy 254.251937 1.057922)
			(xy 254.194168 0.994552) (xy 254.130798 0.936783) (xy 254.062369 0.885107) (xy 253.989463 0.839966)
			(xy 253.912703 0.801744) (xy 253.832744 0.770768) (xy 253.750268 0.747301) (xy 253.665978 0.731545)
			(xy 253.580595 0.723633) (xy 253.494845 0.723633) (xy 253.409462 0.731545) (xy 253.325172 0.747301)
			(xy 253.242696 0.770768) (xy 253.162737 0.801744) (xy 253.085977 0.839966) (xy 253.013071 0.885107)
			(xy 252.944642 0.936783) (xy 252.881272 0.994552) (xy 252.823503 1.057922) (xy 252.771827 1.126351)
			(xy 252.726686 1.199257) (xy 252.688464 1.276017) (xy 252.657488 1.355976) (xy 252.634021 1.438452)
			(xy 252.618265 1.522742) (xy 252.610353 1.608125) (xy 248.115087 1.608125) (xy 248.107175 1.522742)
			(xy 248.091419 1.438452) (xy 248.067952 1.355976) (xy 248.036976 1.276017) (xy 247.998754 1.199257)
			(xy 247.953613 1.126351) (xy 247.901937 1.057922) (xy 247.844168 0.994552) (xy 247.780798 0.936783)
			(xy 247.712369 0.885107) (xy 247.639463 0.839966) (xy 247.562703 0.801744) (xy 247.482744 0.770768)
			(xy 247.400268 0.747301) (xy 247.315978 0.731545) (xy 247.230595 0.723633) (xy 247.144845 0.723633)
			(xy 247.059462 0.731545) (xy 246.975172 0.747301) (xy 246.892696 0.770768) (xy 246.812737 0.801744)
			(xy 246.735977 0.839966) (xy 246.663071 0.885107) (xy 246.594642 0.936783) (xy 246.531272 0.994552)
			(xy 246.473503 1.057922) (xy 246.421827 1.126351) (xy 246.376686 1.199257) (xy 246.338464 1.276017)
			(xy 246.307488 1.355976) (xy 246.284021 1.438452) (xy 246.268265 1.522742) (xy 246.260353 1.608125)
			(xy 186.540407 1.608125) (xy 186.532495 1.522742) (xy 186.516739 1.438452) (xy 186.493272 1.355976)
			(xy 186.462296 1.276017) (xy 186.424074 1.199257) (xy 186.378933 1.126351) (xy 186.327257 1.057922)
			(xy 186.269488 0.994552) (xy 186.206118 0.936783) (xy 186.137689 0.885107) (xy 186.064783 0.839966)
			(xy 185.988023 0.801744) (xy 185.908064 0.770768) (xy 185.825588 0.747301) (xy 185.741298 0.731545)
			(xy 185.655915 0.723633) (xy 185.570165 0.723633) (xy 185.484782 0.731545) (xy 185.400492 0.747301)
			(xy 185.318016 0.770768) (xy 185.238057 0.801744) (xy 185.161297 0.839966) (xy 185.088391 0.885107)
			(xy 185.019962 0.936783) (xy 184.956592 0.994552) (xy 184.898823 1.057922) (xy 184.847147 1.126351)
			(xy 184.802006 1.199257) (xy 184.763784 1.276017) (xy 184.732808 1.355976) (xy 184.709341 1.438452)
			(xy 184.693585 1.522742) (xy 184.685673 1.608125) (xy 180.190407 1.608125) (xy 180.182495 1.522742)
			(xy 180.166739 1.438452) (xy 180.143272 1.355976) (xy 180.112296 1.276017) (xy 180.074074 1.199257)
			(xy 180.028933 1.126351) (xy 179.977257 1.057922) (xy 179.919488 0.994552) (xy 179.856118 0.936783)
			(xy 179.787689 0.885107) (xy 179.714783 0.839966) (xy 179.638023 0.801744) (xy 179.558064 0.770768)
			(xy 179.475588 0.747301) (xy 179.391298 0.731545) (xy 179.305915 0.723633) (xy 179.220165 0.723633)
			(xy 179.134782 0.731545) (xy 179.050492 0.747301) (xy 178.968016 0.770768) (xy 178.888057 0.801744)
			(xy 178.811297 0.839966) (xy 178.738391 0.885107) (xy 178.669962 0.936783) (xy 178.606592 0.994552)
			(xy 178.548823 1.057922) (xy 178.497147 1.126351) (xy 178.452006 1.199257) (xy 178.413784 1.276017)
			(xy 178.382808 1.355976) (xy 178.359341 1.438452) (xy 178.343585 1.522742) (xy 178.335673 1.608125)
			(xy 84.135094 1.608125) (xy 84.162197 1.489382) (xy 84.185766 1.350662) (xy 84.20152 1.210839) (xy 84.20941 1.070352)
			(xy 84.20989 0.999998) (xy 84.20989 -0.931875) (xy 208.043513 -0.931875) (xy 208.043513 -0.846125)
			(xy 208.051425 -0.760742) (xy 208.067181 -0.676452) (xy 208.090648 -0.593976) (xy 208.121624 -0.514017)
			(xy 208.159846 -0.437257) (xy 208.204987 -0.364351) (xy 208.256663 -0.295922) (xy 208.314432 -0.232552)
			(xy 208.377802 -0.174783) (xy 208.446231 -0.123107) (xy 208.519137 -0.077966) (xy 208.595897 -0.039744)
			(xy 208.675856 -0.008768) (xy 208.758332 0.014699) (xy 208.842622 0.030455) (xy 208.928005 0.038367)
			(xy 209.013755 0.038367) (xy 209.099138 0.030455) (xy 209.183428 0.014699) (xy 209.265904 -0.008768)
			(xy 209.345863 -0.039744) (xy 209.422623 -0.077966) (xy 209.495529 -0.123107) (xy 209.563958 -0.174783)
			(xy 209.627328 -0.232552) (xy 209.685097 -0.295922) (xy 209.736773 -0.364351) (xy 209.781914 -0.437257)
			(xy 209.820136 -0.514017) (xy 209.851112 -0.593976) (xy 209.874579 -0.676452) (xy 209.890335 -0.760742)
			(xy 209.898247 -0.846125) (xy 209.898742 -0.889) (xy 209.898247 -0.931875) (xy 214.393513 -0.931875)
			(xy 214.393513 -0.846125) (xy 214.401425 -0.760742) (xy 214.417181 -0.676452) (xy 214.440648 -0.593976)
			(xy 214.471624 -0.514017) (xy 214.509846 -0.437257) (xy 214.554987 -0.364351) (xy 214.606663 -0.295922)
			(xy 214.664432 -0.232552) (xy 214.727802 -0.174783) (xy 214.796231 -0.123107) (xy 214.869137 -0.077966)
			(xy 214.945897 -0.039744) (xy 215.025856 -0.008768) (xy 215.108332 0.014699) (xy 215.192622 0.030455)
			(xy 215.278005 0.038367) (xy 215.363755 0.038367) (xy 215.449138 0.030455) (xy 215.533428 0.014699)
			(xy 215.615904 -0.008768) (xy 215.695863 -0.039744) (xy 215.772623 -0.077966) (xy 215.845529 -0.123107)
			(xy 215.913958 -0.174783) (xy 215.977328 -0.232552) (xy 216.035097 -0.295922) (xy 216.086773 -0.364351)
			(xy 216.131914 -0.437257) (xy 216.170136 -0.514017) (xy 216.201112 -0.593976) (xy 216.224579 -0.676452)
			(xy 216.240335 -0.760742) (xy 216.248247 -0.846125) (xy 216.248742 -0.889) (xy 216.248247 -0.931875)
			(xy 246.260353 -0.931875) (xy 246.260353 -0.846125) (xy 246.268265 -0.760742) (xy 246.284021 -0.676452)
			(xy 246.307488 -0.593976) (xy 246.338464 -0.514017) (xy 246.376686 -0.437257) (xy 246.421827 -0.364351)
			(xy 246.473503 -0.295922) (xy 246.531272 -0.232552) (xy 246.594642 -0.174783) (xy 246.663071 -0.123107)
			(xy 246.735977 -0.077966) (xy 246.812737 -0.039744) (xy 246.892696 -0.008768) (xy 246.975172 0.014699)
			(xy 247.059462 0.030455) (xy 247.144845 0.038367) (xy 247.230595 0.038367) (xy 247.315978 0.030455)
			(xy 247.400268 0.014699) (xy 247.482744 -0.008768) (xy 247.562703 -0.039744) (xy 247.639463 -0.077966)
			(xy 247.712369 -0.123107) (xy 247.780798 -0.174783) (xy 247.844168 -0.232552) (xy 247.901937 -0.295922)
			(xy 247.953613 -0.364351) (xy 247.998754 -0.437257) (xy 248.036976 -0.514017) (xy 248.067952 -0.593976)
			(xy 248.091419 -0.676452) (xy 248.107175 -0.760742) (xy 248.115087 -0.846125) (xy 248.115582 -0.889)
			(xy 248.115087 -0.931875) (xy 252.610353 -0.931875) (xy 252.610353 -0.846125) (xy 252.618265 -0.760742)
			(xy 252.634021 -0.676452) (xy 252.657488 -0.593976) (xy 252.688464 -0.514017) (xy 252.726686 -0.437257)
			(xy 252.771827 -0.364351) (xy 252.823503 -0.295922) (xy 252.881272 -0.232552) (xy 252.944642 -0.174783)
			(xy 253.013071 -0.123107) (xy 253.085977 -0.077966) (xy 253.162737 -0.039744) (xy 253.242696 -0.008768)
			(xy 253.325172 0.014699) (xy 253.409462 0.030455) (xy 253.494845 0.038367) (xy 253.580595 0.038367)
			(xy 253.665978 0.030455) (xy 253.750268 0.014699) (xy 253.832744 -0.008768) (xy 253.912703 -0.039744)
			(xy 253.989463 -0.077966) (xy 254.062369 -0.123107) (xy 254.130798 -0.174783) (xy 254.194168 -0.232552)
			(xy 254.251937 -0.295922) (xy 254.303613 -0.364351) (xy 254.348754 -0.437257) (xy 254.386976 -0.514017)
			(xy 254.417952 -0.593976) (xy 254.441419 -0.676452) (xy 254.457175 -0.760742) (xy 254.465087 -0.846125)
			(xy 254.465582 -0.889) (xy 254.465119 -0.929081) (xy 256.921241 -0.929081) (xy 256.921241 -0.843331)
			(xy 256.929153 -0.757948) (xy 256.944909 -0.673658) (xy 256.968376 -0.591182) (xy 256.999352 -0.511223)
			(xy 257.037574 -0.434463) (xy 257.082715 -0.361557) (xy 257.134391 -0.293128) (xy 257.19216 -0.229758)
			(xy 257.25553 -0.171989) (xy 257.323959 -0.120313) (xy 257.396865 -0.075172) (xy 257.473625 -0.03695)
			(xy 257.553584 -0.005974) (xy 257.63606 0.017493) (xy 257.72035 0.033249) (xy 257.805733 0.041161)
			(xy 257.891483 0.041161) (xy 257.976866 0.033249) (xy 258.061156 0.017493) (xy 258.143632 -0.005974)
			(xy 258.223591 -0.03695) (xy 258.300351 -0.075172) (xy 258.373257 -0.120313) (xy 258.428864 -0.162306)
			(xy 261.079996 -0.162306) (xy 261.079996 0.934974) (xy 261.080529 0.947058) (xy 261.087973 0.97005)
			(xy 261.102144 0.989627) (xy 261.121661 1.00388) (xy 261.144622 1.01142) (xy 261.156704 1.011936)
			(xy 261.768844 1.011936) (xy 261.777315 1.011685) (xy 261.793848 1.007973) (xy 261.80161 1.00457)
			(xy 261.814596 0.998995) (xy 261.842475 0.99445) (xy 261.870532 0.997721) (xy 261.896619 1.008555)
			(xy 261.918738 1.026125) (xy 261.92734 1.037336) (xy 261.942756 1.058198) (xy 261.978318 1.095962)
			(xy 262.018669 1.128561) (xy 262.063063 1.155392) (xy 262.110683 1.175961) (xy 262.160651 1.189889)
			(xy 262.212046 1.196919) (xy 262.237982 1.197356) (xy 262.265253 1.196882) (xy 262.31924 1.189122)
			(xy 262.371572 1.173758) (xy 262.421186 1.151102) (xy 262.46707 1.121615) (xy 262.508291 1.085899)
			(xy 262.544008 1.04468) (xy 262.573496 0.998797) (xy 262.596153 0.949184) (xy 262.611519 0.896851)
			(xy 262.619281 0.842865) (xy 262.619744 0.815594) (xy 262.619744 -0.048006) (xy 262.619304 -0.075278)
			(xy 262.611541 -0.129267) (xy 262.596173 -0.181601) (xy 262.573513 -0.231215) (xy 262.544023 -0.2771)
			(xy 262.508303 -0.31832) (xy 262.46708 -0.354038) (xy 262.421194 -0.383525) (xy 262.371578 -0.406181)
			(xy 262.319243 -0.421546) (xy 262.265254 -0.429306) (xy 262.237982 -0.429768) (xy 262.211789 -0.4293)
			(xy 262.159897 -0.422107) (xy 262.109477 -0.407885) (xy 262.061475 -0.386903) (xy 262.016793 -0.359554)
			(xy 261.976271 -0.326352) (xy 261.940669 -0.287921) (xy 261.925308 -0.2667) (xy 261.916825 -0.255465)
			(xy 261.894967 -0.23774) (xy 261.86911 -0.226634) (xy 261.841207 -0.222984) (xy 261.813364 -0.227065)
			(xy 261.80034 -0.23241) (xy 261.792854 -0.23558) (xy 261.776971 -0.239039) (xy 261.768844 -0.239268)
			(xy 261.156704 -0.239268) (xy 261.144592 -0.23888) (xy 261.121559 -0.231378) (xy 261.101983 -0.21711)
			(xy 261.08779 -0.19748) (xy 261.080375 -0.174419) (xy 261.079996 -0.162306) (xy 258.428864 -0.162306)
			(xy 258.441686 -0.171989) (xy 258.505056 -0.229758) (xy 258.562825 -0.293128) (xy 258.614501 -0.361557)
			(xy 258.659642 -0.434463) (xy 258.697864 -0.511223) (xy 258.72884 -0.591182) (xy 258.752307 -0.673658)
			(xy 258.768063 -0.757948) (xy 258.775975 -0.843331) (xy 258.77647 -0.886206) (xy 258.775975 -0.929081)
			(xy 263.271241 -0.929081) (xy 263.271241 -0.843331) (xy 263.279153 -0.757948) (xy 263.294909 -0.673658)
			(xy 263.318376 -0.591182) (xy 263.349352 -0.511223) (xy 263.387574 -0.434463) (xy 263.432715 -0.361557)
			(xy 263.484391 -0.293128) (xy 263.54216 -0.229758) (xy 263.60553 -0.171989) (xy 263.673959 -0.120313)
			(xy 263.746865 -0.075172) (xy 263.823625 -0.03695) (xy 263.903584 -0.005974) (xy 263.98606 0.017493)
			(xy 264.07035 0.033249) (xy 264.155733 0.041161) (xy 264.241483 0.041161) (xy 264.326866 0.033249)
			(xy 264.411156 0.017493) (xy 264.493632 -0.005974) (xy 264.573591 -0.03695) (xy 264.650351 -0.075172)
			(xy 264.723257 -0.120313) (xy 264.791686 -0.171989) (xy 264.855056 -0.229758) (xy 264.912825 -0.293128)
			(xy 264.964501 -0.361557) (xy 265.009642 -0.434463) (xy 265.047864 -0.511223) (xy 265.07884 -0.591182)
			(xy 265.102307 -0.673658) (xy 265.118063 -0.757948) (xy 265.125975 -0.843331) (xy 265.12647 -0.886206)
			(xy 265.125975 -0.929081) (xy 324.845921 -0.929081) (xy 324.845921 -0.843331) (xy 324.853833 -0.757948)
			(xy 324.869589 -0.673658) (xy 324.893056 -0.591182) (xy 324.924032 -0.511223) (xy 324.962254 -0.434463)
			(xy 325.007395 -0.361557) (xy 325.059071 -0.293128) (xy 325.11684 -0.229758) (xy 325.18021 -0.171989)
			(xy 325.248639 -0.120313) (xy 325.321545 -0.075172) (xy 325.398305 -0.03695) (xy 325.478264 -0.005974)
			(xy 325.56074 0.017493) (xy 325.64503 0.033249) (xy 325.730413 0.041161) (xy 325.816163 0.041161)
			(xy 325.901546 0.033249) (xy 325.985836 0.017493) (xy 326.068312 -0.005974) (xy 326.148271 -0.03695)
			(xy 326.170474 -0.048006) (xy 327.352152 -0.048006) (xy 327.352152 0.815594) (xy 327.352607 0.842865)
			(xy 327.360369 0.896853) (xy 327.375735 0.949187) (xy 327.398393 0.998801) (xy 327.427881 1.044686)
			(xy 327.4636 1.085906) (xy 327.504821 1.121624) (xy 327.550706 1.151111) (xy 327.60032 1.173768)
			(xy 327.652654 1.189133) (xy 327.706642 1.196893) (xy 327.733914 1.197356) (xy 327.760108 1.19689)
			(xy 327.811999 1.189697) (xy 327.86242 1.175476) (xy 327.910422 1.154493) (xy 327.955104 1.127144)
			(xy 327.995626 1.093942) (xy 328.031228 1.05551) (xy 328.046588 1.034288) (xy 328.055072 1.023054)
			(xy 328.07693 1.005331) (xy 328.102787 0.994225) (xy 328.130689 0.990574) (xy 328.158532 0.994654)
			(xy 328.171556 0.999998) (xy 328.179043 1.003167) (xy 328.194925 1.006627) (xy 328.203052 1.006856)
			(xy 328.815192 1.006856) (xy 328.827295 1.006378) (xy 328.850312 0.998887) (xy 328.869881 0.98464)
			(xy 328.884078 0.965035) (xy 328.891509 0.941998) (xy 328.8919 0.929894) (xy 328.8919 -0.167386)
			(xy 328.891381 -0.179471) (xy 328.883933 -0.202464) (xy 328.869759 -0.222041) (xy 328.850238 -0.236293)
			(xy 328.827275 -0.243833) (xy 328.815192 -0.244348) (xy 328.203052 -0.244348) (xy 328.194581 -0.244097)
			(xy 328.178048 -0.240385) (xy 328.170286 -0.236982) (xy 328.157303 -0.231399) (xy 328.129422 -0.226854)
			(xy 328.101363 -0.230126) (xy 328.075276 -0.240963) (xy 328.053157 -0.258535) (xy 328.044556 -0.269748)
			(xy 328.029145 -0.290615) (xy 327.993582 -0.328378) (xy 327.953231 -0.360976) (xy 327.908835 -0.387806)
			(xy 327.861214 -0.408375) (xy 327.811245 -0.422302) (xy 327.759851 -0.429332) (xy 327.733914 -0.429768)
			(xy 327.706644 -0.429286) (xy 327.652658 -0.421525) (xy 327.600326 -0.406161) (xy 327.550713 -0.383506)
			(xy 327.50483 -0.35402) (xy 327.46361 -0.318305) (xy 327.427892 -0.277086) (xy 327.398404 -0.231205)
			(xy 327.375746 -0.181593) (xy 327.360379 -0.129262) (xy 327.352616 -0.075276) (xy 327.352152 -0.048006)
			(xy 326.170474 -0.048006) (xy 326.225031 -0.075172) (xy 326.297937 -0.120313) (xy 326.366366 -0.171989)
			(xy 326.429736 -0.229758) (xy 326.487505 -0.293128) (xy 326.539181 -0.361557) (xy 326.584322 -0.434463)
			(xy 326.622544 -0.511223) (xy 326.65352 -0.591182) (xy 326.676987 -0.673658) (xy 326.692743 -0.757948)
			(xy 326.700655 -0.843331) (xy 326.70115 -0.886206) (xy 326.700655 -0.929081) (xy 331.195921 -0.929081)
			(xy 331.195921 -0.843331) (xy 331.203833 -0.757948) (xy 331.219589 -0.673658) (xy 331.243056 -0.591182)
			(xy 331.274032 -0.511223) (xy 331.312254 -0.434463) (xy 331.357395 -0.361557) (xy 331.409071 -0.293128)
			(xy 331.46684 -0.229758) (xy 331.53021 -0.171989) (xy 331.598639 -0.120313) (xy 331.671545 -0.075172)
			(xy 331.748305 -0.03695) (xy 331.828264 -0.005974) (xy 331.91074 0.017493) (xy 331.99503 0.033249)
			(xy 332.080413 0.041161) (xy 332.166163 0.041161) (xy 332.251546 0.033249) (xy 332.335836 0.017493)
			(xy 332.418312 -0.005974) (xy 332.498271 -0.03695) (xy 332.575031 -0.075172) (xy 332.647937 -0.120313)
			(xy 332.716366 -0.171989) (xy 332.779736 -0.229758) (xy 332.837505 -0.293128) (xy 332.889181 -0.361557)
			(xy 332.934322 -0.434463) (xy 332.972544 -0.511223) (xy 333.00352 -0.591182) (xy 333.026987 -0.673658)
			(xy 333.042743 -0.757948) (xy 333.050655 -0.843331) (xy 333.05115 -0.886206) (xy 333.050655 -0.929081)
			(xy 335.488267 -0.929081) (xy 335.488267 -0.843331) (xy 335.496179 -0.757948) (xy 335.511935 -0.673658)
			(xy 335.535402 -0.591182) (xy 335.566378 -0.511223) (xy 335.6046 -0.434463) (xy 335.649741 -0.361557)
			(xy 335.701417 -0.293128) (xy 335.759186 -0.229758) (xy 335.822556 -0.171989) (xy 335.890985 -0.120313)
			(xy 335.963891 -0.075172) (xy 336.040651 -0.03695) (xy 336.12061 -0.005974) (xy 336.203086 0.017493)
			(xy 336.287376 0.033249) (xy 336.372759 0.041161) (xy 336.458509 0.041161) (xy 336.543892 0.033249)
			(xy 336.628182 0.017493) (xy 336.710658 -0.005974) (xy 336.790617 -0.03695) (xy 336.867377 -0.075172)
			(xy 336.940283 -0.120313) (xy 336.99589 -0.162306) (xy 339.646768 -0.162306) (xy 339.646768 0.934974)
			(xy 339.647183 0.947098) (xy 339.654671 0.970161) (xy 339.668923 0.98978) (xy 339.688542 1.004031)
			(xy 339.711606 1.011518) (xy 339.72373 1.011936) (xy 340.33587 1.011936) (xy 340.344342 1.011693)
			(xy 340.360875 1.007975) (xy 340.368636 1.00457) (xy 340.381611 0.998968) (xy 340.409496 0.994428)
			(xy 340.437557 0.997705) (xy 340.463646 1.008546) (xy 340.485765 1.026121) (xy 340.494366 1.037336)
			(xy 340.509767 1.05821) (xy 340.545331 1.095974) (xy 340.585684 1.128572) (xy 340.630081 1.155401)
			(xy 340.677704 1.175968) (xy 340.727675 1.189894) (xy 340.779071 1.196921) (xy 340.805008 1.197356)
			(xy 340.83227 1.196851) (xy 340.88624 1.189088) (xy 340.938554 1.173721) (xy 340.988148 1.151062)
			(xy 341.034011 1.121574) (xy 341.075209 1.085857) (xy 341.110903 1.044639) (xy 341.140365 0.99876)
			(xy 341.162996 0.949153) (xy 341.178334 0.89683) (xy 341.186067 0.842857) (xy 341.186516 0.815594)
			(xy 341.186516 -0.048006) (xy 341.186082 -0.075266) (xy 341.178325 -0.129232) (xy 341.162969 -0.181545)
			(xy 341.140327 -0.231141) (xy 341.11086 -0.277012) (xy 341.075167 -0.318224) (xy 341.033974 -0.353939)
			(xy 340.988119 -0.383431) (xy 340.938534 -0.406098) (xy 340.886229 -0.421482) (xy 340.832268 -0.429267)
			(xy 340.805008 -0.429768) (xy 340.778815 -0.42928) (xy 340.726925 -0.422091) (xy 340.676505 -0.407873)
			(xy 340.628503 -0.386894) (xy 340.583821 -0.359548) (xy 340.543298 -0.326349) (xy 340.507695 -0.28792)
			(xy 340.492334 -0.2667) (xy 340.483828 -0.255483) (xy 340.461977 -0.237758) (xy 340.436126 -0.226649)
			(xy 340.408228 -0.222994) (xy 340.380389 -0.227069) (xy 340.367366 -0.23241) (xy 340.359877 -0.235573)
			(xy 340.343996 -0.239036) (xy 340.33587 -0.239268) (xy 339.72373 -0.239268) (xy 339.711609 -0.238815)
			(xy 339.688553 -0.231331) (xy 339.668937 -0.217088) (xy 339.654685 -0.19748) (xy 339.647191 -0.174426)
			(xy 339.646768 -0.162306) (xy 336.99589 -0.162306) (xy 337.008712 -0.171989) (xy 337.072082 -0.229758)
			(xy 337.129851 -0.293128) (xy 337.181527 -0.361557) (xy 337.226668 -0.434463) (xy 337.26489 -0.511223)
			(xy 337.295866 -0.591182) (xy 337.319333 -0.673658) (xy 337.335089 -0.757948) (xy 337.343001 -0.843331)
			(xy 337.343496 -0.886206) (xy 337.343001 -0.929081) (xy 341.838267 -0.929081) (xy 341.838267 -0.843331)
			(xy 341.846179 -0.757948) (xy 341.861935 -0.673658) (xy 341.885402 -0.591182) (xy 341.916378 -0.511223)
			(xy 341.9546 -0.434463) (xy 341.999741 -0.361557) (xy 342.051417 -0.293128) (xy 342.109186 -0.229758)
			(xy 342.172556 -0.171989) (xy 342.240985 -0.120313) (xy 342.313891 -0.075172) (xy 342.390651 -0.03695)
			(xy 342.47061 -0.005974) (xy 342.553086 0.017493) (xy 342.637376 0.033249) (xy 342.722759 0.041161)
			(xy 342.808509 0.041161) (xy 342.893892 0.033249) (xy 342.978182 0.017493) (xy 343.060658 -0.005974)
			(xy 343.140617 -0.03695) (xy 343.217377 -0.075172) (xy 343.290283 -0.120313) (xy 343.358712 -0.171989)
			(xy 343.422082 -0.229758) (xy 343.479851 -0.293128) (xy 343.531527 -0.361557) (xy 343.576668 -0.434463)
			(xy 343.61489 -0.511223) (xy 343.645866 -0.591182) (xy 343.669333 -0.673658) (xy 343.685089 -0.757948)
			(xy 343.693001 -0.843331) (xy 343.693496 -0.886206) (xy 343.693001 -0.929081) (xy 373.705107 -0.929081)
			(xy 373.705107 -0.843331) (xy 373.713019 -0.757948) (xy 373.728775 -0.673658) (xy 373.752242 -0.591182)
			(xy 373.783218 -0.511223) (xy 373.82144 -0.434463) (xy 373.866581 -0.361557) (xy 373.918257 -0.293128)
			(xy 373.976026 -0.229758) (xy 374.039396 -0.171989) (xy 374.107825 -0.120313) (xy 374.180731 -0.075172)
			(xy 374.257491 -0.03695) (xy 374.33745 -0.005974) (xy 374.419926 0.017493) (xy 374.504216 0.033249)
			(xy 374.589599 0.041161) (xy 374.675349 0.041161) (xy 374.760732 0.033249) (xy 374.845022 0.017493)
			(xy 374.927498 -0.005974) (xy 375.007457 -0.03695) (xy 375.02966 -0.048006) (xy 376.211592 -0.048006)
			(xy 376.211592 0.815594) (xy 376.212129 0.84285) (xy 376.219882 0.896807) (xy 376.235231 0.949112)
			(xy 376.257865 0.998702) (xy 376.287322 1.044569) (xy 376.323005 1.085779) (xy 376.364186 1.121494)
			(xy 376.410029 1.150988) (xy 376.459601 1.173661) (xy 376.511894 1.189053) (xy 376.565845 1.196849)
			(xy 376.5931 1.197356) (xy 376.619293 1.196879) (xy 376.671184 1.189688) (xy 376.721605 1.175469)
			(xy 376.769607 1.154488) (xy 376.814289 1.127141) (xy 376.854812 1.09394) (xy 376.890413 1.055509)
			(xy 376.905774 1.034288) (xy 376.91427 1.023064) (xy 376.936125 1.005341) (xy 376.961978 0.994233)
			(xy 376.989878 0.99058) (xy 377.017719 0.994656) (xy 377.030742 0.999998) (xy 377.038231 1.003163)
			(xy 377.054112 1.006625) (xy 377.062238 1.006856) (xy 377.674378 1.006856) (xy 377.6865 1.006421)
			(xy 377.709559 0.998934) (xy 377.729175 0.984687) (xy 377.743427 0.965074) (xy 377.750919 0.942016)
			(xy 377.75134 0.929894) (xy 377.75134 -0.167386) (xy 377.750928 -0.17951) (xy 377.743437 -0.202572)
			(xy 377.729184 -0.222189) (xy 377.709565 -0.23644) (xy 377.686502 -0.243929) (xy 377.674378 -0.244348)
			(xy 377.062238 -0.244348) (xy 377.053766 -0.244102) (xy 377.037234 -0.240386) (xy 377.029472 -0.236982)
			(xy 377.016495 -0.231384) (xy 376.988611 -0.226842) (xy 376.96055 -0.230117) (xy 376.934462 -0.240958)
			(xy 376.912343 -0.258533) (xy 376.903742 -0.269748) (xy 376.88834 -0.290621) (xy 376.852775 -0.328385)
			(xy 376.812422 -0.360982) (xy 376.768025 -0.387811) (xy 376.720403 -0.408379) (xy 376.670433 -0.422305)
			(xy 376.619037 -0.429332) (xy 376.5931 -0.429768) (xy 376.565834 -0.429344) (xy 376.511857 -0.421579)
			(xy 376.459536 -0.406208) (xy 376.409936 -0.383544) (xy 376.364069 -0.354049) (xy 376.322868 -0.318323)
			(xy 376.287175 -0.277096) (xy 376.257715 -0.231206) (xy 376.235089 -0.181588) (xy 376.219758 -0.129255)
			(xy 376.212035 -0.075273) (xy 376.211592 -0.048006) (xy 375.02966 -0.048006) (xy 375.084217 -0.075172)
			(xy 375.157123 -0.120313) (xy 375.225552 -0.171989) (xy 375.288922 -0.229758) (xy 375.346691 -0.293128)
			(xy 375.398367 -0.361557) (xy 375.443508 -0.434463) (xy 375.48173 -0.511223) (xy 375.512706 -0.591182)
			(xy 375.536173 -0.673658) (xy 375.551929 -0.757948) (xy 375.559841 -0.843331) (xy 375.560336 -0.886206)
			(xy 375.559841 -0.929081) (xy 380.055107 -0.929081) (xy 380.055107 -0.843331) (xy 380.063019 -0.757948)
			(xy 380.078775 -0.673658) (xy 380.102242 -0.591182) (xy 380.133218 -0.511223) (xy 380.17144 -0.434463)
			(xy 380.216581 -0.361557) (xy 380.268257 -0.293128) (xy 380.326026 -0.229758) (xy 380.389396 -0.171989)
			(xy 380.457825 -0.120313) (xy 380.530731 -0.075172) (xy 380.607491 -0.03695) (xy 380.68745 -0.005974)
			(xy 380.769926 0.017493) (xy 380.854216 0.033249) (xy 380.939599 0.041161) (xy 381.025349 0.041161)
			(xy 381.110732 0.033249) (xy 381.195022 0.017493) (xy 381.277498 -0.005974) (xy 381.357457 -0.03695)
			(xy 381.434217 -0.075172) (xy 381.507123 -0.120313) (xy 381.575552 -0.171989) (xy 381.638922 -0.229758)
			(xy 381.696691 -0.293128) (xy 381.748367 -0.361557) (xy 381.793508 -0.434463) (xy 381.83173 -0.511223)
			(xy 381.862706 -0.591182) (xy 381.886173 -0.673658) (xy 381.901929 -0.757948) (xy 381.909841 -0.843331)
			(xy 381.910336 -0.886206) (xy 381.909841 -0.929081) (xy 381.901929 -1.014464) (xy 381.886173 -1.098754)
			(xy 381.862706 -1.18123) (xy 381.83173 -1.261189) (xy 381.793508 -1.337949) (xy 381.748367 -1.410855)
			(xy 381.696691 -1.479284) (xy 381.638922 -1.542654) (xy 381.575552 -1.600423) (xy 381.507123 -1.652099)
			(xy 381.434217 -1.69724) (xy 381.357457 -1.735462) (xy 381.277498 -1.766438) (xy 381.195022 -1.789905)
			(xy 381.110732 -1.805661) (xy 381.025349 -1.813573) (xy 380.939599 -1.813573) (xy 380.854216 -1.805661)
			(xy 380.769926 -1.789905) (xy 380.68745 -1.766438) (xy 380.607491 -1.735462) (xy 380.530731 -1.69724)
			(xy 380.457825 -1.652099) (xy 380.389396 -1.600423) (xy 380.326026 -1.542654) (xy 380.268257 -1.479284)
			(xy 380.216581 -1.410855) (xy 380.17144 -1.337949) (xy 380.133218 -1.261189) (xy 380.102242 -1.18123)
			(xy 380.078775 -1.098754) (xy 380.063019 -1.014464) (xy 380.055107 -0.929081) (xy 375.559841 -0.929081)
			(xy 375.551929 -1.014464) (xy 375.536173 -1.098754) (xy 375.512706 -1.18123) (xy 375.48173 -1.261189)
			(xy 375.443508 -1.337949) (xy 375.398367 -1.410855) (xy 375.346691 -1.479284) (xy 375.288922 -1.542654)
			(xy 375.225552 -1.600423) (xy 375.157123 -1.652099) (xy 375.084217 -1.69724) (xy 375.007457 -1.735462)
			(xy 374.927498 -1.766438) (xy 374.845022 -1.789905) (xy 374.760732 -1.805661) (xy 374.675349 -1.813573)
			(xy 374.589599 -1.813573) (xy 374.504216 -1.805661) (xy 374.419926 -1.789905) (xy 374.33745 -1.766438)
			(xy 374.257491 -1.735462) (xy 374.180731 -1.69724) (xy 374.107825 -1.652099) (xy 374.039396 -1.600423)
			(xy 373.976026 -1.542654) (xy 373.918257 -1.479284) (xy 373.866581 -1.410855) (xy 373.82144 -1.337949)
			(xy 373.783218 -1.261189) (xy 373.752242 -1.18123) (xy 373.728775 -1.098754) (xy 373.713019 -1.014464)
			(xy 373.705107 -0.929081) (xy 343.693001 -0.929081) (xy 343.685089 -1.014464) (xy 343.669333 -1.098754)
			(xy 343.645866 -1.18123) (xy 343.61489 -1.261189) (xy 343.576668 -1.337949) (xy 343.531527 -1.410855)
			(xy 343.479851 -1.479284) (xy 343.422082 -1.542654) (xy 343.358712 -1.600423) (xy 343.290283 -1.652099)
			(xy 343.217377 -1.69724) (xy 343.140617 -1.735462) (xy 343.060658 -1.766438) (xy 342.978182 -1.789905)
			(xy 342.893892 -1.805661) (xy 342.808509 -1.813573) (xy 342.722759 -1.813573) (xy 342.637376 -1.805661)
			(xy 342.553086 -1.789905) (xy 342.47061 -1.766438) (xy 342.390651 -1.735462) (xy 342.313891 -1.69724)
			(xy 342.240985 -1.652099) (xy 342.172556 -1.600423) (xy 342.109186 -1.542654) (xy 342.051417 -1.479284)
			(xy 341.999741 -1.410855) (xy 341.9546 -1.337949) (xy 341.916378 -1.261189) (xy 341.885402 -1.18123)
			(xy 341.861935 -1.098754) (xy 341.846179 -1.014464) (xy 341.838267 -0.929081) (xy 337.343001 -0.929081)
			(xy 337.335089 -1.014464) (xy 337.319333 -1.098754) (xy 337.295866 -1.18123) (xy 337.26489 -1.261189)
			(xy 337.226668 -1.337949) (xy 337.181527 -1.410855) (xy 337.129851 -1.479284) (xy 337.072082 -1.542654)
			(xy 337.008712 -1.600423) (xy 336.940283 -1.652099) (xy 336.867377 -1.69724) (xy 336.790617 -1.735462)
			(xy 336.710658 -1.766438) (xy 336.628182 -1.789905) (xy 336.543892 -1.805661) (xy 336.458509 -1.813573)
			(xy 336.372759 -1.813573) (xy 336.287376 -1.805661) (xy 336.203086 -1.789905) (xy 336.12061 -1.766438)
			(xy 336.040651 -1.735462) (xy 335.963891 -1.69724) (xy 335.890985 -1.652099) (xy 335.822556 -1.600423)
			(xy 335.759186 -1.542654) (xy 335.701417 -1.479284) (xy 335.649741 -1.410855) (xy 335.6046 -1.337949)
			(xy 335.566378 -1.261189) (xy 335.535402 -1.18123) (xy 335.511935 -1.098754) (xy 335.496179 -1.014464)
			(xy 335.488267 -0.929081) (xy 333.050655 -0.929081) (xy 333.042743 -1.014464) (xy 333.026987 -1.098754)
			(xy 333.00352 -1.18123) (xy 332.972544 -1.261189) (xy 332.934322 -1.337949) (xy 332.889181 -1.410855)
			(xy 332.837505 -1.479284) (xy 332.779736 -1.542654) (xy 332.716366 -1.600423) (xy 332.647937 -1.652099)
			(xy 332.575031 -1.69724) (xy 332.498271 -1.735462) (xy 332.418312 -1.766438) (xy 332.335836 -1.789905)
			(xy 332.251546 -1.805661) (xy 332.166163 -1.813573) (xy 332.080413 -1.813573) (xy 331.99503 -1.805661)
			(xy 331.91074 -1.789905) (xy 331.828264 -1.766438) (xy 331.748305 -1.735462) (xy 331.671545 -1.69724)
			(xy 331.598639 -1.652099) (xy 331.53021 -1.600423) (xy 331.46684 -1.542654) (xy 331.409071 -1.479284)
			(xy 331.357395 -1.410855) (xy 331.312254 -1.337949) (xy 331.274032 -1.261189) (xy 331.243056 -1.18123)
			(xy 331.219589 -1.098754) (xy 331.203833 -1.014464) (xy 331.195921 -0.929081) (xy 326.700655 -0.929081)
			(xy 326.692743 -1.014464) (xy 326.676987 -1.098754) (xy 326.65352 -1.18123) (xy 326.622544 -1.261189)
			(xy 326.584322 -1.337949) (xy 326.539181 -1.410855) (xy 326.487505 -1.479284) (xy 326.429736 -1.542654)
			(xy 326.366366 -1.600423) (xy 326.297937 -1.652099) (xy 326.225031 -1.69724) (xy 326.148271 -1.735462)
			(xy 326.068312 -1.766438) (xy 325.985836 -1.789905) (xy 325.901546 -1.805661) (xy 325.816163 -1.813573)
			(xy 325.730413 -1.813573) (xy 325.64503 -1.805661) (xy 325.56074 -1.789905) (xy 325.478264 -1.766438)
			(xy 325.398305 -1.735462) (xy 325.321545 -1.69724) (xy 325.248639 -1.652099) (xy 325.18021 -1.600423)
			(xy 325.11684 -1.542654) (xy 325.059071 -1.479284) (xy 325.007395 -1.410855) (xy 324.962254 -1.337949)
			(xy 324.924032 -1.261189) (xy 324.893056 -1.18123) (xy 324.869589 -1.098754) (xy 324.853833 -1.014464)
			(xy 324.845921 -0.929081) (xy 265.125975 -0.929081) (xy 265.118063 -1.014464) (xy 265.102307 -1.098754)
			(xy 265.07884 -1.18123) (xy 265.047864 -1.261189) (xy 265.009642 -1.337949) (xy 264.964501 -1.410855)
			(xy 264.912825 -1.479284) (xy 264.855056 -1.542654) (xy 264.791686 -1.600423) (xy 264.723257 -1.652099)
			(xy 264.650351 -1.69724) (xy 264.573591 -1.735462) (xy 264.493632 -1.766438) (xy 264.411156 -1.789905)
			(xy 264.326866 -1.805661) (xy 264.241483 -1.813573) (xy 264.155733 -1.813573) (xy 264.07035 -1.805661)
			(xy 263.98606 -1.789905) (xy 263.903584 -1.766438) (xy 263.823625 -1.735462) (xy 263.746865 -1.69724)
			(xy 263.673959 -1.652099) (xy 263.60553 -1.600423) (xy 263.54216 -1.542654) (xy 263.484391 -1.479284)
			(xy 263.432715 -1.410855) (xy 263.387574 -1.337949) (xy 263.349352 -1.261189) (xy 263.318376 -1.18123)
			(xy 263.294909 -1.098754) (xy 263.279153 -1.014464) (xy 263.271241 -0.929081) (xy 258.775975 -0.929081)
			(xy 258.768063 -1.014464) (xy 258.752307 -1.098754) (xy 258.72884 -1.18123) (xy 258.697864 -1.261189)
			(xy 258.659642 -1.337949) (xy 258.614501 -1.410855) (xy 258.562825 -1.479284) (xy 258.505056 -1.542654)
			(xy 258.441686 -1.600423) (xy 258.373257 -1.652099) (xy 258.300351 -1.69724) (xy 258.223591 -1.735462)
			(xy 258.143632 -1.766438) (xy 258.061156 -1.789905) (xy 257.976866 -1.805661) (xy 257.891483 -1.813573)
			(xy 257.805733 -1.813573) (xy 257.72035 -1.805661) (xy 257.63606 -1.789905) (xy 257.553584 -1.766438)
			(xy 257.473625 -1.735462) (xy 257.396865 -1.69724) (xy 257.323959 -1.652099) (xy 257.25553 -1.600423)
			(xy 257.19216 -1.542654) (xy 257.134391 -1.479284) (xy 257.082715 -1.410855) (xy 257.037574 -1.337949)
			(xy 256.999352 -1.261189) (xy 256.968376 -1.18123) (xy 256.944909 -1.098754) (xy 256.929153 -1.014464)
			(xy 256.921241 -0.929081) (xy 254.465119 -0.929081) (xy 254.465087 -0.931875) (xy 254.457175 -1.017258)
			(xy 254.441419 -1.101548) (xy 254.417952 -1.184024) (xy 254.386976 -1.263983) (xy 254.348754 -1.340743)
			(xy 254.303613 -1.413649) (xy 254.251937 -1.482078) (xy 254.194168 -1.545448) (xy 254.130798 -1.603217)
			(xy 254.062369 -1.654893) (xy 253.989463 -1.700034) (xy 253.912703 -1.738256) (xy 253.832744 -1.769232)
			(xy 253.750268 -1.792699) (xy 253.665978 -1.808455) (xy 253.580595 -1.816367) (xy 253.494845 -1.816367)
			(xy 253.409462 -1.808455) (xy 253.325172 -1.792699) (xy 253.242696 -1.769232) (xy 253.162737 -1.738256)
			(xy 253.085977 -1.700034) (xy 253.013071 -1.654893) (xy 252.944642 -1.603217) (xy 252.881272 -1.545448)
			(xy 252.823503 -1.482078) (xy 252.771827 -1.413649) (xy 252.726686 -1.340743) (xy 252.688464 -1.263983)
			(xy 252.657488 -1.184024) (xy 252.634021 -1.101548) (xy 252.618265 -1.017258) (xy 252.610353 -0.931875)
			(xy 248.115087 -0.931875) (xy 248.107175 -1.017258) (xy 248.091419 -1.101548) (xy 248.067952 -1.184024)
			(xy 248.036976 -1.263983) (xy 247.998754 -1.340743) (xy 247.953613 -1.413649) (xy 247.901937 -1.482078)
			(xy 247.844168 -1.545448) (xy 247.780798 -1.603217) (xy 247.712369 -1.654893) (xy 247.639463 -1.700034)
			(xy 247.562703 -1.738256) (xy 247.482744 -1.769232) (xy 247.400268 -1.792699) (xy 247.315978 -1.808455)
			(xy 247.230595 -1.816367) (xy 247.144845 -1.816367) (xy 247.059462 -1.808455) (xy 246.975172 -1.792699)
			(xy 246.892696 -1.769232) (xy 246.812737 -1.738256) (xy 246.735977 -1.700034) (xy 246.663071 -1.654893)
			(xy 246.594642 -1.603217) (xy 246.531272 -1.545448) (xy 246.473503 -1.482078) (xy 246.421827 -1.413649)
			(xy 246.376686 -1.340743) (xy 246.338464 -1.263983) (xy 246.307488 -1.184024) (xy 246.284021 -1.101548)
			(xy 246.268265 -1.017258) (xy 246.260353 -0.931875) (xy 216.248247 -0.931875) (xy 216.240335 -1.017258)
			(xy 216.224579 -1.101548) (xy 216.201112 -1.184024) (xy 216.170136 -1.263983) (xy 216.131914 -1.340743)
			(xy 216.086773 -1.413649) (xy 216.035097 -1.482078) (xy 215.977328 -1.545448) (xy 215.913958 -1.603217)
			(xy 215.845529 -1.654893) (xy 215.772623 -1.700034) (xy 215.695863 -1.738256) (xy 215.615904 -1.769232)
			(xy 215.533428 -1.792699) (xy 215.449138 -1.808455) (xy 215.363755 -1.816367) (xy 215.278005 -1.816367)
			(xy 215.192622 -1.808455) (xy 215.108332 -1.792699) (xy 215.025856 -1.769232) (xy 214.945897 -1.738256)
			(xy 214.869137 -1.700034) (xy 214.796231 -1.654893) (xy 214.727802 -1.603217) (xy 214.664432 -1.545448)
			(xy 214.606663 -1.482078) (xy 214.554987 -1.413649) (xy 214.509846 -1.340743) (xy 214.471624 -1.263983)
			(xy 214.440648 -1.184024) (xy 214.417181 -1.101548) (xy 214.401425 -1.017258) (xy 214.393513 -0.931875)
			(xy 209.898247 -0.931875) (xy 209.890335 -1.017258) (xy 209.874579 -1.101548) (xy 209.851112 -1.184024)
			(xy 209.820136 -1.263983) (xy 209.781914 -1.340743) (xy 209.736773 -1.413649) (xy 209.685097 -1.482078)
			(xy 209.627328 -1.545448) (xy 209.563958 -1.603217) (xy 209.495529 -1.654893) (xy 209.422623 -1.700034)
			(xy 209.345863 -1.738256) (xy 209.265904 -1.769232) (xy 209.183428 -1.792699) (xy 209.099138 -1.808455)
			(xy 209.013755 -1.816367) (xy 208.928005 -1.816367) (xy 208.842622 -1.808455) (xy 208.758332 -1.792699)
			(xy 208.675856 -1.769232) (xy 208.595897 -1.738256) (xy 208.519137 -1.700034) (xy 208.446231 -1.654893)
			(xy 208.377802 -1.603217) (xy 208.314432 -1.545448) (xy 208.256663 -1.482078) (xy 208.204987 -1.413649)
			(xy 208.159846 -1.340743) (xy 208.121624 -1.263983) (xy 208.090648 -1.184024) (xy 208.067181 -1.101548)
			(xy 208.051425 -1.017258) (xy 208.043513 -0.931875) (xy 84.20989 -0.931875) (xy 84.20989 -7.78002)
			(xy 84.210412 -7.835827) (xy 84.218755 -7.947128) (xy 84.235391 -8.057495) (xy 84.260229 -8.16631)
			(xy 84.293128 -8.272964) (xy 84.333906 -8.376862) (xy 84.382334 -8.477422) (xy 84.438141 -8.574082)
			(xy 84.501016 -8.666301) (xy 84.570606 -8.753563) (xy 84.646523 -8.835382) (xy 84.728341 -8.911298)
			(xy 84.815604 -8.980888) (xy 84.907824 -9.043762) (xy 85.004484 -9.099569) (xy 85.105044 -9.147996)
			(xy 85.208942 -9.188774) (xy 85.315596 -9.221673) (xy 85.424411 -9.24651) (xy 85.534778 -9.263146)
			(xy 85.646079 -9.271488) (xy 85.701886 -9.272016) (xy 122.102118 -9.272016) (xy 122.157925 -9.271494)
			(xy 122.269226 -9.263152) (xy 122.379593 -9.246515) (xy 122.488409 -9.221678) (xy 122.595063 -9.188778)
			(xy 122.698961 -9.148001) (xy 122.799522 -9.099573) (xy 122.896182 -9.043766) (xy 122.988401 -8.980891)
			(xy 123.075664 -8.911301) (xy 123.157483 -8.835384) (xy 123.2334 -8.753566) (xy 123.30299 -8.666303)
			(xy 123.365865 -8.574084) (xy 123.421672 -8.477423) (xy 123.4701 -8.376863) (xy 123.510878 -8.272965)
			(xy 123.543777 -8.16631) (xy 123.568615 -8.057495) (xy 123.585251 -7.947128) (xy 123.593594 -7.835827)
			(xy 123.594114 -7.78002) (xy 123.594114 -4.2799) (xy 123.594598 -4.209546) (xy 123.602488 -4.06906)
			(xy 123.618242 -3.929237) (xy 123.641812 -3.790517) (xy 123.673122 -3.653337) (xy 123.712075 -3.518129)
			(xy 123.758548 -3.385317) (xy 123.812395 -3.25532) (xy 123.873446 -3.128547) (xy 123.941509 -3.005396)
			(xy 124.01637 -2.886255) (xy 124.097794 -2.7715) (xy 124.185524 -2.66149) (xy 124.279284 -2.556573)
			(xy 124.37878 -2.457077) (xy 124.483698 -2.363317) (xy 124.593708 -2.275588) (xy 124.708464 -2.194165)
			(xy 124.827605 -2.119304) (xy 124.950755 -2.051241) (xy 125.077529 -1.990191) (xy 125.207526 -1.936345)
			(xy 125.340338 -1.889872) (xy 125.475547 -1.85092) (xy 125.612727 -1.81961) (xy 125.751447 -1.796041)
			(xy 125.89127 -1.780287) (xy 126.031756 -1.772398) (xy 126.10211 -1.771904) (xy 194.701922 -1.771904)
			(xy 194.772275 -1.772398) (xy 194.912761 -1.780289) (xy 195.052582 -1.796044) (xy 195.191301 -1.819614)
			(xy 195.32848 -1.850925) (xy 195.463687 -1.889879) (xy 195.596497 -1.936352) (xy 195.726493 -1.990199)
			(xy 195.853265 -2.05125) (xy 195.976414 -2.119314) (xy 196.095554 -2.194175) (xy 196.210308 -2.275598)
			(xy 196.320316 -2.363328) (xy 196.425233 -2.457088) (xy 196.524727 -2.556583) (xy 196.618486 -2.6615)
			(xy 196.706215 -2.77151) (xy 196.787637 -2.886265) (xy 196.862497 -3.005405) (xy 196.93056 -3.128555)
			(xy 196.99161 -3.255327) (xy 197.045455 -3.385323) (xy 197.075741 -3.471875) (xy 208.043513 -3.471875)
			(xy 208.043513 -3.386125) (xy 208.051425 -3.300742) (xy 208.067181 -3.216452) (xy 208.090648 -3.133976)
			(xy 208.121624 -3.054017) (xy 208.159846 -2.977257) (xy 208.204987 -2.904351) (xy 208.256663 -2.835922)
			(xy 208.314432 -2.772552) (xy 208.377802 -2.714783) (xy 208.446231 -2.663107) (xy 208.519137 -2.617966)
			(xy 208.595897 -2.579744) (xy 208.675856 -2.548768) (xy 208.758332 -2.525301) (xy 208.842622 -2.509545)
			(xy 208.928005 -2.501633) (xy 209.013755 -2.501633) (xy 209.099138 -2.509545) (xy 209.183428 -2.525301)
			(xy 209.265904 -2.548768) (xy 209.345863 -2.579744) (xy 209.368066 -2.5908) (xy 212.978492 -2.5908)
			(xy 212.978492 -1.7272) (xy 212.978978 -1.699931) (xy 212.98674 -1.645947) (xy 213.002105 -1.593617)
			(xy 213.024762 -1.544007) (xy 213.054248 -1.498126) (xy 213.089963 -1.456909) (xy 213.13118 -1.421194)
			(xy 213.177061 -1.391708) (xy 213.226671 -1.369051) (xy 213.279001 -1.353686) (xy 213.332985 -1.345924)
			(xy 213.387523 -1.345924) (xy 213.441507 -1.353686) (xy 213.493837 -1.369051) (xy 213.543447 -1.391708)
			(xy 213.589328 -1.421194) (xy 213.630545 -1.456909) (xy 213.66626 -1.498126) (xy 213.695746 -1.544007)
			(xy 213.718403 -1.593617) (xy 213.733768 -1.645947) (xy 213.74153 -1.699931) (xy 213.742016 -1.7272)
			(xy 213.742016 -2.5908) (xy 213.74153 -2.618069) (xy 213.733768 -2.672053) (xy 213.718403 -2.724383)
			(xy 213.695746 -2.773993) (xy 213.66626 -2.819874) (xy 213.630545 -2.861091) (xy 213.589328 -2.896806)
			(xy 213.543447 -2.926292) (xy 213.493837 -2.948949) (xy 213.441507 -2.964314) (xy 213.387523 -2.972076)
			(xy 213.332985 -2.972076) (xy 213.279001 -2.964314) (xy 213.226671 -2.948949) (xy 213.177061 -2.926292)
			(xy 213.13118 -2.896806) (xy 213.089963 -2.861091) (xy 213.054248 -2.819874) (xy 213.024762 -2.773993)
			(xy 213.002105 -2.724383) (xy 212.98674 -2.672053) (xy 212.978978 -2.618069) (xy 212.978492 -2.5908)
			(xy 209.368066 -2.5908) (xy 209.422623 -2.617966) (xy 209.495529 -2.663107) (xy 209.563958 -2.714783)
			(xy 209.627328 -2.772552) (xy 209.685097 -2.835922) (xy 209.736773 -2.904351) (xy 209.781914 -2.977257)
			(xy 209.820136 -3.054017) (xy 209.851112 -3.133976) (xy 209.874579 -3.216452) (xy 209.890335 -3.300742)
			(xy 209.898247 -3.386125) (xy 209.898742 -3.429) (xy 209.898247 -3.471875) (xy 214.393513 -3.471875)
			(xy 214.393513 -3.386125) (xy 214.401425 -3.300742) (xy 214.417181 -3.216452) (xy 214.440648 -3.133976)
			(xy 214.471624 -3.054017) (xy 214.509846 -2.977257) (xy 214.554987 -2.904351) (xy 214.606663 -2.835922)
			(xy 214.664432 -2.772552) (xy 214.727802 -2.714783) (xy 214.796231 -2.663107) (xy 214.869137 -2.617966)
			(xy 214.945897 -2.579744) (xy 215.025856 -2.548768) (xy 215.108332 -2.525301) (xy 215.192622 -2.509545)
			(xy 215.278005 -2.501633) (xy 215.363755 -2.501633) (xy 215.449138 -2.509545) (xy 215.533428 -2.525301)
			(xy 215.615904 -2.548768) (xy 215.695863 -2.579744) (xy 215.772623 -2.617966) (xy 215.845529 -2.663107)
			(xy 215.913958 -2.714783) (xy 215.977328 -2.772552) (xy 216.035097 -2.835922) (xy 216.086773 -2.904351)
			(xy 216.131914 -2.977257) (xy 216.170136 -3.054017) (xy 216.201112 -3.133976) (xy 216.224579 -3.216452)
			(xy 216.240335 -3.300742) (xy 216.248247 -3.386125) (xy 216.248742 -3.429) (xy 216.248247 -3.471875)
			(xy 246.260353 -3.471875) (xy 246.260353 -3.386125) (xy 246.268265 -3.300742) (xy 246.284021 -3.216452)
			(xy 246.307488 -3.133976) (xy 246.338464 -3.054017) (xy 246.376686 -2.977257) (xy 246.421827 -2.904351)
			(xy 246.473503 -2.835922) (xy 246.531272 -2.772552) (xy 246.594642 -2.714783) (xy 246.663071 -2.663107)
			(xy 246.735977 -2.617966) (xy 246.812737 -2.579744) (xy 246.892696 -2.548768) (xy 246.975172 -2.525301)
			(xy 247.059462 -2.509545) (xy 247.144845 -2.501633) (xy 247.230595 -2.501633) (xy 247.315978 -2.509545)
			(xy 247.400268 -2.525301) (xy 247.482744 -2.548768) (xy 247.562703 -2.579744) (xy 247.584906 -2.5908)
			(xy 248.766584 -2.5908) (xy 248.766584 -1.7272) (xy 248.76707 -1.699931) (xy 248.774832 -1.645947)
			(xy 248.790197 -1.593617) (xy 248.812854 -1.544007) (xy 248.84234 -1.498126) (xy 248.878055 -1.456909)
			(xy 248.919272 -1.421194) (xy 248.965153 -1.391708) (xy 249.014763 -1.369051) (xy 249.067093 -1.353686)
			(xy 249.121077 -1.345924) (xy 249.175615 -1.345924) (xy 249.229599 -1.353686) (xy 249.281929 -1.369051)
			(xy 249.331539 -1.391708) (xy 249.37742 -1.421194) (xy 249.418637 -1.456909) (xy 249.454352 -1.498126)
			(xy 249.483838 -1.544007) (xy 249.506495 -1.593617) (xy 249.52186 -1.645947) (xy 249.529622 -1.699931)
			(xy 249.530108 -1.7272) (xy 249.530108 -2.5908) (xy 249.529622 -2.618069) (xy 249.52186 -2.672053)
			(xy 249.506495 -2.724383) (xy 249.483838 -2.773993) (xy 249.454352 -2.819874) (xy 249.418637 -2.861091)
			(xy 249.37742 -2.896806) (xy 249.331539 -2.926292) (xy 249.281929 -2.948949) (xy 249.229599 -2.964314)
			(xy 249.175615 -2.972076) (xy 249.121077 -2.972076) (xy 249.067093 -2.964314) (xy 249.014763 -2.948949)
			(xy 248.965153 -2.926292) (xy 248.919272 -2.896806) (xy 248.878055 -2.861091) (xy 248.84234 -2.819874)
			(xy 248.812854 -2.773993) (xy 248.790197 -2.724383) (xy 248.774832 -2.672053) (xy 248.76707 -2.618069)
			(xy 248.766584 -2.5908) (xy 247.584906 -2.5908) (xy 247.639463 -2.617966) (xy 247.712369 -2.663107)
			(xy 247.780798 -2.714783) (xy 247.844168 -2.772552) (xy 247.901937 -2.835922) (xy 247.953613 -2.904351)
			(xy 247.998754 -2.977257) (xy 248.036976 -3.054017) (xy 248.067952 -3.133976) (xy 248.091419 -3.216452)
			(xy 248.107175 -3.300742) (xy 248.115087 -3.386125) (xy 248.115582 -3.429) (xy 248.115087 -3.471875)
			(xy 252.610353 -3.471875) (xy 252.610353 -3.386125) (xy 252.618265 -3.300742) (xy 252.634021 -3.216452)
			(xy 252.657488 -3.133976) (xy 252.688464 -3.054017) (xy 252.726686 -2.977257) (xy 252.771827 -2.904351)
			(xy 252.823503 -2.835922) (xy 252.881272 -2.772552) (xy 252.944642 -2.714783) (xy 253.013071 -2.663107)
			(xy 253.085977 -2.617966) (xy 253.162737 -2.579744) (xy 253.242696 -2.548768) (xy 253.325172 -2.525301)
			(xy 253.409462 -2.509545) (xy 253.494845 -2.501633) (xy 253.580595 -2.501633) (xy 253.665978 -2.509545)
			(xy 253.750268 -2.525301) (xy 253.832744 -2.548768) (xy 253.912703 -2.579744) (xy 253.989463 -2.617966)
			(xy 254.062369 -2.663107) (xy 254.130798 -2.714783) (xy 254.194168 -2.772552) (xy 254.251937 -2.835922)
			(xy 254.303613 -2.904351) (xy 254.348754 -2.977257) (xy 254.386976 -3.054017) (xy 254.417952 -3.133976)
			(xy 254.441419 -3.216452) (xy 254.457175 -3.300742) (xy 254.465087 -3.386125) (xy 254.465582 -3.429)
			(xy 254.465119 -3.469081) (xy 256.921241 -3.469081) (xy 256.921241 -3.383331) (xy 256.929153 -3.297948)
			(xy 256.944909 -3.213658) (xy 256.968376 -3.131182) (xy 256.999352 -3.051223) (xy 257.037574 -2.974463)
			(xy 257.082715 -2.901557) (xy 257.134391 -2.833128) (xy 257.19216 -2.769758) (xy 257.25553 -2.711989)
			(xy 257.323959 -2.660313) (xy 257.396865 -2.615172) (xy 257.473625 -2.57695) (xy 257.553584 -2.545974)
			(xy 257.63606 -2.522507) (xy 257.72035 -2.506751) (xy 257.805733 -2.498839) (xy 257.891483 -2.498839)
			(xy 257.976866 -2.506751) (xy 258.061156 -2.522507) (xy 258.143632 -2.545974) (xy 258.223591 -2.57695)
			(xy 258.300351 -2.615172) (xy 258.373257 -2.660313) (xy 258.441686 -2.711989) (xy 258.505056 -2.769758)
			(xy 258.562825 -2.833128) (xy 258.614501 -2.901557) (xy 258.659642 -2.974463) (xy 258.697864 -3.051223)
			(xy 258.72884 -3.131182) (xy 258.752307 -3.213658) (xy 258.768063 -3.297948) (xy 258.775975 -3.383331)
			(xy 258.77647 -3.426206) (xy 258.775975 -3.469081) (xy 263.271241 -3.469081) (xy 263.271241 -3.383331)
			(xy 263.279153 -3.297948) (xy 263.294909 -3.213658) (xy 263.318376 -3.131182) (xy 263.349352 -3.051223)
			(xy 263.387574 -2.974463) (xy 263.432715 -2.901557) (xy 263.484391 -2.833128) (xy 263.54216 -2.769758)
			(xy 263.60553 -2.711989) (xy 263.673959 -2.660313) (xy 263.746865 -2.615172) (xy 263.823625 -2.57695)
			(xy 263.903584 -2.545974) (xy 263.98606 -2.522507) (xy 264.07035 -2.506751) (xy 264.155733 -2.498839)
			(xy 264.241483 -2.498839) (xy 264.326866 -2.506751) (xy 264.411156 -2.522507) (xy 264.493632 -2.545974)
			(xy 264.573591 -2.57695) (xy 264.650351 -2.615172) (xy 264.723257 -2.660313) (xy 264.791686 -2.711989)
			(xy 264.855056 -2.769758) (xy 264.912825 -2.833128) (xy 264.964501 -2.901557) (xy 265.009642 -2.974463)
			(xy 265.047864 -3.051223) (xy 265.07884 -3.131182) (xy 265.102307 -3.213658) (xy 265.118063 -3.297948)
			(xy 265.125975 -3.383331) (xy 265.12647 -3.426206) (xy 265.125975 -3.469081) (xy 324.845921 -3.469081)
			(xy 324.845921 -3.383331) (xy 324.853833 -3.297948) (xy 324.869589 -3.213658) (xy 324.893056 -3.131182)
			(xy 324.924032 -3.051223) (xy 324.962254 -2.974463) (xy 325.007395 -2.901557) (xy 325.059071 -2.833128)
			(xy 325.11684 -2.769758) (xy 325.18021 -2.711989) (xy 325.248639 -2.660313) (xy 325.321545 -2.615172)
			(xy 325.398305 -2.57695) (xy 325.478264 -2.545974) (xy 325.56074 -2.522507) (xy 325.64503 -2.506751)
			(xy 325.730413 -2.498839) (xy 325.816163 -2.498839) (xy 325.901546 -2.506751) (xy 325.985836 -2.522507)
			(xy 326.068312 -2.545974) (xy 326.148271 -2.57695) (xy 326.225031 -2.615172) (xy 326.297937 -2.660313)
			(xy 326.366366 -2.711989) (xy 326.429736 -2.769758) (xy 326.487505 -2.833128) (xy 326.539181 -2.901557)
			(xy 326.584322 -2.974463) (xy 326.622544 -3.051223) (xy 326.65352 -3.131182) (xy 326.676987 -3.213658)
			(xy 326.692743 -3.297948) (xy 326.700655 -3.383331) (xy 326.70115 -3.426206) (xy 326.700655 -3.469081)
			(xy 331.195921 -3.469081) (xy 331.195921 -3.383331) (xy 331.203833 -3.297948) (xy 331.219589 -3.213658)
			(xy 331.243056 -3.131182) (xy 331.274032 -3.051223) (xy 331.312254 -2.974463) (xy 331.357395 -2.901557)
			(xy 331.409071 -2.833128) (xy 331.46684 -2.769758) (xy 331.53021 -2.711989) (xy 331.598639 -2.660313)
			(xy 331.671545 -2.615172) (xy 331.748305 -2.57695) (xy 331.828264 -2.545974) (xy 331.91074 -2.522507)
			(xy 331.99503 -2.506751) (xy 332.080413 -2.498839) (xy 332.166163 -2.498839) (xy 332.251546 -2.506751)
			(xy 332.335836 -2.522507) (xy 332.418312 -2.545974) (xy 332.498271 -2.57695) (xy 332.575031 -2.615172)
			(xy 332.647937 -2.660313) (xy 332.716366 -2.711989) (xy 332.779736 -2.769758) (xy 332.837505 -2.833128)
			(xy 332.889181 -2.901557) (xy 332.934322 -2.974463) (xy 332.972544 -3.051223) (xy 333.00352 -3.131182)
			(xy 333.026987 -3.213658) (xy 333.042743 -3.297948) (xy 333.050655 -3.383331) (xy 333.05115 -3.426206)
			(xy 333.050655 -3.469081) (xy 335.488267 -3.469081) (xy 335.488267 -3.383331) (xy 335.496179 -3.297948)
			(xy 335.511935 -3.213658) (xy 335.535402 -3.131182) (xy 335.566378 -3.051223) (xy 335.6046 -2.974463)
			(xy 335.649741 -2.901557) (xy 335.701417 -2.833128) (xy 335.759186 -2.769758) (xy 335.822556 -2.711989)
			(xy 335.890985 -2.660313) (xy 335.963891 -2.615172) (xy 336.040651 -2.57695) (xy 336.12061 -2.545974)
			(xy 336.203086 -2.522507) (xy 336.287376 -2.506751) (xy 336.372759 -2.498839) (xy 336.458509 -2.498839)
			(xy 336.543892 -2.506751) (xy 336.628182 -2.522507) (xy 336.710658 -2.545974) (xy 336.790617 -2.57695)
			(xy 336.867377 -2.615172) (xy 336.940283 -2.660313) (xy 337.008712 -2.711989) (xy 337.072082 -2.769758)
			(xy 337.129851 -2.833128) (xy 337.181527 -2.901557) (xy 337.226668 -2.974463) (xy 337.26489 -3.051223)
			(xy 337.295866 -3.131182) (xy 337.319333 -3.213658) (xy 337.335089 -3.297948) (xy 337.343001 -3.383331)
			(xy 337.343496 -3.426206) (xy 337.343001 -3.469081) (xy 341.838267 -3.469081) (xy 341.838267 -3.383331)
			(xy 341.846179 -3.297948) (xy 341.861935 -3.213658) (xy 341.885402 -3.131182) (xy 341.916378 -3.051223)
			(xy 341.9546 -2.974463) (xy 341.999741 -2.901557) (xy 342.051417 -2.833128) (xy 342.109186 -2.769758)
			(xy 342.172556 -2.711989) (xy 342.240985 -2.660313) (xy 342.313891 -2.615172) (xy 342.390651 -2.57695)
			(xy 342.47061 -2.545974) (xy 342.553086 -2.522507) (xy 342.637376 -2.506751) (xy 342.722759 -2.498839)
			(xy 342.808509 -2.498839) (xy 342.893892 -2.506751) (xy 342.978182 -2.522507) (xy 343.060658 -2.545974)
			(xy 343.140617 -2.57695) (xy 343.217377 -2.615172) (xy 343.290283 -2.660313) (xy 343.358712 -2.711989)
			(xy 343.422082 -2.769758) (xy 343.479851 -2.833128) (xy 343.531527 -2.901557) (xy 343.576668 -2.974463)
			(xy 343.61489 -3.051223) (xy 343.645866 -3.131182) (xy 343.669333 -3.213658) (xy 343.685089 -3.297948)
			(xy 343.693001 -3.383331) (xy 343.693496 -3.426206) (xy 343.693001 -3.469081) (xy 373.705107 -3.469081)
			(xy 373.705107 -3.383331) (xy 373.713019 -3.297948) (xy 373.728775 -3.213658) (xy 373.752242 -3.131182)
			(xy 373.783218 -3.051223) (xy 373.82144 -2.974463) (xy 373.866581 -2.901557) (xy 373.918257 -2.833128)
			(xy 373.976026 -2.769758) (xy 374.039396 -2.711989) (xy 374.107825 -2.660313) (xy 374.180731 -2.615172)
			(xy 374.257491 -2.57695) (xy 374.33745 -2.545974) (xy 374.419926 -2.522507) (xy 374.504216 -2.506751)
			(xy 374.589599 -2.498839) (xy 374.675349 -2.498839) (xy 374.760732 -2.506751) (xy 374.845022 -2.522507)
			(xy 374.927498 -2.545974) (xy 375.007457 -2.57695) (xy 375.084217 -2.615172) (xy 375.157123 -2.660313)
			(xy 375.225552 -2.711989) (xy 375.288922 -2.769758) (xy 375.346691 -2.833128) (xy 375.398367 -2.901557)
			(xy 375.443508 -2.974463) (xy 375.48173 -3.051223) (xy 375.512706 -3.131182) (xy 375.536173 -3.213658)
			(xy 375.551929 -3.297948) (xy 375.559841 -3.383331) (xy 375.560336 -3.426206) (xy 375.559841 -3.469081)
			(xy 380.055107 -3.469081) (xy 380.055107 -3.383331) (xy 380.063019 -3.297948) (xy 380.078775 -3.213658)
			(xy 380.102242 -3.131182) (xy 380.133218 -3.051223) (xy 380.17144 -2.974463) (xy 380.216581 -2.901557)
			(xy 380.268257 -2.833128) (xy 380.326026 -2.769758) (xy 380.389396 -2.711989) (xy 380.457825 -2.660313)
			(xy 380.530731 -2.615172) (xy 380.607491 -2.57695) (xy 380.68745 -2.545974) (xy 380.769926 -2.522507)
			(xy 380.854216 -2.506751) (xy 380.939599 -2.498839) (xy 381.025349 -2.498839) (xy 381.110732 -2.506751)
			(xy 381.195022 -2.522507) (xy 381.277498 -2.545974) (xy 381.357457 -2.57695) (xy 381.434217 -2.615172)
			(xy 381.507123 -2.660313) (xy 381.575552 -2.711989) (xy 381.638922 -2.769758) (xy 381.696691 -2.833128)
			(xy 381.748367 -2.901557) (xy 381.793508 -2.974463) (xy 381.83173 -3.051223) (xy 381.862706 -3.131182)
			(xy 381.886173 -3.213658) (xy 381.901929 -3.297948) (xy 381.909841 -3.383331) (xy 381.910336 -3.426206)
			(xy 381.909841 -3.469081) (xy 381.901929 -3.554464) (xy 381.886173 -3.638754) (xy 381.862706 -3.72123)
			(xy 381.83173 -3.801189) (xy 381.793508 -3.877949) (xy 381.748367 -3.950855) (xy 381.696691 -4.019284)
			(xy 381.638922 -4.082654) (xy 381.575552 -4.140423) (xy 381.507123 -4.192099) (xy 381.434217 -4.23724)
			(xy 381.357457 -4.275462) (xy 381.277498 -4.306438) (xy 381.195022 -4.329905) (xy 381.110732 -4.345661)
			(xy 381.025349 -4.353573) (xy 380.939599 -4.353573) (xy 380.854216 -4.345661) (xy 380.769926 -4.329905)
			(xy 380.68745 -4.306438) (xy 380.607491 -4.275462) (xy 380.530731 -4.23724) (xy 380.457825 -4.192099)
			(xy 380.389396 -4.140423) (xy 380.326026 -4.082654) (xy 380.268257 -4.019284) (xy 380.216581 -3.950855)
			(xy 380.17144 -3.877949) (xy 380.133218 -3.801189) (xy 380.102242 -3.72123) (xy 380.078775 -3.638754)
			(xy 380.063019 -3.554464) (xy 380.055107 -3.469081) (xy 375.559841 -3.469081) (xy 375.551929 -3.554464)
			(xy 375.536173 -3.638754) (xy 375.512706 -3.72123) (xy 375.48173 -3.801189) (xy 375.443508 -3.877949)
			(xy 375.398367 -3.950855) (xy 375.346691 -4.019284) (xy 375.288922 -4.082654) (xy 375.225552 -4.140423)
			(xy 375.157123 -4.192099) (xy 375.084217 -4.23724) (xy 375.007457 -4.275462) (xy 374.927498 -4.306438)
			(xy 374.845022 -4.329905) (xy 374.760732 -4.345661) (xy 374.675349 -4.353573) (xy 374.589599 -4.353573)
			(xy 374.504216 -4.345661) (xy 374.419926 -4.329905) (xy 374.33745 -4.306438) (xy 374.257491 -4.275462)
			(xy 374.180731 -4.23724) (xy 374.107825 -4.192099) (xy 374.039396 -4.140423) (xy 373.976026 -4.082654)
			(xy 373.918257 -4.019284) (xy 373.866581 -3.950855) (xy 373.82144 -3.877949) (xy 373.783218 -3.801189)
			(xy 373.752242 -3.72123) (xy 373.728775 -3.638754) (xy 373.713019 -3.554464) (xy 373.705107 -3.469081)
			(xy 343.693001 -3.469081) (xy 343.685089 -3.554464) (xy 343.669333 -3.638754) (xy 343.645866 -3.72123)
			(xy 343.61489 -3.801189) (xy 343.576668 -3.877949) (xy 343.531527 -3.950855) (xy 343.479851 -4.019284)
			(xy 343.422082 -4.082654) (xy 343.358712 -4.140423) (xy 343.290283 -4.192099) (xy 343.217377 -4.23724)
			(xy 343.140617 -4.275462) (xy 343.060658 -4.306438) (xy 342.978182 -4.329905) (xy 342.893892 -4.345661)
			(xy 342.808509 -4.353573) (xy 342.722759 -4.353573) (xy 342.637376 -4.345661) (xy 342.553086 -4.329905)
			(xy 342.47061 -4.306438) (xy 342.390651 -4.275462) (xy 342.313891 -4.23724) (xy 342.240985 -4.192099)
			(xy 342.172556 -4.140423) (xy 342.109186 -4.082654) (xy 342.051417 -4.019284) (xy 341.999741 -3.950855)
			(xy 341.9546 -3.877949) (xy 341.916378 -3.801189) (xy 341.885402 -3.72123) (xy 341.861935 -3.638754)
			(xy 341.846179 -3.554464) (xy 341.838267 -3.469081) (xy 337.343001 -3.469081) (xy 337.335089 -3.554464)
			(xy 337.319333 -3.638754) (xy 337.295866 -3.72123) (xy 337.26489 -3.801189) (xy 337.226668 -3.877949)
			(xy 337.181527 -3.950855) (xy 337.129851 -4.019284) (xy 337.072082 -4.082654) (xy 337.008712 -4.140423)
			(xy 336.940283 -4.192099) (xy 336.867377 -4.23724) (xy 336.790617 -4.275462) (xy 336.710658 -4.306438)
			(xy 336.628182 -4.329905) (xy 336.543892 -4.345661) (xy 336.458509 -4.353573) (xy 336.372759 -4.353573)
			(xy 336.287376 -4.345661) (xy 336.203086 -4.329905) (xy 336.12061 -4.306438) (xy 336.040651 -4.275462)
			(xy 335.963891 -4.23724) (xy 335.890985 -4.192099) (xy 335.822556 -4.140423) (xy 335.759186 -4.082654)
			(xy 335.701417 -4.019284) (xy 335.649741 -3.950855) (xy 335.6046 -3.877949) (xy 335.566378 -3.801189)
			(xy 335.535402 -3.72123) (xy 335.511935 -3.638754) (xy 335.496179 -3.554464) (xy 335.488267 -3.469081)
			(xy 333.050655 -3.469081) (xy 333.042743 -3.554464) (xy 333.026987 -3.638754) (xy 333.00352 -3.72123)
			(xy 332.972544 -3.801189) (xy 332.934322 -3.877949) (xy 332.889181 -3.950855) (xy 332.837505 -4.019284)
			(xy 332.779736 -4.082654) (xy 332.716366 -4.140423) (xy 332.647937 -4.192099) (xy 332.575031 -4.23724)
			(xy 332.498271 -4.275462) (xy 332.418312 -4.306438) (xy 332.335836 -4.329905) (xy 332.251546 -4.345661)
			(xy 332.166163 -4.353573) (xy 332.080413 -4.353573) (xy 331.99503 -4.345661) (xy 331.91074 -4.329905)
			(xy 331.828264 -4.306438) (xy 331.748305 -4.275462) (xy 331.671545 -4.23724) (xy 331.598639 -4.192099)
			(xy 331.53021 -4.140423) (xy 331.46684 -4.082654) (xy 331.409071 -4.019284) (xy 331.357395 -3.950855)
			(xy 331.312254 -3.877949) (xy 331.274032 -3.801189) (xy 331.243056 -3.72123) (xy 331.219589 -3.638754)
			(xy 331.203833 -3.554464) (xy 331.195921 -3.469081) (xy 326.700655 -3.469081) (xy 326.692743 -3.554464)
			(xy 326.676987 -3.638754) (xy 326.65352 -3.72123) (xy 326.622544 -3.801189) (xy 326.584322 -3.877949)
			(xy 326.539181 -3.950855) (xy 326.487505 -4.019284) (xy 326.429736 -4.082654) (xy 326.366366 -4.140423)
			(xy 326.297937 -4.192099) (xy 326.225031 -4.23724) (xy 326.148271 -4.275462) (xy 326.068312 -4.306438)
			(xy 325.985836 -4.329905) (xy 325.901546 -4.345661) (xy 325.816163 -4.353573) (xy 325.730413 -4.353573)
			(xy 325.64503 -4.345661) (xy 325.56074 -4.329905) (xy 325.478264 -4.306438) (xy 325.398305 -4.275462)
			(xy 325.321545 -4.23724) (xy 325.248639 -4.192099) (xy 325.18021 -4.140423) (xy 325.11684 -4.082654)
			(xy 325.059071 -4.019284) (xy 325.007395 -3.950855) (xy 324.962254 -3.877949) (xy 324.924032 -3.801189)
			(xy 324.893056 -3.72123) (xy 324.869589 -3.638754) (xy 324.853833 -3.554464) (xy 324.845921 -3.469081)
			(xy 265.125975 -3.469081) (xy 265.118063 -3.554464) (xy 265.102307 -3.638754) (xy 265.07884 -3.72123)
			(xy 265.047864 -3.801189) (xy 265.009642 -3.877949) (xy 264.964501 -3.950855) (xy 264.912825 -4.019284)
			(xy 264.855056 -4.082654) (xy 264.791686 -4.140423) (xy 264.723257 -4.192099) (xy 264.650351 -4.23724)
			(xy 264.573591 -4.275462) (xy 264.493632 -4.306438) (xy 264.411156 -4.329905) (xy 264.326866 -4.345661)
			(xy 264.241483 -4.353573) (xy 264.155733 -4.353573) (xy 264.07035 -4.345661) (xy 263.98606 -4.329905)
			(xy 263.903584 -4.306438) (xy 263.823625 -4.275462) (xy 263.746865 -4.23724) (xy 263.673959 -4.192099)
			(xy 263.60553 -4.140423) (xy 263.54216 -4.082654) (xy 263.484391 -4.019284) (xy 263.432715 -3.950855)
			(xy 263.387574 -3.877949) (xy 263.349352 -3.801189) (xy 263.318376 -3.72123) (xy 263.294909 -3.638754)
			(xy 263.279153 -3.554464) (xy 263.271241 -3.469081) (xy 258.775975 -3.469081) (xy 258.768063 -3.554464)
			(xy 258.752307 -3.638754) (xy 258.72884 -3.72123) (xy 258.697864 -3.801189) (xy 258.659642 -3.877949)
			(xy 258.614501 -3.950855) (xy 258.562825 -4.019284) (xy 258.505056 -4.082654) (xy 258.441686 -4.140423)
			(xy 258.373257 -4.192099) (xy 258.300351 -4.23724) (xy 258.223591 -4.275462) (xy 258.143632 -4.306438)
			(xy 258.061156 -4.329905) (xy 257.976866 -4.345661) (xy 257.891483 -4.353573) (xy 257.805733 -4.353573)
			(xy 257.72035 -4.345661) (xy 257.63606 -4.329905) (xy 257.553584 -4.306438) (xy 257.473625 -4.275462)
			(xy 257.396865 -4.23724) (xy 257.323959 -4.192099) (xy 257.25553 -4.140423) (xy 257.19216 -4.082654)
			(xy 257.134391 -4.019284) (xy 257.082715 -3.950855) (xy 257.037574 -3.877949) (xy 256.999352 -3.801189)
			(xy 256.968376 -3.72123) (xy 256.944909 -3.638754) (xy 256.929153 -3.554464) (xy 256.921241 -3.469081)
			(xy 254.465119 -3.469081) (xy 254.465087 -3.471875) (xy 254.457175 -3.557258) (xy 254.441419 -3.641548)
			(xy 254.417952 -3.724024) (xy 254.386976 -3.803983) (xy 254.348754 -3.880743) (xy 254.303613 -3.953649)
			(xy 254.251937 -4.022078) (xy 254.194168 -4.085448) (xy 254.130798 -4.143217) (xy 254.062369 -4.194893)
			(xy 253.989463 -4.240034) (xy 253.912703 -4.278256) (xy 253.832744 -4.309232) (xy 253.750268 -4.332699)
			(xy 253.665978 -4.348455) (xy 253.580595 -4.356367) (xy 253.494845 -4.356367) (xy 253.409462 -4.348455)
			(xy 253.325172 -4.332699) (xy 253.242696 -4.309232) (xy 253.162737 -4.278256) (xy 253.085977 -4.240034)
			(xy 253.013071 -4.194893) (xy 252.944642 -4.143217) (xy 252.881272 -4.085448) (xy 252.823503 -4.022078)
			(xy 252.771827 -3.953649) (xy 252.726686 -3.880743) (xy 252.688464 -3.803983) (xy 252.657488 -3.724024)
			(xy 252.634021 -3.641548) (xy 252.618265 -3.557258) (xy 252.610353 -3.471875) (xy 248.115087 -3.471875)
			(xy 248.107175 -3.557258) (xy 248.091419 -3.641548) (xy 248.067952 -3.724024) (xy 248.036976 -3.803983)
			(xy 247.998754 -3.880743) (xy 247.953613 -3.953649) (xy 247.901937 -4.022078) (xy 247.844168 -4.085448)
			(xy 247.780798 -4.143217) (xy 247.712369 -4.194893) (xy 247.639463 -4.240034) (xy 247.562703 -4.278256)
			(xy 247.482744 -4.309232) (xy 247.400268 -4.332699) (xy 247.315978 -4.348455) (xy 247.230595 -4.356367)
			(xy 247.144845 -4.356367) (xy 247.059462 -4.348455) (xy 246.975172 -4.332699) (xy 246.892696 -4.309232)
			(xy 246.812737 -4.278256) (xy 246.735977 -4.240034) (xy 246.663071 -4.194893) (xy 246.594642 -4.143217)
			(xy 246.531272 -4.085448) (xy 246.473503 -4.022078) (xy 246.421827 -3.953649) (xy 246.376686 -3.880743)
			(xy 246.338464 -3.803983) (xy 246.307488 -3.724024) (xy 246.284021 -3.641548) (xy 246.268265 -3.557258)
			(xy 246.260353 -3.471875) (xy 216.248247 -3.471875) (xy 216.240335 -3.557258) (xy 216.224579 -3.641548)
			(xy 216.201112 -3.724024) (xy 216.170136 -3.803983) (xy 216.131914 -3.880743) (xy 216.086773 -3.953649)
			(xy 216.035097 -4.022078) (xy 215.977328 -4.085448) (xy 215.913958 -4.143217) (xy 215.845529 -4.194893)
			(xy 215.772623 -4.240034) (xy 215.695863 -4.278256) (xy 215.615904 -4.309232) (xy 215.533428 -4.332699)
			(xy 215.449138 -4.348455) (xy 215.363755 -4.356367) (xy 215.278005 -4.356367) (xy 215.192622 -4.348455)
			(xy 215.108332 -4.332699) (xy 215.025856 -4.309232) (xy 214.945897 -4.278256) (xy 214.869137 -4.240034)
			(xy 214.796231 -4.194893) (xy 214.727802 -4.143217) (xy 214.664432 -4.085448) (xy 214.606663 -4.022078)
			(xy 214.554987 -3.953649) (xy 214.509846 -3.880743) (xy 214.471624 -3.803983) (xy 214.440648 -3.724024)
			(xy 214.417181 -3.641548) (xy 214.401425 -3.557258) (xy 214.393513 -3.471875) (xy 209.898247 -3.471875)
			(xy 209.890335 -3.557258) (xy 209.874579 -3.641548) (xy 209.851112 -3.724024) (xy 209.820136 -3.803983)
			(xy 209.781914 -3.880743) (xy 209.736773 -3.953649) (xy 209.685097 -4.022078) (xy 209.627328 -4.085448)
			(xy 209.563958 -4.143217) (xy 209.495529 -4.194893) (xy 209.422623 -4.240034) (xy 209.345863 -4.278256)
			(xy 209.265904 -4.309232) (xy 209.183428 -4.332699) (xy 209.099138 -4.348455) (xy 209.013755 -4.356367)
			(xy 208.928005 -4.356367) (xy 208.842622 -4.348455) (xy 208.758332 -4.332699) (xy 208.675856 -4.309232)
			(xy 208.595897 -4.278256) (xy 208.519137 -4.240034) (xy 208.446231 -4.194893) (xy 208.377802 -4.143217)
			(xy 208.314432 -4.085448) (xy 208.256663 -4.022078) (xy 208.204987 -3.953649) (xy 208.159846 -3.880743)
			(xy 208.121624 -3.803983) (xy 208.090648 -3.724024) (xy 208.067181 -3.641548) (xy 208.051425 -3.557258)
			(xy 208.043513 -3.471875) (xy 197.075741 -3.471875) (xy 197.091928 -3.518134) (xy 197.13088 -3.653342)
			(xy 197.16219 -3.790521) (xy 197.185759 -3.929239) (xy 197.201513 -4.069061) (xy 197.209403 -4.209547)
			(xy 197.209918 -4.2799) (xy 197.209918 -6.011875) (xy 208.043513 -6.011875) (xy 208.043513 -5.926125)
			(xy 208.051425 -5.840742) (xy 208.067181 -5.756452) (xy 208.090648 -5.673976) (xy 208.121624 -5.594017)
			(xy 208.159846 -5.517257) (xy 208.204987 -5.444351) (xy 208.256663 -5.375922) (xy 208.314432 -5.312552)
			(xy 208.377802 -5.254783) (xy 208.446231 -5.203107) (xy 208.519137 -5.157966) (xy 208.595897 -5.119744)
			(xy 208.675856 -5.088768) (xy 208.758332 -5.065301) (xy 208.842622 -5.049545) (xy 208.928005 -5.041633)
			(xy 209.013755 -5.041633) (xy 209.099138 -5.049545) (xy 209.183428 -5.065301) (xy 209.265904 -5.088768)
			(xy 209.345863 -5.119744) (xy 209.422623 -5.157966) (xy 209.495529 -5.203107) (xy 209.551136 -5.2451)
			(xy 212.202268 -5.2451) (xy 212.202268 -4.14782) (xy 212.202781 -4.135749) (xy 212.210235 -4.112786)
			(xy 212.22442 -4.093251) (xy 212.243947 -4.079055) (xy 212.266905 -4.071588) (xy 212.278976 -4.071112)
			(xy 212.891116 -4.071112) (xy 212.899577 -4.07128) (xy 212.916112 -4.07487) (xy 212.923882 -4.078224)
			(xy 212.936838 -4.083876) (xy 212.964732 -4.088406) (xy 212.9928 -4.085119) (xy 213.018892 -4.074266)
			(xy 213.041012 -4.056678) (xy 213.049612 -4.045458) (xy 213.064996 -4.02458) (xy 213.100573 -3.986847)
			(xy 213.140936 -3.954285) (xy 213.185341 -3.927493) (xy 213.232966 -3.906967) (xy 213.282935 -3.893085)
			(xy 213.334323 -3.886104) (xy 213.360254 -3.885692) (xy 213.387509 -3.886266) (xy 213.441464 -3.894014)
			(xy 213.493769 -3.909358) (xy 213.543359 -3.931987) (xy 213.589226 -3.96144) (xy 213.630436 -3.997119)
			(xy 213.666152 -4.038297) (xy 213.695647 -4.084137) (xy 213.718321 -4.133706) (xy 213.733712 -4.185997)
			(xy 213.741509 -4.239946) (xy 213.742016 -4.2672) (xy 213.742016 -5.1308) (xy 213.741544 -5.158064)
			(xy 213.733781 -5.212037) (xy 213.718412 -5.264354) (xy 213.695752 -5.313951) (xy 213.666261 -5.359816)
			(xy 213.63054 -5.401015) (xy 213.589318 -5.436708) (xy 213.543434 -5.46617) (xy 213.493823 -5.488798)
			(xy 213.441496 -5.504133) (xy 213.387518 -5.511861) (xy 213.360254 -5.512308) (xy 213.33407 -5.511873)
			(xy 213.282195 -5.504698) (xy 213.231787 -5.490502) (xy 213.183791 -5.469553) (xy 213.139108 -5.442241)
			(xy 213.098576 -5.409081) (xy 213.062954 -5.370694) (xy 213.04758 -5.349494) (xy 213.039123 -5.338237)
			(xy 213.017257 -5.320514) (xy 212.991394 -5.309412) (xy 212.963484 -5.305767) (xy 212.935637 -5.309855)
			(xy 212.922612 -5.315204) (xy 212.915108 -5.318291) (xy 212.899228 -5.321617) (xy 212.891116 -5.321808)
			(xy 212.278976 -5.321808) (xy 212.2669 -5.321356) (xy 212.243932 -5.313887) (xy 212.224396 -5.299687)
			(xy 212.210202 -5.280146) (xy 212.20274 -5.257176) (xy 212.202268 -5.2451) (xy 209.551136 -5.2451)
			(xy 209.563958 -5.254783) (xy 209.627328 -5.312552) (xy 209.685097 -5.375922) (xy 209.736773 -5.444351)
			(xy 209.781914 -5.517257) (xy 209.820136 -5.594017) (xy 209.851112 -5.673976) (xy 209.874579 -5.756452)
			(xy 209.890335 -5.840742) (xy 209.898247 -5.926125) (xy 209.898742 -5.969) (xy 209.898247 -6.011875)
			(xy 214.393513 -6.011875) (xy 214.393513 -5.926125) (xy 214.401425 -5.840742) (xy 214.417181 -5.756452)
			(xy 214.440648 -5.673976) (xy 214.471624 -5.594017) (xy 214.509846 -5.517257) (xy 214.554987 -5.444351)
			(xy 214.606663 -5.375922) (xy 214.664432 -5.312552) (xy 214.727802 -5.254783) (xy 214.796231 -5.203107)
			(xy 214.869137 -5.157966) (xy 214.945897 -5.119744) (xy 215.025856 -5.088768) (xy 215.108332 -5.065301)
			(xy 215.192622 -5.049545) (xy 215.278005 -5.041633) (xy 215.363755 -5.041633) (xy 215.449138 -5.049545)
			(xy 215.533428 -5.065301) (xy 215.615904 -5.088768) (xy 215.695863 -5.119744) (xy 215.772623 -5.157966)
			(xy 215.845529 -5.203107) (xy 215.913958 -5.254783) (xy 215.977328 -5.312552) (xy 216.035097 -5.375922)
			(xy 216.086773 -5.444351) (xy 216.131914 -5.517257) (xy 216.170136 -5.594017) (xy 216.201112 -5.673976)
			(xy 216.224579 -5.756452) (xy 216.240335 -5.840742) (xy 216.248247 -5.926125) (xy 216.248742 -5.969)
			(xy 216.248247 -6.011875) (xy 246.260353 -6.011875) (xy 246.260353 -5.926125) (xy 246.268265 -5.840742)
			(xy 246.284021 -5.756452) (xy 246.307488 -5.673976) (xy 246.338464 -5.594017) (xy 246.376686 -5.517257)
			(xy 246.421827 -5.444351) (xy 246.473503 -5.375922) (xy 246.531272 -5.312552) (xy 246.594642 -5.254783)
			(xy 246.663071 -5.203107) (xy 246.735977 -5.157966) (xy 246.812737 -5.119744) (xy 246.892696 -5.088768)
			(xy 246.975172 -5.065301) (xy 247.059462 -5.049545) (xy 247.144845 -5.041633) (xy 247.230595 -5.041633)
			(xy 247.315978 -5.049545) (xy 247.400268 -5.065301) (xy 247.482744 -5.088768) (xy 247.562703 -5.119744)
			(xy 247.584906 -5.1308) (xy 248.766584 -5.1308) (xy 248.766584 -4.2672) (xy 248.767056 -4.239936)
			(xy 248.774819 -4.185963) (xy 248.790188 -4.133646) (xy 248.812848 -4.084049) (xy 248.842339 -4.038184)
			(xy 248.87806 -3.996985) (xy 248.919282 -3.961292) (xy 248.965166 -3.93183) (xy 249.014777 -3.909202)
			(xy 249.067104 -3.893867) (xy 249.121082 -3.886139) (xy 249.148346 -3.885692) (xy 249.17453 -3.886127)
			(xy 249.226405 -3.893302) (xy 249.276813 -3.907498) (xy 249.324809 -3.928447) (xy 249.369492 -3.955759)
			(xy 249.410024 -3.988919) (xy 249.445646 -4.027306) (xy 249.46102 -4.048506) (xy 249.469477 -4.059763)
			(xy 249.491343 -4.077486) (xy 249.517206 -4.088588) (xy 249.545116 -4.092233) (xy 249.572963 -4.088145)
			(xy 249.585988 -4.082796) (xy 249.593492 -4.079709) (xy 249.609372 -4.076383) (xy 249.617484 -4.076192)
			(xy 250.229624 -4.076192) (xy 250.2417 -4.076644) (xy 250.264668 -4.084113) (xy 250.284204 -4.098313)
			(xy 250.298398 -4.117854) (xy 250.30586 -4.140824) (xy 250.306332 -4.1529) (xy 250.306332 -5.25018)
			(xy 250.305819 -5.262251) (xy 250.298365 -5.285214) (xy 250.28418 -5.304749) (xy 250.264653 -5.318945)
			(xy 250.241695 -5.326412) (xy 250.229624 -5.326888) (xy 249.617484 -5.326888) (xy 249.609023 -5.32672)
			(xy 249.592488 -5.32313) (xy 249.584718 -5.319776) (xy 249.571762 -5.314124) (xy 249.543868 -5.309594)
			(xy 249.5158 -5.312881) (xy 249.489708 -5.323734) (xy 249.467588 -5.341322) (xy 249.458988 -5.352542)
			(xy 249.443604 -5.37342) (xy 249.408027 -5.411153) (xy 249.367664 -5.443715) (xy 249.323259 -5.470507)
			(xy 249.275634 -5.491033) (xy 249.225665 -5.504915) (xy 249.174277 -5.511896) (xy 249.148346 -5.512308)
			(xy 249.121091 -5.511734) (xy 249.067136 -5.503986) (xy 249.014831 -5.488642) (xy 248.965241 -5.466013)
			(xy 248.919374 -5.43656) (xy 248.878164 -5.400881) (xy 248.842448 -5.359703) (xy 248.812953 -5.313863)
			(xy 248.790279 -5.264294) (xy 248.774888 -5.212003) (xy 248.767091 -5.158054) (xy 248.766584 -5.1308)
			(xy 247.584906 -5.1308) (xy 247.639463 -5.157966) (xy 247.712369 -5.203107) (xy 247.780798 -5.254783)
			(xy 247.844168 -5.312552) (xy 247.901937 -5.375922) (xy 247.953613 -5.444351) (xy 247.998754 -5.517257)
			(xy 248.036976 -5.594017) (xy 248.067952 -5.673976) (xy 248.091419 -5.756452) (xy 248.107175 -5.840742)
			(xy 248.115087 -5.926125) (xy 248.115582 -5.969) (xy 248.115087 -6.011875) (xy 252.610353 -6.011875)
			(xy 252.610353 -5.926125) (xy 252.618265 -5.840742) (xy 252.634021 -5.756452) (xy 252.657488 -5.673976)
			(xy 252.688464 -5.594017) (xy 252.726686 -5.517257) (xy 252.771827 -5.444351) (xy 252.823503 -5.375922)
			(xy 252.881272 -5.312552) (xy 252.944642 -5.254783) (xy 253.013071 -5.203107) (xy 253.085977 -5.157966)
			(xy 253.162737 -5.119744) (xy 253.242696 -5.088768) (xy 253.325172 -5.065301) (xy 253.409462 -5.049545)
			(xy 253.494845 -5.041633) (xy 253.580595 -5.041633) (xy 253.665978 -5.049545) (xy 253.750268 -5.065301)
			(xy 253.832744 -5.088768) (xy 253.912703 -5.119744) (xy 253.989463 -5.157966) (xy 254.062369 -5.203107)
			(xy 254.130798 -5.254783) (xy 254.194168 -5.312552) (xy 254.251937 -5.375922) (xy 254.303613 -5.444351)
			(xy 254.348754 -5.517257) (xy 254.386976 -5.594017) (xy 254.417952 -5.673976) (xy 254.441419 -5.756452)
			(xy 254.457175 -5.840742) (xy 254.465087 -5.926125) (xy 254.465582 -5.969) (xy 254.465119 -6.009081)
			(xy 256.921241 -6.009081) (xy 256.921241 -5.923331) (xy 256.929153 -5.837948) (xy 256.944909 -5.753658)
			(xy 256.968376 -5.671182) (xy 256.999352 -5.591223) (xy 257.037574 -5.514463) (xy 257.082715 -5.441557)
			(xy 257.134391 -5.373128) (xy 257.19216 -5.309758) (xy 257.25553 -5.251989) (xy 257.323959 -5.200313)
			(xy 257.396865 -5.155172) (xy 257.473625 -5.11695) (xy 257.553584 -5.085974) (xy 257.63606 -5.062507)
			(xy 257.72035 -5.046751) (xy 257.805733 -5.038839) (xy 257.891483 -5.038839) (xy 257.976866 -5.046751)
			(xy 258.061156 -5.062507) (xy 258.143632 -5.085974) (xy 258.223591 -5.11695) (xy 258.300351 -5.155172)
			(xy 258.373257 -5.200313) (xy 258.428864 -5.242306) (xy 261.079996 -5.242306) (xy 261.079996 -4.145026)
			(xy 261.080529 -4.132942) (xy 261.087973 -4.10995) (xy 261.102144 -4.090373) (xy 261.121661 -4.07612)
			(xy 261.144622 -4.06858) (xy 261.156704 -4.068064) (xy 261.768844 -4.068064) (xy 261.780952 -4.068478)
			(xy 261.803974 -4.075986) (xy 261.823543 -4.090249) (xy 261.837738 -4.109868) (xy 261.845164 -4.132917)
			(xy 261.845552 -4.145026) (xy 261.845552 -5.242306) (xy 261.845097 -5.254397) (xy 261.837638 -5.277399)
			(xy 261.823449 -5.296979) (xy 261.803912 -5.311229) (xy 261.780933 -5.31876) (xy 261.768844 -5.319268)
			(xy 261.156704 -5.319268) (xy 261.144592 -5.31888) (xy 261.121559 -5.311378) (xy 261.101983 -5.29711)
			(xy 261.08779 -5.27748) (xy 261.080375 -5.254419) (xy 261.079996 -5.242306) (xy 258.428864 -5.242306)
			(xy 258.441686 -5.251989) (xy 258.505056 -5.309758) (xy 258.562825 -5.373128) (xy 258.614501 -5.441557)
			(xy 258.659642 -5.514463) (xy 258.697864 -5.591223) (xy 258.72884 -5.671182) (xy 258.752307 -5.753658)
			(xy 258.768063 -5.837948) (xy 258.775975 -5.923331) (xy 258.77647 -5.966206) (xy 258.775975 -6.009081)
			(xy 263.271241 -6.009081) (xy 263.271241 -5.923331) (xy 263.279153 -5.837948) (xy 263.294909 -5.753658)
			(xy 263.318376 -5.671182) (xy 263.349352 -5.591223) (xy 263.387574 -5.514463) (xy 263.432715 -5.441557)
			(xy 263.484391 -5.373128) (xy 263.54216 -5.309758) (xy 263.60553 -5.251989) (xy 263.673959 -5.200313)
			(xy 263.746865 -5.155172) (xy 263.823625 -5.11695) (xy 263.903584 -5.085974) (xy 263.98606 -5.062507)
			(xy 264.07035 -5.046751) (xy 264.155733 -5.038839) (xy 264.241483 -5.038839) (xy 264.326866 -5.046751)
			(xy 264.411156 -5.062507) (xy 264.493632 -5.085974) (xy 264.573591 -5.11695) (xy 264.650351 -5.155172)
			(xy 264.723257 -5.200313) (xy 264.791686 -5.251989) (xy 264.855056 -5.309758) (xy 264.912825 -5.373128)
			(xy 264.964501 -5.441557) (xy 265.009642 -5.514463) (xy 265.047864 -5.591223) (xy 265.07884 -5.671182)
			(xy 265.102307 -5.753658) (xy 265.118063 -5.837948) (xy 265.125975 -5.923331) (xy 265.12647 -5.966206)
			(xy 265.125975 -6.009081) (xy 324.845921 -6.009081) (xy 324.845921 -5.923331) (xy 324.853833 -5.837948)
			(xy 324.869589 -5.753658) (xy 324.893056 -5.671182) (xy 324.924032 -5.591223) (xy 324.962254 -5.514463)
			(xy 325.007395 -5.441557) (xy 325.059071 -5.373128) (xy 325.11684 -5.309758) (xy 325.18021 -5.251989)
			(xy 325.248639 -5.200313) (xy 325.321545 -5.155172) (xy 325.398305 -5.11695) (xy 325.478264 -5.085974)
			(xy 325.56074 -5.062507) (xy 325.64503 -5.046751) (xy 325.730413 -5.038839) (xy 325.816163 -5.038839)
			(xy 325.901546 -5.046751) (xy 325.985836 -5.062507) (xy 326.068312 -5.085974) (xy 326.148271 -5.11695)
			(xy 326.225031 -5.155172) (xy 326.297937 -5.200313) (xy 326.360271 -5.247386) (xy 328.126344 -5.247386)
			(xy 328.126344 -4.150106) (xy 328.126813 -4.138016) (xy 328.134268 -4.115015) (xy 328.148454 -4.095435)
			(xy 328.167988 -4.081184) (xy 328.190964 -4.073653) (xy 328.203052 -4.073144) (xy 328.815192 -4.073144)
			(xy 328.827295 -4.073622) (xy 328.850312 -4.081113) (xy 328.869881 -4.09536) (xy 328.884078 -4.114965)
			(xy 328.891509 -4.138002) (xy 328.8919 -4.150106) (xy 328.8919 -5.247386) (xy 328.891381 -5.259471)
			(xy 328.883933 -5.282464) (xy 328.869759 -5.302041) (xy 328.850238 -5.316293) (xy 328.827275 -5.323833)
			(xy 328.815192 -5.324348) (xy 328.203052 -5.324348) (xy 328.190945 -5.323925) (xy 328.167925 -5.316418)
			(xy 328.148357 -5.302157) (xy 328.134162 -5.28254) (xy 328.126734 -5.259494) (xy 328.126344 -5.247386)
			(xy 326.360271 -5.247386) (xy 326.366366 -5.251989) (xy 326.429736 -5.309758) (xy 326.487505 -5.373128)
			(xy 326.539181 -5.441557) (xy 326.584322 -5.514463) (xy 326.622544 -5.591223) (xy 326.65352 -5.671182)
			(xy 326.676987 -5.753658) (xy 326.692743 -5.837948) (xy 326.700655 -5.923331) (xy 326.70115 -5.966206)
			(xy 326.700655 -6.009081) (xy 331.195921 -6.009081) (xy 331.195921 -5.923331) (xy 331.203833 -5.837948)
			(xy 331.219589 -5.753658) (xy 331.243056 -5.671182) (xy 331.274032 -5.591223) (xy 331.312254 -5.514463)
			(xy 331.357395 -5.441557) (xy 331.409071 -5.373128) (xy 331.46684 -5.309758) (xy 331.53021 -5.251989)
			(xy 331.598639 -5.200313) (xy 331.671545 -5.155172) (xy 331.748305 -5.11695) (xy 331.828264 -5.085974)
			(xy 331.91074 -5.062507) (xy 331.99503 -5.046751) (xy 332.080413 -5.038839) (xy 332.166163 -5.038839)
			(xy 332.251546 -5.046751) (xy 332.335836 -5.062507) (xy 332.418312 -5.085974) (xy 332.498271 -5.11695)
			(xy 332.575031 -5.155172) (xy 332.647937 -5.200313) (xy 332.716366 -5.251989) (xy 332.779736 -5.309758)
			(xy 332.837505 -5.373128) (xy 332.889181 -5.441557) (xy 332.934322 -5.514463) (xy 332.972544 -5.591223)
			(xy 333.00352 -5.671182) (xy 333.026987 -5.753658) (xy 333.042743 -5.837948) (xy 333.050655 -5.923331)
			(xy 333.05115 -5.966206) (xy 333.050655 -6.009081) (xy 335.488267 -6.009081) (xy 335.488267 -5.923331)
			(xy 335.496179 -5.837948) (xy 335.511935 -5.753658) (xy 335.535402 -5.671182) (xy 335.566378 -5.591223)
			(xy 335.6046 -5.514463) (xy 335.649741 -5.441557) (xy 335.701417 -5.373128) (xy 335.759186 -5.309758)
			(xy 335.822556 -5.251989) (xy 335.890985 -5.200313) (xy 335.963891 -5.155172) (xy 336.040651 -5.11695)
			(xy 336.12061 -5.085974) (xy 336.203086 -5.062507) (xy 336.287376 -5.046751) (xy 336.372759 -5.038839)
			(xy 336.458509 -5.038839) (xy 336.543892 -5.046751) (xy 336.628182 -5.062507) (xy 336.710658 -5.085974)
			(xy 336.790617 -5.11695) (xy 336.867377 -5.155172) (xy 336.940283 -5.200313) (xy 336.99589 -5.242306)
			(xy 339.646768 -5.242306) (xy 339.646768 -4.145026) (xy 339.647183 -4.132902) (xy 339.654671 -4.109839)
			(xy 339.668923 -4.09022) (xy 339.688542 -4.075969) (xy 339.711606 -4.068482) (xy 339.72373 -4.068064)
			(xy 340.33587 -4.068064) (xy 340.347994 -4.068486) (xy 340.371056 -4.075973) (xy 340.390674 -4.090223)
			(xy 340.404925 -4.10984) (xy 340.412414 -4.132902) (xy 340.412832 -4.145026) (xy 340.412832 -5.242306)
			(xy 340.412445 -5.254432) (xy 340.404947 -5.277496) (xy 340.390688 -5.297114) (xy 340.371064 -5.311363)
			(xy 340.347996 -5.31885) (xy 340.33587 -5.319268) (xy 339.72373 -5.319268) (xy 339.711609 -5.318815)
			(xy 339.688553 -5.311331) (xy 339.668937 -5.297088) (xy 339.654685 -5.27748) (xy 339.647191 -5.254426)
			(xy 339.646768 -5.242306) (xy 336.99589 -5.242306) (xy 337.008712 -5.251989) (xy 337.072082 -5.309758)
			(xy 337.129851 -5.373128) (xy 337.181527 -5.441557) (xy 337.226668 -5.514463) (xy 337.26489 -5.591223)
			(xy 337.295866 -5.671182) (xy 337.319333 -5.753658) (xy 337.335089 -5.837948) (xy 337.343001 -5.923331)
			(xy 337.343496 -5.966206) (xy 337.343001 -6.009081) (xy 341.838267 -6.009081) (xy 341.838267 -5.923331)
			(xy 341.846179 -5.837948) (xy 341.861935 -5.753658) (xy 341.885402 -5.671182) (xy 341.916378 -5.591223)
			(xy 341.9546 -5.514463) (xy 341.999741 -5.441557) (xy 342.051417 -5.373128) (xy 342.109186 -5.309758)
			(xy 342.172556 -5.251989) (xy 342.240985 -5.200313) (xy 342.313891 -5.155172) (xy 342.390651 -5.11695)
			(xy 342.47061 -5.085974) (xy 342.553086 -5.062507) (xy 342.637376 -5.046751) (xy 342.722759 -5.038839)
			(xy 342.808509 -5.038839) (xy 342.893892 -5.046751) (xy 342.978182 -5.062507) (xy 343.060658 -5.085974)
			(xy 343.140617 -5.11695) (xy 343.217377 -5.155172) (xy 343.290283 -5.200313) (xy 343.358712 -5.251989)
			(xy 343.422082 -5.309758) (xy 343.479851 -5.373128) (xy 343.531527 -5.441557) (xy 343.576668 -5.514463)
			(xy 343.61489 -5.591223) (xy 343.645866 -5.671182) (xy 343.669333 -5.753658) (xy 343.685089 -5.837948)
			(xy 343.693001 -5.923331) (xy 343.693496 -5.966206) (xy 343.693001 -6.009081) (xy 373.705107 -6.009081)
			(xy 373.705107 -5.923331) (xy 373.713019 -5.837948) (xy 373.728775 -5.753658) (xy 373.752242 -5.671182)
			(xy 373.783218 -5.591223) (xy 373.82144 -5.514463) (xy 373.866581 -5.441557) (xy 373.918257 -5.373128)
			(xy 373.976026 -5.309758) (xy 374.039396 -5.251989) (xy 374.107825 -5.200313) (xy 374.180731 -5.155172)
			(xy 374.257491 -5.11695) (xy 374.33745 -5.085974) (xy 374.419926 -5.062507) (xy 374.504216 -5.046751)
			(xy 374.589599 -5.038839) (xy 374.675349 -5.038839) (xy 374.760732 -5.046751) (xy 374.845022 -5.062507)
			(xy 374.927498 -5.085974) (xy 375.007457 -5.11695) (xy 375.084217 -5.155172) (xy 375.157123 -5.200313)
			(xy 375.219457 -5.247386) (xy 376.985276 -5.247386) (xy 376.985276 -4.150106) (xy 376.985666 -4.13798)
			(xy 376.993161 -4.114915) (xy 377.007419 -4.095296) (xy 377.027043 -4.081046) (xy 377.050112 -4.073561)
			(xy 377.062238 -4.073144) (xy 377.674378 -4.073144) (xy 377.6865 -4.073579) (xy 377.709559 -4.081066)
			(xy 377.729175 -4.095313) (xy 377.743427 -4.114926) (xy 377.750919 -4.137984) (xy 377.75134 -4.150106)
			(xy 377.75134 -5.247386) (xy 377.750928 -5.25951) (xy 377.743437 -5.282572) (xy 377.729184 -5.302189)
			(xy 377.709565 -5.31644) (xy 377.686502 -5.323929) (xy 377.674378 -5.324348) (xy 377.062238 -5.324348)
			(xy 377.050116 -5.323908) (xy 377.027056 -5.316424) (xy 377.007439 -5.302178) (xy 376.993187 -5.282566)
			(xy 376.985696 -5.259508) (xy 376.985276 -5.247386) (xy 375.219457 -5.247386) (xy 375.225552 -5.251989)
			(xy 375.288922 -5.309758) (xy 375.346691 -5.373128) (xy 375.398367 -5.441557) (xy 375.443508 -5.514463)
			(xy 375.48173 -5.591223) (xy 375.512706 -5.671182) (xy 375.536173 -5.753658) (xy 375.551929 -5.837948)
			(xy 375.559841 -5.923331) (xy 375.560336 -5.966206) (xy 375.559841 -6.009081) (xy 380.055107 -6.009081)
			(xy 380.055107 -5.923331) (xy 380.063019 -5.837948) (xy 380.078775 -5.753658) (xy 380.102242 -5.671182)
			(xy 380.133218 -5.591223) (xy 380.17144 -5.514463) (xy 380.216581 -5.441557) (xy 380.268257 -5.373128)
			(xy 380.326026 -5.309758) (xy 380.389396 -5.251989) (xy 380.457825 -5.200313) (xy 380.530731 -5.155172)
			(xy 380.607491 -5.11695) (xy 380.68745 -5.085974) (xy 380.769926 -5.062507) (xy 380.854216 -5.046751)
			(xy 380.939599 -5.038839) (xy 381.025349 -5.038839) (xy 381.110732 -5.046751) (xy 381.195022 -5.062507)
			(xy 381.277498 -5.085974) (xy 381.357457 -5.11695) (xy 381.434217 -5.155172) (xy 381.507123 -5.200313)
			(xy 381.575552 -5.251989) (xy 381.638922 -5.309758) (xy 381.696691 -5.373128) (xy 381.748367 -5.441557)
			(xy 381.793508 -5.514463) (xy 381.83173 -5.591223) (xy 381.862706 -5.671182) (xy 381.886173 -5.753658)
			(xy 381.901929 -5.837948) (xy 381.909841 -5.923331) (xy 381.910336 -5.966206) (xy 381.909841 -6.009081)
			(xy 381.901929 -6.094464) (xy 381.886173 -6.178754) (xy 381.862706 -6.26123) (xy 381.83173 -6.341189)
			(xy 381.793508 -6.417949) (xy 381.748367 -6.490855) (xy 381.696691 -6.559284) (xy 381.638922 -6.622654)
			(xy 381.575552 -6.680423) (xy 381.507123 -6.732099) (xy 381.434217 -6.77724) (xy 381.357457 -6.815462)
			(xy 381.277498 -6.846438) (xy 381.195022 -6.869905) (xy 381.110732 -6.885661) (xy 381.025349 -6.893573)
			(xy 380.939599 -6.893573) (xy 380.854216 -6.885661) (xy 380.769926 -6.869905) (xy 380.68745 -6.846438)
			(xy 380.607491 -6.815462) (xy 380.530731 -6.77724) (xy 380.457825 -6.732099) (xy 380.389396 -6.680423)
			(xy 380.326026 -6.622654) (xy 380.268257 -6.559284) (xy 380.216581 -6.490855) (xy 380.17144 -6.417949)
			(xy 380.133218 -6.341189) (xy 380.102242 -6.26123) (xy 380.078775 -6.178754) (xy 380.063019 -6.094464)
			(xy 380.055107 -6.009081) (xy 375.559841 -6.009081) (xy 375.551929 -6.094464) (xy 375.536173 -6.178754)
			(xy 375.512706 -6.26123) (xy 375.48173 -6.341189) (xy 375.443508 -6.417949) (xy 375.398367 -6.490855)
			(xy 375.346691 -6.559284) (xy 375.288922 -6.622654) (xy 375.225552 -6.680423) (xy 375.157123 -6.732099)
			(xy 375.084217 -6.77724) (xy 375.007457 -6.815462) (xy 374.927498 -6.846438) (xy 374.845022 -6.869905)
			(xy 374.760732 -6.885661) (xy 374.675349 -6.893573) (xy 374.589599 -6.893573) (xy 374.504216 -6.885661)
			(xy 374.419926 -6.869905) (xy 374.33745 -6.846438) (xy 374.257491 -6.815462) (xy 374.180731 -6.77724)
			(xy 374.107825 -6.732099) (xy 374.039396 -6.680423) (xy 373.976026 -6.622654) (xy 373.918257 -6.559284)
			(xy 373.866581 -6.490855) (xy 373.82144 -6.417949) (xy 373.783218 -6.341189) (xy 373.752242 -6.26123)
			(xy 373.728775 -6.178754) (xy 373.713019 -6.094464) (xy 373.705107 -6.009081) (xy 343.693001 -6.009081)
			(xy 343.685089 -6.094464) (xy 343.669333 -6.178754) (xy 343.645866 -6.26123) (xy 343.61489 -6.341189)
			(xy 343.576668 -6.417949) (xy 343.531527 -6.490855) (xy 343.479851 -6.559284) (xy 343.422082 -6.622654)
			(xy 343.358712 -6.680423) (xy 343.290283 -6.732099) (xy 343.217377 -6.77724) (xy 343.140617 -6.815462)
			(xy 343.060658 -6.846438) (xy 342.978182 -6.869905) (xy 342.893892 -6.885661) (xy 342.808509 -6.893573)
			(xy 342.722759 -6.893573) (xy 342.637376 -6.885661) (xy 342.553086 -6.869905) (xy 342.47061 -6.846438)
			(xy 342.390651 -6.815462) (xy 342.313891 -6.77724) (xy 342.240985 -6.732099) (xy 342.172556 -6.680423)
			(xy 342.109186 -6.622654) (xy 342.051417 -6.559284) (xy 341.999741 -6.490855) (xy 341.9546 -6.417949)
			(xy 341.916378 -6.341189) (xy 341.885402 -6.26123) (xy 341.861935 -6.178754) (xy 341.846179 -6.094464)
			(xy 341.838267 -6.009081) (xy 337.343001 -6.009081) (xy 337.335089 -6.094464) (xy 337.319333 -6.178754)
			(xy 337.295866 -6.26123) (xy 337.26489 -6.341189) (xy 337.226668 -6.417949) (xy 337.181527 -6.490855)
			(xy 337.129851 -6.559284) (xy 337.072082 -6.622654) (xy 337.008712 -6.680423) (xy 336.940283 -6.732099)
			(xy 336.867377 -6.77724) (xy 336.790617 -6.815462) (xy 336.710658 -6.846438) (xy 336.628182 -6.869905)
			(xy 336.543892 -6.885661) (xy 336.458509 -6.893573) (xy 336.372759 -6.893573) (xy 336.287376 -6.885661)
			(xy 336.203086 -6.869905) (xy 336.12061 -6.846438) (xy 336.040651 -6.815462) (xy 335.963891 -6.77724)
			(xy 335.890985 -6.732099) (xy 335.822556 -6.680423) (xy 335.759186 -6.622654) (xy 335.701417 -6.559284)
			(xy 335.649741 -6.490855) (xy 335.6046 -6.417949) (xy 335.566378 -6.341189) (xy 335.535402 -6.26123)
			(xy 335.511935 -6.178754) (xy 335.496179 -6.094464) (xy 335.488267 -6.009081) (xy 333.050655 -6.009081)
			(xy 333.042743 -6.094464) (xy 333.026987 -6.178754) (xy 333.00352 -6.26123) (xy 332.972544 -6.341189)
			(xy 332.934322 -6.417949) (xy 332.889181 -6.490855) (xy 332.837505 -6.559284) (xy 332.779736 -6.622654)
			(xy 332.716366 -6.680423) (xy 332.647937 -6.732099) (xy 332.575031 -6.77724) (xy 332.498271 -6.815462)
			(xy 332.418312 -6.846438) (xy 332.335836 -6.869905) (xy 332.251546 -6.885661) (xy 332.166163 -6.893573)
			(xy 332.080413 -6.893573) (xy 331.99503 -6.885661) (xy 331.91074 -6.869905) (xy 331.828264 -6.846438)
			(xy 331.748305 -6.815462) (xy 331.671545 -6.77724) (xy 331.598639 -6.732099) (xy 331.53021 -6.680423)
			(xy 331.46684 -6.622654) (xy 331.409071 -6.559284) (xy 331.357395 -6.490855) (xy 331.312254 -6.417949)
			(xy 331.274032 -6.341189) (xy 331.243056 -6.26123) (xy 331.219589 -6.178754) (xy 331.203833 -6.094464)
			(xy 331.195921 -6.009081) (xy 326.700655 -6.009081) (xy 326.692743 -6.094464) (xy 326.676987 -6.178754)
			(xy 326.65352 -6.26123) (xy 326.622544 -6.341189) (xy 326.584322 -6.417949) (xy 326.539181 -6.490855)
			(xy 326.487505 -6.559284) (xy 326.429736 -6.622654) (xy 326.366366 -6.680423) (xy 326.297937 -6.732099)
			(xy 326.225031 -6.77724) (xy 326.148271 -6.815462) (xy 326.068312 -6.846438) (xy 325.985836 -6.869905)
			(xy 325.901546 -6.885661) (xy 325.816163 -6.893573) (xy 325.730413 -6.893573) (xy 325.64503 -6.885661)
			(xy 325.56074 -6.869905) (xy 325.478264 -6.846438) (xy 325.398305 -6.815462) (xy 325.321545 -6.77724)
			(xy 325.248639 -6.732099) (xy 325.18021 -6.680423) (xy 325.11684 -6.622654) (xy 325.059071 -6.559284)
			(xy 325.007395 -6.490855) (xy 324.962254 -6.417949) (xy 324.924032 -6.341189) (xy 324.893056 -6.26123)
			(xy 324.869589 -6.178754) (xy 324.853833 -6.094464) (xy 324.845921 -6.009081) (xy 265.125975 -6.009081)
			(xy 265.118063 -6.094464) (xy 265.102307 -6.178754) (xy 265.07884 -6.26123) (xy 265.047864 -6.341189)
			(xy 265.009642 -6.417949) (xy 264.964501 -6.490855) (xy 264.912825 -6.559284) (xy 264.855056 -6.622654)
			(xy 264.791686 -6.680423) (xy 264.723257 -6.732099) (xy 264.650351 -6.77724) (xy 264.573591 -6.815462)
			(xy 264.493632 -6.846438) (xy 264.411156 -6.869905) (xy 264.326866 -6.885661) (xy 264.241483 -6.893573)
			(xy 264.155733 -6.893573) (xy 264.07035 -6.885661) (xy 263.98606 -6.869905) (xy 263.903584 -6.846438)
			(xy 263.823625 -6.815462) (xy 263.746865 -6.77724) (xy 263.673959 -6.732099) (xy 263.60553 -6.680423)
			(xy 263.54216 -6.622654) (xy 263.484391 -6.559284) (xy 263.432715 -6.490855) (xy 263.387574 -6.417949)
			(xy 263.349352 -6.341189) (xy 263.318376 -6.26123) (xy 263.294909 -6.178754) (xy 263.279153 -6.094464)
			(xy 263.271241 -6.009081) (xy 258.775975 -6.009081) (xy 258.768063 -6.094464) (xy 258.752307 -6.178754)
			(xy 258.72884 -6.26123) (xy 258.697864 -6.341189) (xy 258.659642 -6.417949) (xy 258.614501 -6.490855)
			(xy 258.562825 -6.559284) (xy 258.505056 -6.622654) (xy 258.441686 -6.680423) (xy 258.373257 -6.732099)
			(xy 258.300351 -6.77724) (xy 258.223591 -6.815462) (xy 258.143632 -6.846438) (xy 258.061156 -6.869905)
			(xy 257.976866 -6.885661) (xy 257.891483 -6.893573) (xy 257.805733 -6.893573) (xy 257.72035 -6.885661)
			(xy 257.63606 -6.869905) (xy 257.553584 -6.846438) (xy 257.473625 -6.815462) (xy 257.396865 -6.77724)
			(xy 257.323959 -6.732099) (xy 257.25553 -6.680423) (xy 257.19216 -6.622654) (xy 257.134391 -6.559284)
			(xy 257.082715 -6.490855) (xy 257.037574 -6.417949) (xy 256.999352 -6.341189) (xy 256.968376 -6.26123)
			(xy 256.944909 -6.178754) (xy 256.929153 -6.094464) (xy 256.921241 -6.009081) (xy 254.465119 -6.009081)
			(xy 254.465087 -6.011875) (xy 254.457175 -6.097258) (xy 254.441419 -6.181548) (xy 254.417952 -6.264024)
			(xy 254.386976 -6.343983) (xy 254.348754 -6.420743) (xy 254.303613 -6.493649) (xy 254.251937 -6.562078)
			(xy 254.194168 -6.625448) (xy 254.130798 -6.683217) (xy 254.062369 -6.734893) (xy 253.989463 -6.780034)
			(xy 253.912703 -6.818256) (xy 253.832744 -6.849232) (xy 253.750268 -6.872699) (xy 253.665978 -6.888455)
			(xy 253.580595 -6.896367) (xy 253.494845 -6.896367) (xy 253.409462 -6.888455) (xy 253.325172 -6.872699)
			(xy 253.242696 -6.849232) (xy 253.162737 -6.818256) (xy 253.085977 -6.780034) (xy 253.013071 -6.734893)
			(xy 252.944642 -6.683217) (xy 252.881272 -6.625448) (xy 252.823503 -6.562078) (xy 252.771827 -6.493649)
			(xy 252.726686 -6.420743) (xy 252.688464 -6.343983) (xy 252.657488 -6.264024) (xy 252.634021 -6.181548)
			(xy 252.618265 -6.097258) (xy 252.610353 -6.011875) (xy 248.115087 -6.011875) (xy 248.107175 -6.097258)
			(xy 248.091419 -6.181548) (xy 248.067952 -6.264024) (xy 248.036976 -6.343983) (xy 247.998754 -6.420743)
			(xy 247.953613 -6.493649) (xy 247.901937 -6.562078) (xy 247.844168 -6.625448) (xy 247.780798 -6.683217)
			(xy 247.712369 -6.734893) (xy 247.639463 -6.780034) (xy 247.562703 -6.818256) (xy 247.482744 -6.849232)
			(xy 247.400268 -6.872699) (xy 247.315978 -6.888455) (xy 247.230595 -6.896367) (xy 247.144845 -6.896367)
			(xy 247.059462 -6.888455) (xy 246.975172 -6.872699) (xy 246.892696 -6.849232) (xy 246.812737 -6.818256)
			(xy 246.735977 -6.780034) (xy 246.663071 -6.734893) (xy 246.594642 -6.683217) (xy 246.531272 -6.625448)
			(xy 246.473503 -6.562078) (xy 246.421827 -6.493649) (xy 246.376686 -6.420743) (xy 246.338464 -6.343983)
			(xy 246.307488 -6.264024) (xy 246.284021 -6.181548) (xy 246.268265 -6.097258) (xy 246.260353 -6.011875)
			(xy 216.248247 -6.011875) (xy 216.240335 -6.097258) (xy 216.224579 -6.181548) (xy 216.201112 -6.264024)
			(xy 216.170136 -6.343983) (xy 216.131914 -6.420743) (xy 216.086773 -6.493649) (xy 216.035097 -6.562078)
			(xy 215.977328 -6.625448) (xy 215.913958 -6.683217) (xy 215.845529 -6.734893) (xy 215.772623 -6.780034)
			(xy 215.695863 -6.818256) (xy 215.615904 -6.849232) (xy 215.533428 -6.872699) (xy 215.449138 -6.888455)
			(xy 215.363755 -6.896367) (xy 215.278005 -6.896367) (xy 215.192622 -6.888455) (xy 215.108332 -6.872699)
			(xy 215.025856 -6.849232) (xy 214.945897 -6.818256) (xy 214.869137 -6.780034) (xy 214.796231 -6.734893)
			(xy 214.727802 -6.683217) (xy 214.664432 -6.625448) (xy 214.606663 -6.562078) (xy 214.554987 -6.493649)
			(xy 214.509846 -6.420743) (xy 214.471624 -6.343983) (xy 214.440648 -6.264024) (xy 214.417181 -6.181548)
			(xy 214.401425 -6.097258) (xy 214.393513 -6.011875) (xy 209.898247 -6.011875) (xy 209.890335 -6.097258)
			(xy 209.874579 -6.181548) (xy 209.851112 -6.264024) (xy 209.820136 -6.343983) (xy 209.781914 -6.420743)
			(xy 209.736773 -6.493649) (xy 209.685097 -6.562078) (xy 209.627328 -6.625448) (xy 209.563958 -6.683217)
			(xy 209.495529 -6.734893) (xy 209.422623 -6.780034) (xy 209.345863 -6.818256) (xy 209.265904 -6.849232)
			(xy 209.183428 -6.872699) (xy 209.099138 -6.888455) (xy 209.013755 -6.896367) (xy 208.928005 -6.896367)
			(xy 208.842622 -6.888455) (xy 208.758332 -6.872699) (xy 208.675856 -6.849232) (xy 208.595897 -6.818256)
			(xy 208.519137 -6.780034) (xy 208.446231 -6.734893) (xy 208.377802 -6.683217) (xy 208.314432 -6.625448)
			(xy 208.256663 -6.562078) (xy 208.204987 -6.493649) (xy 208.159846 -6.420743) (xy 208.121624 -6.343983)
			(xy 208.090648 -6.264024) (xy 208.067181 -6.181548) (xy 208.051425 -6.097258) (xy 208.043513 -6.011875)
			(xy 197.209918 -6.011875) (xy 197.209918 -7.78002) (xy 197.21044 -7.835826) (xy 197.218783 -7.947127)
			(xy 197.235419 -8.057493) (xy 197.260257 -8.166307) (xy 197.293157 -8.27296) (xy 197.333935 -8.376857)
			(xy 197.382363 -8.477416) (xy 197.43817 -8.574075) (xy 197.501045 -8.666293) (xy 197.570635 -8.753555)
			(xy 197.646552 -8.835372) (xy 197.728371 -8.911287) (xy 197.815634 -8.980875) (xy 197.907854 -9.043748)
			(xy 198.004514 -9.099553) (xy 198.105074 -9.147979) (xy 198.208972 -9.188755) (xy 198.315626 -9.221652)
			(xy 198.424441 -9.246487) (xy 198.534807 -9.263121) (xy 198.646108 -9.271461) (xy 198.701914 -9.272016)
			(xy 223.300036 -9.272016) (xy 223.370389 -9.27251) (xy 223.510873 -9.280402) (xy 223.650694 -9.296158)
			(xy 223.789412 -9.319729) (xy 223.92659 -9.35104) (xy 224.061796 -9.389995) (xy 224.194606 -9.436468)
			(xy 224.3246 -9.490316) (xy 224.451371 -9.551367) (xy 224.57452 -9.619431) (xy 224.693658 -9.694292)
			(xy 224.808411 -9.775716) (xy 224.918419 -9.863446) (xy 225.023334 -9.957206) (xy 225.122827 -10.056701)
			(xy 225.216585 -10.161618) (xy 225.304313 -10.271627) (xy 225.385734 -10.386382) (xy 225.460594 -10.505522)
			(xy 225.528655 -10.628671) (xy 225.589704 -10.755444) (xy 225.643549 -10.885439) (xy 225.69002 -11.01825)
			(xy 225.728972 -11.153457) (xy 225.760281 -11.290635) (xy 225.783849 -11.429353) (xy 225.799602 -11.569174)
			(xy 225.807491 -11.709659) (xy 225.808032 -11.780012) (xy 225.808032 -31.197296) (xy 227.377752 -32.767016)
			(xy 254.645668 -32.767016)
		)
		(stroke
			(width 0)
			(type solid)
		)
		(fill yes)
		(layer "In1.Cu")
		(net "DELTA_L_GND_1")
	)
	(gr_poly
		(pts
			(xy 194.495928 -441.17006) (xy 194.49641 -441.126022) (xy 194.50409 -441.03828) (xy 194.519387 -440.951542)
			(xy 194.542185 -440.866466) (xy 194.572311 -440.783702) (xy 194.609536 -440.703878) (xy 194.653576 -440.627602)
			(xy 194.704095 -440.555454) (xy 194.760711 -440.487984) (xy 194.822991 -440.425704) (xy 194.890462 -440.369089)
			(xy 194.96261 -440.31857) (xy 195.038887 -440.274531) (xy 195.118711 -440.237308) (xy 195.201476 -440.207182)
			(xy 195.286551 -440.184385) (xy 195.37329 -440.169088) (xy 195.461032 -440.16141) (xy 195.50507 -440.160918)
			(xy 276.314916 -440.160918) (xy 276.358955 -440.161399) (xy 276.446699 -440.169077) (xy 276.533439 -440.184372)
			(xy 276.618516 -440.207169) (xy 276.701283 -440.237294) (xy 276.781109 -440.274518) (xy 276.857388 -440.318557)
			(xy 276.929538 -440.369076) (xy 276.99701 -440.425692) (xy 277.059292 -440.487972) (xy 277.115909 -440.555443)
			(xy 277.16643 -440.627592) (xy 277.210471 -440.703869) (xy 277.247697 -440.783695) (xy 277.277823 -440.866461)
			(xy 277.300622 -440.951538) (xy 277.31592 -441.038278) (xy 277.3236 -441.126021) (xy 277.324058 -441.17006)
			(xy 277.324058 -441.480956) (xy 463.300064 -441.480956) (xy 463.355834 -441.480449) (xy 463.467062 -441.472116)
			(xy 463.577357 -441.455494) (xy 463.686101 -441.430676) (xy 463.792686 -441.397801) (xy 463.896517 -441.357052)
			(xy 463.997011 -441.308658) (xy 464.093608 -441.252889) (xy 464.185768 -441.190057) (xy 464.272974 -441.120513)
			(xy 464.354739 -441.044647) (xy 464.430606 -440.962883) (xy 464.50015 -440.875677) (xy 464.562982 -440.783519)
			(xy 464.618752 -440.686922) (xy 464.667147 -440.586428) (xy 464.707897 -440.482598) (xy 464.740773 -440.376013)
			(xy 464.765592 -440.267269) (xy 464.782215 -440.156974) (xy 464.790548 -440.045746) (xy 464.791044 -439.989976)
			(xy 464.791044 -419.236652) (xy 464.79206 -419.236652) (xy 464.79206 -419.160198) (xy 464.791552 -419.157912)
			(xy 464.783498 -419.125745) (xy 464.774831 -419.060003) (xy 464.77428 -419.026848) (xy 464.774826 -418.994155)
			(xy 464.783231 -418.929312) (xy 464.791044 -418.897562) (xy 464.791044 -409.528264) (xy 464.791527 -409.457889)
			(xy 464.799416 -409.317359) (xy 464.815173 -409.177493) (xy 464.838748 -409.03873) (xy 464.870067 -408.901508)
			(xy 464.909031 -408.766258) (xy 464.955519 -408.633405) (xy 465.009383 -408.503369) (xy 465.070454 -408.376557)
			(xy 465.138539 -408.25337) (xy 465.213426 -408.134194) (xy 465.294877 -408.019405) (xy 465.382637 -407.909364)
			(xy 465.47643 -407.804418) (xy 465.525866 -407.754328) (xy 467.354412 -405.925782) (xy 467.391723 -405.887821)
			(xy 467.461438 -405.807375) (xy 467.525236 -405.722161) (xy 467.582791 -405.632611) (xy 467.633809 -405.539182)
			(xy 467.678031 -405.442352) (xy 467.715231 -405.342613) (xy 467.74522 -405.240474) (xy 467.767844 -405.136455)
			(xy 467.782988 -405.031087) (xy 467.790575 -404.924907) (xy 467.791038 -404.871682) (xy 467.791038 -82.82813)
			(xy 467.791541 -82.757757) (xy 467.799451 -82.617233) (xy 467.815226 -82.477373) (xy 467.838815 -82.338618)
			(xy 467.870145 -82.201402) (xy 467.909116 -82.066159) (xy 467.955608 -81.933313) (xy 468.009473 -81.803282)
			(xy 468.070541 -81.676474) (xy 468.138622 -81.553289) (xy 468.213501 -81.434114) (xy 468.294942 -81.319323)
			(xy 468.382689 -81.209278) (xy 468.476467 -81.104324) (xy 468.52586 -81.054194) (xy 470.854278 -78.725776)
			(xy 470.891589 -78.687815) (xy 470.961306 -78.60737) (xy 471.025105 -78.522156) (xy 471.082661 -78.432606)
			(xy 471.13368 -78.339178) (xy 471.177903 -78.242348) (xy 471.215103 -78.142608) (xy 471.245092 -78.040469)
			(xy 471.267716 -77.93645) (xy 471.28286 -77.831082) (xy 471.290447 -77.724901) (xy 471.290904 -77.671676)
			(xy 471.290904 -13.780008) (xy 471.290383 -13.724238) (xy 471.282048 -13.613011) (xy 471.265425 -13.502718)
			(xy 471.240606 -13.393975) (xy 471.20773 -13.287391) (xy 471.166981 -13.183562) (xy 471.118587 -13.083068)
			(xy 471.062818 -12.986472) (xy 470.999987 -12.894314) (xy 470.930444 -12.807108) (xy 470.854579 -12.725344)
			(xy 470.772816 -12.649477) (xy 470.685612 -12.579932) (xy 470.593455 -12.517099) (xy 470.49686 -12.461328)
			(xy 470.396367 -12.412932) (xy 470.292539 -12.372181) (xy 470.185956 -12.339303) (xy 470.077214 -12.314481)
			(xy 469.966921 -12.297855) (xy 469.855694 -12.289518) (xy 469.799924 -12.289028) (xy 464.613244 -12.289028)
			(xy 464.613244 -12.288012) (xy 464.272376 -12.288012) (xy 464.272376 -12.289028) (xy 458.20203 -12.289028)
			(xy 458.131647 -12.288544) (xy 457.991102 -12.280653) (xy 457.85122 -12.264894) (xy 457.712443 -12.241316)
			(xy 457.575205 -12.209994) (xy 457.43994 -12.171027) (xy 457.307072 -12.124536) (xy 457.177021 -12.070668)
			(xy 457.050194 -12.009593) (xy 456.926991 -11.941503) (xy 456.8078 -11.866612) (xy 456.692996 -11.785156)
			(xy 456.582939 -11.69739) (xy 456.477977 -11.603592) (xy 456.378439 -11.504056) (xy 456.284639 -11.399096)
			(xy 456.196872 -11.289041) (xy 456.115413 -11.174238) (xy 456.04052 -11.055048) (xy 455.972428 -10.931847)
			(xy 455.911351 -10.805021) (xy 455.857481 -10.674971) (xy 455.810987 -10.542104) (xy 455.772017 -10.406839)
			(xy 455.740693 -10.269603) (xy 455.717113 -10.130825) (xy 455.701351 -9.990944) (xy 455.693457 -9.850399)
			(xy 455.693018 -9.780016) (xy 455.693018 -0.999998) (xy 455.692493 -0.967851) (xy 455.684101 -0.904107)
			(xy 455.667461 -0.842004) (xy 455.642857 -0.782603) (xy 455.610712 -0.726922) (xy 455.571573 -0.675913)
			(xy 455.526112 -0.630449) (xy 455.475106 -0.591307) (xy 455.419427 -0.559158) (xy 455.360029 -0.53455)
			(xy 455.297926 -0.517906) (xy 455.234183 -0.50951) (xy 455.202036 -0.509016) (xy 388.601966 -0.509016)
			(xy 388.569821 -0.509544) (xy 388.506082 -0.517939) (xy 388.443984 -0.534582) (xy 388.384589 -0.559188)
			(xy 388.328914 -0.591335) (xy 388.277911 -0.630474) (xy 388.232453 -0.675936) (xy 388.193318 -0.726941)
			(xy 388.161174 -0.782618) (xy 388.136572 -0.842014) (xy 388.119933 -0.904114) (xy 388.111542 -0.967853)
			(xy 388.110984 -0.999998) (xy 388.110984 -5.169916) (xy 388.850131 -5.169916) (xy 388.854136 -5.082008)
			(xy 388.866119 -4.994828) (xy 388.885979 -4.909099) (xy 388.913554 -4.825531) (xy 388.948613 -4.744817)
			(xy 388.990866 -4.667625) (xy 389.039964 -4.594596) (xy 389.0955 -4.526334) (xy 389.157012 -4.463404)
			(xy 389.223993 -4.40633) (xy 389.295886 -4.355582) (xy 389.372095 -4.311582) (xy 389.45199 -4.274695)
			(xy 389.534909 -4.245226) (xy 389.620164 -4.223419) (xy 389.707048 -4.209455) (xy 389.794842 -4.203449)
			(xy 389.882819 -4.205453) (xy 389.970249 -4.215448) (xy 390.056408 -4.233352) (xy 390.140582 -4.259016)
			(xy 390.222073 -4.292229) (xy 390.300207 -4.332715) (xy 390.374335 -4.380137) (xy 390.443843 -4.434104)
			(xy 390.508157 -4.494169) (xy 390.566741 -4.559833) (xy 390.619112 -4.630552) (xy 390.664835 -4.70574)
			(xy 390.703532 -4.784775) (xy 390.734881 -4.867001) (xy 390.758623 -4.951737) (xy 390.763638 -4.978969)
			(xy 394.947631 -4.978969) (xy 394.947631 -4.924431) (xy 394.955393 -4.870448) (xy 394.970758 -4.81812)
			(xy 394.993414 -4.76851) (xy 395.0229 -4.72263) (xy 395.058614 -4.681413) (xy 395.099832 -4.645698)
			(xy 395.145712 -4.616213) (xy 395.195321 -4.593557) (xy 395.24765 -4.578193) (xy 395.301633 -4.570431)
			(xy 395.328902 -4.569968) (xy 396.192502 -4.569968) (xy 396.219773 -4.570395) (xy 396.273761 -4.578157)
			(xy 396.326094 -4.593524) (xy 396.375708 -4.616182) (xy 396.421593 -4.64567) (xy 396.462813 -4.681388)
			(xy 396.498531 -4.722609) (xy 396.528019 -4.768493) (xy 396.550677 -4.818107) (xy 396.566043 -4.870441)
			(xy 396.573806 -4.924429) (xy 396.573806 -4.978971) (xy 398.547532 -4.978971) (xy 398.547532 -4.924429)
			(xy 398.555294 -4.870443) (xy 398.570661 -4.818111) (xy 398.593321 -4.768498) (xy 398.62281 -4.722616)
			(xy 398.658529 -4.681398) (xy 398.699751 -4.645684) (xy 398.745637 -4.616199) (xy 398.795252 -4.593546)
			(xy 398.847586 -4.578185) (xy 398.901573 -4.570428) (xy 398.928844 -4.569968) (xy 399.792444 -4.569968)
			(xy 399.819713 -4.570398) (xy 399.873697 -4.578165) (xy 399.926025 -4.593535) (xy 399.975633 -4.616196)
			(xy 400.021512 -4.645685) (xy 400.062728 -4.681403) (xy 400.098441 -4.722623) (xy 400.127925 -4.768505)
			(xy 400.15058 -4.818116) (xy 400.165944 -4.870447) (xy 400.173706 -4.92443) (xy 400.173706 -4.978967)
			(xy 402.147554 -4.978967) (xy 402.147554 -4.924433) (xy 402.155315 -4.870455) (xy 402.170678 -4.818131)
			(xy 402.193332 -4.768526) (xy 402.222814 -4.722649) (xy 402.258525 -4.681435) (xy 402.299738 -4.645722)
			(xy 402.345613 -4.616239) (xy 402.395218 -4.593583) (xy 402.447542 -4.578218) (xy 402.501519 -4.570455)
			(xy 402.528786 -4.569968) (xy 403.392386 -4.569968) (xy 403.41966 -4.570371) (xy 403.473652 -4.578132)
			(xy 403.525991 -4.593498) (xy 403.57561 -4.616157) (xy 403.621499 -4.645646) (xy 403.662724 -4.681366)
			(xy 403.698445 -4.72259) (xy 403.727937 -4.768478) (xy 403.750597 -4.818096) (xy 403.765965 -4.870434)
			(xy 403.773728 -4.924426) (xy 403.773728 -4.978966) (xy 405.747754 -4.978966) (xy 405.747754 -4.924434)
			(xy 405.755515 -4.870456) (xy 405.770878 -4.818132) (xy 405.793531 -4.768527) (xy 405.823013 -4.72265)
			(xy 405.858724 -4.681436) (xy 405.899936 -4.645724) (xy 405.945811 -4.61624) (xy 405.995415 -4.593584)
			(xy 406.047738 -4.578219) (xy 406.101716 -4.570456) (xy 406.128982 -4.569968) (xy 406.992582 -4.569968)
			(xy 407.019856 -4.57037) (xy 407.073849 -4.578131) (xy 407.126188 -4.593497) (xy 407.175807 -4.616155)
			(xy 407.221697 -4.645645) (xy 407.262922 -4.681365) (xy 407.298644 -4.722589) (xy 407.328136 -4.768477)
			(xy 407.350797 -4.818095) (xy 407.366165 -4.870433) (xy 407.373928 -4.924426) (xy 407.373928 -4.978971)
			(xy 414.857632 -4.978971) (xy 414.857632 -4.924429) (xy 414.865394 -4.870442) (xy 414.880762 -4.81811)
			(xy 414.903421 -4.768498) (xy 414.93291 -4.722616) (xy 414.96863 -4.681397) (xy 415.009852 -4.645683)
			(xy 415.055738 -4.616199) (xy 415.105353 -4.593546) (xy 415.157687 -4.578184) (xy 415.211675 -4.570428)
			(xy 415.238946 -4.569968) (xy 416.102546 -4.569968) (xy 416.129815 -4.570398) (xy 416.183798 -4.578165)
			(xy 416.236126 -4.593536) (xy 416.285735 -4.616196) (xy 416.331613 -4.645686) (xy 416.372829 -4.681404)
			(xy 416.408542 -4.722624) (xy 416.438026 -4.768506) (xy 416.46068 -4.818117) (xy 416.476045 -4.870447)
			(xy 416.483806 -4.924431) (xy 416.483806 -4.978967) (xy 418.457654 -4.978967) (xy 418.457654 -4.924433)
			(xy 418.465415 -4.870455) (xy 418.480779 -4.818131) (xy 418.503432 -4.768525) (xy 418.532915 -4.722648)
			(xy 418.568626 -4.681434) (xy 418.609839 -4.645722) (xy 418.655715 -4.616238) (xy 418.705319 -4.593583)
			(xy 418.757643 -4.578218) (xy 418.811621 -4.570455) (xy 418.838888 -4.569968) (xy 419.702488 -4.569968)
			(xy 419.729762 -4.570371) (xy 419.783754 -4.578132) (xy 419.836092 -4.593499) (xy 419.885711 -4.616157)
			(xy 419.9316 -4.645647) (xy 419.972824 -4.681367) (xy 420.008546 -4.722591) (xy 420.038037 -4.768479)
			(xy 420.060697 -4.818096) (xy 420.076065 -4.870434) (xy 420.083828 -4.924426) (xy 420.083828 -4.978966)
			(xy 426.067754 -4.978966) (xy 426.067754 -4.924434) (xy 426.075515 -4.870456) (xy 426.090878 -4.818132)
			(xy 426.113531 -4.768527) (xy 426.143013 -4.72265) (xy 426.178724 -4.681436) (xy 426.219936 -4.645724)
			(xy 426.265811 -4.61624) (xy 426.315415 -4.593584) (xy 426.367738 -4.578219) (xy 426.421716 -4.570456)
			(xy 426.448982 -4.569968) (xy 427.312582 -4.569968) (xy 427.339856 -4.57037) (xy 427.393849 -4.578131)
			(xy 427.446188 -4.593497) (xy 427.495807 -4.616155) (xy 427.541697 -4.645645) (xy 427.582922 -4.681365)
			(xy 427.618644 -4.722589) (xy 427.648136 -4.768477) (xy 427.670797 -4.818095) (xy 427.686165 -4.870433)
			(xy 427.693928 -4.924426) (xy 427.693928 -4.97897) (xy 429.667631 -4.97897) (xy 429.667631 -4.92443)
			(xy 429.675394 -4.870445) (xy 429.69076 -4.818115) (xy 429.713417 -4.768504) (xy 429.742905 -4.722623)
			(xy 429.778622 -4.681405) (xy 429.819842 -4.645691) (xy 429.865725 -4.616206) (xy 429.915337 -4.593552)
			(xy 429.967669 -4.578189) (xy 430.021654 -4.57043) (xy 430.048924 -4.569968) (xy 430.912524 -4.569968)
			(xy 430.939794 -4.570396) (xy 430.99378 -4.578161) (xy 431.04611 -4.59353) (xy 431.095721 -4.616189)
			(xy 431.141603 -4.645678) (xy 431.182821 -4.681396) (xy 431.218536 -4.722616) (xy 431.248022 -4.7685)
			(xy 431.270679 -4.818112) (xy 431.286044 -4.870444) (xy 431.293806 -4.92443) (xy 431.293806 -4.97897)
			(xy 431.286044 -5.032956) (xy 431.270679 -5.085288) (xy 431.248022 -5.1349) (xy 431.218536 -5.180784)
			(xy 431.182821 -5.222004) (xy 431.141603 -5.257722) (xy 431.095721 -5.287211) (xy 431.04611 -5.30987)
			(xy 430.99378 -5.325239) (xy 430.939794 -5.333004) (xy 430.912524 -5.333492) (xy 430.048924 -5.333492)
			(xy 430.021654 -5.33297) (xy 429.967669 -5.325211) (xy 429.915337 -5.309848) (xy 429.865725 -5.287194)
			(xy 429.819842 -5.257709) (xy 429.778622 -5.221995) (xy 429.742905 -5.180777) (xy 429.713417 -5.134896)
			(xy 429.69076 -5.085285) (xy 429.675394 -5.032955) (xy 429.667631 -4.97897) (xy 427.693928 -4.97897)
			(xy 427.693928 -4.978974) (xy 427.686165 -5.032967) (xy 427.670797 -5.085305) (xy 427.648136 -5.134923)
			(xy 427.618644 -5.180811) (xy 427.582922 -5.222035) (xy 427.541697 -5.257755) (xy 427.495807 -5.287245)
			(xy 427.446188 -5.309903) (xy 427.393849 -5.325269) (xy 427.339856 -5.33303) (xy 427.312582 -5.333492)
			(xy 426.448982 -5.333492) (xy 426.421716 -5.332944) (xy 426.367738 -5.325181) (xy 426.315415 -5.309816)
			(xy 426.265811 -5.28716) (xy 426.219936 -5.257676) (xy 426.178724 -5.221964) (xy 426.143013 -5.18075)
			(xy 426.113531 -5.134873) (xy 426.090878 -5.085268) (xy 426.075515 -5.032944) (xy 426.067754 -4.978966)
			(xy 420.083828 -4.978966) (xy 420.083828 -4.978974) (xy 420.076065 -5.032966) (xy 420.060697 -5.085304)
			(xy 420.038037 -5.134921) (xy 420.008546 -5.180809) (xy 419.972824 -5.222033) (xy 419.9316 -5.257753)
			(xy 419.885711 -5.287243) (xy 419.836092 -5.309901) (xy 419.783754 -5.325268) (xy 419.729762 -5.333029)
			(xy 419.702488 -5.333492) (xy 418.838888 -5.333492) (xy 418.811621 -5.332945) (xy 418.757643 -5.325182)
			(xy 418.705319 -5.309817) (xy 418.655715 -5.287162) (xy 418.609839 -5.257678) (xy 418.568626 -5.221966)
			(xy 418.532915 -5.180752) (xy 418.503432 -5.134875) (xy 418.480779 -5.085269) (xy 418.465415 -5.032945)
			(xy 418.457654 -4.978967) (xy 416.483806 -4.978967) (xy 416.483806 -4.978969) (xy 416.476045 -5.032953)
			(xy 416.46068 -5.085283) (xy 416.438026 -5.134894) (xy 416.408542 -5.180776) (xy 416.372829 -5.221996)
			(xy 416.331613 -5.257714) (xy 416.285735 -5.287204) (xy 416.236126 -5.309864) (xy 416.183798 -5.325235)
			(xy 416.129815 -5.333002) (xy 416.102546 -5.333492) (xy 415.238946 -5.333492) (xy 415.211675 -5.332972)
			(xy 415.157687 -5.325216) (xy 415.105353 -5.309854) (xy 415.055738 -5.287201) (xy 415.009852 -5.257717)
			(xy 414.96863 -5.222003) (xy 414.93291 -5.180784) (xy 414.903421 -5.134902) (xy 414.880762 -5.08529)
			(xy 414.865394 -5.032958) (xy 414.857632 -4.978971) (xy 407.373928 -4.978971) (xy 407.373928 -4.978974)
			(xy 407.366165 -5.032967) (xy 407.350797 -5.085305) (xy 407.328136 -5.134923) (xy 407.298644 -5.180811)
			(xy 407.262922 -5.222035) (xy 407.221697 -5.257755) (xy 407.175807 -5.287245) (xy 407.126188 -5.309903)
			(xy 407.073849 -5.325269) (xy 407.019856 -5.33303) (xy 406.992582 -5.333492) (xy 406.128982 -5.333492)
			(xy 406.101716 -5.332944) (xy 406.047738 -5.325181) (xy 405.995415 -5.309816) (xy 405.945811 -5.28716)
			(xy 405.899936 -5.257676) (xy 405.858724 -5.221964) (xy 405.823013 -5.18075) (xy 405.793531 -5.134873)
			(xy 405.770878 -5.085268) (xy 405.755515 -5.032944) (xy 405.747754 -4.978966) (xy 403.773728 -4.978966)
			(xy 403.773728 -4.978974) (xy 403.765965 -5.032966) (xy 403.750597 -5.085304) (xy 403.727937 -5.134922)
			(xy 403.698445 -5.18081) (xy 403.662724 -5.222034) (xy 403.621499 -5.257754) (xy 403.57561 -5.287243)
			(xy 403.525991 -5.309902) (xy 403.473652 -5.325268) (xy 403.41966 -5.333029) (xy 403.392386 -5.333492)
			(xy 402.528786 -5.333492) (xy 402.501519 -5.332945) (xy 402.447542 -5.325182) (xy 402.395218 -5.309817)
			(xy 402.345613 -5.287161) (xy 402.299738 -5.257678) (xy 402.258525 -5.221965) (xy 402.222814 -5.180751)
			(xy 402.193332 -5.134874) (xy 402.170678 -5.085269) (xy 402.155315 -5.032945) (xy 402.147554 -4.978967)
			(xy 400.173706 -4.978967) (xy 400.173706 -4.97897) (xy 400.165944 -5.032953) (xy 400.15058 -5.085284)
			(xy 400.127925 -5.134895) (xy 400.098441 -5.180777) (xy 400.062728 -5.221997) (xy 400.021512 -5.257715)
			(xy 399.975633 -5.287204) (xy 399.926025 -5.309865) (xy 399.873697 -5.325235) (xy 399.819713 -5.333002)
			(xy 399.792444 -5.333492) (xy 398.928844 -5.333492) (xy 398.901573 -5.332972) (xy 398.847586 -5.325215)
			(xy 398.795252 -5.309854) (xy 398.745637 -5.287201) (xy 398.699751 -5.257716) (xy 398.658529 -5.222002)
			(xy 398.62281 -5.180784) (xy 398.593321 -5.134902) (xy 398.570661 -5.085289) (xy 398.555294 -5.032957)
			(xy 398.547532 -4.978971) (xy 396.573806 -4.978971) (xy 396.566043 -5.032959) (xy 396.550677 -5.085293)
			(xy 396.528019 -5.134907) (xy 396.498531 -5.180791) (xy 396.462813 -5.222012) (xy 396.421593 -5.25773)
			(xy 396.375708 -5.287218) (xy 396.326094 -5.309876) (xy 396.273761 -5.325243) (xy 396.219773 -5.333005)
			(xy 396.192502 -5.333492) (xy 395.328902 -5.333492) (xy 395.301633 -5.332969) (xy 395.24765 -5.325207)
			(xy 395.195321 -5.309843) (xy 395.145712 -5.287187) (xy 395.099832 -5.257702) (xy 395.058614 -5.221987)
			(xy 395.0229 -5.18077) (xy 394.993414 -5.13489) (xy 394.970758 -5.08528) (xy 394.955393 -5.032952)
			(xy 394.947631 -4.978969) (xy 390.763638 -4.978969) (xy 390.774561 -5.038281) (xy 390.782563 -5.125916)
			(xy 390.783064 -5.169916) (xy 390.782563 -5.213916) (xy 390.774561 -5.301551) (xy 390.758623 -5.388095)
			(xy 390.734881 -5.472831) (xy 390.703532 -5.555057) (xy 390.664835 -5.634092) (xy 390.619112 -5.70928)
			(xy 390.566741 -5.779999) (xy 390.508157 -5.845663) (xy 390.443843 -5.905728) (xy 390.374335 -5.959695)
			(xy 390.300207 -6.007117) (xy 390.222073 -6.047603) (xy 390.140582 -6.080816) (xy 390.056408 -6.10648)
			(xy 389.970249 -6.124384) (xy 389.882819 -6.134379) (xy 389.794842 -6.136383) (xy 389.707048 -6.130377)
			(xy 389.620164 -6.116413) (xy 389.534909 -6.094606) (xy 389.45199 -6.065137) (xy 389.372095 -6.02825)
			(xy 389.295886 -5.98425) (xy 389.223993 -5.933502) (xy 389.157012 -5.876428) (xy 389.0955 -5.813498)
			(xy 389.039964 -5.745236) (xy 388.990866 -5.672207) (xy 388.948613 -5.595015) (xy 388.913554 -5.514301)
			(xy 388.885979 -5.430733) (xy 388.866119 -5.345004) (xy 388.854136 -5.257824) (xy 388.850131 -5.169916)
			(xy 388.110984 -5.169916) (xy 388.110984 -6.169914) (xy 453.015103 -6.169914) (xy 453.019108 -6.082006)
			(xy 453.031091 -5.994826) (xy 453.050951 -5.909097) (xy 453.078526 -5.825529) (xy 453.113585 -5.744815)
			(xy 453.155838 -5.667623) (xy 453.204936 -5.594594) (xy 453.260472 -5.526332) (xy 453.321984 -5.463402)
			(xy 453.388965 -5.406328) (xy 453.460858 -5.35558) (xy 453.537067 -5.31158) (xy 453.616962 -5.274693)
			(xy 453.699881 -5.245224) (xy 453.785136 -5.223417) (xy 453.87202 -5.209453) (xy 453.959814 -5.203447)
			(xy 454.047791 -5.205451) (xy 454.135221 -5.215446) (xy 454.22138 -5.23335) (xy 454.305554 -5.259014)
			(xy 454.387045 -5.292227) (xy 454.465179 -5.332713) (xy 454.539307 -5.380135) (xy 454.608815 -5.434102)
			(xy 454.673129 -5.494167) (xy 454.731713 -5.559831) (xy 454.784084 -5.63055) (xy 454.829807 -5.705738)
			(xy 454.868504 -5.784773) (xy 454.899853 -5.866999) (xy 454.923595 -5.951735) (xy 454.939533 -6.038279)
			(xy 454.947535 -6.125914) (xy 454.948036 -6.169914) (xy 454.947535 -6.213914) (xy 454.939533 -6.301549)
			(xy 454.923595 -6.388093) (xy 454.899853 -6.472829) (xy 454.868504 -6.555055) (xy 454.829807 -6.63409)
			(xy 454.784084 -6.709278) (xy 454.731713 -6.779997) (xy 454.673129 -6.845661) (xy 454.608815 -6.905726)
			(xy 454.539307 -6.959693) (xy 454.465179 -7.007115) (xy 454.387045 -7.047601) (xy 454.305554 -7.080814)
			(xy 454.22138 -7.106478) (xy 454.135221 -7.124382) (xy 454.047791 -7.134377) (xy 453.959814 -7.136381)
			(xy 453.87202 -7.130375) (xy 453.785136 -7.116411) (xy 453.699881 -7.094604) (xy 453.616962 -7.065135)
			(xy 453.537067 -7.028248) (xy 453.460858 -6.984248) (xy 453.388965 -6.9335) (xy 453.321984 -6.876426)
			(xy 453.260472 -6.813496) (xy 453.204936 -6.745234) (xy 453.155838 -6.672205) (xy 453.113585 -6.595013)
			(xy 453.078526 -6.514299) (xy 453.050951 -6.430731) (xy 453.031091 -6.345002) (xy 453.019108 -6.257822)
			(xy 453.015103 -6.169914) (xy 388.110984 -6.169914) (xy 388.110984 -6.740774) (xy 393.142876 -6.740774)
			(xy 393.142876 -6.686226) (xy 393.150639 -6.632232) (xy 393.166008 -6.579894) (xy 393.18867 -6.530275)
			(xy 393.218162 -6.484387) (xy 393.253885 -6.443163) (xy 393.295112 -6.407443) (xy 393.341003 -6.377954)
			(xy 393.390624 -6.355297) (xy 393.442964 -6.339932) (xy 393.496958 -6.332173) (xy 393.524232 -6.331712)
			(xy 394.387832 -6.331712) (xy 394.415098 -6.332253) (xy 394.469074 -6.340017) (xy 394.521397 -6.355384)
			(xy 394.570999 -6.378041) (xy 394.616873 -6.407526) (xy 394.658084 -6.443238) (xy 394.693794 -6.484452)
			(xy 394.723274 -6.530329) (xy 394.745927 -6.579933) (xy 394.761289 -6.632257) (xy 394.76905 -6.686234)
			(xy 394.76905 -6.740766) (xy 394.769049 -6.74077) (xy 396.742898 -6.74077) (xy 396.742898 -6.68623)
			(xy 396.75066 -6.632245) (xy 396.766025 -6.579914) (xy 396.788681 -6.530302) (xy 396.818166 -6.484419)
			(xy 396.853881 -6.4432) (xy 396.895099 -6.407482) (xy 396.940979 -6.377993) (xy 396.99059 -6.355334)
			(xy 397.04292 -6.339965) (xy 397.096904 -6.3322) (xy 397.124174 -6.331712) (xy 397.987774 -6.331712)
			(xy 398.015044 -6.332226) (xy 398.06903 -6.339984) (xy 398.121363 -6.355347) (xy 398.170976 -6.378002)
			(xy 398.216859 -6.407487) (xy 398.25808 -6.443202) (xy 398.293798 -6.48442) (xy 398.323286 -6.530301)
			(xy 398.345944 -6.579913) (xy 398.36131 -6.632244) (xy 398.369072 -6.68623) (xy 398.369072 -6.74077)
			(xy 398.369071 -6.740774) (xy 400.342776 -6.740774) (xy 400.342776 -6.686226) (xy 400.350539 -6.632234)
			(xy 400.365907 -6.579897) (xy 400.388567 -6.530279) (xy 400.418058 -6.484392) (xy 400.45378 -6.443168)
			(xy 400.495005 -6.407449) (xy 400.540893 -6.377959) (xy 400.590512 -6.355301) (xy 400.64285 -6.339935)
			(xy 400.696842 -6.332174) (xy 400.724116 -6.331712) (xy 401.587716 -6.331712) (xy 401.614983 -6.332251)
			(xy 401.668961 -6.340014) (xy 401.721285 -6.35538) (xy 401.77089 -6.378036) (xy 401.816766 -6.40752)
			(xy 401.857978 -6.443233) (xy 401.89369 -6.484447) (xy 401.923172 -6.530324) (xy 401.945825 -6.57993)
			(xy 401.961189 -6.632255) (xy 401.96895 -6.686233) (xy 401.96895 -6.740767) (xy 401.968949 -6.740773)
			(xy 403.942976 -6.740773) (xy 403.942976 -6.686227) (xy 403.950739 -6.632235) (xy 403.966106 -6.579898)
			(xy 403.988766 -6.53028) (xy 404.018257 -6.484393) (xy 404.053978 -6.44317) (xy 404.095203 -6.40745)
			(xy 404.141091 -6.377961) (xy 404.190709 -6.355302) (xy 404.243047 -6.339936) (xy 404.297039 -6.332175)
			(xy 404.324312 -6.331712) (xy 405.187912 -6.331712) (xy 405.215179 -6.332251) (xy 405.269158 -6.340014)
			(xy 405.321482 -6.355379) (xy 405.371087 -6.378034) (xy 405.416964 -6.407519) (xy 405.458177 -6.443231)
			(xy 405.493889 -6.484446) (xy 405.523371 -6.530323) (xy 405.546025 -6.579929) (xy 405.561389 -6.632254)
			(xy 405.56915 -6.686233) (xy 405.56915 -6.740767) (xy 405.56915 -6.74077) (xy 413.052998 -6.74077)
			(xy 413.052998 -6.68623) (xy 413.06076 -6.632245) (xy 413.076125 -6.579914) (xy 413.098781 -6.530302)
			(xy 413.128267 -6.484419) (xy 413.163982 -6.443199) (xy 413.205199 -6.407481) (xy 413.25108 -6.377993)
			(xy 413.300691 -6.355334) (xy 413.353021 -6.339965) (xy 413.407006 -6.3322) (xy 413.434276 -6.331712)
			(xy 414.297876 -6.331712) (xy 414.325146 -6.332226) (xy 414.379132 -6.339985) (xy 414.431464 -6.355348)
			(xy 414.481077 -6.378002) (xy 414.52696 -6.407487) (xy 414.568181 -6.443202) (xy 414.603898 -6.48442)
			(xy 414.633386 -6.530302) (xy 414.656044 -6.579913) (xy 414.67141 -6.632244) (xy 414.679173 -6.68623)
			(xy 414.679173 -6.74077) (xy 414.679172 -6.740774) (xy 416.652876 -6.740774) (xy 416.652876 -6.686226)
			(xy 416.660639 -6.632234) (xy 416.676007 -6.579897) (xy 416.698667 -6.530279) (xy 416.728159 -6.484391)
			(xy 416.763881 -6.443168) (xy 416.805106 -6.407448) (xy 416.850995 -6.377959) (xy 416.900613 -6.355301)
			(xy 416.952952 -6.339935) (xy 417.006944 -6.332174) (xy 417.034218 -6.331712) (xy 417.897818 -6.331712)
			(xy 417.925085 -6.332252) (xy 417.979063 -6.340015) (xy 418.031386 -6.355381) (xy 418.080991 -6.378036)
			(xy 418.126867 -6.407521) (xy 418.168079 -6.443234) (xy 418.20379 -6.484448) (xy 418.233272 -6.530325)
			(xy 418.255926 -6.57993) (xy 418.271289 -6.632255) (xy 418.27905 -6.686233) (xy 418.27905 -6.740767)
			(xy 418.279049 -6.740773) (xy 424.262976 -6.740773) (xy 424.262976 -6.686227) (xy 424.270739 -6.632235)
			(xy 424.286106 -6.579898) (xy 424.308766 -6.53028) (xy 424.338257 -6.484393) (xy 424.373978 -6.44317)
			(xy 424.415203 -6.40745) (xy 424.461091 -6.377961) (xy 424.510709 -6.355302) (xy 424.563047 -6.339936)
			(xy 424.617039 -6.332175) (xy 424.644312 -6.331712) (xy 425.507912 -6.331712) (xy 425.535179 -6.332251)
			(xy 425.589158 -6.340014) (xy 425.641482 -6.355379) (xy 425.691087 -6.378034) (xy 425.736964 -6.407519)
			(xy 425.778177 -6.443231) (xy 425.813889 -6.484446) (xy 425.843371 -6.530323) (xy 425.866025 -6.579929)
			(xy 425.881389 -6.632254) (xy 425.88915 -6.686233) (xy 425.88915 -6.740767) (xy 425.88915 -6.740769)
			(xy 427.862998 -6.740769) (xy 427.862998 -6.686231) (xy 427.870759 -6.632248) (xy 427.886123 -6.579918)
			(xy 427.908778 -6.530308) (xy 427.938261 -6.484426) (xy 427.973974 -6.443207) (xy 428.015189 -6.407489)
			(xy 428.061067 -6.378) (xy 428.110675 -6.35534) (xy 428.163003 -6.339969) (xy 428.216985 -6.332202)
			(xy 428.244254 -6.331712) (xy 429.107854 -6.331712) (xy 429.135125 -6.332224) (xy 429.189113 -6.339981)
			(xy 429.241448 -6.355342) (xy 429.291064 -6.377995) (xy 429.33695 -6.40748) (xy 429.378173 -6.443195)
			(xy 429.413893 -6.484413) (xy 429.443383 -6.530296) (xy 429.466042 -6.579909) (xy 429.48141 -6.632242)
			(xy 429.489172 -6.686229) (xy 429.489172 -6.740771) (xy 429.488151 -6.747873) (xy 431.473788 -6.747873)
			(xy 431.473788 -6.693327) (xy 431.48155 -6.639337) (xy 431.496918 -6.587001) (xy 431.519578 -6.537385)
			(xy 431.549068 -6.491498) (xy 431.584789 -6.450276) (xy 431.626013 -6.414558) (xy 431.6719 -6.385069)
			(xy 431.721518 -6.362412) (xy 431.773854 -6.347047) (xy 431.827845 -6.339286) (xy 431.855118 -6.338824)
			(xy 432.718718 -6.338824) (xy 432.745986 -6.33934) (xy 432.799965 -6.347103) (xy 432.852291 -6.362469)
			(xy 432.901897 -6.385126) (xy 432.947774 -6.414611) (xy 432.988988 -6.450325) (xy 433.0247 -6.491541)
			(xy 433.054183 -6.537419) (xy 433.076837 -6.587026) (xy 433.092201 -6.639352) (xy 433.099962 -6.693332)
			(xy 433.099962 -6.740771) (xy 445.457798 -6.740771) (xy 445.457798 -6.686229) (xy 445.46556 -6.632243)
			(xy 445.480926 -6.579911) (xy 445.503583 -6.530298) (xy 445.53307 -6.484415) (xy 445.568786 -6.443195)
			(xy 445.610005 -6.407477) (xy 445.655888 -6.377989) (xy 445.7055 -6.35533) (xy 445.757831 -6.339963)
			(xy 445.811817 -6.332199) (xy 445.839088 -6.331712) (xy 446.702688 -6.331712) (xy 446.729958 -6.332227)
			(xy 446.783942 -6.339987) (xy 446.836273 -6.355351) (xy 446.885884 -6.378006) (xy 446.931766 -6.407492)
			(xy 446.972985 -6.443207) (xy 447.008701 -6.484424) (xy 447.038188 -6.530305) (xy 447.060845 -6.579916)
			(xy 447.076211 -6.632246) (xy 447.083973 -6.68623) (xy 447.083973 -6.74077) (xy 447.076211 -6.794754)
			(xy 447.060845 -6.847084) (xy 447.038188 -6.896695) (xy 447.008701 -6.942576) (xy 446.972985 -6.983793)
			(xy 446.931766 -7.019508) (xy 446.885884 -7.048994) (xy 446.836273 -7.071649) (xy 446.783942 -7.087013)
			(xy 446.729958 -7.094773) (xy 446.702688 -7.095236) (xy 445.839088 -7.095236) (xy 445.811817 -7.094801)
			(xy 445.757831 -7.087037) (xy 445.7055 -7.07167) (xy 445.655888 -7.049011) (xy 445.610005 -7.019523)
			(xy 445.568786 -6.983805) (xy 445.53307 -6.942585) (xy 445.503583 -6.896702) (xy 445.480926 -6.847089)
			(xy 445.46556 -6.794757) (xy 445.457798 -6.740771) (xy 433.099962 -6.740771) (xy 433.099962 -6.747868)
			(xy 433.092201 -6.801848) (xy 433.076837 -6.854174) (xy 433.054183 -6.903781) (xy 433.0247 -6.949659)
			(xy 432.988988 -6.990875) (xy 432.947774 -7.026589) (xy 432.901897 -7.056074) (xy 432.852291 -7.078731)
			(xy 432.799965 -7.094097) (xy 432.745986 -7.10186) (xy 432.718718 -7.102348) (xy 431.855118 -7.102348)
			(xy 431.827845 -7.101914) (xy 431.773854 -7.094153) (xy 431.721518 -7.078788) (xy 431.6719 -7.056131)
			(xy 431.626013 -7.026642) (xy 431.584789 -6.990924) (xy 431.549068 -6.949702) (xy 431.519578 -6.903815)
			(xy 431.496918 -6.854199) (xy 431.48155 -6.801863) (xy 431.473788 -6.747873) (xy 429.488151 -6.747873)
			(xy 429.48141 -6.794758) (xy 429.466042 -6.847091) (xy 429.443383 -6.896704) (xy 429.413893 -6.942587)
			(xy 429.378173 -6.983805) (xy 429.33695 -7.01952) (xy 429.291064 -7.049005) (xy 429.241448 -7.071658)
			(xy 429.189113 -7.087019) (xy 429.135125 -7.094776) (xy 429.107854 -7.095236) (xy 428.244254 -7.095236)
			(xy 428.216985 -7.094798) (xy 428.163003 -7.087031) (xy 428.110675 -7.07166) (xy 428.061067 -7.049)
			(xy 428.015189 -7.019511) (xy 427.973974 -6.983793) (xy 427.938261 -6.942574) (xy 427.908778 -6.896692)
			(xy 427.886123 -6.847082) (xy 427.870759 -6.794752) (xy 427.862998 -6.740769) (xy 425.88915 -6.740769)
			(xy 425.881389 -6.794746) (xy 425.866025 -6.847071) (xy 425.843371 -6.896677) (xy 425.813889 -6.942554)
			(xy 425.778177 -6.983769) (xy 425.736964 -7.019481) (xy 425.691087 -7.048966) (xy 425.641482 -7.071621)
			(xy 425.589158 -7.086986) (xy 425.535179 -7.094749) (xy 425.507912 -7.095236) (xy 424.644312 -7.095236)
			(xy 424.617039 -7.094825) (xy 424.563047 -7.087064) (xy 424.510709 -7.071698) (xy 424.461091 -7.049039)
			(xy 424.415203 -7.01955) (xy 424.373978 -6.98383) (xy 424.338257 -6.942607) (xy 424.308766 -6.89672)
			(xy 424.286106 -6.847102) (xy 424.270739 -6.794765) (xy 424.262976 -6.740773) (xy 418.279049 -6.740773)
			(xy 418.271289 -6.794745) (xy 418.255926 -6.84707) (xy 418.233272 -6.896675) (xy 418.20379 -6.942552)
			(xy 418.168079 -6.983766) (xy 418.126867 -7.019479) (xy 418.080991 -7.048964) (xy 418.031386 -7.071619)
			(xy 417.979063 -7.086985) (xy 417.925085 -7.094748) (xy 417.897818 -7.095236) (xy 417.034218 -7.095236)
			(xy 417.006944 -7.094826) (xy 416.952952 -7.087065) (xy 416.900613 -7.071699) (xy 416.850995 -7.049041)
			(xy 416.805106 -7.019552) (xy 416.763881 -6.983832) (xy 416.728159 -6.942609) (xy 416.698667 -6.896721)
			(xy 416.676007 -6.847103) (xy 416.660639 -6.794766) (xy 416.652876 -6.740774) (xy 414.679172 -6.740774)
			(xy 414.67141 -6.794756) (xy 414.656044 -6.847087) (xy 414.633386 -6.896698) (xy 414.603898 -6.94258)
			(xy 414.568181 -6.983798) (xy 414.52696 -7.019513) (xy 414.481077 -7.048998) (xy 414.431464 -7.071652)
			(xy 414.379132 -7.087015) (xy 414.325146 -7.094774) (xy 414.297876 -7.095236) (xy 413.434276 -7.095236)
			(xy 413.407006 -7.0948) (xy 413.353021 -7.087035) (xy 413.300691 -7.071666) (xy 413.25108 -7.049007)
			(xy 413.205199 -7.019519) (xy 413.163982 -6.983801) (xy 413.128267 -6.942581) (xy 413.098781 -6.896698)
			(xy 413.076125 -6.847086) (xy 413.06076 -6.794755) (xy 413.052998 -6.74077) (xy 405.56915 -6.74077)
			(xy 405.561389 -6.794746) (xy 405.546025 -6.847071) (xy 405.523371 -6.896677) (xy 405.493889 -6.942554)
			(xy 405.458177 -6.983769) (xy 405.416964 -7.019481) (xy 405.371087 -7.048966) (xy 405.321482 -7.071621)
			(xy 405.269158 -7.086986) (xy 405.215179 -7.094749) (xy 405.187912 -7.095236) (xy 404.324312 -7.095236)
			(xy 404.297039 -7.094825) (xy 404.243047 -7.087064) (xy 404.190709 -7.071698) (xy 404.141091 -7.049039)
			(xy 404.095203 -7.01955) (xy 404.053978 -6.98383) (xy 404.018257 -6.942607) (xy 403.988766 -6.89672)
			(xy 403.966106 -6.847102) (xy 403.950739 -6.794765) (xy 403.942976 -6.740773) (xy 401.968949 -6.740773)
			(xy 401.961189 -6.794745) (xy 401.945825 -6.84707) (xy 401.923172 -6.896676) (xy 401.89369 -6.942553)
			(xy 401.857978 -6.983767) (xy 401.816766 -7.01948) (xy 401.77089 -7.048964) (xy 401.721285 -7.07162)
			(xy 401.668961 -7.086986) (xy 401.614983 -7.094749) (xy 401.587716 -7.095236) (xy 400.724116 -7.095236)
			(xy 400.696842 -7.094826) (xy 400.64285 -7.087065) (xy 400.590512 -7.071699) (xy 400.540893 -7.049041)
			(xy 400.495005 -7.019551) (xy 400.45378 -6.983832) (xy 400.418058 -6.942608) (xy 400.388567 -6.896721)
			(xy 400.365907 -6.847103) (xy 400.350539 -6.794766) (xy 400.342776 -6.740774) (xy 398.369071 -6.740774)
			(xy 398.36131 -6.794756) (xy 398.345944 -6.847087) (xy 398.323286 -6.896699) (xy 398.293798 -6.94258)
			(xy 398.25808 -6.983798) (xy 398.216859 -7.019513) (xy 398.170976 -7.048998) (xy 398.121363 -7.071653)
			(xy 398.06903 -7.087016) (xy 398.015044 -7.094774) (xy 397.987774 -7.095236) (xy 397.124174 -7.095236)
			(xy 397.096904 -7.0948) (xy 397.04292 -7.087035) (xy 396.99059 -7.071666) (xy 396.940979 -7.049007)
			(xy 396.895099 -7.019518) (xy 396.853881 -6.9838) (xy 396.818166 -6.942581) (xy 396.788681 -6.896698)
			(xy 396.766025 -6.847086) (xy 396.75066 -6.794755) (xy 396.742898 -6.74077) (xy 394.769049 -6.74077)
			(xy 394.761289 -6.794743) (xy 394.745927 -6.847067) (xy 394.723274 -6.896671) (xy 394.693794 -6.942548)
			(xy 394.658084 -6.983762) (xy 394.616873 -7.019474) (xy 394.570999 -7.048959) (xy 394.521397 -7.071616)
			(xy 394.469074 -7.086983) (xy 394.415098 -7.094747) (xy 394.387832 -7.095236) (xy 393.524232 -7.095236)
			(xy 393.496958 -7.094827) (xy 393.442964 -7.087068) (xy 393.390624 -7.071703) (xy 393.341003 -7.049046)
			(xy 393.295112 -7.019557) (xy 393.253885 -6.983837) (xy 393.218162 -6.942613) (xy 393.18867 -6.896725)
			(xy 393.166008 -6.847106) (xy 393.150639 -6.794768) (xy 393.142876 -6.740774) (xy 388.110984 -6.740774)
			(xy 388.110984 -7.601204) (xy 391.651236 -7.601204) (xy 392.642852 -7.601204) (xy 392.642852 -9.04494)
			(xy 391.651236 -9.04494) (xy 391.651236 -7.601204) (xy 388.110984 -7.601204) (xy 388.110984 -9.094724)
			(xy 393.231624 -9.094724) (xy 393.231624 -7.672324) (xy 393.232034 -7.660239) (xy 393.239499 -7.637252)
			(xy 393.253704 -7.617699) (xy 393.273259 -7.603495) (xy 393.296247 -7.596032) (xy 393.308332 -7.595616)
			(xy 394.589762 -7.595616) (xy 394.601847 -7.596139) (xy 394.624843 -7.603583) (xy 394.644421 -7.617756)
			(xy 394.658674 -7.637276) (xy 394.666211 -7.660241) (xy 394.666724 -7.672324) (xy 394.666724 -9.094724)
			(xy 395.031468 -9.094724) (xy 395.031468 -7.672324) (xy 395.031937 -7.66022) (xy 395.039425 -7.637199)
			(xy 395.053675 -7.617628) (xy 395.073283 -7.603431) (xy 395.096325 -7.596004) (xy 395.10843 -7.595616)
			(xy 396.38986 -7.595616) (xy 396.401943 -7.596047) (xy 396.424929 -7.603507) (xy 396.444482 -7.617707)
			(xy 396.458686 -7.637257) (xy 396.46615 -7.660241) (xy 396.466568 -7.672324) (xy 396.466568 -9.094724)
			(xy 396.831312 -9.094724) (xy 396.831312 -7.672324) (xy 396.831737 -7.660215) (xy 396.839231 -7.637187)
			(xy 396.85349 -7.617612) (xy 396.873111 -7.603417) (xy 396.896164 -7.595998) (xy 396.908274 -7.595616)
			(xy 398.189704 -7.595616) (xy 398.201789 -7.596009) (xy 398.224776 -7.603481) (xy 398.244329 -7.617691)
			(xy 398.258532 -7.637249) (xy 398.265995 -7.660238) (xy 398.266412 -7.672324) (xy 398.266412 -9.094724)
			(xy 398.631664 -9.094724) (xy 398.631664 -7.672324) (xy 398.632184 -7.660253) (xy 398.639637 -7.637292)
			(xy 398.65382 -7.617757) (xy 398.673345 -7.60356) (xy 398.696302 -7.596092) (xy 398.708372 -7.595616)
			(xy 399.989802 -7.595616) (xy 400.001889 -7.596105) (xy 400.024886 -7.60356) (xy 400.044464 -7.617741)
			(xy 400.058715 -7.637269) (xy 400.066251 -7.660238) (xy 400.066764 -7.672324) (xy 400.066764 -9.094724)
			(xy 400.431508 -9.094724) (xy 400.431508 -7.672324) (xy 400.431933 -7.660241) (xy 400.439396 -7.637256)
			(xy 400.453599 -7.617704) (xy 400.473149 -7.6035) (xy 400.496133 -7.596035) (xy 400.508216 -7.595616)
			(xy 401.789646 -7.595616) (xy 401.801736 -7.596068) (xy 401.824734 -7.603534) (xy 401.844311 -7.617726)
			(xy 401.858561 -7.63726) (xy 401.866096 -7.660236) (xy 401.866608 -7.672324) (xy 401.866608 -9.094724)
			(xy 402.231352 -9.094724) (xy 402.231352 -7.672324) (xy 402.231836 -7.660221) (xy 402.239323 -7.637203)
			(xy 402.253569 -7.617634) (xy 402.273173 -7.603436) (xy 402.29621 -7.596007) (xy 402.308314 -7.595616)
			(xy 403.589744 -7.595616) (xy 403.601823 -7.596027) (xy 403.624796 -7.603504) (xy 403.644334 -7.617714)
			(xy 403.658527 -7.637265) (xy 403.665984 -7.660244) (xy 403.666452 -7.672324) (xy 403.666452 -9.094724)
			(xy 404.031196 -9.094724) (xy 404.031196 -7.672324) (xy 404.031637 -7.660217) (xy 404.039129 -7.637191)
			(xy 404.053385 -7.617618) (xy 404.073001 -7.603422) (xy 404.09605 -7.596) (xy 404.108158 -7.595616)
			(xy 405.389588 -7.595616) (xy 405.401672 -7.596023) (xy 405.424659 -7.603491) (xy 405.444211 -7.617697)
			(xy 405.458415 -7.637252) (xy 405.465878 -7.660239) (xy 405.466296 -7.672324) (xy 405.466296 -9.094724)
			(xy 405.831548 -9.094724) (xy 405.831548 -7.672324) (xy 405.832084 -7.660255) (xy 405.839534 -7.637296)
			(xy 405.853714 -7.617762) (xy 405.873235 -7.603566) (xy 405.896187 -7.596095) (xy 405.908256 -7.595616)
			(xy 407.189686 -7.595616) (xy 407.201772 -7.596119) (xy 407.224769 -7.603569) (xy 407.244347 -7.617747)
			(xy 407.258598 -7.637272) (xy 407.266135 -7.660239) (xy 407.266648 -7.672324) (xy 407.266648 -9.094724)
			(xy 413.141668 -9.094724) (xy 413.141668 -7.672324) (xy 413.142184 -7.660253) (xy 413.149637 -7.637291)
			(xy 413.163821 -7.617755) (xy 413.183348 -7.603559) (xy 413.206305 -7.596092) (xy 413.218376 -7.595616)
			(xy 414.499806 -7.595616) (xy 414.511893 -7.596102) (xy 414.53489 -7.603557) (xy 414.554468 -7.61774)
			(xy 414.568719 -7.637268) (xy 414.576255 -7.660238) (xy 414.576768 -7.672324) (xy 414.576768 -9.094724)
			(xy 414.941512 -9.094724) (xy 414.941512 -7.672324) (xy 414.941937 -7.660215) (xy 414.949431 -7.637187)
			(xy 414.96369 -7.617612) (xy 414.983311 -7.603417) (xy 415.006364 -7.595998) (xy 415.018474 -7.595616)
			(xy 416.299904 -7.595616) (xy 416.311989 -7.596009) (xy 416.334976 -7.603481) (xy 416.354529 -7.617691)
			(xy 416.368732 -7.637249) (xy 416.376195 -7.660238) (xy 416.376612 -7.672324) (xy 416.376612 -9.094724)
			(xy 416.741356 -9.094724) (xy 416.741356 -7.672324) (xy 416.741836 -7.660221) (xy 416.749324 -7.637202)
			(xy 416.76357 -7.617632) (xy 416.783176 -7.603435) (xy 416.806214 -7.596006) (xy 416.818318 -7.595616)
			(xy 418.099748 -7.595616) (xy 418.111827 -7.596024) (xy 418.1348 -7.603502) (xy 418.154339 -7.617713)
			(xy 418.168531 -7.637264) (xy 418.175988 -7.660244) (xy 418.176456 -7.672324) (xy 418.176456 -9.094724)
			(xy 418.541708 -9.094724) (xy 418.541708 -7.672324) (xy 418.542133 -7.660241) (xy 418.549596 -7.637256)
			(xy 418.563799 -7.617704) (xy 418.583349 -7.6035) (xy 418.606333 -7.596035) (xy 418.618416 -7.595616)
			(xy 419.899846 -7.595616) (xy 419.911936 -7.596068) (xy 419.934934 -7.603534) (xy 419.954511 -7.617726)
			(xy 419.968761 -7.63726) (xy 419.976296 -7.660236) (xy 419.976808 -7.672324) (xy 419.976808 -9.094724)
			(xy 424.351704 -9.094724) (xy 424.351704 -7.672324) (xy 424.352133 -7.660241) (xy 424.359596 -7.637257)
			(xy 424.373797 -7.617706) (xy 424.393347 -7.603501) (xy 424.416329 -7.596035) (xy 424.428412 -7.595616)
			(xy 425.709842 -7.595616) (xy 425.721931 -7.596071) (xy 425.744929 -7.603536) (xy 425.764507 -7.617727)
			(xy 425.778757 -7.637261) (xy 425.786292 -7.660236) (xy 425.786804 -7.672324) (xy 425.786804 -9.094724)
			(xy 426.151548 -9.094724) (xy 426.151548 -7.672324) (xy 426.152036 -7.660222) (xy 426.159523 -7.637204)
			(xy 426.173768 -7.617635) (xy 426.193371 -7.603438) (xy 426.216407 -7.596007) (xy 426.22851 -7.595616)
			(xy 427.50994 -7.595616) (xy 427.522019 -7.59603) (xy 427.544992 -7.603507) (xy 427.56453 -7.617715)
			(xy 427.578722 -7.637266) (xy 427.58618 -7.660245) (xy 427.586648 -7.672324) (xy 427.586648 -9.094724)
			(xy 427.951392 -9.094724) (xy 427.951392 -7.672324) (xy 427.951837 -7.660217) (xy 427.959329 -7.637192)
			(xy 427.973583 -7.617619) (xy 427.993199 -7.603424) (xy 428.016246 -7.596001) (xy 428.028354 -7.595616)
			(xy 429.309784 -7.595616) (xy 429.321868 -7.596027) (xy 429.344854 -7.603493) (xy 429.364407 -7.617699)
			(xy 429.378611 -7.637253) (xy 429.386074 -7.66024) (xy 429.386492 -7.672324) (xy 429.386492 -9.094724)
			(xy 429.751744 -9.094724) (xy 429.751744 -7.672324) (xy 429.752284 -7.660255) (xy 429.759734 -7.637297)
			(xy 429.773913 -7.617764) (xy 429.793433 -7.603567) (xy 429.816384 -7.596095) (xy 429.828452 -7.595616)
			(xy 431.109882 -7.595616) (xy 431.121968 -7.596122) (xy 431.144964 -7.603571) (xy 431.164542 -7.617748)
			(xy 431.178794 -7.637272) (xy 431.186331 -7.66024) (xy 431.186844 -7.672324) (xy 431.186844 -9.094724)
			(xy 431.186405 -9.10683) (xy 431.178904 -9.12985) (xy 431.164647 -9.149419) (xy 431.145033 -9.163615)
			(xy 431.121989 -9.171043) (xy 431.109882 -9.171432) (xy 429.828452 -9.171432) (xy 429.816377 -9.170977)
			(xy 429.793413 -9.163504) (xy 429.773878 -9.149304) (xy 429.759685 -9.129766) (xy 429.752219 -9.106799)
			(xy 429.751744 -9.094724) (xy 429.386492 -9.094724) (xy 429.386056 -9.106801) (xy 429.378585 -9.129772)
			(xy 429.364381 -9.14931) (xy 429.344836 -9.163503) (xy 429.321862 -9.170962) (xy 429.309784 -9.171432)
			(xy 428.028354 -9.171432) (xy 428.016259 -9.171031) (xy 427.993252 -9.163559) (xy 427.973671 -9.149356)
			(xy 427.959423 -9.129807) (xy 427.951897 -9.106818) (xy 427.951392 -9.094724) (xy 427.586648 -9.094724)
			(xy 427.586157 -9.106796) (xy 427.578692 -9.129757) (xy 427.564501 -9.14929) (xy 427.544971 -9.163485)
			(xy 427.522012 -9.170954) (xy 427.50994 -9.171432) (xy 426.22851 -9.171432) (xy 426.216418 -9.170983)
			(xy 426.193413 -9.163526) (xy 426.173831 -9.149336) (xy 426.159581 -9.129797) (xy 426.152054 -9.106814)
			(xy 426.151548 -9.094724) (xy 425.786804 -9.094724) (xy 425.786404 -9.106834) (xy 425.778899 -9.129861)
			(xy 425.764633 -9.149433) (xy 425.745008 -9.163627) (xy 425.721953 -9.171048) (xy 425.709842 -9.171432)
			(xy 424.428412 -9.171432) (xy 424.41634 -9.170926) (xy 424.393378 -9.16347) (xy 424.373843 -9.149283)
			(xy 424.359647 -9.129755) (xy 424.35218 -9.106795) (xy 424.351704 -9.094724) (xy 419.976808 -9.094724)
			(xy 419.976404 -9.106833) (xy 419.968899 -9.12986) (xy 419.954634 -9.149432) (xy 419.935011 -9.163626)
			(xy 419.911957 -9.171048) (xy 419.899846 -9.171432) (xy 418.618416 -9.171432) (xy 418.606345 -9.170923)
			(xy 418.583382 -9.163467) (xy 418.563847 -9.149282) (xy 418.549651 -9.129754) (xy 418.542184 -9.106795)
			(xy 418.541708 -9.094724) (xy 418.176456 -9.094724) (xy 418.175957 -9.106795) (xy 418.168494 -9.129755)
			(xy 418.154304 -9.149287) (xy 418.134776 -9.163483) (xy 418.111819 -9.170953) (xy 418.099748 -9.171432)
			(xy 416.818318 -9.171432) (xy 416.806227 -9.170977) (xy 416.783222 -9.163522) (xy 416.763639 -9.149333)
			(xy 416.749389 -9.129795) (xy 416.741862 -9.106814) (xy 416.741356 -9.094724) (xy 416.376612 -9.094724)
			(xy 416.376156 -9.106799) (xy 416.368687 -9.129767) (xy 416.354489 -9.149303) (xy 416.334949 -9.163497)
			(xy 416.311979 -9.170959) (xy 416.299904 -9.171432) (xy 415.018474 -9.171432) (xy 415.00638 -9.171014)
			(xy 414.983374 -9.163547) (xy 414.963792 -9.149349) (xy 414.949543 -9.129803) (xy 414.942017 -9.106816)
			(xy 414.941512 -9.094724) (xy 414.576768 -9.094724) (xy 414.576404 -9.106837) (xy 414.568894 -9.129871)
			(xy 414.55462 -9.149446) (xy 414.534985 -9.163639) (xy 414.511921 -9.171053) (xy 414.499806 -9.171432)
			(xy 413.218376 -9.171432) (xy 413.206303 -9.170956) (xy 413.183339 -9.16349) (xy 413.163804 -9.149296)
			(xy 413.14961 -9.129761) (xy 413.142144 -9.106797) (xy 413.141668 -9.094724) (xy 407.266648 -9.094724)
			(xy 407.266205 -9.106829) (xy 407.258705 -9.129849) (xy 407.244448 -9.149418) (xy 407.224836 -9.163613)
			(xy 407.201793 -9.171042) (xy 407.189686 -9.171432) (xy 405.908256 -9.171432) (xy 405.896182 -9.170974)
			(xy 405.873217 -9.163502) (xy 405.853683 -9.149303) (xy 405.839489 -9.129765) (xy 405.832023 -9.106799)
			(xy 405.831548 -9.094724) (xy 405.466296 -9.094724) (xy 405.465856 -9.106801) (xy 405.458385 -9.129771)
			(xy 405.444183 -9.149309) (xy 405.424639 -9.163502) (xy 405.401665 -9.170961) (xy 405.389588 -9.171432)
			(xy 404.108158 -9.171432) (xy 404.096063 -9.171028) (xy 404.073057 -9.163556) (xy 404.053475 -9.149354)
			(xy 404.039227 -9.129806) (xy 404.031701 -9.106817) (xy 404.031196 -9.094724) (xy 403.666452 -9.094724)
			(xy 403.665957 -9.106795) (xy 403.658493 -9.129756) (xy 403.644303 -9.149289) (xy 403.624774 -9.163484)
			(xy 403.601815 -9.170954) (xy 403.589744 -9.171432) (xy 402.308314 -9.171432) (xy 402.296222 -9.17098)
			(xy 402.273218 -9.163524) (xy 402.253635 -9.149334) (xy 402.239385 -9.129796) (xy 402.231858 -9.106814)
			(xy 402.231352 -9.094724) (xy 401.866608 -9.094724) (xy 401.866204 -9.106833) (xy 401.858699 -9.12986)
			(xy 401.844434 -9.149432) (xy 401.824811 -9.163626) (xy 401.801757 -9.171048) (xy 401.789646 -9.171432)
			(xy 400.508216 -9.171432) (xy 400.496145 -9.170923) (xy 400.473182 -9.163467) (xy 400.453647 -9.149282)
			(xy 400.439451 -9.129754) (xy 400.431984 -9.106795) (xy 400.431508 -9.094724) (xy 400.066764 -9.094724)
			(xy 400.066404 -9.106838) (xy 400.058893 -9.129872) (xy 400.044618 -9.149448) (xy 400.024983 -9.16364)
			(xy 400.001917 -9.171054) (xy 399.989802 -9.171432) (xy 398.708372 -9.171432) (xy 398.696298 -9.17096)
			(xy 398.673334 -9.163493) (xy 398.6538 -9.149297) (xy 398.639605 -9.129762) (xy 398.632139 -9.106798)
			(xy 398.631664 -9.094724) (xy 398.266412 -9.094724) (xy 398.265956 -9.106799) (xy 398.258487 -9.129767)
			(xy 398.244289 -9.149303) (xy 398.224749 -9.163497) (xy 398.201779 -9.170959) (xy 398.189704 -9.171432)
			(xy 396.908274 -9.171432) (xy 396.89618 -9.171014) (xy 396.873174 -9.163547) (xy 396.853592 -9.149349)
			(xy 396.839343 -9.129803) (xy 396.831817 -9.106816) (xy 396.831312 -9.094724) (xy 396.466568 -9.094724)
			(xy 396.466207 -9.106812) (xy 396.458728 -9.129802) (xy 396.44451 -9.149356) (xy 396.424945 -9.163557)
			(xy 396.401948 -9.171017) (xy 396.38986 -9.171432) (xy 395.10843 -9.171432) (xy 395.096339 -9.170967)
			(xy 395.073335 -9.163515) (xy 395.053752 -9.149329) (xy 395.039501 -9.129793) (xy 395.031974 -9.106813)
			(xy 395.031468 -9.094724) (xy 394.666724 -9.094724) (xy 394.666304 -9.106832) (xy 394.658801 -9.129856)
			(xy 394.64454 -9.149426) (xy 394.624921 -9.163621) (xy 394.601871 -9.171045) (xy 394.589762 -9.171432)
			(xy 393.308332 -9.171432) (xy 393.296253 -9.17096) (xy 393.273276 -9.163505) (xy 393.253727 -9.149313)
			(xy 393.239521 -9.129774) (xy 393.232048 -9.106802) (xy 393.231624 -9.094724) (xy 388.110984 -9.094724)
			(xy 388.110984 -9.780016) (xy 388.110499 -9.850398) (xy 388.102605 -9.99094) (xy 388.086844 -10.130819)
			(xy 388.063264 -10.269594) (xy 388.03194 -10.406828) (xy 387.992971 -10.54209) (xy 387.946478 -10.674954)
			(xy 387.892609 -10.805003) (xy 387.831533 -10.931826) (xy 387.763442 -11.055026) (xy 387.68855 -11.174213)
			(xy 387.607093 -11.289014) (xy 387.519328 -11.399067) (xy 387.425529 -11.504025) (xy 387.325993 -11.60356)
			(xy 387.221033 -11.697356) (xy 387.110979 -11.78512) (xy 386.996176 -11.866575) (xy 386.914842 -11.91768)
			(xy 393.227052 -11.91768) (xy 393.227052 -10.49528) (xy 393.227499 -10.483175) (xy 393.234998 -10.460155)
			(xy 393.249253 -10.440587) (xy 393.268865 -10.426391) (xy 393.291908 -10.418962) (xy 393.304014 -10.418572)
			(xy 394.585444 -10.418572) (xy 394.597519 -10.419026) (xy 394.620484 -10.426498) (xy 394.640019 -10.440698)
			(xy 394.654213 -10.460237) (xy 394.661678 -10.483205) (xy 394.662152 -10.49528) (xy 394.662152 -11.91768)
			(xy 395.027404 -11.91768) (xy 395.027404 -10.49528) (xy 395.027848 -10.483203) (xy 395.035317 -10.460233)
			(xy 395.049519 -10.440696) (xy 395.069062 -10.426502) (xy 395.092035 -10.419043) (xy 395.104112 -10.418572)
			(xy 396.385542 -10.418572) (xy 396.397637 -10.418972) (xy 396.420644 -10.426444) (xy 396.440226 -10.440647)
			(xy 396.454474 -10.460196) (xy 396.462 -10.483186) (xy 396.462504 -10.49528) (xy 396.462504 -11.91768)
			(xy 396.827248 -11.91768) (xy 396.827248 -10.49528) (xy 396.827747 -10.483209) (xy 396.835209 -10.460248)
			(xy 396.849399 -10.440716) (xy 396.868927 -10.42652) (xy 396.891885 -10.41905) (xy 396.903956 -10.418572)
			(xy 398.185386 -10.418572) (xy 398.197478 -10.41902) (xy 398.220484 -10.426477) (xy 398.240066 -10.440667)
			(xy 398.254316 -10.460207) (xy 398.261843 -10.483189) (xy 398.262348 -10.49528) (xy 398.262348 -11.91768)
			(xy 398.627092 -11.91768) (xy 398.627092 -10.49528) (xy 398.627499 -10.483171) (xy 398.635003 -10.460144)
			(xy 398.649267 -10.440572) (xy 398.66889 -10.426378) (xy 398.691943 -10.418956) (xy 398.704054 -10.418572)
			(xy 399.985484 -10.418572) (xy 399.997556 -10.419078) (xy 400.020519 -10.426533) (xy 400.040055 -10.44072)
			(xy 400.05425 -10.460249) (xy 400.061717 -10.483208) (xy 400.062192 -10.49528) (xy 400.062192 -11.91768)
			(xy 400.426936 -11.91768) (xy 400.426936 -10.49528) (xy 400.4273 -10.483166) (xy 400.434809 -10.460132)
			(xy 400.449083 -10.440556) (xy 400.468718 -10.426364) (xy 400.491783 -10.41895) (xy 400.503898 -10.418572)
			(xy 401.785328 -10.418572) (xy 401.797402 -10.41904) (xy 401.820367 -10.426508) (xy 401.839902 -10.440704)
			(xy 401.854096 -10.46024) (xy 401.861561 -10.483206) (xy 401.862036 -10.49528) (xy 401.862036 -11.91768)
			(xy 402.227288 -11.91768) (xy 402.227288 -10.49528) (xy 402.227747 -10.483205) (xy 402.235215 -10.460238)
			(xy 402.249413 -10.440701) (xy 402.268952 -10.426507) (xy 402.291921 -10.419045) (xy 402.303996 -10.418572)
			(xy 403.585426 -10.418572) (xy 403.59752 -10.418986) (xy 403.620527 -10.426453) (xy 403.640109 -10.440653)
			(xy 403.654358 -10.460199) (xy 403.661884 -10.483187) (xy 403.662388 -10.49528) (xy 403.662388 -11.91768)
			(xy 404.027132 -11.91768) (xy 404.027132 -10.49528) (xy 404.027496 -10.483192) (xy 404.034974 -10.460202)
			(xy 404.049191 -10.440649) (xy 404.068756 -10.426447) (xy 404.091752 -10.418987) (xy 404.10384 -10.418572)
			(xy 405.38527 -10.418572) (xy 405.397361 -10.419034) (xy 405.420366 -10.426486) (xy 405.439949 -10.440673)
			(xy 405.4542 -10.46021) (xy 405.461727 -10.48319) (xy 405.462232 -10.49528) (xy 405.462232 -11.91768)
			(xy 405.826976 -11.91768) (xy 405.826976 -10.49528) (xy 405.827399 -10.483172) (xy 405.834901 -10.460149)
			(xy 405.849162 -10.440578) (xy 405.86878 -10.426383) (xy 405.891829 -10.418959) (xy 405.903938 -10.418572)
			(xy 407.185368 -10.418572) (xy 407.197447 -10.41904) (xy 407.220425 -10.426496) (xy 407.239974 -10.440689)
			(xy 407.25418 -10.460228) (xy 407.261652 -10.483201) (xy 407.262076 -10.49528) (xy 407.262076 -11.91768)
			(xy 413.137096 -11.91768) (xy 413.137096 -10.49528) (xy 413.137499 -10.48317) (xy 413.145004 -10.460143)
			(xy 413.159269 -10.440571) (xy 413.178893 -10.426377) (xy 413.201947 -10.418956) (xy 413.214058 -10.418572)
			(xy 414.495488 -10.418572) (xy 414.50756 -10.419074) (xy 414.530523 -10.426531) (xy 414.550059 -10.440718)
			(xy 414.564254 -10.460248) (xy 414.571721 -10.483208) (xy 414.572196 -10.49528) (xy 414.572196 -11.91768)
			(xy 414.937448 -11.91768) (xy 414.937448 -10.49528) (xy 414.937947 -10.483209) (xy 414.945409 -10.460248)
			(xy 414.959599 -10.440716) (xy 414.979127 -10.42652) (xy 415.002085 -10.41905) (xy 415.014156 -10.418572)
			(xy 416.295586 -10.418572) (xy 416.307678 -10.41902) (xy 416.330684 -10.426477) (xy 416.350266 -10.440667)
			(xy 416.364516 -10.460207) (xy 416.372043 -10.483189) (xy 416.372548 -10.49528) (xy 416.372548 -11.91768)
			(xy 416.737292 -11.91768) (xy 416.737292 -10.49528) (xy 416.737747 -10.483204) (xy 416.745215 -10.460237)
			(xy 416.759414 -10.4407) (xy 416.778955 -10.426506) (xy 416.801924 -10.419044) (xy 416.814 -10.418572)
			(xy 418.09543 -10.418572) (xy 418.107524 -10.418982) (xy 418.130531 -10.426451) (xy 418.150114 -10.440651)
			(xy 418.164362 -10.460198) (xy 418.171888 -10.483187) (xy 418.172392 -10.49528) (xy 418.172392 -11.91768)
			(xy 418.537136 -11.91768) (xy 418.537136 -10.49528) (xy 418.5375 -10.483166) (xy 418.545009 -10.460132)
			(xy 418.559283 -10.440556) (xy 418.578918 -10.426364) (xy 418.601983 -10.41895) (xy 418.614098 -10.418572)
			(xy 419.895528 -10.418572) (xy 419.907602 -10.41904) (xy 419.930567 -10.426508) (xy 419.950102 -10.440704)
			(xy 419.964296 -10.46024) (xy 419.971761 -10.483206) (xy 419.972236 -10.49528) (xy 419.972236 -11.91768)
			(xy 424.347132 -11.91768) (xy 424.347132 -10.49528) (xy 424.3475 -10.483167) (xy 424.355008 -10.460133)
			(xy 424.369281 -10.440558) (xy 424.388915 -10.426365) (xy 424.411979 -10.418951) (xy 424.424094 -10.418572)
			(xy 425.705524 -10.418572) (xy 425.717598 -10.419044) (xy 425.740562 -10.42651) (xy 425.760097 -10.440706)
			(xy 425.774292 -10.460241) (xy 425.781757 -10.483206) (xy 425.782232 -10.49528) (xy 425.782232 -11.91768)
			(xy 426.147484 -11.91768) (xy 426.147484 -10.49528) (xy 426.147947 -10.483205) (xy 426.155414 -10.460239)
			(xy 426.169611 -10.440703) (xy 426.18915 -10.426509) (xy 426.212117 -10.419045) (xy 426.224192 -10.418572)
			(xy 427.505622 -10.418572) (xy 427.517716 -10.418989) (xy 427.540723 -10.426456) (xy 427.560305 -10.440654)
			(xy 427.574554 -10.4602) (xy 427.58208 -10.483187) (xy 427.582584 -10.49528) (xy 427.582584 -11.91768)
			(xy 427.947328 -11.91768) (xy 427.947328 -10.49528) (xy 427.947696 -10.483193) (xy 427.955174 -10.460203)
			(xy 427.96939 -10.44065) (xy 427.988953 -10.426448) (xy 428.011948 -10.418987) (xy 428.024036 -10.418572)
			(xy 429.305466 -10.418572) (xy 429.317557 -10.419037) (xy 429.340562 -10.426488) (xy 429.360145 -10.440674)
			(xy 429.374396 -10.46021) (xy 429.381923 -10.483191) (xy 429.382428 -10.49528) (xy 429.382428 -11.91768)
			(xy 429.747172 -11.91768) (xy 429.747172 -10.49528) (xy 429.747599 -10.483173) (xy 429.7551 -10.46015)
			(xy 429.76936 -10.440579) (xy 429.788978 -10.426384) (xy 429.812026 -10.418959) (xy 429.824134 -10.418572)
			(xy 431.105564 -10.418572) (xy 431.117643 -10.419043) (xy 431.140621 -10.426498) (xy 431.16017 -10.44069)
			(xy 431.174376 -10.460229) (xy 431.181848 -10.483201) (xy 431.182272 -10.49528) (xy 431.182272 -11.91768)
			(xy 431.18187 -11.929765) (xy 431.174403 -11.952753) (xy 431.160196 -11.972307) (xy 431.140639 -11.986511)
			(xy 431.117649 -11.993972) (xy 431.105564 -11.994388) (xy 429.824134 -11.994388) (xy 429.812049 -11.993864)
			(xy 429.789054 -11.98642) (xy 429.769476 -11.972247) (xy 429.755223 -11.952727) (xy 429.747686 -11.929763)
			(xy 429.747172 -11.91768) (xy 429.382428 -11.91768) (xy 429.381967 -11.929785) (xy 429.374476 -11.952807)
			(xy 429.360225 -11.972378) (xy 429.340615 -11.986574) (xy 429.317572 -11.994) (xy 429.305466 -11.994388)
			(xy 428.024036 -11.994388) (xy 428.011953 -11.993956) (xy 427.988968 -11.986496) (xy 427.969416 -11.972296)
			(xy 427.955211 -11.952746) (xy 427.947746 -11.929763) (xy 427.947328 -11.91768) (xy 427.582584 -11.91768)
			(xy 427.582166 -11.929789) (xy 427.57467 -11.952819) (xy 427.56041 -11.972393) (xy 427.540787 -11.986588)
			(xy 427.517733 -11.994007) (xy 427.505622 -11.994388) (xy 426.224192 -11.994388) (xy 426.212107 -11.993994)
			(xy 426.18912 -11.986522) (xy 426.169569 -11.972312) (xy 426.155365 -11.952754) (xy 426.147902 -11.929765)
			(xy 426.147484 -11.91768) (xy 425.782232 -11.91768) (xy 425.781719 -11.929751) (xy 425.774265 -11.952714)
			(xy 425.76008 -11.972249) (xy 425.740553 -11.986445) (xy 425.717595 -11.993912) (xy 425.705524 -11.994388)
			(xy 424.424094 -11.994388) (xy 424.412007 -11.993898) (xy 424.389011 -11.986443) (xy 424.369434 -11.972261)
			(xy 424.355182 -11.952735) (xy 424.347645 -11.929765) (xy 424.347132 -11.91768) (xy 419.972236 -11.91768)
			(xy 419.971719 -11.929751) (xy 419.964266 -11.952713) (xy 419.950082 -11.972248) (xy 419.930556 -11.986444)
			(xy 419.907598 -11.993912) (xy 419.895528 -11.994388) (xy 418.614098 -11.994388) (xy 418.602011 -11.993895)
			(xy 418.579015 -11.986441) (xy 418.559438 -11.97226) (xy 418.545186 -11.952734) (xy 418.537649 -11.929765)
			(xy 418.537136 -11.91768) (xy 418.172392 -11.91768) (xy 418.171966 -11.929789) (xy 418.164472 -11.952817)
			(xy 418.150213 -11.972391) (xy 418.130592 -11.986586) (xy 418.10754 -11.994005) (xy 418.09543 -11.994388)
			(xy 416.814 -11.994388) (xy 416.801915 -11.993987) (xy 416.778929 -11.986517) (xy 416.759377 -11.972309)
			(xy 416.745174 -11.952753) (xy 416.73771 -11.929765) (xy 416.737292 -11.91768) (xy 416.372548 -11.91768)
			(xy 416.372067 -11.929783) (xy 416.364579 -11.952801) (xy 416.350332 -11.972371) (xy 416.330727 -11.986568)
			(xy 416.30769 -11.993997) (xy 416.295586 -11.994388) (xy 415.014156 -11.994388) (xy 415.002077 -11.993973)
			(xy 414.979105 -11.986496) (xy 414.959567 -11.972287) (xy 414.945375 -11.952738) (xy 414.937917 -11.929759)
			(xy 414.937448 -11.91768) (xy 414.572196 -11.91768) (xy 414.57177 -11.929763) (xy 414.564306 -11.952747)
			(xy 414.550104 -11.972299) (xy 414.530554 -11.986503) (xy 414.507571 -11.993969) (xy 414.495488 -11.994388)
			(xy 413.214058 -11.994388) (xy 413.201969 -11.993929) (xy 413.178972 -11.986464) (xy 413.159395 -11.972274)
			(xy 413.145145 -11.952742) (xy 413.137609 -11.929767) (xy 413.137096 -11.91768) (xy 407.262076 -11.91768)
			(xy 407.26167 -11.929765) (xy 407.254204 -11.952752) (xy 407.239997 -11.972306) (xy 407.220442 -11.986509)
			(xy 407.197453 -11.993972) (xy 407.185368 -11.994388) (xy 405.903938 -11.994388) (xy 405.891853 -11.993861)
			(xy 405.868858 -11.986418) (xy 405.84928 -11.972246) (xy 405.835028 -11.952726) (xy 405.82749 -11.929763)
			(xy 405.826976 -11.91768) (xy 405.462232 -11.91768) (xy 405.461767 -11.929785) (xy 405.454277 -11.952806)
			(xy 405.440027 -11.972376) (xy 405.420417 -11.986573) (xy 405.397376 -11.994) (xy 405.38527 -11.994388)
			(xy 404.10384 -11.994388) (xy 404.091757 -11.993953) (xy 404.068773 -11.986494) (xy 404.04922 -11.972294)
			(xy 404.035015 -11.952745) (xy 404.02755 -11.929763) (xy 404.027132 -11.91768) (xy 403.662388 -11.91768)
			(xy 403.661966 -11.929789) (xy 403.654471 -11.952818) (xy 403.640211 -11.972392) (xy 403.62059 -11.986587)
			(xy 403.597536 -11.994006) (xy 403.585426 -11.994388) (xy 402.303996 -11.994388) (xy 402.291911 -11.993991)
			(xy 402.268925 -11.98652) (xy 402.249373 -11.97231) (xy 402.235169 -11.952754) (xy 402.227706 -11.929765)
			(xy 402.227288 -11.91768) (xy 401.862036 -11.91768) (xy 401.861519 -11.929751) (xy 401.854066 -11.952713)
			(xy 401.839882 -11.972248) (xy 401.820356 -11.986444) (xy 401.797398 -11.993912) (xy 401.785328 -11.994388)
			(xy 400.503898 -11.994388) (xy 400.491811 -11.993895) (xy 400.468815 -11.986441) (xy 400.449238 -11.97226)
			(xy 400.434986 -11.952734) (xy 400.427449 -11.929765) (xy 400.426936 -11.91768) (xy 400.062192 -11.91768)
			(xy 400.06177 -11.929763) (xy 400.054306 -11.952748) (xy 400.040103 -11.9723) (xy 400.020552 -11.986504)
			(xy 399.997567 -11.993969) (xy 399.985484 -11.994388) (xy 398.704054 -11.994388) (xy 398.691965 -11.993932)
			(xy 398.668967 -11.986466) (xy 398.649391 -11.972276) (xy 398.635141 -11.952742) (xy 398.627605 -11.929768)
			(xy 398.627092 -11.91768) (xy 398.262348 -11.91768) (xy 398.261867 -11.929783) (xy 398.254379 -11.952801)
			(xy 398.240132 -11.972371) (xy 398.220527 -11.986568) (xy 398.19749 -11.993997) (xy 398.185386 -11.994388)
			(xy 396.903956 -11.994388) (xy 396.891877 -11.993973) (xy 396.868905 -11.986496) (xy 396.849367 -11.972287)
			(xy 396.835175 -11.952738) (xy 396.827717 -11.929759) (xy 396.827248 -11.91768) (xy 396.462504 -11.91768)
			(xy 396.462067 -11.929787) (xy 396.454573 -11.952813) (xy 396.440317 -11.972386) (xy 396.4207 -11.986582)
			(xy 396.397651 -11.994004) (xy 396.385542 -11.994388) (xy 395.104112 -11.994388) (xy 395.092028 -11.993977)
			(xy 395.069042 -11.98651) (xy 395.04949 -11.972304) (xy 395.035286 -11.952751) (xy 395.027822 -11.929764)
			(xy 395.027404 -11.91768) (xy 394.662152 -11.91768) (xy 394.661619 -11.929749) (xy 394.654168 -11.952708)
			(xy 394.639987 -11.972242) (xy 394.620466 -11.986439) (xy 394.597513 -11.993909) (xy 394.585444 -11.994388)
			(xy 393.304014 -11.994388) (xy 393.291928 -11.993881) (xy 393.268933 -11.986432) (xy 393.249355 -11.972254)
			(xy 393.235103 -11.952731) (xy 393.227566 -11.929764) (xy 393.227052 -11.91768) (xy 386.914842 -11.91768)
			(xy 386.876988 -11.941465) (xy 386.753787 -12.009554) (xy 386.626963 -12.070627) (xy 386.496913 -12.124494)
			(xy 386.364048 -12.170984) (xy 386.228785 -12.209951) (xy 386.091551 -12.241273) (xy 385.952775 -12.26485)
			(xy 385.812896 -12.280609) (xy 385.672354 -12.2885) (xy 385.601972 -12.289028) (xy 260.800088 -12.289028)
			(xy 260.744319 -12.28955) (xy 260.633094 -12.297886) (xy 260.522803 -12.314511) (xy 260.414062 -12.339331)
			(xy 260.30748 -12.372208) (xy 260.203654 -12.412958) (xy 260.103162 -12.461353) (xy 260.006569 -12.517122)
			(xy 259.914413 -12.579954) (xy 259.82721 -12.649497) (xy 259.745448 -12.725362) (xy 259.669584 -12.807125)
			(xy 259.601847 -12.892065) (xy 431.46197 -12.892065) (xy 431.46197 -12.837535) (xy 431.46973 -12.783559)
			(xy 431.485093 -12.731238) (xy 431.507745 -12.681635) (xy 431.537225 -12.635761) (xy 431.572934 -12.594548)
			(xy 431.614145 -12.558837) (xy 431.660017 -12.529355) (xy 431.709619 -12.5067) (xy 431.76194 -12.491335)
			(xy 431.815915 -12.483572) (xy 431.84318 -12.483084) (xy 432.70678 -12.483084) (xy 432.734055 -12.483454)
			(xy 432.788051 -12.491215) (xy 432.840392 -12.506581) (xy 432.890014 -12.529241) (xy 432.935905 -12.558731)
			(xy 432.977133 -12.594453) (xy 433.012857 -12.635678) (xy 433.04235 -12.681569) (xy 433.065012 -12.731189)
			(xy 433.080381 -12.78353) (xy 433.088144 -12.837525) (xy 433.088144 -12.864846) (xy 445.45631 -12.864846)
			(xy 445.45631 -12.864592) (xy 445.456564 -12.850622) (xy 445.45717 -12.823469) (xy 445.46523 -12.769758)
			(xy 445.48082 -12.717731) (xy 445.503625 -12.668439) (xy 445.533186 -12.622876) (xy 445.568905 -12.581962)
			(xy 445.610062 -12.546522) (xy 445.655826 -12.517273) (xy 445.705273 -12.494804) (xy 445.757405 -12.47957)
			(xy 445.81117 -12.471876) (xy 445.838326 -12.4714) (xy 446.701926 -12.4714) (xy 446.72908 -12.471883)
			(xy 446.782838 -12.479582) (xy 446.834964 -12.494821) (xy 446.884404 -12.517293) (xy 446.93016 -12.546543)
			(xy 446.971311 -12.581982) (xy 447.007024 -12.622895) (xy 447.03658 -12.668455) (xy 447.059381 -12.717744)
			(xy 447.074968 -12.769766) (xy 447.083027 -12.823472) (xy 447.083688 -12.850622) (xy 447.083942 -12.864592)
			(xy 447.083942 -12.864846) (xy 447.083472 -12.892133) (xy 447.0757 -12.946152) (xy 447.06032 -12.998515)
			(xy 447.037645 -13.048157) (xy 447.008137 -13.094067) (xy 446.972397 -13.135311) (xy 446.931151 -13.171049)
			(xy 446.885239 -13.200555) (xy 446.835597 -13.223227) (xy 446.783233 -13.238604) (xy 446.729214 -13.246374)
			(xy 446.701926 -13.246862) (xy 446.679426 -13.246581) (xy 446.634732 -13.241355) (xy 446.612772 -13.236448)
			(xy 446.60693 -13.234924) (xy 445.933322 -13.234924) (xy 445.92748 -13.236448) (xy 445.905519 -13.241348)
			(xy 445.860825 -13.246566) (xy 445.838326 -13.246862) (xy 445.811041 -13.246305) (xy 445.757027 -13.238543)
			(xy 445.704666 -13.223173) (xy 445.655026 -13.200508) (xy 445.609117 -13.17101) (xy 445.567873 -13.135278)
			(xy 445.532133 -13.094041) (xy 445.502626 -13.048137) (xy 445.479952 -12.998501) (xy 445.464572 -12.946144)
			(xy 445.4568 -12.892131) (xy 445.45631 -12.864846) (xy 433.088144 -12.864846) (xy 433.088144 -12.892075)
			(xy 433.080381 -12.94607) (xy 433.065012 -12.998411) (xy 433.04235 -13.048031) (xy 433.012857 -13.093921)
			(xy 432.977133 -13.135147) (xy 432.935905 -13.170869) (xy 432.890014 -13.200359) (xy 432.840392 -13.223019)
			(xy 432.788051 -13.238385) (xy 432.734055 -13.246146) (xy 432.70678 -13.246608) (xy 431.84318 -13.246608)
			(xy 431.815915 -13.246028) (xy 431.76194 -13.238265) (xy 431.709619 -13.2229) (xy 431.660017 -13.200245)
			(xy 431.614145 -13.170763) (xy 431.572934 -13.135052) (xy 431.537225 -13.093839) (xy 431.507745 -13.047965)
			(xy 431.485093 -12.998362) (xy 431.46973 -12.946041) (xy 431.46197 -12.892065) (xy 259.601847 -12.892065)
			(xy 259.600042 -12.894329) (xy 259.537211 -12.986486) (xy 259.481443 -13.08308) (xy 259.43305 -13.183572)
			(xy 259.392301 -13.287399) (xy 259.359426 -13.393981) (xy 259.334607 -13.502722) (xy 259.317984 -13.613014)
			(xy 259.309649 -13.724239) (xy 259.309108 -13.780008) (xy 259.309108 -14.79042) (xy 387.011672 -14.79042)
			(xy 387.011672 -13.72108) (xy 387.012313 -13.708702) (xy 387.018874 -13.684809) (xy 387.031074 -13.663243)
			(xy 387.039358 -13.654024) (xy 387.049034 -13.644631) (xy 387.072242 -13.630921) (xy 387.098268 -13.623899)
			(xy 387.111748 -13.623544) (xy 387.41858 -13.623544) (xy 387.43297 -13.624792) (xy 387.460202 -13.634363)
			(xy 387.483533 -13.651358) (xy 387.500993 -13.674344) (xy 387.511107 -13.701378) (xy 387.51256 -13.715746)
			(xy 387.51256 -14.78534) (xy 387.512298 -14.79042) (xy 388.027672 -14.79042) (xy 388.027672 -13.72108)
			(xy 388.028313 -13.708702) (xy 388.034874 -13.684809) (xy 388.047074 -13.663243) (xy 388.055358 -13.654024)
			(xy 388.065034 -13.644631) (xy 388.088242 -13.630921) (xy 388.114268 -13.623899) (xy 388.127748 -13.623544)
			(xy 388.43458 -13.623544) (xy 388.44897 -13.624792) (xy 388.476202 -13.634363) (xy 388.499533 -13.651358)
			(xy 388.516993 -13.674344) (xy 388.527107 -13.701378) (xy 388.52856 -13.715746) (xy 388.52856 -14.78534)
			(xy 388.527921 -14.797718) (xy 388.521358 -14.821611) (xy 388.509158 -14.843177) (xy 388.500874 -14.852396)
			(xy 388.491188 -14.861777) (xy 388.467984 -14.87549) (xy 388.441963 -14.882517) (xy 388.428484 -14.882876)
			(xy 388.121652 -14.882876) (xy 388.107919 -14.881684) (xy 388.081829 -14.872836) (xy 388.059168 -14.85717)
			(xy 388.041675 -14.835886) (xy 388.030694 -14.81062) (xy 388.028434 -14.797024) (xy 388.027672 -14.79042)
			(xy 387.512298 -14.79042) (xy 387.511921 -14.797718) (xy 387.505358 -14.821611) (xy 387.493158 -14.843177)
			(xy 387.484874 -14.852396) (xy 387.475188 -14.861777) (xy 387.451984 -14.87549) (xy 387.425963 -14.882517)
			(xy 387.412484 -14.882876) (xy 387.105652 -14.882876) (xy 387.091919 -14.881684) (xy 387.065829 -14.872836)
			(xy 387.043168 -14.85717) (xy 387.025675 -14.835886) (xy 387.014694 -14.81062) (xy 387.012434 -14.797024)
			(xy 387.011672 -14.79042) (xy 259.309108 -14.79042) (xy 259.309108 -16.431514) (xy 389.823452 -16.431514)
			(xy 389.823452 -15.745714) (xy 389.823872 -15.733591) (xy 389.831362 -15.71053) (xy 389.845613 -15.690913)
			(xy 389.86523 -15.676662) (xy 389.888291 -15.669172) (xy 389.900414 -15.668752) (xy 390.094978 -15.668752)
			(xy 390.106102 -15.66919) (xy 390.127399 -15.675633) (xy 390.136888 -15.681452) (xy 390.430512 -15.873984)
			(xy 390.439879 -15.879719) (xy 390.460899 -15.88605) (xy 390.482853 -15.886115) (xy 390.503911 -15.879909)
			(xy 390.513316 -15.874238) (xy 390.80948 -15.681452) (xy 390.818986 -15.675666) (xy 390.840271 -15.669202)
			(xy 390.85139 -15.668752) (xy 391.045954 -15.668752) (xy 391.058076 -15.669199) (xy 391.081136 -15.676681)
			(xy 391.100753 -15.690925) (xy 391.115005 -15.710536) (xy 391.122496 -15.733592) (xy 391.122916 -15.745714)
			(xy 391.122916 -16.431514) (xy 395.411452 -16.431514) (xy 395.411452 -15.745714) (xy 395.411872 -15.733591)
			(xy 395.419362 -15.71053) (xy 395.433613 -15.690913) (xy 395.45323 -15.676662) (xy 395.476291 -15.669172)
			(xy 395.488414 -15.668752) (xy 395.682978 -15.668752) (xy 395.694102 -15.66919) (xy 395.715399 -15.675633)
			(xy 395.724888 -15.681452) (xy 396.018512 -15.873984) (xy 396.027879 -15.879719) (xy 396.048899 -15.88605)
			(xy 396.070853 -15.886115) (xy 396.091911 -15.879909) (xy 396.101316 -15.874238) (xy 396.39748 -15.681452)
			(xy 396.406986 -15.675666) (xy 396.428271 -15.669202) (xy 396.43939 -15.668752) (xy 396.633954 -15.668752)
			(xy 396.646076 -15.669199) (xy 396.669136 -15.676681) (xy 396.688753 -15.690925) (xy 396.703005 -15.710536)
			(xy 396.710496 -15.733592) (xy 396.710916 -15.745714) (xy 396.710916 -16.431514) (xy 400.999452 -16.431514)
			(xy 400.999452 -15.745714) (xy 400.999872 -15.733591) (xy 401.007362 -15.71053) (xy 401.021613 -15.690913)
			(xy 401.04123 -15.676662) (xy 401.064291 -15.669172) (xy 401.076414 -15.668752) (xy 401.270978 -15.668752)
			(xy 401.282102 -15.66919) (xy 401.303399 -15.675633) (xy 401.312888 -15.681452) (xy 401.606512 -15.873984)
			(xy 401.615879 -15.879719) (xy 401.636899 -15.88605) (xy 401.658853 -15.886115) (xy 401.679911 -15.879909)
			(xy 401.689316 -15.874238) (xy 401.98548 -15.681452) (xy 401.994986 -15.675666) (xy 402.016271 -15.669202)
			(xy 402.02739 -15.668752) (xy 402.221954 -15.668752) (xy 402.234076 -15.669199) (xy 402.257136 -15.676681)
			(xy 402.276753 -15.690925) (xy 402.291005 -15.710536) (xy 402.298496 -15.733592) (xy 402.298916 -15.745714)
			(xy 402.298916 -16.431514) (xy 406.587452 -16.431514) (xy 406.587452 -15.745714) (xy 406.587872 -15.733591)
			(xy 406.595362 -15.71053) (xy 406.609613 -15.690913) (xy 406.62923 -15.676662) (xy 406.652291 -15.669172)
			(xy 406.664414 -15.668752) (xy 406.858978 -15.668752) (xy 406.870102 -15.66919) (xy 406.891399 -15.675633)
			(xy 406.900888 -15.681452) (xy 407.194512 -15.873984) (xy 407.203879 -15.879719) (xy 407.224899 -15.88605)
			(xy 407.246853 -15.886115) (xy 407.267911 -15.879909) (xy 407.277316 -15.874238) (xy 407.57348 -15.681452)
			(xy 407.582986 -15.675666) (xy 407.604271 -15.669202) (xy 407.61539 -15.668752) (xy 407.809954 -15.668752)
			(xy 407.822076 -15.669199) (xy 407.845136 -15.676681) (xy 407.864753 -15.690925) (xy 407.879005 -15.710536)
			(xy 407.886496 -15.733592) (xy 407.886916 -15.745714) (xy 407.886916 -16.431514) (xy 412.175452 -16.431514)
			(xy 412.175452 -15.745714) (xy 412.175872 -15.733591) (xy 412.183362 -15.71053) (xy 412.197613 -15.690913)
			(xy 412.21723 -15.676662) (xy 412.240291 -15.669172) (xy 412.252414 -15.668752) (xy 412.446978 -15.668752)
			(xy 412.458102 -15.66919) (xy 412.479399 -15.675633) (xy 412.488888 -15.681452) (xy 412.782512 -15.873984)
			(xy 412.791879 -15.879719) (xy 412.812899 -15.88605) (xy 412.834853 -15.886115) (xy 412.855911 -15.879909)
			(xy 412.865316 -15.874238) (xy 413.16148 -15.681452) (xy 413.170986 -15.675666) (xy 413.192271 -15.669202)
			(xy 413.20339 -15.668752) (xy 413.397954 -15.668752) (xy 413.410076 -15.669199) (xy 413.433136 -15.676681)
			(xy 413.452753 -15.690925) (xy 413.467005 -15.710536) (xy 413.474496 -15.733592) (xy 413.474916 -15.745714)
			(xy 413.474916 -16.431514) (xy 418.069268 -16.431514) (xy 418.069268 -15.745714) (xy 418.069672 -15.733589)
			(xy 418.077164 -15.710526) (xy 418.091419 -15.690908) (xy 418.11104 -15.676657) (xy 418.134105 -15.66917)
			(xy 418.14623 -15.668752) (xy 418.340794 -15.668752) (xy 418.351918 -15.669184) (xy 418.373215 -15.675631)
			(xy 418.382704 -15.681452) (xy 418.676328 -15.873984) (xy 418.685687 -15.879732) (xy 418.706711 -15.88606)
			(xy 418.728667 -15.886122) (xy 418.749727 -15.879912) (xy 418.759132 -15.874238) (xy 419.055296 -15.681452)
			(xy 419.064799 -15.67566) (xy 419.086086 -15.6692) (xy 419.097206 -15.668752) (xy 419.29177 -15.668752)
			(xy 419.303893 -15.669186) (xy 419.326953 -15.676671) (xy 419.34657 -15.690919) (xy 419.360821 -15.710533)
			(xy 419.368312 -15.733592) (xy 419.368732 -15.745714) (xy 419.368732 -16.431514) (xy 423.657268 -16.431514)
			(xy 423.657268 -15.745714) (xy 423.657672 -15.733589) (xy 423.665164 -15.710526) (xy 423.679419 -15.690908)
			(xy 423.69904 -15.676657) (xy 423.722105 -15.66917) (xy 423.73423 -15.668752) (xy 423.928794 -15.668752)
			(xy 423.939918 -15.669184) (xy 423.961215 -15.675631) (xy 423.970704 -15.681452) (xy 424.264328 -15.873984)
			(xy 424.273687 -15.879732) (xy 424.294711 -15.88606) (xy 424.316667 -15.886122) (xy 424.337727 -15.879912)
			(xy 424.347132 -15.874238) (xy 424.643296 -15.681452) (xy 424.652799 -15.67566) (xy 424.674086 -15.6692)
			(xy 424.685206 -15.668752) (xy 424.87977 -15.668752) (xy 424.891893 -15.669186) (xy 424.914953 -15.676671)
			(xy 424.93457 -15.690919) (xy 424.948821 -15.710533) (xy 424.956312 -15.733592) (xy 424.956732 -15.745714)
			(xy 424.956732 -16.431514) (xy 429.279304 -16.431514) (xy 429.279304 -15.745714) (xy 429.279823 -15.733604)
			(xy 429.287302 -15.710567) (xy 429.301533 -15.690968) (xy 429.321124 -15.676724) (xy 429.344156 -15.669231)
			(xy 429.356266 -15.668752) (xy 429.55083 -15.668752) (xy 429.561955 -15.669169) (xy 429.583252 -15.675626)
			(xy 429.59274 -15.681452) (xy 429.886364 -15.873984) (xy 429.895753 -15.879677) (xy 429.916763 -15.886018)
			(xy 429.938709 -15.886095) (xy 429.959763 -15.879902) (xy 429.969168 -15.874238) (xy 430.265332 -15.681452)
			(xy 430.274828 -15.675647) (xy 430.296121 -15.669195) (xy 430.307242 -15.668752) (xy 430.501806 -15.668752)
			(xy 430.51393 -15.669155) (xy 430.536992 -15.676651) (xy 430.556608 -15.690906) (xy 430.570858 -15.710526)
			(xy 430.578348 -15.733589) (xy 430.578768 -15.745714) (xy 430.578768 -16.431514) (xy 430.5783 -16.443629)
			(xy 430.57081 -16.466671) (xy 430.556567 -16.486273) (xy 430.536964 -16.500514) (xy 430.513921 -16.508002)
			(xy 430.501806 -16.508476) (xy 430.307242 -16.508476) (xy 430.296116 -16.508066) (xy 430.274819 -16.501604)
			(xy 430.265332 -16.495776) (xy 429.970438 -16.303244) (xy 429.961051 -16.297541) (xy 429.940013 -16.291268)
			(xy 429.918059 -16.291268) (xy 429.897021 -16.297541) (xy 429.887634 -16.303244) (xy 429.59401 -16.495776)
			(xy 429.584507 -16.501568) (xy 429.56322 -16.508028) (xy 429.5521 -16.508476) (xy 429.356266 -16.508476)
			(xy 429.344151 -16.508018) (xy 429.321109 -16.500523) (xy 429.301509 -16.486277) (xy 429.287268 -16.466673)
			(xy 429.279779 -16.443629) (xy 429.279304 -16.431514) (xy 424.956732 -16.431514) (xy 424.956351 -16.44364)
			(xy 424.948852 -16.466705) (xy 424.934591 -16.486322) (xy 424.914965 -16.500572) (xy 424.891897 -16.508058)
			(xy 424.87977 -16.508476) (xy 424.685206 -16.508476) (xy 424.674082 -16.50804) (xy 424.652785 -16.501596)
			(xy 424.643296 -16.495776) (xy 424.348402 -16.303244) (xy 424.339015 -16.297541) (xy 424.317977 -16.291268)
			(xy 424.296023 -16.291268) (xy 424.274985 -16.297541) (xy 424.265598 -16.303244) (xy 423.971974 -16.495776)
			(xy 423.962478 -16.501581) (xy 423.941185 -16.508033) (xy 423.930064 -16.508476) (xy 423.73423 -16.508476)
			(xy 423.72211 -16.508015) (xy 423.699055 -16.500532) (xy 423.67944 -16.486291) (xy 423.665188 -16.466685)
			(xy 423.657692 -16.443634) (xy 423.657268 -16.431514) (xy 419.368732 -16.431514) (xy 419.368351 -16.44364)
			(xy 419.360852 -16.466705) (xy 419.346591 -16.486322) (xy 419.326965 -16.500572) (xy 419.303897 -16.508058)
			(xy 419.29177 -16.508476) (xy 419.097206 -16.508476) (xy 419.086082 -16.50804) (xy 419.064785 -16.501596)
			(xy 419.055296 -16.495776) (xy 418.760402 -16.303244) (xy 418.751015 -16.297541) (xy 418.729977 -16.291268)
			(xy 418.708023 -16.291268) (xy 418.686985 -16.297541) (xy 418.677598 -16.303244) (xy 418.383974 -16.495776)
			(xy 418.374478 -16.501581) (xy 418.353185 -16.508033) (xy 418.342064 -16.508476) (xy 418.14623 -16.508476)
			(xy 418.13411 -16.508015) (xy 418.111055 -16.500532) (xy 418.09144 -16.486291) (xy 418.077188 -16.466685)
			(xy 418.069692 -16.443634) (xy 418.069268 -16.431514) (xy 413.474916 -16.431514) (xy 413.474551 -16.443642)
			(xy 413.467049 -16.466709) (xy 413.452785 -16.486328) (xy 413.433155 -16.500577) (xy 413.410082 -16.50806)
			(xy 413.397954 -16.508476) (xy 413.20339 -16.508476) (xy 413.192266 -16.508047) (xy 413.170969 -16.501598)
			(xy 413.16148 -16.495776) (xy 412.866586 -16.303244) (xy 412.857199 -16.297541) (xy 412.836161 -16.291268)
			(xy 412.814207 -16.291268) (xy 412.793169 -16.297541) (xy 412.783782 -16.303244) (xy 412.490158 -16.495776)
			(xy 412.480665 -16.501587) (xy 412.45937 -16.508035) (xy 412.448248 -16.508476) (xy 412.252414 -16.508476)
			(xy 412.240302 -16.507976) (xy 412.217261 -16.500495) (xy 412.19766 -16.486259) (xy 412.183418 -16.466664)
			(xy 412.175928 -16.443626) (xy 412.175452 -16.431514) (xy 407.886916 -16.431514) (xy 407.886551 -16.443642)
			(xy 407.879049 -16.466709) (xy 407.864785 -16.486328) (xy 407.845155 -16.500577) (xy 407.822082 -16.50806)
			(xy 407.809954 -16.508476) (xy 407.61539 -16.508476) (xy 407.604266 -16.508047) (xy 407.582969 -16.501598)
			(xy 407.57348 -16.495776) (xy 407.278586 -16.303244) (xy 407.269199 -16.297541) (xy 407.248161 -16.291268)
			(xy 407.226207 -16.291268) (xy 407.205169 -16.297541) (xy 407.195782 -16.303244) (xy 406.902158 -16.495776)
			(xy 406.892665 -16.501587) (xy 406.87137 -16.508035) (xy 406.860248 -16.508476) (xy 406.664414 -16.508476)
			(xy 406.652302 -16.507976) (xy 406.629261 -16.500495) (xy 406.60966 -16.486259) (xy 406.595418 -16.466664)
			(xy 406.587928 -16.443626) (xy 406.587452 -16.431514) (xy 402.298916 -16.431514) (xy 402.298551 -16.443642)
			(xy 402.291049 -16.466709) (xy 402.276785 -16.486328) (xy 402.257155 -16.500577) (xy 402.234082 -16.50806)
			(xy 402.221954 -16.508476) (xy 402.02739 -16.508476) (xy 402.016266 -16.508047) (xy 401.994969 -16.501598)
			(xy 401.98548 -16.495776) (xy 401.690586 -16.303244) (xy 401.681199 -16.297541) (xy 401.660161 -16.291268)
			(xy 401.638207 -16.291268) (xy 401.617169 -16.297541) (xy 401.607782 -16.303244) (xy 401.314158 -16.495776)
			(xy 401.304665 -16.501587) (xy 401.28337 -16.508035) (xy 401.272248 -16.508476) (xy 401.076414 -16.508476)
			(xy 401.064302 -16.507976) (xy 401.041261 -16.500495) (xy 401.02166 -16.486259) (xy 401.007418 -16.466664)
			(xy 400.999928 -16.443626) (xy 400.999452 -16.431514) (xy 396.710916 -16.431514) (xy 396.710551 -16.443642)
			(xy 396.703049 -16.466709) (xy 396.688785 -16.486328) (xy 396.669155 -16.500577) (xy 396.646082 -16.50806)
			(xy 396.633954 -16.508476) (xy 396.43939 -16.508476) (xy 396.428266 -16.508047) (xy 396.406969 -16.501598)
			(xy 396.39748 -16.495776) (xy 396.102586 -16.303244) (xy 396.093199 -16.297541) (xy 396.072161 -16.291268)
			(xy 396.050207 -16.291268) (xy 396.029169 -16.297541) (xy 396.019782 -16.303244) (xy 395.726158 -16.495776)
			(xy 395.716665 -16.501587) (xy 395.69537 -16.508035) (xy 395.684248 -16.508476) (xy 395.488414 -16.508476)
			(xy 395.476302 -16.507976) (xy 395.453261 -16.500495) (xy 395.43366 -16.486259) (xy 395.419418 -16.466664)
			(xy 395.411928 -16.443626) (xy 395.411452 -16.431514) (xy 391.122916 -16.431514) (xy 391.122551 -16.443642)
			(xy 391.115049 -16.466709) (xy 391.100785 -16.486328) (xy 391.081155 -16.500577) (xy 391.058082 -16.50806)
			(xy 391.045954 -16.508476) (xy 390.85139 -16.508476) (xy 390.840266 -16.508047) (xy 390.818969 -16.501598)
			(xy 390.80948 -16.495776) (xy 390.514586 -16.303244) (xy 390.505199 -16.297541) (xy 390.484161 -16.291268)
			(xy 390.462207 -16.291268) (xy 390.441169 -16.297541) (xy 390.431782 -16.303244) (xy 390.138158 -16.495776)
			(xy 390.128665 -16.501587) (xy 390.10737 -16.508035) (xy 390.096248 -16.508476) (xy 389.900414 -16.508476)
			(xy 389.888302 -16.507976) (xy 389.865261 -16.500495) (xy 389.84566 -16.486259) (xy 389.831418 -16.466664)
			(xy 389.823928 -16.443626) (xy 389.823452 -16.431514) (xy 259.309108 -16.431514) (xy 259.309108 -17.628666)
			(xy 389.660162 -17.628666) (xy 389.660162 -17.574134) (xy 389.667923 -17.520157) (xy 389.683286 -17.467834)
			(xy 389.705939 -17.41823) (xy 389.73542 -17.372354) (xy 389.77113 -17.331141) (xy 389.812342 -17.29543)
			(xy 389.858216 -17.265946) (xy 389.907819 -17.243291) (xy 389.960142 -17.227926) (xy 390.014118 -17.220163)
			(xy 390.041384 -17.219676) (xy 390.904984 -17.219676) (xy 390.932258 -17.220062) (xy 390.986252 -17.227824)
			(xy 391.038592 -17.24319) (xy 391.088212 -17.265849) (xy 391.134103 -17.295339) (xy 391.175329 -17.33106)
			(xy 391.211051 -17.372285) (xy 391.240543 -17.418174) (xy 391.263204 -17.467793) (xy 391.278573 -17.520132)
			(xy 391.286336 -17.574126) (xy 391.286336 -17.628674) (xy 391.278573 -17.682668) (xy 391.263204 -17.735007)
			(xy 391.240543 -17.784626) (xy 391.211051 -17.830515) (xy 391.175329 -17.87174) (xy 391.134103 -17.907461)
			(xy 391.088212 -17.936951) (xy 391.047562 -17.955514) (xy 392.617452 -17.955514) (xy 392.617452 -17.269714)
			(xy 392.617872 -17.257591) (xy 392.625362 -17.23453) (xy 392.639613 -17.214913) (xy 392.65923 -17.200662)
			(xy 392.682291 -17.193172) (xy 392.694414 -17.192752) (xy 392.888978 -17.192752) (xy 392.900102 -17.19319)
			(xy 392.921399 -17.199633) (xy 392.930888 -17.205452) (xy 393.224512 -17.397984) (xy 393.233879 -17.403719)
			(xy 393.254899 -17.41005) (xy 393.276853 -17.410115) (xy 393.297911 -17.403909) (xy 393.307316 -17.398238)
			(xy 393.60348 -17.205452) (xy 393.612986 -17.199666) (xy 393.634271 -17.193202) (xy 393.64539 -17.192752)
			(xy 393.839954 -17.192752) (xy 393.852076 -17.193199) (xy 393.875136 -17.200681) (xy 393.894753 -17.214925)
			(xy 393.909005 -17.234536) (xy 393.916496 -17.257592) (xy 393.916916 -17.269714) (xy 393.916916 -17.628666)
			(xy 395.248162 -17.628666) (xy 395.248162 -17.574134) (xy 395.255923 -17.520157) (xy 395.271286 -17.467834)
			(xy 395.293939 -17.41823) (xy 395.32342 -17.372354) (xy 395.35913 -17.331141) (xy 395.400342 -17.29543)
			(xy 395.446216 -17.265946) (xy 395.495819 -17.243291) (xy 395.548142 -17.227926) (xy 395.602118 -17.220163)
			(xy 395.629384 -17.219676) (xy 396.492984 -17.219676) (xy 396.520258 -17.220062) (xy 396.574252 -17.227824)
			(xy 396.626592 -17.24319) (xy 396.676212 -17.265849) (xy 396.722103 -17.295339) (xy 396.763329 -17.33106)
			(xy 396.799051 -17.372285) (xy 396.828543 -17.418174) (xy 396.851204 -17.467793) (xy 396.866573 -17.520132)
			(xy 396.874336 -17.574126) (xy 396.874336 -17.628674) (xy 396.866573 -17.682668) (xy 396.851204 -17.735007)
			(xy 396.828543 -17.784626) (xy 396.799051 -17.830515) (xy 396.763329 -17.87174) (xy 396.722103 -17.907461)
			(xy 396.676212 -17.936951) (xy 396.635562 -17.955514) (xy 398.205452 -17.955514) (xy 398.205452 -17.269714)
			(xy 398.205872 -17.257591) (xy 398.213362 -17.23453) (xy 398.227613 -17.214913) (xy 398.24723 -17.200662)
			(xy 398.270291 -17.193172) (xy 398.282414 -17.192752) (xy 398.476978 -17.192752) (xy 398.488102 -17.19319)
			(xy 398.509399 -17.199633) (xy 398.518888 -17.205452) (xy 398.812512 -17.397984) (xy 398.821879 -17.403719)
			(xy 398.842899 -17.41005) (xy 398.864853 -17.410115) (xy 398.885911 -17.403909) (xy 398.895316 -17.398238)
			(xy 399.19148 -17.205452) (xy 399.200986 -17.199666) (xy 399.222271 -17.193202) (xy 399.23339 -17.192752)
			(xy 399.427954 -17.192752) (xy 399.440076 -17.193199) (xy 399.463136 -17.200681) (xy 399.482753 -17.214925)
			(xy 399.497005 -17.234536) (xy 399.504496 -17.257592) (xy 399.504916 -17.269714) (xy 399.504916 -17.628666)
			(xy 400.836162 -17.628666) (xy 400.836162 -17.574134) (xy 400.843923 -17.520157) (xy 400.859286 -17.467834)
			(xy 400.881939 -17.41823) (xy 400.91142 -17.372354) (xy 400.94713 -17.331141) (xy 400.988342 -17.29543)
			(xy 401.034216 -17.265946) (xy 401.083819 -17.243291) (xy 401.136142 -17.227926) (xy 401.190118 -17.220163)
			(xy 401.217384 -17.219676) (xy 402.080984 -17.219676) (xy 402.108258 -17.220062) (xy 402.162252 -17.227824)
			(xy 402.214592 -17.24319) (xy 402.264212 -17.265849) (xy 402.310103 -17.295339) (xy 402.351329 -17.33106)
			(xy 402.387051 -17.372285) (xy 402.416543 -17.418174) (xy 402.439204 -17.467793) (xy 402.454573 -17.520132)
			(xy 402.462336 -17.574126) (xy 402.462336 -17.628674) (xy 402.454573 -17.682668) (xy 402.439204 -17.735007)
			(xy 402.416543 -17.784626) (xy 402.387051 -17.830515) (xy 402.351329 -17.87174) (xy 402.310103 -17.907461)
			(xy 402.264212 -17.936951) (xy 402.223562 -17.955514) (xy 403.793452 -17.955514) (xy 403.793452 -17.269714)
			(xy 403.793872 -17.257591) (xy 403.801362 -17.23453) (xy 403.815613 -17.214913) (xy 403.83523 -17.200662)
			(xy 403.858291 -17.193172) (xy 403.870414 -17.192752) (xy 404.064978 -17.192752) (xy 404.076102 -17.19319)
			(xy 404.097399 -17.199633) (xy 404.106888 -17.205452) (xy 404.400512 -17.397984) (xy 404.409879 -17.403719)
			(xy 404.430899 -17.41005) (xy 404.452853 -17.410115) (xy 404.473911 -17.403909) (xy 404.483316 -17.398238)
			(xy 404.77948 -17.205452) (xy 404.788986 -17.199666) (xy 404.810271 -17.193202) (xy 404.82139 -17.192752)
			(xy 405.015954 -17.192752) (xy 405.028076 -17.193199) (xy 405.051136 -17.200681) (xy 405.070753 -17.214925)
			(xy 405.085005 -17.234536) (xy 405.092496 -17.257592) (xy 405.092916 -17.269714) (xy 405.092916 -17.628666)
			(xy 406.424162 -17.628666) (xy 406.424162 -17.574134) (xy 406.431923 -17.520157) (xy 406.447286 -17.467834)
			(xy 406.469939 -17.41823) (xy 406.49942 -17.372354) (xy 406.53513 -17.331141) (xy 406.576342 -17.29543)
			(xy 406.622216 -17.265946) (xy 406.671819 -17.243291) (xy 406.724142 -17.227926) (xy 406.778118 -17.220163)
			(xy 406.805384 -17.219676) (xy 407.668984 -17.219676) (xy 407.696258 -17.220062) (xy 407.750252 -17.227824)
			(xy 407.802592 -17.24319) (xy 407.852212 -17.265849) (xy 407.898103 -17.295339) (xy 407.939329 -17.33106)
			(xy 407.975051 -17.372285) (xy 408.004543 -17.418174) (xy 408.027204 -17.467793) (xy 408.042573 -17.520132)
			(xy 408.050336 -17.574126) (xy 408.050336 -17.628674) (xy 408.042573 -17.682668) (xy 408.027204 -17.735007)
			(xy 408.004543 -17.784626) (xy 407.975051 -17.830515) (xy 407.939329 -17.87174) (xy 407.898103 -17.907461)
			(xy 407.852212 -17.936951) (xy 407.811562 -17.955514) (xy 409.381452 -17.955514) (xy 409.381452 -17.269714)
			(xy 409.381872 -17.257591) (xy 409.389362 -17.23453) (xy 409.403613 -17.214913) (xy 409.42323 -17.200662)
			(xy 409.446291 -17.193172) (xy 409.458414 -17.192752) (xy 409.652978 -17.192752) (xy 409.664102 -17.19319)
			(xy 409.685399 -17.199633) (xy 409.694888 -17.205452) (xy 409.988512 -17.397984) (xy 409.997879 -17.403719)
			(xy 410.018899 -17.41005) (xy 410.040853 -17.410115) (xy 410.061911 -17.403909) (xy 410.071316 -17.398238)
			(xy 410.36748 -17.205452) (xy 410.376986 -17.199666) (xy 410.398271 -17.193202) (xy 410.40939 -17.192752)
			(xy 410.603954 -17.192752) (xy 410.616076 -17.193199) (xy 410.639136 -17.200681) (xy 410.658753 -17.214925)
			(xy 410.673005 -17.234536) (xy 410.680496 -17.257592) (xy 410.680916 -17.269714) (xy 410.680916 -17.628666)
			(xy 412.012162 -17.628666) (xy 412.012162 -17.574134) (xy 412.019923 -17.520157) (xy 412.035286 -17.467834)
			(xy 412.057939 -17.41823) (xy 412.08742 -17.372354) (xy 412.12313 -17.331141) (xy 412.164342 -17.29543)
			(xy 412.210216 -17.265946) (xy 412.259819 -17.243291) (xy 412.312142 -17.227926) (xy 412.366118 -17.220163)
			(xy 412.393384 -17.219676) (xy 413.256984 -17.219676) (xy 413.284258 -17.220062) (xy 413.338252 -17.227824)
			(xy 413.390592 -17.24319) (xy 413.440212 -17.265849) (xy 413.486103 -17.295339) (xy 413.527329 -17.33106)
			(xy 413.563051 -17.372285) (xy 413.592543 -17.418174) (xy 413.615204 -17.467793) (xy 413.630573 -17.520132)
			(xy 413.638336 -17.574126) (xy 413.638336 -17.628674) (xy 413.630573 -17.682668) (xy 413.615204 -17.735007)
			(xy 413.592543 -17.784626) (xy 413.563051 -17.830515) (xy 413.527329 -17.87174) (xy 413.486103 -17.907461)
			(xy 413.440212 -17.936951) (xy 413.399562 -17.955514) (xy 415.275268 -17.955514) (xy 415.275268 -17.269714)
			(xy 415.275672 -17.257589) (xy 415.283164 -17.234526) (xy 415.297419 -17.214908) (xy 415.31704 -17.200657)
			(xy 415.340105 -17.19317) (xy 415.35223 -17.192752) (xy 415.546794 -17.192752) (xy 415.557918 -17.193184)
			(xy 415.579215 -17.199631) (xy 415.588704 -17.205452) (xy 415.882328 -17.397984) (xy 415.891687 -17.403732)
			(xy 415.912711 -17.41006) (xy 415.934667 -17.410122) (xy 415.955727 -17.403912) (xy 415.965132 -17.398238)
			(xy 416.261296 -17.205452) (xy 416.270799 -17.19966) (xy 416.292086 -17.1932) (xy 416.303206 -17.192752)
			(xy 416.49777 -17.192752) (xy 416.509893 -17.193186) (xy 416.532953 -17.200671) (xy 416.55257 -17.214919)
			(xy 416.566821 -17.234533) (xy 416.574312 -17.257592) (xy 416.574732 -17.269714) (xy 416.574732 -17.628667)
			(xy 417.905962 -17.628667) (xy 417.905962 -17.574133) (xy 417.913723 -17.520155) (xy 417.929087 -17.467831)
			(xy 417.951741 -17.418226) (xy 417.981224 -17.372349) (xy 418.016936 -17.331136) (xy 418.058149 -17.295424)
			(xy 418.104026 -17.265941) (xy 418.153631 -17.243287) (xy 418.205955 -17.227923) (xy 418.259933 -17.220162)
			(xy 418.2872 -17.219676) (xy 419.1508 -17.219676) (xy 419.178072 -17.220087) (xy 419.232061 -17.227849)
			(xy 419.284396 -17.243216) (xy 419.334011 -17.265874) (xy 419.379896 -17.295363) (xy 419.421118 -17.331082)
			(xy 419.456837 -17.372304) (xy 419.486326 -17.418189) (xy 419.508984 -17.467804) (xy 419.524351 -17.520139)
			(xy 419.532113 -17.574128) (xy 419.532113 -17.628672) (xy 419.524351 -17.682661) (xy 419.508984 -17.734996)
			(xy 419.486326 -17.784611) (xy 419.456837 -17.830496) (xy 419.421118 -17.871718) (xy 419.379896 -17.907437)
			(xy 419.334011 -17.936926) (xy 419.293308 -17.955514) (xy 420.863268 -17.955514) (xy 420.863268 -17.269714)
			(xy 420.863672 -17.257589) (xy 420.871164 -17.234526) (xy 420.885419 -17.214908) (xy 420.90504 -17.200657)
			(xy 420.928105 -17.19317) (xy 420.94023 -17.192752) (xy 421.134794 -17.192752) (xy 421.145918 -17.193184)
			(xy 421.167215 -17.199631) (xy 421.176704 -17.205452) (xy 421.470328 -17.397984) (xy 421.479687 -17.403732)
			(xy 421.500711 -17.41006) (xy 421.522667 -17.410122) (xy 421.543727 -17.403912) (xy 421.553132 -17.398238)
			(xy 421.849296 -17.205452) (xy 421.858799 -17.19966) (xy 421.880086 -17.1932) (xy 421.891206 -17.192752)
			(xy 422.08577 -17.192752) (xy 422.097893 -17.193186) (xy 422.120953 -17.200671) (xy 422.14057 -17.214919)
			(xy 422.154821 -17.234533) (xy 422.162312 -17.257592) (xy 422.162732 -17.269714) (xy 422.162732 -17.628667)
			(xy 423.493962 -17.628667) (xy 423.493962 -17.574133) (xy 423.501723 -17.520155) (xy 423.517087 -17.467831)
			(xy 423.539741 -17.418226) (xy 423.569224 -17.372349) (xy 423.604936 -17.331136) (xy 423.646149 -17.295424)
			(xy 423.692026 -17.265941) (xy 423.741631 -17.243287) (xy 423.793955 -17.227923) (xy 423.847933 -17.220162)
			(xy 423.8752 -17.219676) (xy 424.7388 -17.219676) (xy 424.766072 -17.220087) (xy 424.820061 -17.227849)
			(xy 424.872396 -17.243216) (xy 424.922011 -17.265874) (xy 424.967896 -17.295363) (xy 425.009118 -17.331082)
			(xy 425.044837 -17.372304) (xy 425.074326 -17.418189) (xy 425.096984 -17.467804) (xy 425.112351 -17.520139)
			(xy 425.120113 -17.574128) (xy 425.120113 -17.628672) (xy 425.112351 -17.682661) (xy 425.096984 -17.734996)
			(xy 425.074326 -17.784611) (xy 425.044837 -17.830496) (xy 425.009118 -17.871718) (xy 424.967896 -17.907437)
			(xy 424.922011 -17.936926) (xy 424.881308 -17.955514) (xy 426.485304 -17.955514) (xy 426.485304 -17.269714)
			(xy 426.485823 -17.257604) (xy 426.493302 -17.234567) (xy 426.507533 -17.214968) (xy 426.527124 -17.200724)
			(xy 426.550156 -17.193231) (xy 426.562266 -17.192752) (xy 426.75683 -17.192752) (xy 426.767955 -17.193169)
			(xy 426.789252 -17.199626) (xy 426.79874 -17.205452) (xy 427.092364 -17.397984) (xy 427.101753 -17.403677)
			(xy 427.122763 -17.410018) (xy 427.144709 -17.410095) (xy 427.165763 -17.403902) (xy 427.175168 -17.398238)
			(xy 427.471332 -17.205452) (xy 427.480828 -17.199647) (xy 427.502121 -17.193195) (xy 427.513242 -17.192752)
			(xy 427.707806 -17.192752) (xy 427.71993 -17.193155) (xy 427.742992 -17.200651) (xy 427.762608 -17.214906)
			(xy 427.776858 -17.234526) (xy 427.784348 -17.257589) (xy 427.784768 -17.269714) (xy 427.784768 -17.62867)
			(xy 429.11594 -17.62867) (xy 429.11594 -17.57413) (xy 429.123702 -17.520145) (xy 429.139068 -17.467815)
			(xy 429.161726 -17.418204) (xy 429.191214 -17.372324) (xy 429.226932 -17.331107) (xy 429.268152 -17.295393)
			(xy 429.314036 -17.265909) (xy 429.363649 -17.243256) (xy 429.415981 -17.227894) (xy 429.469966 -17.220137)
			(xy 429.497236 -17.219676) (xy 430.360836 -17.219676) (xy 430.388106 -17.220089) (xy 430.442091 -17.227856)
			(xy 430.494422 -17.243226) (xy 430.544032 -17.265886) (xy 430.589913 -17.295376) (xy 430.631131 -17.331095)
			(xy 430.666846 -17.372315) (xy 430.696331 -17.418199) (xy 430.718987 -17.467812) (xy 430.734352 -17.520144)
			(xy 430.742114 -17.57413) (xy 430.742114 -17.62867) (xy 430.734352 -17.682656) (xy 430.718987 -17.734988)
			(xy 430.696331 -17.784601) (xy 430.666846 -17.830485) (xy 430.631131 -17.871705) (xy 430.589913 -17.907424)
			(xy 430.544032 -17.936914) (xy 430.503311 -17.955514) (xy 432.073304 -17.955514) (xy 432.073304 -17.269714)
			(xy 432.073823 -17.257604) (xy 432.081302 -17.234567) (xy 432.095533 -17.214968) (xy 432.115124 -17.200724)
			(xy 432.138156 -17.193231) (xy 432.150266 -17.192752) (xy 432.34483 -17.192752) (xy 432.355955 -17.193169)
			(xy 432.377252 -17.199626) (xy 432.38674 -17.205452) (xy 432.680364 -17.397984) (xy 432.689753 -17.403677)
			(xy 432.710763 -17.410018) (xy 432.732709 -17.410095) (xy 432.753763 -17.403902) (xy 432.763168 -17.398238)
			(xy 433.059332 -17.205452) (xy 433.068828 -17.199647) (xy 433.090121 -17.193195) (xy 433.101242 -17.192752)
			(xy 433.295806 -17.192752) (xy 433.30793 -17.193155) (xy 433.330992 -17.200651) (xy 433.350608 -17.214906)
			(xy 433.364858 -17.234526) (xy 433.372348 -17.257589) (xy 433.372768 -17.269714) (xy 433.372768 -17.955514)
			(xy 433.3723 -17.967629) (xy 433.36481 -17.990671) (xy 433.350567 -18.010273) (xy 433.330964 -18.024514)
			(xy 433.307921 -18.032002) (xy 433.295806 -18.032476) (xy 433.101242 -18.032476) (xy 433.090116 -18.032066)
			(xy 433.068819 -18.025604) (xy 433.059332 -18.019776) (xy 432.764438 -17.827244) (xy 432.755051 -17.821541)
			(xy 432.734013 -17.815268) (xy 432.712059 -17.815268) (xy 432.691021 -17.821541) (xy 432.681634 -17.827244)
			(xy 432.38801 -18.019776) (xy 432.378507 -18.025568) (xy 432.35722 -18.032028) (xy 432.3461 -18.032476)
			(xy 432.150266 -18.032476) (xy 432.138151 -18.032018) (xy 432.115109 -18.024523) (xy 432.095509 -18.010277)
			(xy 432.081268 -17.990673) (xy 432.073779 -17.967629) (xy 432.073304 -17.955514) (xy 430.503311 -17.955514)
			(xy 430.494422 -17.959574) (xy 430.442091 -17.974944) (xy 430.388106 -17.982711) (xy 430.360836 -17.9832)
			(xy 429.497236 -17.9832) (xy 429.469966 -17.982663) (xy 429.415981 -17.974906) (xy 429.363649 -17.959544)
			(xy 429.314036 -17.936891) (xy 429.268152 -17.907407) (xy 429.226932 -17.871693) (xy 429.191214 -17.830476)
			(xy 429.161726 -17.784596) (xy 429.139068 -17.734985) (xy 429.123702 -17.682655) (xy 429.11594 -17.62867)
			(xy 427.784768 -17.62867) (xy 427.784768 -17.955514) (xy 427.7843 -17.967629) (xy 427.77681 -17.990671)
			(xy 427.762567 -18.010273) (xy 427.742964 -18.024514) (xy 427.719921 -18.032002) (xy 427.707806 -18.032476)
			(xy 427.513242 -18.032476) (xy 427.502116 -18.032066) (xy 427.480819 -18.025604) (xy 427.471332 -18.019776)
			(xy 427.176438 -17.827244) (xy 427.167051 -17.821541) (xy 427.146013 -17.815268) (xy 427.124059 -17.815268)
			(xy 427.103021 -17.821541) (xy 427.093634 -17.827244) (xy 426.80001 -18.019776) (xy 426.790507 -18.025568)
			(xy 426.76922 -18.032028) (xy 426.7581 -18.032476) (xy 426.562266 -18.032476) (xy 426.550151 -18.032018)
			(xy 426.527109 -18.024523) (xy 426.507509 -18.010277) (xy 426.493268 -17.990673) (xy 426.485779 -17.967629)
			(xy 426.485304 -17.955514) (xy 424.881308 -17.955514) (xy 424.872396 -17.959584) (xy 424.820061 -17.974951)
			(xy 424.766072 -17.982713) (xy 424.7388 -17.9832) (xy 423.8752 -17.9832) (xy 423.847933 -17.982638)
			(xy 423.793955 -17.974877) (xy 423.741631 -17.959513) (xy 423.692026 -17.936859) (xy 423.646149 -17.907376)
			(xy 423.604936 -17.871664) (xy 423.569224 -17.830451) (xy 423.539741 -17.784574) (xy 423.517087 -17.734969)
			(xy 423.501723 -17.682645) (xy 423.493962 -17.628667) (xy 422.162732 -17.628667) (xy 422.162732 -17.955514)
			(xy 422.162351 -17.96764) (xy 422.154852 -17.990705) (xy 422.140591 -18.010322) (xy 422.120965 -18.024572)
			(xy 422.097897 -18.032058) (xy 422.08577 -18.032476) (xy 421.891206 -18.032476) (xy 421.880082 -18.03204)
			(xy 421.858785 -18.025596) (xy 421.849296 -18.019776) (xy 421.554402 -17.827244) (xy 421.545015 -17.821541)
			(xy 421.523977 -17.815268) (xy 421.502023 -17.815268) (xy 421.480985 -17.821541) (xy 421.471598 -17.827244)
			(xy 421.177974 -18.019776) (xy 421.168478 -18.025581) (xy 421.147185 -18.032033) (xy 421.136064 -18.032476)
			(xy 420.94023 -18.032476) (xy 420.92811 -18.032015) (xy 420.905055 -18.024532) (xy 420.88544 -18.010291)
			(xy 420.871188 -17.990685) (xy 420.863692 -17.967634) (xy 420.863268 -17.955514) (xy 419.293308 -17.955514)
			(xy 419.284396 -17.959584) (xy 419.232061 -17.974951) (xy 419.178072 -17.982713) (xy 419.1508 -17.9832)
			(xy 418.2872 -17.9832) (xy 418.259933 -17.982638) (xy 418.205955 -17.974877) (xy 418.153631 -17.959513)
			(xy 418.104026 -17.936859) (xy 418.058149 -17.907376) (xy 418.016936 -17.871664) (xy 417.981224 -17.830451)
			(xy 417.951741 -17.784574) (xy 417.929087 -17.734969) (xy 417.913723 -17.682645) (xy 417.905962 -17.628667)
			(xy 416.574732 -17.628667) (xy 416.574732 -17.955514) (xy 416.574351 -17.96764) (xy 416.566852 -17.990705)
			(xy 416.552591 -18.010322) (xy 416.532965 -18.024572) (xy 416.509897 -18.032058) (xy 416.49777 -18.032476)
			(xy 416.303206 -18.032476) (xy 416.292082 -18.03204) (xy 416.270785 -18.025596) (xy 416.261296 -18.019776)
			(xy 415.966402 -17.827244) (xy 415.957015 -17.821541) (xy 415.935977 -17.815268) (xy 415.914023 -17.815268)
			(xy 415.892985 -17.821541) (xy 415.883598 -17.827244) (xy 415.589974 -18.019776) (xy 415.580478 -18.025581)
			(xy 415.559185 -18.032033) (xy 415.548064 -18.032476) (xy 415.35223 -18.032476) (xy 415.34011 -18.032015)
			(xy 415.317055 -18.024532) (xy 415.29744 -18.010291) (xy 415.283188 -17.990685) (xy 415.275692 -17.967634)
			(xy 415.275268 -17.955514) (xy 413.399562 -17.955514) (xy 413.390592 -17.95961) (xy 413.338252 -17.974976)
			(xy 413.284258 -17.982738) (xy 413.256984 -17.9832) (xy 412.393384 -17.9832) (xy 412.366118 -17.982637)
			(xy 412.312142 -17.974874) (xy 412.259819 -17.959509) (xy 412.210216 -17.936854) (xy 412.164342 -17.90737)
			(xy 412.12313 -17.871659) (xy 412.08742 -17.830446) (xy 412.057939 -17.78457) (xy 412.035286 -17.734966)
			(xy 412.019923 -17.682643) (xy 412.012162 -17.628666) (xy 410.680916 -17.628666) (xy 410.680916 -17.955514)
			(xy 410.680551 -17.967642) (xy 410.673049 -17.990709) (xy 410.658785 -18.010328) (xy 410.639155 -18.024577)
			(xy 410.616082 -18.03206) (xy 410.603954 -18.032476) (xy 410.40939 -18.032476) (xy 410.398266 -18.032047)
			(xy 410.376969 -18.025598) (xy 410.36748 -18.019776) (xy 410.072586 -17.827244) (xy 410.063199 -17.821541)
			(xy 410.042161 -17.815268) (xy 410.020207 -17.815268) (xy 409.999169 -17.821541) (xy 409.989782 -17.827244)
			(xy 409.696158 -18.019776) (xy 409.686665 -18.025587) (xy 409.66537 -18.032035) (xy 409.654248 -18.032476)
			(xy 409.458414 -18.032476) (xy 409.446302 -18.031976) (xy 409.423261 -18.024495) (xy 409.40366 -18.010259)
			(xy 409.389418 -17.990664) (xy 409.381928 -17.967626) (xy 409.381452 -17.955514) (xy 407.811562 -17.955514)
			(xy 407.802592 -17.95961) (xy 407.750252 -17.974976) (xy 407.696258 -17.982738) (xy 407.668984 -17.9832)
			(xy 406.805384 -17.9832) (xy 406.778118 -17.982637) (xy 406.724142 -17.974874) (xy 406.671819 -17.959509)
			(xy 406.622216 -17.936854) (xy 406.576342 -17.90737) (xy 406.53513 -17.871659) (xy 406.49942 -17.830446)
			(xy 406.469939 -17.78457) (xy 406.447286 -17.734966) (xy 406.431923 -17.682643) (xy 406.424162 -17.628666)
			(xy 405.092916 -17.628666) (xy 405.092916 -17.955514) (xy 405.092551 -17.967642) (xy 405.085049 -17.990709)
			(xy 405.070785 -18.010328) (xy 405.051155 -18.024577) (xy 405.028082 -18.03206) (xy 405.015954 -18.032476)
			(xy 404.82139 -18.032476) (xy 404.810266 -18.032047) (xy 404.788969 -18.025598) (xy 404.77948 -18.019776)
			(xy 404.484586 -17.827244) (xy 404.475199 -17.821541) (xy 404.454161 -17.815268) (xy 404.432207 -17.815268)
			(xy 404.411169 -17.821541) (xy 404.401782 -17.827244) (xy 404.108158 -18.019776) (xy 404.098665 -18.025587)
			(xy 404.07737 -18.032035) (xy 404.066248 -18.032476) (xy 403.870414 -18.032476) (xy 403.858302 -18.031976)
			(xy 403.835261 -18.024495) (xy 403.81566 -18.010259) (xy 403.801418 -17.990664) (xy 403.793928 -17.967626)
			(xy 403.793452 -17.955514) (xy 402.223562 -17.955514) (xy 402.214592 -17.95961) (xy 402.162252 -17.974976)
			(xy 402.108258 -17.982738) (xy 402.080984 -17.9832) (xy 401.217384 -17.9832) (xy 401.190118 -17.982637)
			(xy 401.136142 -17.974874) (xy 401.083819 -17.959509) (xy 401.034216 -17.936854) (xy 400.988342 -17.90737)
			(xy 400.94713 -17.871659) (xy 400.91142 -17.830446) (xy 400.881939 -17.78457) (xy 400.859286 -17.734966)
			(xy 400.843923 -17.682643) (xy 400.836162 -17.628666) (xy 399.504916 -17.628666) (xy 399.504916 -17.955514)
			(xy 399.504551 -17.967642) (xy 399.497049 -17.990709) (xy 399.482785 -18.010328) (xy 399.463155 -18.024577)
			(xy 399.440082 -18.03206) (xy 399.427954 -18.032476) (xy 399.23339 -18.032476) (xy 399.222266 -18.032047)
			(xy 399.200969 -18.025598) (xy 399.19148 -18.019776) (xy 398.896586 -17.827244) (xy 398.887199 -17.821541)
			(xy 398.866161 -17.815268) (xy 398.844207 -17.815268) (xy 398.823169 -17.821541) (xy 398.813782 -17.827244)
			(xy 398.520158 -18.019776) (xy 398.510665 -18.025587) (xy 398.48937 -18.032035) (xy 398.478248 -18.032476)
			(xy 398.282414 -18.032476) (xy 398.270302 -18.031976) (xy 398.247261 -18.024495) (xy 398.22766 -18.010259)
			(xy 398.213418 -17.990664) (xy 398.205928 -17.967626) (xy 398.205452 -17.955514) (xy 396.635562 -17.955514)
			(xy 396.626592 -17.95961) (xy 396.574252 -17.974976) (xy 396.520258 -17.982738) (xy 396.492984 -17.9832)
			(xy 395.629384 -17.9832) (xy 395.602118 -17.982637) (xy 395.548142 -17.974874) (xy 395.495819 -17.959509)
			(xy 395.446216 -17.936854) (xy 395.400342 -17.90737) (xy 395.35913 -17.871659) (xy 395.32342 -17.830446)
			(xy 395.293939 -17.78457) (xy 395.271286 -17.734966) (xy 395.255923 -17.682643) (xy 395.248162 -17.628666)
			(xy 393.916916 -17.628666) (xy 393.916916 -17.955514) (xy 393.916551 -17.967642) (xy 393.909049 -17.990709)
			(xy 393.894785 -18.010328) (xy 393.875155 -18.024577) (xy 393.852082 -18.03206) (xy 393.839954 -18.032476)
			(xy 393.64539 -18.032476) (xy 393.634266 -18.032047) (xy 393.612969 -18.025598) (xy 393.60348 -18.019776)
			(xy 393.308586 -17.827244) (xy 393.299199 -17.821541) (xy 393.278161 -17.815268) (xy 393.256207 -17.815268)
			(xy 393.235169 -17.821541) (xy 393.225782 -17.827244) (xy 392.932158 -18.019776) (xy 392.922665 -18.025587)
			(xy 392.90137 -18.032035) (xy 392.890248 -18.032476) (xy 392.694414 -18.032476) (xy 392.682302 -18.031976)
			(xy 392.659261 -18.024495) (xy 392.63966 -18.010259) (xy 392.625418 -17.990664) (xy 392.617928 -17.967626)
			(xy 392.617452 -17.955514) (xy 391.047562 -17.955514) (xy 391.038592 -17.95961) (xy 390.986252 -17.974976)
			(xy 390.932258 -17.982738) (xy 390.904984 -17.9832) (xy 390.041384 -17.9832) (xy 390.014118 -17.982637)
			(xy 389.960142 -17.974874) (xy 389.907819 -17.959509) (xy 389.858216 -17.936854) (xy 389.812342 -17.90737)
			(xy 389.77113 -17.871659) (xy 389.73542 -17.830446) (xy 389.705939 -17.78457) (xy 389.683286 -17.734966)
			(xy 389.667923 -17.682643) (xy 389.660162 -17.628666) (xy 259.309108 -17.628666) (xy 259.309108 -19.050762)
			(xy 389.346437 -19.050762) (xy 389.350516 -18.995029) (xy 389.362666 -18.940483) (xy 389.382629 -18.888288)
			(xy 389.409979 -18.839556) (xy 389.444133 -18.795325) (xy 389.484363 -18.756538) (xy 389.529812 -18.724022)
			(xy 389.57951 -18.698471) (xy 389.6324 -18.680427) (xy 389.687353 -18.670277) (xy 389.743198 -18.668236)
			(xy 389.798745 -18.674348) (xy 389.852811 -18.688482) (xy 389.904242 -18.710338) (xy 389.951943 -18.73945)
			(xy 389.994897 -18.775196) (xy 390.032188 -18.816816) (xy 390.063022 -18.863422) (xy 390.086742 -18.914021)
			(xy 390.102842 -18.967534) (xy 390.110978 -19.022821) (xy 390.111488 -19.050762) (xy 390.110978 -19.078703)
			(xy 390.102842 -19.13399) (xy 390.097223 -19.152666) (xy 392.454162 -19.152666) (xy 392.454162 -19.098134)
			(xy 392.461923 -19.044157) (xy 392.477286 -18.991834) (xy 392.499939 -18.94223) (xy 392.52942 -18.896354)
			(xy 392.56513 -18.855141) (xy 392.606342 -18.81943) (xy 392.652216 -18.789946) (xy 392.701819 -18.767291)
			(xy 392.754142 -18.751926) (xy 392.808118 -18.744163) (xy 392.835384 -18.743676) (xy 393.698984 -18.743676)
			(xy 393.726258 -18.744062) (xy 393.780252 -18.751824) (xy 393.832592 -18.76719) (xy 393.882212 -18.789849)
			(xy 393.928103 -18.819339) (xy 393.969329 -18.85506) (xy 394.005051 -18.896285) (xy 394.034543 -18.942174)
			(xy 394.057204 -18.991793) (xy 394.072573 -19.044132) (xy 394.080336 -19.098126) (xy 394.080336 -19.152666)
			(xy 398.042162 -19.152666) (xy 398.042162 -19.098134) (xy 398.049923 -19.044157) (xy 398.065286 -18.991834)
			(xy 398.087939 -18.94223) (xy 398.11742 -18.896354) (xy 398.15313 -18.855141) (xy 398.194342 -18.81943)
			(xy 398.240216 -18.789946) (xy 398.289819 -18.767291) (xy 398.342142 -18.751926) (xy 398.396118 -18.744163)
			(xy 398.423384 -18.743676) (xy 399.286984 -18.743676) (xy 399.314258 -18.744062) (xy 399.368252 -18.751824)
			(xy 399.420592 -18.76719) (xy 399.470212 -18.789849) (xy 399.516103 -18.819339) (xy 399.557329 -18.85506)
			(xy 399.593051 -18.896285) (xy 399.622543 -18.942174) (xy 399.645204 -18.991793) (xy 399.660573 -19.044132)
			(xy 399.668336 -19.098126) (xy 399.668336 -19.152666) (xy 403.630162 -19.152666) (xy 403.630162 -19.098134)
			(xy 403.637923 -19.044157) (xy 403.653286 -18.991834) (xy 403.675939 -18.94223) (xy 403.70542 -18.896354)
			(xy 403.74113 -18.855141) (xy 403.782342 -18.81943) (xy 403.828216 -18.789946) (xy 403.877819 -18.767291)
			(xy 403.930142 -18.751926) (xy 403.984118 -18.744163) (xy 404.011384 -18.743676) (xy 404.874984 -18.743676)
			(xy 404.902258 -18.744062) (xy 404.956252 -18.751824) (xy 405.008592 -18.76719) (xy 405.058212 -18.789849)
			(xy 405.104103 -18.819339) (xy 405.145329 -18.85506) (xy 405.181051 -18.896285) (xy 405.210543 -18.942174)
			(xy 405.233204 -18.991793) (xy 405.248573 -19.044132) (xy 405.256336 -19.098126) (xy 405.256336 -19.152666)
			(xy 409.218162 -19.152666) (xy 409.218162 -19.098134) (xy 409.225923 -19.044157) (xy 409.241286 -18.991834)
			(xy 409.263939 -18.94223) (xy 409.29342 -18.896354) (xy 409.32913 -18.855141) (xy 409.370342 -18.81943)
			(xy 409.416216 -18.789946) (xy 409.465819 -18.767291) (xy 409.518142 -18.751926) (xy 409.572118 -18.744163)
			(xy 409.599384 -18.743676) (xy 410.462984 -18.743676) (xy 410.490258 -18.744062) (xy 410.544252 -18.751824)
			(xy 410.596592 -18.76719) (xy 410.646212 -18.789849) (xy 410.692103 -18.819339) (xy 410.733329 -18.85506)
			(xy 410.769051 -18.896285) (xy 410.798543 -18.942174) (xy 410.821204 -18.991793) (xy 410.836573 -19.044132)
			(xy 410.844336 -19.098126) (xy 410.844336 -19.152667) (xy 415.111962 -19.152667) (xy 415.111962 -19.098133)
			(xy 415.119723 -19.044155) (xy 415.135087 -18.991831) (xy 415.157741 -18.942226) (xy 415.187224 -18.896349)
			(xy 415.222936 -18.855136) (xy 415.264149 -18.819424) (xy 415.310026 -18.789941) (xy 415.359631 -18.767287)
			(xy 415.411955 -18.751923) (xy 415.465933 -18.744162) (xy 415.4932 -18.743676) (xy 416.3568 -18.743676)
			(xy 416.384072 -18.744087) (xy 416.438061 -18.751849) (xy 416.490396 -18.767216) (xy 416.540011 -18.789874)
			(xy 416.585896 -18.819363) (xy 416.627118 -18.855082) (xy 416.662837 -18.896304) (xy 416.692326 -18.942189)
			(xy 416.714984 -18.991804) (xy 416.730351 -19.044139) (xy 416.738113 -19.098128) (xy 416.738113 -19.152667)
			(xy 420.699962 -19.152667) (xy 420.699962 -19.098133) (xy 420.707723 -19.044155) (xy 420.723087 -18.991831)
			(xy 420.745741 -18.942226) (xy 420.775224 -18.896349) (xy 420.810936 -18.855136) (xy 420.852149 -18.819424)
			(xy 420.898026 -18.789941) (xy 420.947631 -18.767287) (xy 420.999955 -18.751923) (xy 421.053933 -18.744162)
			(xy 421.0812 -18.743676) (xy 421.9448 -18.743676) (xy 421.972072 -18.744087) (xy 422.026061 -18.751849)
			(xy 422.078396 -18.767216) (xy 422.128011 -18.789874) (xy 422.173896 -18.819363) (xy 422.215118 -18.855082)
			(xy 422.250837 -18.896304) (xy 422.280326 -18.942189) (xy 422.302984 -18.991804) (xy 422.318351 -19.044139)
			(xy 422.326113 -19.098128) (xy 422.326113 -19.15267) (xy 426.32194 -19.15267) (xy 426.32194 -19.09813)
			(xy 426.329702 -19.044145) (xy 426.345068 -18.991815) (xy 426.367726 -18.942204) (xy 426.397214 -18.896324)
			(xy 426.432932 -18.855107) (xy 426.474152 -18.819393) (xy 426.520036 -18.789909) (xy 426.569649 -18.767256)
			(xy 426.621981 -18.751894) (xy 426.675966 -18.744137) (xy 426.703236 -18.743676) (xy 427.566836 -18.743676)
			(xy 427.594106 -18.744089) (xy 427.648091 -18.751856) (xy 427.700422 -18.767226) (xy 427.750032 -18.789886)
			(xy 427.795913 -18.819376) (xy 427.837131 -18.855095) (xy 427.872846 -18.896315) (xy 427.902331 -18.942199)
			(xy 427.924987 -18.991812) (xy 427.940352 -19.044144) (xy 427.948114 -19.09813) (xy 427.948114 -19.15267)
			(xy 431.90994 -19.15267) (xy 431.90994 -19.09813) (xy 431.917702 -19.044145) (xy 431.933068 -18.991815)
			(xy 431.955726 -18.942204) (xy 431.985214 -18.896324) (xy 432.020932 -18.855107) (xy 432.062152 -18.819393)
			(xy 432.108036 -18.789909) (xy 432.157649 -18.767256) (xy 432.209981 -18.751894) (xy 432.263966 -18.744137)
			(xy 432.291236 -18.743676) (xy 433.154836 -18.743676) (xy 433.182106 -18.744089) (xy 433.236091 -18.751856)
			(xy 433.288422 -18.767226) (xy 433.338032 -18.789886) (xy 433.383913 -18.819376) (xy 433.425131 -18.855095)
			(xy 433.460846 -18.896315) (xy 433.490331 -18.942199) (xy 433.512987 -18.991812) (xy 433.528352 -19.044144)
			(xy 433.536114 -19.09813) (xy 433.536114 -19.15267) (xy 433.528352 -19.206656) (xy 433.512987 -19.258988)
			(xy 433.490331 -19.308601) (xy 433.460846 -19.354485) (xy 433.425131 -19.395705) (xy 433.383913 -19.431424)
			(xy 433.338032 -19.460914) (xy 433.288422 -19.483574) (xy 433.236091 -19.498944) (xy 433.182106 -19.506711)
			(xy 433.154836 -19.5072) (xy 432.291236 -19.5072) (xy 432.263966 -19.506663) (xy 432.209981 -19.498906)
			(xy 432.157649 -19.483544) (xy 432.108036 -19.460891) (xy 432.062152 -19.431407) (xy 432.020932 -19.395693)
			(xy 431.985214 -19.354476) (xy 431.955726 -19.308596) (xy 431.933068 -19.258985) (xy 431.917702 -19.206655)
			(xy 431.90994 -19.15267) (xy 427.948114 -19.15267) (xy 427.940352 -19.206656) (xy 427.924987 -19.258988)
			(xy 427.902331 -19.308601) (xy 427.872846 -19.354485) (xy 427.837131 -19.395705) (xy 427.795913 -19.431424)
			(xy 427.750032 -19.460914) (xy 427.700422 -19.483574) (xy 427.648091 -19.498944) (xy 427.594106 -19.506711)
			(xy 427.566836 -19.5072) (xy 426.703236 -19.5072) (xy 426.675966 -19.506663) (xy 426.621981 -19.498906)
			(xy 426.569649 -19.483544) (xy 426.520036 -19.460891) (xy 426.474152 -19.431407) (xy 426.432932 -19.395693)
			(xy 426.397214 -19.354476) (xy 426.367726 -19.308596) (xy 426.345068 -19.258985) (xy 426.329702 -19.206655)
			(xy 426.32194 -19.15267) (xy 422.326113 -19.15267) (xy 422.326113 -19.152672) (xy 422.318351 -19.206661)
			(xy 422.302984 -19.258996) (xy 422.280326 -19.308611) (xy 422.250837 -19.354496) (xy 422.215118 -19.395718)
			(xy 422.173896 -19.431437) (xy 422.128011 -19.460926) (xy 422.078396 -19.483584) (xy 422.026061 -19.498951)
			(xy 421.972072 -19.506713) (xy 421.9448 -19.5072) (xy 421.0812 -19.5072) (xy 421.053933 -19.506638)
			(xy 420.999955 -19.498877) (xy 420.947631 -19.483513) (xy 420.898026 -19.460859) (xy 420.852149 -19.431376)
			(xy 420.810936 -19.395664) (xy 420.775224 -19.354451) (xy 420.745741 -19.308574) (xy 420.723087 -19.258969)
			(xy 420.707723 -19.206645) (xy 420.699962 -19.152667) (xy 416.738113 -19.152667) (xy 416.738113 -19.152672)
			(xy 416.730351 -19.206661) (xy 416.714984 -19.258996) (xy 416.692326 -19.308611) (xy 416.662837 -19.354496)
			(xy 416.627118 -19.395718) (xy 416.585896 -19.431437) (xy 416.540011 -19.460926) (xy 416.490396 -19.483584)
			(xy 416.438061 -19.498951) (xy 416.384072 -19.506713) (xy 416.3568 -19.5072) (xy 415.4932 -19.5072)
			(xy 415.465933 -19.506638) (xy 415.411955 -19.498877) (xy 415.359631 -19.483513) (xy 415.310026 -19.460859)
			(xy 415.264149 -19.431376) (xy 415.222936 -19.395664) (xy 415.187224 -19.354451) (xy 415.157741 -19.308574)
			(xy 415.135087 -19.258969) (xy 415.119723 -19.206645) (xy 415.111962 -19.152667) (xy 410.844336 -19.152667)
			(xy 410.844336 -19.152674) (xy 410.836573 -19.206668) (xy 410.821204 -19.259007) (xy 410.798543 -19.308626)
			(xy 410.769051 -19.354515) (xy 410.733329 -19.39574) (xy 410.692103 -19.431461) (xy 410.646212 -19.460951)
			(xy 410.596592 -19.48361) (xy 410.544252 -19.498976) (xy 410.490258 -19.506738) (xy 410.462984 -19.5072)
			(xy 409.599384 -19.5072) (xy 409.572118 -19.506637) (xy 409.518142 -19.498874) (xy 409.465819 -19.483509)
			(xy 409.416216 -19.460854) (xy 409.370342 -19.43137) (xy 409.32913 -19.395659) (xy 409.29342 -19.354446)
			(xy 409.263939 -19.30857) (xy 409.241286 -19.258966) (xy 409.225923 -19.206643) (xy 409.218162 -19.152666)
			(xy 405.256336 -19.152666) (xy 405.256336 -19.152674) (xy 405.248573 -19.206668) (xy 405.233204 -19.259007)
			(xy 405.210543 -19.308626) (xy 405.181051 -19.354515) (xy 405.145329 -19.39574) (xy 405.104103 -19.431461)
			(xy 405.058212 -19.460951) (xy 405.008592 -19.48361) (xy 404.956252 -19.498976) (xy 404.902258 -19.506738)
			(xy 404.874984 -19.5072) (xy 404.011384 -19.5072) (xy 403.984118 -19.506637) (xy 403.930142 -19.498874)
			(xy 403.877819 -19.483509) (xy 403.828216 -19.460854) (xy 403.782342 -19.43137) (xy 403.74113 -19.395659)
			(xy 403.70542 -19.354446) (xy 403.675939 -19.30857) (xy 403.653286 -19.258966) (xy 403.637923 -19.206643)
			(xy 403.630162 -19.152666) (xy 399.668336 -19.152666) (xy 399.668336 -19.152674) (xy 399.660573 -19.206668)
			(xy 399.645204 -19.259007) (xy 399.622543 -19.308626) (xy 399.593051 -19.354515) (xy 399.557329 -19.39574)
			(xy 399.516103 -19.431461) (xy 399.470212 -19.460951) (xy 399.420592 -19.48361) (xy 399.368252 -19.498976)
			(xy 399.314258 -19.506738) (xy 399.286984 -19.5072) (xy 398.423384 -19.5072) (xy 398.396118 -19.506637)
			(xy 398.342142 -19.498874) (xy 398.289819 -19.483509) (xy 398.240216 -19.460854) (xy 398.194342 -19.43137)
			(xy 398.15313 -19.395659) (xy 398.11742 -19.354446) (xy 398.087939 -19.30857) (xy 398.065286 -19.258966)
			(xy 398.049923 -19.206643) (xy 398.042162 -19.152666) (xy 394.080336 -19.152666) (xy 394.080336 -19.152674)
			(xy 394.072573 -19.206668) (xy 394.057204 -19.259007) (xy 394.034543 -19.308626) (xy 394.005051 -19.354515)
			(xy 393.969329 -19.39574) (xy 393.928103 -19.431461) (xy 393.882212 -19.460951) (xy 393.832592 -19.48361)
			(xy 393.780252 -19.498976) (xy 393.726258 -19.506738) (xy 393.698984 -19.5072) (xy 392.835384 -19.5072)
			(xy 392.808118 -19.506637) (xy 392.754142 -19.498874) (xy 392.701819 -19.483509) (xy 392.652216 -19.460854)
			(xy 392.606342 -19.43137) (xy 392.56513 -19.395659) (xy 392.52942 -19.354446) (xy 392.499939 -19.30857)
			(xy 392.477286 -19.258966) (xy 392.461923 -19.206643) (xy 392.454162 -19.152666) (xy 390.097223 -19.152666)
			(xy 390.086742 -19.187503) (xy 390.063022 -19.238102) (xy 390.032188 -19.284708) (xy 389.994897 -19.326328)
			(xy 389.951943 -19.362074) (xy 389.904242 -19.391186) (xy 389.852811 -19.413042) (xy 389.798745 -19.427176)
			(xy 389.743198 -19.433288) (xy 389.687353 -19.431247) (xy 389.6324 -19.421097) (xy 389.57951 -19.403053)
			(xy 389.529812 -19.377502) (xy 389.484363 -19.344986) (xy 389.444133 -19.306199) (xy 389.409979 -19.261968)
			(xy 389.382629 -19.213236) (xy 389.362666 -19.161041) (xy 389.350516 -19.106495) (xy 389.346437 -19.050762)
			(xy 259.309108 -19.050762) (xy 259.309108 -19.769328) (xy 388.600185 -19.769328) (xy 388.604264 -19.713595)
			(xy 388.616414 -19.659049) (xy 388.636377 -19.606854) (xy 388.663727 -19.558122) (xy 388.697881 -19.513891)
			(xy 388.738111 -19.475104) (xy 388.78356 -19.442588) (xy 388.833258 -19.417037) (xy 388.886148 -19.398993)
			(xy 388.941101 -19.388843) (xy 388.996946 -19.386802) (xy 389.052493 -19.392914) (xy 389.106559 -19.407048)
			(xy 389.15799 -19.428904) (xy 389.205691 -19.458016) (xy 389.248645 -19.493762) (xy 389.285936 -19.535382)
			(xy 389.31677 -19.581988) (xy 389.34049 -19.632587) (xy 389.35659 -19.6861) (xy 389.364726 -19.741387)
			(xy 389.365236 -19.769328) (xy 389.364726 -19.797269) (xy 389.35659 -19.852556) (xy 389.34049 -19.906069)
			(xy 389.31677 -19.956668) (xy 389.285936 -20.003274) (xy 389.248645 -20.044894) (xy 389.205691 -20.08064)
			(xy 389.15799 -20.109752) (xy 389.106559 -20.131608) (xy 389.052493 -20.145742) (xy 388.996946 -20.151854)
			(xy 388.941101 -20.149813) (xy 388.886148 -20.139663) (xy 388.833258 -20.121619) (xy 388.78356 -20.096068)
			(xy 388.738111 -20.063552) (xy 388.697881 -20.024765) (xy 388.663727 -19.980534) (xy 388.636377 -19.931802)
			(xy 388.616414 -19.879607) (xy 388.604264 -19.825061) (xy 388.600185 -19.769328) (xy 259.309108 -19.769328)
			(xy 259.309108 -25.468351) (xy 388.406603 -25.468351) (xy 388.406603 -25.413849) (xy 388.41436 -25.359901)
			(xy 388.429716 -25.307607) (xy 388.452359 -25.25803) (xy 388.481827 -25.212181) (xy 388.517521 -25.170992)
			(xy 388.558713 -25.135303) (xy 388.604565 -25.10584) (xy 388.654144 -25.083202) (xy 388.70644 -25.067852)
			(xy 388.760389 -25.0601) (xy 388.78764 -25.05964) (xy 389.65124 -25.05964) (xy 389.678493 -25.060033)
			(xy 389.732443 -25.067795) (xy 389.78474 -25.083155) (xy 389.834318 -25.105802) (xy 389.880169 -25.135273)
			(xy 389.92136 -25.170969) (xy 389.957051 -25.212163) (xy 389.986518 -25.258017) (xy 390.009159 -25.307598)
			(xy 390.024514 -25.359896) (xy 390.03227 -25.413847) (xy 390.03227 -25.468353) (xy 390.024514 -25.522304)
			(xy 390.009159 -25.574602) (xy 389.986518 -25.624183) (xy 389.957051 -25.670037) (xy 389.92136 -25.711231)
			(xy 389.880169 -25.746927) (xy 389.834318 -25.776398) (xy 389.78474 -25.799045) (xy 389.732443 -25.814405)
			(xy 389.678493 -25.822167) (xy 389.65124 -25.822656) (xy 388.78764 -25.822656) (xy 388.760389 -25.8221)
			(xy 388.70644 -25.814348) (xy 388.654144 -25.798998) (xy 388.604565 -25.77636) (xy 388.558713 -25.746897)
			(xy 388.517521 -25.711208) (xy 388.481827 -25.670019) (xy 388.452359 -25.62417) (xy 388.429716 -25.574593)
			(xy 388.41436 -25.522299) (xy 388.406603 -25.468351) (xy 259.309108 -25.468351) (xy 259.309108 -28.450032)
			(xy 354.840804 -28.450032) (xy 354.844787 -28.322014) (xy 354.856722 -28.194492) (xy 354.876561 -28.067958)
			(xy 354.904228 -27.942902) (xy 354.939617 -27.819809) (xy 354.98259 -27.699153) (xy 355.032981 -27.581403)
			(xy 355.090595 -27.467013) (xy 355.155209 -27.356426) (xy 355.226573 -27.25007) (xy 355.304411 -27.148357)
			(xy 355.388422 -27.051679) (xy 355.478281 -26.960412) (xy 355.57364 -26.874907) (xy 355.674131 -26.795497)
			(xy 355.779364 -26.722487) (xy 355.888933 -26.656161) (xy 356.002413 -26.596775) (xy 356.119365 -26.544559)
			(xy 356.239338 -26.499715) (xy 356.361866 -26.462417) (xy 356.486477 -26.432808) (xy 356.612686 -26.411003)
			(xy 356.740008 -26.397087) (xy 356.867948 -26.391113) (xy 356.996012 -26.393105) (xy 357.123705 -26.403055)
			(xy 357.250532 -26.420924) (xy 357.376003 -26.446643) (xy 357.499632 -26.480113) (xy 357.620941 -26.521204)
			(xy 357.739461 -26.569758) (xy 357.854733 -26.625586) (xy 357.966311 -26.688472) (xy 358.073764 -26.758174)
			(xy 358.176676 -26.834421) (xy 358.274648 -26.916918) (xy 358.367302 -27.005347) (xy 358.454279 -27.099365)
			(xy 358.535243 -27.198608) (xy 358.60988 -27.302693) (xy 358.677902 -27.411217) (xy 358.739046 -27.52376)
			(xy 358.793074 -27.639886) (xy 358.839779 -27.759147) (xy 358.878979 -27.88108) (xy 358.910522 -28.005215)
			(xy 358.934287 -28.131071) (xy 358.950181 -28.25816) (xy 358.958144 -28.385992) (xy 358.958642 -28.450032)
			(xy 358.958144 -28.514072) (xy 358.950181 -28.641904) (xy 358.934287 -28.768993) (xy 358.910522 -28.894849)
			(xy 358.878979 -29.018984) (xy 358.839779 -29.140917) (xy 358.793074 -29.260178) (xy 358.739046 -29.376304)
			(xy 358.677902 -29.488847) (xy 358.60988 -29.597371) (xy 358.535243 -29.701456) (xy 358.454279 -29.800699)
			(xy 358.367302 -29.894717) (xy 358.274648 -29.983146) (xy 358.176676 -30.065643) (xy 358.073764 -30.14189)
			(xy 357.966311 -30.211592) (xy 357.854733 -30.274478) (xy 357.739461 -30.330306) (xy 357.620941 -30.37886)
			(xy 357.499632 -30.419951) (xy 357.376003 -30.453421) (xy 357.250532 -30.47914) (xy 357.123705 -30.497009)
			(xy 356.996012 -30.506959) (xy 356.867948 -30.508951) (xy 356.740008 -30.502977) (xy 356.612686 -30.489061)
			(xy 356.486477 -30.467256) (xy 356.361866 -30.437647) (xy 356.239338 -30.400349) (xy 356.119365 -30.355505)
			(xy 356.002413 -30.303289) (xy 355.888933 -30.243903) (xy 355.779364 -30.177577) (xy 355.674131 -30.104567)
			(xy 355.57364 -30.025157) (xy 355.478281 -29.939652) (xy 355.388422 -29.848385) (xy 355.304411 -29.751707)
			(xy 355.226573 -29.649994) (xy 355.155209 -29.543638) (xy 355.090595 -29.433051) (xy 355.032981 -29.318661)
			(xy 354.98259 -29.200911) (xy 354.939617 -29.080255) (xy 354.904228 -28.957162) (xy 354.876561 -28.832106)
			(xy 354.856722 -28.705572) (xy 354.844787 -28.57805) (xy 354.840804 -28.450032) (xy 259.309108 -28.450032)
			(xy 259.309108 -33.275016) (xy 259.308614 -33.345398) (xy 259.30072 -33.48594) (xy 259.284959 -33.625819)
			(xy 259.261379 -33.764594) (xy 259.230448 -33.90011) (xy 462.69148 -33.90011) (xy 462.69148 -32.29991)
			(xy 462.691988 -32.23523) (xy 462.700111 -32.106124) (xy 462.716324 -31.977784) (xy 462.740564 -31.850714)
			(xy 462.772734 -31.725418) (xy 462.812709 -31.602388) (xy 462.86033 -31.482112) (xy 462.915409 -31.365063)
			(xy 462.977729 -31.251703) (xy 463.047044 -31.14248) (xy 463.12308 -31.037825) (xy 463.205538 -30.938151)
			(xy 463.294091 -30.843851) (xy 463.388391 -30.755298) (xy 463.488065 -30.67284) (xy 463.59272 -30.596804)
			(xy 463.701943 -30.527489) (xy 463.815303 -30.465169) (xy 463.932352 -30.41009) (xy 464.052628 -30.362469)
			(xy 464.175658 -30.322494) (xy 464.300954 -30.290324) (xy 464.428024 -30.266084) (xy 464.556364 -30.249871)
			(xy 464.68547 -30.241748) (xy 464.81483 -30.241748) (xy 464.943936 -30.249871) (xy 465.072276 -30.266084)
			(xy 465.199346 -30.290324) (xy 465.324642 -30.322494) (xy 465.447672 -30.362469) (xy 465.567948 -30.41009)
			(xy 465.684997 -30.465169) (xy 465.798357 -30.527489) (xy 465.90758 -30.596804) (xy 466.012235 -30.67284)
			(xy 466.111909 -30.755298) (xy 466.206209 -30.843851) (xy 466.294762 -30.938151) (xy 466.37722 -31.037825)
			(xy 466.453256 -31.14248) (xy 466.522571 -31.251703) (xy 466.584891 -31.365063) (xy 466.63997 -31.482112)
			(xy 466.687591 -31.602388) (xy 466.727566 -31.725418) (xy 466.759736 -31.850714) (xy 466.783976 -31.977784)
			(xy 466.800189 -32.106124) (xy 466.808312 -32.23523) (xy 466.80882 -32.29991) (xy 466.80882 -33.90011)
			(xy 466.808312 -33.96479) (xy 466.800189 -34.093896) (xy 466.783976 -34.222236) (xy 466.759736 -34.349306)
			(xy 466.727566 -34.474602) (xy 466.687591 -34.597632) (xy 466.63997 -34.717908) (xy 466.584891 -34.834957)
			(xy 466.522571 -34.948317) (xy 466.453256 -35.05754) (xy 466.37722 -35.162195) (xy 466.294762 -35.261869)
			(xy 466.206209 -35.356169) (xy 466.111909 -35.444722) (xy 466.012235 -35.52718) (xy 465.90758 -35.603216)
			(xy 465.798357 -35.672531) (xy 465.684997 -35.734851) (xy 465.567948 -35.78993) (xy 465.447672 -35.837551)
			(xy 465.324642 -35.877526) (xy 465.199346 -35.909696) (xy 465.072276 -35.933936) (xy 464.943936 -35.950149)
			(xy 464.81483 -35.958272) (xy 464.68547 -35.958272) (xy 464.556364 -35.950149) (xy 464.428024 -35.933936)
			(xy 464.300954 -35.909696) (xy 464.175658 -35.877526) (xy 464.052628 -35.837551) (xy 463.932352 -35.78993)
			(xy 463.815303 -35.734851) (xy 463.701943 -35.672531) (xy 463.59272 -35.603216) (xy 463.488065 -35.52718)
			(xy 463.388391 -35.444722) (xy 463.294091 -35.356169) (xy 463.205538 -35.261869) (xy 463.12308 -35.162195)
			(xy 463.047044 -35.05754) (xy 462.977729 -34.948317) (xy 462.915409 -34.834957) (xy 462.86033 -34.717908)
			(xy 462.812709 -34.597632) (xy 462.772734 -34.474602) (xy 462.740564 -34.349306) (xy 462.716324 -34.222236)
			(xy 462.700111 -34.093896) (xy 462.691988 -33.96479) (xy 462.69148 -33.90011) (xy 259.230448 -33.90011)
			(xy 259.230056 -33.901828) (xy 259.191086 -34.03709) (xy 259.144594 -34.169955) (xy 259.090726 -34.300003)
			(xy 259.02965 -34.426827) (xy 258.961559 -34.550026) (xy 258.886668 -34.669214) (xy 258.805211 -34.784015)
			(xy 258.717446 -34.894068) (xy 258.623648 -34.999027) (xy 258.524113 -35.098562) (xy 258.419153 -35.192359)
			(xy 258.324611 -35.267753) (xy 356.989346 -35.267753) (xy 356.989346 -35.213247) (xy 356.997102 -35.159297)
			(xy 357.012458 -35.106999) (xy 357.035099 -35.057419) (xy 357.064566 -35.011566) (xy 357.100259 -34.970373)
			(xy 357.14145 -34.934678) (xy 357.187302 -34.905209) (xy 357.236881 -34.882565) (xy 357.289177 -34.867207)
			(xy 357.343127 -34.859447) (xy 357.37038 -34.85896) (xy 358.23398 -34.85896) (xy 358.261232 -34.859486)
			(xy 358.31518 -34.86724) (xy 358.367476 -34.882593) (xy 358.417054 -34.905232) (xy 358.462906 -34.934697)
			(xy 358.504098 -34.970388) (xy 358.539791 -35.011578) (xy 358.569258 -35.057428) (xy 358.5919 -35.107005)
			(xy 358.607256 -35.1593) (xy 358.615013 -35.213249) (xy 358.615013 -35.267751) (xy 358.607256 -35.3217)
			(xy 358.5919 -35.373995) (xy 358.569258 -35.423572) (xy 358.539791 -35.469422) (xy 358.504098 -35.510612)
			(xy 358.462906 -35.546303) (xy 358.417054 -35.575768) (xy 358.367476 -35.598407) (xy 358.31518 -35.61376)
			(xy 358.261232 -35.621514) (xy 358.23398 -35.621976) (xy 357.37038 -35.621976) (xy 357.343127 -35.621553)
			(xy 357.289177 -35.613793) (xy 357.236881 -35.598435) (xy 357.187302 -35.575791) (xy 357.14145 -35.546322)
			(xy 357.100259 -35.510627) (xy 357.064566 -35.469434) (xy 357.035099 -35.423581) (xy 357.012458 -35.374001)
			(xy 356.997102 -35.321703) (xy 356.989346 -35.267753) (xy 258.324611 -35.267753) (xy 258.309099 -35.280123)
			(xy 258.194297 -35.361579) (xy 258.075109 -35.436469) (xy 257.951909 -35.504559) (xy 257.825085 -35.565634)
			(xy 257.695036 -35.619502) (xy 257.562171 -35.665993) (xy 257.426909 -35.704961) (xy 257.289674 -35.736283)
			(xy 257.150899 -35.759862) (xy 257.01102 -35.775622) (xy 256.870478 -35.783514) (xy 256.800096 -35.784028)
			(xy 225.300032 -35.784028) (xy 225.229649 -35.783544) (xy 225.089104 -35.775653) (xy 224.949222 -35.759894)
			(xy 224.810444 -35.736316) (xy 224.673207 -35.704995) (xy 224.537941 -35.666027) (xy 224.405074 -35.619536)
			(xy 224.275022 -35.565669) (xy 224.148195 -35.504594) (xy 224.024992 -35.436504) (xy 223.905801 -35.361613)
			(xy 223.790997 -35.280156) (xy 223.68094 -35.192391) (xy 223.575978 -35.098593) (xy 223.47644 -34.999057)
			(xy 223.38264 -34.894096) (xy 223.294872 -34.784042) (xy 223.213414 -34.669239) (xy 223.138521 -34.550049)
			(xy 223.070428 -34.426848) (xy 223.009351 -34.300022) (xy 222.955481 -34.169971) (xy 222.908988 -34.037104)
			(xy 222.870017 -33.90184) (xy 222.838693 -33.764603) (xy 222.815113 -33.625825) (xy 222.799351 -33.485944)
			(xy 222.791457 -33.345399) (xy 222.79102 -33.275016) (xy 222.79102 -13.780008) (xy 222.790499 -13.724238)
			(xy 222.782164 -13.613011) (xy 222.765541 -13.502717) (xy 222.740722 -13.393974) (xy 222.707846 -13.287389)
			(xy 222.667097 -13.183559) (xy 222.618703 -13.083065) (xy 222.562935 -12.986469) (xy 222.500103 -12.894309)
			(xy 222.430561 -12.807103) (xy 222.354696 -12.725338) (xy 222.272933 -12.64947) (xy 222.185729 -12.579925)
			(xy 222.093572 -12.517091) (xy 221.996977 -12.461319) (xy 221.896485 -12.412922) (xy 221.792656 -12.37217)
			(xy 221.686073 -12.339291) (xy 221.57733 -12.314468) (xy 221.467037 -12.297841) (xy 221.35581 -12.289503)
			(xy 221.30004 -12.289028) (xy 196.701918 -12.289028) (xy 196.631535 -12.288544) (xy 196.49099 -12.280652)
			(xy 196.35111 -12.264892) (xy 196.212332 -12.241314) (xy 196.075095 -12.209992) (xy 195.939831 -12.171024)
			(xy 195.806964 -12.124532) (xy 195.676913 -12.070665) (xy 195.550086 -12.009589) (xy 195.426884 -11.941499)
			(xy 195.307694 -11.866608) (xy 195.19289 -11.785152) (xy 195.082834 -11.697386) (xy 194.977873 -11.603588)
			(xy 194.878335 -11.504052) (xy 194.784536 -11.399092) (xy 194.696769 -11.289037) (xy 194.615311 -11.174234)
			(xy 194.540418 -11.055045) (xy 194.472326 -10.931844) (xy 194.411249 -10.805018) (xy 194.35738 -10.674968)
			(xy 194.310887 -10.542102) (xy 194.271917 -10.406837) (xy 194.240593 -10.269601) (xy 194.217013 -10.130824)
			(xy 194.201251 -9.990943) (xy 194.193357 -9.850399) (xy 194.192906 -9.780016) (xy 194.192906 -6.279896)
			(xy 194.19238 -6.247749) (xy 194.183988 -6.184006) (xy 194.167348 -6.121904) (xy 194.142744 -6.062504)
			(xy 194.110598 -6.006824) (xy 194.07146 -5.955816) (xy 194.025999 -5.910353) (xy 193.974992 -5.871213)
			(xy 193.919314 -5.839064) (xy 193.859915 -5.814458) (xy 193.797813 -5.797816) (xy 193.734071 -5.789421)
			(xy 193.701924 -5.788914) (xy 127.102108 -5.788914) (xy 127.06996 -5.789416) (xy 127.006214 -5.797808)
			(xy 126.944108 -5.814448) (xy 126.884706 -5.839052) (xy 126.829023 -5.8712) (xy 126.778013 -5.91034)
			(xy 126.732548 -5.955804) (xy 126.693406 -6.006813) (xy 126.661257 -6.062495) (xy 126.636652 -6.121897)
			(xy 126.62001 -6.184002) (xy 126.611617 -6.247748) (xy 126.611126 -6.279896) (xy 126.611126 -9.780016)
			(xy 126.610632 -9.850398) (xy 126.602738 -9.990941) (xy 126.586977 -10.13082) (xy 126.563397 -10.269595)
			(xy 126.532074 -10.40683) (xy 126.519617 -10.450068) (xy 127.350273 -10.450068) (xy 127.354278 -10.36216)
			(xy 127.366261 -10.27498) (xy 127.386121 -10.189251) (xy 127.413696 -10.105683) (xy 127.448755 -10.024969)
			(xy 127.491008 -9.947777) (xy 127.540106 -9.874748) (xy 127.595642 -9.806486) (xy 127.657154 -9.743556)
			(xy 127.724135 -9.686482) (xy 127.796028 -9.635734) (xy 127.872237 -9.591734) (xy 127.952132 -9.554847)
			(xy 128.035051 -9.525378) (xy 128.120306 -9.503571) (xy 128.20719 -9.489607) (xy 128.294984 -9.483601)
			(xy 128.382961 -9.485605) (xy 128.470391 -9.4956) (xy 128.55655 -9.513504) (xy 128.640724 -9.539168)
			(xy 128.722215 -9.572381) (xy 128.800349 -9.612867) (xy 128.874477 -9.660289) (xy 128.943985 -9.714256)
			(xy 129.008299 -9.774321) (xy 129.066883 -9.839985) (xy 129.119254 -9.910704) (xy 129.164977 -9.985892)
			(xy 129.203674 -10.064927) (xy 129.235023 -10.147153) (xy 129.258765 -10.231889) (xy 129.265884 -10.270548)
			(xy 131.63909 -10.270548) (xy 131.63909 -10.216052) (xy 131.646845 -10.16211) (xy 131.662198 -10.10982)
			(xy 131.684835 -10.060247) (xy 131.714296 -10.014401) (xy 131.749982 -9.973213) (xy 131.791165 -9.937522)
			(xy 131.837009 -9.908056) (xy 131.886579 -9.885413) (xy 131.938866 -9.870055) (xy 131.992808 -9.862293)
			(xy 132.020056 -9.861804) (xy 132.883656 -9.861804) (xy 132.910912 -9.86224) (xy 132.964869 -9.869992)
			(xy 133.017174 -9.885345) (xy 133.066761 -9.907985) (xy 133.112622 -9.937453) (xy 133.153821 -9.973148)
			(xy 133.18952 -10.014343) (xy 133.218993 -10.0602) (xy 133.24164 -10.109785) (xy 133.256999 -10.162088)
			(xy 133.264757 -10.216044) (xy 133.264757 -10.270556) (xy 133.256999 -10.324512) (xy 133.24164 -10.376815)
			(xy 133.218993 -10.4264) (xy 133.18952 -10.472257) (xy 133.153821 -10.513452) (xy 133.112622 -10.549147)
			(xy 133.066761 -10.578615) (xy 133.017174 -10.601255) (xy 132.964869 -10.616608) (xy 132.910912 -10.62436)
			(xy 132.883656 -10.62482) (xy 132.020056 -10.62482) (xy 131.992808 -10.624307) (xy 131.938866 -10.616545)
			(xy 131.886579 -10.601187) (xy 131.837009 -10.578544) (xy 131.791165 -10.549078) (xy 131.749982 -10.513387)
			(xy 131.714296 -10.472199) (xy 131.684835 -10.426353) (xy 131.662198 -10.37678) (xy 131.646845 -10.32449)
			(xy 131.63909 -10.270548) (xy 129.265884 -10.270548) (xy 129.274703 -10.318433) (xy 129.282705 -10.406068)
			(xy 129.283206 -10.450068) (xy 129.282705 -10.494068) (xy 129.274703 -10.581703) (xy 129.258765 -10.668247)
			(xy 129.235023 -10.752983) (xy 129.203674 -10.835209) (xy 129.164977 -10.914244) (xy 129.119254 -10.989432)
			(xy 129.087321 -11.032553) (xy 168.158867 -11.032553) (xy 168.158867 -10.978047) (xy 168.166625 -10.924096)
			(xy 168.181981 -10.871798) (xy 168.204625 -10.822218) (xy 168.234094 -10.776365) (xy 168.269789 -10.735173)
			(xy 168.310983 -10.699481) (xy 168.356837 -10.670014) (xy 168.406419 -10.647374) (xy 168.458717 -10.63202)
			(xy 168.512669 -10.624266) (xy 168.539922 -10.623804) (xy 169.403522 -10.623804) (xy 169.430773 -10.624267)
			(xy 169.48472 -10.632027) (xy 169.537014 -10.647384) (xy 169.58659 -10.670027) (xy 169.632439 -10.699495)
			(xy 169.673628 -10.735188) (xy 169.709318 -10.776379) (xy 169.738783 -10.822229) (xy 169.761424 -10.871807)
			(xy 169.776778 -10.924101) (xy 169.784534 -10.978049) (xy 169.784534 -11.032551) (xy 169.776778 -11.086499)
			(xy 169.761424 -11.138793) (xy 169.738783 -11.188371) (xy 169.709318 -11.234221) (xy 169.673628 -11.275412)
			(xy 169.632439 -11.311105) (xy 169.58659 -11.340573) (xy 169.537014 -11.363216) (xy 169.48472 -11.378573)
			(xy 169.430773 -11.386333) (xy 169.403522 -11.38682) (xy 168.539922 -11.38682) (xy 168.512669 -11.386334)
			(xy 168.458717 -11.37858) (xy 168.406419 -11.363226) (xy 168.356837 -11.340586) (xy 168.310983 -11.311119)
			(xy 168.269789 -11.275427) (xy 168.234094 -11.234235) (xy 168.204625 -11.188382) (xy 168.181981 -11.138802)
			(xy 168.166625 -11.086504) (xy 168.158867 -11.032553) (xy 129.087321 -11.032553) (xy 129.066883 -11.060151)
			(xy 129.008299 -11.125815) (xy 128.943985 -11.18588) (xy 128.874477 -11.239847) (xy 128.800349 -11.287269)
			(xy 128.722215 -11.327755) (xy 128.640724 -11.360968) (xy 128.55655 -11.386632) (xy 128.470391 -11.404536)
			(xy 128.382961 -11.414531) (xy 128.294984 -11.416535) (xy 128.20719 -11.410529) (xy 128.120306 -11.396565)
			(xy 128.035051 -11.374758) (xy 127.952132 -11.345289) (xy 127.872237 -11.308402) (xy 127.796028 -11.264402)
			(xy 127.724135 -11.213654) (xy 127.657154 -11.15658) (xy 127.595642 -11.09365) (xy 127.540106 -11.025388)
			(xy 127.491008 -10.952359) (xy 127.448755 -10.875167) (xy 127.413696 -10.794453) (xy 127.386121 -10.710885)
			(xy 127.366261 -10.625156) (xy 127.354278 -10.537976) (xy 127.350273 -10.450068) (xy 126.519617 -10.450068)
			(xy 126.493105 -10.542092) (xy 126.446613 -10.674957) (xy 126.392744 -10.805006) (xy 126.331668 -10.93183)
			(xy 126.263578 -11.05503) (xy 126.188687 -11.174218) (xy 126.10723 -11.28902) (xy 126.019465 -11.399074)
			(xy 125.973895 -11.450066) (xy 191.515245 -11.450066) (xy 191.51925 -11.362158) (xy 191.531233 -11.274978)
			(xy 191.551093 -11.189249) (xy 191.578668 -11.105681) (xy 191.613727 -11.024967) (xy 191.65598 -10.947775)
			(xy 191.705078 -10.874746) (xy 191.760614 -10.806484) (xy 191.822126 -10.743554) (xy 191.889107 -10.68648)
			(xy 191.961 -10.635732) (xy 192.037209 -10.591732) (xy 192.117104 -10.554845) (xy 192.200023 -10.525376)
			(xy 192.285278 -10.503569) (xy 192.372162 -10.489605) (xy 192.459956 -10.483599) (xy 192.547933 -10.485603)
			(xy 192.635363 -10.495598) (xy 192.721522 -10.513502) (xy 192.805696 -10.539166) (xy 192.887187 -10.572379)
			(xy 192.965321 -10.612865) (xy 193.039449 -10.660287) (xy 193.108957 -10.714254) (xy 193.173271 -10.774319)
			(xy 193.231855 -10.839983) (xy 193.284226 -10.910702) (xy 193.329949 -10.98589) (xy 193.368646 -11.064925)
			(xy 193.399995 -11.147151) (xy 193.423737 -11.231887) (xy 193.439675 -11.318431) (xy 193.447677 -11.406066)
			(xy 193.448178 -11.450066) (xy 193.447677 -11.494066) (xy 193.439675 -11.581701) (xy 193.423737 -11.668245)
			(xy 193.399995 -11.752981) (xy 193.368646 -11.835207) (xy 193.329949 -11.914242) (xy 193.284226 -11.98943)
			(xy 193.231855 -12.060149) (xy 193.173271 -12.125813) (xy 193.108957 -12.185878) (xy 193.039449 -12.239845)
			(xy 192.965321 -12.287267) (xy 192.887187 -12.327753) (xy 192.805696 -12.360966) (xy 192.721522 -12.38663)
			(xy 192.635363 -12.404534) (xy 192.547933 -12.414529) (xy 192.459956 -12.416533) (xy 192.372162 -12.410527)
			(xy 192.285278 -12.396563) (xy 192.200023 -12.374756) (xy 192.117104 -12.345287) (xy 192.037209 -12.3084)
			(xy 191.961 -12.2644) (xy 191.889107 -12.213652) (xy 191.822126 -12.156578) (xy 191.760614 -12.093648)
			(xy 191.705078 -12.025386) (xy 191.65598 -11.952357) (xy 191.613727 -11.875165) (xy 191.578668 -11.794451)
			(xy 191.551093 -11.710883) (xy 191.531233 -11.625154) (xy 191.51925 -11.537974) (xy 191.515245 -11.450066)
			(xy 125.973895 -11.450066) (xy 125.925667 -11.504033) (xy 125.826132 -11.603569) (xy 125.721172 -11.697366)
			(xy 125.611118 -11.785131) (xy 125.496317 -11.866588) (xy 125.377128 -11.941479) (xy 125.253928 -12.009569)
			(xy 125.206611 -12.032356) (xy 166.354411 -12.032356) (xy 166.354411 -11.977844) (xy 166.362169 -11.923886)
			(xy 166.377527 -11.871582) (xy 166.400173 -11.821995) (xy 166.429645 -11.776137) (xy 166.465343 -11.734939)
			(xy 166.506541 -11.699241) (xy 166.552401 -11.66977) (xy 166.601987 -11.647125) (xy 166.654292 -11.631768)
			(xy 166.70825 -11.624011) (xy 166.735506 -11.623548) (xy 167.599106 -11.623548) (xy 167.626354 -11.624123)
			(xy 167.680295 -11.631879) (xy 167.732583 -11.647233) (xy 167.782153 -11.669872) (xy 167.827998 -11.699335)
			(xy 167.869182 -11.735022) (xy 167.904869 -11.776207) (xy 167.934331 -11.822052) (xy 167.956969 -11.871623)
			(xy 167.972322 -11.923911) (xy 167.980078 -11.977852) (xy 167.980078 -12.032348) (xy 167.980077 -12.032358)
			(xy 169.954311 -12.032358) (xy 169.954311 -11.977842) (xy 169.96207 -11.92388) (xy 169.97743 -11.871573)
			(xy 170.000079 -11.821984) (xy 170.029555 -11.776123) (xy 170.065258 -11.734924) (xy 170.106461 -11.699226)
			(xy 170.152326 -11.669756) (xy 170.201918 -11.647114) (xy 170.254227 -11.63176) (xy 170.30819 -11.624008)
			(xy 170.335448 -11.623548) (xy 171.199048 -11.623548) (xy 171.226294 -11.624125) (xy 171.28023 -11.631887)
			(xy 171.332513 -11.647244) (xy 171.382078 -11.669885) (xy 171.427917 -11.699349) (xy 171.469097 -11.735037)
			(xy 171.504779 -11.776221) (xy 171.534238 -11.822064) (xy 171.556873 -11.871632) (xy 171.572224 -11.923917)
			(xy 171.579978 -11.977854) (xy 171.579978 -12.032346) (xy 171.572224 -12.086283) (xy 171.556873 -12.138568)
			(xy 171.534238 -12.188136) (xy 171.504779 -12.233979) (xy 171.469097 -12.275163) (xy 171.427917 -12.310851)
			(xy 171.382078 -12.340315) (xy 171.332513 -12.362956) (xy 171.28023 -12.378313) (xy 171.226294 -12.386075)
			(xy 171.199048 -12.386564) (xy 170.335448 -12.386564) (xy 170.30819 -12.386192) (xy 170.254227 -12.37844)
			(xy 170.201918 -12.363086) (xy 170.152326 -12.340444) (xy 170.106461 -12.310974) (xy 170.065258 -12.275276)
			(xy 170.029555 -12.234077) (xy 170.000079 -12.188216) (xy 169.97743 -12.138627) (xy 169.96207 -12.08632)
			(xy 169.954311 -12.032358) (xy 167.980077 -12.032358) (xy 167.972322 -12.086289) (xy 167.956969 -12.138577)
			(xy 167.934331 -12.188148) (xy 167.904869 -12.233993) (xy 167.869182 -12.275178) (xy 167.827998 -12.310865)
			(xy 167.782153 -12.340328) (xy 167.732583 -12.362967) (xy 167.680295 -12.378321) (xy 167.626354 -12.386077)
			(xy 167.599106 -12.386564) (xy 166.735506 -12.386564) (xy 166.70825 -12.386189) (xy 166.654292 -12.378432)
			(xy 166.601987 -12.363075) (xy 166.552401 -12.34043) (xy 166.506541 -12.310959) (xy 166.465343 -12.275261)
			(xy 166.429645 -12.234063) (xy 166.400173 -12.188205) (xy 166.377527 -12.138618) (xy 166.362169 -12.086314)
			(xy 166.354411 -12.032356) (xy 125.206611 -12.032356) (xy 125.127104 -12.070645) (xy 124.997055 -12.124513)
			(xy 124.86419 -12.171005) (xy 124.728928 -12.209974) (xy 124.591693 -12.241298) (xy 124.452918 -12.264877)
			(xy 124.313039 -12.280639) (xy 124.172496 -12.288532) (xy 124.102114 -12.289028) (xy 83.70189 -12.289028)
			(xy 83.631508 -12.288534) (xy 83.490965 -12.280641) (xy 83.351086 -12.26488) (xy 83.21231 -12.2413)
			(xy 83.075075 -12.209977) (xy 82.939812 -12.171008) (xy 82.806947 -12.124516) (xy 82.676898 -12.070648)
			(xy 82.550073 -12.009572) (xy 82.426873 -11.941482) (xy 82.307684 -11.866591) (xy 82.192882 -11.785134)
			(xy 82.082828 -11.697369) (xy 81.977868 -11.603571) (xy 81.878333 -11.504036) (xy 81.784535 -11.399076)
			(xy 81.696769 -11.289022) (xy 81.615313 -11.174221) (xy 81.540421 -11.055032) (xy 81.47233 -10.931832)
			(xy 81.411254 -10.805008) (xy 81.357386 -10.674959) (xy 81.310894 -10.542094) (xy 81.271924 -10.406831)
			(xy 81.240601 -10.269596) (xy 81.217021 -10.13082) (xy 81.20126 -9.990941) (xy 81.193366 -9.850398)
			(xy 81.192878 -9.780016) (xy 81.192878 -0.999998) (xy 81.192375 -0.96785) (xy 81.183982 -0.904106)
			(xy 81.167341 -0.842001) (xy 81.142736 -0.782601) (xy 81.110589 -0.72692) (xy 81.071448 -0.675911)
			(xy 81.025984 -0.630448) (xy 80.974975 -0.591308) (xy 80.919294 -0.559161) (xy 80.859893 -0.534557)
			(xy 80.797789 -0.517916) (xy 80.734044 -0.509525) (xy 80.701896 -0.509016) (xy 14.10208 -0.509016)
			(xy 14.069935 -0.509543) (xy 14.006194 -0.517937) (xy 13.944095 -0.534579) (xy 13.884698 -0.559184)
			(xy 13.829022 -0.59133) (xy 13.778017 -0.630469) (xy 13.732558 -0.675931) (xy 13.69342 -0.726937)
			(xy 13.661276 -0.782614) (xy 13.636673 -0.842012) (xy 13.620034 -0.904112) (xy 13.611642 -0.967853)
			(xy 13.611098 -0.999998) (xy 13.611098 -5.184498) (xy 14.350702 -5.184498) (xy 14.35331 -5.097781)
			(xy 14.363685 -5.011647) (xy 14.381743 -4.926791) (xy 14.40734 -4.843896) (xy 14.440268 -4.763631)
			(xy 14.480262 -4.686643) (xy 14.526999 -4.613552) (xy 14.580104 -4.544948) (xy 14.639148 -4.481383)
			(xy 14.703655 -4.42337) (xy 14.738096 -4.396994) (xy 14.773029 -4.371293) (xy 14.846784 -4.325653)
			(xy 14.924335 -4.28681) (xy 15.005056 -4.255076) (xy 15.088297 -4.230709) (xy 15.173387 -4.213903)
			(xy 15.259642 -4.204794) (xy 15.346366 -4.203455) (xy 15.432861 -4.209898) (xy 15.518429 -4.224071)
			(xy 15.602382 -4.245858) (xy 15.684044 -4.275086) (xy 15.762756 -4.311517) (xy 15.837884 -4.35486)
			(xy 15.908824 -4.404764) (xy 15.975003 -4.460828) (xy 16.035889 -4.5226) (xy 16.090991 -4.589582)
			(xy 16.139865 -4.661235) (xy 16.182118 -4.736981) (xy 16.217409 -4.816211) (xy 16.245454 -4.898286)
			(xy 16.266027 -4.982545) (xy 16.267136 -4.989901) (xy 20.44038 -4.989901) (xy 20.44038 -4.935399)
			(xy 20.448136 -4.881452) (xy 20.463491 -4.829158) (xy 20.486132 -4.779581) (xy 20.515597 -4.733731)
			(xy 20.551288 -4.692541) (xy 20.592478 -4.65685) (xy 20.638328 -4.627384) (xy 20.687904 -4.604742)
			(xy 20.740198 -4.589387) (xy 20.794145 -4.58163) (xy 20.821396 -4.581144) (xy 21.684996 -4.581144)
			(xy 21.712249 -4.581603) (xy 21.766201 -4.58936) (xy 21.818499 -4.604715) (xy 21.86808 -4.627358)
			(xy 21.913934 -4.656826) (xy 21.955128 -4.69252) (xy 21.990822 -4.733713) (xy 22.02029 -4.779566)
			(xy 22.042933 -4.829147) (xy 22.05829 -4.881445) (xy 22.066047 -4.935397) (xy 22.066047 -4.989901)
			(xy 24.04032 -4.989901) (xy 24.04032 -4.935399) (xy 24.048076 -4.881452) (xy 24.063431 -4.829157)
			(xy 24.086072 -4.779581) (xy 24.115538 -4.73373) (xy 24.151229 -4.692541) (xy 24.192419 -4.656849)
			(xy 24.238269 -4.627383) (xy 24.287846 -4.604742) (xy 24.34014 -4.589387) (xy 24.394087 -4.58163)
			(xy 24.421338 -4.581144) (xy 25.284938 -4.581144) (xy 25.312191 -4.581603) (xy 25.366143 -4.58936)
			(xy 25.418441 -4.604716) (xy 25.468021 -4.627358) (xy 25.513875 -4.656827) (xy 25.555068 -4.69252)
			(xy 25.590762 -4.733713) (xy 25.620231 -4.779567) (xy 25.642873 -4.829147) (xy 25.65823 -4.881446)
			(xy 25.665987 -4.935397) (xy 25.665987 -4.989903) (xy 25.66598 -4.989954) (xy 27.64023 -4.989954)
			(xy 27.64023 -4.935446) (xy 27.647987 -4.881493) (xy 27.663343 -4.829194) (xy 27.685985 -4.779612)
			(xy 27.715454 -4.733756) (xy 27.751147 -4.692562) (xy 27.79234 -4.656866) (xy 27.838194 -4.627395)
			(xy 27.887775 -4.60475) (xy 27.940074 -4.589391) (xy 27.994026 -4.581631) (xy 28.02128 -4.581144)
			(xy 28.88488 -4.581144) (xy 28.91213 -4.581702) (xy 28.966077 -4.589456) (xy 29.01837 -4.604808)
			(xy 29.067947 -4.627446) (xy 29.113797 -4.65691) (xy 29.154986 -4.692599) (xy 29.190678 -4.733787)
			(xy 29.220144 -4.779636) (xy 29.242785 -4.829211) (xy 29.25814 -4.881504) (xy 29.265897 -4.93545)
			(xy 29.265897 -4.98995) (xy 29.265896 -4.989954) (xy 31.24043 -4.989954) (xy 31.24043 -4.935446)
			(xy 31.248187 -4.881494) (xy 31.263543 -4.829195) (xy 31.286185 -4.779613) (xy 31.315653 -4.733758)
			(xy 31.351346 -4.692563) (xy 31.392538 -4.656867) (xy 31.438392 -4.627396) (xy 31.487972 -4.604751)
			(xy 31.540271 -4.589392) (xy 31.594222 -4.581632) (xy 31.621476 -4.581144) (xy 32.485076 -4.581144)
			(xy 32.512327 -4.581702) (xy 32.566273 -4.589455) (xy 32.618567 -4.604807) (xy 32.668144 -4.627445)
			(xy 32.713995 -4.656909) (xy 32.755185 -4.692598) (xy 32.790877 -4.733786) (xy 32.820343 -4.779635)
			(xy 32.842985 -4.82921) (xy 32.85834 -4.881503) (xy 32.866097 -4.935449) (xy 32.866097 -4.989951)
			(xy 32.866096 -4.989958) (xy 40.350307 -4.989958) (xy 40.350307 -4.935442) (xy 40.358066 -4.881481)
			(xy 40.373426 -4.829173) (xy 40.396074 -4.779584) (xy 40.42555 -4.733723) (xy 40.461252 -4.692524)
			(xy 40.502455 -4.656826) (xy 40.548319 -4.627355) (xy 40.59791 -4.604712) (xy 40.65022 -4.589358)
			(xy 40.704182 -4.581604) (xy 40.73144 -4.581144) (xy 41.59504 -4.581144) (xy 41.622286 -4.581729)
			(xy 41.676222 -4.589489) (xy 41.728506 -4.604846) (xy 41.778072 -4.627486) (xy 41.823911 -4.65695)
			(xy 41.865091 -4.692637) (xy 41.900774 -4.733821) (xy 41.930233 -4.779663) (xy 41.952868 -4.829232)
			(xy 41.968219 -4.881517) (xy 41.975974 -4.935454) (xy 41.975974 -4.989946) (xy 41.975973 -4.989954)
			(xy 43.95033 -4.989954) (xy 43.95033 -4.935446) (xy 43.958087 -4.881493) (xy 43.973443 -4.829193)
			(xy 43.996086 -4.779611) (xy 44.025554 -4.733756) (xy 44.061248 -4.692561) (xy 44.102441 -4.656865)
			(xy 44.148295 -4.627394) (xy 44.197876 -4.604749) (xy 44.250176 -4.589391) (xy 44.304128 -4.581631)
			(xy 44.331382 -4.581144) (xy 45.194982 -4.581144) (xy 45.222232 -4.581702) (xy 45.276178 -4.589456)
			(xy 45.328472 -4.604808) (xy 45.378048 -4.627447) (xy 45.423898 -4.656911) (xy 45.465087 -4.6926)
			(xy 45.500778 -4.733788) (xy 45.530244 -4.779636) (xy 45.552885 -4.829211) (xy 45.56824 -4.881504)
			(xy 45.575997 -4.93545) (xy 45.575997 -4.98995) (xy 45.575996 -4.989954) (xy 51.56043 -4.989954)
			(xy 51.56043 -4.935446) (xy 51.568187 -4.881494) (xy 51.583543 -4.829195) (xy 51.606185 -4.779613)
			(xy 51.635653 -4.733758) (xy 51.671346 -4.692563) (xy 51.712538 -4.656867) (xy 51.758392 -4.627396)
			(xy 51.807972 -4.604751) (xy 51.860271 -4.589392) (xy 51.914222 -4.581632) (xy 51.941476 -4.581144)
			(xy 52.805076 -4.581144) (xy 52.832327 -4.581702) (xy 52.886273 -4.589455) (xy 52.938567 -4.604807)
			(xy 52.988144 -4.627445) (xy 53.033995 -4.656909) (xy 53.075185 -4.692598) (xy 53.110877 -4.733786)
			(xy 53.140343 -4.779635) (xy 53.162985 -4.82921) (xy 53.17834 -4.881503) (xy 53.186097 -4.935449)
			(xy 53.186097 -4.989951) (xy 53.186096 -4.989957) (xy 55.160307 -4.989957) (xy 55.160307 -4.935443)
			(xy 55.168065 -4.881484) (xy 55.183424 -4.829178) (xy 55.206071 -4.77959) (xy 55.235544 -4.73373)
			(xy 55.271245 -4.692532) (xy 55.312445 -4.656834) (xy 55.358306 -4.627362) (xy 55.407894 -4.604718)
			(xy 55.460201 -4.589362) (xy 55.514161 -4.581606) (xy 55.541418 -4.581144) (xy 56.405018 -4.581144)
			(xy 56.432265 -4.581727) (xy 56.486204 -4.589485) (xy 56.53849 -4.60484) (xy 56.588058 -4.627479)
			(xy 56.633901 -4.656942) (xy 56.675084 -4.692629) (xy 56.710769 -4.733814) (xy 56.74023 -4.779657)
			(xy 56.762867 -4.829227) (xy 56.778219 -4.881514) (xy 56.785974 -4.935453) (xy 56.785974 -4.989947)
			(xy 56.778219 -5.043886) (xy 56.762867 -5.096173) (xy 56.74023 -5.145743) (xy 56.710769 -5.191586)
			(xy 56.675084 -5.232771) (xy 56.633901 -5.268458) (xy 56.588058 -5.297921) (xy 56.53849 -5.32056)
			(xy 56.486204 -5.335915) (xy 56.432265 -5.343673) (xy 56.405018 -5.34416) (xy 55.541418 -5.34416)
			(xy 55.514161 -5.343794) (xy 55.460201 -5.336038) (xy 55.407894 -5.320682) (xy 55.358306 -5.298038)
			(xy 55.312445 -5.268566) (xy 55.271245 -5.232868) (xy 55.235544 -5.19167) (xy 55.206071 -5.14581)
			(xy 55.183424 -5.096222) (xy 55.168065 -5.043916) (xy 55.160307 -4.989957) (xy 53.186096 -4.989957)
			(xy 53.17834 -5.043897) (xy 53.162985 -5.09619) (xy 53.140343 -5.145765) (xy 53.110877 -5.191614)
			(xy 53.075185 -5.232802) (xy 53.033995 -5.268491) (xy 52.988144 -5.297955) (xy 52.938567 -5.320593)
			(xy 52.886273 -5.335945) (xy 52.832327 -5.343698) (xy 52.805076 -5.34416) (xy 51.941476 -5.34416)
			(xy 51.914222 -5.343768) (xy 51.860271 -5.336008) (xy 51.807972 -5.320649) (xy 51.758392 -5.298004)
			(xy 51.712538 -5.268533) (xy 51.671346 -5.232837) (xy 51.635653 -5.191642) (xy 51.606185 -5.145787)
			(xy 51.583543 -5.096205) (xy 51.568187 -5.043906) (xy 51.56043 -4.989954) (xy 45.575996 -4.989954)
			(xy 45.56824 -5.043896) (xy 45.552885 -5.096189) (xy 45.530244 -5.145764) (xy 45.500778 -5.191612)
			(xy 45.465087 -5.2328) (xy 45.423898 -5.268489) (xy 45.378048 -5.297953) (xy 45.328472 -5.320592)
			(xy 45.276178 -5.335944) (xy 45.222232 -5.343698) (xy 45.194982 -5.34416) (xy 44.331382 -5.34416)
			(xy 44.304128 -5.343769) (xy 44.250176 -5.336009) (xy 44.197876 -5.320651) (xy 44.148295 -5.298006)
			(xy 44.102441 -5.268535) (xy 44.061248 -5.232839) (xy 44.025554 -5.191644) (xy 43.996086 -5.145789)
			(xy 43.973443 -5.096207) (xy 43.958087 -5.043907) (xy 43.95033 -4.989954) (xy 41.975973 -4.989954)
			(xy 41.968219 -5.043883) (xy 41.952868 -5.096168) (xy 41.930233 -5.145737) (xy 41.900774 -5.191579)
			(xy 41.865091 -5.232763) (xy 41.823911 -5.26845) (xy 41.778072 -5.297914) (xy 41.728506 -5.320554)
			(xy 41.676222 -5.335911) (xy 41.622286 -5.343671) (xy 41.59504 -5.34416) (xy 40.73144 -5.34416) (xy 40.704182 -5.343796)
			(xy 40.65022 -5.336042) (xy 40.59791 -5.320688) (xy 40.548319 -5.298045) (xy 40.502455 -5.268574)
			(xy 40.461252 -5.232876) (xy 40.42555 -5.191677) (xy 40.396074 -5.145816) (xy 40.373426 -5.096227)
			(xy 40.358066 -5.043919) (xy 40.350307 -4.989958) (xy 32.866096 -4.989958) (xy 32.85834 -5.043897)
			(xy 32.842985 -5.09619) (xy 32.820343 -5.145765) (xy 32.790877 -5.191614) (xy 32.755185 -5.232802)
			(xy 32.713995 -5.268491) (xy 32.668144 -5.297955) (xy 32.618567 -5.320593) (xy 32.566273 -5.335945)
			(xy 32.512327 -5.343698) (xy 32.485076 -5.34416) (xy 31.621476 -5.34416) (xy 31.594222 -5.343768)
			(xy 31.540271 -5.336008) (xy 31.487972 -5.320649) (xy 31.438392 -5.298004) (xy 31.392538 -5.268533)
			(xy 31.351346 -5.232837) (xy 31.315653 -5.191642) (xy 31.286185 -5.145787) (xy 31.263543 -5.096205)
			(xy 31.248187 -5.043906) (xy 31.24043 -4.989954) (xy 29.265896 -4.989954) (xy 29.25814 -5.043896)
			(xy 29.242785 -5.096189) (xy 29.220144 -5.145764) (xy 29.190678 -5.191613) (xy 29.154986 -5.232801)
			(xy 29.113797 -5.26849) (xy 29.067947 -5.297954) (xy 29.01837 -5.320592) (xy 28.966077 -5.335944)
			(xy 28.91213 -5.343698) (xy 28.88488 -5.34416) (xy 28.02128 -5.34416) (xy 27.994026 -5.343769) (xy 27.940074 -5.336009)
			(xy 27.887775 -5.32065) (xy 27.838194 -5.298005) (xy 27.79234 -5.268534) (xy 27.751147 -5.232838)
			(xy 27.715454 -5.191644) (xy 27.685985 -5.145788) (xy 27.663343 -5.096206) (xy 27.647987 -5.043907)
			(xy 27.64023 -4.989954) (xy 25.66598 -4.989954) (xy 25.65823 -5.043854) (xy 25.642873 -5.096153)
			(xy 25.620231 -5.145733) (xy 25.590762 -5.191587) (xy 25.555068 -5.23278) (xy 25.513875 -5.268473)
			(xy 25.468021 -5.297942) (xy 25.418441 -5.320584) (xy 25.366143 -5.33594) (xy 25.312191 -5.343697)
			(xy 25.284938 -5.34416) (xy 24.421338 -5.34416) (xy 24.394087 -5.34367) (xy 24.34014 -5.335913) (xy 24.287846 -5.320558)
			(xy 24.238269 -5.297917) (xy 24.192419 -5.268451) (xy 24.151229 -5.232759) (xy 24.115538 -5.19157)
			(xy 24.086072 -5.145719) (xy 24.063431 -5.096143) (xy 24.048076 -5.043848) (xy 24.04032 -4.989901)
			(xy 22.066047 -4.989901) (xy 22.066047 -4.989903) (xy 22.05829 -5.043855) (xy 22.042933 -5.096153)
			(xy 22.02029 -5.145734) (xy 21.990822 -5.191587) (xy 21.955128 -5.23278) (xy 21.913934 -5.268474)
			(xy 21.86808 -5.297942) (xy 21.818499 -5.320585) (xy 21.766201 -5.33594) (xy 21.712249 -5.343697)
			(xy 21.684996 -5.34416) (xy 20.821396 -5.34416) (xy 20.794145 -5.34367) (xy 20.740198 -5.335913)
			(xy 20.687904 -5.320558) (xy 20.638328 -5.297916) (xy 20.592478 -5.26845) (xy 20.551288 -5.232759)
			(xy 20.515597 -5.191569) (xy 20.486132 -5.145719) (xy 20.463491 -5.096142) (xy 20.448136 -5.043848)
			(xy 20.44038 -4.989901) (xy 16.267136 -4.989901) (xy 16.278962 -5.06831) (xy 16.284155 -5.154889)
			(xy 16.281564 -5.241584) (xy 16.27121 -5.327698) (xy 16.253177 -5.412537) (xy 16.22761 -5.495418)
			(xy 16.194714 -5.575672) (xy 16.154755 -5.652653) (xy 16.108054 -5.725741) (xy 16.054988 -5.794348)
			(xy 15.995985 -5.85792) (xy 15.931519 -5.915946) (xy 15.897098 -5.94233) (xy 15.862132 -5.968006)
			(xy 15.788377 -6.013689) (xy 15.710822 -6.052572) (xy 15.630093 -6.084344) (xy 15.546839 -6.108746)
			(xy 15.461732 -6.125584) (xy 15.375458 -6.13472) (xy 15.288712 -6.136082) (xy 15.202194 -6.129659)
			(xy 15.116601 -6.115502) (xy 15.032622 -6.093724) (xy 14.950935 -6.064503) (xy 14.872197 -6.028073)
			(xy 14.797045 -5.984729) (xy 14.726083 -5.934818) (xy 14.659883 -5.878744) (xy 14.598979 -5.816959)
			(xy 14.543862 -5.749961) (xy 14.494977 -5.678289) (xy 14.452716 -5.602521) (xy 14.417421 -5.523269)
			(xy 14.389376 -5.44117) (xy 14.368808 -5.356887) (xy 14.355882 -5.271099) (xy 14.350702 -5.184498)
			(xy 13.611098 -5.184498) (xy 13.611098 -6.169914) (xy 78.515217 -6.169914) (xy 78.519222 -6.082006)
			(xy 78.531205 -5.994826) (xy 78.551065 -5.909097) (xy 78.57864 -5.825529) (xy 78.613699 -5.744815)
			(xy 78.655952 -5.667623) (xy 78.70505 -5.594594) (xy 78.760586 -5.526332) (xy 78.822098 -5.463402)
			(xy 78.889079 -5.406328) (xy 78.960972 -5.35558) (xy 79.037181 -5.31158) (xy 79.117076 -5.274693)
			(xy 79.199995 -5.245224) (xy 79.28525 -5.223417) (xy 79.372134 -5.209453) (xy 79.459928 -5.203447)
			(xy 79.547905 -5.205451) (xy 79.635335 -5.215446) (xy 79.721494 -5.23335) (xy 79.805668 -5.259014)
			(xy 79.887159 -5.292227) (xy 79.965293 -5.332713) (xy 80.039421 -5.380135) (xy 80.108929 -5.434102)
			(xy 80.173243 -5.494167) (xy 80.231827 -5.559831) (xy 80.284198 -5.63055) (xy 80.329921 -5.705738)
			(xy 80.368618 -5.784773) (xy 80.399967 -5.866999) (xy 80.423709 -5.951735) (xy 80.439647 -6.038279)
			(xy 80.447649 -6.125914) (xy 80.44815 -6.169914) (xy 80.447649 -6.213914) (xy 80.439647 -6.301549)
			(xy 80.423709 -6.388093) (xy 80.399967 -6.472829) (xy 80.368618 -6.555055) (xy 80.329921 -6.63409)
			(xy 80.284198 -6.709278) (xy 80.231827 -6.779997) (xy 80.173243 -6.845661) (xy 80.108929 -6.905726)
			(xy 80.039421 -6.959693) (xy 79.965293 -7.007115) (xy 79.887159 -7.047601) (xy 79.805668 -7.080814)
			(xy 79.721494 -7.106478) (xy 79.635335 -7.124382) (xy 79.547905 -7.134377) (xy 79.459928 -7.136381)
			(xy 79.372134 -7.130375) (xy 79.28525 -7.116411) (xy 79.199995 -7.094604) (xy 79.117076 -7.065135)
			(xy 79.037181 -7.028248) (xy 78.960972 -6.984248) (xy 78.889079 -6.9335) (xy 78.822098 -6.876426)
			(xy 78.760586 -6.813496) (xy 78.70505 -6.745234) (xy 78.655952 -6.672205) (xy 78.613699 -6.595013)
			(xy 78.57864 -6.514299) (xy 78.551065 -6.430731) (xy 78.531205 -6.345002) (xy 78.519222 -6.257822)
			(xy 78.515217 -6.169914) (xy 13.611098 -6.169914) (xy 13.611098 -6.751654) (xy 18.635651 -6.751654)
			(xy 18.635651 -6.697146) (xy 18.643409 -6.643192) (xy 18.658767 -6.590891) (xy 18.681411 -6.541309)
			(xy 18.710882 -6.495454) (xy 18.746579 -6.45426) (xy 18.787775 -6.418566) (xy 18.833632 -6.389099)
			(xy 18.883216 -6.366458) (xy 18.935517 -6.351104) (xy 18.989472 -6.34335) (xy 19.016726 -6.342888)
			(xy 19.880326 -6.342888) (xy 19.907576 -6.343384) (xy 19.96152 -6.351143) (xy 20.013811 -6.3665)
			(xy 20.063385 -6.389143) (xy 20.109231 -6.418609) (xy 20.150418 -6.4543) (xy 20.186106 -6.49549)
			(xy 20.21557 -6.541338) (xy 20.238209 -6.590913) (xy 20.253563 -6.643205) (xy 20.261318 -6.69715)
			(xy 20.261318 -6.75165) (xy 22.235674 -6.75165) (xy 22.235674 -6.69715) (xy 22.243429 -6.643204)
			(xy 22.258783 -6.590912) (xy 22.281422 -6.541336) (xy 22.310886 -6.495487) (xy 22.346574 -6.454297)
			(xy 22.387761 -6.418605) (xy 22.433608 -6.389138) (xy 22.483182 -6.366494) (xy 22.535473 -6.351136)
			(xy 22.589418 -6.343376) (xy 22.616668 -6.342888) (xy 23.480268 -6.342888) (xy 23.507522 -6.343357)
			(xy 23.561476 -6.35111) (xy 23.613777 -6.366463) (xy 23.663361 -6.389104) (xy 23.709217 -6.418571)
			(xy 23.750413 -6.454264) (xy 23.78611 -6.495457) (xy 23.815581 -6.541311) (xy 23.838225 -6.590893)
			(xy 23.853583 -6.643193) (xy 23.861341 -6.697146) (xy 23.861341 -6.751654) (xy 25.835551 -6.751654)
			(xy 25.835551 -6.697146) (xy 25.843309 -6.643194) (xy 25.858665 -6.590895) (xy 25.881309 -6.541314)
			(xy 25.910778 -6.495459) (xy 25.946473 -6.454266) (xy 25.987667 -6.418572) (xy 26.033522 -6.389104)
			(xy 26.083104 -6.366462) (xy 26.135404 -6.351107) (xy 26.189356 -6.343351) (xy 26.21661 -6.342888)
			(xy 27.08021 -6.342888) (xy 27.10746 -6.343382) (xy 27.161407 -6.35114) (xy 27.2137 -6.366496) (xy 27.263275 -6.389137)
			(xy 27.309124 -6.418604) (xy 27.350312 -6.454295) (xy 27.386002 -6.495484) (xy 27.415467 -6.541334)
			(xy 27.438108 -6.59091) (xy 27.453462 -6.643203) (xy 27.461218 -6.697149) (xy 27.461218 -6.751651)
			(xy 27.461218 -6.751653) (xy 29.435751 -6.751653) (xy 29.435751 -6.697147) (xy 29.443509 -6.643195)
			(xy 29.458865 -6.590896) (xy 29.481508 -6.541315) (xy 29.510977 -6.495461) (xy 29.546672 -6.454268)
			(xy 29.587866 -6.418574) (xy 29.63372 -6.389105) (xy 29.683301 -6.366463) (xy 29.7356 -6.351107)
			(xy 29.789553 -6.343351) (xy 29.816806 -6.342888) (xy 30.680406 -6.342888) (xy 30.707657 -6.343382)
			(xy 30.761603 -6.351139) (xy 30.813897 -6.366495) (xy 30.863473 -6.389136) (xy 30.909322 -6.418602)
			(xy 30.950511 -6.454293) (xy 30.986201 -6.495483) (xy 31.015667 -6.541333) (xy 31.038307 -6.590909)
			(xy 31.053662 -6.643203) (xy 31.061418 -6.697149) (xy 31.061418 -6.75165) (xy 38.545774 -6.75165)
			(xy 38.545774 -6.69715) (xy 38.55353 -6.643204) (xy 38.568883 -6.590911) (xy 38.591522 -6.541336)
			(xy 38.620986 -6.495486) (xy 38.656675 -6.454296) (xy 38.697862 -6.418604) (xy 38.743709 -6.389137)
			(xy 38.793283 -6.366494) (xy 38.845575 -6.351136) (xy 38.89952 -6.343376) (xy 38.92677 -6.342888)
			(xy 39.79037 -6.342888) (xy 39.817624 -6.343357) (xy 39.871578 -6.351111) (xy 39.923878 -6.366464)
			(xy 39.973462 -6.389105) (xy 40.019318 -6.418571) (xy 40.060514 -6.454265) (xy 40.096211 -6.495458)
			(xy 40.125681 -6.541312) (xy 40.148326 -6.590893) (xy 40.163683 -6.643193) (xy 40.171441 -6.697146)
			(xy 40.171441 -6.751654) (xy 42.145651 -6.751654) (xy 42.145651 -6.697146) (xy 42.153409 -6.643194)
			(xy 42.168766 -6.590894) (xy 42.191409 -6.541313) (xy 42.220879 -6.495459) (xy 42.256574 -6.454265)
			(xy 42.297768 -6.418571) (xy 42.343624 -6.389103) (xy 42.393206 -6.366461) (xy 42.445506 -6.351106)
			(xy 42.499458 -6.343351) (xy 42.526712 -6.342888) (xy 43.390312 -6.342888) (xy 43.417562 -6.343383)
			(xy 43.471508 -6.35114) (xy 43.523801 -6.366496) (xy 43.573376 -6.389138) (xy 43.619225 -6.418604)
			(xy 43.660413 -6.454295) (xy 43.696103 -6.495485) (xy 43.725568 -6.541334) (xy 43.748208 -6.59091)
			(xy 43.763562 -6.643203) (xy 43.771318 -6.69715) (xy 43.771318 -6.75165) (xy 43.771318 -6.751653)
			(xy 49.755751 -6.751653) (xy 49.755751 -6.697147) (xy 49.763509 -6.643195) (xy 49.778865 -6.590896)
			(xy 49.801508 -6.541315) (xy 49.830977 -6.495461) (xy 49.866672 -6.454268) (xy 49.907866 -6.418574)
			(xy 49.95372 -6.389105) (xy 50.003301 -6.366463) (xy 50.0556 -6.351107) (xy 50.109553 -6.343351)
			(xy 50.136806 -6.342888) (xy 51.000406 -6.342888) (xy 51.027657 -6.343382) (xy 51.081603 -6.351139)
			(xy 51.133897 -6.366495) (xy 51.183473 -6.389136) (xy 51.229322 -6.418602) (xy 51.270511 -6.454293)
			(xy 51.306201 -6.495483) (xy 51.335667 -6.541333) (xy 51.358307 -6.590909) (xy 51.373662 -6.643203)
			(xy 51.381418 -6.697149) (xy 51.381418 -6.751651) (xy 51.381417 -6.751655) (xy 53.355652 -6.751655)
			(xy 53.355652 -6.697145) (xy 53.36341 -6.643189) (xy 53.378768 -6.590887) (xy 53.401415 -6.541303)
			(xy 53.430887 -6.495447) (xy 53.466587 -6.454253) (xy 53.507785 -6.418559) (xy 53.553645 -6.389092)
			(xy 53.603232 -6.366452) (xy 53.655536 -6.3511) (xy 53.709493 -6.343348) (xy 53.736748 -6.342888)
			(xy 54.600348 -6.342888) (xy 54.627597 -6.343385) (xy 54.681539 -6.351147) (xy 54.733827 -6.366506)
			(xy 54.783398 -6.38915) (xy 54.829242 -6.418617) (xy 54.870426 -6.454308) (xy 54.906112 -6.495497)
			(xy 54.935573 -6.541344) (xy 54.958211 -6.590918) (xy 54.973563 -6.643208) (xy 54.981318 -6.697151)
			(xy 54.981318 -6.751649) (xy 54.981318 -6.751651) (xy 56.955674 -6.751651) (xy 56.955674 -6.697149)
			(xy 56.96343 -6.643201) (xy 56.978785 -6.590907) (xy 57.001426 -6.54133) (xy 57.030891 -6.49548)
			(xy 57.066582 -6.454289) (xy 57.107771 -6.418597) (xy 57.153621 -6.38913) (xy 57.203198 -6.366488)
			(xy 57.255492 -6.351132) (xy 57.309439 -6.343374) (xy 57.33669 -6.342888) (xy 58.20029 -6.342888)
			(xy 58.227543 -6.343359) (xy 58.281494 -6.351114) (xy 58.333793 -6.366469) (xy 58.383374 -6.389111)
			(xy 58.429228 -6.418578) (xy 58.470421 -6.454272) (xy 58.506116 -6.495464) (xy 58.535584 -6.541317)
			(xy 58.558227 -6.590898) (xy 58.573583 -6.643196) (xy 58.581341 -6.697147) (xy 58.581341 -6.751651)
			(xy 70.950574 -6.751651) (xy 70.950574 -6.697149) (xy 70.95833 -6.643203) (xy 70.973684 -6.590909)
			(xy 70.996324 -6.541332) (xy 71.025789 -6.495482) (xy 71.061479 -6.454292) (xy 71.102668 -6.4186)
			(xy 71.148516 -6.389133) (xy 71.198092 -6.366491) (xy 71.250385 -6.351134) (xy 71.304331 -6.343375)
			(xy 71.331582 -6.342888) (xy 72.195182 -6.342888) (xy 72.222435 -6.343358) (xy 72.276388 -6.351113)
			(xy 72.328687 -6.366467) (xy 72.378269 -6.389108) (xy 72.424124 -6.418576) (xy 72.465318 -6.454269)
			(xy 72.501014 -6.495462) (xy 72.530483 -6.541315) (xy 72.553126 -6.590896) (xy 72.568483 -6.643195)
			(xy 72.576241 -6.697147) (xy 72.576241 -6.751653) (xy 72.568483 -6.805605) (xy 72.553126 -6.857904)
			(xy 72.530483 -6.907485) (xy 72.501014 -6.953338) (xy 72.465318 -6.994531) (xy 72.424124 -7.030224)
			(xy 72.378269 -7.059692) (xy 72.328687 -7.082333) (xy 72.276388 -7.097687) (xy 72.222435 -7.105442)
			(xy 72.195182 -7.105904) (xy 71.331582 -7.105904) (xy 71.304331 -7.105425) (xy 71.250385 -7.097666)
			(xy 71.198092 -7.082309) (xy 71.148516 -7.059667) (xy 71.102668 -7.0302) (xy 71.061479 -6.994508)
			(xy 71.025789 -6.953318) (xy 70.996324 -6.907468) (xy 70.973684 -6.857891) (xy 70.95833 -6.805597)
			(xy 70.950574 -6.751651) (xy 58.581341 -6.751651) (xy 58.581341 -6.751653) (xy 58.573583 -6.805604)
			(xy 58.558227 -6.857902) (xy 58.535584 -6.907483) (xy 58.506116 -6.953336) (xy 58.470421 -6.994528)
			(xy 58.429228 -7.030222) (xy 58.383374 -7.059689) (xy 58.333793 -7.082331) (xy 58.281494 -7.097686)
			(xy 58.227543 -7.105441) (xy 58.20029 -7.105904) (xy 57.33669 -7.105904) (xy 57.309439 -7.105426)
			(xy 57.255492 -7.097668) (xy 57.203198 -7.082312) (xy 57.153621 -7.05967) (xy 57.107771 -7.030203)
			(xy 57.066582 -6.994511) (xy 57.030891 -6.95332) (xy 57.001426 -6.90747) (xy 56.978785 -6.857893)
			(xy 56.96343 -6.805599) (xy 56.955674 -6.751651) (xy 54.981318 -6.751651) (xy 54.973563 -6.805592)
			(xy 54.958211 -6.857882) (xy 54.935573 -6.907456) (xy 54.906112 -6.953303) (xy 54.870426 -6.994492)
			(xy 54.829242 -7.030183) (xy 54.783398 -7.05965) (xy 54.733827 -7.082294) (xy 54.681539 -7.097653)
			(xy 54.627597 -7.105415) (xy 54.600348 -7.105904) (xy 53.736748 -7.105904) (xy 53.709493 -7.105452)
			(xy 53.655536 -7.0977) (xy 53.603232 -7.082348) (xy 53.553645 -7.059708) (xy 53.507785 -7.030241)
			(xy 53.466587 -6.994547) (xy 53.430887 -6.953353) (xy 53.401415 -6.907497) (xy 53.378768 -6.857913)
			(xy 53.36341 -6.805611) (xy 53.355652 -6.751655) (xy 51.381417 -6.751655) (xy 51.373662 -6.805597)
			(xy 51.358307 -6.857891) (xy 51.335667 -6.907467) (xy 51.306201 -6.953317) (xy 51.270511 -6.994507)
			(xy 51.229322 -7.030198) (xy 51.183473 -7.059664) (xy 51.133897 -7.082305) (xy 51.081603 -7.097661)
			(xy 51.027657 -7.105418) (xy 51.000406 -7.105904) (xy 50.136806 -7.105904) (xy 50.109553 -7.105449)
			(xy 50.0556 -7.097693) (xy 50.003301 -7.082337) (xy 49.95372 -7.059695) (xy 49.907866 -7.030226)
			(xy 49.866672 -6.994532) (xy 49.830977 -6.953339) (xy 49.801508 -6.907485) (xy 49.778865 -6.857904)
			(xy 49.763509 -6.805605) (xy 49.755751 -6.751653) (xy 43.771318 -6.751653) (xy 43.763562 -6.805597)
			(xy 43.748208 -6.85789) (xy 43.725568 -6.907466) (xy 43.696103 -6.953315) (xy 43.660413 -6.994505)
			(xy 43.619225 -7.030196) (xy 43.573376 -7.059662) (xy 43.523801 -7.082304) (xy 43.471508 -7.09766)
			(xy 43.417562 -7.105417) (xy 43.390312 -7.105904) (xy 42.526712 -7.105904) (xy 42.499458 -7.105449)
			(xy 42.445506 -7.097694) (xy 42.393206 -7.082339) (xy 42.343624 -7.059697) (xy 42.297768 -7.030229)
			(xy 42.256574 -6.994535) (xy 42.220879 -6.953341) (xy 42.191409 -6.907487) (xy 42.168766 -6.857906)
			(xy 42.153409 -6.805606) (xy 42.145651 -6.751654) (xy 40.171441 -6.751654) (xy 40.163683 -6.805607)
			(xy 40.148326 -6.857907) (xy 40.125681 -6.907488) (xy 40.096211 -6.953342) (xy 40.060514 -6.994535)
			(xy 40.019318 -7.030229) (xy 39.973462 -7.059695) (xy 39.923878 -7.082336) (xy 39.871578 -7.097689)
			(xy 39.817624 -7.105443) (xy 39.79037 -7.105904) (xy 38.92677 -7.105904) (xy 38.89952 -7.105424)
			(xy 38.845575 -7.097664) (xy 38.793283 -7.082306) (xy 38.743709 -7.059663) (xy 38.697862 -7.030196)
			(xy 38.656675 -6.994504) (xy 38.620986 -6.953314) (xy 38.591522 -6.907464) (xy 38.568883 -6.857889)
			(xy 38.55353 -6.805596) (xy 38.545774 -6.75165) (xy 31.061418 -6.75165) (xy 31.061418 -6.751651)
			(xy 31.053662 -6.805597) (xy 31.038307 -6.857891) (xy 31.015667 -6.907467) (xy 30.986201 -6.953317)
			(xy 30.950511 -6.994507) (xy 30.909322 -7.030198) (xy 30.863473 -7.059664) (xy 30.813897 -7.082305)
			(xy 30.761603 -7.097661) (xy 30.707657 -7.105418) (xy 30.680406 -7.105904) (xy 29.816806 -7.105904)
			(xy 29.789553 -7.105449) (xy 29.7356 -7.097693) (xy 29.683301 -7.082337) (xy 29.63372 -7.059695)
			(xy 29.587866 -7.030226) (xy 29.546672 -6.994532) (xy 29.510977 -6.953339) (xy 29.481508 -6.907485)
			(xy 29.458865 -6.857904) (xy 29.443509 -6.805605) (xy 29.435751 -6.751653) (xy 27.461218 -6.751653)
			(xy 27.453462 -6.805597) (xy 27.438108 -6.85789) (xy 27.415467 -6.907466) (xy 27.386002 -6.953316)
			(xy 27.350312 -6.994505) (xy 27.309124 -7.030196) (xy 27.263275 -7.059663) (xy 27.2137 -7.082304)
			(xy 27.161407 -7.09766) (xy 27.10746 -7.105418) (xy 27.08021 -7.105904) (xy 26.21661 -7.105904) (xy 26.189356 -7.105449)
			(xy 26.135404 -7.097693) (xy 26.083104 -7.082338) (xy 26.033522 -7.059696) (xy 25.987667 -7.030228)
			(xy 25.946473 -6.994534) (xy 25.910778 -6.953341) (xy 25.881309 -6.907486) (xy 25.858665 -6.857905)
			(xy 25.843309 -6.805606) (xy 25.835551 -6.751654) (xy 23.861341 -6.751654) (xy 23.853583 -6.805607)
			(xy 23.838225 -6.857907) (xy 23.815581 -6.907489) (xy 23.78611 -6.953343) (xy 23.750413 -6.994536)
			(xy 23.709217 -7.030229) (xy 23.663361 -7.059696) (xy 23.613777 -7.082337) (xy 23.561476 -7.09769)
			(xy 23.507522 -7.105443) (xy 23.480268 -7.105904) (xy 22.616668 -7.105904) (xy 22.589418 -7.105424)
			(xy 22.535473 -7.097664) (xy 22.483182 -7.082306) (xy 22.433608 -7.059662) (xy 22.387761 -7.030195)
			(xy 22.346574 -6.994503) (xy 22.310886 -6.953313) (xy 22.281422 -6.907464) (xy 22.258783 -6.857888)
			(xy 22.243429 -6.805596) (xy 22.235674 -6.75165) (xy 20.261318 -6.75165) (xy 20.253563 -6.805595)
			(xy 20.238209 -6.857887) (xy 20.21557 -6.907462) (xy 20.186106 -6.95331) (xy 20.150418 -6.9945) (xy 20.109231 -7.030191)
			(xy 20.063385 -7.059657) (xy 20.013811 -7.0823) (xy 19.96152 -7.097657) (xy 19.907576 -7.105416)
			(xy 19.880326 -7.105904) (xy 19.016726 -7.105904) (xy 18.989472 -7.10545) (xy 18.935517 -7.097696)
			(xy 18.883216 -7.082342) (xy 18.833632 -7.059701) (xy 18.787775 -7.030234) (xy 18.746579 -6.99454)
			(xy 18.710882 -6.953346) (xy 18.681411 -6.907491) (xy 18.658767 -6.857909) (xy 18.643409 -6.805608)
			(xy 18.635651 -6.751654) (xy 13.611098 -6.751654) (xy 13.611098 -7.597648) (xy 17.167352 -7.597648)
			(xy 18.136108 -7.597648) (xy 18.136108 -9.057132) (xy 17.167352 -9.057132) (xy 17.167352 -7.597648)
			(xy 13.611098 -7.597648) (xy 13.611098 -9.094724) (xy 18.7325 -9.094724) (xy 18.7325 -7.672324) (xy 18.732937 -7.660216)
			(xy 18.74043 -7.63719) (xy 18.754686 -7.617616) (xy 18.774304 -7.603421) (xy 18.797353 -7.596) (xy 18.809462 -7.595616)
			(xy 20.090892 -7.595616) (xy 20.102977 -7.59602) (xy 20.125963 -7.603488) (xy 20.145516 -7.617695)
			(xy 20.159719 -7.637251) (xy 20.167183 -7.660239) (xy 20.1676 -7.672324) (xy 20.1676 -9.094724) (xy 20.532852 -9.094724)
			(xy 20.532852 -7.672324) (xy 20.533384 -7.660255) (xy 20.540835 -7.637295) (xy 20.555015 -7.617761)
			(xy 20.574538 -7.603564) (xy 20.597491 -7.596094) (xy 20.60956 -7.595616) (xy 21.89099 -7.595616)
			(xy 21.903077 -7.596116) (xy 21.926073 -7.603567) (xy 21.945651 -7.617746) (xy 21.959903 -7.637271)
			(xy 21.967439 -7.660239) (xy 21.967952 -7.672324) (xy 21.967952 -9.094724) (xy 22.332696 -9.094724)
			(xy 22.332696 -7.672324) (xy 22.333133 -7.660242) (xy 22.340595 -7.63726) (xy 22.354794 -7.617709)
			(xy 22.374342 -7.603504) (xy 22.397322 -7.596036) (xy 22.409404 -7.595616) (xy 23.690834 -7.595616)
			(xy 23.702923 -7.596078) (xy 23.725921 -7.603541) (xy 23.745498 -7.61773) (xy 23.759748 -7.637262)
			(xy 23.767284 -7.660237) (xy 23.767796 -7.672324) (xy 23.767796 -9.094724) (xy 24.13254 -9.094724)
			(xy 24.13254 -7.672324) (xy 24.132937 -7.660212) (xy 24.140435 -7.637179) (xy 24.1547 -7.617602)
			(xy 24.174329 -7.603408) (xy 24.197389 -7.595994) (xy 24.209502 -7.595616) (xy 25.490932 -7.595616)
			(xy 25.503011 -7.596037) (xy 25.525983 -7.603511) (xy 25.545522 -7.617718) (xy 25.559714 -7.637267)
			(xy 25.567172 -7.660245) (xy 25.56764 -7.672324) (xy 25.56764 -9.094724) (xy 25.932384 -9.094724)
			(xy 25.932384 -7.672324) (xy 25.932837 -7.660218) (xy 25.940328 -7.637194) (xy 25.95458 -7.617622)
			(xy 25.974194 -7.603426) (xy 25.997239 -7.596002) (xy 26.009346 -7.595616) (xy 27.290776 -7.595616)
			(xy 27.30286 -7.596034) (xy 27.325846 -7.603497) (xy 27.345399 -7.617701) (xy 27.359603 -7.637254)
			(xy 27.367066 -7.66024) (xy 27.367484 -7.672324) (xy 27.367484 -9.094724) (xy 27.732736 -9.094724)
			(xy 27.732736 -7.672324) (xy 27.733134 -7.660238) (xy 27.7406 -7.637249) (xy 27.754809 -7.617694)
			(xy 27.774367 -7.603491) (xy 27.797358 -7.596031) (xy 27.809444 -7.595616) (xy 29.090874 -7.595616)
			(xy 29.10296 -7.596129) (xy 29.125956 -7.603576) (xy 29.145534 -7.617751) (xy 29.159786 -7.637274)
			(xy 29.167323 -7.66024) (xy 29.167836 -7.672324) (xy 29.167836 -9.094724) (xy 29.53258 -9.094724)
			(xy 29.53258 -7.672324) (xy 29.533033 -7.660244) (xy 29.540493 -7.637264) (xy 29.554689 -7.617714)
			(xy 29.574232 -7.603509) (xy 29.597208 -7.596039) (xy 29.609288 -7.595616) (xy 30.890718 -7.595616)
			(xy 30.902806 -7.596091) (xy 30.925803 -7.60355) (xy 30.945381 -7.617735) (xy 30.959632 -7.637265)
			(xy 30.967168 -7.660237) (xy 30.96768 -7.672324) (xy 30.96768 -9.094724) (xy 31.332424 -9.094724)
			(xy 31.332424 -7.672324) (xy 31.332837 -7.660214) (xy 31.340333 -7.637183) (xy 31.354594 -7.617608)
			(xy 31.374219 -7.603413) (xy 31.397275 -7.595996) (xy 31.409386 -7.595616) (xy 32.690816 -7.595616)
			(xy 32.702902 -7.595999) (xy 32.725889 -7.603474) (xy 32.745441 -7.617687) (xy 32.759644 -7.637247)
			(xy 32.767107 -7.660238) (xy 32.767524 -7.672324) (xy 32.767524 -9.094724) (xy 38.642544 -9.094724)
			(xy 38.642544 -7.672324) (xy 38.643036 -7.660222) (xy 38.650522 -7.637205) (xy 38.664766 -7.617637)
			(xy 38.684368 -7.603439) (xy 38.707403 -7.596008) (xy 38.719506 -7.595616) (xy 40.000936 -7.595616)
			(xy 40.013015 -7.596034) (xy 40.035987 -7.603509) (xy 40.055526 -7.617717) (xy 40.069718 -7.637266)
			(xy 40.077176 -7.660245) (xy 40.077644 -7.672324) (xy 40.077644 -9.094724) (xy 40.442896 -9.094724)
			(xy 40.442896 -7.672324) (xy 40.443333 -7.660242) (xy 40.450795 -7.63726) (xy 40.464994 -7.617709)
			(xy 40.484542 -7.603504) (xy 40.507522 -7.596036) (xy 40.519604 -7.595616) (xy 41.801034 -7.595616)
			(xy 41.813123 -7.596078) (xy 41.836121 -7.603541) (xy 41.855698 -7.61773) (xy 41.869948 -7.637262)
			(xy 41.877484 -7.660237) (xy 41.877996 -7.672324) (xy 41.877996 -9.094724) (xy 42.24274 -9.094724)
			(xy 42.24274 -7.672324) (xy 42.243134 -7.660238) (xy 42.250601 -7.637248) (xy 42.26481 -7.617693)
			(xy 42.284369 -7.60349) (xy 42.307362 -7.59603) (xy 42.319448 -7.595616) (xy 43.600878 -7.595616)
			(xy 43.612964 -7.596126) (xy 43.63596 -7.603573) (xy 43.655538 -7.61775) (xy 43.66979 -7.637273)
			(xy 43.677327 -7.66024) (xy 43.67784 -7.672324) (xy 43.67784 -9.094724) (xy 44.042584 -9.094724)
			(xy 44.042584 -7.672324) (xy 44.043037 -7.660218) (xy 44.050528 -7.637194) (xy 44.06478 -7.617622)
			(xy 44.084394 -7.603426) (xy 44.107439 -7.596002) (xy 44.119546 -7.595616) (xy 45.400976 -7.595616)
			(xy 45.41306 -7.596034) (xy 45.436046 -7.603497) (xy 45.455599 -7.617701) (xy 45.469803 -7.637254)
			(xy 45.477266 -7.66024) (xy 45.477684 -7.672324) (xy 45.477684 -9.094724) (xy 49.85258 -9.094724)
			(xy 49.85258 -7.672324) (xy 49.853037 -7.660218) (xy 49.860527 -7.637195) (xy 49.874779 -7.617624)
			(xy 49.894391 -7.603427) (xy 49.917435 -7.596003) (xy 49.929542 -7.595616) (xy 51.210972 -7.595616)
			(xy 51.223056 -7.596037) (xy 51.246041 -7.6035) (xy 51.265594 -7.617703) (xy 51.279798 -7.637255)
			(xy 51.287262 -7.66024) (xy 51.28768 -7.672324) (xy 51.28768 -9.094724) (xy 51.652932 -9.094724)
			(xy 51.652932 -7.672324) (xy 51.653334 -7.660239) (xy 51.6608 -7.63725) (xy 51.675007 -7.617696)
			(xy 51.694564 -7.603492) (xy 51.717554 -7.596031) (xy 51.72964 -7.595616) (xy 53.01107 -7.595616)
			(xy 53.023156 -7.596133) (xy 53.046151 -7.603578) (xy 53.06573 -7.617753) (xy 53.079982 -7.637275)
			(xy 53.087519 -7.66024) (xy 53.088032 -7.672324) (xy 53.088032 -9.094724) (xy 53.452776 -9.094724)
			(xy 53.452776 -7.672324) (xy 53.453233 -7.660244) (xy 53.460692 -7.637265) (xy 53.474887 -7.617716)
			(xy 53.494429 -7.60351) (xy 53.517404 -7.596039) (xy 53.529484 -7.595616) (xy 54.810914 -7.595616)
			(xy 54.823002 -7.596095) (xy 54.845999 -7.603552) (xy 54.865577 -7.617737) (xy 54.879828 -7.637266)
			(xy 54.887364 -7.660238) (xy 54.887876 -7.672324) (xy 54.887876 -9.094724) (xy 55.25262 -9.094724)
			(xy 55.25262 -7.672324) (xy 55.253037 -7.660214) (xy 55.260532 -7.637185) (xy 55.274793 -7.617609)
			(xy 55.294416 -7.603415) (xy 55.317471 -7.595997) (xy 55.329582 -7.595616) (xy 56.611012 -7.595616)
			(xy 56.623098 -7.596003) (xy 56.646085 -7.603476) (xy 56.665637 -7.617688) (xy 56.67984 -7.637247)
			(xy 56.687303 -7.660238) (xy 56.68772 -7.672324) (xy 56.68772 -9.094724) (xy 56.687256 -9.106799)
			(xy 56.679789 -9.129764) (xy 56.665591 -9.1493) (xy 56.646054 -9.163494) (xy 56.623087 -9.170958)
			(xy 56.611012 -9.171432) (xy 55.329582 -9.171432) (xy 55.317489 -9.171008) (xy 55.294483 -9.163543)
			(xy 55.274901 -9.149346) (xy 55.260652 -9.129802) (xy 55.253125 -9.106816) (xy 55.25262 -9.094724)
			(xy 54.887876 -9.094724) (xy 54.887504 -9.106837) (xy 54.879995 -9.129869) (xy 54.865723 -9.149443)
			(xy 54.84609 -9.163636) (xy 54.823028 -9.171052) (xy 54.810914 -9.171432) (xy 53.529484 -9.171432)
			(xy 53.517411 -9.17095) (xy 53.494447 -9.163486) (xy 53.474913 -9.149293) (xy 53.460718 -9.12976)
			(xy 53.453252 -9.106797) (xy 53.452776 -9.094724) (xy 53.088032 -9.094724) (xy 53.087605 -9.106831)
			(xy 53.080102 -9.129854) (xy 53.065843 -9.149423) (xy 53.046226 -9.163618) (xy 53.023178 -9.171044)
			(xy 53.01107 -9.171432) (xy 51.72964 -9.171432) (xy 51.717562 -9.170954) (xy 51.694584 -9.1635) (xy 51.675036 -9.14931)
			(xy 51.660829 -9.129773) (xy 51.653356 -9.106802) (xy 51.652932 -9.094724) (xy 51.28768 -9.094724)
			(xy 51.287307 -9.106811) (xy 51.27983 -9.129799) (xy 51.265614 -9.149351) (xy 51.246052 -9.163554)
			(xy 51.223059 -9.171016) (xy 51.210972 -9.171432) (xy 49.929542 -9.171432) (xy 49.917452 -9.170956)
			(xy 49.894448 -9.163508) (xy 49.874865 -9.149324) (xy 49.860614 -9.129791) (xy 49.853086 -9.106812)
			(xy 49.85258 -9.094724) (xy 45.477684 -9.094724) (xy 45.477256 -9.106802) (xy 45.469784 -9.129774)
			(xy 45.455579 -9.149313) (xy 45.436031 -9.163506) (xy 45.413054 -9.170963) (xy 45.400976 -9.171432)
			(xy 44.119546 -9.171432) (xy 44.107456 -9.170953) (xy 44.084452 -9.163506) (xy 44.064869 -9.149323)
			(xy 44.050618 -9.12979) (xy 44.04309 -9.106812) (xy 44.042584 -9.094724) (xy 43.67784 -9.094724)
			(xy 43.677405 -9.10683) (xy 43.669904 -9.129851) (xy 43.655645 -9.149421) (xy 43.636031 -9.163616)
			(xy 43.612985 -9.171043) (xy 43.600878 -9.171432) (xy 42.319448 -9.171432) (xy 42.30737 -9.170947)
			(xy 42.284393 -9.163495) (xy 42.264844 -9.149307) (xy 42.250637 -9.129772) (xy 42.243164 -9.106801)
			(xy 42.24274 -9.094724) (xy 41.877996 -9.094724) (xy 41.877604 -9.106835) (xy 41.870098 -9.129863)
			(xy 41.85583 -9.149436) (xy 41.836203 -9.16363) (xy 41.813146 -9.171049) (xy 41.801034 -9.171432)
			(xy 40.519604 -9.171432) (xy 40.507532 -9.170933) (xy 40.484569 -9.163474) (xy 40.465034 -9.149286)
			(xy 40.450839 -9.129756) (xy 40.443372 -9.106796) (xy 40.442896 -9.094724) (xy 40.077644 -9.094724)
			(xy 40.077157 -9.106796) (xy 40.069692 -9.129758) (xy 40.0555 -9.149291) (xy 40.035969 -9.163486)
			(xy 40.013008 -9.170955) (xy 40.000936 -9.171432) (xy 38.719506 -9.171432) (xy 38.707414 -9.170987)
			(xy 38.684409 -9.163528) (xy 38.664826 -9.149337) (xy 38.650577 -9.129797) (xy 38.64305 -9.106815)
			(xy 38.642544 -9.094724) (xy 32.767524 -9.094724) (xy 32.767056 -9.106798) (xy 32.759589 -9.129763)
			(xy 32.745393 -9.149299) (xy 32.725856 -9.163493) (xy 32.70289 -9.170958) (xy 32.690816 -9.171432)
			(xy 31.409386 -9.171432) (xy 31.397293 -9.171004) (xy 31.374287 -9.16354) (xy 31.354705 -9.149345)
			(xy 31.340456 -9.129801) (xy 31.332929 -9.106816) (xy 31.332424 -9.094724) (xy 30.96768 -9.094724)
			(xy 30.967304 -9.106836) (xy 30.959795 -9.129868) (xy 30.945524 -9.149442) (xy 30.925893 -9.163635)
			(xy 30.902832 -9.171052) (xy 30.890718 -9.171432) (xy 29.609288 -9.171432) (xy 29.597215 -9.170946)
			(xy 29.574252 -9.163483) (xy 29.554717 -9.149292) (xy 29.540522 -9.129759) (xy 29.533056 -9.106797)
			(xy 29.53258 -9.094724) (xy 29.167836 -9.094724) (xy 29.167405 -9.106831) (xy 29.159903 -9.129852)
			(xy 29.145644 -9.149422) (xy 29.126028 -9.163617) (xy 29.102982 -9.171044) (xy 29.090874 -9.171432)
			(xy 27.809444 -9.171432) (xy 27.797366 -9.17095) (xy 27.774389 -9.163498) (xy 27.75484 -9.149309)
			(xy 27.740633 -9.129772) (xy 27.73316 -9.106802) (xy 27.732736 -9.094724) (xy 27.367484 -9.094724)
			(xy 27.367056 -9.106802) (xy 27.359584 -9.129774) (xy 27.345379 -9.149313) (xy 27.325831 -9.163506)
			(xy 27.302854 -9.170963) (xy 27.290776 -9.171432) (xy 26.009346 -9.171432) (xy 25.997256 -9.170953)
			(xy 25.974252 -9.163506) (xy 25.954669 -9.149323) (xy 25.940418 -9.12979) (xy 25.93289 -9.106812)
			(xy 25.932384 -9.094724) (xy 25.56764 -9.094724) (xy 25.567157 -9.106797) (xy 25.559691 -9.129759)
			(xy 25.545499 -9.149293) (xy 25.525966 -9.163488) (xy 25.503005 -9.170955) (xy 25.490932 -9.171432)
			(xy 24.209502 -9.171432) (xy 24.19741 -9.17099) (xy 24.174405 -9.163531) (xy 24.154822 -9.149339)
			(xy 24.140573 -9.129798) (xy 24.133046 -9.106815) (xy 24.13254 -9.094724) (xy 23.767796 -9.094724)
			(xy 23.767404 -9.106835) (xy 23.759898 -9.129863) (xy 23.74563 -9.149436) (xy 23.726003 -9.16363)
			(xy 23.702946 -9.171049) (xy 23.690834 -9.171432) (xy 22.409404 -9.171432) (xy 22.397332 -9.170933)
			(xy 22.374369 -9.163474) (xy 22.354834 -9.149286) (xy 22.340639 -9.129756) (xy 22.333172 -9.106796)
			(xy 22.332696 -9.094724) (xy 21.967952 -9.094724) (xy 21.967505 -9.106829) (xy 21.960005 -9.129848)
			(xy 21.94575 -9.149416) (xy 21.926138 -9.163612) (xy 21.903096 -9.171041) (xy 21.89099 -9.171432)
			(xy 20.60956 -9.171432) (xy 20.597486 -9.17097) (xy 20.574521 -9.1635) (xy 20.554987 -9.149302) (xy 20.540793 -9.129764)
			(xy 20.533327 -9.106798) (xy 20.532852 -9.094724) (xy 20.1676 -9.094724) (xy 20.167156 -9.106801)
			(xy 20.159686 -9.12977) (xy 20.145484 -9.149307) (xy 20.125941 -9.1635) (xy 20.102969 -9.170961)
			(xy 20.090892 -9.171432) (xy 18.809462 -9.171432) (xy 18.797368 -9.171025) (xy 18.774361 -9.163554)
			(xy 18.754779 -9.149353) (xy 18.740531 -9.129806) (xy 18.733005 -9.106817) (xy 18.7325 -9.094724)
			(xy 13.611098 -9.094724) (xy 13.611098 -9.780016) (xy 13.610604 -9.850398) (xy 13.602711 -9.990941)
			(xy 13.58695 -10.13082) (xy 13.563371 -10.269596) (xy 13.532048 -10.406831) (xy 13.493079 -10.542094)
			(xy 13.446587 -10.674959) (xy 13.392719 -10.805008) (xy 13.331643 -10.931832) (xy 13.263553 -11.055033)
			(xy 13.188662 -11.174221) (xy 13.107205 -11.289023) (xy 13.01944 -11.399077) (xy 12.925642 -11.504037)
			(xy 12.826107 -11.603572) (xy 12.721147 -11.69737) (xy 12.611093 -11.785135) (xy 12.496291 -11.866592)
			(xy 12.414985 -11.91768) (xy 18.728436 -11.91768) (xy 18.728436 -10.49528) (xy 18.728796 -10.483192)
			(xy 18.736275 -10.460201) (xy 18.750493 -10.440647) (xy 18.770058 -10.426445) (xy 18.793055 -10.418986)
			(xy 18.805144 -10.418572) (xy 20.086574 -10.418572) (xy 20.098665 -10.41903) (xy 20.121671 -10.426484)
			(xy 20.141254 -10.440671) (xy 20.155504 -10.460209) (xy 20.163031 -10.48319) (xy 20.163536 -10.49528)
			(xy 20.163536 -11.91768) (xy 20.52828 -11.91768) (xy 20.52828 -10.49528) (xy 20.528699 -10.483172)
			(xy 20.536201 -10.460148) (xy 20.550463 -10.440577) (xy 20.570083 -10.426382) (xy 20.593133 -10.418958)
			(xy 20.605242 -10.418572) (xy 21.886672 -10.418572) (xy 21.898751 -10.419036) (xy 21.92173 -10.426494)
			(xy 21.941279 -10.440687) (xy 21.955484 -10.460227) (xy 21.962956 -10.483201) (xy 21.96338 -10.49528)
			(xy 21.96338 -11.91768) (xy 22.328124 -11.91768) (xy 22.328124 -10.49528) (xy 22.3285 -10.483168)
			(xy 22.336007 -10.460136) (xy 22.350279 -10.440561) (xy 22.36991 -10.426368) (xy 22.392972 -10.418952)
			(xy 22.405086 -10.418572) (xy 23.686516 -10.418572) (xy 23.698589 -10.41905) (xy 23.721554 -10.426515)
			(xy 23.741089 -10.440709) (xy 23.755283 -10.460243) (xy 23.762749 -10.483207) (xy 23.763224 -10.49528)
			(xy 23.763224 -11.91768) (xy 24.128476 -11.91768) (xy 24.128476 -10.49528) (xy 24.128947 -10.483206)
			(xy 24.136413 -10.460241) (xy 24.150609 -10.440706) (xy 24.170145 -10.426511) (xy 24.19311 -10.419046)
			(xy 24.205184 -10.418572) (xy 25.486614 -10.418572) (xy 25.498708 -10.418996) (xy 25.521714 -10.42646)
			(xy 25.541297 -10.440657) (xy 25.555546 -10.460201) (xy 25.563072 -10.483188) (xy 25.563576 -10.49528)
			(xy 25.563576 -11.91768) (xy 25.92832 -11.91768) (xy 25.92832 -10.49528) (xy 25.928696 -10.483193)
			(xy 25.936172 -10.460205) (xy 25.950387 -10.440653) (xy 25.969948 -10.42645) (xy 25.992941 -10.418988)
			(xy 26.005028 -10.418572) (xy 27.286458 -10.418572) (xy 27.298549 -10.419044) (xy 27.321553 -10.426493)
			(xy 27.341137 -10.440677) (xy 27.355387 -10.460212) (xy 27.362915 -10.483191) (xy 27.36342 -10.49528)
			(xy 27.36342 -11.91768) (xy 27.728164 -11.91768) (xy 27.728164 -10.49528) (xy 27.728599 -10.483174)
			(xy 27.736099 -10.460152) (xy 27.750357 -10.440582) (xy 27.769973 -10.426387) (xy 27.793018 -10.41896)
			(xy 27.805126 -10.418572) (xy 29.086556 -10.418572) (xy 29.098634 -10.41905) (xy 29.121612 -10.426503)
			(xy 29.141162 -10.440693) (xy 29.155368 -10.46023) (xy 29.16284 -10.483202) (xy 29.163264 -10.49528)
			(xy 29.163264 -11.91768) (xy 29.528008 -11.91768) (xy 29.528008 -10.49528) (xy 29.528399 -10.483169)
			(xy 29.535905 -10.46014) (xy 29.550173 -10.440567) (xy 29.5698 -10.426373) (xy 29.592858 -10.418954)
			(xy 29.60497 -10.418572) (xy 30.8864 -10.418572) (xy 30.898473 -10.419064) (xy 30.921436 -10.426524)
			(xy 30.940972 -10.440714) (xy 30.955167 -10.460246) (xy 30.962633 -10.483208) (xy 30.963108 -10.49528)
			(xy 30.963108 -11.91768) (xy 31.32836 -11.91768) (xy 31.32836 -10.49528) (xy 31.328847 -10.483208)
			(xy 31.336311 -10.460245) (xy 31.350503 -10.440711) (xy 31.370035 -10.426516) (xy 31.392996 -10.419049)
			(xy 31.405068 -10.418572) (xy 32.686498 -10.418572) (xy 32.698591 -10.41901) (xy 32.721596 -10.42647)
			(xy 32.741179 -10.440663) (xy 32.755429 -10.460205) (xy 32.762955 -10.483189) (xy 32.76346 -10.49528)
			(xy 32.76346 -11.91768) (xy 38.63848 -11.91768) (xy 38.63848 -10.49528) (xy 38.638947 -10.483206)
			(xy 38.646414 -10.46024) (xy 38.66061 -10.440704) (xy 38.680147 -10.42651) (xy 38.703114 -10.419046)
			(xy 38.715188 -10.418572) (xy 39.996618 -10.418572) (xy 40.008712 -10.418992) (xy 40.031718 -10.426458)
			(xy 40.051301 -10.440655) (xy 40.06555 -10.460201) (xy 40.073076 -10.483188) (xy 40.07358 -10.49528)
			(xy 40.07358 -11.91768) (xy 40.438324 -11.91768) (xy 40.438324 -10.49528) (xy 40.4387 -10.483168)
			(xy 40.446207 -10.460136) (xy 40.460479 -10.440561) (xy 40.48011 -10.426368) (xy 40.503172 -10.418952)
			(xy 40.515286 -10.418572) (xy 41.796716 -10.418572) (xy 41.808789 -10.41905) (xy 41.831754 -10.426515)
			(xy 41.851289 -10.440709) (xy 41.865483 -10.460243) (xy 41.872949 -10.483207) (xy 41.873424 -10.49528)
			(xy 41.873424 -11.91768) (xy 42.238168 -11.91768) (xy 42.238168 -10.49528) (xy 42.238599 -10.483173)
			(xy 42.2461 -10.460151) (xy 42.260359 -10.440581) (xy 42.279975 -10.426386) (xy 42.303022 -10.41896)
			(xy 42.31513 -10.418572) (xy 43.59656 -10.418572) (xy 43.608639 -10.419046) (xy 43.631617 -10.426501)
			(xy 43.651166 -10.440691) (xy 43.665372 -10.46023) (xy 43.672844 -10.483202) (xy 43.673268 -10.49528)
			(xy 43.673268 -11.91768) (xy 44.03852 -11.91768) (xy 44.03852 -10.49528) (xy 44.038896 -10.483193)
			(xy 44.046372 -10.460205) (xy 44.060587 -10.440653) (xy 44.080148 -10.42645) (xy 44.103141 -10.418988)
			(xy 44.115228 -10.418572) (xy 45.396658 -10.418572) (xy 45.408749 -10.419044) (xy 45.431753 -10.426493)
			(xy 45.451337 -10.440677) (xy 45.465587 -10.460212) (xy 45.473115 -10.483191) (xy 45.47362 -10.49528)
			(xy 45.47362 -11.91768) (xy 49.848516 -11.91768) (xy 49.848516 -10.49528) (xy 49.848896 -10.483194)
			(xy 49.856372 -10.460206) (xy 49.870586 -10.440654) (xy 49.890146 -10.426452) (xy 49.913138 -10.418989)
			(xy 49.925224 -10.418572) (xy 51.206654 -10.418572) (xy 51.218744 -10.419047) (xy 51.241749 -10.426495)
			(xy 51.261332 -10.440678) (xy 51.275583 -10.460213) (xy 51.283111 -10.483191) (xy 51.283616 -10.49528)
			(xy 51.283616 -11.91768) (xy 51.64836 -11.91768) (xy 51.64836 -10.49528) (xy 51.648799 -10.483174)
			(xy 51.656299 -10.460153) (xy 51.670556 -10.440584) (xy 51.69017 -10.426388) (xy 51.713215 -10.418961)
			(xy 51.725322 -10.418572) (xy 53.006752 -10.418572) (xy 53.01883 -10.419053) (xy 53.041808 -10.426505)
			(xy 53.061357 -10.440694) (xy 53.075564 -10.460231) (xy 53.083036 -10.483202) (xy 53.08346 -10.49528)
			(xy 53.08346 -11.91768) (xy 53.448204 -11.91768) (xy 53.448204 -10.49528) (xy 53.448599 -10.48317)
			(xy 53.456105 -10.460141) (xy 53.470372 -10.440568) (xy 53.489998 -10.426374) (xy 53.513054 -10.418955)
			(xy 53.525166 -10.418572) (xy 54.806596 -10.418572) (xy 54.818668 -10.419067) (xy 54.841632 -10.426526)
			(xy 54.861167 -10.440716) (xy 54.875363 -10.460246) (xy 54.882829 -10.483208) (xy 54.883304 -10.49528)
			(xy 54.883304 -11.91768) (xy 55.248556 -11.91768) (xy 55.248556 -10.49528) (xy 55.249047 -10.483208)
			(xy 55.25651 -10.460246) (xy 55.270701 -10.440713) (xy 55.290232 -10.426518) (xy 55.313192 -10.419049)
			(xy 55.325264 -10.418572) (xy 56.606694 -10.418572) (xy 56.618786 -10.419013) (xy 56.641792 -10.426472)
			(xy 56.661375 -10.440664) (xy 56.675625 -10.460205) (xy 56.683151 -10.483189) (xy 56.683656 -10.49528)
			(xy 56.683656 -11.91768) (xy 56.683167 -11.929782) (xy 56.67568 -11.952799) (xy 56.661435 -11.972368)
			(xy 56.641832 -11.986565) (xy 56.618797 -11.993996) (xy 56.606694 -11.994388) (xy 55.325264 -11.994388)
			(xy 55.313186 -11.993966) (xy 55.290214 -11.986491) (xy 55.270676 -11.972285) (xy 55.256483 -11.952736)
			(xy 55.249025 -11.929759) (xy 55.248556 -11.91768) (xy 54.883304 -11.91768) (xy 54.88287 -11.929762)
			(xy 54.875408 -11.952745) (xy 54.861207 -11.972296) (xy 54.841659 -11.9865) (xy 54.818678 -11.993968)
			(xy 54.806596 -11.994388) (xy 53.525166 -11.994388) (xy 53.513077 -11.993922) (xy 53.49008 -11.98646)
			(xy 53.470503 -11.972272) (xy 53.456253 -11.95274) (xy 53.448717 -11.929767) (xy 53.448204 -11.91768)
			(xy 53.08346 -11.91768) (xy 53.083069 -11.929766) (xy 53.075602 -11.952757) (xy 53.061391 -11.972311)
			(xy 53.041831 -11.986514) (xy 53.018839 -11.993974) (xy 53.006752 -11.994388) (xy 51.725322 -11.994388)
			(xy 51.713236 -11.993874) (xy 51.690241 -11.986427) (xy 51.670663 -11.972252) (xy 51.656411 -11.952729)
			(xy 51.648874 -11.929764) (xy 51.64836 -11.91768) (xy 51.283616 -11.91768) (xy 51.283167 -11.929786)
			(xy 51.275675 -11.95281) (xy 51.261421 -11.972382) (xy 51.241807 -11.986578) (xy 51.218761 -11.994002)
			(xy 51.206654 -11.994388) (xy 49.925224 -11.994388) (xy 49.913141 -11.993966) (xy 49.890155 -11.986503)
			(xy 49.870603 -11.9723) (xy 49.856399 -11.952748) (xy 49.848934 -11.929763) (xy 49.848516 -11.91768)
			(xy 45.47362 -11.91768) (xy 45.473167 -11.929786) (xy 45.465675 -11.952809) (xy 45.451423 -11.972381)
			(xy 45.43181 -11.986577) (xy 45.408765 -11.994001) (xy 45.396658 -11.994388) (xy 44.115228 -11.994388)
			(xy 44.103145 -11.993963) (xy 44.08016 -11.986501) (xy 44.060607 -11.972299) (xy 44.046403 -11.952748)
			(xy 44.038938 -11.929763) (xy 44.03852 -11.91768) (xy 43.673268 -11.91768) (xy 43.67287 -11.929766)
			(xy 43.665403 -11.952754) (xy 43.651194 -11.972308) (xy 43.631637 -11.986512) (xy 43.608646 -11.993973)
			(xy 43.59656 -11.994388) (xy 42.31513 -11.994388) (xy 42.303045 -11.993868) (xy 42.28005 -11.986423)
			(xy 42.260472 -11.972249) (xy 42.246219 -11.952728) (xy 42.238682 -11.929763) (xy 42.238168 -11.91768)
			(xy 41.873424 -11.91768) (xy 41.87297 -11.92976) (xy 41.86551 -11.952739) (xy 41.851314 -11.972289)
			(xy 41.831772 -11.986494) (xy 41.808796 -11.993965) (xy 41.796716 -11.994388) (xy 40.515286 -11.994388)
			(xy 40.503198 -11.993905) (xy 40.480202 -11.986448) (xy 40.460625 -11.972265) (xy 40.446374 -11.952736)
			(xy 40.438837 -11.929766) (xy 40.438324 -11.91768) (xy 40.07358 -11.91768) (xy 40.073166 -11.92979)
			(xy 40.06567 -11.95282) (xy 40.051408 -11.972395) (xy 40.031785 -11.986589) (xy 40.008729 -11.994007)
			(xy 39.996618 -11.994388) (xy 38.715188 -11.994388) (xy 38.703103 -11.993997) (xy 38.680116 -11.986524)
			(xy 38.660564 -11.972313) (xy 38.646361 -11.952755) (xy 38.638898 -11.929766) (xy 38.63848 -11.91768)
			(xy 32.76346 -11.91768) (xy 32.763066 -11.929792) (xy 32.755567 -11.952825) (xy 32.741301 -11.972402)
			(xy 32.721672 -11.986596) (xy 32.698611 -11.99401) (xy 32.686498 -11.994388) (xy 31.405068 -11.994388)
			(xy 31.39299 -11.993963) (xy 31.370018 -11.986489) (xy 31.35048 -11.972283) (xy 31.336287 -11.952735)
			(xy 31.328829 -11.929759) (xy 31.32836 -11.91768) (xy 30.963108 -11.91768) (xy 30.96267 -11.929762)
			(xy 30.955208 -11.952744) (xy 30.941008 -11.972294) (xy 30.921462 -11.986499) (xy 30.898482 -11.993967)
			(xy 30.8864 -11.994388) (xy 29.60497 -11.994388) (xy 29.592882 -11.993919) (xy 29.569885 -11.986457)
			(xy 29.550308 -11.97227) (xy 29.536057 -11.952739) (xy 29.528521 -11.929767) (xy 29.528008 -11.91768)
			(xy 29.163264 -11.91768) (xy 29.162869 -11.929766) (xy 29.155402 -11.952756) (xy 29.141193 -11.97231)
			(xy 29.121634 -11.986513) (xy 29.098642 -11.993973) (xy 29.086556 -11.994388) (xy 27.805126 -11.994388)
			(xy 27.793041 -11.993871) (xy 27.770046 -11.986425) (xy 27.750468 -11.97225) (xy 27.736215 -11.952729)
			(xy 27.728678 -11.929763) (xy 27.728164 -11.91768) (xy 27.36342 -11.91768) (xy 27.362967 -11.929786)
			(xy 27.355475 -11.952809) (xy 27.341223 -11.972381) (xy 27.32161 -11.986577) (xy 27.298565 -11.994001)
			(xy 27.286458 -11.994388) (xy 26.005028 -11.994388) (xy 25.992945 -11.993963) (xy 25.96996 -11.986501)
			(xy 25.950407 -11.972299) (xy 25.936203 -11.952748) (xy 25.928738 -11.929763) (xy 25.92832 -11.91768)
			(xy 25.563576 -11.91768) (xy 25.563166 -11.92979) (xy 25.555669 -11.952821) (xy 25.541407 -11.972396)
			(xy 25.521782 -11.986591) (xy 25.498726 -11.994008) (xy 25.486614 -11.994388) (xy 24.205184 -11.994388)
			(xy 24.193098 -11.994001) (xy 24.170112 -11.986526) (xy 24.15056 -11.972314) (xy 24.136357 -11.952756)
			(xy 24.128894 -11.929766) (xy 24.128476 -11.91768) (xy 23.763224 -11.91768) (xy 23.76277 -11.92976)
			(xy 23.75531 -11.952739) (xy 23.741114 -11.972289) (xy 23.721572 -11.986494) (xy 23.698596 -11.993965)
			(xy 23.686516 -11.994388) (xy 22.405086 -11.994388) (xy 22.392998 -11.993905) (xy 22.370002 -11.986448)
			(xy 22.350425 -11.972265) (xy 22.336174 -11.952736) (xy 22.328637 -11.929766) (xy 22.328124 -11.91768)
			(xy 21.96338 -11.91768) (xy 21.96297 -11.929764) (xy 21.955504 -11.952751) (xy 21.941299 -11.972304)
			(xy 21.921744 -11.986508) (xy 21.898756 -11.993971) (xy 21.886672 -11.994388) (xy 20.605242 -11.994388)
			(xy 20.593157 -11.993857) (xy 20.570163 -11.986416) (xy 20.550585 -11.972244) (xy 20.536332 -11.952726)
			(xy 20.528794 -11.929763) (xy 20.52828 -11.91768) (xy 20.163536 -11.91768) (xy 20.163067 -11.929784)
			(xy 20.155577 -11.952805) (xy 20.141328 -11.972375) (xy 20.12172 -11.986571) (xy 20.098679 -11.993999)
			(xy 20.086574 -11.994388) (xy 18.805144 -11.994388) (xy 18.793062 -11.99395) (xy 18.770077 -11.986492)
			(xy 18.750524 -11.972293) (xy 18.736319 -11.952745) (xy 18.728854 -11.929762) (xy 18.728436 -11.91768)
			(xy 12.414985 -11.91768) (xy 12.377103 -11.941483) (xy 12.253902 -12.009573) (xy 12.127078 -12.070649)
			(xy 11.997029 -12.124517) (xy 11.864164 -12.171009) (xy 11.728901 -12.209978) (xy 11.591666 -12.241301)
			(xy 11.45289 -12.26488) (xy 11.313011 -12.280641) (xy 11.172468 -12.288534) (xy 11.102086 -12.289028)
			(xy 1.999996 -12.289028) (xy 1.944227 -12.289537) (xy 1.833 -12.297872) (xy 1.722707 -12.314497)
			(xy 1.613965 -12.339317) (xy 1.507382 -12.372193) (xy 1.403554 -12.412943) (xy 1.303061 -12.461339)
			(xy 1.206466 -12.517108) (xy 1.114309 -12.579941) (xy 1.027105 -12.649484) (xy 0.945341 -12.72535)
			(xy 0.869476 -12.807114) (xy 0.802299 -12.891351) (xy 56.954662 -12.891351) (xy 56.954662 -12.836849)
			(xy 56.962418 -12.782901) (xy 56.977772 -12.730606) (xy 57.000413 -12.681029) (xy 57.029878 -12.635178)
			(xy 57.065568 -12.593986) (xy 57.106757 -12.558293) (xy 57.152606 -12.528825) (xy 57.202182 -12.506181)
			(xy 57.254476 -12.490823) (xy 57.308423 -12.483064) (xy 57.335674 -12.482576) (xy 58.199274 -12.482576)
			(xy 58.226527 -12.48307) (xy 58.280478 -12.490823) (xy 58.332777 -12.506176) (xy 58.382358 -12.528816)
			(xy 58.428213 -12.558282) (xy 58.469407 -12.593975) (xy 58.505102 -12.635166) (xy 58.534571 -12.681019)
			(xy 58.557215 -12.730598) (xy 58.572571 -12.782896) (xy 58.580329 -12.836847) (xy 58.580329 -12.891353)
			(xy 58.580329 -12.891355) (xy 70.949739 -12.891355) (xy 70.949739 -12.836845) (xy 70.957497 -12.78289)
			(xy 70.972854 -12.730588) (xy 70.995499 -12.681005) (xy 71.024971 -12.635149) (xy 71.060668 -12.593954)
			(xy 71.101865 -12.558259) (xy 71.147722 -12.52879) (xy 71.197307 -12.506147) (xy 71.24961 -12.490793)
			(xy 71.303565 -12.483038) (xy 71.33082 -12.482576) (xy 72.19442 -12.482576) (xy 72.221669 -12.483096)
			(xy 72.275612 -12.490854) (xy 72.327902 -12.50621) (xy 72.377475 -12.528852) (xy 72.423321 -12.558317)
			(xy 72.464507 -12.594007) (xy 72.500195 -12.635195) (xy 72.529658 -12.681043) (xy 72.552297 -12.730616)
			(xy 72.56765 -12.782907) (xy 72.575406 -12.836851) (xy 72.575406 -12.891349) (xy 72.56765 -12.945293)
			(xy 72.552297 -12.997584) (xy 72.529658 -13.047157) (xy 72.500195 -13.093005) (xy 72.464507 -13.134193)
			(xy 72.423321 -13.169883) (xy 72.377475 -13.199348) (xy 72.327902 -13.22199) (xy 72.275612 -13.237346)
			(xy 72.221669 -13.245104) (xy 72.19442 -13.245592) (xy 71.33082 -13.245592) (xy 71.303565 -13.245162)
			(xy 71.24961 -13.237407) (xy 71.197307 -13.222053) (xy 71.147722 -13.19941) (xy 71.101865 -13.169941)
			(xy 71.060668 -13.134246) (xy 71.024971 -13.093051) (xy 70.995499 -13.047195) (xy 70.972854 -12.997612)
			(xy 70.957497 -12.94531) (xy 70.949739 -12.891355) (xy 58.580329 -12.891355) (xy 58.572571 -12.945304)
			(xy 58.557215 -12.997602) (xy 58.534571 -13.047181) (xy 58.505102 -13.093034) (xy 58.469407 -13.134225)
			(xy 58.428213 -13.169918) (xy 58.382358 -13.199384) (xy 58.332777 -13.222024) (xy 58.280478 -13.237377)
			(xy 58.226527 -13.24513) (xy 58.199274 -13.245592) (xy 57.335674 -13.245592) (xy 57.308423 -13.245136)
			(xy 57.254476 -13.237377) (xy 57.202182 -13.222019) (xy 57.152606 -13.199375) (xy 57.106757 -13.169907)
			(xy 57.065568 -13.134214) (xy 57.029878 -13.093022) (xy 57.000413 -13.047171) (xy 56.977772 -12.997594)
			(xy 56.962418 -12.945299) (xy 56.954662 -12.891351) (xy 0.802299 -12.891351) (xy 0.799933 -12.894318)
			(xy 0.737102 -12.986476) (xy 0.681333 -13.083072) (xy 0.632939 -13.183565) (xy 0.59219 -13.287393)
			(xy 0.559313 -13.393977) (xy 0.534494 -13.502719) (xy 0.517871 -13.613012) (xy 0.509536 -13.724239)
			(xy 0.509016 -13.780008) (xy 0.509016 -14.374622) (xy 131.731512 -14.374622) (xy 131.731512 -12.952222)
			(xy 131.732026 -12.940136) (xy 131.739473 -12.917141) (xy 131.753648 -12.897563) (xy 131.773171 -12.883311)
			(xy 131.796136 -12.875774) (xy 131.80822 -12.87526) (xy 133.08965 -12.87526) (xy 133.101769 -12.87567)
			(xy 133.10207 -12.875768) (xy 135.555736 -12.875768) (xy 136.5377 -12.875768) (xy 136.5377 -14.324076)
			(xy 135.555736 -14.324076) (xy 135.555736 -12.875768) (xy 133.10207 -12.875768) (xy 133.124818 -12.883173)
			(xy 133.144421 -12.897431) (xy 133.15866 -12.917047) (xy 133.166142 -12.940102) (xy 133.166612 -12.952222)
			(xy 133.166612 -14.374622) (xy 166.45128 -14.374622) (xy 166.45128 -12.952222) (xy 166.451679 -12.940096)
			(xy 166.459171 -12.917031) (xy 166.473426 -12.897412) (xy 166.493049 -12.883162) (xy 166.516116 -12.875676)
			(xy 166.528242 -12.87526) (xy 167.809672 -12.87526) (xy 167.821775 -12.87574) (xy 167.844795 -12.883227)
			(xy 167.864365 -12.897473) (xy 167.878562 -12.917079) (xy 167.885991 -12.940118) (xy 167.88638 -12.952222)
			(xy 167.88638 -14.374622) (xy 168.251632 -14.374622) (xy 168.251632 -12.952222) (xy 168.252126 -12.940134)
			(xy 168.259576 -12.917136) (xy 168.273756 -12.897556) (xy 168.293283 -12.883305) (xy 168.316254 -12.875771)
			(xy 168.32834 -12.87526) (xy 169.60977 -12.87526) (xy 169.621893 -12.875686) (xy 169.644955 -12.883172)
			(xy 169.664572 -12.897422) (xy 169.678824 -12.917038) (xy 169.686313 -12.940099) (xy 169.686732 -12.952222)
			(xy 169.686732 -14.374622) (xy 169.686358 -14.386749) (xy 169.678856 -14.409813) (xy 169.664594 -14.429431)
			(xy 169.644967 -14.44368) (xy 169.621897 -14.451166) (xy 169.60977 -14.451584) (xy 168.32834 -14.451584)
			(xy 168.316232 -14.451149) (xy 168.293203 -14.443659) (xy 168.273628 -14.429403) (xy 168.259432 -14.409783)
			(xy 168.252014 -14.386732) (xy 168.251632 -14.374622) (xy 167.88638 -14.374622) (xy 167.885912 -14.386711)
			(xy 167.878452 -14.409709) (xy 167.864265 -14.429287) (xy 167.844733 -14.443537) (xy 167.821759 -14.451072)
			(xy 167.809672 -14.451584) (xy 166.528242 -14.451584) (xy 166.516124 -14.451105) (xy 166.49307 -14.443627)
			(xy 166.473456 -14.42939) (xy 166.459203 -14.409788) (xy 166.451705 -14.38674) (xy 166.45128 -14.374622)
			(xy 133.166612 -14.374622) (xy 133.166108 -14.386733) (xy 133.158621 -14.409768) (xy 133.144385 -14.429365)
			(xy 133.124793 -14.443608) (xy 133.101761 -14.451104) (xy 133.08965 -14.451584) (xy 131.80822 -14.451584)
			(xy 131.796111 -14.451166) (xy 131.773081 -14.44367) (xy 131.753507 -14.42941) (xy 131.739312 -14.409787)
			(xy 131.731893 -14.386733) (xy 131.731512 -14.374622) (xy 0.509016 -14.374622) (xy 0.509016 -15.866618)
			(xy 12.535916 -15.866618) (xy 12.535916 -14.764004) (xy 12.536316 -14.751919) (xy 12.543786 -14.728932)
			(xy 12.557994 -14.70938) (xy 12.57755 -14.695176) (xy 12.600539 -14.687713) (xy 12.612624 -14.687296)
			(xy 12.945872 -14.687296) (xy 12.957954 -14.687737) (xy 12.980936 -14.695197) (xy 13.000487 -14.709396)
			(xy 13.014692 -14.728942) (xy 13.02216 -14.751922) (xy 13.02258 -14.764004) (xy 13.02258 -15.866618)
			(xy 13.61694 -15.866618) (xy 13.61694 -14.782292) (xy 13.617306 -14.770204) (xy 13.624782 -14.747213)
			(xy 13.638998 -14.727659) (xy 13.658563 -14.713456) (xy 13.68156 -14.705998) (xy 13.693648 -14.705584)
			(xy 14.045184 -14.705584) (xy 14.057265 -14.706026) (xy 14.080246 -14.713488) (xy 14.099796 -14.727687)
			(xy 14.114001 -14.747233) (xy 14.12147 -14.770211) (xy 14.121892 -14.782292) (xy 14.121892 -15.222054)
			(xy 135.233343 -15.222054) (xy 135.233343 -15.167546) (xy 135.2411 -15.113592) (xy 135.256457 -15.061292)
			(xy 135.279101 -15.011709) (xy 135.308571 -14.965854) (xy 135.344267 -14.92466) (xy 135.385462 -14.888965)
			(xy 135.431318 -14.859497) (xy 135.480901 -14.836854) (xy 135.533202 -14.821498) (xy 135.587156 -14.813742)
			(xy 135.61441 -14.81328) (xy 136.47801 -14.81328) (xy 136.50526 -14.813791) (xy 136.559205 -14.821548)
			(xy 136.611497 -14.836904) (xy 136.661071 -14.859545) (xy 136.706919 -14.88901) (xy 136.748106 -14.924701)
			(xy 136.783796 -14.965889) (xy 136.81326 -15.011738) (xy 136.8359 -15.061313) (xy 136.851254 -15.113605)
			(xy 136.85901 -15.16755) (xy 136.85901 -15.22205) (xy 136.851254 -15.275995) (xy 136.8359 -15.328287)
			(xy 136.81326 -15.377862) (xy 136.783796 -15.423711) (xy 136.748106 -15.464899) (xy 136.706919 -15.50059)
			(xy 136.661071 -15.530055) (xy 136.611497 -15.552696) (xy 136.559205 -15.568052) (xy 136.50526 -15.575809)
			(xy 136.47801 -15.576296) (xy 135.61441 -15.576296) (xy 135.587156 -15.575858) (xy 135.533202 -15.568102)
			(xy 135.480901 -15.552746) (xy 135.431318 -15.530103) (xy 135.385462 -15.500635) (xy 135.344267 -15.46494)
			(xy 135.308571 -15.423746) (xy 135.279101 -15.377891) (xy 135.256457 -15.328308) (xy 135.2411 -15.276008)
			(xy 135.233343 -15.222054) (xy 14.121892 -15.222054) (xy 14.121892 -15.866618) (xy 14.121409 -15.878705)
			(xy 14.113951 -15.901701) (xy 14.099767 -15.921278) (xy 14.08024 -15.935529) (xy 14.05727 -15.943066)
			(xy 14.045184 -15.94358) (xy 13.693648 -15.94358) (xy 13.68154 -15.943143) (xy 13.65851 -15.935654)
			(xy 13.638935 -15.921399) (xy 13.624739 -15.901779) (xy 13.617321 -15.878728) (xy 13.61694 -15.866618)
			(xy 13.02258 -15.866618) (xy 13.022109 -15.878707) (xy 13.014649 -15.901704) (xy 13.000463 -15.921282)
			(xy 12.980932 -15.935533) (xy 12.957959 -15.943068) (xy 12.945872 -15.94358) (xy 12.612624 -15.94358)
			(xy 12.600514 -15.943163) (xy 12.577485 -15.935668) (xy 12.557909 -15.921407) (xy 12.543715 -15.901784)
			(xy 12.536297 -15.878729) (xy 12.535916 -15.866618) (xy 0.509016 -15.866618) (xy 0.509016 -16.442436)
			(xy 15.3162 -16.442436) (xy 15.3162 -15.756636) (xy 15.316644 -15.744554) (xy 15.324102 -15.721571)
			(xy 15.3383 -15.70202) (xy 15.357846 -15.687815) (xy 15.380827 -15.680348) (xy 15.392908 -15.679928)
			(xy 15.587472 -15.679928) (xy 15.598578 -15.680299) (xy 15.61987 -15.68663) (xy 15.629382 -15.692374)
			(xy 15.923006 -15.884906) (xy 15.932376 -15.890634) (xy 15.953395 -15.896965) (xy 15.975347 -15.897031)
			(xy 15.996404 -15.890829) (xy 16.00581 -15.88516) (xy 16.301974 -15.692374) (xy 16.311481 -15.68662)
			(xy 16.332777 -15.680298) (xy 16.343884 -15.679928) (xy 16.538448 -15.679928) (xy 16.550529 -15.680324)
			(xy 16.573504 -15.687804) (xy 16.593043 -15.702017) (xy 16.607235 -15.721572) (xy 16.614689 -15.744555)
			(xy 16.615156 -15.756636) (xy 16.615156 -16.442436) (xy 20.9042 -16.442436) (xy 20.9042 -15.756636)
			(xy 20.904644 -15.744554) (xy 20.912102 -15.721571) (xy 20.9263 -15.70202) (xy 20.945846 -15.687815)
			(xy 20.968827 -15.680348) (xy 20.980908 -15.679928) (xy 21.175472 -15.679928) (xy 21.186578 -15.680299)
			(xy 21.20787 -15.68663) (xy 21.217382 -15.692374) (xy 21.511006 -15.884906) (xy 21.520376 -15.890634)
			(xy 21.541395 -15.896965) (xy 21.563347 -15.897031) (xy 21.584404 -15.890829) (xy 21.59381 -15.88516)
			(xy 21.889974 -15.692374) (xy 21.899481 -15.68662) (xy 21.920777 -15.680298) (xy 21.931884 -15.679928)
			(xy 22.126448 -15.679928) (xy 22.138529 -15.680324) (xy 22.161504 -15.687804) (xy 22.181043 -15.702017)
			(xy 22.195235 -15.721572) (xy 22.202689 -15.744555) (xy 22.203156 -15.756636) (xy 22.203156 -16.442436)
			(xy 26.4922 -16.442436) (xy 26.4922 -15.756636) (xy 26.492644 -15.744554) (xy 26.500102 -15.721571)
			(xy 26.5143 -15.70202) (xy 26.533846 -15.687815) (xy 26.556827 -15.680348) (xy 26.568908 -15.679928)
			(xy 26.763472 -15.679928) (xy 26.774578 -15.680299) (xy 26.79587 -15.68663) (xy 26.805382 -15.692374)
			(xy 27.099006 -15.884906) (xy 27.108376 -15.890634) (xy 27.129395 -15.896965) (xy 27.151347 -15.897031)
			(xy 27.172404 -15.890829) (xy 27.18181 -15.88516) (xy 27.477974 -15.692374) (xy 27.487481 -15.68662)
			(xy 27.508777 -15.680298) (xy 27.519884 -15.679928) (xy 27.714448 -15.679928) (xy 27.726529 -15.680324)
			(xy 27.749504 -15.687804) (xy 27.769043 -15.702017) (xy 27.783235 -15.721572) (xy 27.790689 -15.744555)
			(xy 27.791156 -15.756636) (xy 27.791156 -16.442436) (xy 32.0802 -16.442436) (xy 32.0802 -15.756636)
			(xy 32.080644 -15.744554) (xy 32.088102 -15.721571) (xy 32.1023 -15.70202) (xy 32.121846 -15.687815)
			(xy 32.144827 -15.680348) (xy 32.156908 -15.679928) (xy 32.351472 -15.679928) (xy 32.362578 -15.680299)
			(xy 32.38387 -15.68663) (xy 32.393382 -15.692374) (xy 32.687006 -15.884906) (xy 32.696376 -15.890634)
			(xy 32.717395 -15.896965) (xy 32.739347 -15.897031) (xy 32.760404 -15.890829) (xy 32.76981 -15.88516)
			(xy 33.065974 -15.692374) (xy 33.075481 -15.68662) (xy 33.096777 -15.680298) (xy 33.107884 -15.679928)
			(xy 33.302448 -15.679928) (xy 33.314529 -15.680324) (xy 33.337504 -15.687804) (xy 33.357043 -15.702017)
			(xy 33.371235 -15.721572) (xy 33.378689 -15.744555) (xy 33.379156 -15.756636) (xy 33.379156 -16.442436)
			(xy 37.6682 -16.442436) (xy 37.6682 -15.756636) (xy 37.668644 -15.744554) (xy 37.676102 -15.721571)
			(xy 37.6903 -15.70202) (xy 37.709846 -15.687815) (xy 37.732827 -15.680348) (xy 37.744908 -15.679928)
			(xy 37.939472 -15.679928) (xy 37.950578 -15.680299) (xy 37.97187 -15.68663) (xy 37.981382 -15.692374)
			(xy 38.275006 -15.884906) (xy 38.284376 -15.890634) (xy 38.305395 -15.896965) (xy 38.327347 -15.897031)
			(xy 38.348404 -15.890829) (xy 38.35781 -15.88516) (xy 38.653974 -15.692374) (xy 38.663481 -15.68662)
			(xy 38.684777 -15.680298) (xy 38.695884 -15.679928) (xy 38.890448 -15.679928) (xy 38.902529 -15.680324)
			(xy 38.925504 -15.687804) (xy 38.945043 -15.702017) (xy 38.959235 -15.721572) (xy 38.966689 -15.744555)
			(xy 38.967156 -15.756636) (xy 38.967156 -16.442436) (xy 43.562016 -16.442436) (xy 43.562016 -15.756636)
			(xy 43.562444 -15.744553) (xy 43.569904 -15.721567) (xy 43.584106 -15.702014) (xy 43.603656 -15.68781)
			(xy 43.626641 -15.680346) (xy 43.638724 -15.679928) (xy 43.833288 -15.679928) (xy 43.844394 -15.680293)
			(xy 43.865686 -15.686628) (xy 43.875198 -15.692374) (xy 44.168822 -15.884906) (xy 44.178184 -15.890648)
			(xy 44.199207 -15.896975) (xy 44.221161 -15.897038) (xy 44.24222 -15.890831) (xy 44.251626 -15.88516)
			(xy 44.54779 -15.692374) (xy 44.557294 -15.686614) (xy 44.578592 -15.680296) (xy 44.5897 -15.679928)
			(xy 44.784264 -15.679928) (xy 44.796348 -15.680344) (xy 44.819336 -15.687806) (xy 44.83889 -15.70201)
			(xy 44.853094 -15.721564) (xy 44.860556 -15.744552) (xy 44.860972 -15.756636) (xy 44.860972 -16.442436)
			(xy 49.150016 -16.442436) (xy 49.150016 -15.756636) (xy 49.150444 -15.744553) (xy 49.157904 -15.721567)
			(xy 49.172106 -15.702014) (xy 49.191656 -15.68781) (xy 49.214641 -15.680346) (xy 49.226724 -15.679928)
			(xy 49.421288 -15.679928) (xy 49.432394 -15.680293) (xy 49.453686 -15.686628) (xy 49.463198 -15.692374)
			(xy 49.756822 -15.884906) (xy 49.766184 -15.890648) (xy 49.787207 -15.896975) (xy 49.809161 -15.897038)
			(xy 49.83022 -15.890831) (xy 49.839626 -15.88516) (xy 50.13579 -15.692374) (xy 50.145294 -15.686614)
			(xy 50.166592 -15.680296) (xy 50.1777 -15.679928) (xy 50.372264 -15.679928) (xy 50.384348 -15.680344)
			(xy 50.407336 -15.687806) (xy 50.42689 -15.70201) (xy 50.441094 -15.721564) (xy 50.448556 -15.744552)
			(xy 50.448972 -15.756636) (xy 50.448972 -16.442436) (xy 54.772052 -16.442436) (xy 54.772052 -15.756636)
			(xy 54.772594 -15.744567) (xy 54.780042 -15.721608) (xy 54.79422 -15.702074) (xy 54.81374 -15.687877)
			(xy 54.836692 -15.680406) (xy 54.84876 -15.679928) (xy 55.043324 -15.679928) (xy 55.054428 -15.680318)
			(xy 55.07572 -15.686635) (xy 55.085234 -15.692374) (xy 55.378858 -15.884906) (xy 55.388251 -15.890593)
			(xy 55.409259 -15.896932) (xy 55.431203 -15.897011) (xy 55.452256 -15.890822) (xy 55.461662 -15.88516)
			(xy 55.757826 -15.692374) (xy 55.767343 -15.686638) (xy 55.788631 -15.680305) (xy 55.799736 -15.679928)
			(xy 55.9943 -15.679928) (xy 56.006386 -15.680313) (xy 56.029375 -15.687785) (xy 56.048929 -15.701997)
			(xy 56.063132 -15.721557) (xy 56.070593 -15.744549) (xy 56.071008 -15.756636) (xy 56.071008 -16.442436)
			(xy 56.070567 -16.454512) (xy 56.063094 -16.477481) (xy 56.048892 -16.497017) (xy 56.029349 -16.511211)
			(xy 56.006377 -16.518672) (xy 55.9943 -16.519144) (xy 55.799736 -16.519144) (xy 55.788627 -16.518796)
			(xy 55.76733 -16.512461) (xy 55.757826 -16.506698) (xy 55.462932 -16.314166) (xy 55.453545 -16.308463)
			(xy 55.432507 -16.30219) (xy 55.410553 -16.30219) (xy 55.389515 -16.308463) (xy 55.380128 -16.314166)
			(xy 55.086504 -16.506698) (xy 55.077 -16.512458) (xy 55.055702 -16.518776) (xy 55.044594 -16.519144)
			(xy 54.84876 -16.519144) (xy 54.836687 -16.518671) (xy 54.813724 -16.511201) (xy 54.794191 -16.497006)
			(xy 54.779997 -16.477472) (xy 54.772529 -16.454509) (xy 54.772052 -16.442436) (xy 50.448972 -16.442436)
			(xy 50.448566 -16.454516) (xy 50.441089 -16.477491) (xy 50.426879 -16.49703) (xy 50.407326 -16.511222)
			(xy 50.384344 -16.518677) (xy 50.372264 -16.519144) (xy 50.1777 -16.519144) (xy 50.166593 -16.518769)
			(xy 50.145297 -16.512453) (xy 50.13579 -16.506698) (xy 49.840896 -16.314166) (xy 49.831509 -16.308463)
			(xy 49.810471 -16.30219) (xy 49.788517 -16.30219) (xy 49.767479 -16.308463) (xy 49.758092 -16.314166)
			(xy 49.464468 -16.506698) (xy 49.454951 -16.512434) (xy 49.433663 -16.518768) (xy 49.422558 -16.519144)
			(xy 49.226724 -16.519144) (xy 49.214654 -16.518616) (xy 49.191694 -16.511164) (xy 49.17216 -16.496983)
			(xy 49.157963 -16.47746) (xy 49.150493 -16.454505) (xy 49.150016 -16.442436) (xy 44.860972 -16.442436)
			(xy 44.860566 -16.454516) (xy 44.853089 -16.477491) (xy 44.838879 -16.49703) (xy 44.819326 -16.511222)
			(xy 44.796344 -16.518677) (xy 44.784264 -16.519144) (xy 44.5897 -16.519144) (xy 44.578593 -16.518769)
			(xy 44.557297 -16.512453) (xy 44.54779 -16.506698) (xy 44.252896 -16.314166) (xy 44.243509 -16.308463)
			(xy 44.222471 -16.30219) (xy 44.200517 -16.30219) (xy 44.179479 -16.308463) (xy 44.170092 -16.314166)
			(xy 43.876468 -16.506698) (xy 43.866951 -16.512434) (xy 43.845663 -16.518768) (xy 43.834558 -16.519144)
			(xy 43.638724 -16.519144) (xy 43.626654 -16.518616) (xy 43.603694 -16.511164) (xy 43.58416 -16.496983)
			(xy 43.569963 -16.47746) (xy 43.562493 -16.454505) (xy 43.562016 -16.442436) (xy 38.967156 -16.442436)
			(xy 38.966667 -16.454508) (xy 38.959201 -16.477468) (xy 38.945009 -16.497) (xy 38.925479 -16.511195)
			(xy 38.90252 -16.518666) (xy 38.890448 -16.519144) (xy 38.695884 -16.519144) (xy 38.684776 -16.518776)
			(xy 38.66348 -16.512455) (xy 38.653974 -16.506698) (xy 38.35908 -16.314166) (xy 38.349693 -16.308463)
			(xy 38.328655 -16.30219) (xy 38.306701 -16.30219) (xy 38.285663 -16.308463) (xy 38.276276 -16.314166)
			(xy 37.982652 -16.506698) (xy 37.973138 -16.51244) (xy 37.951848 -16.51877) (xy 37.940742 -16.519144)
			(xy 37.744908 -16.519144) (xy 37.732837 -16.51863) (xy 37.709877 -16.511174) (xy 37.690343 -16.496989)
			(xy 37.676147 -16.477463) (xy 37.668677 -16.454506) (xy 37.6682 -16.442436) (xy 33.379156 -16.442436)
			(xy 33.378667 -16.454508) (xy 33.371201 -16.477468) (xy 33.357009 -16.497) (xy 33.337479 -16.511195)
			(xy 33.31452 -16.518666) (xy 33.302448 -16.519144) (xy 33.107884 -16.519144) (xy 33.096776 -16.518776)
			(xy 33.07548 -16.512455) (xy 33.065974 -16.506698) (xy 32.77108 -16.314166) (xy 32.761693 -16.308463)
			(xy 32.740655 -16.30219) (xy 32.718701 -16.30219) (xy 32.697663 -16.308463) (xy 32.688276 -16.314166)
			(xy 32.394652 -16.506698) (xy 32.385138 -16.51244) (xy 32.363848 -16.51877) (xy 32.352742 -16.519144)
			(xy 32.156908 -16.519144) (xy 32.144837 -16.51863) (xy 32.121877 -16.511174) (xy 32.102343 -16.496989)
			(xy 32.088147 -16.477463) (xy 32.080677 -16.454506) (xy 32.0802 -16.442436) (xy 27.791156 -16.442436)
			(xy 27.790667 -16.454508) (xy 27.783201 -16.477468) (xy 27.769009 -16.497) (xy 27.749479 -16.511195)
			(xy 27.72652 -16.518666) (xy 27.714448 -16.519144) (xy 27.519884 -16.519144) (xy 27.508776 -16.518776)
			(xy 27.48748 -16.512455) (xy 27.477974 -16.506698) (xy 27.18308 -16.314166) (xy 27.173693 -16.308463)
			(xy 27.152655 -16.30219) (xy 27.130701 -16.30219) (xy 27.109663 -16.308463) (xy 27.100276 -16.314166)
			(xy 26.806652 -16.506698) (xy 26.797138 -16.51244) (xy 26.775848 -16.51877) (xy 26.764742 -16.519144)
			(xy 26.568908 -16.519144) (xy 26.556837 -16.51863) (xy 26.533877 -16.511174) (xy 26.514343 -16.496989)
			(xy 26.500147 -16.477463) (xy 26.492677 -16.454506) (xy 26.4922 -16.442436) (xy 22.203156 -16.442436)
			(xy 22.202667 -16.454508) (xy 22.195201 -16.477468) (xy 22.181009 -16.497) (xy 22.161479 -16.511195)
			(xy 22.13852 -16.518666) (xy 22.126448 -16.519144) (xy 21.931884 -16.519144) (xy 21.920776 -16.518776)
			(xy 21.89948 -16.512455) (xy 21.889974 -16.506698) (xy 21.59508 -16.314166) (xy 21.585693 -16.308463)
			(xy 21.564655 -16.30219) (xy 21.542701 -16.30219) (xy 21.521663 -16.308463) (xy 21.512276 -16.314166)
			(xy 21.218652 -16.506698) (xy 21.209138 -16.51244) (xy 21.187848 -16.51877) (xy 21.176742 -16.519144)
			(xy 20.980908 -16.519144) (xy 20.968837 -16.51863) (xy 20.945877 -16.511174) (xy 20.926343 -16.496989)
			(xy 20.912147 -16.477463) (xy 20.904677 -16.454506) (xy 20.9042 -16.442436) (xy 16.615156 -16.442436)
			(xy 16.614667 -16.454508) (xy 16.607201 -16.477468) (xy 16.593009 -16.497) (xy 16.573479 -16.511195)
			(xy 16.55052 -16.518666) (xy 16.538448 -16.519144) (xy 16.343884 -16.519144) (xy 16.332776 -16.518776)
			(xy 16.31148 -16.512455) (xy 16.301974 -16.506698) (xy 16.00708 -16.314166) (xy 15.997693 -16.308463)
			(xy 15.976655 -16.30219) (xy 15.954701 -16.30219) (xy 15.933663 -16.308463) (xy 15.924276 -16.314166)
			(xy 15.630652 -16.506698) (xy 15.621138 -16.51244) (xy 15.599848 -16.51877) (xy 15.588742 -16.519144)
			(xy 15.392908 -16.519144) (xy 15.380837 -16.51863) (xy 15.357877 -16.511174) (xy 15.338343 -16.496989)
			(xy 15.324147 -16.477463) (xy 15.316677 -16.454506) (xy 15.3162 -16.442436) (xy 0.509016 -16.442436)
			(xy 0.509016 -17.197578) (xy 131.72694 -17.197578) (xy 131.72694 -15.775178) (xy 131.727393 -15.763062)
			(xy 131.734886 -15.740018) (xy 131.749133 -15.720416) (xy 131.768739 -15.706175) (xy 131.791786 -15.698689)
			(xy 131.803902 -15.698216) (xy 133.085332 -15.698216) (xy 133.097444 -15.698589) (xy 133.120475 -15.706099)
			(xy 133.140049 -15.720372) (xy 133.154242 -15.740003) (xy 133.161659 -15.763064) (xy 133.16204 -15.775178)
			(xy 133.16204 -15.825724) (xy 135.555736 -15.825724) (xy 136.5377 -15.825724) (xy 137.356088 -15.825724)
			(xy 138.337544 -15.825724) (xy 139.155932 -15.825724) (xy 140.137388 -15.825724) (xy 140.955776 -15.825724)
			(xy 141.93774 -15.825724) (xy 141.93774 -15.83436) (xy 186.074812 -15.83436) (xy 187.058808 -15.83436)
			(xy 187.058808 -17.270476) (xy 186.074812 -17.270476) (xy 186.074812 -15.83436) (xy 141.93774 -15.83436)
			(xy 141.93774 -17.274032) (xy 140.955776 -17.274032) (xy 140.955776 -15.825724) (xy 140.137388 -15.825724)
			(xy 140.137388 -17.274032) (xy 139.155932 -17.274032) (xy 139.155932 -15.825724) (xy 138.337544 -15.825724)
			(xy 138.337544 -17.274032) (xy 137.356088 -17.274032) (xy 137.356088 -15.825724) (xy 136.5377 -15.825724)
			(xy 136.5377 -17.274032) (xy 135.555736 -17.274032) (xy 135.555736 -15.825724) (xy 133.16204 -15.825724)
			(xy 133.16204 -17.197578) (xy 133.161573 -17.209668) (xy 133.15412 -17.232672) (xy 133.139934 -17.252254)
			(xy 133.120399 -17.266504) (xy 133.097421 -17.274033) (xy 133.085332 -17.27454) (xy 131.803902 -17.27454)
			(xy 131.791777 -17.274138) (xy 131.768715 -17.266644) (xy 131.749098 -17.252388) (xy 131.734847 -17.232767)
			(xy 131.727359 -17.209703) (xy 131.72694 -17.197578) (xy 0.509016 -17.197578) (xy 0.509016 -17.639611)
			(xy 15.152858 -17.639611) (xy 15.152858 -17.585109) (xy 15.160614 -17.531161) (xy 15.175969 -17.478867)
			(xy 15.19861 -17.42929) (xy 15.228076 -17.383439) (xy 15.263768 -17.342249) (xy 15.304958 -17.306558)
			(xy 15.350808 -17.277091) (xy 15.400385 -17.25445) (xy 15.452679 -17.239095) (xy 15.506627 -17.231338)
			(xy 15.533878 -17.230852) (xy 16.397478 -17.230852) (xy 16.424731 -17.231315) (xy 16.478682 -17.239072)
			(xy 16.53098 -17.254428) (xy 16.580561 -17.27707) (xy 16.626414 -17.306538) (xy 16.667607 -17.342232)
			(xy 16.703301 -17.383424) (xy 16.732769 -17.429278) (xy 16.755412 -17.478858) (xy 16.770768 -17.531156)
			(xy 16.778525 -17.585107) (xy 16.778525 -17.639613) (xy 16.770768 -17.693564) (xy 16.755412 -17.745862)
			(xy 16.732769 -17.795442) (xy 16.703301 -17.841296) (xy 16.667607 -17.882488) (xy 16.626414 -17.918182)
			(xy 16.580561 -17.94765) (xy 16.539424 -17.966436) (xy 18.1102 -17.966436) (xy 18.1102 -17.280636)
			(xy 18.110644 -17.268554) (xy 18.118102 -17.245571) (xy 18.1323 -17.22602) (xy 18.151846 -17.211815)
			(xy 18.174827 -17.204348) (xy 18.186908 -17.203928) (xy 18.381472 -17.203928) (xy 18.392578 -17.204299)
			(xy 18.41387 -17.21063) (xy 18.423382 -17.216374) (xy 18.717006 -17.408906) (xy 18.726376 -17.414634)
			(xy 18.747395 -17.420965) (xy 18.769347 -17.421031) (xy 18.790404 -17.414829) (xy 18.79981 -17.40916)
			(xy 19.095974 -17.216374) (xy 19.105481 -17.21062) (xy 19.126777 -17.204298) (xy 19.137884 -17.203928)
			(xy 19.332448 -17.203928) (xy 19.344529 -17.204324) (xy 19.367504 -17.211804) (xy 19.387043 -17.226017)
			(xy 19.401235 -17.245572) (xy 19.408689 -17.268555) (xy 19.409156 -17.280636) (xy 19.409156 -17.639611)
			(xy 20.740858 -17.639611) (xy 20.740858 -17.585109) (xy 20.748614 -17.531161) (xy 20.763969 -17.478867)
			(xy 20.78661 -17.42929) (xy 20.816076 -17.383439) (xy 20.851768 -17.342249) (xy 20.892958 -17.306558)
			(xy 20.938808 -17.277091) (xy 20.988385 -17.25445) (xy 21.040679 -17.239095) (xy 21.094627 -17.231338)
			(xy 21.121878 -17.230852) (xy 21.985478 -17.230852) (xy 22.012729 -17.231394) (xy 22.066677 -17.239147)
			(xy 22.118972 -17.2545) (xy 22.168549 -17.277139) (xy 22.2144 -17.306603) (xy 22.255591 -17.342293)
			(xy 22.291284 -17.383482) (xy 22.320751 -17.429331) (xy 22.343392 -17.478908) (xy 22.358748 -17.531202)
			(xy 22.366505 -17.585149) (xy 22.366505 -17.639651) (xy 22.358748 -17.693598) (xy 22.343392 -17.745892)
			(xy 22.320751 -17.795469) (xy 22.291284 -17.841318) (xy 22.255591 -17.882507) (xy 22.2144 -17.918197)
			(xy 22.168549 -17.947661) (xy 22.127434 -17.966436) (xy 23.6982 -17.966436) (xy 23.6982 -17.280636)
			(xy 23.698644 -17.268554) (xy 23.706102 -17.245571) (xy 23.7203 -17.22602) (xy 23.739846 -17.211815)
			(xy 23.762827 -17.204348) (xy 23.774908 -17.203928) (xy 23.969472 -17.203928) (xy 23.980578 -17.204299)
			(xy 24.00187 -17.21063) (xy 24.011382 -17.216374) (xy 24.305006 -17.408906) (xy 24.314376 -17.414634)
			(xy 24.335395 -17.420965) (xy 24.357347 -17.421031) (xy 24.378404 -17.414829) (xy 24.38781 -17.40916)
			(xy 24.683974 -17.216374) (xy 24.693481 -17.21062) (xy 24.714777 -17.204298) (xy 24.725884 -17.203928)
			(xy 24.920448 -17.203928) (xy 24.932529 -17.204324) (xy 24.955504 -17.211804) (xy 24.975043 -17.226017)
			(xy 24.989235 -17.245572) (xy 24.996689 -17.268555) (xy 24.997156 -17.280636) (xy 24.997156 -17.639653)
			(xy 26.328838 -17.639653) (xy 26.328838 -17.585147) (xy 26.336595 -17.531195) (xy 26.35195 -17.478897)
			(xy 26.374592 -17.429316) (xy 26.404059 -17.383462) (xy 26.439752 -17.342268) (xy 26.480944 -17.306573)
			(xy 26.526797 -17.277103) (xy 26.576376 -17.254458) (xy 26.628674 -17.239099) (xy 26.682625 -17.231339)
			(xy 26.709878 -17.230852) (xy 27.573478 -17.230852) (xy 27.600729 -17.231394) (xy 27.654677 -17.239147)
			(xy 27.706972 -17.2545) (xy 27.756549 -17.277139) (xy 27.8024 -17.306603) (xy 27.843591 -17.342293)
			(xy 27.879284 -17.383482) (xy 27.908751 -17.429331) (xy 27.931392 -17.478908) (xy 27.946748 -17.531202)
			(xy 27.954505 -17.585149) (xy 27.954505 -17.639651) (xy 27.946748 -17.693598) (xy 27.931392 -17.745892)
			(xy 27.908751 -17.795469) (xy 27.879284 -17.841318) (xy 27.843591 -17.882507) (xy 27.8024 -17.918197)
			(xy 27.756549 -17.947661) (xy 27.715434 -17.966436) (xy 29.2862 -17.966436) (xy 29.2862 -17.280636)
			(xy 29.286644 -17.268554) (xy 29.294102 -17.245571) (xy 29.3083 -17.22602) (xy 29.327846 -17.211815)
			(xy 29.350827 -17.204348) (xy 29.362908 -17.203928) (xy 29.557472 -17.203928) (xy 29.568578 -17.204299)
			(xy 29.58987 -17.21063) (xy 29.599382 -17.216374) (xy 29.893006 -17.408906) (xy 29.902376 -17.414634)
			(xy 29.923395 -17.420965) (xy 29.945347 -17.421031) (xy 29.966404 -17.414829) (xy 29.97581 -17.40916)
			(xy 30.271974 -17.216374) (xy 30.281481 -17.21062) (xy 30.302777 -17.204298) (xy 30.313884 -17.203928)
			(xy 30.508448 -17.203928) (xy 30.520529 -17.204324) (xy 30.543504 -17.211804) (xy 30.563043 -17.226017)
			(xy 30.577235 -17.245572) (xy 30.584689 -17.268555) (xy 30.585156 -17.280636) (xy 30.585156 -17.639653)
			(xy 31.916838 -17.639653) (xy 31.916838 -17.585147) (xy 31.924595 -17.531195) (xy 31.93995 -17.478897)
			(xy 31.962592 -17.429316) (xy 31.992059 -17.383462) (xy 32.027752 -17.342268) (xy 32.068944 -17.306573)
			(xy 32.114797 -17.277103) (xy 32.164376 -17.254458) (xy 32.216674 -17.239099) (xy 32.270625 -17.231339)
			(xy 32.297878 -17.230852) (xy 33.161478 -17.230852) (xy 33.188729 -17.231394) (xy 33.242677 -17.239147)
			(xy 33.294972 -17.2545) (xy 33.344549 -17.277139) (xy 33.3904 -17.306603) (xy 33.431591 -17.342293)
			(xy 33.467284 -17.383482) (xy 33.496751 -17.429331) (xy 33.519392 -17.478908) (xy 33.534748 -17.531202)
			(xy 33.542505 -17.585149) (xy 33.542505 -17.639651) (xy 33.534748 -17.693598) (xy 33.519392 -17.745892)
			(xy 33.496751 -17.795469) (xy 33.467284 -17.841318) (xy 33.431591 -17.882507) (xy 33.3904 -17.918197)
			(xy 33.344549 -17.947661) (xy 33.303434 -17.966436) (xy 34.8742 -17.966436) (xy 34.8742 -17.280636)
			(xy 34.874644 -17.268554) (xy 34.882102 -17.245571) (xy 34.8963 -17.22602) (xy 34.915846 -17.211815)
			(xy 34.938827 -17.204348) (xy 34.950908 -17.203928) (xy 35.145472 -17.203928) (xy 35.156578 -17.204299)
			(xy 35.17787 -17.21063) (xy 35.187382 -17.216374) (xy 35.481006 -17.408906) (xy 35.490376 -17.414634)
			(xy 35.511395 -17.420965) (xy 35.533347 -17.421031) (xy 35.554404 -17.414829) (xy 35.56381 -17.40916)
			(xy 35.859974 -17.216374) (xy 35.869481 -17.21062) (xy 35.890777 -17.204298) (xy 35.901884 -17.203928)
			(xy 36.096448 -17.203928) (xy 36.108529 -17.204324) (xy 36.131504 -17.211804) (xy 36.151043 -17.226017)
			(xy 36.165235 -17.245572) (xy 36.172689 -17.268555) (xy 36.173156 -17.280636) (xy 36.173156 -17.639653)
			(xy 37.504838 -17.639653) (xy 37.504838 -17.585147) (xy 37.512595 -17.531195) (xy 37.52795 -17.478897)
			(xy 37.550592 -17.429316) (xy 37.580059 -17.383462) (xy 37.615752 -17.342268) (xy 37.656944 -17.306573)
			(xy 37.702797 -17.277103) (xy 37.752376 -17.254458) (xy 37.804674 -17.239099) (xy 37.858625 -17.231339)
			(xy 37.885878 -17.230852) (xy 38.749478 -17.230852) (xy 38.776729 -17.231394) (xy 38.830677 -17.239147)
			(xy 38.882972 -17.2545) (xy 38.932549 -17.277139) (xy 38.9784 -17.306603) (xy 39.019591 -17.342293)
			(xy 39.055284 -17.383482) (xy 39.084751 -17.429331) (xy 39.107392 -17.478908) (xy 39.122748 -17.531202)
			(xy 39.130505 -17.585149) (xy 39.130505 -17.639651) (xy 39.122748 -17.693598) (xy 39.107392 -17.745892)
			(xy 39.084751 -17.795469) (xy 39.055284 -17.841318) (xy 39.019591 -17.882507) (xy 38.9784 -17.918197)
			(xy 38.932549 -17.947661) (xy 38.891434 -17.966436) (xy 40.768016 -17.966436) (xy 40.768016 -17.280636)
			(xy 40.768444 -17.268553) (xy 40.775904 -17.245567) (xy 40.790106 -17.226014) (xy 40.809656 -17.21181)
			(xy 40.832641 -17.204346) (xy 40.844724 -17.203928) (xy 41.039288 -17.203928) (xy 41.050394 -17.204293)
			(xy 41.071686 -17.210628) (xy 41.081198 -17.216374) (xy 41.374822 -17.408906) (xy 41.384184 -17.414648)
			(xy 41.405207 -17.420975) (xy 41.427161 -17.421038) (xy 41.44822 -17.414831) (xy 41.457626 -17.40916)
			(xy 41.75379 -17.216374) (xy 41.763294 -17.210614) (xy 41.784592 -17.204296) (xy 41.7957 -17.203928)
			(xy 41.990264 -17.203928) (xy 42.002348 -17.204344) (xy 42.025336 -17.211806) (xy 42.04489 -17.22601)
			(xy 42.059094 -17.245564) (xy 42.066556 -17.268552) (xy 42.066972 -17.280636) (xy 42.066972 -17.639654)
			(xy 43.398638 -17.639654) (xy 43.398638 -17.585146) (xy 43.406395 -17.531193) (xy 43.421751 -17.478894)
			(xy 43.444395 -17.429312) (xy 43.473863 -17.383457) (xy 43.509558 -17.342262) (xy 43.550752 -17.306567)
			(xy 43.596606 -17.277097) (xy 43.646188 -17.254454) (xy 43.698487 -17.239096) (xy 43.75244 -17.231338)
			(xy 43.779694 -17.230852) (xy 44.643294 -17.230852) (xy 44.670544 -17.231395) (xy 44.72449 -17.23915)
			(xy 44.776783 -17.254504) (xy 44.826359 -17.277144) (xy 44.872208 -17.306609) (xy 44.913397 -17.342299)
			(xy 44.949088 -17.383487) (xy 44.978553 -17.429336) (xy 45.001194 -17.478911) (xy 45.016548 -17.531204)
			(xy 45.024305 -17.58515) (xy 45.024305 -17.63965) (xy 45.016548 -17.693596) (xy 45.001194 -17.745889)
			(xy 44.978553 -17.795464) (xy 44.949088 -17.841313) (xy 44.913397 -17.882501) (xy 44.872208 -17.918191)
			(xy 44.826359 -17.947656) (xy 44.785235 -17.966436) (xy 46.356016 -17.966436) (xy 46.356016 -17.280636)
			(xy 46.356444 -17.268553) (xy 46.363904 -17.245567) (xy 46.378106 -17.226014) (xy 46.397656 -17.21181)
			(xy 46.420641 -17.204346) (xy 46.432724 -17.203928) (xy 46.627288 -17.203928) (xy 46.638394 -17.204293)
			(xy 46.659686 -17.210628) (xy 46.669198 -17.216374) (xy 46.962822 -17.408906) (xy 46.972184 -17.414648)
			(xy 46.993207 -17.420975) (xy 47.015161 -17.421038) (xy 47.03622 -17.414831) (xy 47.045626 -17.40916)
			(xy 47.34179 -17.216374) (xy 47.351294 -17.210614) (xy 47.372592 -17.204296) (xy 47.3837 -17.203928)
			(xy 47.578264 -17.203928) (xy 47.590348 -17.204344) (xy 47.613336 -17.211806) (xy 47.63289 -17.22601)
			(xy 47.647094 -17.245564) (xy 47.654556 -17.268552) (xy 47.654972 -17.280636) (xy 47.654972 -17.639654)
			(xy 48.986638 -17.639654) (xy 48.986638 -17.585146) (xy 48.994395 -17.531193) (xy 49.009751 -17.478894)
			(xy 49.032395 -17.429312) (xy 49.061863 -17.383457) (xy 49.097558 -17.342262) (xy 49.138752 -17.306567)
			(xy 49.184606 -17.277097) (xy 49.234188 -17.254454) (xy 49.286487 -17.239096) (xy 49.34044 -17.231338)
			(xy 49.367694 -17.230852) (xy 50.231294 -17.230852) (xy 50.258544 -17.231395) (xy 50.31249 -17.23915)
			(xy 50.364783 -17.254504) (xy 50.414359 -17.277144) (xy 50.460208 -17.306609) (xy 50.501397 -17.342299)
			(xy 50.537088 -17.383487) (xy 50.566553 -17.429336) (xy 50.589194 -17.478911) (xy 50.604548 -17.531204)
			(xy 50.612305 -17.58515) (xy 50.612305 -17.63965) (xy 50.604548 -17.693596) (xy 50.589194 -17.745889)
			(xy 50.566553 -17.795464) (xy 50.537088 -17.841313) (xy 50.501397 -17.882501) (xy 50.460208 -17.918191)
			(xy 50.414359 -17.947656) (xy 50.373235 -17.966436) (xy 51.978052 -17.966436) (xy 51.978052 -17.280636)
			(xy 51.978594 -17.268567) (xy 51.986042 -17.245608) (xy 52.00022 -17.226074) (xy 52.01974 -17.211877)
			(xy 52.042692 -17.204406) (xy 52.05476 -17.203928) (xy 52.249324 -17.203928) (xy 52.260428 -17.204318)
			(xy 52.28172 -17.210635) (xy 52.291234 -17.216374) (xy 52.584858 -17.408906) (xy 52.594251 -17.414593)
			(xy 52.615259 -17.420932) (xy 52.637203 -17.421011) (xy 52.658256 -17.414822) (xy 52.667662 -17.40916)
			(xy 52.963826 -17.216374) (xy 52.973343 -17.210638) (xy 52.994631 -17.204305) (xy 53.005736 -17.203928)
			(xy 53.2003 -17.203928) (xy 53.212386 -17.204313) (xy 53.235375 -17.211785) (xy 53.254929 -17.225997)
			(xy 53.269132 -17.245557) (xy 53.276593 -17.268549) (xy 53.277008 -17.280636) (xy 53.277008 -17.639657)
			(xy 54.608615 -17.639657) (xy 54.608615 -17.585143) (xy 54.616374 -17.531184) (xy 54.631733 -17.478878)
			(xy 54.65438 -17.42929) (xy 54.683854 -17.383431) (xy 54.719554 -17.342233) (xy 54.760755 -17.306536)
			(xy 54.806617 -17.277065) (xy 54.856206 -17.254422) (xy 54.908513 -17.239067) (xy 54.962473 -17.231313)
			(xy 54.98973 -17.230852) (xy 55.85333 -17.230852) (xy 55.880577 -17.23142) (xy 55.934516 -17.239179)
			(xy 55.986801 -17.254535) (xy 56.03637 -17.277176) (xy 56.082211 -17.30664) (xy 56.123394 -17.342328)
			(xy 56.159078 -17.383513) (xy 56.188538 -17.429357) (xy 56.211175 -17.478927) (xy 56.226527 -17.531214)
			(xy 56.234282 -17.585153) (xy 56.234282 -17.639647) (xy 56.226527 -17.693586) (xy 56.211175 -17.745873)
			(xy 56.188538 -17.795443) (xy 56.159078 -17.841287) (xy 56.123394 -17.882472) (xy 56.082211 -17.91816)
			(xy 56.03637 -17.947624) (xy 55.995184 -17.966436) (xy 57.566052 -17.966436) (xy 57.566052 -17.280636)
			(xy 57.566594 -17.268567) (xy 57.574042 -17.245608) (xy 57.58822 -17.226074) (xy 57.60774 -17.211877)
			(xy 57.630692 -17.204406) (xy 57.64276 -17.203928) (xy 57.837324 -17.203928) (xy 57.848428 -17.204318)
			(xy 57.86972 -17.210635) (xy 57.879234 -17.216374) (xy 58.172858 -17.408906) (xy 58.182251 -17.414593)
			(xy 58.203259 -17.420932) (xy 58.225203 -17.421011) (xy 58.246256 -17.414822) (xy 58.255662 -17.40916)
			(xy 58.551826 -17.216374) (xy 58.561343 -17.210638) (xy 58.582631 -17.204305) (xy 58.593736 -17.203928)
			(xy 58.7883 -17.203928) (xy 58.800386 -17.204313) (xy 58.823375 -17.211785) (xy 58.842929 -17.225997)
			(xy 58.857132 -17.245557) (xy 58.864593 -17.268549) (xy 58.865008 -17.280636) (xy 58.865008 -17.966436)
			(xy 58.864567 -17.978512) (xy 58.857094 -18.001481) (xy 58.842892 -18.021017) (xy 58.823349 -18.035211)
			(xy 58.800377 -18.042672) (xy 58.7883 -18.043144) (xy 58.593736 -18.043144) (xy 58.582627 -18.042796)
			(xy 58.56133 -18.036461) (xy 58.551826 -18.030698) (xy 58.256932 -17.838166) (xy 58.247545 -17.832463)
			(xy 58.226507 -17.82619) (xy 58.204553 -17.82619) (xy 58.183515 -17.832463) (xy 58.174128 -17.838166)
			(xy 57.880504 -18.030698) (xy 57.871 -18.036458) (xy 57.849702 -18.042776) (xy 57.838594 -18.043144)
			(xy 57.64276 -18.043144) (xy 57.630687 -18.042671) (xy 57.607724 -18.035201) (xy 57.588191 -18.021006)
			(xy 57.573997 -18.001472) (xy 57.566529 -17.978509) (xy 57.566052 -17.966436) (xy 55.995184 -17.966436)
			(xy 55.986801 -17.970265) (xy 55.934516 -17.985621) (xy 55.880577 -17.99338) (xy 55.85333 -17.993868)
			(xy 54.98973 -17.993868) (xy 54.962473 -17.993487) (xy 54.908513 -17.985733) (xy 54.856206 -17.970378)
			(xy 54.806617 -17.947735) (xy 54.760755 -17.918264) (xy 54.719554 -17.882567) (xy 54.683854 -17.841369)
			(xy 54.65438 -17.79551) (xy 54.631733 -17.745922) (xy 54.616374 -17.693616) (xy 54.608615 -17.639657)
			(xy 53.277008 -17.639657) (xy 53.277008 -17.966436) (xy 53.276567 -17.978512) (xy 53.269094 -18.001481)
			(xy 53.254892 -18.021017) (xy 53.235349 -18.035211) (xy 53.212377 -18.042672) (xy 53.2003 -18.043144)
			(xy 53.005736 -18.043144) (xy 52.994627 -18.042796) (xy 52.97333 -18.036461) (xy 52.963826 -18.030698)
			(xy 52.668932 -17.838166) (xy 52.659545 -17.832463) (xy 52.638507 -17.82619) (xy 52.616553 -17.82619)
			(xy 52.595515 -17.832463) (xy 52.586128 -17.838166) (xy 52.292504 -18.030698) (xy 52.283 -18.036458)
			(xy 52.261702 -18.042776) (xy 52.250594 -18.043144) (xy 52.05476 -18.043144) (xy 52.042687 -18.042671)
			(xy 52.019724 -18.035201) (xy 52.000191 -18.021006) (xy 51.985997 -18.001472) (xy 51.978529 -17.978509)
			(xy 51.978052 -17.966436) (xy 50.373235 -17.966436) (xy 50.364783 -17.970296) (xy 50.31249 -17.98565)
			(xy 50.258544 -17.993405) (xy 50.231294 -17.993868) (xy 49.367694 -17.993868) (xy 49.34044 -17.993462)
			(xy 49.286487 -17.985704) (xy 49.234188 -17.970346) (xy 49.184606 -17.947703) (xy 49.138752 -17.918233)
			(xy 49.097558 -17.882538) (xy 49.061863 -17.841343) (xy 49.032395 -17.795488) (xy 49.009751 -17.745906)
			(xy 48.994395 -17.693607) (xy 48.986638 -17.639654) (xy 47.654972 -17.639654) (xy 47.654972 -17.966436)
			(xy 47.654566 -17.978516) (xy 47.647089 -18.001491) (xy 47.632879 -18.02103) (xy 47.613326 -18.035222)
			(xy 47.590344 -18.042677) (xy 47.578264 -18.043144) (xy 47.3837 -18.043144) (xy 47.372593 -18.042769)
			(xy 47.351297 -18.036453) (xy 47.34179 -18.030698) (xy 47.046896 -17.838166) (xy 47.037509 -17.832463)
			(xy 47.016471 -17.82619) (xy 46.994517 -17.82619) (xy 46.973479 -17.832463) (xy 46.964092 -17.838166)
			(xy 46.670468 -18.030698) (xy 46.660951 -18.036434) (xy 46.639663 -18.042768) (xy 46.628558 -18.043144)
			(xy 46.432724 -18.043144) (xy 46.420654 -18.042616) (xy 46.397694 -18.035164) (xy 46.37816 -18.020983)
			(xy 46.363963 -18.00146) (xy 46.356493 -17.978505) (xy 46.356016 -17.966436) (xy 44.785235 -17.966436)
			(xy 44.776783 -17.970296) (xy 44.72449 -17.98565) (xy 44.670544 -17.993405) (xy 44.643294 -17.993868)
			(xy 43.779694 -17.993868) (xy 43.75244 -17.993462) (xy 43.698487 -17.985704) (xy 43.646188 -17.970346)
			(xy 43.596606 -17.947703) (xy 43.550752 -17.918233) (xy 43.509558 -17.882538) (xy 43.473863 -17.841343)
			(xy 43.444395 -17.795488) (xy 43.421751 -17.745906) (xy 43.406395 -17.693607) (xy 43.398638 -17.639654)
			(xy 42.066972 -17.639654) (xy 42.066972 -17.966436) (xy 42.066566 -17.978516) (xy 42.059089 -18.001491)
			(xy 42.044879 -18.02103) (xy 42.025326 -18.035222) (xy 42.002344 -18.042677) (xy 41.990264 -18.043144)
			(xy 41.7957 -18.043144) (xy 41.784593 -18.042769) (xy 41.763297 -18.036453) (xy 41.75379 -18.030698)
			(xy 41.458896 -17.838166) (xy 41.449509 -17.832463) (xy 41.428471 -17.82619) (xy 41.406517 -17.82619)
			(xy 41.385479 -17.832463) (xy 41.376092 -17.838166) (xy 41.082468 -18.030698) (xy 41.072951 -18.036434)
			(xy 41.051663 -18.042768) (xy 41.040558 -18.043144) (xy 40.844724 -18.043144) (xy 40.832654 -18.042616)
			(xy 40.809694 -18.035164) (xy 40.79016 -18.020983) (xy 40.775963 -18.00146) (xy 40.768493 -17.978505)
			(xy 40.768016 -17.966436) (xy 38.891434 -17.966436) (xy 38.882972 -17.9703) (xy 38.830677 -17.985653)
			(xy 38.776729 -17.993406) (xy 38.749478 -17.993868) (xy 37.885878 -17.993868) (xy 37.858625 -17.993461)
			(xy 37.804674 -17.985701) (xy 37.752376 -17.970342) (xy 37.702797 -17.947697) (xy 37.656944 -17.918227)
			(xy 37.615752 -17.882532) (xy 37.580059 -17.841338) (xy 37.550592 -17.795484) (xy 37.52795 -17.745903)
			(xy 37.512595 -17.693605) (xy 37.504838 -17.639653) (xy 36.173156 -17.639653) (xy 36.173156 -17.966436)
			(xy 36.172667 -17.978508) (xy 36.165201 -18.001468) (xy 36.151009 -18.021) (xy 36.131479 -18.035195)
			(xy 36.10852 -18.042666) (xy 36.096448 -18.043144) (xy 35.901884 -18.043144) (xy 35.890776 -18.042776)
			(xy 35.86948 -18.036455) (xy 35.859974 -18.030698) (xy 35.56508 -17.838166) (xy 35.555693 -17.832463)
			(xy 35.534655 -17.82619) (xy 35.512701 -17.82619) (xy 35.491663 -17.832463) (xy 35.482276 -17.838166)
			(xy 35.188652 -18.030698) (xy 35.179138 -18.03644) (xy 35.157848 -18.04277) (xy 35.146742 -18.043144)
			(xy 34.950908 -18.043144) (xy 34.938837 -18.04263) (xy 34.915877 -18.035174) (xy 34.896343 -18.020989)
			(xy 34.882147 -18.001463) (xy 34.874677 -17.978506) (xy 34.8742 -17.966436) (xy 33.303434 -17.966436)
			(xy 33.294972 -17.9703) (xy 33.242677 -17.985653) (xy 33.188729 -17.993406) (xy 33.161478 -17.993868)
			(xy 32.297878 -17.993868) (xy 32.270625 -17.993461) (xy 32.216674 -17.985701) (xy 32.164376 -17.970342)
			(xy 32.114797 -17.947697) (xy 32.068944 -17.918227) (xy 32.027752 -17.882532) (xy 31.992059 -17.841338)
			(xy 31.962592 -17.795484) (xy 31.93995 -17.745903) (xy 31.924595 -17.693605) (xy 31.916838 -17.639653)
			(xy 30.585156 -17.639653) (xy 30.585156 -17.966436) (xy 30.584667 -17.978508) (xy 30.577201 -18.001468)
			(xy 30.563009 -18.021) (xy 30.543479 -18.035195) (xy 30.52052 -18.042666) (xy 30.508448 -18.043144)
			(xy 30.313884 -18.043144) (xy 30.302776 -18.042776) (xy 30.28148 -18.036455) (xy 30.271974 -18.030698)
			(xy 29.97708 -17.838166) (xy 29.967693 -17.832463) (xy 29.946655 -17.82619) (xy 29.924701 -17.82619)
			(xy 29.903663 -17.832463) (xy 29.894276 -17.838166) (xy 29.600652 -18.030698) (xy 29.591138 -18.03644)
			(xy 29.569848 -18.04277) (xy 29.558742 -18.043144) (xy 29.362908 -18.043144) (xy 29.350837 -18.04263)
			(xy 29.327877 -18.035174) (xy 29.308343 -18.020989) (xy 29.294147 -18.001463) (xy 29.286677 -17.978506)
			(xy 29.2862 -17.966436) (xy 27.715434 -17.966436) (xy 27.706972 -17.9703) (xy 27.654677 -17.985653)
			(xy 27.600729 -17.993406) (xy 27.573478 -17.993868) (xy 26.709878 -17.993868) (xy 26.682625 -17.993461)
			(xy 26.628674 -17.985701) (xy 26.576376 -17.970342) (xy 26.526797 -17.947697) (xy 26.480944 -17.918227)
			(xy 26.439752 -17.882532) (xy 26.404059 -17.841338) (xy 26.374592 -17.795484) (xy 26.35195 -17.745903)
			(xy 26.336595 -17.693605) (xy 26.328838 -17.639653) (xy 24.997156 -17.639653) (xy 24.997156 -17.966436)
			(xy 24.996667 -17.978508) (xy 24.989201 -18.001468) (xy 24.975009 -18.021) (xy 24.955479 -18.035195)
			(xy 24.93252 -18.042666) (xy 24.920448 -18.043144) (xy 24.725884 -18.043144) (xy 24.714776 -18.042776)
			(xy 24.69348 -18.036455) (xy 24.683974 -18.030698) (xy 24.38908 -17.838166) (xy 24.379693 -17.832463)
			(xy 24.358655 -17.82619) (xy 24.336701 -17.82619) (xy 24.315663 -17.832463) (xy 24.306276 -17.838166)
			(xy 24.012652 -18.030698) (xy 24.003138 -18.03644) (xy 23.981848 -18.04277) (xy 23.970742 -18.043144)
			(xy 23.774908 -18.043144) (xy 23.762837 -18.04263) (xy 23.739877 -18.035174) (xy 23.720343 -18.020989)
			(xy 23.706147 -18.001463) (xy 23.698677 -17.978506) (xy 23.6982 -17.966436) (xy 22.127434 -17.966436)
			(xy 22.118972 -17.9703) (xy 22.066677 -17.985653) (xy 22.012729 -17.993406) (xy 21.985478 -17.993868)
			(xy 21.121878 -17.993868) (xy 21.094627 -17.993382) (xy 21.040679 -17.985625) (xy 20.988385 -17.97027)
			(xy 20.938808 -17.947629) (xy 20.892958 -17.918162) (xy 20.851768 -17.882471) (xy 20.816076 -17.841281)
			(xy 20.78661 -17.79543) (xy 20.763969 -17.745853) (xy 20.748614 -17.693559) (xy 20.740858 -17.639611)
			(xy 19.409156 -17.639611) (xy 19.409156 -17.966436) (xy 19.408667 -17.978508) (xy 19.401201 -18.001468)
			(xy 19.387009 -18.021) (xy 19.367479 -18.035195) (xy 19.34452 -18.042666) (xy 19.332448 -18.043144)
			(xy 19.137884 -18.043144) (xy 19.126776 -18.042776) (xy 19.10548 -18.036455) (xy 19.095974 -18.030698)
			(xy 18.80108 -17.838166) (xy 18.791693 -17.832463) (xy 18.770655 -17.82619) (xy 18.748701 -17.82619)
			(xy 18.727663 -17.832463) (xy 18.718276 -17.838166) (xy 18.424652 -18.030698) (xy 18.415138 -18.03644)
			(xy 18.393848 -18.04277) (xy 18.382742 -18.043144) (xy 18.186908 -18.043144) (xy 18.174837 -18.04263)
			(xy 18.151877 -18.035174) (xy 18.132343 -18.020989) (xy 18.118147 -18.001463) (xy 18.110677 -17.978506)
			(xy 18.1102 -17.966436) (xy 16.539424 -17.966436) (xy 16.53098 -17.970292) (xy 16.478682 -17.985648)
			(xy 16.424731 -17.993405) (xy 16.397478 -17.993868) (xy 15.533878 -17.993868) (xy 15.506627 -17.993382)
			(xy 15.452679 -17.985625) (xy 15.400385 -17.97027) (xy 15.350808 -17.947629) (xy 15.304958 -17.918162)
			(xy 15.263768 -17.882471) (xy 15.228076 -17.841281) (xy 15.19861 -17.79543) (xy 15.175969 -17.745853)
			(xy 15.160614 -17.693559) (xy 15.152858 -17.639611) (xy 0.509016 -17.639611) (xy 0.509016 -18.171947)
			(xy 131.633522 -18.171947) (xy 131.633522 -18.117453) (xy 131.641277 -18.063515) (xy 131.656629 -18.011229)
			(xy 131.679265 -17.961659) (xy 131.708725 -17.915816) (xy 131.744409 -17.874631) (xy 131.78559 -17.838944)
			(xy 131.831431 -17.80948) (xy 131.880999 -17.78684) (xy 131.933283 -17.771484) (xy 131.987221 -17.763724)
			(xy 132.014468 -17.763236) (xy 132.878068 -17.763236) (xy 132.905326 -17.763609) (xy 132.959286 -17.771363)
			(xy 133.011594 -17.786718) (xy 133.061184 -17.809361) (xy 133.107046 -17.838832) (xy 133.148248 -17.87453)
			(xy 133.183949 -17.915728) (xy 133.213423 -17.961588) (xy 133.236071 -18.011176) (xy 133.25143 -18.063483)
			(xy 133.259189 -18.117443) (xy 133.259189 -18.17195) (xy 137.033499 -18.17195) (xy 137.033499 -18.11745)
			(xy 137.041256 -18.063505) (xy 137.05661 -18.011212) (xy 137.079251 -17.961637) (xy 137.108716 -17.915789)
			(xy 137.144406 -17.874601) (xy 137.185595 -17.838911) (xy 137.231444 -17.809447) (xy 137.28102 -17.786807)
			(xy 137.333312 -17.771454) (xy 137.387258 -17.763699) (xy 137.414508 -17.763236) (xy 138.278108 -17.763236)
			(xy 138.305362 -17.763634) (xy 138.359315 -17.771393) (xy 138.411615 -17.78675) (xy 138.461197 -17.809395)
			(xy 138.507052 -17.838864) (xy 138.548246 -17.87456) (xy 138.58394 -17.915755) (xy 138.613409 -17.96161)
			(xy 138.636052 -18.011193) (xy 138.651409 -18.063493) (xy 138.659166 -18.117446) (xy 138.659166 -18.171946)
			(xy 140.633522 -18.171946) (xy 140.633522 -18.117454) (xy 140.641276 -18.063517) (xy 140.656627 -18.011232)
			(xy 140.679262 -17.961664) (xy 140.70872 -17.915822) (xy 140.744402 -17.874638) (xy 140.785582 -17.83895)
			(xy 140.83142 -17.809486) (xy 140.880986 -17.786845) (xy 140.933268 -17.771487) (xy 140.987204 -17.763726)
			(xy 141.01445 -17.763236) (xy 141.87805 -17.763236) (xy 141.905308 -17.763608) (xy 141.959271 -17.77136)
			(xy 142.011581 -17.786713) (xy 142.061173 -17.809355) (xy 142.107038 -17.838825) (xy 142.148241 -17.874523)
			(xy 142.183945 -17.915722) (xy 142.213421 -17.961583) (xy 142.236069 -18.011172) (xy 142.25143 -18.06348)
			(xy 142.259189 -18.117442) (xy 142.259189 -18.171951) (xy 185.748399 -18.171951) (xy 185.748399 -18.117449)
			(xy 185.756156 -18.063503) (xy 185.771511 -18.011209) (xy 185.794153 -17.961633) (xy 185.823619 -17.915784)
			(xy 185.859311 -17.874596) (xy 185.900502 -17.838906) (xy 185.946353 -17.809442) (xy 185.99593 -17.786804)
			(xy 186.048224 -17.771451) (xy 186.102171 -17.763698) (xy 186.129422 -17.763236) (xy 186.993022 -17.763236)
			(xy 187.020275 -17.763635) (xy 187.074227 -17.771395) (xy 187.126525 -17.786754) (xy 187.176105 -17.809399)
			(xy 187.201242 -17.825555) (xy 218.803143 -17.825555) (xy 218.803143 -17.771045) (xy 218.810901 -17.717091)
			(xy 218.826258 -17.66479) (xy 218.848903 -17.615207) (xy 218.878374 -17.569351) (xy 218.914071 -17.528157)
			(xy 218.955267 -17.492462) (xy 219.001124 -17.462993) (xy 219.050709 -17.440351) (xy 219.10301 -17.424996)
			(xy 219.156965 -17.417242) (xy 219.18422 -17.41678) (xy 220.04782 -17.41678) (xy 220.075069 -17.417292)
			(xy 220.129013 -17.42505) (xy 220.181304 -17.440407) (xy 220.230877 -17.463048) (xy 220.276723 -17.492514)
			(xy 220.31791 -17.528204) (xy 220.353598 -17.569393) (xy 220.383062 -17.615241) (xy 220.4057 -17.664815)
			(xy 220.421054 -17.717106) (xy 220.42881 -17.771051) (xy 220.42881 -17.825549) (xy 220.421054 -17.879494)
			(xy 220.4057 -17.931785) (xy 220.383062 -17.981359) (xy 220.353598 -18.027207) (xy 220.31791 -18.068396)
			(xy 220.276723 -18.104086) (xy 220.230877 -18.133552) (xy 220.181304 -18.156193) (xy 220.129013 -18.17155)
			(xy 220.075069 -18.179308) (xy 220.04782 -18.179796) (xy 219.18422 -18.179796) (xy 219.156965 -18.179358)
			(xy 219.10301 -18.171604) (xy 219.050709 -18.156249) (xy 219.001124 -18.133607) (xy 218.955267 -18.104138)
			(xy 218.914071 -18.068443) (xy 218.878374 -18.027249) (xy 218.848903 -17.981393) (xy 218.826258 -17.93181)
			(xy 218.810901 -17.879509) (xy 218.803143 -17.825555) (xy 187.201242 -17.825555) (xy 187.221958 -17.838869)
			(xy 187.263151 -17.874565) (xy 187.298844 -17.915759) (xy 187.328311 -17.961614) (xy 187.350954 -18.011196)
			(xy 187.366309 -18.063495) (xy 187.374066 -18.117447) (xy 187.374066 -18.171953) (xy 187.366309 -18.225905)
			(xy 187.350954 -18.278204) (xy 187.328311 -18.327786) (xy 187.298844 -18.373641) (xy 187.263151 -18.414835)
			(xy 187.221958 -18.450531) (xy 187.176105 -18.480001) (xy 187.126525 -18.502646) (xy 187.074227 -18.518005)
			(xy 187.020275 -18.525765) (xy 186.993022 -18.526252) (xy 186.129422 -18.526252) (xy 186.102171 -18.525702)
			(xy 186.048224 -18.517949) (xy 185.99593 -18.502596) (xy 185.946353 -18.479958) (xy 185.900502 -18.450494)
			(xy 185.859311 -18.414804) (xy 185.823619 -18.373616) (xy 185.794153 -18.327767) (xy 185.771511 -18.278191)
			(xy 185.756156 -18.225897) (xy 185.748399 -18.171951) (xy 142.259189 -18.171951) (xy 142.259189 -18.171958)
			(xy 142.25143 -18.22592) (xy 142.236069 -18.278228) (xy 142.213421 -18.327817) (xy 142.183945 -18.373678)
			(xy 142.148241 -18.414877) (xy 142.107038 -18.450575) (xy 142.061173 -18.480045) (xy 142.011581 -18.502687)
			(xy 141.959271 -18.51804) (xy 141.905308 -18.525792) (xy 141.87805 -18.526252) (xy 141.01445 -18.526252)
			(xy 140.987204 -18.525674) (xy 140.933268 -18.517913) (xy 140.880986 -18.502555) (xy 140.83142 -18.479914)
			(xy 140.785582 -18.45045) (xy 140.744402 -18.414762) (xy 140.70872 -18.373578) (xy 140.679262 -18.327736)
			(xy 140.656627 -18.278168) (xy 140.641276 -18.225883) (xy 140.633522 -18.171946) (xy 138.659166 -18.171946)
			(xy 138.659166 -18.171954) (xy 138.651409 -18.225907) (xy 138.636052 -18.278207) (xy 138.613409 -18.32779)
			(xy 138.58394 -18.373645) (xy 138.548246 -18.41484) (xy 138.507052 -18.450536) (xy 138.461197 -18.480005)
			(xy 138.411615 -18.50265) (xy 138.359315 -18.518007) (xy 138.305362 -18.525766) (xy 138.278108 -18.526252)
			(xy 137.414508 -18.526252) (xy 137.387258 -18.525701) (xy 137.333312 -18.517946) (xy 137.28102 -18.502593)
			(xy 137.231444 -18.479953) (xy 137.185595 -18.450489) (xy 137.144406 -18.414799) (xy 137.108716 -18.373611)
			(xy 137.079251 -18.327763) (xy 137.05661 -18.278188) (xy 137.041256 -18.225895) (xy 137.033499 -18.17195)
			(xy 133.259189 -18.17195) (xy 133.259189 -18.171957) (xy 133.25143 -18.225917) (xy 133.236071 -18.278224)
			(xy 133.213423 -18.327812) (xy 133.183949 -18.373672) (xy 133.148248 -18.41487) (xy 133.107046 -18.450568)
			(xy 133.061184 -18.480039) (xy 133.011594 -18.502682) (xy 132.959286 -18.518037) (xy 132.905326 -18.525791)
			(xy 132.878068 -18.526252) (xy 132.014468 -18.526252) (xy 131.987221 -18.525676) (xy 131.933283 -18.517916)
			(xy 131.880999 -18.50256) (xy 131.831431 -18.47992) (xy 131.78559 -18.450456) (xy 131.744409 -18.414769)
			(xy 131.708725 -18.373584) (xy 131.679265 -18.327741) (xy 131.656629 -18.278171) (xy 131.641277 -18.225885)
			(xy 131.633522 -18.171947) (xy 0.509016 -18.171947) (xy 0.509016 -19.163611) (xy 17.946858 -19.163611)
			(xy 17.946858 -19.109109) (xy 17.954614 -19.055161) (xy 17.969969 -19.002867) (xy 17.99261 -18.95329)
			(xy 18.022076 -18.907439) (xy 18.057768 -18.866249) (xy 18.098958 -18.830558) (xy 18.144808 -18.801091)
			(xy 18.194385 -18.77845) (xy 18.246679 -18.763095) (xy 18.300627 -18.755338) (xy 18.327878 -18.754852)
			(xy 19.191478 -18.754852) (xy 19.218731 -18.755315) (xy 19.272682 -18.763072) (xy 19.32498 -18.778428)
			(xy 19.374561 -18.80107) (xy 19.420414 -18.830538) (xy 19.461607 -18.866232) (xy 19.497301 -18.907424)
			(xy 19.526769 -18.953278) (xy 19.549412 -19.002858) (xy 19.564768 -19.055156) (xy 19.572525 -19.109107)
			(xy 19.572525 -19.163613) (xy 19.572519 -19.163653) (xy 23.534838 -19.163653) (xy 23.534838 -19.109147)
			(xy 23.542595 -19.055195) (xy 23.55795 -19.002897) (xy 23.580592 -18.953316) (xy 23.610059 -18.907462)
			(xy 23.645752 -18.866268) (xy 23.686944 -18.830573) (xy 23.732797 -18.801103) (xy 23.782376 -18.778458)
			(xy 23.834674 -18.763099) (xy 23.888625 -18.755339) (xy 23.915878 -18.754852) (xy 24.779478 -18.754852)
			(xy 24.806729 -18.755394) (xy 24.860677 -18.763147) (xy 24.912972 -18.7785) (xy 24.962549 -18.801139)
			(xy 25.0084 -18.830603) (xy 25.049591 -18.866293) (xy 25.085284 -18.907482) (xy 25.114751 -18.953331)
			(xy 25.137392 -19.002908) (xy 25.152748 -19.055202) (xy 25.160505 -19.109149) (xy 25.160505 -19.163651)
			(xy 25.160505 -19.163653) (xy 29.122838 -19.163653) (xy 29.122838 -19.109147) (xy 29.130595 -19.055195)
			(xy 29.14595 -19.002897) (xy 29.168592 -18.953316) (xy 29.198059 -18.907462) (xy 29.233752 -18.866268)
			(xy 29.274944 -18.830573) (xy 29.320797 -18.801103) (xy 29.370376 -18.778458) (xy 29.422674 -18.763099)
			(xy 29.476625 -18.755339) (xy 29.503878 -18.754852) (xy 30.367478 -18.754852) (xy 30.394729 -18.755394)
			(xy 30.448677 -18.763147) (xy 30.500972 -18.7785) (xy 30.550549 -18.801139) (xy 30.5964 -18.830603)
			(xy 30.637591 -18.866293) (xy 30.673284 -18.907482) (xy 30.702751 -18.953331) (xy 30.725392 -19.002908)
			(xy 30.740748 -19.055202) (xy 30.748505 -19.109149) (xy 30.748505 -19.163651) (xy 30.748505 -19.163653)
			(xy 34.710838 -19.163653) (xy 34.710838 -19.109147) (xy 34.718595 -19.055195) (xy 34.73395 -19.002897)
			(xy 34.756592 -18.953316) (xy 34.786059 -18.907462) (xy 34.821752 -18.866268) (xy 34.862944 -18.830573)
			(xy 34.908797 -18.801103) (xy 34.958376 -18.778458) (xy 35.010674 -18.763099) (xy 35.064625 -18.755339)
			(xy 35.091878 -18.754852) (xy 35.955478 -18.754852) (xy 35.982729 -18.755394) (xy 36.036677 -18.763147)
			(xy 36.088972 -18.7785) (xy 36.138549 -18.801139) (xy 36.1844 -18.830603) (xy 36.225591 -18.866293)
			(xy 36.261284 -18.907482) (xy 36.290751 -18.953331) (xy 36.313392 -19.002908) (xy 36.328748 -19.055202)
			(xy 36.336505 -19.109149) (xy 36.336505 -19.163651) (xy 36.336505 -19.163654) (xy 40.604638 -19.163654)
			(xy 40.604638 -19.109146) (xy 40.612395 -19.055193) (xy 40.627751 -19.002894) (xy 40.650395 -18.953312)
			(xy 40.679863 -18.907457) (xy 40.715558 -18.866262) (xy 40.756752 -18.830567) (xy 40.802606 -18.801097)
			(xy 40.852188 -18.778454) (xy 40.904487 -18.763096) (xy 40.95844 -18.755338) (xy 40.985694 -18.754852)
			(xy 41.849294 -18.754852) (xy 41.876544 -18.755395) (xy 41.93049 -18.76315) (xy 41.982783 -18.778504)
			(xy 42.032359 -18.801144) (xy 42.078208 -18.830609) (xy 42.119397 -18.866299) (xy 42.155088 -18.907487)
			(xy 42.184553 -18.953336) (xy 42.207194 -19.002911) (xy 42.222548 -19.055204) (xy 42.230305 -19.10915)
			(xy 42.230305 -19.16365) (xy 42.230304 -19.163654) (xy 46.192638 -19.163654) (xy 46.192638 -19.109146)
			(xy 46.200395 -19.055193) (xy 46.215751 -19.002894) (xy 46.238395 -18.953312) (xy 46.267863 -18.907457)
			(xy 46.303558 -18.866262) (xy 46.344752 -18.830567) (xy 46.390606 -18.801097) (xy 46.440188 -18.778454)
			(xy 46.492487 -18.763096) (xy 46.54644 -18.755338) (xy 46.573694 -18.754852) (xy 47.437294 -18.754852)
			(xy 47.464544 -18.755395) (xy 47.51849 -18.76315) (xy 47.570783 -18.778504) (xy 47.620359 -18.801144)
			(xy 47.666208 -18.830609) (xy 47.707397 -18.866299) (xy 47.743088 -18.907487) (xy 47.772553 -18.953336)
			(xy 47.795194 -19.002911) (xy 47.810548 -19.055204) (xy 47.818305 -19.10915) (xy 47.818305 -19.16365)
			(xy 47.818304 -19.163657) (xy 51.814615 -19.163657) (xy 51.814615 -19.109143) (xy 51.822374 -19.055184)
			(xy 51.837733 -19.002878) (xy 51.86038 -18.95329) (xy 51.889854 -18.907431) (xy 51.925554 -18.866233)
			(xy 51.966755 -18.830536) (xy 52.012617 -18.801065) (xy 52.062206 -18.778422) (xy 52.114513 -18.763067)
			(xy 52.168473 -18.755313) (xy 52.19573 -18.754852) (xy 53.05933 -18.754852) (xy 53.086577 -18.75542)
			(xy 53.140516 -18.763179) (xy 53.192801 -18.778535) (xy 53.24237 -18.801176) (xy 53.288211 -18.83064)
			(xy 53.329394 -18.866328) (xy 53.365078 -18.907513) (xy 53.394538 -18.953357) (xy 53.417175 -19.002927)
			(xy 53.432527 -19.055214) (xy 53.440282 -19.109153) (xy 53.440282 -19.163647) (xy 53.440281 -19.163657)
			(xy 57.402615 -19.163657) (xy 57.402615 -19.109143) (xy 57.410374 -19.055184) (xy 57.425733 -19.002878)
			(xy 57.44838 -18.95329) (xy 57.477854 -18.907431) (xy 57.513554 -18.866233) (xy 57.554755 -18.830536)
			(xy 57.600617 -18.801065) (xy 57.650206 -18.778422) (xy 57.702513 -18.763067) (xy 57.756473 -18.755313)
			(xy 57.78373 -18.754852) (xy 58.64733 -18.754852) (xy 58.674577 -18.75542) (xy 58.728516 -18.763179)
			(xy 58.780801 -18.778535) (xy 58.83037 -18.801176) (xy 58.876211 -18.83064) (xy 58.917394 -18.866328)
			(xy 58.953078 -18.907513) (xy 58.982538 -18.953357) (xy 59.005175 -19.002927) (xy 59.020527 -19.055214)
			(xy 59.028282 -19.109153) (xy 59.028282 -19.163647) (xy 59.020527 -19.217586) (xy 59.005175 -19.269873)
			(xy 58.982538 -19.319443) (xy 58.953078 -19.365287) (xy 58.917394 -19.406472) (xy 58.876211 -19.44216)
			(xy 58.83037 -19.471624) (xy 58.780801 -19.494265) (xy 58.728516 -19.509621) (xy 58.674577 -19.51738)
			(xy 58.64733 -19.517868) (xy 57.78373 -19.517868) (xy 57.756473 -19.517487) (xy 57.702513 -19.509733)
			(xy 57.650206 -19.494378) (xy 57.600617 -19.471735) (xy 57.554755 -19.442264) (xy 57.513554 -19.406567)
			(xy 57.477854 -19.365369) (xy 57.44838 -19.31951) (xy 57.425733 -19.269922) (xy 57.410374 -19.217616)
			(xy 57.402615 -19.163657) (xy 53.440281 -19.163657) (xy 53.432527 -19.217586) (xy 53.417175 -19.269873)
			(xy 53.394538 -19.319443) (xy 53.365078 -19.365287) (xy 53.329394 -19.406472) (xy 53.288211 -19.44216)
			(xy 53.24237 -19.471624) (xy 53.192801 -19.494265) (xy 53.140516 -19.509621) (xy 53.086577 -19.51738)
			(xy 53.05933 -19.517868) (xy 52.19573 -19.517868) (xy 52.168473 -19.517487) (xy 52.114513 -19.509733)
			(xy 52.062206 -19.494378) (xy 52.012617 -19.471735) (xy 51.966755 -19.442264) (xy 51.925554 -19.406567)
			(xy 51.889854 -19.365369) (xy 51.86038 -19.31951) (xy 51.837733 -19.269922) (xy 51.822374 -19.217616)
			(xy 51.814615 -19.163657) (xy 47.818304 -19.163657) (xy 47.810548 -19.217596) (xy 47.795194 -19.269889)
			(xy 47.772553 -19.319464) (xy 47.743088 -19.365313) (xy 47.707397 -19.406501) (xy 47.666208 -19.442191)
			(xy 47.620359 -19.471656) (xy 47.570783 -19.494296) (xy 47.51849 -19.50965) (xy 47.464544 -19.517405)
			(xy 47.437294 -19.517868) (xy 46.573694 -19.517868) (xy 46.54644 -19.517462) (xy 46.492487 -19.509704)
			(xy 46.440188 -19.494346) (xy 46.390606 -19.471703) (xy 46.344752 -19.442233) (xy 46.303558 -19.406538)
			(xy 46.267863 -19.365343) (xy 46.238395 -19.319488) (xy 46.215751 -19.269906) (xy 46.200395 -19.217607)
			(xy 46.192638 -19.163654) (xy 42.230304 -19.163654) (xy 42.222548 -19.217596) (xy 42.207194 -19.269889)
			(xy 42.184553 -19.319464) (xy 42.155088 -19.365313) (xy 42.119397 -19.406501) (xy 42.078208 -19.442191)
			(xy 42.032359 -19.471656) (xy 41.982783 -19.494296) (xy 41.93049 -19.50965) (xy 41.876544 -19.517405)
			(xy 41.849294 -19.517868) (xy 40.985694 -19.517868) (xy 40.95844 -19.517462) (xy 40.904487 -19.509704)
			(xy 40.852188 -19.494346) (xy 40.802606 -19.471703) (xy 40.756752 -19.442233) (xy 40.715558 -19.406538)
			(xy 40.679863 -19.365343) (xy 40.650395 -19.319488) (xy 40.627751 -19.269906) (xy 40.612395 -19.217607)
			(xy 40.604638 -19.163654) (xy 36.336505 -19.163654) (xy 36.328748 -19.217598) (xy 36.313392 -19.269892)
			(xy 36.290751 -19.319469) (xy 36.261284 -19.365318) (xy 36.225591 -19.406507) (xy 36.1844 -19.442197)
			(xy 36.138549 -19.471661) (xy 36.088972 -19.4943) (xy 36.036677 -19.509653) (xy 35.982729 -19.517406)
			(xy 35.955478 -19.517868) (xy 35.091878 -19.517868) (xy 35.064625 -19.517461) (xy 35.010674 -19.509701)
			(xy 34.958376 -19.494342) (xy 34.908797 -19.471697) (xy 34.862944 -19.442227) (xy 34.821752 -19.406532)
			(xy 34.786059 -19.365338) (xy 34.756592 -19.319484) (xy 34.73395 -19.269903) (xy 34.718595 -19.217605)
			(xy 34.710838 -19.163653) (xy 30.748505 -19.163653) (xy 30.740748 -19.217598) (xy 30.725392 -19.269892)
			(xy 30.702751 -19.319469) (xy 30.673284 -19.365318) (xy 30.637591 -19.406507) (xy 30.5964 -19.442197)
			(xy 30.550549 -19.471661) (xy 30.500972 -19.4943) (xy 30.448677 -19.509653) (xy 30.394729 -19.517406)
			(xy 30.367478 -19.517868) (xy 29.503878 -19.517868) (xy 29.476625 -19.517461) (xy 29.422674 -19.509701)
			(xy 29.370376 -19.494342) (xy 29.320797 -19.471697) (xy 29.274944 -19.442227) (xy 29.233752 -19.406532)
			(xy 29.198059 -19.365338) (xy 29.168592 -19.319484) (xy 29.14595 -19.269903) (xy 29.130595 -19.217605)
			(xy 29.122838 -19.163653) (xy 25.160505 -19.163653) (xy 25.152748 -19.217598) (xy 25.137392 -19.269892)
			(xy 25.114751 -19.319469) (xy 25.085284 -19.365318) (xy 25.049591 -19.406507) (xy 25.0084 -19.442197)
			(xy 24.962549 -19.471661) (xy 24.912972 -19.4943) (xy 24.860677 -19.509653) (xy 24.806729 -19.517406)
			(xy 24.779478 -19.517868) (xy 23.915878 -19.517868) (xy 23.888625 -19.517461) (xy 23.834674 -19.509701)
			(xy 23.782376 -19.494342) (xy 23.732797 -19.471697) (xy 23.686944 -19.442227) (xy 23.645752 -19.406532)
			(xy 23.610059 -19.365338) (xy 23.580592 -19.319484) (xy 23.55795 -19.269903) (xy 23.542595 -19.217605)
			(xy 23.534838 -19.163653) (xy 19.572519 -19.163653) (xy 19.564768 -19.217564) (xy 19.549412 -19.269862)
			(xy 19.526769 -19.319442) (xy 19.497301 -19.365296) (xy 19.461607 -19.406488) (xy 19.420414 -19.442182)
			(xy 19.374561 -19.47165) (xy 19.32498 -19.494292) (xy 19.272682 -19.509648) (xy 19.218731 -19.517405)
			(xy 19.191478 -19.517868) (xy 18.327878 -19.517868) (xy 18.300627 -19.517382) (xy 18.246679 -19.509625)
			(xy 18.194385 -19.49427) (xy 18.144808 -19.471629) (xy 18.098958 -19.442162) (xy 18.057768 -19.406471)
			(xy 18.022076 -19.365281) (xy 17.99261 -19.31943) (xy 17.969969 -19.269853) (xy 17.954614 -19.217559)
			(xy 17.946858 -19.163611) (xy 0.509016 -19.163611) (xy 0.509016 -19.819874) (xy 15.63192 -19.819874)
			(xy 15.635993 -19.764215) (xy 15.648128 -19.709742) (xy 15.668064 -19.657616) (xy 15.695378 -19.608948)
			(xy 15.729486 -19.564776) (xy 15.769663 -19.526041) (xy 15.815051 -19.493569) (xy 15.864683 -19.468051)
			(xy 15.917503 -19.450032) (xy 15.972382 -19.439895) (xy 16.028153 -19.437857) (xy 16.083627 -19.44396)
			(xy 16.13762 -19.458076) (xy 16.188983 -19.479903) (xy 16.236621 -19.508976) (xy 16.279517 -19.544675)
			(xy 16.316759 -19.586239) (xy 16.347553 -19.632783) (xy 16.371241 -19.683314) (xy 16.387319 -19.736756)
			(xy 16.395445 -19.79197) (xy 16.395954 -19.819874) (xy 16.395445 -19.847778) (xy 16.387319 -19.902992)
			(xy 16.371241 -19.956434) (xy 16.347553 -20.006965) (xy 16.316759 -20.053509) (xy 16.279517 -20.095073)
			(xy 16.236621 -20.130772) (xy 16.188983 -20.159845) (xy 16.13762 -20.181672) (xy 16.114368 -20.187751)
			(xy 138.828766 -20.187751) (xy 138.828766 -20.133249) (xy 138.836522 -20.079301) (xy 138.851877 -20.027006)
			(xy 138.874517 -19.977429) (xy 138.903982 -19.931578) (xy 138.939673 -19.890387) (xy 138.980862 -19.854694)
			(xy 139.026711 -19.825227) (xy 139.076288 -19.802584) (xy 139.128582 -19.787226) (xy 139.182529 -19.779467)
			(xy 139.20978 -19.77898) (xy 140.07338 -19.77898) (xy 140.100633 -19.779466) (xy 140.154584 -19.78722)
			(xy 140.206883 -19.802574) (xy 140.256464 -19.825215) (xy 140.302318 -19.854681) (xy 140.343512 -19.890374)
			(xy 140.379207 -19.931566) (xy 140.408676 -19.977418) (xy 140.431319 -20.026998) (xy 140.446675 -20.079296)
			(xy 140.454433 -20.133247) (xy 140.454433 -20.187753) (xy 140.446675 -20.241704) (xy 140.431319 -20.294002)
			(xy 140.408676 -20.343582) (xy 140.379207 -20.389434) (xy 140.343512 -20.430626) (xy 140.302318 -20.466319)
			(xy 140.256464 -20.495785) (xy 140.206883 -20.518426) (xy 140.154584 -20.53378) (xy 140.100633 -20.541534)
			(xy 140.07338 -20.541996) (xy 139.20978 -20.541996) (xy 139.182529 -20.541533) (xy 139.128582 -20.533774)
			(xy 139.076288 -20.518416) (xy 139.026711 -20.495773) (xy 138.980862 -20.466306) (xy 138.939673 -20.430613)
			(xy 138.903982 -20.389422) (xy 138.874517 -20.343571) (xy 138.851877 -20.293994) (xy 138.836522 -20.241699)
			(xy 138.828766 -20.187751) (xy 16.114368 -20.187751) (xy 16.083627 -20.195788) (xy 16.028153 -20.201891)
			(xy 15.972382 -20.199853) (xy 15.917503 -20.189716) (xy 15.864683 -20.171697) (xy 15.815051 -20.146179)
			(xy 15.769663 -20.113707) (xy 15.729486 -20.074972) (xy 15.695378 -20.0308) (xy 15.668064 -19.982132)
			(xy 15.648128 -19.930006) (xy 15.635993 -19.875533) (xy 15.63192 -19.819874) (xy 0.509016 -19.819874)
			(xy 0.509016 -20.53844) (xy 14.913353 -20.53844) (xy 14.917429 -20.482744) (xy 14.929572 -20.428234)
			(xy 14.949522 -20.376074) (xy 14.976853 -20.327374) (xy 15.010985 -20.283173) (xy 15.051188 -20.244412)
			(xy 15.096606 -20.211918) (xy 15.146272 -20.186383) (xy 15.199126 -20.168351) (xy 15.254043 -20.158208)
			(xy 15.309851 -20.156168) (xy 15.365361 -20.162276) (xy 15.41939 -20.176401) (xy 15.470788 -20.198243)
			(xy 15.518457 -20.227335) (xy 15.561382 -20.263057) (xy 15.598649 -20.30465) (xy 15.629462 -20.351224)
			(xy 15.653166 -20.40179) (xy 15.669255 -20.455267) (xy 15.677387 -20.510517) (xy 15.677896 -20.53844)
			(xy 15.677387 -20.566363) (xy 15.669255 -20.621613) (xy 15.653166 -20.67509) (xy 15.629462 -20.725656)
			(xy 15.598649 -20.77223) (xy 15.561382 -20.813823) (xy 15.518457 -20.849545) (xy 15.470788 -20.878637)
			(xy 15.41939 -20.900479) (xy 15.365361 -20.914604) (xy 15.309851 -20.920712) (xy 15.254043 -20.918672)
			(xy 15.199126 -20.908529) (xy 15.146272 -20.890497) (xy 15.096606 -20.864962) (xy 15.051188 -20.832468)
			(xy 15.010985 -20.793707) (xy 14.976853 -20.749506) (xy 14.949522 -20.700806) (xy 14.929572 -20.648646)
			(xy 14.917429 -20.594136) (xy 14.913353 -20.53844) (xy 0.509016 -20.53844) (xy 0.509016 -21.521251)
			(xy 15.232366 -21.521251) (xy 15.232366 -21.466749) (xy 15.240122 -21.412801) (xy 15.255477 -21.360506)
			(xy 15.278117 -21.310929) (xy 15.307582 -21.265078) (xy 15.343273 -21.223887) (xy 15.384462 -21.188194)
			(xy 15.430311 -21.158727) (xy 15.479888 -21.136084) (xy 15.532182 -21.120726) (xy 15.586129 -21.112967)
			(xy 15.61338 -21.11248) (xy 16.47698 -21.11248) (xy 16.504233 -21.112966) (xy 16.558184 -21.12072)
			(xy 16.610483 -21.136074) (xy 16.660064 -21.158715) (xy 16.705918 -21.188181) (xy 16.747112 -21.223874)
			(xy 16.782807 -21.265066) (xy 16.812276 -21.310918) (xy 16.834919 -21.360498) (xy 16.850275 -21.412796)
			(xy 16.858033 -21.466747) (xy 16.858033 -21.521253) (xy 16.850275 -21.575204) (xy 16.834919 -21.627502)
			(xy 16.812276 -21.677082) (xy 16.782807 -21.722934) (xy 16.747112 -21.764126) (xy 16.705918 -21.799819)
			(xy 16.660064 -21.829285) (xy 16.610483 -21.851926) (xy 16.558184 -21.86728) (xy 16.504233 -21.875034)
			(xy 16.47698 -21.875496) (xy 15.61338 -21.875496) (xy 15.586129 -21.875033) (xy 15.532182 -21.867274)
			(xy 15.479888 -21.851916) (xy 15.430311 -21.829273) (xy 15.384462 -21.799806) (xy 15.343273 -21.764113)
			(xy 15.307582 -21.722922) (xy 15.278117 -21.677071) (xy 15.255477 -21.627494) (xy 15.240122 -21.575199)
			(xy 15.232366 -21.521251) (xy 0.509016 -21.521251) (xy 0.509016 -24.929338) (xy 133.555232 -24.929338)
			(xy 133.555232 -24.065738) (xy 133.555718 -24.038487) (xy 133.563474 -23.984539) (xy 133.578829 -23.932244)
			(xy 133.601471 -23.882667) (xy 133.630937 -23.836817) (xy 133.666628 -23.795626) (xy 133.707819 -23.759935)
			(xy 133.753669 -23.730469) (xy 133.803246 -23.707827) (xy 133.855541 -23.692472) (xy 133.909489 -23.684716)
			(xy 133.963991 -23.684716) (xy 134.017939 -23.692472) (xy 134.070234 -23.707827) (xy 134.119811 -23.730469)
			(xy 134.165661 -23.759935) (xy 134.206852 -23.795626) (xy 134.242543 -23.836817) (xy 134.272009 -23.882667)
			(xy 134.294651 -23.932244) (xy 134.310006 -23.984539) (xy 134.317762 -24.038487) (xy 134.318248 -24.065738)
			(xy 134.318248 -24.929338) (xy 134.317762 -24.956589) (xy 134.310006 -25.010537) (xy 134.294651 -25.062832)
			(xy 134.272009 -25.112409) (xy 134.242543 -25.158259) (xy 134.206852 -25.19945) (xy 134.165661 -25.235141)
			(xy 134.119811 -25.264607) (xy 134.070234 -25.287249) (xy 134.017939 -25.302604) (xy 133.963991 -25.31036)
			(xy 133.909489 -25.31036) (xy 133.855541 -25.302604) (xy 133.803246 -25.287249) (xy 133.753669 -25.264607)
			(xy 133.707819 -25.235141) (xy 133.666628 -25.19945) (xy 133.630937 -25.158259) (xy 133.601471 -25.112409)
			(xy 133.578829 -25.062832) (xy 133.563474 -25.010537) (xy 133.555718 -24.956589) (xy 133.555232 -24.929338)
			(xy 0.509016 -24.929338) (xy 0.509016 -29.070615) (xy 12.244307 -29.070615) (xy 12.252198 -28.941486)
			(xy 12.268182 -28.813107) (xy 12.292195 -28.685984) (xy 12.324144 -28.560621) (xy 12.363901 -28.437511)
			(xy 12.41131 -28.31714) (xy 12.466183 -28.199984) (xy 12.528305 -28.086504) (xy 12.59743 -27.97715)
			(xy 12.673285 -27.872351) (xy 12.75557 -27.772522) (xy 12.843962 -27.678057) (xy 12.938111 -27.589329)
			(xy 13.037646 -27.506688) (xy 13.142173 -27.43046) (xy 13.25128 -27.360945) (xy 13.364537 -27.298419)
			(xy 13.481497 -27.243128) (xy 13.601698 -27.19529) (xy 13.724665 -27.155093) (xy 13.849914 -27.122698)
			(xy 13.97695 -27.098231) (xy 14.105271 -27.081789) (xy 14.234372 -27.073437) (xy 14.363742 -27.073208)
			(xy 14.492871 -27.081103) (xy 14.62125 -27.097091) (xy 14.748372 -27.121108) (xy 14.873734 -27.15306)
			(xy 14.996843 -27.19282) (xy 15.117212 -27.240232) (xy 15.234367 -27.295109) (xy 15.347845 -27.357234)
			(xy 15.457198 -27.426362) (xy 15.561994 -27.50222) (xy 15.661821 -27.584508) (xy 15.709392 -27.628342)
			(xy 16.877792 -28.721304) (xy 16.92464 -28.765906) (xy 17.013363 -28.860052) (xy 17.096 -28.959584)
			(xy 17.172224 -29.064107) (xy 17.241734 -29.17321) (xy 17.304257 -29.286463) (xy 17.359545 -29.403418)
			(xy 17.407381 -29.523614) (xy 17.447575 -29.646576) (xy 17.479969 -29.771819) (xy 17.504435 -29.898849)
			(xy 17.520877 -30.027165) (xy 17.529229 -30.15626) (xy 17.529459 -30.285624) (xy 17.521566 -30.414748)
			(xy 17.50558 -30.543122) (xy 17.481566 -30.670238) (xy 17.449617 -30.795596) (xy 17.40986 -30.9187)
			(xy 17.362452 -31.039065) (xy 17.30758 -31.156215) (xy 17.24546 -31.26969) (xy 17.176338 -31.379039)
			(xy 17.100486 -31.483833) (xy 17.018204 -31.583657) (xy 16.929816 -31.678118) (xy 16.835671 -31.766843)
			(xy 16.736141 -31.849481) (xy 16.631619 -31.925706) (xy 16.522517 -31.995218) (xy 16.409265 -32.057743)
			(xy 16.292311 -32.113033) (xy 16.172116 -32.16087) (xy 16.049154 -32.201066) (xy 15.923911 -32.233462)
			(xy 15.796882 -32.25793) (xy 15.668566 -32.274374) (xy 15.539471 -32.282728) (xy 15.410107 -32.28296)
			(xy 15.280983 -32.275069) (xy 15.152609 -32.259085) (xy 15.025493 -32.235073) (xy 14.900134 -32.203126)
			(xy 14.77703 -32.163371) (xy 14.656664 -32.115965) (xy 14.539512 -32.061094) (xy 14.426037 -31.998976)
			(xy 14.316687 -31.929855) (xy 14.211892 -31.854005) (xy 14.112066 -31.771724) (xy 14.064488 -31.727902)
			(xy 12.896088 -30.63494) (xy 12.849198 -30.590378) (xy 12.760467 -30.496232) (xy 12.677823 -30.3967)
			(xy 12.601592 -30.292174) (xy 12.532074 -30.183069) (xy 12.469545 -30.069814) (xy 12.41425 -29.952855)
			(xy 12.366409 -29.832656) (xy 12.32621 -29.70969) (xy 12.293811 -29.584442) (xy 12.26934 -29.457407)
			(xy 12.252895 -29.329086) (xy 12.244539 -29.199985) (xy 12.244307 -29.070615) (xy 0.509016 -29.070615)
			(xy 0.509016 -37.099629) (xy 170.600616 -37.099629) (xy 170.600616 -37.000299) (xy 170.608608 -36.901292)
			(xy 170.624542 -36.803249) (xy 170.648313 -36.706806) (xy 170.679768 -36.612588) (xy 170.718701 -36.521208)
			(xy 170.764862 -36.433256) (xy 170.81795 -36.349304) (xy 170.877621 -36.269895) (xy 170.943489 -36.195546)
			(xy 171.015126 -36.126738) (xy 171.092067 -36.063918) (xy 171.173813 -36.007493) (xy 171.259835 -35.957828)
			(xy 171.349574 -35.915246) (xy 171.442448 -35.880024) (xy 171.537856 -35.852388) (xy 171.635178 -35.83252)
			(xy 171.733783 -35.820547) (xy 171.833032 -35.816548) (xy 171.932281 -35.820547) (xy 172.030886 -35.83252)
			(xy 172.128208 -35.852388) (xy 172.223616 -35.880024) (xy 172.31649 -35.915246) (xy 172.406229 -35.957828)
			(xy 172.492251 -36.007493) (xy 172.573997 -36.063918) (xy 172.650938 -36.126738) (xy 172.722575 -36.195546)
			(xy 172.788443 -36.269895) (xy 172.848114 -36.349304) (xy 172.901202 -36.433256) (xy 172.947363 -36.521208)
			(xy 172.986296 -36.612588) (xy 173.017751 -36.706806) (xy 173.041522 -36.803249) (xy 173.057456 -36.901292)
			(xy 173.065448 -37.000299) (xy 173.065948 -37.049964) (xy 173.065448 -37.099629) (xy 173.057456 -37.198636)
			(xy 173.041522 -37.296679) (xy 173.017751 -37.393122) (xy 172.986296 -37.48734) (xy 172.947363 -37.57872)
			(xy 172.901202 -37.666672) (xy 172.848114 -37.750624) (xy 172.788443 -37.830033) (xy 172.722575 -37.904382)
			(xy 172.650938 -37.97319) (xy 172.573997 -38.03601) (xy 172.492251 -38.092435) (xy 172.406229 -38.1421)
			(xy 172.31649 -38.184682) (xy 172.223616 -38.219904) (xy 172.128208 -38.24754) (xy 172.030886 -38.267408)
			(xy 171.932281 -38.279381) (xy 171.833032 -38.283381) (xy 171.733783 -38.279381) (xy 171.635178 -38.267408)
			(xy 171.537856 -38.24754) (xy 171.442448 -38.219904) (xy 171.349574 -38.184682) (xy 171.259835 -38.1421)
			(xy 171.173813 -38.092435) (xy 171.092067 -38.03601) (xy 171.015126 -37.97319) (xy 170.943489 -37.904382)
			(xy 170.877621 -37.830033) (xy 170.81795 -37.750624) (xy 170.764862 -37.666672) (xy 170.718701 -37.57872)
			(xy 170.679768 -37.48734) (xy 170.648313 -37.393122) (xy 170.624542 -37.296679) (xy 170.608608 -37.198636)
			(xy 170.600616 -37.099629) (xy 0.509016 -37.099629) (xy 0.509016 -39.657528) (xy 357.003604 -39.657528)
			(xy 357.003604 -38.793928) (xy 357.00409 -38.766659) (xy 357.011852 -38.712675) (xy 357.027217 -38.660345)
			(xy 357.049874 -38.610735) (xy 357.07936 -38.564854) (xy 357.115075 -38.523637) (xy 357.156292 -38.487922)
			(xy 357.202173 -38.458436) (xy 357.251783 -38.435779) (xy 357.304113 -38.420414) (xy 357.358097 -38.412652)
			(xy 357.412635 -38.412652) (xy 357.466619 -38.420414) (xy 357.518949 -38.435779) (xy 357.568559 -38.458436)
			(xy 357.61444 -38.487922) (xy 357.655657 -38.523637) (xy 357.691372 -38.564854) (xy 357.720858 -38.610735)
			(xy 357.743515 -38.660345) (xy 357.75888 -38.712675) (xy 357.766642 -38.766659) (xy 357.767128 -38.793928)
			(xy 357.767128 -39.657528) (xy 357.766642 -39.684797) (xy 357.75888 -39.738781) (xy 357.743515 -39.791111)
			(xy 357.720858 -39.840721) (xy 357.691372 -39.886602) (xy 357.655657 -39.927819) (xy 357.61444 -39.963534)
			(xy 357.568559 -39.99302) (xy 357.518949 -40.015677) (xy 357.466619 -40.031042) (xy 357.412635 -40.038804)
			(xy 357.358097 -40.038804) (xy 357.304113 -40.031042) (xy 357.251783 -40.015677) (xy 357.202173 -39.99302)
			(xy 357.156292 -39.963534) (xy 357.115075 -39.927819) (xy 357.07936 -39.886602) (xy 357.049874 -39.840721)
			(xy 357.027217 -39.791111) (xy 357.011852 -39.738781) (xy 357.00409 -39.684797) (xy 357.003604 -39.657528)
			(xy 0.509016 -39.657528) (xy 0.509016 -39.83736) (xy 157.004512 -39.83736) (xy 157.782768 -39.83736)
			(xy 158.005272 -39.83736) (xy 158.765748 -39.83736) (xy 158.765748 -40.577516) (xy 158.005272 -40.577516)
			(xy 158.005272 -39.83736) (xy 157.782768 -39.83736) (xy 157.782768 -40.577516) (xy 157.004512 -40.577516)
			(xy 157.004512 -39.83736) (xy 0.509016 -39.83736) (xy 0.509016 -40.744902) (xy 235.083357 -40.744902)
			(xy 235.087362 -40.656994) (xy 235.099345 -40.569814) (xy 235.119205 -40.484085) (xy 235.14678 -40.400517)
			(xy 235.181839 -40.319803) (xy 235.224092 -40.242611) (xy 235.27319 -40.169582) (xy 235.328726 -40.10132)
			(xy 235.390238 -40.03839) (xy 235.457219 -39.981316) (xy 235.529112 -39.930568) (xy 235.605321 -39.886568)
			(xy 235.685216 -39.849681) (xy 235.768135 -39.820212) (xy 235.85339 -39.798405) (xy 235.940274 -39.784441)
			(xy 236.028068 -39.778435) (xy 236.116045 -39.780439) (xy 236.203475 -39.790434) (xy 236.289634 -39.808338)
			(xy 236.373808 -39.834002) (xy 236.455299 -39.867215) (xy 236.533433 -39.907701) (xy 236.607561 -39.955123)
			(xy 236.677069 -40.00909) (xy 236.741383 -40.069155) (xy 236.799967 -40.134819) (xy 236.852338 -40.205538)
			(xy 236.898061 -40.280726) (xy 236.936758 -40.359761) (xy 236.968107 -40.441987) (xy 236.991849 -40.526723)
			(xy 237.007787 -40.613267) (xy 237.015789 -40.700902) (xy 237.01629 -40.744902) (xy 237.015789 -40.788902)
			(xy 237.007787 -40.876537) (xy 236.991849 -40.963081) (xy 236.968107 -41.047817) (xy 236.936758 -41.130043)
			(xy 236.898061 -41.209078) (xy 236.852338 -41.284266) (xy 236.799967 -41.354985) (xy 236.741383 -41.420649)
			(xy 236.677069 -41.480714) (xy 236.607561 -41.534681) (xy 236.533433 -41.582103) (xy 236.455299 -41.622589)
			(xy 236.373808 -41.655802) (xy 236.289634 -41.681466) (xy 236.203475 -41.69937) (xy 236.116045 -41.709365)
			(xy 236.028068 -41.711369) (xy 235.940274 -41.705363) (xy 235.85339 -41.691399) (xy 235.768135 -41.669592)
			(xy 235.685216 -41.640123) (xy 235.605321 -41.603236) (xy 235.529112 -41.559236) (xy 235.457219 -41.508488)
			(xy 235.390238 -41.451414) (xy 235.328726 -41.388484) (xy 235.27319 -41.320222) (xy 235.224092 -41.247193)
			(xy 235.181839 -41.170001) (xy 235.14678 -41.089287) (xy 235.119205 -41.005719) (xy 235.099345 -40.91999)
			(xy 235.087362 -40.83281) (xy 235.083357 -40.744902) (xy 0.509016 -40.744902) (xy 0.509016 -41.530524)
			(xy 158.857185 -41.530524) (xy 158.861264 -41.474791) (xy 158.873414 -41.420245) (xy 158.893377 -41.36805)
			(xy 158.920727 -41.319318) (xy 158.954881 -41.275087) (xy 158.995111 -41.2363) (xy 159.04056 -41.203784)
			(xy 159.090258 -41.178233) (xy 159.143148 -41.160189) (xy 159.198101 -41.150039) (xy 159.253946 -41.147998)
			(xy 159.309493 -41.15411) (xy 159.363559 -41.168244) (xy 159.41499 -41.1901) (xy 159.462691 -41.219212)
			(xy 159.505645 -41.254958) (xy 159.542936 -41.296578) (xy 159.57377 -41.343184) (xy 159.59749 -41.393783)
			(xy 159.61359 -41.447296) (xy 159.621726 -41.502583) (xy 159.622236 -41.530524) (xy 159.621726 -41.558465)
			(xy 159.61359 -41.613752) (xy 159.59749 -41.667265) (xy 159.57377 -41.717864) (xy 159.542936 -41.76447)
			(xy 159.505645 -41.80609) (xy 159.462691 -41.841836) (xy 159.41499 -41.870948) (xy 159.363559 -41.892804)
			(xy 159.309493 -41.906938) (xy 159.253946 -41.91305) (xy 159.198101 -41.911009) (xy 159.143148 -41.900859)
			(xy 159.090258 -41.882815) (xy 159.04056 -41.857264) (xy 158.995111 -41.824748) (xy 158.954881 -41.785961)
			(xy 158.920727 -41.74173) (xy 158.893377 -41.692998) (xy 158.873414 -41.640803) (xy 158.861264 -41.586257)
			(xy 158.857185 -41.530524) (xy 0.509016 -41.530524) (xy 0.509016 -42.24909) (xy 158.139127 -42.24909)
			(xy 158.143203 -42.193394) (xy 158.155346 -42.138884) (xy 158.175296 -42.086724) (xy 158.202627 -42.038024)
			(xy 158.236759 -41.993823) (xy 158.276962 -41.955062) (xy 158.32238 -41.922568) (xy 158.372046 -41.897033)
			(xy 158.4249 -41.879001) (xy 158.479817 -41.868858) (xy 158.535625 -41.866818) (xy 158.591135 -41.872926)
			(xy 158.645164 -41.887051) (xy 158.696562 -41.908893) (xy 158.744231 -41.937985) (xy 158.787156 -41.973707)
			(xy 158.824423 -42.0153) (xy 158.855236 -42.061874) (xy 158.87894 -42.11244) (xy 158.895029 -42.165917)
			(xy 158.903161 -42.221167) (xy 158.90367 -42.24909) (xy 158.903161 -42.277013) (xy 158.895029 -42.332263)
			(xy 158.87894 -42.38574) (xy 158.855236 -42.436306) (xy 158.824423 -42.48288) (xy 158.787156 -42.524473)
			(xy 158.744231 -42.560195) (xy 158.696562 -42.589287) (xy 158.645164 -42.611129) (xy 158.591135 -42.625254)
			(xy 158.535625 -42.631362) (xy 158.479817 -42.629322) (xy 158.4249 -42.619179) (xy 158.372046 -42.601147)
			(xy 158.32238 -42.575612) (xy 158.276962 -42.543118) (xy 158.236759 -42.504357) (xy 158.202627 -42.460156)
			(xy 158.175296 -42.411456) (xy 158.155346 -42.359296) (xy 158.143203 -42.304786) (xy 158.139127 -42.24909)
			(xy 0.509016 -42.24909) (xy 0.509016 -42.91711) (xy 155.487113 -42.91711) (xy 155.491189 -42.861414)
			(xy 155.503332 -42.806904) (xy 155.523282 -42.754744) (xy 155.550613 -42.706044) (xy 155.584745 -42.661843)
			(xy 155.624948 -42.623082) (xy 155.670366 -42.590588) (xy 155.720032 -42.565053) (xy 155.772886 -42.547021)
			(xy 155.827803 -42.536878) (xy 155.883611 -42.534838) (xy 155.939121 -42.540946) (xy 155.99315 -42.555071)
			(xy 156.044548 -42.576913) (xy 156.092217 -42.606005) (xy 156.135142 -42.641727) (xy 156.172409 -42.68332)
			(xy 156.203222 -42.729894) (xy 156.226926 -42.78046) (xy 156.243015 -42.833937) (xy 156.251147 -42.889187)
			(xy 156.251656 -42.91711) (xy 156.502859 -42.91711) (xy 156.506938 -42.861377) (xy 156.519088 -42.806831)
			(xy 156.539051 -42.754636) (xy 156.566401 -42.705904) (xy 156.600555 -42.661673) (xy 156.640785 -42.622886)
			(xy 156.686234 -42.59037) (xy 156.735932 -42.564819) (xy 156.788822 -42.546775) (xy 156.843775 -42.536625)
			(xy 156.89962 -42.534584) (xy 156.955167 -42.540696) (xy 157.009233 -42.55483) (xy 157.060664 -42.576686)
			(xy 157.108365 -42.605798) (xy 157.151319 -42.641544) (xy 157.18861 -42.683164) (xy 157.219444 -42.72977)
			(xy 157.243164 -42.780369) (xy 157.259264 -42.833882) (xy 157.2674 -42.889169) (xy 157.26791 -42.91711)
			(xy 157.2674 -42.945051) (xy 157.259264 -43.000338) (xy 157.243164 -43.053851) (xy 157.219444 -43.10445)
			(xy 157.18861 -43.151056) (xy 157.151319 -43.192676) (xy 157.108365 -43.228422) (xy 157.060664 -43.257534)
			(xy 157.009233 -43.27939) (xy 156.955167 -43.293524) (xy 156.89962 -43.299636) (xy 156.843775 -43.297595)
			(xy 156.788822 -43.287445) (xy 156.735932 -43.269401) (xy 156.686234 -43.24385) (xy 156.640785 -43.211334)
			(xy 156.600555 -43.172547) (xy 156.566401 -43.128316) (xy 156.539051 -43.079584) (xy 156.519088 -43.027389)
			(xy 156.506938 -42.972843) (xy 156.502859 -42.91711) (xy 156.251656 -42.91711) (xy 156.251147 -42.945033)
			(xy 156.243015 -43.000283) (xy 156.226926 -43.05376) (xy 156.203222 -43.104326) (xy 156.172409 -43.1509)
			(xy 156.135142 -43.192493) (xy 156.092217 -43.228215) (xy 156.044548 -43.257307) (xy 155.99315 -43.279149)
			(xy 155.939121 -43.293274) (xy 155.883611 -43.299382) (xy 155.827803 -43.297342) (xy 155.772886 -43.287199)
			(xy 155.720032 -43.269167) (xy 155.670366 -43.243632) (xy 155.624948 -43.211138) (xy 155.584745 -43.172377)
			(xy 155.550613 -43.128176) (xy 155.523282 -43.079476) (xy 155.503332 -43.027316) (xy 155.491189 -42.972806)
			(xy 155.487113 -42.91711) (xy 0.509016 -42.91711) (xy 0.509016 -43.999912) (xy 16.983969 -43.999912)
			(xy 16.987993 -43.914144) (xy 17.000031 -43.82913) (xy 17.019978 -43.745616) (xy 17.047657 -43.664337)
			(xy 17.082825 -43.586008) (xy 17.125174 -43.511315) (xy 17.174331 -43.440917) (xy 17.229864 -43.375431)
			(xy 17.291286 -43.315433) (xy 17.358055 -43.26145) (xy 17.429587 -43.213957) (xy 17.505251 -43.173371)
			(xy 17.584384 -43.140048) (xy 17.666289 -43.114282) (xy 17.750247 -43.096299) (xy 17.835521 -43.086257)
			(xy 17.92136 -43.084244) (xy 18.00701 -43.090278) (xy 18.091718 -43.104306) (xy 18.174741 -43.126205)
			(xy 18.255349 -43.155782) (xy 18.332833 -43.192777) (xy 18.406512 -43.236865) (xy 18.475738 -43.287659)
			(xy 18.539905 -43.344712) (xy 18.598446 -43.407523) (xy 18.650849 -43.47554) (xy 18.696652 -43.548165)
			(xy 18.735453 -43.62476) (xy 18.766912 -43.704652) (xy 18.790751 -43.787139) (xy 18.806761 -43.871496)
			(xy 18.814801 -43.956981) (xy 18.815304 -43.999912) (xy 18.814801 -44.042843) (xy 18.806761 -44.128328)
			(xy 18.790751 -44.212685) (xy 18.766912 -44.295172) (xy 18.735453 -44.375064) (xy 18.696652 -44.451659)
			(xy 18.650849 -44.524284) (xy 18.598446 -44.592301) (xy 18.539905 -44.655112) (xy 18.475738 -44.712165)
			(xy 18.406512 -44.762959) (xy 18.332833 -44.807047) (xy 18.255349 -44.844042) (xy 18.174741 -44.873619)
			(xy 18.091718 -44.895518) (xy 18.00701 -44.909546) (xy 17.92136 -44.91558) (xy 17.835521 -44.913567)
			(xy 17.750247 -44.903525) (xy 17.666289 -44.885542) (xy 17.584384 -44.859776) (xy 17.505251 -44.826453)
			(xy 17.429587 -44.785867) (xy 17.358055 -44.738374) (xy 17.291286 -44.684391) (xy 17.229864 -44.624393)
			(xy 17.174331 -44.558907) (xy 17.125174 -44.488509) (xy 17.082825 -44.413816) (xy 17.047657 -44.335487)
			(xy 17.019978 -44.254208) (xy 17.000031 -44.170694) (xy 16.987993 -44.08568) (xy 16.983969 -43.999912)
			(xy 0.509016 -43.999912) (xy 0.509016 -47.049813) (xy 59.781451 -47.049813) (xy 59.785436 -46.895317)
			(xy 59.79737 -46.74123) (xy 59.817219 -46.587962) (xy 59.844933 -46.43592) (xy 59.880436 -46.285505)
			(xy 59.923635 -46.137118) (xy 59.974415 -45.991151) (xy 60.032642 -45.847991) (xy 60.098162 -45.708019)
			(xy 60.1708 -45.571605) (xy 60.250363 -45.439111) (xy 60.336642 -45.310889) (xy 60.429407 -45.187278)
			(xy 60.528412 -45.068606) (xy 60.633395 -44.955188) (xy 60.744077 -44.847324) (xy 60.860165 -44.745302)
			(xy 60.981351 -44.64939) (xy 61.107313 -44.559844) (xy 61.237718 -44.476901) (xy 61.37222 -44.400781)
			(xy 61.510462 -44.331685) (xy 61.652077 -44.269798) (xy 61.796691 -44.215282) (xy 61.943919 -44.168283)
			(xy 62.093371 -44.128926) (xy 62.244652 -44.097314) (xy 62.397358 -44.073531) (xy 62.551087 -44.057641)
			(xy 62.70543 -44.049685) (xy 62.782704 -44.049188) (xy 64.383158 -44.049188) (xy 64.460432 -44.049684)
			(xy 64.614774 -44.057653) (xy 64.768502 -44.073557) (xy 64.921207 -44.097353) (xy 65.072484 -44.128978)
			(xy 65.221933 -44.168349) (xy 65.369158 -44.21536) (xy 65.513767 -44.269888) (xy 65.655377 -44.331788)
			(xy 65.793613 -44.400896) (xy 65.928108 -44.477028) (xy 66.058506 -44.559982) (xy 66.184461 -44.649539)
			(xy 66.305639 -44.745461) (xy 66.421718 -44.847494) (xy 66.532391 -44.955367) (xy 66.637364 -45.068794)
			(xy 66.736359 -45.187475) (xy 66.829113 -45.311094) (xy 66.915381 -45.439324) (xy 66.994934 -45.571824)
			(xy 67.06756 -45.708245) (xy 67.133068 -45.848223) (xy 67.191283 -45.991387) (xy 67.242051 -46.137359)
			(xy 67.285237 -46.28575) (xy 67.320727 -46.436168) (xy 67.348428 -46.588213) (xy 67.368264 -46.741483)
			(xy 67.380185 -46.89557) (xy 67.384154 -47.04994) (xy 89.78165 -47.04994) (xy 89.78563 -46.895439)
			(xy 89.797557 -46.741349) (xy 89.817402 -46.588076) (xy 89.84511 -46.436028) (xy 89.880608 -46.285609)
			(xy 89.923803 -46.137216) (xy 89.97458 -45.991243) (xy 90.032804 -45.848078) (xy 90.098321 -45.708101)
			(xy 90.170957 -45.571681) (xy 90.250519 -45.439181) (xy 90.336796 -45.310953) (xy 90.42956 -45.187337)
			(xy 90.528565 -45.068659) (xy 90.633548 -44.955236) (xy 90.74423 -44.847368) (xy 90.860319 -44.74534)
			(xy 90.981506 -44.649424) (xy 91.10747 -44.559873) (xy 91.237877 -44.476926) (xy 91.372381 -44.400801)
			(xy 91.510626 -44.331702) (xy 91.652244 -44.269811) (xy 91.796861 -44.215293) (xy 91.944092 -44.168291)
			(xy 92.093548 -44.128931) (xy 92.244832 -44.097317) (xy 92.397543 -44.073533) (xy 92.551275 -44.057642)
			(xy 92.705622 -44.049686) (xy 92.782898 -44.049188) (xy 94.383098 -44.049188) (xy 94.460374 -44.049669)
			(xy 94.614722 -44.057625) (xy 94.768456 -44.073516) (xy 94.921168 -44.0973) (xy 95.072452 -44.128914)
			(xy 95.221909 -44.168274) (xy 95.369142 -44.215276) (xy 95.513759 -44.269795) (xy 95.655379 -44.331686)
			(xy 95.793624 -44.400785) (xy 95.928129 -44.47691) (xy 96.058537 -44.559858) (xy 96.184502 -44.649409)
			(xy 96.30569 -44.745326) (xy 96.421779 -44.847354) (xy 96.532463 -44.955223) (xy 96.637446 -45.068647)
			(xy 96.73394 -45.184314) (xy 155.3845 -45.184314) (xy 155.3845 -44.11472) (xy 155.385027 -44.103504)
			(xy 155.390408 -44.08171) (xy 155.395168 -44.07154) (xy 155.398615 -44.065034) (xy 155.407161 -44.053045)
			(xy 155.412186 -44.047664) (xy 155.421841 -44.038248) (xy 155.445061 -44.024547) (xy 155.471093 -44.017535)
			(xy 155.484576 -44.017184) (xy 155.791408 -44.017184) (xy 155.805805 -44.018374) (xy 155.833044 -44.027956)
			(xy 155.856376 -44.044965) (xy 155.873834 -44.067965) (xy 155.883941 -44.095013) (xy 155.885388 -44.109386)
			(xy 155.885388 -44.47667) (xy 155.885857 -44.490439) (xy 155.893287 -44.516957) (xy 155.907534 -44.540526)
			(xy 155.927561 -44.55943) (xy 155.951911 -44.572295) (xy 155.978814 -44.578184) (xy 156.006312 -44.57667)
			(xy 156.032406 -44.567862) (xy 156.055196 -44.552402) (xy 156.064458 -44.542202) (xy 156.082701 -44.52148)
			(xy 156.124089 -44.484944) (xy 156.170309 -44.454753) (xy 156.220398 -44.431538) (xy 156.273309 -44.415784)
			(xy 156.327939 -44.40782) (xy 156.355542 -44.407328) (xy 156.35605 -44.407328) (xy 156.382134 -44.407766)
			(xy 156.433813 -44.414897) (xy 156.484038 -44.429006) (xy 156.53187 -44.449829) (xy 156.576418 -44.476978)
			(xy 156.61685 -44.509945) (xy 156.634942 -44.52874) (xy 156.644438 -44.538392) (xy 156.667413 -44.552703)
			(xy 156.693342 -44.56047) (xy 156.720401 -44.561147) (xy 156.746686 -44.554685) (xy 156.770348 -44.54154)
			(xy 156.789721 -44.522637) (xy 156.803442 -44.499305) (xy 156.810546 -44.473186) (xy 156.810964 -44.459652)
			(xy 156.810964 -44.130468) (xy 156.811601 -44.11809) (xy 156.818164 -44.094197) (xy 156.830365 -44.072631)
			(xy 156.83865 -44.063412) (xy 156.848327 -44.054021) (xy 156.871536 -44.040311) (xy 156.89756 -44.033288)
			(xy 156.91104 -44.032932) (xy 157.217872 -44.032932) (xy 157.232281 -44.034026) (xy 157.259527 -44.043631)
			(xy 157.282862 -44.060663) (xy 157.300315 -44.083685) (xy 157.310412 -44.110753) (xy 157.311852 -44.125134)
			(xy 157.311852 -45.169836) (xy 158.65094 -45.169836) (xy 158.65094 -43.300396) (xy 158.651598 -43.28802)
			(xy 158.658153 -43.264128) (xy 158.670346 -43.242561) (xy 158.678626 -43.23334) (xy 158.688302 -43.223948)
			(xy 158.711512 -43.210242) (xy 158.737536 -43.203218) (xy 158.751016 -43.20286) (xy 159.057848 -43.20286)
			(xy 159.072246 -43.204039) (xy 159.099481 -43.213629) (xy 159.122812 -43.230642) (xy 159.140268 -43.253642)
			(xy 159.150378 -43.280689) (xy 159.151828 -43.295062) (xy 159.151828 -43.446446) (xy 159.152285 -43.460837)
			(xy 159.160327 -43.488472) (xy 159.175759 -43.512767) (xy 159.197356 -43.531792) (xy 159.223403 -43.544036)
			(xy 159.251832 -43.548529) (xy 159.280385 -43.544911) (xy 159.306796 -43.533472) (xy 159.318198 -43.524678)
			(xy 159.33882 -43.508195) (xy 159.383741 -43.480459) (xy 159.432056 -43.459181) (xy 159.482844 -43.444767)
			(xy 159.535133 -43.437493) (xy 159.56153 -43.437048) (xy 159.561784 -43.437048) (xy 159.589164 -43.437498)
			(xy 159.643359 -43.445338) (xy 159.695878 -43.460844) (xy 159.74564 -43.483698) (xy 159.791624 -43.513431)
			(xy 159.832886 -43.549433) (xy 159.85109 -43.56989) (xy 159.860351 -43.580066) (xy 159.883159 -43.595438)
			(xy 159.909246 -43.604151) (xy 159.936714 -43.605573) (xy 159.963561 -43.599599) (xy 159.987834 -43.586664)
			(xy 160.007765 -43.56771) (xy 160.021903 -43.544117) (xy 160.029217 -43.517603) (xy 160.029652 -43.50385)
			(xy 160.029652 -43.300396) (xy 160.030301 -43.288001) (xy 160.036962 -43.264096) (xy 160.049261 -43.242542)
			(xy 160.057592 -43.23334) (xy 160.067241 -43.223917) (xy 160.090464 -43.21022) (xy 160.116498 -43.20321)
			(xy 160.129982 -43.20286) (xy 160.436814 -43.20286) (xy 160.451176 -43.204093) (xy 160.478321 -43.213752)
			(xy 160.501567 -43.230776) (xy 160.51897 -43.253739) (xy 160.529074 -43.280722) (xy 160.53054 -43.295062)
			(xy 160.53054 -43.481752) (xy 178.891692 -43.481752) (xy 178.891692 -42.618152) (xy 178.892178 -42.590901)
			(xy 178.899934 -42.536953) (xy 178.915289 -42.484658) (xy 178.937931 -42.435081) (xy 178.967397 -42.389231)
			(xy 179.003088 -42.34804) (xy 179.044279 -42.312349) (xy 179.090129 -42.282883) (xy 179.139706 -42.260241)
			(xy 179.192001 -42.244886) (xy 179.245949 -42.23713) (xy 179.300451 -42.23713) (xy 179.354399 -42.244886)
			(xy 179.406694 -42.260241) (xy 179.456271 -42.282883) (xy 179.502121 -42.312349) (xy 179.543312 -42.34804)
			(xy 179.579003 -42.389231) (xy 179.608469 -42.435081) (xy 179.631111 -42.484658) (xy 179.646466 -42.536953)
			(xy 179.654222 -42.590901) (xy 179.654708 -42.618152) (xy 179.654708 -43.481752) (xy 179.654222 -43.509003)
			(xy 179.647839 -43.5534) (xy 353.767583 -43.5534) (xy 353.771544 -43.500544) (xy 353.783339 -43.44887)
			(xy 353.802705 -43.39953) (xy 353.829208 -43.353628) (xy 353.862256 -43.312189) (xy 353.901112 -43.276139)
			(xy 353.944908 -43.246283) (xy 353.992664 -43.223289) (xy 354.043314 -43.207669) (xy 354.095726 -43.199773)
			(xy 354.122228 -43.199304) (xy 354.122736 -43.199304) (xy 354.153713 -43.199978) (xy 354.214715 -43.210807)
			(xy 354.272905 -43.232077) (xy 354.300028 -43.247056) (xy 354.328004 -43.238767) (xy 354.385663 -43.229845)
			(xy 354.414836 -43.229276) (xy 354.99548 -43.229276) (xy 355.004624 -43.225466) (xy 355.025917 -43.217194)
			(xy 355.070087 -43.205543) (xy 355.115388 -43.199665) (xy 355.138228 -43.199304) (xy 355.162681 -43.199729)
			(xy 355.211118 -43.206478) (xy 355.25817 -43.219815) (xy 355.280722 -43.229276) (xy 355.307866 -43.229907)
			(xy 355.361565 -43.237931) (xy 355.413585 -43.253486) (xy 355.462874 -43.276259) (xy 355.508436 -43.305789)
			(xy 355.549352 -43.341481) (xy 355.584795 -43.382612) (xy 355.61405 -43.428352) (xy 355.636524 -43.477777)
			(xy 355.651765 -43.52989) (xy 355.659465 -43.583636) (xy 355.659944 -43.610784) (xy 355.659468 -43.634951)
			(xy 356.178591 -43.634951) (xy 356.178591 -43.580449) (xy 356.186348 -43.526502) (xy 356.201703 -43.474208)
			(xy 356.224344 -43.424632) (xy 356.253811 -43.378783) (xy 356.289502 -43.337594) (xy 356.330692 -43.301903)
			(xy 356.376543 -43.272438) (xy 356.42612 -43.249799) (xy 356.478414 -43.234445) (xy 356.532361 -43.22669)
			(xy 356.559612 -43.226228) (xy 357.423212 -43.226228) (xy 357.450465 -43.226643) (xy 357.504417 -43.234401)
			(xy 357.556715 -43.249759) (xy 357.606295 -43.272403) (xy 357.652149 -43.301872) (xy 357.693341 -43.337567)
			(xy 357.729035 -43.378761) (xy 357.758503 -43.424615) (xy 357.781145 -43.474196) (xy 357.796501 -43.526495)
			(xy 357.804258 -43.580447) (xy 357.804258 -43.634953) (xy 357.803812 -43.638056) (xy 358.339039 -43.638056)
			(xy 358.339039 -43.583544) (xy 358.346797 -43.529588) (xy 358.362156 -43.477285) (xy 358.384802 -43.4277)
			(xy 358.414274 -43.381843) (xy 358.449974 -43.340648) (xy 358.491172 -43.304953) (xy 358.537032 -43.275485)
			(xy 358.586619 -43.252843) (xy 358.638923 -43.23749) (xy 358.69288 -43.229736) (xy 358.720136 -43.229276)
			(xy 359.583736 -43.229276) (xy 359.610984 -43.229797) (xy 359.664926 -43.237557) (xy 359.717214 -43.252915)
			(xy 359.766785 -43.275557) (xy 359.812629 -43.305023) (xy 359.853813 -43.340713) (xy 359.889499 -43.3819)
			(xy 359.91896 -43.427747) (xy 359.941598 -43.47732) (xy 359.956951 -43.529609) (xy 359.964706 -43.583552)
			(xy 359.964706 -43.638048) (xy 359.956951 -43.691991) (xy 359.941598 -43.74428) (xy 359.91896 -43.793853)
			(xy 359.889499 -43.8397) (xy 359.853813 -43.880887) (xy 359.812629 -43.916577) (xy 359.766785 -43.946043)
			(xy 359.717214 -43.968685) (xy 359.664926 -43.984043) (xy 359.610984 -43.991803) (xy 359.583736 -43.992292)
			(xy 358.720136 -43.992292) (xy 358.69288 -43.991864) (xy 358.638923 -43.98411) (xy 358.586619 -43.968757)
			(xy 358.537032 -43.946115) (xy 358.491172 -43.916647) (xy 358.449974 -43.880952) (xy 358.414274 -43.839757)
			(xy 358.384802 -43.7939) (xy 358.362156 -43.744315) (xy 358.346797 -43.692012) (xy 358.339039 -43.638056)
			(xy 357.803812 -43.638056) (xy 357.796501 -43.688905) (xy 357.781145 -43.741204) (xy 357.758503 -43.790785)
			(xy 357.729035 -43.836639) (xy 357.693341 -43.877833) (xy 357.652149 -43.913528) (xy 357.606295 -43.942997)
			(xy 357.556715 -43.965641) (xy 357.504417 -43.980999) (xy 357.450465 -43.988757) (xy 357.423212 -43.989244)
			(xy 356.559612 -43.989244) (xy 356.532361 -43.98871) (xy 356.478414 -43.980955) (xy 356.42612 -43.965601)
			(xy 356.376543 -43.942962) (xy 356.330692 -43.913497) (xy 356.289502 -43.877806) (xy 356.253811 -43.836617)
			(xy 356.224344 -43.790768) (xy 356.201703 -43.741192) (xy 356.186348 -43.688898) (xy 356.178591 -43.634951)
			(xy 355.659468 -43.634951) (xy 355.659407 -43.638033) (xy 355.651654 -43.691977) (xy 355.636302 -43.744269)
			(xy 355.613666 -43.793843) (xy 355.584204 -43.839692) (xy 355.548518 -43.880882) (xy 355.507334 -43.916573)
			(xy 355.461489 -43.946041) (xy 355.411917 -43.968684) (xy 355.359628 -43.984043) (xy 355.305685 -43.991803)
			(xy 355.278436 -43.992292) (xy 354.414836 -43.992292) (xy 354.388369 -43.991825) (xy 354.335944 -43.984518)
			(xy 354.285033 -43.970025) (xy 354.236619 -43.948625) (xy 354.191633 -43.920731) (xy 354.170996 -43.904154)
			(xy 354.158864 -43.905712) (xy 354.134459 -43.907367) (xy 354.122228 -43.907456) (xy 354.095726 -43.907027)
			(xy 354.043314 -43.899131) (xy 353.992664 -43.883511) (xy 353.944908 -43.860517) (xy 353.901112 -43.830661)
			(xy 353.862256 -43.794611) (xy 353.829208 -43.753172) (xy 353.802705 -43.70727) (xy 353.783339 -43.65793)
			(xy 353.771544 -43.606256) (xy 353.767583 -43.5534) (xy 179.647839 -43.5534) (xy 179.646466 -43.562951)
			(xy 179.631111 -43.615246) (xy 179.608469 -43.664823) (xy 179.579003 -43.710673) (xy 179.543312 -43.751864)
			(xy 179.502121 -43.787555) (xy 179.456271 -43.817021) (xy 179.406694 -43.839663) (xy 179.354399 -43.855018)
			(xy 179.300451 -43.862774) (xy 179.245949 -43.862774) (xy 179.192001 -43.855018) (xy 179.139706 -43.839663)
			(xy 179.090129 -43.817021) (xy 179.044279 -43.787555) (xy 179.003088 -43.751864) (xy 178.967397 -43.710673)
			(xy 178.937931 -43.664823) (xy 178.915289 -43.615246) (xy 178.899934 -43.562951) (xy 178.892178 -43.509003)
			(xy 178.891692 -43.481752) (xy 160.53054 -43.481752) (xy 160.53054 -44.221908) (xy 160.531048 -44.221908)
			(xy 160.531048 -44.364656) (xy 160.530794 -44.368466) (xy 160.53054 -44.36999) (xy 160.53054 -44.859956)
			(xy 176.305972 -44.859956) (xy 176.305972 -44.227496) (xy 176.306461 -44.215423) (xy 176.313922 -44.192459)
			(xy 176.328113 -44.172924) (xy 176.347645 -44.158729) (xy 176.370607 -44.151263) (xy 176.38268 -44.150788)
			(xy 177.83556 -44.150788) (xy 177.84764 -44.151247) (xy 177.870621 -44.158703) (xy 177.890172 -44.172897)
			(xy 177.904377 -44.19244) (xy 177.911846 -44.215416) (xy 177.912268 -44.227496) (xy 177.912268 -44.256198)
			(xy 180.05806 -44.256198) (xy 180.05806 -43.925998) (xy 180.058506 -43.913906) (xy 180.065966 -43.890902)
			(xy 180.080157 -43.871321) (xy 180.099696 -43.857071) (xy 180.122678 -43.849543) (xy 180.134768 -43.849036)
			(xy 180.388768 -43.849036) (xy 180.400879 -43.849444) (xy 180.423911 -43.856939) (xy 180.443488 -43.871201)
			(xy 180.457682 -43.890828) (xy 180.465097 -43.913886) (xy 180.465476 -43.925998) (xy 180.465476 -44.256198)
			(xy 180.59146 -44.256198) (xy 180.59146 -43.925998) (xy 180.591906 -43.913906) (xy 180.599366 -43.890902)
			(xy 180.613557 -43.871321) (xy 180.633096 -43.857071) (xy 180.656078 -43.849543) (xy 180.668168 -43.849036)
			(xy 180.922168 -43.849036) (xy 180.934279 -43.849444) (xy 180.957311 -43.856939) (xy 180.976888 -43.871201)
			(xy 180.991082 -43.890828) (xy 180.998497 -43.913886) (xy 180.998876 -43.925998) (xy 180.998876 -44.256198)
			(xy 180.998391 -44.268286) (xy 180.990937 -44.291284) (xy 180.976754 -44.310862) (xy 180.957226 -44.325113)
			(xy 180.934254 -44.332648) (xy 180.922168 -44.33316) (xy 180.668168 -44.33316) (xy 180.656053 -44.33281)
			(xy 180.633018 -44.325297) (xy 180.613442 -44.31102) (xy 180.59925 -44.291382) (xy 180.591837 -44.268314)
			(xy 180.59146 -44.256198) (xy 180.465476 -44.256198) (xy 180.464991 -44.268286) (xy 180.457537 -44.291284)
			(xy 180.443354 -44.310862) (xy 180.423826 -44.325113) (xy 180.400854 -44.332648) (xy 180.388768 -44.33316)
			(xy 180.134768 -44.33316) (xy 180.122653 -44.33281) (xy 180.099618 -44.325297) (xy 180.080042 -44.31102)
			(xy 180.06585 -44.291382) (xy 180.058437 -44.268314) (xy 180.05806 -44.256198) (xy 177.912268 -44.256198)
			(xy 177.912268 -44.859956) (xy 177.911849 -44.87204) (xy 177.904389 -44.895028) (xy 177.890186 -44.914583)
			(xy 177.870632 -44.928787) (xy 177.847644 -44.936249) (xy 177.83556 -44.936664) (xy 176.38268 -44.936664)
			(xy 176.370592 -44.936304) (xy 176.347601 -44.928825) (xy 176.328047 -44.914607) (xy 176.313845 -44.895042)
			(xy 176.306386 -44.872045) (xy 176.305972 -44.859956) (xy 160.53054 -44.859956) (xy 160.53054 -45.022008)
			(xy 160.531048 -45.022008) (xy 160.531048 -45.164756) (xy 160.530729 -45.170598) (xy 180.05806 -45.170598)
			(xy 180.05806 -44.840398) (xy 180.058506 -44.828306) (xy 180.065966 -44.805302) (xy 180.080157 -44.785721)
			(xy 180.099696 -44.771471) (xy 180.122678 -44.763943) (xy 180.134768 -44.763436) (xy 180.388768 -44.763436)
			(xy 180.400879 -44.763844) (xy 180.423911 -44.771339) (xy 180.443488 -44.785601) (xy 180.457682 -44.805228)
			(xy 180.465097 -44.828286) (xy 180.465476 -44.840398) (xy 180.465476 -45.170598) (xy 180.59146 -45.170598)
			(xy 180.59146 -44.840398) (xy 180.591906 -44.828306) (xy 180.599366 -44.805302) (xy 180.613557 -44.785721)
			(xy 180.633096 -44.771471) (xy 180.656078 -44.763943) (xy 180.668168 -44.763436) (xy 180.922168 -44.763436)
			(xy 180.934279 -44.763844) (xy 180.957311 -44.771339) (xy 180.976888 -44.785601) (xy 180.991082 -44.805228)
			(xy 180.998497 -44.828286) (xy 180.998876 -44.840398) (xy 180.998876 -44.980098) (xy 181.659784 -44.980098)
			(xy 181.659784 -44.116498) (xy 181.66027 -44.089247) (xy 181.668026 -44.035299) (xy 181.683381 -43.983004)
			(xy 181.706023 -43.933427) (xy 181.735489 -43.887577) (xy 181.77118 -43.846386) (xy 181.812371 -43.810695)
			(xy 181.858221 -43.781229) (xy 181.907798 -43.758587) (xy 181.960093 -43.743232) (xy 182.014041 -43.735476)
			(xy 182.068543 -43.735476) (xy 182.122491 -43.743232) (xy 182.174786 -43.758587) (xy 182.224363 -43.781229)
			(xy 182.270213 -43.810695) (xy 182.311404 -43.846386) (xy 182.347095 -43.887577) (xy 182.376561 -43.933427)
			(xy 182.399203 -43.983004) (xy 182.414558 -44.035299) (xy 182.422314 -44.089247) (xy 182.4228 -44.116498)
			(xy 182.4228 -44.840452) (xy 348.511075 -44.840452) (xy 348.511075 -44.785948) (xy 348.518832 -44.731999)
			(xy 348.534188 -44.679702) (xy 348.556831 -44.630124) (xy 348.586298 -44.584273) (xy 348.621992 -44.543082)
			(xy 348.663184 -44.50739) (xy 348.709036 -44.477924) (xy 348.758616 -44.455283) (xy 348.810912 -44.439929)
			(xy 348.864862 -44.432174) (xy 348.892114 -44.431712) (xy 349.755714 -44.431712) (xy 349.782966 -44.432159)
			(xy 349.836915 -44.439917) (xy 349.889211 -44.455274) (xy 349.938789 -44.477918) (xy 349.98464 -44.507386)
			(xy 350.025831 -44.543079) (xy 350.061523 -44.584271) (xy 350.090989 -44.630123) (xy 350.11363 -44.679702)
			(xy 350.128986 -44.731999) (xy 350.136742 -44.785948) (xy 350.136742 -44.840452) (xy 350.128986 -44.894401)
			(xy 350.11363 -44.946698) (xy 350.090989 -44.996277) (xy 350.072098 -45.025673) (xy 355.559288 -45.025673)
			(xy 355.559288 -44.971127) (xy 355.56705 -44.917137) (xy 355.582418 -44.864802) (xy 355.605077 -44.815186)
			(xy 355.634567 -44.7693) (xy 355.670288 -44.728078) (xy 355.711511 -44.692359) (xy 355.757398 -44.662871)
			(xy 355.807015 -44.640213) (xy 355.859351 -44.624847) (xy 355.913341 -44.617087) (xy 355.940614 -44.616624)
			(xy 356.804214 -44.616624) (xy 356.831482 -44.617139) (xy 356.885462 -44.624902) (xy 356.937788 -44.640268)
			(xy 356.987394 -44.662925) (xy 357.033272 -44.69241) (xy 357.074486 -44.728124) (xy 357.110199 -44.769339)
			(xy 357.139682 -44.815218) (xy 357.162337 -44.864825) (xy 357.177701 -44.917152) (xy 357.185462 -44.971132)
			(xy 357.185462 -45.025668) (xy 357.177701 -45.079648) (xy 357.162337 -45.131975) (xy 357.139682 -45.181582)
			(xy 357.110199 -45.227461) (xy 357.074486 -45.268676) (xy 357.033272 -45.30439) (xy 356.987394 -45.333875)
			(xy 356.937788 -45.356532) (xy 356.885462 -45.371898) (xy 356.831482 -45.379661) (xy 356.804214 -45.380148)
			(xy 355.940614 -45.380148) (xy 355.913341 -45.379713) (xy 355.859351 -45.371953) (xy 355.807015 -45.356587)
			(xy 355.757398 -45.333929) (xy 355.711511 -45.304441) (xy 355.670288 -45.268722) (xy 355.634567 -45.2275)
			(xy 355.605077 -45.181614) (xy 355.582418 -45.131998) (xy 355.56705 -45.079663) (xy 355.559288 -45.025673)
			(xy 350.072098 -45.025673) (xy 350.061523 -45.042129) (xy 350.025831 -45.083321) (xy 349.98464 -45.119014)
			(xy 349.938789 -45.148482) (xy 349.889211 -45.171126) (xy 349.836915 -45.186483) (xy 349.782966 -45.194241)
			(xy 349.755714 -45.194728) (xy 348.892114 -45.194728) (xy 348.864862 -45.194226) (xy 348.810912 -45.186471)
			(xy 348.758616 -45.171117) (xy 348.709036 -45.148476) (xy 348.663184 -45.11901) (xy 348.621992 -45.083318)
			(xy 348.586298 -45.042127) (xy 348.556831 -44.996276) (xy 348.534188 -44.946698) (xy 348.518832 -44.894401)
			(xy 348.511075 -44.840452) (xy 182.4228 -44.840452) (xy 182.4228 -44.980098) (xy 182.422314 -45.007349)
			(xy 182.414558 -45.061297) (xy 182.399203 -45.113592) (xy 182.376561 -45.163169) (xy 182.347095 -45.209019)
			(xy 182.311404 -45.25021) (xy 182.270213 -45.285901) (xy 182.224363 -45.315367) (xy 182.174786 -45.338009)
			(xy 182.122491 -45.353364) (xy 182.068543 -45.36112) (xy 182.014041 -45.36112) (xy 181.960093 -45.353364)
			(xy 181.907798 -45.338009) (xy 181.858221 -45.315367) (xy 181.812371 -45.285901) (xy 181.77118 -45.25021)
			(xy 181.735489 -45.209019) (xy 181.706023 -45.163169) (xy 181.683381 -45.113592) (xy 181.668026 -45.061297)
			(xy 181.66027 -45.007349) (xy 181.659784 -44.980098) (xy 180.998876 -44.980098) (xy 180.998876 -45.170598)
			(xy 180.998391 -45.182686) (xy 180.990937 -45.205684) (xy 180.976754 -45.225262) (xy 180.957226 -45.239513)
			(xy 180.934254 -45.247048) (xy 180.922168 -45.24756) (xy 180.668168 -45.24756) (xy 180.656053 -45.24721)
			(xy 180.633018 -45.239697) (xy 180.613442 -45.22542) (xy 180.59925 -45.205782) (xy 180.591837 -45.182714)
			(xy 180.59146 -45.170598) (xy 180.465476 -45.170598) (xy 180.464991 -45.182686) (xy 180.457537 -45.205684)
			(xy 180.443354 -45.225262) (xy 180.423826 -45.239513) (xy 180.400854 -45.247048) (xy 180.388768 -45.24756)
			(xy 180.134768 -45.24756) (xy 180.122653 -45.24721) (xy 180.099618 -45.239697) (xy 180.080042 -45.22542)
			(xy 180.06585 -45.205782) (xy 180.058437 -45.182714) (xy 180.05806 -45.170598) (xy 160.530729 -45.170598)
			(xy 160.530372 -45.177149) (xy 160.523723 -45.201053) (xy 160.511434 -45.222608) (xy 160.503108 -45.231812)
			(xy 160.493452 -45.241227) (xy 160.470233 -45.254929) (xy 160.444201 -45.261941) (xy 160.430718 -45.262292)
			(xy 160.123886 -45.262292) (xy 160.110137 -45.261224) (xy 160.084035 -45.252351) (xy 160.061371 -45.236655)
			(xy 160.043883 -45.215341) (xy 160.032917 -45.190047) (xy 160.030668 -45.17644) (xy 160.029652 -45.169836)
			(xy 160.029652 -44.996862) (xy 160.029169 -44.98313) (xy 160.021806 -44.956671) (xy 160.007652 -44.933135)
			(xy 159.987732 -44.914227) (xy 159.96349 -44.901319) (xy 159.936683 -44.895346) (xy 159.909253 -44.89674)
			(xy 159.88319 -44.905401) (xy 159.860382 -44.920701) (xy 159.85109 -44.930822) (xy 159.832877 -44.95127)
			(xy 159.791621 -44.987276) (xy 159.745639 -45.01701) (xy 159.695877 -45.039863) (xy 159.643359 -45.055363)
			(xy 159.589163 -45.063192) (xy 159.561784 -45.063664) (xy 159.56153 -45.063664) (xy 159.534825 -45.063165)
			(xy 159.481939 -45.055709) (xy 159.43061 -45.04095) (xy 159.381839 -45.019179) (xy 159.336581 -44.990821)
			(xy 159.295718 -44.956428) (xy 159.260051 -44.916674) (xy 159.244792 -44.894754) (xy 159.229552 -44.872402)
			(xy 159.151828 -44.872402) (xy 159.151828 -45.164756) (xy 159.151206 -45.177136) (xy 159.144637 -45.201029)
			(xy 159.13243 -45.222594) (xy 159.124142 -45.231812) (xy 159.114472 -45.241211) (xy 159.09126 -45.254917)
			(xy 159.065233 -45.261937) (xy 159.051752 -45.262292) (xy 158.74492 -45.262292) (xy 158.731175 -45.261197)
			(xy 158.705073 -45.252332) (xy 158.682408 -45.236643) (xy 158.66492 -45.215335) (xy 158.653952 -45.190045)
			(xy 158.651702 -45.17644) (xy 158.65094 -45.169836) (xy 157.311852 -45.169836) (xy 157.311852 -45.994828)
			(xy 157.311209 -46.007206) (xy 157.304648 -46.031098) (xy 157.292449 -46.052664) (xy 157.284166 -46.061884)
			(xy 157.274481 -46.071267) (xy 157.251277 -46.08498) (xy 157.225255 -46.092006) (xy 157.211776 -46.092364)
			(xy 156.904944 -46.092364) (xy 156.891209 -46.091189) (xy 156.865117 -46.082338) (xy 156.842455 -46.066667)
			(xy 156.824964 -46.045379) (xy 156.813984 -46.020109) (xy 156.811726 -46.006512) (xy 156.810964 -45.999908)
			(xy 156.810964 -45.98162) (xy 156.810594 -45.96809) (xy 156.803465 -45.941986) (xy 156.78973 -45.918671)
			(xy 156.770352 -45.899784) (xy 156.746694 -45.886649) (xy 156.720416 -45.880191) (xy 156.693364 -45.880862)
			(xy 156.667439 -45.888615) (xy 156.64446 -45.902907) (xy 156.634942 -45.912532) (xy 156.616875 -45.93135)
			(xy 156.576429 -45.964301) (xy 156.531874 -45.991438) (xy 156.484038 -46.012255) (xy 156.433813 -46.026364)
			(xy 156.382134 -46.033502) (xy 156.35605 -46.033944) (xy 156.355542 -46.033944) (xy 156.327641 -46.033384)
			(xy 156.272433 -46.025252) (xy 156.218998 -46.00917) (xy 156.168472 -45.98548) (xy 156.121934 -45.954688)
			(xy 156.080374 -45.917449) (xy 156.044678 -45.874556) (xy 156.015606 -45.826924) (xy 155.993778 -45.775567)
			(xy 155.986226 -45.748702) (xy 155.97632 -45.710602) (xy 155.886404 -45.710602) (xy 155.886404 -45.984668)
			(xy 155.885769 -45.997046) (xy 155.879202 -46.020938) (xy 155.867001 -46.042504) (xy 155.858718 -46.051724)
			(xy 155.849059 -46.061136) (xy 155.825842 -46.074838) (xy 155.79981 -46.081852) (xy 155.786328 -46.082204)
			(xy 155.479496 -46.082204) (xy 155.46575 -46.081118) (xy 155.439649 -46.072249) (xy 155.416985 -46.056557)
			(xy 155.399497 -46.035248) (xy 155.388528 -46.009958) (xy 155.386278 -45.996352) (xy 155.385516 -45.989748)
			(xy 155.385516 -45.192442) (xy 155.3845 -45.184314) (xy 96.73394 -45.184314) (xy 96.736452 -45.187325)
			(xy 96.829216 -45.310943) (xy 96.915495 -45.439171) (xy 96.995057 -45.571672) (xy 97.067693 -45.708092)
			(xy 97.133211 -45.848071) (xy 97.191435 -45.991237) (xy 97.242212 -46.13721) (xy 97.285407 -46.285604)
			(xy 97.302923 -46.359826) (xy 176.305972 -46.359826) (xy 176.305972 -45.727366) (xy 176.306379 -45.715271)
			(xy 176.313849 -45.692264) (xy 176.32805 -45.672682) (xy 176.347598 -45.658434) (xy 176.370587 -45.650908)
			(xy 176.38268 -45.650404) (xy 177.83556 -45.650404) (xy 177.847667 -45.650851) (xy 177.870694 -45.658339)
			(xy 177.890268 -45.672593) (xy 177.904464 -45.692209) (xy 177.911885 -45.715258) (xy 177.912268 -45.727366)
			(xy 177.912268 -46.359826) (xy 177.911815 -46.371916) (xy 177.904352 -46.394916) (xy 177.890162 -46.414495)
			(xy 177.870626 -46.428745) (xy 177.847649 -46.436278) (xy 177.83556 -46.436788) (xy 176.38268 -46.436788)
			(xy 176.370569 -46.436401) (xy 176.347539 -46.428894) (xy 176.327965 -46.414626) (xy 176.313772 -46.394997)
			(xy 176.306353 -46.371939) (xy 176.305972 -46.359826) (xy 97.302923 -46.359826) (xy 97.320906 -46.436025)
			(xy 97.329238 -46.481746) (xy 178.630072 -46.481746) (xy 178.630072 -45.618146) (xy 178.630558 -45.590895)
			(xy 178.638314 -45.536947) (xy 178.653669 -45.484652) (xy 178.676311 -45.435075) (xy 178.705777 -45.389225)
			(xy 178.741468 -45.348034) (xy 178.782659 -45.312343) (xy 178.828509 -45.282877) (xy 178.878086 -45.260235)
			(xy 178.930381 -45.24488) (xy 178.984329 -45.237124) (xy 179.038831 -45.237124) (xy 179.092779 -45.24488)
			(xy 179.145074 -45.260235) (xy 179.194651 -45.282877) (xy 179.240501 -45.312343) (xy 179.281692 -45.348034)
			(xy 179.317383 -45.389225) (xy 179.346849 -45.435075) (xy 179.369491 -45.484652) (xy 179.384846 -45.536947)
			(xy 179.392602 -45.590895) (xy 179.393088 -45.618146) (xy 179.393088 -46.481746) (xy 179.392602 -46.508997)
			(xy 179.384846 -46.562945) (xy 179.369491 -46.61524) (xy 179.346849 -46.664817) (xy 179.317383 -46.710667)
			(xy 179.281692 -46.751858) (xy 179.240501 -46.787549) (xy 179.194651 -46.817015) (xy 179.145074 -46.839657)
			(xy 179.092779 -46.855012) (xy 179.038831 -46.862768) (xy 178.984329 -46.862768) (xy 178.930381 -46.855012)
			(xy 178.878086 -46.839657) (xy 178.828509 -46.817015) (xy 178.782659 -46.787549) (xy 178.741468 -46.751858)
			(xy 178.705777 -46.710667) (xy 178.676311 -46.664817) (xy 178.653669 -46.61524) (xy 178.638314 -46.562945)
			(xy 178.630558 -46.508997) (xy 178.630072 -46.481746) (xy 97.329238 -46.481746) (xy 97.348615 -46.588073)
			(xy 97.368459 -46.741347) (xy 97.380387 -46.895438) (xy 97.384366 -47.04994) (xy 97.380387 -47.204442)
			(xy 97.368459 -47.358533) (xy 97.348615 -47.511807) (xy 97.320906 -47.663855) (xy 97.285407 -47.814276)
			(xy 97.242212 -47.96267) (xy 97.239575 -47.97025) (xy 155.567386 -47.97025) (xy 155.567386 -47.91575)
			(xy 155.575142 -47.861805) (xy 155.590495 -47.809513) (xy 155.613135 -47.759938) (xy 155.642598 -47.71409)
			(xy 155.678287 -47.672901) (xy 155.719474 -47.63721) (xy 155.765321 -47.607744) (xy 155.814895 -47.585102)
			(xy 155.867186 -47.569746) (xy 155.92113 -47.561987) (xy 155.94838 -47.5615) (xy 156.81198 -47.5615)
			(xy 156.839234 -47.561946) (xy 156.893189 -47.569701) (xy 156.94549 -47.585055) (xy 156.995074 -47.607697)
			(xy 157.04093 -47.637165) (xy 157.082126 -47.67286) (xy 157.117823 -47.714054) (xy 157.147293 -47.759909)
			(xy 157.169938 -47.809491) (xy 157.185295 -47.861792) (xy 157.193053 -47.915746) (xy 157.193053 -47.970249)
			(xy 158.785586 -47.970249) (xy 158.785586 -47.915751) (xy 158.793341 -47.861808) (xy 158.808694 -47.809518)
			(xy 158.831331 -47.759944) (xy 158.860793 -47.714097) (xy 158.89648 -47.672908) (xy 158.937664 -47.637217)
			(xy 158.983509 -47.607751) (xy 159.03308 -47.585108) (xy 159.085369 -47.569749) (xy 159.139311 -47.561988)
			(xy 159.16656 -47.5615) (xy 160.03016 -47.5615) (xy 160.057415 -47.561945) (xy 160.111372 -47.569697)
			(xy 160.163675 -47.58505) (xy 160.213262 -47.607691) (xy 160.259121 -47.637158) (xy 160.300319 -47.672853)
			(xy 160.336018 -47.714047) (xy 160.36549 -47.759903) (xy 160.388136 -47.809487) (xy 160.402954 -47.85995)
			(xy 176.305972 -47.85995) (xy 176.305972 -47.22749) (xy 176.3064 -47.215397) (xy 176.313863 -47.192391)
			(xy 176.328059 -47.172808) (xy 176.347602 -47.158559) (xy 176.370588 -47.151033) (xy 176.38268 -47.150528)
			(xy 177.83556 -47.150528) (xy 177.84767 -47.150951) (xy 177.8707 -47.158443) (xy 177.890277 -47.172701)
			(xy 177.904472 -47.192324) (xy 177.911888 -47.215379) (xy 177.912268 -47.22749) (xy 177.912268 -47.304198)
			(xy 180.05806 -47.304198) (xy 180.05806 -46.973998) (xy 180.058506 -46.961906) (xy 180.065966 -46.938902)
			(xy 180.080157 -46.919321) (xy 180.099696 -46.905071) (xy 180.122678 -46.897543) (xy 180.134768 -46.897036)
			(xy 180.388768 -46.897036) (xy 180.400879 -46.897444) (xy 180.423911 -46.904939) (xy 180.443488 -46.919201)
			(xy 180.457682 -46.938828) (xy 180.465097 -46.961886) (xy 180.465476 -46.973998) (xy 180.465476 -47.304198)
			(xy 180.59146 -47.304198) (xy 180.59146 -46.973998) (xy 180.591906 -46.961906) (xy 180.599366 -46.938902)
			(xy 180.613557 -46.919321) (xy 180.633096 -46.905071) (xy 180.656078 -46.897543) (xy 180.668168 -46.897036)
			(xy 180.922168 -46.897036) (xy 180.934279 -46.897444) (xy 180.957311 -46.904939) (xy 180.976888 -46.919201)
			(xy 180.991082 -46.938828) (xy 180.998497 -46.961886) (xy 180.998876 -46.973998) (xy 180.998876 -47.304198)
			(xy 180.998391 -47.316286) (xy 180.990937 -47.339284) (xy 180.976754 -47.358862) (xy 180.957226 -47.373113)
			(xy 180.934254 -47.380648) (xy 180.922168 -47.38116) (xy 180.668168 -47.38116) (xy 180.656053 -47.38081)
			(xy 180.633018 -47.373297) (xy 180.613442 -47.35902) (xy 180.59925 -47.339382) (xy 180.591837 -47.316314)
			(xy 180.59146 -47.304198) (xy 180.465476 -47.304198) (xy 180.464991 -47.316286) (xy 180.457537 -47.339284)
			(xy 180.443354 -47.358862) (xy 180.423826 -47.373113) (xy 180.400854 -47.380648) (xy 180.388768 -47.38116)
			(xy 180.134768 -47.38116) (xy 180.122653 -47.38081) (xy 180.099618 -47.373297) (xy 180.080042 -47.35902)
			(xy 180.06585 -47.339382) (xy 180.058437 -47.316314) (xy 180.05806 -47.304198) (xy 177.912268 -47.304198)
			(xy 177.912268 -47.85995) (xy 177.91175 -47.872036) (xy 177.904308 -47.895034) (xy 177.890135 -47.914614)
			(xy 177.870612 -47.928867) (xy 177.847644 -47.936401) (xy 177.83556 -47.936912) (xy 176.38268 -47.936912)
			(xy 176.370571 -47.936501) (xy 176.347545 -47.928997) (xy 176.327974 -47.914734) (xy 176.313779 -47.895112)
			(xy 176.306357 -47.87206) (xy 176.305972 -47.85995) (xy 160.402954 -47.85995) (xy 160.403494 -47.861789)
			(xy 160.411253 -47.915745) (xy 160.411253 -47.970255) (xy 160.403494 -48.024211) (xy 160.388136 -48.076513)
			(xy 160.36549 -48.126097) (xy 160.336018 -48.171953) (xy 160.300319 -48.213147) (xy 160.294028 -48.218598)
			(xy 180.05806 -48.218598) (xy 180.05806 -47.888398) (xy 180.058506 -47.876306) (xy 180.065966 -47.853302)
			(xy 180.080157 -47.833721) (xy 180.099696 -47.819471) (xy 180.122678 -47.811943) (xy 180.134768 -47.811436)
			(xy 180.388768 -47.811436) (xy 180.400879 -47.811844) (xy 180.423911 -47.819339) (xy 180.443488 -47.833601)
			(xy 180.457682 -47.853228) (xy 180.465097 -47.876286) (xy 180.465476 -47.888398) (xy 180.465476 -48.218598)
			(xy 180.59146 -48.218598) (xy 180.59146 -47.888398) (xy 180.591906 -47.876306) (xy 180.599366 -47.853302)
			(xy 180.613557 -47.833721) (xy 180.633096 -47.819471) (xy 180.656078 -47.811943) (xy 180.668168 -47.811436)
			(xy 180.922168 -47.811436) (xy 180.934279 -47.811844) (xy 180.957311 -47.819339) (xy 180.976888 -47.833601)
			(xy 180.991082 -47.853228) (xy 180.998497 -47.876286) (xy 180.998876 -47.888398) (xy 180.998876 -48.028098)
			(xy 181.659784 -48.028098) (xy 181.659784 -47.164498) (xy 181.66027 -47.137247) (xy 181.668026 -47.083299)
			(xy 181.683381 -47.031004) (xy 181.706023 -46.981427) (xy 181.735489 -46.935577) (xy 181.77118 -46.894386)
			(xy 181.812371 -46.858695) (xy 181.858221 -46.829229) (xy 181.907798 -46.806587) (xy 181.960093 -46.791232)
			(xy 182.014041 -46.783476) (xy 182.068543 -46.783476) (xy 182.122491 -46.791232) (xy 182.174786 -46.806587)
			(xy 182.224363 -46.829229) (xy 182.225669 -46.830068) (xy 356.445326 -46.830068) (xy 356.445326 -46.775532)
			(xy 356.453087 -46.721552) (xy 356.468451 -46.669225) (xy 356.491104 -46.619618) (xy 356.520587 -46.573739)
			(xy 356.556298 -46.532522) (xy 356.597512 -46.496807) (xy 356.643388 -46.467321) (xy 356.692994 -46.444663)
			(xy 356.745319 -46.429294) (xy 356.799298 -46.421529) (xy 356.826566 -46.42104) (xy 357.690166 -46.42104)
			(xy 357.717439 -46.421497) (xy 357.77143 -46.429255) (xy 357.823767 -46.444619) (xy 357.873384 -46.467275)
			(xy 357.919272 -46.496761) (xy 357.960497 -46.532479) (xy 357.996218 -46.5737) (xy 358.025709 -46.619586)
			(xy 358.048369 -46.669202) (xy 358.063737 -46.721537) (xy 358.0715 -46.775527) (xy 358.0715 -46.830069)
			(xy 358.762026 -46.830069) (xy 358.762026 -46.775531) (xy 358.769788 -46.721547) (xy 358.785153 -46.669218)
			(xy 358.807809 -46.619608) (xy 358.837295 -46.573728) (xy 358.87301 -46.53251) (xy 358.914228 -46.496795)
			(xy 358.960108 -46.467309) (xy 359.009718 -46.444653) (xy 359.062047 -46.429288) (xy 359.116031 -46.421526)
			(xy 359.1433 -46.42104) (xy 360.0069 -46.42104) (xy 360.03417 -46.421522) (xy 360.088153 -46.429284)
			(xy 360.140483 -46.44465) (xy 360.190094 -46.467306) (xy 360.235975 -46.496792) (xy 360.277193 -46.532507)
			(xy 360.312908 -46.573725) (xy 360.342394 -46.619606) (xy 360.36505 -46.669217) (xy 360.380416 -46.721547)
			(xy 360.388178 -46.77553) (xy 360.388178 -46.83007) (xy 360.388178 -46.830073) (xy 361.088604 -46.830073)
			(xy 361.088604 -46.775527) (xy 361.096367 -46.721537) (xy 361.111735 -46.669202) (xy 361.134395 -46.619586)
			(xy 361.163887 -46.573701) (xy 361.199608 -46.53248) (xy 361.240833 -46.496763) (xy 361.286721 -46.467276)
			(xy 361.336339 -46.444621) (xy 361.388676 -46.429258) (xy 361.442667 -46.421501) (xy 361.46994 -46.42104)
			(xy 362.33354 -46.42104) (xy 362.360808 -46.421525) (xy 362.414787 -46.429291) (xy 362.467112 -46.44466)
			(xy 362.516718 -46.467319) (xy 362.562594 -46.496806) (xy 362.603807 -46.532522) (xy 362.639518 -46.573738)
			(xy 362.669 -46.619618) (xy 362.691654 -46.669225) (xy 362.707017 -46.721552) (xy 362.714778 -46.775532)
			(xy 362.714778 -46.830068) (xy 362.707017 -46.884048) (xy 362.691654 -46.936375) (xy 362.672751 -46.977768)
			(xy 396.642323 -46.977768) (xy 396.642323 -46.891996) (xy 396.650237 -46.806588) (xy 396.665998 -46.722276)
			(xy 396.689471 -46.639777) (xy 396.720456 -46.559796) (xy 396.758688 -46.483015) (xy 396.803842 -46.41009)
			(xy 396.855532 -46.341642) (xy 396.913317 -46.278255) (xy 396.976704 -46.22047) (xy 397.045152 -46.16878)
			(xy 397.118077 -46.123626) (xy 397.194858 -46.085394) (xy 397.274839 -46.054409) (xy 397.357338 -46.030936)
			(xy 397.44165 -46.015175) (xy 397.527058 -46.007261) (xy 397.61283 -46.007261) (xy 397.698238 -46.015175)
			(xy 397.78255 -46.030936) (xy 397.865049 -46.054409) (xy 397.94503 -46.085394) (xy 398.021811 -46.123626)
			(xy 398.094736 -46.16878) (xy 398.163184 -46.22047) (xy 398.226571 -46.278255) (xy 398.284356 -46.341642)
			(xy 398.336046 -46.41009) (xy 398.3812 -46.483015) (xy 398.419432 -46.559796) (xy 398.450417 -46.639777)
			(xy 398.47389 -46.722276) (xy 398.489651 -46.806588) (xy 398.497565 -46.891996) (xy 398.49806 -46.934882)
			(xy 398.497565 -46.977768) (xy 398.489651 -47.063176) (xy 398.47389 -47.147488) (xy 398.450417 -47.229987)
			(xy 398.419432 -47.309968) (xy 398.3812 -47.386749) (xy 398.336046 -47.459674) (xy 398.284356 -47.528122)
			(xy 398.226571 -47.591509) (xy 398.163184 -47.649294) (xy 398.094736 -47.700984) (xy 398.021811 -47.746138)
			(xy 397.94503 -47.78437) (xy 397.865049 -47.815355) (xy 397.78255 -47.838828) (xy 397.698238 -47.854589)
			(xy 397.61283 -47.862503) (xy 397.527058 -47.862503) (xy 397.44165 -47.854589) (xy 397.357338 -47.838828)
			(xy 397.274839 -47.815355) (xy 397.194858 -47.78437) (xy 397.118077 -47.746138) (xy 397.045152 -47.700984)
			(xy 396.976704 -47.649294) (xy 396.913317 -47.591509) (xy 396.855532 -47.528122) (xy 396.803842 -47.459674)
			(xy 396.758688 -47.386749) (xy 396.720456 -47.309968) (xy 396.689471 -47.229987) (xy 396.665998 -47.147488)
			(xy 396.650237 -47.063176) (xy 396.642323 -46.977768) (xy 362.672751 -46.977768) (xy 362.669 -46.985982)
			(xy 362.639518 -47.031862) (xy 362.603807 -47.073078) (xy 362.562594 -47.108794) (xy 362.516718 -47.138281)
			(xy 362.467112 -47.16094) (xy 362.414787 -47.176309) (xy 362.360808 -47.184075) (xy 362.33354 -47.184564)
			(xy 361.46994 -47.184564) (xy 361.442667 -47.184099) (xy 361.388676 -47.176342) (xy 361.336339 -47.160979)
			(xy 361.286721 -47.138324) (xy 361.240833 -47.108837) (xy 361.199608 -47.07312) (xy 361.163887 -47.031899)
			(xy 361.134395 -46.986014) (xy 361.111735 -46.936398) (xy 361.096367 -46.884063) (xy 361.088604 -46.830073)
			(xy 360.388178 -46.830073) (xy 360.380416 -46.884053) (xy 360.36505 -46.936383) (xy 360.342394 -46.985994)
			(xy 360.312908 -47.031875) (xy 360.277193 -47.073093) (xy 360.235975 -47.108808) (xy 360.190094 -47.138294)
			(xy 360.140483 -47.16095) (xy 360.088153 -47.176316) (xy 360.03417 -47.184078) (xy 360.0069 -47.184564)
			(xy 359.1433 -47.184564) (xy 359.116031 -47.184074) (xy 359.062047 -47.176312) (xy 359.009718 -47.160947)
			(xy 358.960108 -47.138291) (xy 358.914228 -47.108805) (xy 358.87301 -47.07309) (xy 358.837295 -47.031872)
			(xy 358.807809 -46.985992) (xy 358.785153 -46.936382) (xy 358.769788 -46.884053) (xy 358.762026 -46.830069)
			(xy 358.0715 -46.830069) (xy 358.0715 -46.830073) (xy 358.063737 -46.884063) (xy 358.048369 -46.936398)
			(xy 358.025709 -46.986014) (xy 357.996218 -47.0319) (xy 357.960497 -47.073121) (xy 357.919272 -47.108839)
			(xy 357.873384 -47.138325) (xy 357.823767 -47.160981) (xy 357.77143 -47.176345) (xy 357.717439 -47.184103)
			(xy 357.690166 -47.184564) (xy 356.826566 -47.184564) (xy 356.799298 -47.184071) (xy 356.745319 -47.176306)
			(xy 356.692994 -47.160937) (xy 356.643388 -47.138279) (xy 356.597512 -47.108793) (xy 356.556298 -47.073078)
			(xy 356.520587 -47.031861) (xy 356.491104 -46.985982) (xy 356.468451 -46.936375) (xy 356.453087 -46.884048)
			(xy 356.445326 -46.830068) (xy 182.225669 -46.830068) (xy 182.270213 -46.858695) (xy 182.311404 -46.894386)
			(xy 182.347095 -46.935577) (xy 182.376561 -46.981427) (xy 182.399203 -47.031004) (xy 182.414558 -47.083299)
			(xy 182.422314 -47.137247) (xy 182.4228 -47.164498) (xy 182.4228 -48.028098) (xy 182.422314 -48.055349)
			(xy 182.414558 -48.109297) (xy 182.399203 -48.161592) (xy 182.376561 -48.211169) (xy 182.347095 -48.257019)
			(xy 182.311404 -48.29821) (xy 182.270213 -48.333901) (xy 182.224363 -48.363367) (xy 182.174786 -48.386009)
			(xy 182.122491 -48.401364) (xy 182.068543 -48.40912) (xy 182.014041 -48.40912) (xy 181.960093 -48.401364)
			(xy 181.907798 -48.386009) (xy 181.858221 -48.363367) (xy 181.812371 -48.333901) (xy 181.77118 -48.29821)
			(xy 181.735489 -48.257019) (xy 181.706023 -48.211169) (xy 181.683381 -48.161592) (xy 181.668026 -48.109297)
			(xy 181.66027 -48.055349) (xy 181.659784 -48.028098) (xy 180.998876 -48.028098) (xy 180.998876 -48.218598)
			(xy 180.998391 -48.230686) (xy 180.990937 -48.253684) (xy 180.976754 -48.273262) (xy 180.957226 -48.287513)
			(xy 180.934254 -48.295048) (xy 180.922168 -48.29556) (xy 180.668168 -48.29556) (xy 180.656053 -48.29521)
			(xy 180.633018 -48.287697) (xy 180.613442 -48.27342) (xy 180.59925 -48.253782) (xy 180.591837 -48.230714)
			(xy 180.59146 -48.218598) (xy 180.465476 -48.218598) (xy 180.464991 -48.230686) (xy 180.457537 -48.253684)
			(xy 180.443354 -48.273262) (xy 180.423826 -48.287513) (xy 180.400854 -48.295048) (xy 180.388768 -48.29556)
			(xy 180.134768 -48.29556) (xy 180.122653 -48.29521) (xy 180.099618 -48.287697) (xy 180.080042 -48.27342)
			(xy 180.06585 -48.253782) (xy 180.058437 -48.230714) (xy 180.05806 -48.218598) (xy 160.294028 -48.218598)
			(xy 160.259121 -48.248842) (xy 160.213262 -48.278309) (xy 160.163675 -48.30095) (xy 160.111372 -48.316303)
			(xy 160.057415 -48.324055) (xy 160.03016 -48.324516) (xy 159.16656 -48.324516) (xy 159.139311 -48.324012)
			(xy 159.085369 -48.316251) (xy 159.03308 -48.300892) (xy 158.983509 -48.278249) (xy 158.937664 -48.248783)
			(xy 158.89648 -48.213092) (xy 158.860793 -48.171903) (xy 158.831331 -48.126056) (xy 158.808694 -48.076482)
			(xy 158.793341 -48.024192) (xy 158.785586 -47.970249) (xy 157.193053 -47.970249) (xy 157.193053 -47.970254)
			(xy 157.185295 -48.024208) (xy 157.169938 -48.076509) (xy 157.147293 -48.126091) (xy 157.117823 -48.171946)
			(xy 157.082126 -48.21314) (xy 157.04093 -48.248835) (xy 156.995074 -48.278303) (xy 156.94549 -48.300945)
			(xy 156.893189 -48.316299) (xy 156.839234 -48.324054) (xy 156.81198 -48.324516) (xy 155.94838 -48.324516)
			(xy 155.92113 -48.324013) (xy 155.867186 -48.316254) (xy 155.814895 -48.300898) (xy 155.765321 -48.278256)
			(xy 155.719474 -48.24879) (xy 155.678287 -48.213099) (xy 155.642598 -48.17191) (xy 155.613135 -48.126062)
			(xy 155.590495 -48.076487) (xy 155.575142 -48.024195) (xy 155.567386 -47.97025) (xy 97.239575 -47.97025)
			(xy 97.191435 -48.108643) (xy 97.133211 -48.251809) (xy 97.067693 -48.391788) (xy 96.995057 -48.528208)
			(xy 96.915495 -48.660709) (xy 96.829216 -48.788937) (xy 96.736452 -48.912555) (xy 96.637446 -49.031233)
			(xy 96.532463 -49.144657) (xy 96.421779 -49.252526) (xy 96.30569 -49.354554) (xy 96.299037 -49.35982)
			(xy 176.305972 -49.35982) (xy 176.305972 -48.72736) (xy 176.30643 -48.715285) (xy 176.313901 -48.69232)
			(xy 176.3281 -48.672785) (xy 176.347638 -48.658592) (xy 176.370605 -48.651126) (xy 176.38268 -48.650652)
			(xy 177.83556 -48.650652) (xy 177.847629 -48.651198) (xy 177.870588 -48.658644) (xy 177.890122 -48.672821)
			(xy 177.904319 -48.692341) (xy 177.91179 -48.715292) (xy 177.912268 -48.72736) (xy 177.912268 -49.35982)
			(xy 177.911904 -49.371908) (xy 177.904426 -49.394898) (xy 177.890209 -49.414451) (xy 177.870644 -49.428653)
			(xy 177.847648 -49.436113) (xy 177.83556 -49.436528) (xy 176.38268 -49.436528) (xy 176.370606 -49.436053)
			(xy 176.347642 -49.428587) (xy 176.328107 -49.414393) (xy 176.313913 -49.394858) (xy 176.306447 -49.371894)
			(xy 176.305972 -49.35982) (xy 96.299037 -49.35982) (xy 96.184502 -49.450471) (xy 96.140518 -49.48174)
			(xy 178.630072 -49.48174) (xy 178.630072 -48.61814) (xy 178.630558 -48.590889) (xy 178.638314 -48.536941)
			(xy 178.653669 -48.484646) (xy 178.676311 -48.435069) (xy 178.705777 -48.389219) (xy 178.741468 -48.348028)
			(xy 178.782659 -48.312337) (xy 178.828509 -48.282871) (xy 178.878086 -48.260229) (xy 178.930381 -48.244874)
			(xy 178.984329 -48.237118) (xy 179.038831 -48.237118) (xy 179.092779 -48.244874) (xy 179.145074 -48.260229)
			(xy 179.194651 -48.282871) (xy 179.240501 -48.312337) (xy 179.281692 -48.348028) (xy 179.317383 -48.389219)
			(xy 179.346849 -48.435069) (xy 179.369491 -48.484646) (xy 179.384846 -48.536941) (xy 179.392602 -48.590889)
			(xy 179.393088 -48.61814) (xy 179.393088 -49.48174) (xy 179.392602 -49.508991) (xy 179.384846 -49.562939)
			(xy 179.369491 -49.615234) (xy 179.346849 -49.664811) (xy 179.317383 -49.710661) (xy 179.281692 -49.751852)
			(xy 179.240501 -49.787543) (xy 179.194651 -49.817009) (xy 179.145074 -49.839651) (xy 179.092779 -49.855006)
			(xy 179.038831 -49.862762) (xy 178.984329 -49.862762) (xy 178.930381 -49.855006) (xy 178.878086 -49.839651)
			(xy 178.828509 -49.817009) (xy 178.782659 -49.787543) (xy 178.741468 -49.751852) (xy 178.705777 -49.710661)
			(xy 178.676311 -49.664811) (xy 178.653669 -49.615234) (xy 178.638314 -49.562939) (xy 178.630558 -49.508991)
			(xy 178.630072 -49.48174) (xy 96.140518 -49.48174) (xy 96.058537 -49.540022) (xy 95.928129 -49.62297)
			(xy 95.793624 -49.699095) (xy 95.655379 -49.768194) (xy 95.513759 -49.830085) (xy 95.369142 -49.884604)
			(xy 95.221909 -49.931606) (xy 95.072452 -49.970966) (xy 94.921168 -50.00258) (xy 94.768456 -50.026364)
			(xy 94.614722 -50.042255) (xy 94.460374 -50.050211) (xy 94.383098 -50.0507) (xy 92.782898 -50.0507)
			(xy 92.705622 -50.050194) (xy 92.551275 -50.042238) (xy 92.397543 -50.026347) (xy 92.244832 -50.002563)
			(xy 92.093548 -49.970949) (xy 91.944092 -49.931589) (xy 91.796861 -49.884587) (xy 91.652244 -49.830069)
			(xy 91.510626 -49.768178) (xy 91.372381 -49.699079) (xy 91.237877 -49.622954) (xy 91.10747 -49.540007)
			(xy 90.981506 -49.450456) (xy 90.860319 -49.35454) (xy 90.74423 -49.252512) (xy 90.633548 -49.144644)
			(xy 90.528565 -49.031221) (xy 90.42956 -48.912543) (xy 90.336796 -48.788927) (xy 90.250519 -48.660699)
			(xy 90.170957 -48.528199) (xy 90.098321 -48.391779) (xy 90.032804 -48.251802) (xy 89.97458 -48.108637)
			(xy 89.923803 -47.962664) (xy 89.880608 -47.814271) (xy 89.84511 -47.663852) (xy 89.817402 -47.511804)
			(xy 89.797557 -47.358531) (xy 89.78563 -47.204441) (xy 89.78165 -47.04994) (xy 67.384154 -47.04994)
			(xy 67.384157 -47.050067) (xy 67.380172 -47.204564) (xy 67.368238 -47.35865) (xy 67.348389 -47.511918)
			(xy 67.320675 -47.663961) (xy 67.285172 -47.814376) (xy 67.241973 -47.962763) (xy 67.191193 -48.108731)
			(xy 67.132966 -48.25189) (xy 67.067447 -48.391863) (xy 66.994809 -48.528277) (xy 66.915245 -48.660771)
			(xy 66.828966 -48.788993) (xy 66.736201 -48.912605) (xy 66.637196 -49.031277) (xy 66.532213 -49.144695)
			(xy 66.421531 -49.252559) (xy 66.305444 -49.354582) (xy 66.184258 -49.450493) (xy 66.058295 -49.54004)
			(xy 65.927891 -49.622983) (xy 65.793389 -49.699104) (xy 65.655147 -49.768199) (xy 65.513531 -49.830087)
			(xy 65.368918 -49.884603) (xy 65.22169 -49.931602) (xy 65.072237 -49.970961) (xy 64.920957 -50.002573)
			(xy 64.76825 -50.026356) (xy 64.614521 -50.042247) (xy 64.460178 -50.050202) (xy 64.382904 -50.0507)
			(xy 62.78245 -50.0507) (xy 62.705176 -50.050188) (xy 62.550834 -50.04222) (xy 62.397107 -50.026316)
			(xy 62.244402 -50.002521) (xy 62.093124 -49.970896) (xy 61.943675 -49.931526) (xy 61.796451 -49.884514)
			(xy 61.651842 -49.829987) (xy 61.510232 -49.768087) (xy 61.371996 -49.69898) (xy 61.2375 -49.622848)
			(xy 61.107102 -49.539894) (xy 60.981148 -49.450337) (xy 60.85997 -49.354416) (xy 60.743891 -49.252383)
			(xy 60.633218 -49.14451) (xy 60.528245 -49.031083) (xy 60.429249 -48.912403) (xy 60.336495 -48.788784)
			(xy 60.250227 -48.660555) (xy 60.170674 -48.528054) (xy 60.098048 -48.391634) (xy 60.032541 -48.251656)
			(xy 59.974326 -48.108492) (xy 59.923558 -47.96252) (xy 59.880371 -47.814129) (xy 59.844881 -47.663712)
			(xy 59.81718 -47.511667) (xy 59.797344 -47.358397) (xy 59.785423 -47.20431) (xy 59.781451 -47.049813)
			(xy 0.509016 -47.049813) (xy 0.509016 -50.859944) (xy 176.305972 -50.859944) (xy 176.305972 -50.227484)
			(xy 176.30645 -50.215411) (xy 176.313915 -50.192446) (xy 176.328109 -50.172911) (xy 176.347643 -50.158717)
			(xy 176.370607 -50.151251) (xy 176.38268 -50.150776) (xy 177.83556 -50.150776) (xy 177.847639 -50.151247)
			(xy 177.870618 -50.158701) (xy 177.890167 -50.172893) (xy 177.904373 -50.192432) (xy 177.911845 -50.215405)
			(xy 177.912188 -50.225198) (xy 180.05806 -50.225198) (xy 180.05806 -49.894998) (xy 180.058506 -49.882906)
			(xy 180.065966 -49.859902) (xy 180.080157 -49.840321) (xy 180.099696 -49.826071) (xy 180.122678 -49.818543)
			(xy 180.134768 -49.818036) (xy 180.388768 -49.818036) (xy 180.400879 -49.818444) (xy 180.423911 -49.825939)
			(xy 180.443488 -49.840201) (xy 180.457682 -49.859828) (xy 180.465097 -49.882886) (xy 180.465476 -49.894998)
			(xy 180.465476 -50.225198) (xy 180.59146 -50.225198) (xy 180.59146 -49.894998) (xy 180.591906 -49.882906)
			(xy 180.599366 -49.859902) (xy 180.613557 -49.840321) (xy 180.633096 -49.826071) (xy 180.656078 -49.818543)
			(xy 180.668168 -49.818036) (xy 180.922168 -49.818036) (xy 180.934279 -49.818444) (xy 180.957311 -49.825939)
			(xy 180.976888 -49.840201) (xy 180.991082 -49.859828) (xy 180.998497 -49.882886) (xy 180.998876 -49.894998)
			(xy 180.998876 -50.225198) (xy 180.998391 -50.237286) (xy 180.990937 -50.260284) (xy 180.976754 -50.279862)
			(xy 180.957226 -50.294113) (xy 180.934254 -50.301648) (xy 180.922168 -50.30216) (xy 180.668168 -50.30216)
			(xy 180.656053 -50.30181) (xy 180.633018 -50.294297) (xy 180.613442 -50.28002) (xy 180.59925 -50.260382)
			(xy 180.591837 -50.237314) (xy 180.59146 -50.225198) (xy 180.465476 -50.225198) (xy 180.464991 -50.237286)
			(xy 180.457537 -50.260284) (xy 180.443354 -50.279862) (xy 180.423826 -50.294113) (xy 180.400854 -50.301648)
			(xy 180.388768 -50.30216) (xy 180.134768 -50.30216) (xy 180.122653 -50.30181) (xy 180.099618 -50.294297)
			(xy 180.080042 -50.28002) (xy 180.06585 -50.260382) (xy 180.058437 -50.237314) (xy 180.05806 -50.225198)
			(xy 177.912188 -50.225198) (xy 177.912268 -50.227484) (xy 177.912268 -50.859944) (xy 177.911873 -50.872025)
			(xy 177.904393 -50.895) (xy 177.89018 -50.91454) (xy 177.870625 -50.928732) (xy 177.847641 -50.936186)
			(xy 177.83556 -50.936652) (xy 176.38268 -50.936652) (xy 176.370609 -50.936153) (xy 176.347648 -50.928691)
			(xy 176.328116 -50.914501) (xy 176.31392 -50.894973) (xy 176.30645 -50.872015) (xy 176.305972 -50.859944)
			(xy 0.509016 -50.859944) (xy 0.509016 -51.139598) (xy 180.05806 -51.139598) (xy 180.05806 -50.809398)
			(xy 180.058506 -50.797306) (xy 180.065966 -50.774302) (xy 180.080157 -50.754721) (xy 180.099696 -50.740471)
			(xy 180.122678 -50.732943) (xy 180.134768 -50.732436) (xy 180.388768 -50.732436) (xy 180.400879 -50.732844)
			(xy 180.423911 -50.740339) (xy 180.443488 -50.754601) (xy 180.457682 -50.774228) (xy 180.465097 -50.797286)
			(xy 180.465476 -50.809398) (xy 180.465476 -51.139598) (xy 180.59146 -51.139598) (xy 180.59146 -50.809398)
			(xy 180.591906 -50.797306) (xy 180.599366 -50.774302) (xy 180.613557 -50.754721) (xy 180.633096 -50.740471)
			(xy 180.656078 -50.732943) (xy 180.668168 -50.732436) (xy 180.922168 -50.732436) (xy 180.934279 -50.732844)
			(xy 180.957311 -50.740339) (xy 180.976888 -50.754601) (xy 180.991082 -50.774228) (xy 180.998497 -50.797286)
			(xy 180.998876 -50.809398) (xy 180.998876 -50.949098) (xy 181.659784 -50.949098) (xy 181.659784 -50.085498)
			(xy 181.66027 -50.058247) (xy 181.668026 -50.004299) (xy 181.683381 -49.952004) (xy 181.706023 -49.902427)
			(xy 181.735489 -49.856577) (xy 181.77118 -49.815386) (xy 181.812371 -49.779695) (xy 181.858221 -49.750229)
			(xy 181.907798 -49.727587) (xy 181.960093 -49.712232) (xy 182.014041 -49.704476) (xy 182.068543 -49.704476)
			(xy 182.122491 -49.712232) (xy 182.174786 -49.727587) (xy 182.224363 -49.750229) (xy 182.270213 -49.779695)
			(xy 182.311404 -49.815386) (xy 182.347095 -49.856577) (xy 182.376561 -49.902427) (xy 182.399203 -49.952004)
			(xy 182.414558 -50.004299) (xy 182.422314 -50.058247) (xy 182.4228 -50.085498) (xy 182.4228 -50.949098)
			(xy 182.422314 -50.976349) (xy 182.414558 -51.030297) (xy 182.399203 -51.082592) (xy 182.376561 -51.132169)
			(xy 182.347095 -51.178019) (xy 182.311404 -51.21921) (xy 182.270213 -51.254901) (xy 182.224363 -51.284367)
			(xy 182.174786 -51.307009) (xy 182.122491 -51.322364) (xy 182.068543 -51.33012) (xy 182.014041 -51.33012)
			(xy 181.960093 -51.322364) (xy 181.907798 -51.307009) (xy 181.858221 -51.284367) (xy 181.812371 -51.254901)
			(xy 181.77118 -51.21921) (xy 181.735489 -51.178019) (xy 181.706023 -51.132169) (xy 181.683381 -51.082592)
			(xy 181.668026 -51.030297) (xy 181.66027 -50.976349) (xy 181.659784 -50.949098) (xy 180.998876 -50.949098)
			(xy 180.998876 -51.139598) (xy 180.998391 -51.151686) (xy 180.990937 -51.174684) (xy 180.976754 -51.194262)
			(xy 180.957226 -51.208513) (xy 180.934254 -51.216048) (xy 180.922168 -51.21656) (xy 180.668168 -51.21656)
			(xy 180.656053 -51.21621) (xy 180.633018 -51.208697) (xy 180.613442 -51.19442) (xy 180.59925 -51.174782)
			(xy 180.591837 -51.151714) (xy 180.59146 -51.139598) (xy 180.465476 -51.139598) (xy 180.464991 -51.151686)
			(xy 180.457537 -51.174684) (xy 180.443354 -51.194262) (xy 180.423826 -51.208513) (xy 180.400854 -51.216048)
			(xy 180.388768 -51.21656) (xy 180.134768 -51.21656) (xy 180.122653 -51.21621) (xy 180.099618 -51.208697)
			(xy 180.080042 -51.19442) (xy 180.06585 -51.174782) (xy 180.058437 -51.151714) (xy 180.05806 -51.139598)
			(xy 0.509016 -51.139598) (xy 0.509016 -52.359814) (xy 176.305972 -52.359814) (xy 176.305972 -51.727354)
			(xy 176.306369 -51.715259) (xy 176.313842 -51.692251) (xy 176.328046 -51.672669) (xy 176.347595 -51.658422)
			(xy 176.370586 -51.650896) (xy 176.38268 -51.650392) (xy 177.83556 -51.650392) (xy 177.847666 -51.65085)
			(xy 177.870691 -51.658338) (xy 177.890264 -51.672589) (xy 177.90446 -51.692201) (xy 177.911883 -51.715247)
			(xy 177.912268 -51.727354) (xy 177.912268 -52.359814) (xy 177.911805 -52.371904) (xy 177.904345 -52.394903)
			(xy 177.890157 -52.414482) (xy 177.870624 -52.428733) (xy 177.847648 -52.436266) (xy 177.83556 -52.436776)
			(xy 176.38268 -52.436776) (xy 176.370568 -52.4364) (xy 176.347536 -52.428893) (xy 176.327961 -52.414621)
			(xy 176.313768 -52.39499) (xy 176.306352 -52.371928) (xy 176.305972 -52.359814) (xy 0.509016 -52.359814)
			(xy 0.509016 -52.481734) (xy 178.630072 -52.481734) (xy 178.630072 -51.618134) (xy 178.630558 -51.590883)
			(xy 178.638314 -51.536935) (xy 178.653669 -51.48464) (xy 178.676311 -51.435063) (xy 178.705777 -51.389213)
			(xy 178.741468 -51.348022) (xy 178.782659 -51.312331) (xy 178.828509 -51.282865) (xy 178.878086 -51.260223)
			(xy 178.930381 -51.244868) (xy 178.984329 -51.237112) (xy 179.038831 -51.237112) (xy 179.092779 -51.244868)
			(xy 179.145074 -51.260223) (xy 179.194651 -51.282865) (xy 179.240501 -51.312331) (xy 179.281692 -51.348022)
			(xy 179.317383 -51.389213) (xy 179.346849 -51.435063) (xy 179.369491 -51.48464) (xy 179.384846 -51.536935)
			(xy 179.392602 -51.590883) (xy 179.393088 -51.618134) (xy 179.393088 -51.999896) (xy 201.367397 -51.999896)
			(xy 201.371407 -51.837793) (xy 201.38343 -51.676088) (xy 201.403434 -51.515174) (xy 201.431372 -51.355447)
			(xy 201.467175 -51.197297) (xy 201.510755 -51.041111) (xy 201.562006 -50.887271) (xy 201.620802 -50.736154)
			(xy 201.687 -50.58813) (xy 201.760436 -50.44356) (xy 201.840933 -50.302799) (xy 201.928292 -50.166191)
			(xy 202.0223 -50.034071) (xy 202.122727 -49.906761) (xy 202.229327 -49.784573) (xy 202.341839 -49.667807)
			(xy 202.459987 -49.556748) (xy 202.583484 -49.451667) (xy 202.712026 -49.352823) (xy 202.845299 -49.260456)
			(xy 202.982977 -49.174793) (xy 203.124723 -49.096044) (xy 203.27019 -49.024401) (xy 203.419022 -48.960039)
			(xy 203.570854 -48.903117) (xy 203.725316 -48.853773) (xy 203.882029 -48.812128) (xy 204.04061 -48.778283)
			(xy 204.200671 -48.752323) (xy 204.361819 -48.73431) (xy 204.523661 -48.724289) (xy 204.685801 -48.722283)
			(xy 204.847842 -48.728299) (xy 205.009386 -48.74232) (xy 205.17004 -48.764313) (xy 205.32941 -48.794225)
			(xy 205.487105 -48.831981) (xy 205.64274 -48.877489) (xy 205.795934 -48.930639) (xy 205.946312 -48.9913)
			(xy 206.093507 -49.059323) (xy 206.237157 -49.134542) (xy 206.376912 -49.216773) (xy 206.512428 -49.305815)
			(xy 206.643376 -49.40145) (xy 206.769434 -49.503444) (xy 206.890294 -49.611547) (xy 207.00566 -49.725494)
			(xy 207.115249 -49.845008) (xy 207.218794 -49.969795) (xy 207.316041 -50.09955) (xy 207.406753 -50.233955)
			(xy 207.424818 -50.263806) (xy 239.457992 -50.263806) (xy 239.457992 -49.400206) (xy 239.458478 -49.372955)
			(xy 239.466234 -49.319007) (xy 239.481589 -49.266712) (xy 239.504231 -49.217135) (xy 239.533697 -49.171285)
			(xy 239.569388 -49.130094) (xy 239.610579 -49.094403) (xy 239.656429 -49.064937) (xy 239.706006 -49.042295)
			(xy 239.758301 -49.02694) (xy 239.812249 -49.019184) (xy 239.866751 -49.019184) (xy 239.920699 -49.02694)
			(xy 239.972994 -49.042295) (xy 240.022571 -49.064937) (xy 240.068421 -49.094403) (xy 240.109612 -49.130094)
			(xy 240.145303 -49.171285) (xy 240.174769 -49.217135) (xy 240.197411 -49.266712) (xy 240.212766 -49.319007)
			(xy 240.220522 -49.372955) (xy 240.221008 -49.400206) (xy 240.221008 -50.263806) (xy 240.220522 -50.291057)
			(xy 240.212766 -50.345005) (xy 240.197411 -50.3973) (xy 240.174769 -50.446877) (xy 240.145303 -50.492727)
			(xy 240.109612 -50.533918) (xy 240.068421 -50.569609) (xy 240.022571 -50.599075) (xy 239.972994 -50.621717)
			(xy 239.920699 -50.637072) (xy 239.866751 -50.644828) (xy 239.812249 -50.644828) (xy 239.758301 -50.637072)
			(xy 239.706006 -50.621717) (xy 239.656429 -50.599075) (xy 239.610579 -50.569609) (xy 239.569388 -50.533918)
			(xy 239.533697 -50.492727) (xy 239.504231 -50.446877) (xy 239.481589 -50.3973) (xy 239.466234 -50.345005)
			(xy 239.458478 -50.291057) (xy 239.457992 -50.263806) (xy 207.424818 -50.263806) (xy 207.490706 -50.372682)
			(xy 207.567696 -50.515391) (xy 207.637535 -50.661732) (xy 207.70005 -50.811349) (xy 207.755091 -50.963874)
			(xy 207.802521 -51.118934) (xy 207.842224 -51.27615) (xy 207.874105 -51.435138) (xy 207.898083 -51.595507)
			(xy 207.914102 -51.756866) (xy 207.922121 -51.91882) (xy 207.922622 -51.999896) (xy 207.922121 -52.080972)
			(xy 207.914102 -52.242926) (xy 207.898083 -52.404285) (xy 207.874105 -52.564654) (xy 207.842224 -52.723642)
			(xy 207.802521 -52.880858) (xy 207.794624 -52.906676) (xy 228.815392 -52.906676) (xy 228.815392 -52.043076)
			(xy 228.815878 -52.015825) (xy 228.823634 -51.961877) (xy 228.838989 -51.909582) (xy 228.861631 -51.860005)
			(xy 228.891097 -51.814155) (xy 228.926788 -51.772964) (xy 228.967979 -51.737273) (xy 229.013829 -51.707807)
			(xy 229.063406 -51.685165) (xy 229.115701 -51.66981) (xy 229.169649 -51.662054) (xy 229.224151 -51.662054)
			(xy 229.278099 -51.66981) (xy 229.330394 -51.685165) (xy 229.379971 -51.707807) (xy 229.425821 -51.737273)
			(xy 229.467012 -51.772964) (xy 229.502703 -51.814155) (xy 229.532169 -51.860005) (xy 229.554811 -51.909582)
			(xy 229.570166 -51.961877) (xy 229.577922 -52.015825) (xy 229.578408 -52.043076) (xy 229.578408 -52.885086)
			(xy 231.357932 -52.885086) (xy 231.357932 -52.057046) (xy 231.358446 -52.04496) (xy 231.365889 -52.021962)
			(xy 231.380064 -52.002382) (xy 231.399588 -51.988129) (xy 231.422556 -51.980595) (xy 231.43464 -51.980084)
			(xy 232.55986 -51.980084) (xy 232.571965 -51.98055) (xy 232.594988 -51.988037) (xy 232.614561 -52.002286)
			(xy 232.628757 -52.021896) (xy 232.636182 -52.04494) (xy 232.636568 -52.057046) (xy 232.636568 -52.885086)
			(xy 235.957872 -52.885086) (xy 235.957872 -52.057046) (xy 235.958347 -52.044956) (xy 235.965795 -52.021951)
			(xy 235.979978 -52.002368) (xy 235.999513 -51.988117) (xy 236.022491 -51.980589) (xy 236.03458 -51.980084)
			(xy 237.1598 -51.980084) (xy 237.171907 -51.980516) (xy 237.194932 -51.988013) (xy 237.214504 -52.002271)
			(xy 237.228699 -52.021889) (xy 237.236123 -52.044937) (xy 237.236508 -52.057046) (xy 237.236508 -52.176934)
			(xy 238.682276 -52.176934) (xy 238.682276 -51.846734) (xy 238.682737 -51.834643) (xy 238.690189 -51.811637)
			(xy 238.704376 -51.792053) (xy 238.723913 -51.777803) (xy 238.746894 -51.770277) (xy 238.758984 -51.769772)
			(xy 239.012984 -51.769772) (xy 239.025089 -51.77023) (xy 239.048111 -51.777721) (xy 239.067682 -51.791973)
			(xy 239.081878 -51.811585) (xy 239.089304 -51.834628) (xy 239.089692 -51.846734) (xy 239.089692 -52.176934)
			(xy 239.215676 -52.176934) (xy 239.215676 -51.846734) (xy 239.216137 -51.834643) (xy 239.223589 -51.811637)
			(xy 239.237776 -51.792053) (xy 239.257313 -51.777803) (xy 239.280294 -51.770277) (xy 239.292384 -51.769772)
			(xy 239.546384 -51.769772) (xy 239.558489 -51.77023) (xy 239.581511 -51.777721) (xy 239.601082 -51.791973)
			(xy 239.615278 -51.811585) (xy 239.622704 -51.834628) (xy 239.623092 -51.846734) (xy 239.623092 -52.176934)
			(xy 239.622622 -52.189022) (xy 239.61516 -52.212019) (xy 239.600973 -52.231595) (xy 239.581443 -52.245846)
			(xy 239.558471 -52.253383) (xy 239.546384 -52.253896) (xy 239.292384 -52.253896) (xy 239.280274 -52.253497)
			(xy 239.257245 -52.245993) (xy 239.237672 -52.231727) (xy 239.223478 -52.212102) (xy 239.216059 -52.189046)
			(xy 239.215676 -52.176934) (xy 239.089692 -52.176934) (xy 239.089222 -52.189022) (xy 239.08176 -52.212019)
			(xy 239.067573 -52.231595) (xy 239.048043 -52.245846) (xy 239.025071 -52.253383) (xy 239.012984 -52.253896)
			(xy 238.758984 -52.253896) (xy 238.746874 -52.253497) (xy 238.723845 -52.245993) (xy 238.704272 -52.231727)
			(xy 238.690078 -52.212102) (xy 238.682659 -52.189046) (xy 238.682276 -52.176934) (xy 237.236508 -52.176934)
			(xy 237.236508 -52.885086) (xy 237.235982 -52.89717) (xy 237.228534 -52.920162) (xy 237.214362 -52.939738)
			(xy 237.194844 -52.953991) (xy 237.171882 -52.961532) (xy 237.1598 -52.962048) (xy 236.03458 -52.962048)
			(xy 236.022475 -52.961601) (xy 235.999455 -52.954102) (xy 235.979887 -52.939847) (xy 235.965691 -52.920235)
			(xy 235.958262 -52.897192) (xy 235.957872 -52.885086) (xy 232.636568 -52.885086) (xy 232.636081 -52.897174)
			(xy 232.628629 -52.920173) (xy 232.614447 -52.939752) (xy 232.594918 -52.954004) (xy 232.571946 -52.961537)
			(xy 232.55986 -52.962048) (xy 231.43464 -52.962048) (xy 231.422538 -52.96155) (xy 231.39952 -52.954068)
			(xy 231.379951 -52.939825) (xy 231.365753 -52.920224) (xy 231.358323 -52.897189) (xy 231.357932 -52.885086)
			(xy 229.578408 -52.885086) (xy 229.578408 -52.906676) (xy 229.577922 -52.933927) (xy 229.570166 -52.987875)
			(xy 229.554811 -53.04017) (xy 229.532169 -53.089747) (xy 229.531149 -53.091334) (xy 238.682276 -53.091334)
			(xy 238.682276 -52.761134) (xy 238.682737 -52.749043) (xy 238.690189 -52.726037) (xy 238.704376 -52.706453)
			(xy 238.723913 -52.692203) (xy 238.746894 -52.684677) (xy 238.758984 -52.684172) (xy 239.012984 -52.684172)
			(xy 239.025089 -52.68463) (xy 239.048111 -52.692121) (xy 239.067682 -52.706373) (xy 239.081878 -52.725985)
			(xy 239.089304 -52.749028) (xy 239.089692 -52.761134) (xy 239.089692 -53.091334) (xy 239.215676 -53.091334)
			(xy 239.215676 -52.761134) (xy 239.216137 -52.749043) (xy 239.223589 -52.726037) (xy 239.237776 -52.706453)
			(xy 239.257313 -52.692203) (xy 239.280294 -52.684677) (xy 239.292384 -52.684172) (xy 239.546384 -52.684172)
			(xy 239.558489 -52.68463) (xy 239.581511 -52.692121) (xy 239.601082 -52.706373) (xy 239.615278 -52.725985)
			(xy 239.622704 -52.749028) (xy 239.623092 -52.761134) (xy 239.623092 -52.90185) (xy 241.926872 -52.90185)
			(xy 241.926872 -52.03825) (xy 241.927358 -52.010999) (xy 241.935114 -51.957051) (xy 241.950469 -51.904756)
			(xy 241.973111 -51.855179) (xy 242.002577 -51.809329) (xy 242.038268 -51.768138) (xy 242.079459 -51.732447)
			(xy 242.125309 -51.702981) (xy 242.174886 -51.680339) (xy 242.227181 -51.664984) (xy 242.281129 -51.657228)
			(xy 242.335631 -51.657228) (xy 242.389579 -51.664984) (xy 242.441874 -51.680339) (xy 242.491451 -51.702981)
			(xy 242.537301 -51.732447) (xy 242.578492 -51.768138) (xy 242.614183 -51.809329) (xy 242.643649 -51.855179)
			(xy 242.666291 -51.904756) (xy 242.681646 -51.957051) (xy 242.687806 -51.999896) (xy 265.367269 -51.999896)
			(xy 265.371279 -51.837793) (xy 265.383302 -51.676088) (xy 265.403306 -51.515174) (xy 265.431244 -51.355447)
			(xy 265.467047 -51.197297) (xy 265.510627 -51.041111) (xy 265.561878 -50.887271) (xy 265.620674 -50.736154)
			(xy 265.686872 -50.58813) (xy 265.760308 -50.44356) (xy 265.840805 -50.302799) (xy 265.928164 -50.166191)
			(xy 266.022172 -50.034071) (xy 266.122599 -49.906761) (xy 266.229199 -49.784573) (xy 266.341711 -49.667807)
			(xy 266.459859 -49.556748) (xy 266.583356 -49.451667) (xy 266.711898 -49.352823) (xy 266.845171 -49.260456)
			(xy 266.982849 -49.174793) (xy 267.124595 -49.096044) (xy 267.270062 -49.024401) (xy 267.418894 -48.960039)
			(xy 267.570726 -48.903117) (xy 267.725188 -48.853773) (xy 267.881901 -48.812128) (xy 268.040482 -48.778283)
			(xy 268.200543 -48.752323) (xy 268.361691 -48.73431) (xy 268.523533 -48.724289) (xy 268.685673 -48.722283)
			(xy 268.847714 -48.728299) (xy 269.009258 -48.74232) (xy 269.169912 -48.764313) (xy 269.329282 -48.794225)
			(xy 269.486977 -48.831981) (xy 269.642612 -48.877489) (xy 269.795806 -48.930639) (xy 269.946184 -48.9913)
			(xy 270.093379 -49.059323) (xy 270.237029 -49.134542) (xy 270.376784 -49.216773) (xy 270.5123 -49.305815)
			(xy 270.643248 -49.40145) (xy 270.769306 -49.503444) (xy 270.890166 -49.611547) (xy 271.005532 -49.725494)
			(xy 271.115121 -49.845008) (xy 271.218666 -49.969795) (xy 271.315913 -50.09955) (xy 271.406625 -50.233955)
			(xy 271.40723 -50.234955) (xy 350.291827 -50.234955) (xy 350.291827 -50.180445) (xy 350.299585 -50.126489)
			(xy 350.314942 -50.074187) (xy 350.337587 -50.024602) (xy 350.367058 -49.978745) (xy 350.402755 -49.937549)
			(xy 350.443952 -49.901853) (xy 350.489809 -49.872383) (xy 350.539394 -49.849739) (xy 350.591697 -49.834383)
			(xy 350.645653 -49.826626) (xy 350.672908 -49.826164) (xy 351.536508 -49.826164) (xy 351.563757 -49.826707)
			(xy 351.6177 -49.834464) (xy 351.66999 -49.849818) (xy 351.719562 -49.872458) (xy 351.765408 -49.901922)
			(xy 351.806594 -49.937611) (xy 351.842282 -49.978798) (xy 351.871746 -50.024645) (xy 351.894385 -50.074218)
			(xy 351.909738 -50.126508) (xy 351.917494 -50.180451) (xy 351.917494 -50.234949) (xy 351.917493 -50.234956)
			(xy 352.489927 -50.234956) (xy 352.489927 -50.180444) (xy 352.497685 -50.126487) (xy 352.513044 -50.074183)
			(xy 352.535689 -50.024598) (xy 352.565162 -49.97874) (xy 352.600861 -49.937544) (xy 352.642059 -49.901848)
			(xy 352.687919 -49.872378) (xy 352.737506 -49.849735) (xy 352.78981 -49.83438) (xy 352.843768 -49.826625)
			(xy 352.871024 -49.826164) (xy 353.734624 -49.826164) (xy 353.761872 -49.826708) (xy 353.815813 -49.834467)
			(xy 353.868101 -49.849823) (xy 353.917672 -49.872463) (xy 353.963516 -49.901928) (xy 354.0047 -49.937617)
			(xy 354.040386 -49.978804) (xy 354.069848 -50.024649) (xy 354.092486 -50.074221) (xy 354.107839 -50.12651)
			(xy 354.115594 -50.180452) (xy 354.115594 -50.234948) (xy 354.115593 -50.234956) (xy 354.712427 -50.234956)
			(xy 354.712427 -50.180444) (xy 354.720185 -50.126487) (xy 354.735544 -50.074183) (xy 354.758189 -50.024598)
			(xy 354.787662 -49.97874) (xy 354.823361 -49.937544) (xy 354.864559 -49.901848) (xy 354.910419 -49.872378)
			(xy 354.960006 -49.849735) (xy 355.01231 -49.83438) (xy 355.066268 -49.826625) (xy 355.093524 -49.826164)
			(xy 355.957124 -49.826164) (xy 355.984372 -49.826708) (xy 356.038313 -49.834467) (xy 356.090601 -49.849823)
			(xy 356.140172 -49.872463) (xy 356.186016 -49.901928) (xy 356.2272 -49.937617) (xy 356.262886 -49.978804)
			(xy 356.292348 -50.024649) (xy 356.314986 -50.074221) (xy 356.330339 -50.12651) (xy 356.338094 -50.180452)
			(xy 356.338094 -50.234948) (xy 356.338093 -50.234957) (xy 356.942527 -50.234957) (xy 356.942527 -50.180443)
			(xy 356.950286 -50.126484) (xy 356.965645 -50.074179) (xy 356.988293 -50.024592) (xy 357.017767 -49.978734)
			(xy 357.053468 -49.937537) (xy 357.094669 -49.90184) (xy 357.140531 -49.872371) (xy 357.19012 -49.84973)
			(xy 357.242427 -49.834376) (xy 357.296387 -49.826624) (xy 357.323644 -49.826164) (xy 358.187244 -49.826164)
			(xy 358.214491 -49.826709) (xy 358.26843 -49.83447) (xy 358.320716 -49.849828) (xy 358.370284 -49.87247)
			(xy 358.416125 -49.901935) (xy 358.457307 -49.937624) (xy 358.492991 -49.97881) (xy 358.522451 -50.024655)
			(xy 358.545087 -50.074226) (xy 358.560439 -50.126513) (xy 358.568194 -50.180453) (xy 358.568194 -50.234947)
			(xy 358.560439 -50.288887) (xy 358.545087 -50.341174) (xy 358.522451 -50.390745) (xy 358.492991 -50.43659)
			(xy 358.457307 -50.477776) (xy 358.416125 -50.513465) (xy 358.370284 -50.54293) (xy 358.320716 -50.565572)
			(xy 358.26843 -50.58093) (xy 358.214491 -50.588691) (xy 358.187244 -50.58918) (xy 357.323644 -50.58918)
			(xy 357.296387 -50.588776) (xy 357.242427 -50.581024) (xy 357.19012 -50.56567) (xy 357.140531 -50.543029)
			(xy 357.094669 -50.51356) (xy 357.053468 -50.477863) (xy 357.017767 -50.436666) (xy 356.988293 -50.390808)
			(xy 356.965645 -50.341221) (xy 356.950286 -50.288916) (xy 356.942527 -50.234957) (xy 356.338093 -50.234957)
			(xy 356.330339 -50.28889) (xy 356.314986 -50.341179) (xy 356.292348 -50.390751) (xy 356.262886 -50.436596)
			(xy 356.2272 -50.477783) (xy 356.186016 -50.513472) (xy 356.140172 -50.542937) (xy 356.090601 -50.565577)
			(xy 356.038313 -50.580933) (xy 355.984372 -50.588692) (xy 355.957124 -50.58918) (xy 355.093524 -50.58918)
			(xy 355.066268 -50.588775) (xy 355.01231 -50.58102) (xy 354.960006 -50.565665) (xy 354.910419 -50.543022)
			(xy 354.864559 -50.513552) (xy 354.823361 -50.477856) (xy 354.787662 -50.43666) (xy 354.758189 -50.390802)
			(xy 354.735544 -50.341217) (xy 354.720185 -50.288913) (xy 354.712427 -50.234956) (xy 354.115593 -50.234956)
			(xy 354.107839 -50.28889) (xy 354.092486 -50.341179) (xy 354.069848 -50.390751) (xy 354.040386 -50.436596)
			(xy 354.0047 -50.477783) (xy 353.963516 -50.513472) (xy 353.917672 -50.542937) (xy 353.868101 -50.565577)
			(xy 353.815813 -50.580933) (xy 353.761872 -50.588692) (xy 353.734624 -50.58918) (xy 352.871024 -50.58918)
			(xy 352.843768 -50.588775) (xy 352.78981 -50.58102) (xy 352.737506 -50.565665) (xy 352.687919 -50.543022)
			(xy 352.642059 -50.513552) (xy 352.600861 -50.477856) (xy 352.565162 -50.43666) (xy 352.535689 -50.390802)
			(xy 352.513044 -50.341217) (xy 352.497685 -50.288913) (xy 352.489927 -50.234956) (xy 351.917493 -50.234956)
			(xy 351.909738 -50.288892) (xy 351.894385 -50.341182) (xy 351.871746 -50.390755) (xy 351.842282 -50.436602)
			(xy 351.806594 -50.477789) (xy 351.765408 -50.513477) (xy 351.719562 -50.542942) (xy 351.66999 -50.565582)
			(xy 351.6177 -50.580936) (xy 351.563757 -50.588693) (xy 351.536508 -50.58918) (xy 350.672908 -50.58918)
			(xy 350.645653 -50.588774) (xy 350.591697 -50.581017) (xy 350.539394 -50.565661) (xy 350.489809 -50.543017)
			(xy 350.443952 -50.513547) (xy 350.402755 -50.477851) (xy 350.367058 -50.436655) (xy 350.337587 -50.390798)
			(xy 350.314942 -50.341213) (xy 350.299585 -50.288911) (xy 350.291827 -50.234955) (xy 271.40723 -50.234955)
			(xy 271.490578 -50.372682) (xy 271.567568 -50.515391) (xy 271.637407 -50.661732) (xy 271.699922 -50.811349)
			(xy 271.754963 -50.963874) (xy 271.802393 -51.118934) (xy 271.842096 -51.27615) (xy 271.873977 -51.435138)
			(xy 271.897955 -51.595507) (xy 271.913974 -51.756866) (xy 271.921993 -51.91882) (xy 271.922494 -51.999896)
			(xy 271.921993 -52.080972) (xy 271.913974 -52.242926) (xy 271.897955 -52.404285) (xy 271.873977 -52.564654)
			(xy 271.842096 -52.723642) (xy 271.802393 -52.880858) (xy 271.754963 -53.035918) (xy 271.699922 -53.188443)
			(xy 271.637407 -53.33806) (xy 271.567568 -53.484401) (xy 271.490578 -53.62711) (xy 271.406625 -53.765837)
			(xy 271.315913 -53.900242) (xy 271.218666 -54.029997) (xy 271.115121 -54.154784) (xy 271.005532 -54.274298)
			(xy 270.890166 -54.388245) (xy 270.769306 -54.496348) (xy 270.643248 -54.598342) (xy 270.5123 -54.693977)
			(xy 270.376784 -54.783019) (xy 270.237029 -54.86525) (xy 270.093379 -54.940469) (xy 269.946184 -55.008492)
			(xy 269.795806 -55.069153) (xy 269.642612 -55.122303) (xy 269.486977 -55.167811) (xy 269.329282 -55.205567)
			(xy 269.169912 -55.235479) (xy 269.009258 -55.257472) (xy 268.847714 -55.271493) (xy 268.685673 -55.277509)
			(xy 268.523533 -55.275503) (xy 268.361691 -55.265482) (xy 268.200543 -55.247469) (xy 268.040482 -55.221509)
			(xy 267.881901 -55.187664) (xy 267.725188 -55.146019) (xy 267.570726 -55.096675) (xy 267.418894 -55.039753)
			(xy 267.270062 -54.975391) (xy 267.124595 -54.903748) (xy 266.982849 -54.824999) (xy 266.845171 -54.739336)
			(xy 266.711898 -54.646969) (xy 266.583356 -54.548125) (xy 266.459859 -54.443044) (xy 266.341711 -54.331985)
			(xy 266.229199 -54.215219) (xy 266.122599 -54.093031) (xy 266.022172 -53.965721) (xy 265.928164 -53.833601)
			(xy 265.840805 -53.696993) (xy 265.760308 -53.556232) (xy 265.686872 -53.411662) (xy 265.620674 -53.263638)
			(xy 265.561878 -53.112521) (xy 265.510627 -52.958681) (xy 265.467047 -52.802495) (xy 265.431244 -52.644345)
			(xy 265.403306 -52.484618) (xy 265.383302 -52.323704) (xy 265.371279 -52.161999) (xy 265.367269 -51.999896)
			(xy 242.687806 -51.999896) (xy 242.689402 -52.010999) (xy 242.689888 -52.03825) (xy 242.689888 -52.90185)
			(xy 242.689402 -52.929101) (xy 242.681646 -52.983049) (xy 242.666291 -53.035344) (xy 242.643649 -53.084921)
			(xy 242.614183 -53.130771) (xy 242.578492 -53.171962) (xy 242.537301 -53.207653) (xy 242.491451 -53.237119)
			(xy 242.441874 -53.259761) (xy 242.389579 -53.275116) (xy 242.335631 -53.282872) (xy 242.281129 -53.282872)
			(xy 242.227181 -53.275116) (xy 242.174886 -53.259761) (xy 242.125309 -53.237119) (xy 242.079459 -53.207653)
			(xy 242.038268 -53.171962) (xy 242.002577 -53.130771) (xy 241.973111 -53.084921) (xy 241.950469 -53.035344)
			(xy 241.935114 -52.983049) (xy 241.927358 -52.929101) (xy 241.926872 -52.90185) (xy 239.623092 -52.90185)
			(xy 239.623092 -53.091334) (xy 239.622622 -53.103422) (xy 239.61516 -53.126419) (xy 239.600973 -53.145995)
			(xy 239.581443 -53.160246) (xy 239.558471 -53.167783) (xy 239.546384 -53.168296) (xy 239.292384 -53.168296)
			(xy 239.280274 -53.167897) (xy 239.257245 -53.160393) (xy 239.237672 -53.146127) (xy 239.223478 -53.126502)
			(xy 239.216059 -53.103446) (xy 239.215676 -53.091334) (xy 239.089692 -53.091334) (xy 239.089222 -53.103422)
			(xy 239.08176 -53.126419) (xy 239.067573 -53.145995) (xy 239.048043 -53.160246) (xy 239.025071 -53.167783)
			(xy 239.012984 -53.168296) (xy 238.758984 -53.168296) (xy 238.746874 -53.167897) (xy 238.723845 -53.160393)
			(xy 238.704272 -53.146127) (xy 238.690078 -53.126502) (xy 238.682659 -53.103446) (xy 238.682276 -53.091334)
			(xy 229.531149 -53.091334) (xy 229.502703 -53.135597) (xy 229.467012 -53.176788) (xy 229.425821 -53.212479)
			(xy 229.379971 -53.241945) (xy 229.330394 -53.264587) (xy 229.278099 -53.279942) (xy 229.224151 -53.287698)
			(xy 229.169649 -53.287698) (xy 229.115701 -53.279942) (xy 229.063406 -53.264587) (xy 229.013829 -53.241945)
			(xy 228.967979 -53.212479) (xy 228.926788 -53.176788) (xy 228.891097 -53.135597) (xy 228.861631 -53.089747)
			(xy 228.838989 -53.04017) (xy 228.823634 -52.987875) (xy 228.815878 -52.933927) (xy 228.815392 -52.906676)
			(xy 207.794624 -52.906676) (xy 207.755091 -53.035918) (xy 207.70005 -53.188443) (xy 207.637535 -53.33806)
			(xy 207.567696 -53.484401) (xy 207.490706 -53.62711) (xy 207.406753 -53.765837) (xy 207.316041 -53.900242)
			(xy 207.218794 -54.029997) (xy 207.115249 -54.154784) (xy 207.00566 -54.274298) (xy 206.890294 -54.388245)
			(xy 206.769434 -54.496348) (xy 206.643376 -54.598342) (xy 206.512428 -54.693977) (xy 206.493338 -54.70652)
			(xy 230.115872 -54.70652) (xy 230.115872 -53.84292) (xy 230.116358 -53.815669) (xy 230.124114 -53.761721)
			(xy 230.139469 -53.709426) (xy 230.162111 -53.659849) (xy 230.191577 -53.613999) (xy 230.227268 -53.572808)
			(xy 230.268459 -53.537117) (xy 230.314309 -53.507651) (xy 230.363886 -53.485009) (xy 230.416181 -53.469654)
			(xy 230.470129 -53.461898) (xy 230.524631 -53.461898) (xy 230.578579 -53.469654) (xy 230.630874 -53.485009)
			(xy 230.680451 -53.507651) (xy 230.726301 -53.537117) (xy 230.767492 -53.572808) (xy 230.803183 -53.613999)
			(xy 230.832649 -53.659849) (xy 230.855291 -53.709426) (xy 230.870646 -53.761721) (xy 230.878402 -53.815669)
			(xy 230.878888 -53.84292) (xy 230.878888 -54.685184) (xy 231.357932 -54.685184) (xy 231.357932 -53.857144)
			(xy 231.358351 -53.84506) (xy 231.365811 -53.822072) (xy 231.380014 -53.802517) (xy 231.399568 -53.788313)
			(xy 231.422556 -53.780851) (xy 231.43464 -53.780436) (xy 232.55986 -53.780436) (xy 232.571945 -53.780847)
			(xy 232.594934 -53.788309) (xy 232.614489 -53.802514) (xy 232.628693 -53.82207) (xy 232.636153 -53.845059)
			(xy 232.636568 -53.857144) (xy 232.636568 -54.685184) (xy 235.957872 -54.685184) (xy 235.957872 -53.857144)
			(xy 235.95835 -53.845066) (xy 235.965803 -53.822088) (xy 235.979993 -53.802538) (xy 235.99953 -53.788332)
			(xy 236.022502 -53.78086) (xy 236.03458 -53.780436) (xy 237.1598 -53.780436) (xy 237.171887 -53.780813)
			(xy 237.194877 -53.788286) (xy 237.214432 -53.8025) (xy 237.228634 -53.822062) (xy 237.236094 -53.845057)
			(xy 237.236508 -53.857144) (xy 237.236508 -53.985922) (xy 238.682276 -53.985922) (xy 238.682276 -53.655722)
			(xy 238.682727 -53.64363) (xy 238.690182 -53.620624) (xy 238.704371 -53.601041) (xy 238.723911 -53.586791)
			(xy 238.746894 -53.579265) (xy 238.758984 -53.57876) (xy 239.012984 -53.57876) (xy 239.025088 -53.57923)
			(xy 239.048108 -53.58672) (xy 239.067678 -53.600969) (xy 239.081874 -53.620577) (xy 239.089303 -53.643617)
			(xy 239.089692 -53.655722) (xy 239.089692 -53.985922) (xy 239.215676 -53.985922) (xy 239.215676 -53.655722)
			(xy 239.216127 -53.64363) (xy 239.223582 -53.620624) (xy 239.237771 -53.601041) (xy 239.257311 -53.586791)
			(xy 239.280294 -53.579265) (xy 239.292384 -53.57876) (xy 239.546384 -53.57876) (xy 239.558488 -53.57923)
			(xy 239.581508 -53.58672) (xy 239.601078 -53.600969) (xy 239.615274 -53.620577) (xy 239.622703 -53.643617)
			(xy 239.623092 -53.655722) (xy 239.623092 -53.985922) (xy 239.622612 -53.99801) (xy 239.615153 -54.021006)
			(xy 239.600969 -54.040582) (xy 239.58144 -54.054833) (xy 239.55847 -54.062371) (xy 239.546384 -54.062884)
			(xy 239.292384 -54.062884) (xy 239.280273 -54.062497) (xy 239.257242 -54.054991) (xy 239.237668 -54.040723)
			(xy 239.223474 -54.021094) (xy 239.216057 -53.998035) (xy 239.215676 -53.985922) (xy 239.089692 -53.985922)
			(xy 239.089212 -53.99801) (xy 239.081753 -54.021006) (xy 239.067569 -54.040582) (xy 239.04804 -54.054833)
			(xy 239.02507 -54.062371) (xy 239.012984 -54.062884) (xy 238.758984 -54.062884) (xy 238.746873 -54.062497)
			(xy 238.723842 -54.054991) (xy 238.704268 -54.040723) (xy 238.690074 -54.021094) (xy 238.682657 -53.998035)
			(xy 238.682276 -53.985922) (xy 237.236508 -53.985922) (xy 237.236508 -54.685184) (xy 237.236074 -54.697266)
			(xy 237.22861 -54.720248) (xy 237.21441 -54.739799) (xy 237.194862 -54.754003) (xy 237.171882 -54.761471)
			(xy 237.1598 -54.761892) (xy 236.03458 -54.761892) (xy 236.022503 -54.761452) (xy 235.999532 -54.753982)
			(xy 235.979994 -54.73978) (xy 235.965801 -54.720235) (xy 235.958342 -54.697261) (xy 235.957872 -54.685184)
			(xy 232.636568 -54.685184) (xy 232.636173 -54.69727) (xy 232.628705 -54.720259) (xy 232.614496 -54.739813)
			(xy 232.594937 -54.754016) (xy 232.571946 -54.761477) (xy 232.55986 -54.761892) (xy 231.43464 -54.761892)
			(xy 231.422558 -54.761453) (xy 231.399574 -54.753995) (xy 231.380021 -54.739796) (xy 231.365816 -54.720248)
			(xy 231.358351 -54.697266) (xy 231.357932 -54.685184) (xy 230.878888 -54.685184) (xy 230.878888 -54.70652)
			(xy 230.878402 -54.733771) (xy 230.870646 -54.787719) (xy 230.855291 -54.840014) (xy 230.832649 -54.889591)
			(xy 230.825753 -54.900322) (xy 238.682276 -54.900322) (xy 238.682276 -54.570122) (xy 238.682727 -54.55803)
			(xy 238.690182 -54.535024) (xy 238.704371 -54.515441) (xy 238.723911 -54.501191) (xy 238.746894 -54.493665)
			(xy 238.758984 -54.49316) (xy 239.012984 -54.49316) (xy 239.025088 -54.49363) (xy 239.048108 -54.50112)
			(xy 239.067678 -54.515369) (xy 239.081874 -54.534977) (xy 239.089303 -54.558017) (xy 239.089692 -54.570122)
			(xy 239.089692 -54.900322) (xy 239.215676 -54.900322) (xy 239.215676 -54.570122) (xy 239.216127 -54.55803)
			(xy 239.223582 -54.535024) (xy 239.237771 -54.515441) (xy 239.257311 -54.501191) (xy 239.280294 -54.493665)
			(xy 239.292384 -54.49316) (xy 239.546384 -54.49316) (xy 239.558488 -54.49363) (xy 239.581508 -54.50112)
			(xy 239.601078 -54.515369) (xy 239.615274 -54.534977) (xy 239.622703 -54.558017) (xy 239.623092 -54.570122)
			(xy 239.623092 -54.710838) (xy 240.282476 -54.710838) (xy 240.282476 -53.847238) (xy 240.282962 -53.819987)
			(xy 240.290718 -53.766039) (xy 240.306073 -53.713744) (xy 240.328715 -53.664167) (xy 240.358181 -53.618317)
			(xy 240.393872 -53.577126) (xy 240.435063 -53.541435) (xy 240.480913 -53.511969) (xy 240.53049 -53.489327)
			(xy 240.582785 -53.473972) (xy 240.636733 -53.466216) (xy 240.691235 -53.466216) (xy 240.745183 -53.473972)
			(xy 240.797478 -53.489327) (xy 240.847055 -53.511969) (xy 240.892905 -53.541435) (xy 240.934096 -53.577126)
			(xy 240.969787 -53.618317) (xy 240.999253 -53.664167) (xy 241.021895 -53.713744) (xy 241.03725 -53.766039)
			(xy 241.045006 -53.819987) (xy 241.045492 -53.847238) (xy 241.045492 -54.710838) (xy 241.045006 -54.738089)
			(xy 241.03725 -54.792037) (xy 241.021895 -54.844332) (xy 240.999253 -54.893909) (xy 240.969787 -54.939759)
			(xy 240.934096 -54.98095) (xy 240.892905 -55.016641) (xy 240.847055 -55.046107) (xy 240.797478 -55.068749)
			(xy 240.745183 -55.084104) (xy 240.691235 -55.09186) (xy 240.636733 -55.09186) (xy 240.582785 -55.084104)
			(xy 240.53049 -55.068749) (xy 240.480913 -55.046107) (xy 240.435063 -55.016641) (xy 240.393872 -54.98095)
			(xy 240.358181 -54.939759) (xy 240.328715 -54.893909) (xy 240.306073 -54.844332) (xy 240.290718 -54.792037)
			(xy 240.282962 -54.738089) (xy 240.282476 -54.710838) (xy 239.623092 -54.710838) (xy 239.623092 -54.900322)
			(xy 239.622612 -54.91241) (xy 239.615153 -54.935406) (xy 239.600969 -54.954982) (xy 239.58144 -54.969233)
			(xy 239.55847 -54.976771) (xy 239.546384 -54.977284) (xy 239.292384 -54.977284) (xy 239.280273 -54.976897)
			(xy 239.257242 -54.969391) (xy 239.237668 -54.955123) (xy 239.223474 -54.935494) (xy 239.216057 -54.912435)
			(xy 239.215676 -54.900322) (xy 239.089692 -54.900322) (xy 239.089212 -54.91241) (xy 239.081753 -54.935406)
			(xy 239.067569 -54.954982) (xy 239.04804 -54.969233) (xy 239.02507 -54.976771) (xy 239.012984 -54.977284)
			(xy 238.758984 -54.977284) (xy 238.746873 -54.976897) (xy 238.723842 -54.969391) (xy 238.704268 -54.955123)
			(xy 238.690074 -54.935494) (xy 238.682657 -54.912435) (xy 238.682276 -54.900322) (xy 230.825753 -54.900322)
			(xy 230.803183 -54.935441) (xy 230.767492 -54.976632) (xy 230.726301 -55.012323) (xy 230.680451 -55.041789)
			(xy 230.630874 -55.064431) (xy 230.578579 -55.079786) (xy 230.524631 -55.087542) (xy 230.470129 -55.087542)
			(xy 230.416181 -55.079786) (xy 230.363886 -55.064431) (xy 230.314309 -55.041789) (xy 230.268459 -55.012323)
			(xy 230.227268 -54.976632) (xy 230.191577 -54.935441) (xy 230.162111 -54.889591) (xy 230.139469 -54.840014)
			(xy 230.124114 -54.787719) (xy 230.116358 -54.733771) (xy 230.115872 -54.70652) (xy 206.493338 -54.70652)
			(xy 206.376912 -54.783019) (xy 206.237157 -54.86525) (xy 206.093507 -54.940469) (xy 205.946312 -55.008492)
			(xy 205.795934 -55.069153) (xy 205.64274 -55.122303) (xy 205.487105 -55.167811) (xy 205.32941 -55.205567)
			(xy 205.17004 -55.235479) (xy 205.009386 -55.257472) (xy 204.847842 -55.271493) (xy 204.685801 -55.277509)
			(xy 204.523661 -55.275503) (xy 204.361819 -55.265482) (xy 204.200671 -55.247469) (xy 204.04061 -55.221509)
			(xy 203.882029 -55.187664) (xy 203.725316 -55.146019) (xy 203.570854 -55.096675) (xy 203.419022 -55.039753)
			(xy 203.27019 -54.975391) (xy 203.124723 -54.903748) (xy 202.982977 -54.824999) (xy 202.845299 -54.739336)
			(xy 202.712026 -54.646969) (xy 202.583484 -54.548125) (xy 202.459987 -54.443044) (xy 202.341839 -54.331985)
			(xy 202.229327 -54.215219) (xy 202.122727 -54.093031) (xy 202.0223 -53.965721) (xy 201.928292 -53.833601)
			(xy 201.840933 -53.696993) (xy 201.760436 -53.556232) (xy 201.687 -53.411662) (xy 201.620802 -53.263638)
			(xy 201.562006 -53.112521) (xy 201.510755 -52.958681) (xy 201.467175 -52.802495) (xy 201.431372 -52.644345)
			(xy 201.403434 -52.484618) (xy 201.38343 -52.323704) (xy 201.371407 -52.161999) (xy 201.367397 -51.999896)
			(xy 179.393088 -51.999896) (xy 179.393088 -52.481734) (xy 179.392602 -52.508985) (xy 179.384846 -52.562933)
			(xy 179.369491 -52.615228) (xy 179.346849 -52.664805) (xy 179.317383 -52.710655) (xy 179.281692 -52.751846)
			(xy 179.240501 -52.787537) (xy 179.194651 -52.817003) (xy 179.145074 -52.839645) (xy 179.092779 -52.855)
			(xy 179.038831 -52.862756) (xy 178.984329 -52.862756) (xy 178.930381 -52.855) (xy 178.878086 -52.839645)
			(xy 178.828509 -52.817003) (xy 178.782659 -52.787537) (xy 178.741468 -52.751846) (xy 178.705777 -52.710655)
			(xy 178.676311 -52.664805) (xy 178.653669 -52.615228) (xy 178.638314 -52.562933) (xy 178.630558 -52.508985)
			(xy 178.630072 -52.481734) (xy 0.509016 -52.481734) (xy 0.509016 -53.859938) (xy 176.305972 -53.859938)
			(xy 176.305972 -53.227478) (xy 176.306389 -53.215384) (xy 176.313856 -53.192377) (xy 176.328054 -53.172795)
			(xy 176.3476 -53.158546) (xy 176.370587 -53.15102) (xy 176.38268 -53.150516) (xy 177.83556 -53.150516)
			(xy 177.847668 -53.150951) (xy 177.870697 -53.158441) (xy 177.890272 -53.172697) (xy 177.904468 -53.192317)
			(xy 177.911886 -53.215368) (xy 177.912268 -53.227478) (xy 177.912268 -53.231034) (xy 180.05806 -53.231034)
			(xy 180.05806 -52.900834) (xy 180.058537 -52.888744) (xy 180.065986 -52.865741) (xy 180.08017 -52.846159)
			(xy 180.099703 -52.831908) (xy 180.12268 -52.824379) (xy 180.134768 -52.823872) (xy 180.388768 -52.823872)
			(xy 180.400872 -52.824343) (xy 180.423894 -52.831831) (xy 180.443465 -52.846079) (xy 180.457662 -52.865687)
			(xy 180.465088 -52.888729) (xy 180.465476 -52.900834) (xy 180.465476 -53.231034) (xy 180.59146 -53.231034)
			(xy 180.59146 -52.900834) (xy 180.591937 -52.888744) (xy 180.599386 -52.865741) (xy 180.61357 -52.846159)
			(xy 180.633103 -52.831908) (xy 180.65608 -52.824379) (xy 180.668168 -52.823872) (xy 180.922168 -52.823872)
			(xy 180.934272 -52.824343) (xy 180.957294 -52.831831) (xy 180.976865 -52.846079) (xy 180.991062 -52.865687)
			(xy 180.998488 -52.888729) (xy 180.998876 -52.900834) (xy 180.998876 -53.231034) (xy 180.998422 -53.243124)
			(xy 180.990958 -53.266123) (xy 180.976767 -53.285701) (xy 180.957233 -53.299951) (xy 180.934256 -53.307485)
			(xy 180.922168 -53.307996) (xy 180.668168 -53.307996) (xy 180.656057 -53.307611) (xy 180.633028 -53.300102)
			(xy 180.613455 -53.285833) (xy 180.599262 -53.266204) (xy 180.591843 -53.243147) (xy 180.59146 -53.231034)
			(xy 180.465476 -53.231034) (xy 180.465022 -53.243124) (xy 180.457558 -53.266123) (xy 180.443367 -53.285701)
			(xy 180.423833 -53.299951) (xy 180.400856 -53.307485) (xy 180.388768 -53.307996) (xy 180.134768 -53.307996)
			(xy 180.122657 -53.307611) (xy 180.099628 -53.300102) (xy 180.080055 -53.285833) (xy 180.065862 -53.266204)
			(xy 180.058443 -53.243147) (xy 180.05806 -53.231034) (xy 177.912268 -53.231034) (xy 177.912268 -53.859938)
			(xy 177.911825 -53.872029) (xy 177.904359 -53.895029) (xy 177.890166 -53.914608) (xy 177.870628 -53.928857)
			(xy 177.847649 -53.93639) (xy 177.83556 -53.9369) (xy 176.38268 -53.9369) (xy 176.37057 -53.936501)
			(xy 176.347542 -53.928996) (xy 176.327969 -53.91473) (xy 176.313775 -53.895105) (xy 176.306355 -53.872049)
			(xy 176.305972 -53.859938) (xy 0.509016 -53.859938) (xy 0.509016 -54.145434) (xy 180.05806 -54.145434)
			(xy 180.05806 -53.815234) (xy 180.058537 -53.803144) (xy 180.065986 -53.780141) (xy 180.08017 -53.760559)
			(xy 180.099703 -53.746308) (xy 180.12268 -53.738779) (xy 180.134768 -53.738272) (xy 180.388768 -53.738272)
			(xy 180.400872 -53.738743) (xy 180.423894 -53.746231) (xy 180.443465 -53.760479) (xy 180.457662 -53.780087)
			(xy 180.465088 -53.803129) (xy 180.465476 -53.815234) (xy 180.465476 -54.145434) (xy 180.59146 -54.145434)
			(xy 180.59146 -53.815234) (xy 180.591937 -53.803144) (xy 180.599386 -53.780141) (xy 180.61357 -53.760559)
			(xy 180.633103 -53.746308) (xy 180.65608 -53.738779) (xy 180.668168 -53.738272) (xy 180.922168 -53.738272)
			(xy 180.934272 -53.738743) (xy 180.957294 -53.746231) (xy 180.976865 -53.760479) (xy 180.991062 -53.780087)
			(xy 180.998488 -53.803129) (xy 180.998876 -53.815234) (xy 180.998876 -53.954934) (xy 181.659784 -53.954934)
			(xy 181.659784 -53.091334) (xy 181.66027 -53.064083) (xy 181.668026 -53.010135) (xy 181.683381 -52.95784)
			(xy 181.706023 -52.908263) (xy 181.735489 -52.862413) (xy 181.77118 -52.821222) (xy 181.812371 -52.785531)
			(xy 181.858221 -52.756065) (xy 181.907798 -52.733423) (xy 181.960093 -52.718068) (xy 182.014041 -52.710312)
			(xy 182.068543 -52.710312) (xy 182.122491 -52.718068) (xy 182.174786 -52.733423) (xy 182.224363 -52.756065)
			(xy 182.270213 -52.785531) (xy 182.311404 -52.821222) (xy 182.347095 -52.862413) (xy 182.376561 -52.908263)
			(xy 182.399203 -52.95784) (xy 182.414558 -53.010135) (xy 182.422314 -53.064083) (xy 182.4228 -53.091334)
			(xy 182.4228 -53.954934) (xy 182.422314 -53.982185) (xy 182.414558 -54.036133) (xy 182.399203 -54.088428)
			(xy 182.376561 -54.138005) (xy 182.347095 -54.183855) (xy 182.311404 -54.225046) (xy 182.270213 -54.260737)
			(xy 182.224363 -54.290203) (xy 182.174786 -54.312845) (xy 182.122491 -54.3282) (xy 182.068543 -54.335956)
			(xy 182.014041 -54.335956) (xy 181.960093 -54.3282) (xy 181.907798 -54.312845) (xy 181.858221 -54.290203)
			(xy 181.812371 -54.260737) (xy 181.77118 -54.225046) (xy 181.735489 -54.183855) (xy 181.706023 -54.138005)
			(xy 181.683381 -54.088428) (xy 181.668026 -54.036133) (xy 181.66027 -53.982185) (xy 181.659784 -53.954934)
			(xy 180.998876 -53.954934) (xy 180.998876 -54.145434) (xy 180.998422 -54.157524) (xy 180.990958 -54.180523)
			(xy 180.976767 -54.200101) (xy 180.957233 -54.214351) (xy 180.934256 -54.221885) (xy 180.922168 -54.222396)
			(xy 180.668168 -54.222396) (xy 180.656057 -54.222011) (xy 180.633028 -54.214502) (xy 180.613455 -54.200233)
			(xy 180.599262 -54.180604) (xy 180.591843 -54.157547) (xy 180.59146 -54.145434) (xy 180.465476 -54.145434)
			(xy 180.465022 -54.157524) (xy 180.457558 -54.180523) (xy 180.443367 -54.200101) (xy 180.423833 -54.214351)
			(xy 180.400856 -54.221885) (xy 180.388768 -54.222396) (xy 180.134768 -54.222396) (xy 180.122657 -54.222011)
			(xy 180.099628 -54.214502) (xy 180.080055 -54.200233) (xy 180.065862 -54.180604) (xy 180.058443 -54.157547)
			(xy 180.05806 -54.145434) (xy 0.509016 -54.145434) (xy 0.509016 -55.359808) (xy 176.305972 -55.359808)
			(xy 176.305972 -54.727348) (xy 176.306453 -54.71527) (xy 176.313905 -54.692292) (xy 176.328094 -54.672743)
			(xy 176.347631 -54.658536) (xy 176.370602 -54.651064) (xy 176.38268 -54.65064) (xy 177.83556 -54.65064)
			(xy 177.847645 -54.651048) (xy 177.870635 -54.65851) (xy 177.89019 -54.672716) (xy 177.904394 -54.692272)
			(xy 177.911854 -54.715263) (xy 177.912268 -54.727348) (xy 177.912268 -55.359808) (xy 177.911894 -55.371895)
			(xy 177.904419 -55.394885) (xy 177.890204 -55.414439) (xy 177.870642 -55.428641) (xy 177.847647 -55.436101)
			(xy 177.83556 -55.436516) (xy 176.38268 -55.436516) (xy 176.370605 -55.436053) (xy 176.347639 -55.428586)
			(xy 176.328103 -55.414389) (xy 176.313909 -55.39485) (xy 176.306445 -55.371883) (xy 176.305972 -55.359808)
			(xy 0.509016 -55.359808) (xy 0.509016 -55.481728) (xy 178.630072 -55.481728) (xy 178.630072 -54.618128)
			(xy 178.630558 -54.590877) (xy 178.638314 -54.536929) (xy 178.653669 -54.484634) (xy 178.676311 -54.435057)
			(xy 178.705777 -54.389207) (xy 178.741468 -54.348016) (xy 178.782659 -54.312325) (xy 178.828509 -54.282859)
			(xy 178.878086 -54.260217) (xy 178.930381 -54.244862) (xy 178.984329 -54.237106) (xy 179.038831 -54.237106)
			(xy 179.092779 -54.244862) (xy 179.145074 -54.260217) (xy 179.194651 -54.282859) (xy 179.240501 -54.312325)
			(xy 179.281692 -54.348016) (xy 179.317383 -54.389207) (xy 179.346849 -54.435057) (xy 179.369491 -54.484634)
			(xy 179.384846 -54.536929) (xy 179.392602 -54.590877) (xy 179.393088 -54.618128) (xy 179.393088 -55.481728)
			(xy 179.392602 -55.508979) (xy 179.384846 -55.562927) (xy 179.369491 -55.615222) (xy 179.346849 -55.664799)
			(xy 179.317383 -55.710649) (xy 179.281692 -55.75184) (xy 179.240501 -55.787531) (xy 179.194651 -55.816997)
			(xy 179.145074 -55.839639) (xy 179.092779 -55.854994) (xy 179.038831 -55.86275) (xy 178.984329 -55.86275)
			(xy 178.930381 -55.854994) (xy 178.878086 -55.839639) (xy 178.828509 -55.816997) (xy 178.782659 -55.787531)
			(xy 178.741468 -55.75184) (xy 178.705777 -55.710649) (xy 178.676311 -55.664799) (xy 178.653669 -55.615222)
			(xy 178.638314 -55.562927) (xy 178.630558 -55.508979) (xy 178.630072 -55.481728) (xy 0.509016 -55.481728)
			(xy 0.509016 -57.094435) (xy 170.841915 -57.094435) (xy 170.841915 -57.005413) (xy 170.849895 -56.916749)
			(xy 170.865791 -56.829158) (xy 170.889474 -56.743343) (xy 170.920754 -56.659998) (xy 170.95938 -56.579792)
			(xy 171.005039 -56.503371) (xy 171.057365 -56.43135) (xy 171.115936 -56.36431) (xy 171.180281 -56.30279)
			(xy 171.249881 -56.247286) (xy 171.324177 -56.198244) (xy 171.402569 -56.156059) (xy 171.484428 -56.121071)
			(xy 171.569093 -56.093562) (xy 171.655883 -56.073752) (xy 171.744099 -56.061802) (xy 171.833032 -56.057809)
			(xy 171.921965 -56.061802) (xy 172.010181 -56.073752) (xy 172.096971 -56.093562) (xy 172.181636 -56.121071)
			(xy 172.263495 -56.156059) (xy 172.341887 -56.198244) (xy 172.416183 -56.247286) (xy 172.485783 -56.30279)
			(xy 172.550128 -56.36431) (xy 172.608699 -56.43135) (xy 172.661025 -56.503371) (xy 172.663117 -56.506872)
			(xy 228.815392 -56.506872) (xy 228.815392 -55.643272) (xy 228.815878 -55.616021) (xy 228.823634 -55.562073)
			(xy 228.838989 -55.509778) (xy 228.861631 -55.460201) (xy 228.891097 -55.414351) (xy 228.926788 -55.37316)
			(xy 228.967979 -55.337469) (xy 229.013829 -55.308003) (xy 229.063406 -55.285361) (xy 229.115701 -55.270006)
			(xy 229.169649 -55.26225) (xy 229.224151 -55.26225) (xy 229.278099 -55.270006) (xy 229.330394 -55.285361)
			(xy 229.379971 -55.308003) (xy 229.425821 -55.337469) (xy 229.467012 -55.37316) (xy 229.502703 -55.414351)
			(xy 229.532169 -55.460201) (xy 229.554811 -55.509778) (xy 229.570166 -55.562073) (xy 229.577922 -55.616021)
			(xy 229.578408 -55.643272) (xy 229.578408 -56.485028) (xy 231.357932 -56.485028) (xy 231.357932 -55.656988)
			(xy 231.358303 -55.644901) (xy 231.365779 -55.621911) (xy 231.379994 -55.602357) (xy 231.399557 -55.588155)
			(xy 231.422552 -55.580695) (xy 231.43464 -55.58028) (xy 232.55986 -55.58028) (xy 232.571939 -55.580747)
			(xy 232.594919 -55.588202) (xy 232.614469 -55.602394) (xy 232.628675 -55.621935) (xy 232.636145 -55.644909)
			(xy 232.636568 -55.656988) (xy 232.636568 -56.485028) (xy 235.957872 -56.485028) (xy 235.957872 -55.656988)
			(xy 235.958354 -55.644915) (xy 235.965817 -55.621951) (xy 235.98001 -55.602416) (xy 235.999544 -55.588221)
			(xy 236.022507 -55.580755) (xy 236.03458 -55.58028) (xy 237.1598 -55.58028) (xy 237.171873 -55.580764)
			(xy 237.194838 -55.588225) (xy 237.214374 -55.602417) (xy 237.228569 -55.621951) (xy 237.236034 -55.644915)
			(xy 237.236508 -55.656988) (xy 237.236508 -55.776876) (xy 240.384076 -55.776876) (xy 240.384076 -55.446676)
			(xy 240.384544 -55.434602) (xy 240.392011 -55.411637) (xy 240.406207 -55.392101) (xy 240.425744 -55.377907)
			(xy 240.44871 -55.370442) (xy 240.460784 -55.369968) (xy 240.714784 -55.369968) (xy 240.726855 -55.370477)
			(xy 240.749818 -55.377933) (xy 240.769353 -55.392118) (xy 240.783549 -55.411646) (xy 240.791016 -55.434605)
			(xy 240.791492 -55.446676) (xy 240.791492 -55.776876) (xy 240.917476 -55.776876) (xy 240.917476 -55.446676)
			(xy 240.917944 -55.434602) (xy 240.925411 -55.411637) (xy 240.939607 -55.392101) (xy 240.959144 -55.377907)
			(xy 240.98211 -55.370442) (xy 240.994184 -55.369968) (xy 241.248184 -55.369968) (xy 241.260255 -55.370477)
			(xy 241.283218 -55.377933) (xy 241.302753 -55.392118) (xy 241.316949 -55.411646) (xy 241.324416 -55.434605)
			(xy 241.324892 -55.446676) (xy 241.324892 -55.776876) (xy 241.324467 -55.788959) (xy 241.317004 -55.811944)
			(xy 241.302801 -55.831496) (xy 241.283251 -55.8457) (xy 241.260267 -55.853165) (xy 241.248184 -55.853584)
			(xy 240.994184 -55.853584) (xy 240.982098 -55.853201) (xy 240.959111 -55.845726) (xy 240.939559 -55.831513)
			(xy 240.925356 -55.811953) (xy 240.917893 -55.788962) (xy 240.917476 -55.776876) (xy 240.791492 -55.776876)
			(xy 240.791067 -55.788959) (xy 240.783604 -55.811944) (xy 240.769401 -55.831496) (xy 240.749851 -55.8457)
			(xy 240.726867 -55.853165) (xy 240.714784 -55.853584) (xy 240.460784 -55.853584) (xy 240.448698 -55.853201)
			(xy 240.425711 -55.845726) (xy 240.406159 -55.831513) (xy 240.391956 -55.811953) (xy 240.384493 -55.788962)
			(xy 240.384076 -55.776876) (xy 237.236508 -55.776876) (xy 237.236508 -55.911852) (xy 357.10365 -55.911852)
			(xy 357.10365 -55.857348) (xy 357.111406 -55.803398) (xy 357.126762 -55.751101) (xy 357.149403 -55.701521)
			(xy 357.17887 -55.655668) (xy 357.214562 -55.614476) (xy 357.255752 -55.578782) (xy 357.301604 -55.549313)
			(xy 357.351182 -55.526669) (xy 357.403478 -55.511311) (xy 357.457428 -55.503551) (xy 357.48468 -55.503064)
			(xy 358.34828 -55.503064) (xy 358.375532 -55.503582) (xy 358.429481 -55.511336) (xy 358.481777 -55.526689)
			(xy 358.531356 -55.549329) (xy 358.577209 -55.578794) (xy 358.618401 -55.614485) (xy 358.654094 -55.655675)
			(xy 358.683562 -55.701526) (xy 358.706204 -55.751104) (xy 358.72156 -55.8034) (xy 358.729317 -55.857348)
			(xy 358.729317 -55.911852) (xy 358.729316 -55.911856) (xy 359.950927 -55.911856) (xy 359.950927 -55.857344)
			(xy 359.958685 -55.803388) (xy 359.974043 -55.751084) (xy 359.996689 -55.701499) (xy 360.026161 -55.655642)
			(xy 360.061859 -55.614445) (xy 360.103058 -55.578749) (xy 360.148917 -55.549279) (xy 360.198503 -55.526636)
			(xy 360.250807 -55.511281) (xy 360.304764 -55.503526) (xy 360.33202 -55.503064) (xy 361.19562 -55.503064)
			(xy 361.222868 -55.503608) (xy 361.27681 -55.511366) (xy 361.329098 -55.526722) (xy 361.378669 -55.549362)
			(xy 361.424514 -55.578827) (xy 361.465699 -55.614516) (xy 361.501385 -55.655702) (xy 361.530847 -55.701548)
			(xy 361.553485 -55.75112) (xy 361.568838 -55.80341) (xy 361.576594 -55.857352) (xy 361.576594 -55.911848)
			(xy 361.576593 -55.911857) (xy 363.514527 -55.911857) (xy 363.514527 -55.857343) (xy 363.522286 -55.803385)
			(xy 363.537645 -55.75108) (xy 363.560292 -55.701493) (xy 363.589766 -55.655635) (xy 363.625466 -55.614438)
			(xy 363.666667 -55.578742) (xy 363.712529 -55.549273) (xy 363.762117 -55.526631) (xy 363.814424 -55.511277)
			(xy 363.868383 -55.503524) (xy 363.89564 -55.503064) (xy 364.75924 -55.503064) (xy 364.786487 -55.503609)
			(xy 364.840427 -55.511369) (xy 364.892713 -55.526727) (xy 364.942281 -55.549369) (xy 364.988123 -55.578834)
			(xy 365.029306 -55.614523) (xy 365.06499 -55.655709) (xy 365.094451 -55.701554) (xy 365.117087 -55.751125)
			(xy 365.132439 -55.803412) (xy 365.140194 -55.857353) (xy 365.140194 -55.911847) (xy 365.132439 -55.965788)
			(xy 365.117087 -56.018075) (xy 365.094451 -56.067646) (xy 365.06499 -56.113491) (xy 365.029306 -56.154677)
			(xy 364.988123 -56.190366) (xy 364.942281 -56.219831) (xy 364.892713 -56.242473) (xy 364.840427 -56.257831)
			(xy 364.786487 -56.265591) (xy 364.75924 -56.26608) (xy 363.89564 -56.26608) (xy 363.868383 -56.265676)
			(xy 363.814424 -56.257923) (xy 363.762117 -56.242569) (xy 363.712529 -56.219927) (xy 363.666667 -56.190458)
			(xy 363.625466 -56.154762) (xy 363.589766 -56.113565) (xy 363.560292 -56.067707) (xy 363.537645 -56.01812)
			(xy 363.522286 -55.965815) (xy 363.514527 -55.911857) (xy 361.576593 -55.911857) (xy 361.568838 -55.96579)
			(xy 361.553485 -56.01808) (xy 361.530847 -56.067652) (xy 361.501385 -56.113498) (xy 361.465699 -56.154684)
			(xy 361.424514 -56.190373) (xy 361.378669 -56.219838) (xy 361.329098 -56.242478) (xy 361.27681 -56.257834)
			(xy 361.222868 -56.265592) (xy 361.19562 -56.26608) (xy 360.33202 -56.26608) (xy 360.304764 -56.265674)
			(xy 360.250807 -56.257919) (xy 360.198503 -56.242564) (xy 360.148917 -56.219921) (xy 360.103058 -56.190451)
			(xy 360.061859 -56.154755) (xy 360.026161 -56.113558) (xy 359.996689 -56.067701) (xy 359.974043 -56.018116)
			(xy 359.958685 -55.965812) (xy 359.950927 -55.911856) (xy 358.729316 -55.911856) (xy 358.72156 -55.9658)
			(xy 358.706204 -56.018096) (xy 358.683562 -56.067674) (xy 358.654094 -56.113525) (xy 358.618401 -56.154715)
			(xy 358.577209 -56.190406) (xy 358.531356 -56.219871) (xy 358.481777 -56.242511) (xy 358.429481 -56.257864)
			(xy 358.375532 -56.265618) (xy 358.34828 -56.26608) (xy 357.48468 -56.26608) (xy 357.457428 -56.265649)
			(xy 357.403478 -56.257889) (xy 357.351182 -56.242531) (xy 357.301604 -56.219887) (xy 357.255752 -56.190418)
			(xy 357.214562 -56.154724) (xy 357.17887 -56.113532) (xy 357.149403 -56.067679) (xy 357.126762 -56.018099)
			(xy 357.111406 -55.965802) (xy 357.10365 -55.911852) (xy 237.236508 -55.911852) (xy 237.236508 -56.485028)
			(xy 237.23606 -56.497104) (xy 237.22859 -56.520072) (xy 237.214389 -56.539609) (xy 237.194847 -56.553802)
			(xy 237.171876 -56.561264) (xy 237.1598 -56.561736) (xy 236.03458 -56.561736) (xy 236.022507 -56.561253)
			(xy 235.999544 -56.553788) (xy 235.98001 -56.539596) (xy 235.965815 -56.520063) (xy 235.958348 -56.497101)
			(xy 235.957872 -56.485028) (xy 232.636568 -56.485028) (xy 232.636211 -56.497116) (xy 232.628731 -56.520107)
			(xy 232.614511 -56.53966) (xy 232.594946 -56.553862) (xy 232.571949 -56.561321) (xy 232.55986 -56.561736)
			(xy 231.43464 -56.561736) (xy 231.422562 -56.561254) (xy 231.399585 -56.553801) (xy 231.380037 -56.539611)
			(xy 231.365831 -56.520075) (xy 231.358357 -56.497105) (xy 231.357932 -56.485028) (xy 229.578408 -56.485028)
			(xy 229.578408 -56.506872) (xy 229.577922 -56.534123) (xy 229.570166 -56.588071) (xy 229.554811 -56.640366)
			(xy 229.532169 -56.689943) (xy 229.531312 -56.691276) (xy 240.384076 -56.691276) (xy 240.384076 -56.361076)
			(xy 240.384544 -56.349002) (xy 240.392011 -56.326037) (xy 240.406207 -56.306501) (xy 240.425744 -56.292307)
			(xy 240.44871 -56.284842) (xy 240.460784 -56.284368) (xy 240.714784 -56.284368) (xy 240.726855 -56.284877)
			(xy 240.749818 -56.292333) (xy 240.769353 -56.306518) (xy 240.783549 -56.326046) (xy 240.791016 -56.349005)
			(xy 240.791492 -56.361076) (xy 240.791492 -56.691276) (xy 240.917476 -56.691276) (xy 240.917476 -56.361076)
			(xy 240.917944 -56.349002) (xy 240.925411 -56.326037) (xy 240.939607 -56.306501) (xy 240.959144 -56.292307)
			(xy 240.98211 -56.284842) (xy 240.994184 -56.284368) (xy 241.248184 -56.284368) (xy 241.260255 -56.284877)
			(xy 241.283218 -56.292333) (xy 241.302753 -56.306518) (xy 241.316949 -56.326046) (xy 241.324416 -56.349005)
			(xy 241.324892 -56.361076) (xy 241.324892 -56.691276) (xy 241.324467 -56.703359) (xy 241.317004 -56.726344)
			(xy 241.302801 -56.745896) (xy 241.283251 -56.7601) (xy 241.260267 -56.767565) (xy 241.248184 -56.767984)
			(xy 240.994184 -56.767984) (xy 240.982098 -56.767601) (xy 240.959111 -56.760126) (xy 240.939559 -56.745913)
			(xy 240.925356 -56.726353) (xy 240.917893 -56.703362) (xy 240.917476 -56.691276) (xy 240.791492 -56.691276)
			(xy 240.791067 -56.703359) (xy 240.783604 -56.726344) (xy 240.769401 -56.745896) (xy 240.749851 -56.7601)
			(xy 240.726867 -56.767565) (xy 240.714784 -56.767984) (xy 240.460784 -56.767984) (xy 240.448698 -56.767601)
			(xy 240.425711 -56.760126) (xy 240.406159 -56.745913) (xy 240.391956 -56.726353) (xy 240.384493 -56.703362)
			(xy 240.384076 -56.691276) (xy 229.531312 -56.691276) (xy 229.502703 -56.735793) (xy 229.467012 -56.776984)
			(xy 229.425821 -56.812675) (xy 229.379971 -56.842141) (xy 229.330394 -56.864783) (xy 229.278099 -56.880138)
			(xy 229.224151 -56.887894) (xy 229.169649 -56.887894) (xy 229.115701 -56.880138) (xy 229.063406 -56.864783)
			(xy 229.013829 -56.842141) (xy 228.967979 -56.812675) (xy 228.926788 -56.776984) (xy 228.891097 -56.735793)
			(xy 228.861631 -56.689943) (xy 228.838989 -56.640366) (xy 228.823634 -56.588071) (xy 228.815878 -56.534123)
			(xy 228.815392 -56.506872) (xy 172.663117 -56.506872) (xy 172.706684 -56.579792) (xy 172.74531 -56.659998)
			(xy 172.77659 -56.743343) (xy 172.800273 -56.829158) (xy 172.816169 -56.916749) (xy 172.824149 -57.005413)
			(xy 172.824648 -57.049924) (xy 172.824149 -57.094435) (xy 172.816169 -57.183099) (xy 172.800273 -57.27069)
			(xy 172.77659 -57.356505) (xy 172.74531 -57.43985) (xy 172.706684 -57.520056) (xy 172.661025 -57.596477)
			(xy 172.608699 -57.668498) (xy 172.550128 -57.735538) (xy 172.485783 -57.797058) (xy 172.416183 -57.852562)
			(xy 172.341887 -57.901604) (xy 172.263495 -57.943789) (xy 172.181636 -57.978777) (xy 172.096971 -58.006286)
			(xy 172.010181 -58.026096) (xy 171.921965 -58.038046) (xy 171.833032 -58.04204) (xy 171.744099 -58.038046)
			(xy 171.655883 -58.026096) (xy 171.569093 -58.006286) (xy 171.484428 -57.978777) (xy 171.402569 -57.943789)
			(xy 171.324177 -57.901604) (xy 171.249881 -57.852562) (xy 171.180281 -57.797058) (xy 171.115936 -57.735538)
			(xy 171.057365 -57.668498) (xy 171.005039 -57.596477) (xy 170.95938 -57.520056) (xy 170.920754 -57.43985)
			(xy 170.889474 -57.356505) (xy 170.865791 -57.27069) (xy 170.849895 -57.183099) (xy 170.841915 -57.094435)
			(xy 0.509016 -57.094435) (xy 0.509016 -58.306716) (xy 230.115872 -58.306716) (xy 230.115872 -57.443116)
			(xy 230.116358 -57.415865) (xy 230.124114 -57.361917) (xy 230.139469 -57.309622) (xy 230.162111 -57.260045)
			(xy 230.191577 -57.214195) (xy 230.227268 -57.173004) (xy 230.268459 -57.137313) (xy 230.314309 -57.107847)
			(xy 230.363886 -57.085205) (xy 230.416181 -57.06985) (xy 230.470129 -57.062094) (xy 230.524631 -57.062094)
			(xy 230.578579 -57.06985) (xy 230.630874 -57.085205) (xy 230.680451 -57.107847) (xy 230.726301 -57.137313)
			(xy 230.767492 -57.173004) (xy 230.803183 -57.214195) (xy 230.832649 -57.260045) (xy 230.855291 -57.309622)
			(xy 230.870646 -57.361917) (xy 230.878402 -57.415865) (xy 230.878888 -57.443116) (xy 230.878888 -58.285126)
			(xy 231.357932 -58.285126) (xy 231.357932 -57.457086) (xy 231.358395 -57.444996) (xy 231.365855 -57.421997)
			(xy 231.380043 -57.402418) (xy 231.399576 -57.388167) (xy 231.422552 -57.380634) (xy 231.43464 -57.380124)
			(xy 232.55986 -57.380124) (xy 232.571969 -57.380551) (xy 232.594999 -57.388042) (xy 232.614575 -57.4023)
			(xy 232.62877 -57.421922) (xy 232.636188 -57.444976) (xy 232.636568 -57.457086) (xy 232.636568 -58.285126)
			(xy 235.957872 -58.285126) (xy 235.957872 -57.457086) (xy 235.958296 -57.444992) (xy 235.96576 -57.421986)
			(xy 235.979957 -57.402403) (xy 235.999501 -57.388154) (xy 236.022488 -57.380628) (xy 236.03458 -57.380124)
			(xy 237.1598 -57.380124) (xy 237.171911 -57.380516) (xy 237.194943 -57.388019) (xy 237.214518 -57.402286)
			(xy 237.228712 -57.421914) (xy 237.236128 -57.444973) (xy 237.236508 -57.457086) (xy 237.236508 -57.576974)
			(xy 238.682276 -57.576974) (xy 238.682276 -57.246774) (xy 238.682686 -57.234679) (xy 238.690154 -57.211672)
			(xy 238.704354 -57.192089) (xy 238.723902 -57.177841) (xy 238.746891 -57.170316) (xy 238.758984 -57.169812)
			(xy 239.012984 -57.169812) (xy 239.025093 -57.17023) (xy 239.048122 -57.177727) (xy 239.067696 -57.191987)
			(xy 239.081891 -57.21161) (xy 239.08931 -57.234663) (xy 239.089692 -57.246774) (xy 239.089692 -57.576974)
			(xy 239.215676 -57.576974) (xy 239.215676 -57.246774) (xy 239.216086 -57.234679) (xy 239.223554 -57.211672)
			(xy 239.237754 -57.192089) (xy 239.257302 -57.177841) (xy 239.280291 -57.170316) (xy 239.292384 -57.169812)
			(xy 239.546384 -57.169812) (xy 239.558493 -57.17023) (xy 239.581522 -57.177727) (xy 239.601096 -57.191987)
			(xy 239.615291 -57.21161) (xy 239.62271 -57.234663) (xy 239.623092 -57.246774) (xy 239.623092 -57.576974)
			(xy 239.622571 -57.589059) (xy 239.615125 -57.612053) (xy 239.600952 -57.631631) (xy 239.581431 -57.645884)
			(xy 239.558467 -57.653422) (xy 239.546384 -57.653936) (xy 239.292384 -57.653936) (xy 239.280278 -57.653498)
			(xy 239.257256 -57.645998) (xy 239.237687 -57.631741) (xy 239.223491 -57.612127) (xy 239.216064 -57.589081)
			(xy 239.215676 -57.576974) (xy 239.089692 -57.576974) (xy 239.089171 -57.589059) (xy 239.081725 -57.612053)
			(xy 239.067552 -57.631631) (xy 239.048031 -57.645884) (xy 239.025067 -57.653422) (xy 239.012984 -57.653936)
			(xy 238.758984 -57.653936) (xy 238.746878 -57.653498) (xy 238.723856 -57.645998) (xy 238.704287 -57.631741)
			(xy 238.690091 -57.612127) (xy 238.682664 -57.589081) (xy 238.682276 -57.576974) (xy 237.236508 -57.576974)
			(xy 237.236508 -58.285126) (xy 237.236016 -58.297212) (xy 237.228558 -58.320206) (xy 237.214376 -58.339781)
			(xy 237.194851 -58.354032) (xy 237.171884 -58.361572) (xy 237.1598 -58.362088) (xy 236.03458 -58.362088)
			(xy 236.022469 -58.361701) (xy 235.999439 -58.354194) (xy 235.979865 -58.339926) (xy 235.965672 -58.320297)
			(xy 235.958253 -58.297239) (xy 235.957872 -58.285126) (xy 232.636568 -58.285126) (xy 232.636115 -58.297216)
			(xy 232.628652 -58.320216) (xy 232.614462 -58.339795) (xy 232.594926 -58.354045) (xy 232.571949 -58.361578)
			(xy 232.55986 -58.362088) (xy 231.43464 -58.362088) (xy 231.422532 -58.361649) (xy 231.399504 -58.35416)
			(xy 231.379929 -58.339904) (xy 231.365734 -58.320286) (xy 231.358314 -58.297235) (xy 231.357932 -58.285126)
			(xy 230.878888 -58.285126) (xy 230.878888 -58.306716) (xy 230.878402 -58.333967) (xy 230.870646 -58.387915)
			(xy 230.855291 -58.44021) (xy 230.832649 -58.489787) (xy 230.831629 -58.491374) (xy 238.682276 -58.491374)
			(xy 238.682276 -58.161174) (xy 238.682686 -58.149079) (xy 238.690154 -58.126072) (xy 238.704354 -58.106489)
			(xy 238.723902 -58.092241) (xy 238.746891 -58.084716) (xy 238.758984 -58.084212) (xy 239.012984 -58.084212)
			(xy 239.025093 -58.08463) (xy 239.048122 -58.092127) (xy 239.067696 -58.106387) (xy 239.081891 -58.12601)
			(xy 239.08931 -58.149063) (xy 239.089692 -58.161174) (xy 239.089692 -58.491374) (xy 239.215676 -58.491374)
			(xy 239.215676 -58.161174) (xy 239.216086 -58.149079) (xy 239.223554 -58.126072) (xy 239.237754 -58.106489)
			(xy 239.257302 -58.092241) (xy 239.280291 -58.084716) (xy 239.292384 -58.084212) (xy 239.546384 -58.084212)
			(xy 239.558493 -58.08463) (xy 239.581522 -58.092127) (xy 239.601096 -58.106387) (xy 239.615291 -58.12601)
			(xy 239.62271 -58.149063) (xy 239.623092 -58.161174) (xy 239.623092 -58.30189) (xy 240.282476 -58.30189)
			(xy 240.282476 -57.43829) (xy 240.282962 -57.411039) (xy 240.290718 -57.357091) (xy 240.306073 -57.304796)
			(xy 240.328715 -57.255219) (xy 240.358181 -57.209369) (xy 240.393872 -57.168178) (xy 240.435063 -57.132487)
			(xy 240.480913 -57.103021) (xy 240.53049 -57.080379) (xy 240.582785 -57.065024) (xy 240.636733 -57.057268)
			(xy 240.691235 -57.057268) (xy 240.745183 -57.065024) (xy 240.797478 -57.080379) (xy 240.847055 -57.103021)
			(xy 240.892905 -57.132487) (xy 240.934096 -57.168178) (xy 240.969787 -57.209369) (xy 240.999253 -57.255219)
			(xy 241.021895 -57.304796) (xy 241.03725 -57.357091) (xy 241.045006 -57.411039) (xy 241.045492 -57.43829)
			(xy 241.045492 -58.30189) (xy 241.045006 -58.329141) (xy 241.03725 -58.383089) (xy 241.021895 -58.435384)
			(xy 240.999253 -58.484961) (xy 240.969787 -58.530811) (xy 240.941894 -58.563002) (xy 242.736116 -58.563002)
			(xy 242.736116 -57.699402) (xy 242.736602 -57.672151) (xy 242.744358 -57.618203) (xy 242.759713 -57.565908)
			(xy 242.782355 -57.516331) (xy 242.811821 -57.470481) (xy 242.847512 -57.42929) (xy 242.888703 -57.393599)
			(xy 242.934553 -57.364133) (xy 242.98413 -57.341491) (xy 243.036425 -57.326136) (xy 243.090373 -57.31838)
			(xy 243.144875 -57.31838) (xy 243.198823 -57.326136) (xy 243.251118 -57.341491) (xy 243.300695 -57.364133)
			(xy 243.346545 -57.393599) (xy 243.387736 -57.42929) (xy 243.423427 -57.470481) (xy 243.452893 -57.516331)
			(xy 243.475535 -57.565908) (xy 243.49089 -57.618203) (xy 243.498646 -57.672151) (xy 243.499132 -57.699402)
			(xy 243.499132 -58.563002) (xy 243.498646 -58.590253) (xy 243.49089 -58.644201) (xy 243.475535 -58.696496)
			(xy 243.452893 -58.746073) (xy 243.423427 -58.791923) (xy 243.387736 -58.833114) (xy 243.346545 -58.868805)
			(xy 243.300695 -58.898271) (xy 243.251118 -58.920913) (xy 243.198823 -58.936268) (xy 243.144875 -58.944024)
			(xy 243.090373 -58.944024) (xy 243.036425 -58.936268) (xy 242.98413 -58.920913) (xy 242.934553 -58.898271)
			(xy 242.888703 -58.868805) (xy 242.847512 -58.833114) (xy 242.811821 -58.791923) (xy 242.782355 -58.746073)
			(xy 242.759713 -58.696496) (xy 242.744358 -58.644201) (xy 242.736602 -58.590253) (xy 242.736116 -58.563002)
			(xy 240.941894 -58.563002) (xy 240.934096 -58.572002) (xy 240.892905 -58.607693) (xy 240.847055 -58.637159)
			(xy 240.797478 -58.659801) (xy 240.745183 -58.675156) (xy 240.691235 -58.682912) (xy 240.636733 -58.682912)
			(xy 240.582785 -58.675156) (xy 240.53049 -58.659801) (xy 240.480913 -58.637159) (xy 240.435063 -58.607693)
			(xy 240.393872 -58.572002) (xy 240.358181 -58.530811) (xy 240.328715 -58.484961) (xy 240.306073 -58.435384)
			(xy 240.290718 -58.383089) (xy 240.282962 -58.329141) (xy 240.282476 -58.30189) (xy 239.623092 -58.30189)
			(xy 239.623092 -58.491374) (xy 239.622571 -58.503459) (xy 239.615125 -58.526453) (xy 239.600952 -58.546031)
			(xy 239.581431 -58.560284) (xy 239.558467 -58.567822) (xy 239.546384 -58.568336) (xy 239.292384 -58.568336)
			(xy 239.280278 -58.567898) (xy 239.257256 -58.560398) (xy 239.237687 -58.546141) (xy 239.223491 -58.526527)
			(xy 239.216064 -58.503481) (xy 239.215676 -58.491374) (xy 239.089692 -58.491374) (xy 239.089171 -58.503459)
			(xy 239.081725 -58.526453) (xy 239.067552 -58.546031) (xy 239.048031 -58.560284) (xy 239.025067 -58.567822)
			(xy 239.012984 -58.568336) (xy 238.758984 -58.568336) (xy 238.746878 -58.567898) (xy 238.723856 -58.560398)
			(xy 238.704287 -58.546141) (xy 238.690091 -58.526527) (xy 238.682664 -58.503481) (xy 238.682276 -58.491374)
			(xy 230.831629 -58.491374) (xy 230.803183 -58.535637) (xy 230.767492 -58.576828) (xy 230.726301 -58.612519)
			(xy 230.680451 -58.641985) (xy 230.630874 -58.664627) (xy 230.578579 -58.679982) (xy 230.524631 -58.687738)
			(xy 230.470129 -58.687738) (xy 230.416181 -58.679982) (xy 230.363886 -58.664627) (xy 230.314309 -58.641985)
			(xy 230.268459 -58.612519) (xy 230.227268 -58.576828) (xy 230.191577 -58.535637) (xy 230.162111 -58.489787)
			(xy 230.139469 -58.44021) (xy 230.124114 -58.387915) (xy 230.116358 -58.333967) (xy 230.115872 -58.306716)
			(xy 0.509016 -58.306716) (xy 0.509016 -59.99988) (xy 16.983969 -59.99988) (xy 16.987993 -59.914112)
			(xy 17.000031 -59.829098) (xy 17.019978 -59.745584) (xy 17.047657 -59.664305) (xy 17.082825 -59.585976)
			(xy 17.125174 -59.511283) (xy 17.174331 -59.440885) (xy 17.229864 -59.375399) (xy 17.291286 -59.315401)
			(xy 17.358055 -59.261418) (xy 17.429587 -59.213925) (xy 17.505251 -59.173339) (xy 17.584384 -59.140016)
			(xy 17.666289 -59.11425) (xy 17.750247 -59.096267) (xy 17.835521 -59.086225) (xy 17.92136 -59.084212)
			(xy 18.00701 -59.090246) (xy 18.091718 -59.104274) (xy 18.174741 -59.126173) (xy 18.255349 -59.15575)
			(xy 18.332833 -59.192745) (xy 18.406512 -59.236833) (xy 18.475738 -59.287627) (xy 18.539905 -59.34468)
			(xy 18.589034 -59.397392) (xy 63.040514 -59.397392) (xy 63.040913 -59.387368) (xy 63.048589 -59.368849)
			(xy 63.062767 -59.354676) (xy 63.08129 -59.347009) (xy 63.091314 -59.346592) (xy 63.101029 -59.347008)
			(xy 63.119064 -59.354236) (xy 63.13312 -59.36765) (xy 63.137542 -59.37631) (xy 64.015874 -61.292486)
			(xy 64.6303 -61.0108) (xy 63.75146 -59.09437) (xy 63.749325 -59.089364) (xy 63.747026 -59.078729)
			(xy 63.746888 -59.073288) (xy 63.747378 -59.063281) (xy 63.755039 -59.044791) (xy 63.769191 -59.030639)
			(xy 63.787681 -59.022978) (xy 63.797688 -59.022488) (xy 63.8074 -59.022926) (xy 63.825434 -59.030144)
			(xy 63.839492 -59.043549) (xy 63.843916 -59.052206) (xy 64.450542 -60.375038) (xy 233.333297 -60.375038)
			(xy 233.337302 -60.28713) (xy 233.349285 -60.19995) (xy 233.369145 -60.114221) (xy 233.39672 -60.030653)
			(xy 233.431779 -59.949939) (xy 233.474032 -59.872747) (xy 233.52313 -59.799718) (xy 233.578666 -59.731456)
			(xy 233.640178 -59.668526) (xy 233.707159 -59.611452) (xy 233.779052 -59.560704) (xy 233.855261 -59.516704)
			(xy 233.935156 -59.479817) (xy 234.018075 -59.450348) (xy 234.10333 -59.428541) (xy 234.190214 -59.414577)
			(xy 234.278008 -59.408571) (xy 234.365985 -59.410575) (xy 234.453415 -59.42057) (xy 234.539574 -59.438474)
			(xy 234.623748 -59.464138) (xy 234.705239 -59.497351) (xy 234.783373 -59.537837) (xy 234.857501 -59.585259)
			(xy 234.927009 -59.639226) (xy 234.991323 -59.699291) (xy 235.049907 -59.764955) (xy 235.102278 -59.835674)
			(xy 235.148001 -59.910862) (xy 235.186698 -59.989897) (xy 235.218047 -60.072123) (xy 235.241789 -60.156859)
			(xy 235.257727 -60.243403) (xy 235.265729 -60.331038) (xy 235.26623 -60.375038) (xy 235.265729 -60.419038)
			(xy 235.257727 -60.506673) (xy 235.241789 -60.593217) (xy 235.218047 -60.677953) (xy 235.186698 -60.760179)
			(xy 235.148001 -60.839214) (xy 235.102278 -60.914402) (xy 235.049907 -60.985121) (xy 234.991323 -61.050785)
			(xy 234.927009 -61.11085) (xy 234.857501 -61.164817) (xy 234.783373 -61.212239) (xy 234.705239 -61.252725)
			(xy 234.623748 -61.285938) (xy 234.539574 -61.311602) (xy 234.453415 -61.329506) (xy 234.365985 -61.339501)
			(xy 234.278008 -61.341505) (xy 234.190214 -61.335499) (xy 234.10333 -61.321535) (xy 234.018075 -61.299728)
			(xy 233.935156 -61.270259) (xy 233.855261 -61.233372) (xy 233.779052 -61.189372) (xy 233.707159 -61.138624)
			(xy 233.640178 -61.08155) (xy 233.578666 -61.01862) (xy 233.52313 -60.950358) (xy 233.474032 -60.877329)
			(xy 233.431779 -60.800137) (xy 233.39672 -60.719423) (xy 233.369145 -60.635855) (xy 233.349285 -60.550126)
			(xy 233.337302 -60.462946) (xy 233.333297 -60.375038) (xy 64.450542 -60.375038) (xy 64.743838 -61.01461)
			(xy 64.745967 -61.019618) (xy 64.74827 -61.030252) (xy 64.74841 -61.035692) (xy 64.747976 -61.045405)
			(xy 64.740757 -61.063439) (xy 64.72735 -61.077496) (xy 64.718692 -61.08192) (xy 64.012064 -61.406024)
			(xy 64.007059 -61.40816) (xy 63.996423 -61.410458) (xy 63.990982 -61.410596) (xy 63.981266 -61.410189)
			(xy 63.96323 -61.402959) (xy 63.949175 -61.389541) (xy 63.944754 -61.380878) (xy 63.045086 -59.418474)
			(xy 63.042953 -59.413467) (xy 63.040653 -59.402832) (xy 63.040514 -59.397392) (xy 18.589034 -59.397392)
			(xy 18.598446 -59.407491) (xy 18.650849 -59.475508) (xy 18.696652 -59.548133) (xy 18.735453 -59.624728)
			(xy 18.766912 -59.70462) (xy 18.790751 -59.787107) (xy 18.806761 -59.871464) (xy 18.814801 -59.956949)
			(xy 18.815304 -59.99988) (xy 18.814801 -60.042811) (xy 18.808399 -60.110878) (xy 61.191648 -60.110878)
			(xy 61.192003 -60.100849) (xy 61.199689 -60.082323) (xy 61.213882 -60.06815) (xy 61.232419 -60.060489)
			(xy 61.242448 -60.060078) (xy 61.252157 -60.06055) (xy 61.270189 -60.067753) (xy 61.284249 -60.081145)
			(xy 61.288676 -60.089796) (xy 62.167008 -62.005972) (xy 62.781434 -61.724286) (xy 61.902594 -59.807856)
			(xy 61.900456 -59.802851) (xy 61.898159 -59.792215) (xy 61.898022 -59.786774) (xy 61.898467 -59.776762)
			(xy 61.906139 -59.758265) (xy 61.920306 -59.744112) (xy 61.938809 -59.736458) (xy 61.948822 -59.735974)
			(xy 61.958536 -59.736395) (xy 61.97657 -59.743622) (xy 61.990626 -59.757033) (xy 61.99505 -59.765692)
			(xy 62.894972 -61.728096) (xy 62.897093 -61.733107) (xy 62.899401 -61.743738) (xy 62.899544 -61.749178)
			(xy 62.899299 -61.75502) (xy 65.152524 -61.75502) (xy 65.152937 -61.744997) (xy 65.160605 -61.726476)
			(xy 65.174779 -61.712302) (xy 65.193301 -61.704636) (xy 65.203324 -61.70422) (xy 65.213041 -61.704613)
			(xy 65.231079 -61.711849) (xy 65.245133 -61.725273) (xy 65.249552 -61.733938) (xy 66.127884 -63.650114)
			(xy 66.74231 -63.368428) (xy 65.86347 -61.451998) (xy 65.861344 -61.446989) (xy 65.859039 -61.436356)
			(xy 65.858898 -61.430916) (xy 65.859332 -61.420896) (xy 65.866997 -61.40238) (xy 65.881165 -61.388207)
			(xy 65.899678 -61.380536) (xy 65.909698 -61.380116) (xy 65.919413 -61.380531) (xy 65.93745 -61.387757)
			(xy 65.951505 -61.401172) (xy 65.955926 -61.409834) (xy 66.855848 -63.372238) (xy 66.857986 -63.377243)
			(xy 66.860283 -63.387879) (xy 66.86042 -63.39332) (xy 66.860001 -63.403034) (xy 66.852774 -63.421068)
			(xy 66.839361 -63.435125) (xy 66.830702 -63.439548) (xy 66.124074 -63.763652) (xy 66.119068 -63.765786)
			(xy 66.108433 -63.768085) (xy 66.102992 -63.768224) (xy 66.093279 -63.767794) (xy 66.075245 -63.760572)
			(xy 66.061188 -63.747164) (xy 66.056764 -63.738506) (xy 65.157096 -61.776102) (xy 65.154972 -61.771092)
			(xy 65.152666 -61.76046) (xy 65.152524 -61.75502) (xy 62.899299 -61.75502) (xy 62.899137 -61.758895)
			(xy 62.891912 -61.776934) (xy 62.878491 -61.790989) (xy 62.869826 -61.795406) (xy 62.163198 -62.11951)
			(xy 62.158189 -62.121635) (xy 62.147556 -62.123941) (xy 62.142116 -62.124082) (xy 62.132402 -62.123658)
			(xy 62.114365 -62.116437) (xy 62.100309 -62.103025) (xy 62.095888 -62.094364) (xy 61.19622 -60.13196)
			(xy 61.194085 -60.126954) (xy 61.191786 -60.116319) (xy 61.191648 -60.110878) (xy 18.808399 -60.110878)
			(xy 18.806761 -60.128296) (xy 18.790751 -60.212653) (xy 18.766912 -60.29514) (xy 18.735453 -60.375032)
			(xy 18.696652 -60.451627) (xy 18.650849 -60.524252) (xy 18.598446 -60.592269) (xy 18.539905 -60.65508)
			(xy 18.475738 -60.712133) (xy 18.406512 -60.762927) (xy 18.332833 -60.807015) (xy 18.255349 -60.84401)
			(xy 18.174741 -60.873587) (xy 18.091718 -60.895486) (xy 18.00701 -60.909514) (xy 17.92136 -60.915548)
			(xy 17.835521 -60.913535) (xy 17.750247 -60.903493) (xy 17.666289 -60.88551) (xy 17.584384 -60.859744)
			(xy 17.505251 -60.826421) (xy 17.429587 -60.785835) (xy 17.358055 -60.738342) (xy 17.291286 -60.684359)
			(xy 17.229864 -60.624361) (xy 17.174331 -60.558875) (xy 17.125174 -60.488477) (xy 17.082825 -60.413784)
			(xy 17.047657 -60.335455) (xy 17.019978 -60.254176) (xy 17.000031 -60.170662) (xy 16.987993 -60.085648)
			(xy 16.983969 -59.99988) (xy 0.509016 -59.99988) (xy 0.509016 -74.760836) (xy 39.554404 -74.760836)
			(xy 39.554404 -66.060828) (xy 39.554909 -65.955304) (xy 39.562993 -65.74441) (xy 39.579149 -65.533981)
			(xy 39.603352 -65.324324) (xy 39.635569 -65.115749) (xy 39.675751 -64.908561) (xy 39.723839 -64.703064)
			(xy 39.779763 -64.49956) (xy 39.84344 -64.298347) (xy 39.914778 -64.09972) (xy 39.993672 -63.903972)
			(xy 40.080005 -63.71139) (xy 40.173652 -63.522255) (xy 40.274474 -63.336846) (xy 40.382324 -63.155435)
			(xy 40.497043 -62.978288) (xy 40.618463 -62.805666) (xy 40.746406 -62.63782) (xy 40.880684 -62.474998)
			(xy 41.0211 -62.317439) (xy 41.167448 -62.165374) (xy 41.319513 -62.019026) (xy 41.477072 -61.87861)
			(xy 41.639894 -61.744332) (xy 41.80774 -61.616389) (xy 41.980362 -61.494969) (xy 42.157509 -61.38025)
			(xy 42.33892 -61.2724) (xy 42.524329 -61.171578) (xy 42.713464 -61.077931) (xy 42.906046 -60.991598)
			(xy 43.101794 -60.912704) (xy 43.300421 -60.841366) (xy 43.501634 -60.777689) (xy 43.705138 -60.721765)
			(xy 43.910635 -60.673677) (xy 44.117823 -60.633495) (xy 44.326398 -60.601278) (xy 44.536055 -60.577075)
			(xy 44.746484 -60.560919) (xy 44.957378 -60.552835) (xy 45.168426 -60.552835) (xy 45.37932 -60.560919)
			(xy 45.589749 -60.577075) (xy 45.799406 -60.601278) (xy 46.007981 -60.633495) (xy 46.215169 -60.673677)
			(xy 46.395628 -60.715906) (xy 59.386724 -60.715906) (xy 59.387125 -60.705882) (xy 59.394797 -60.687361)
			(xy 59.408976 -60.673187) (xy 59.4275 -60.665521) (xy 59.437524 -60.665106) (xy 59.44724 -60.665507)
			(xy 59.465277 -60.67274) (xy 59.479332 -60.686161) (xy 59.483752 -60.694824) (xy 60.362338 -62.611)
			(xy 60.976764 -62.32906) (xy 60.09767 -60.412884) (xy 60.095539 -60.407877) (xy 60.093238 -60.397242)
			(xy 60.093098 -60.391802) (xy 60.09359 -60.381795) (xy 60.101248 -60.363303) (xy 60.1154 -60.34915)
			(xy 60.133891 -60.341491) (xy 60.143898 -60.341002) (xy 60.153612 -60.341425) (xy 60.171648 -60.348648)
			(xy 60.185704 -60.36206) (xy 60.190126 -60.37072) (xy 61.090302 -62.33287) (xy 61.092418 -62.337883)
			(xy 61.094729 -62.348513) (xy 61.094874 -62.353952) (xy 61.094431 -62.363665) (xy 61.08722 -62.381701)
			(xy 61.073814 -62.395758) (xy 61.065156 -62.40018) (xy 60.527853 -62.646814) (xy 63.43396 -62.646814)
			(xy 63.434498 -62.636812) (xy 63.442146 -62.618328) (xy 63.456283 -62.604176) (xy 63.474759 -62.596509)
			(xy 63.48476 -62.596014) (xy 63.494472 -62.596457) (xy 63.512508 -62.60367) (xy 63.526565 -62.617075)
			(xy 63.530988 -62.625732) (xy 64.40932 -64.541908) (xy 65.023746 -64.260222) (xy 64.144906 -62.343792)
			(xy 64.14278 -62.338783) (xy 64.140475 -62.32815) (xy 64.140334 -62.32271) (xy 64.140728 -62.312685)
			(xy 64.148401 -62.294162) (xy 64.162582 -62.279988) (xy 64.181109 -62.272324) (xy 64.191134 -62.27191)
			(xy 64.200844 -62.272375) (xy 64.218879 -62.279578) (xy 64.232938 -62.292974) (xy 64.237362 -62.301628)
			(xy 65.137284 -64.264032) (xy 65.139417 -64.269039) (xy 65.141717 -64.279674) (xy 65.141856 -64.285114)
			(xy 65.141469 -64.294832) (xy 65.134233 -64.312872) (xy 65.120805 -64.326925) (xy 65.112138 -64.331342)
			(xy 64.40551 -64.655446) (xy 64.4005 -64.65757) (xy 64.389868 -64.659876) (xy 64.384428 -64.660018)
			(xy 64.374717 -64.659565) (xy 64.356684 -64.652354) (xy 64.342625 -64.638954) (xy 64.3382 -64.6303)
			(xy 63.438532 -62.667896) (xy 63.436408 -62.662886) (xy 63.434102 -62.652254) (xy 63.43396 -62.646814)
			(xy 60.527853 -62.646814) (xy 60.358528 -62.724538) (xy 60.353516 -62.726656) (xy 60.342885 -62.728966)
			(xy 60.337446 -62.72911) (xy 60.327736 -62.728649) (xy 60.309702 -62.721442) (xy 60.295643 -62.708046)
			(xy 60.291218 -62.699392) (xy 59.391296 -60.736988) (xy 59.389168 -60.73198) (xy 59.386864 -60.721346)
			(xy 59.386724 -60.715906) (xy 46.395628 -60.715906) (xy 46.420666 -60.721765) (xy 46.62417 -60.777689)
			(xy 46.825383 -60.841366) (xy 47.02401 -60.912704) (xy 47.219758 -60.991598) (xy 47.41234 -61.077931)
			(xy 47.601475 -61.171578) (xy 47.786884 -61.2724) (xy 47.968295 -61.38025) (xy 48.073204 -61.448188)
			(xy 57.588912 -61.448188) (xy 57.589379 -61.438178) (xy 57.597044 -61.419684) (xy 57.611204 -61.405531)
			(xy 57.629702 -61.397874) (xy 57.639712 -61.397388) (xy 57.649426 -61.397808) (xy 57.667461 -61.405034)
			(xy 57.681517 -61.418446) (xy 57.68594 -61.427106) (xy 58.564272 -63.343282) (xy 59.178698 -63.061596)
			(xy 58.299858 -61.145166) (xy 58.297722 -61.140161) (xy 58.295424 -61.129525) (xy 58.295286 -61.124084)
			(xy 58.295774 -61.114077) (xy 58.303437 -61.095587) (xy 58.317589 -61.081436) (xy 58.336079 -61.073774)
			(xy 58.346086 -61.073284) (xy 58.355798 -61.073725) (xy 58.373832 -61.080942) (xy 58.387889 -61.094346)
			(xy 58.392314 -61.103002) (xy 59.292236 -63.065406) (xy 59.294364 -63.070414) (xy 59.296667 -63.081048)
			(xy 59.296808 -63.086488) (xy 59.296373 -63.096201) (xy 59.289154 -63.114235) (xy 59.275747 -63.128292)
			(xy 59.26709 -63.132716) (xy 58.743764 -63.372746) (xy 61.629036 -63.372746) (xy 61.629458 -63.362723)
			(xy 61.63712 -63.3442) (xy 61.651292 -63.330025) (xy 61.669813 -63.32236) (xy 61.679836 -63.321946)
			(xy 61.689549 -63.322389) (xy 61.707587 -63.329598) (xy 61.721643 -63.343005) (xy 61.726064 -63.351664)
			(xy 62.604396 -65.26784) (xy 63.218822 -64.986154) (xy 62.339982 -63.069724) (xy 62.337864 -63.064712)
			(xy 62.335554 -63.054081) (xy 62.33541 -63.048642) (xy 62.335854 -63.038622) (xy 62.343512 -63.020104)
			(xy 62.357677 -63.00593) (xy 62.37619 -62.998261) (xy 62.38621 -62.997842) (xy 62.395928 -62.998233)
			(xy 62.413967 -63.005468) (xy 62.42802 -63.018893) (xy 62.432438 -63.02756) (xy 63.33236 -64.989964)
			(xy 63.334471 -64.994979) (xy 63.336786 -65.005607) (xy 63.336932 -65.011046) (xy 63.336453 -65.020754)
			(xy 63.329252 -65.038785) (xy 63.315864 -65.052846) (xy 63.307214 -65.057274) (xy 62.600586 -65.381378)
			(xy 62.595577 -65.383505) (xy 62.584944 -65.385809) (xy 62.579504 -65.38595) (xy 62.569787 -65.385553)
			(xy 62.551747 -65.378322) (xy 62.537693 -65.364898) (xy 62.533276 -65.356232) (xy 61.633608 -63.393828)
			(xy 61.631492 -63.388815) (xy 61.629181 -63.378185) (xy 61.629036 -63.372746) (xy 58.743764 -63.372746)
			(xy 58.560462 -63.45682) (xy 58.555457 -63.458957) (xy 58.544821 -63.461254) (xy 58.53938 -63.461392)
			(xy 58.529664 -63.460989) (xy 58.511627 -63.453757) (xy 58.497572 -63.440337) (xy 58.493152 -63.431674)
			(xy 57.593484 -61.46927) (xy 57.59135 -61.464264) (xy 57.58905 -61.453629) (xy 57.588912 -61.448188)
			(xy 48.073204 -61.448188) (xy 48.145442 -61.494969) (xy 48.318064 -61.616389) (xy 48.48591 -61.744332)
			(xy 48.648732 -61.87861) (xy 48.715546 -61.938154) (xy 55.692802 -61.938154) (xy 55.693251 -61.928143)
			(xy 55.700926 -61.90965) (xy 55.71509 -61.895499) (xy 55.733591 -61.887841) (xy 55.743602 -61.887354)
			(xy 55.75332 -61.887744) (xy 55.77136 -61.894978) (xy 55.785413 -61.908405) (xy 55.78983 -61.917072)
			(xy 56.668162 -63.833248) (xy 57.282588 -63.551562) (xy 56.403748 -61.635132) (xy 56.401631 -61.63012)
			(xy 56.399321 -61.619489) (xy 56.399176 -61.61405) (xy 56.399647 -61.604042) (xy 56.407318 -61.585554)
			(xy 56.421476 -61.571404) (xy 56.439968 -61.563742) (xy 56.449976 -61.56325) (xy 56.459692 -61.563661)
			(xy 56.477731 -61.570885) (xy 56.491786 -61.584304) (xy 56.496204 -61.592968) (xy 57.396126 -63.555372)
			(xy 57.398243 -63.560384) (xy 57.400554 -63.571015) (xy 57.400698 -63.576454) (xy 57.400244 -63.586165)
			(xy 57.393035 -63.604199) (xy 57.379635 -63.618258) (xy 57.37098 -63.622682) (xy 56.664352 -63.946786)
			(xy 56.659347 -63.948923) (xy 56.648711 -63.951221) (xy 56.64327 -63.951358) (xy 56.633551 -63.950982)
			(xy 56.615511 -63.94374) (xy 56.601458 -63.930309) (xy 56.597042 -63.92164) (xy 55.697374 -61.959236)
			(xy 55.695259 -61.954223) (xy 55.692947 -61.943593) (xy 55.692802 -61.938154) (xy 48.715546 -61.938154)
			(xy 48.806291 -62.019026) (xy 48.958356 -62.165374) (xy 49.104704 -62.317439) (xy 49.24512 -62.474998)
			(xy 49.277052 -62.513718) (xy 53.866288 -62.513718) (xy 53.866734 -62.503699) (xy 53.874396 -62.485185)
			(xy 53.88856 -62.471012) (xy 53.90707 -62.46334) (xy 53.917088 -62.462918) (xy 53.926803 -62.463339)
			(xy 53.944839 -62.470562) (xy 53.958895 -62.483975) (xy 53.963316 -62.492636) (xy 54.841902 -64.408812)
			(xy 55.456328 -64.126872) (xy 54.577234 -62.210696) (xy 54.575111 -62.205686) (xy 54.572804 -62.195054)
			(xy 54.572662 -62.189614) (xy 54.573199 -62.179612) (xy 54.580846 -62.161128) (xy 54.594984 -62.146976)
			(xy 54.61346 -62.139309) (xy 54.623462 -62.138814) (xy 54.633175 -62.139256) (xy 54.65121 -62.146469)
			(xy 54.665267 -62.159874) (xy 54.66969 -62.168532) (xy 55.569866 -64.130682) (xy 55.571983 -64.135695)
			(xy 55.574294 -64.146325) (xy 55.574438 -64.151764) (xy 55.574113 -64.159384) (xy 59.920632 -64.159384)
			(xy 59.921007 -64.149358) (xy 59.928689 -64.130834) (xy 59.942875 -64.116662) (xy 59.961405 -64.108998)
			(xy 59.971432 -64.108584) (xy 59.98114 -64.109065) (xy 59.999172 -64.116263) (xy 60.013233 -64.129652)
			(xy 60.01766 -64.138302) (xy 60.896246 -66.054478) (xy 61.510672 -65.772538) (xy 60.631578 -63.856362)
			(xy 60.629441 -63.851357) (xy 60.627144 -63.840721) (xy 60.627006 -63.83528) (xy 60.627472 -63.82527)
			(xy 60.635139 -63.806777) (xy 60.649299 -63.792624) (xy 60.667796 -63.784967) (xy 60.677806 -63.78448)
			(xy 60.687519 -63.784909) (xy 60.705553 -63.792132) (xy 60.71961 -63.80554) (xy 60.724034 -63.814198)
			(xy 61.62421 -65.776348) (xy 61.626349 -65.781352) (xy 61.628645 -65.791989) (xy 61.628782 -65.79743)
			(xy 61.628392 -65.807148) (xy 61.621155 -65.825185) (xy 61.60773 -65.839239) (xy 61.599064 -65.843658)
			(xy 60.892436 -66.168016) (xy 60.887422 -66.170131) (xy 60.876793 -66.172443) (xy 60.871354 -66.172588)
			(xy 60.861643 -66.172133) (xy 60.843608 -66.164926) (xy 60.82955 -66.151525) (xy 60.825126 -66.14287)
			(xy 59.925204 -64.180466) (xy 59.92307 -64.17546) (xy 59.92077 -64.164825) (xy 59.920632 -64.159384)
			(xy 55.574113 -64.159384) (xy 55.574024 -64.16148) (xy 55.566803 -64.17952) (xy 55.553384 -64.193574)
			(xy 55.54472 -64.197992) (xy 54.838092 -64.52235) (xy 54.833084 -64.524479) (xy 54.82245 -64.526781)
			(xy 54.81701 -64.526922) (xy 54.807298 -64.52648) (xy 54.789265 -64.519263) (xy 54.775207 -64.50586)
			(xy 54.770782 -64.497204) (xy 53.87086 -62.5348) (xy 53.868734 -62.529791) (xy 53.866429 -62.519158)
			(xy 53.866288 -62.513718) (xy 49.277052 -62.513718) (xy 49.379398 -62.63782) (xy 49.507341 -62.805666)
			(xy 49.628761 -62.978288) (xy 49.704423 -63.095124) (xy 52.052728 -63.095124) (xy 52.05314 -63.085101)
			(xy 52.060807 -63.066579) (xy 52.074982 -63.052405) (xy 52.093505 -63.044739) (xy 52.103528 -63.044324)
			(xy 52.113246 -63.044712) (xy 52.131284 -63.05195) (xy 52.145338 -63.065376) (xy 52.149756 -63.074042)
			(xy 53.028088 -64.990218) (xy 53.642514 -64.708532) (xy 52.763674 -62.792102) (xy 52.761549 -62.787092)
			(xy 52.759244 -62.77646) (xy 52.759102 -62.77102) (xy 52.759536 -62.761) (xy 52.7672 -62.742483)
			(xy 52.781368 -62.72831) (xy 52.799882 -62.72064) (xy 52.809902 -62.72022) (xy 52.819618 -62.72063)
			(xy 52.837655 -62.727857) (xy 52.85171 -62.741275) (xy 52.85613 -62.749938) (xy 53.756052 -64.712342)
			(xy 53.758191 -64.717346) (xy 53.760487 -64.727983) (xy 53.760624 -64.733424) (xy 53.760206 -64.743138)
			(xy 53.752978 -64.761172) (xy 53.739565 -64.775228) (xy 53.730906 -64.779652) (xy 53.50164 -64.884808)
			(xy 58.112406 -64.884808) (xy 58.112826 -64.874786) (xy 58.120495 -64.856269) (xy 58.134667 -64.842096)
			(xy 58.153184 -64.834427) (xy 58.163206 -64.834008) (xy 58.172921 -64.834421) (xy 58.190957 -64.841649)
			(xy 58.205013 -64.855064) (xy 58.209434 -64.863726) (xy 59.087766 -66.779902) (xy 59.702192 -66.498216)
			(xy 58.823352 -64.581786) (xy 58.821221 -64.576779) (xy 58.81892 -64.566144) (xy 58.81878 -64.560704)
			(xy 58.819291 -64.550699) (xy 58.826945 -64.532211) (xy 58.841091 -64.518059) (xy 58.859575 -64.510396)
			(xy 58.86958 -64.509904) (xy 58.879293 -64.510338) (xy 58.897328 -64.517556) (xy 58.911385 -64.530964)
			(xy 58.915808 -64.539622) (xy 59.81573 -66.502026) (xy 59.817863 -66.507032) (xy 59.820163 -66.517667)
			(xy 59.820302 -66.523108) (xy 59.819885 -66.532823) (xy 59.812658 -66.550858) (xy 59.799245 -66.564914)
			(xy 59.790584 -66.569336) (xy 59.083956 -66.89344) (xy 59.078952 -66.895579) (xy 59.068315 -66.897875)
			(xy 59.062874 -66.898012) (xy 59.053159 -66.897602) (xy 59.035124 -66.890371) (xy 59.021068 -66.876955)
			(xy 59.016646 -66.868294) (xy 58.116978 -64.90589) (xy 58.11485 -64.900882) (xy 58.112547 -64.890248)
			(xy 58.112406 -64.884808) (xy 53.50164 -64.884808) (xy 53.024278 -65.103756) (xy 53.019272 -65.105889)
			(xy 53.008636 -65.108189) (xy 53.003196 -65.108328) (xy 52.993484 -65.107893) (xy 52.97545 -65.100672)
			(xy 52.961393 -65.087267) (xy 52.956968 -65.07861) (xy 52.0573 -63.116206) (xy 52.055177 -63.111196)
			(xy 52.05287 -63.100564) (xy 52.052728 -63.095124) (xy 49.704423 -63.095124) (xy 49.74348 -63.155435)
			(xy 49.85133 -63.336846) (xy 49.952152 -63.522255) (xy 50.045799 -63.71139) (xy 50.132132 -63.903972)
			(xy 50.211026 -64.09972) (xy 50.282364 -64.298347) (xy 50.346041 -64.49956) (xy 50.401965 -64.703064)
			(xy 50.450053 -64.908561) (xy 50.490235 -65.115749) (xy 50.522452 -65.324324) (xy 50.53329 -65.418208)
			(xy 56.24576 -65.418208) (xy 56.246294 -65.408206) (xy 56.253943 -65.389722) (xy 56.268082 -65.37557)
			(xy 56.286558 -65.367903) (xy 56.29656 -65.367408) (xy 56.306272 -65.367855) (xy 56.324307 -65.375066)
			(xy 56.338365 -65.388469) (xy 56.342788 -65.397126) (xy 57.22112 -67.313302) (xy 57.835546 -67.031616)
			(xy 56.956706 -65.115186) (xy 56.954578 -65.110178) (xy 56.952274 -65.099544) (xy 56.952134 -65.094104)
			(xy 56.952524 -65.084079) (xy 56.960199 -65.065555) (xy 56.974381 -65.051382) (xy 56.992908 -65.043718)
			(xy 57.002934 -65.043304) (xy 57.012644 -65.043772) (xy 57.030678 -65.050974) (xy 57.044737 -65.064369)
			(xy 57.049162 -65.073022) (xy 57.949084 -67.035426) (xy 57.951215 -67.040433) (xy 57.953516 -67.051068)
			(xy 57.953656 -67.056508) (xy 57.953264 -67.066226) (xy 57.946031 -67.084265) (xy 57.932605 -67.098319)
			(xy 57.923938 -67.102736) (xy 57.21731 -67.42684) (xy 57.2123 -67.428963) (xy 57.201668 -67.43127)
			(xy 57.196228 -67.431412) (xy 57.186517 -67.430963) (xy 57.168483 -67.42375) (xy 57.154425 -67.410349)
			(xy 57.15 -67.401694) (xy 56.250332 -65.43929) (xy 56.248207 -65.434281) (xy 56.245901 -65.423648)
			(xy 56.24576 -65.418208) (xy 50.53329 -65.418208) (xy 50.546655 -65.533981) (xy 50.562811 -65.74441)
			(xy 50.570895 -65.955304) (xy 50.571037 -65.984882) (xy 54.400704 -65.984882) (xy 54.401173 -65.974873)
			(xy 54.408839 -65.95638) (xy 54.422998 -65.942227) (xy 54.441494 -65.934569) (xy 54.451504 -65.934082)
			(xy 54.461217 -65.934511) (xy 54.479251 -65.941734) (xy 54.493308 -65.955142) (xy 54.497732 -65.9638)
			(xy 55.376064 -67.879976) (xy 55.99049 -67.59829) (xy 55.11165 -65.68186) (xy 55.109511 -65.676856)
			(xy 55.107215 -65.666219) (xy 55.107078 -65.660778) (xy 55.107569 -65.650772) (xy 55.115232 -65.632284)
			(xy 55.129384 -65.618132) (xy 55.147872 -65.610469) (xy 55.157878 -65.609978) (xy 55.167589 -65.610429)
			(xy 55.185622 -65.617641) (xy 55.19968 -65.631042) (xy 55.204106 -65.639696) (xy 56.104028 -67.6021)
			(xy 56.106154 -67.607109) (xy 56.108458 -67.617742) (xy 56.1086 -67.623182) (xy 56.108165 -67.632895)
			(xy 56.100947 -67.65093) (xy 56.08754 -67.664987) (xy 56.078882 -67.66941) (xy 55.372254 -67.993514)
			(xy 55.36725 -67.995653) (xy 55.356613 -67.997949) (xy 55.351172 -67.998086) (xy 55.341455 -67.997692)
			(xy 55.323417 -67.990456) (xy 55.309363 -67.977033) (xy 55.304944 -67.968368) (xy 54.405276 -66.005964)
			(xy 54.40314 -66.000959) (xy 54.400842 -65.990323) (xy 54.400704 -65.984882) (xy 50.571037 -65.984882)
			(xy 50.5714 -66.060828) (xy 50.5714 -66.798698) (xy 52.727606 -66.798698) (xy 52.728018 -66.788676)
			(xy 52.73569 -66.770158) (xy 52.749864 -66.755985) (xy 52.768384 -66.748316) (xy 52.778406 -66.747898)
			(xy 52.78812 -66.748317) (xy 52.806156 -66.755542) (xy 52.820212 -66.768956) (xy 52.824634 -66.777616)
			(xy 53.702966 -68.693792) (xy 54.317392 -68.412106) (xy 53.438552 -66.495676) (xy 53.436418 -66.49067)
			(xy 53.434119 -66.480035) (xy 53.43398 -66.474594) (xy 53.434483 -66.464588) (xy 53.442141 -66.4461)
			(xy 53.456289 -66.431948) (xy 53.474775 -66.424286) (xy 53.48478 -66.423794) (xy 53.494492 -66.424234)
			(xy 53.512527 -66.43145) (xy 53.526584 -66.444855) (xy 53.531008 -66.453512) (xy 54.43093 -68.415916)
			(xy 54.433061 -68.420923) (xy 54.435362 -68.431558) (xy 54.435502 -68.436998) (xy 54.435077 -68.446712)
			(xy 54.427854 -68.464747) (xy 54.414443 -68.478803) (xy 54.405784 -68.483226) (xy 53.699156 -68.80733)
			(xy 53.694152 -68.809469) (xy 53.683515 -68.811765) (xy 53.678074 -68.811902) (xy 53.668358 -68.811498)
			(xy 53.650322 -68.804265) (xy 53.636267 -68.790847) (xy 53.631846 -68.782184) (xy 52.732178 -66.81978)
			(xy 52.730047 -66.814773) (xy 52.727745 -66.804138) (xy 52.727606 -66.798698) (xy 50.5714 -66.798698)
			(xy 50.5714 -69.552312) (xy 52.967382 -69.552312) (xy 52.967897 -69.542307) (xy 52.97555 -69.523819)
			(xy 52.989694 -69.509666) (xy 53.008178 -69.502003) (xy 53.018182 -69.501512) (xy 53.027896 -69.50194)
			(xy 53.045932 -69.50916) (xy 53.059988 -69.52257) (xy 53.06441 -69.53123) (xy 53.942742 -71.447406)
			(xy 54.557168 -71.16572) (xy 53.678328 -69.24929) (xy 53.676202 -69.244281) (xy 53.673897 -69.233648)
			(xy 53.673756 -69.228208) (xy 53.674294 -69.218206) (xy 53.681942 -69.199723) (xy 53.696079 -69.185571)
			(xy 53.714555 -69.177904) (xy 53.724556 -69.177408) (xy 53.734268 -69.177857) (xy 53.752303 -69.185068)
			(xy 53.766361 -69.19847) (xy 53.770784 -69.207126) (xy 54.670706 -71.16953) (xy 54.672839 -71.174536)
			(xy 54.675139 -71.185171) (xy 54.675278 -71.190612) (xy 54.674877 -71.200329) (xy 54.667645 -71.218366)
			(xy 54.654224 -71.23242) (xy 54.64556 -71.23684) (xy 53.938932 -71.560944) (xy 53.933919 -71.563061)
			(xy 53.923289 -71.565371) (xy 53.91785 -71.565516) (xy 53.90814 -71.565049) (xy 53.890108 -71.557844)
			(xy 53.876048 -71.54445) (xy 53.871622 -71.535798) (xy 52.971954 -69.573394) (xy 52.969826 -69.568386)
			(xy 52.967523 -69.557752) (xy 52.967382 -69.552312) (xy 50.5714 -69.552312) (xy 50.5714 -74.760836)
			(xy 50.571366 -74.767948) (xy 173.354492 -74.767948) (xy 173.354492 -66.06794) (xy 173.354997 -65.962416)
			(xy 173.363081 -65.751522) (xy 173.379237 -65.541093) (xy 173.40344 -65.331436) (xy 173.435657 -65.122861)
			(xy 173.475839 -64.915673) (xy 173.523927 -64.710176) (xy 173.579851 -64.506672) (xy 173.643528 -64.305459)
			(xy 173.714866 -64.106832) (xy 173.79376 -63.911084) (xy 173.880093 -63.718502) (xy 173.97374 -63.529367)
			(xy 174.074562 -63.343958) (xy 174.182412 -63.162547) (xy 174.297131 -62.9854) (xy 174.418551 -62.812778)
			(xy 174.546494 -62.644932) (xy 174.680772 -62.48211) (xy 174.821188 -62.324551) (xy 174.967536 -62.172486)
			(xy 175.119601 -62.026138) (xy 175.27716 -61.885722) (xy 175.439982 -61.751444) (xy 175.607828 -61.623501)
			(xy 175.78045 -61.502081) (xy 175.957597 -61.387362) (xy 176.139008 -61.279512) (xy 176.324417 -61.17869)
			(xy 176.513552 -61.085043) (xy 176.706134 -60.99871) (xy 176.901882 -60.919816) (xy 177.100509 -60.848478)
			(xy 177.301722 -60.784801) (xy 177.505226 -60.728877) (xy 177.710723 -60.680789) (xy 177.917911 -60.640607)
			(xy 178.126486 -60.60839) (xy 178.336143 -60.584187) (xy 178.546572 -60.568031) (xy 178.757466 -60.559947)
			(xy 178.968514 -60.559947) (xy 179.179408 -60.568031) (xy 179.389837 -60.584187) (xy 179.599494 -60.60839)
			(xy 179.808069 -60.640607) (xy 180.015257 -60.680789) (xy 180.220754 -60.728877) (xy 180.424258 -60.784801)
			(xy 180.625471 -60.848478) (xy 180.824098 -60.919816) (xy 181.019846 -60.99871) (xy 181.212428 -61.085043)
			(xy 181.401563 -61.17869) (xy 181.586972 -61.279512) (xy 181.768383 -61.387362) (xy 181.94553 -61.502081)
			(xy 182.118152 -61.623501) (xy 182.285998 -61.751444) (xy 182.44882 -61.885722) (xy 182.606379 -62.026138)
			(xy 182.758444 -62.172486) (xy 182.904792 -62.324551) (xy 183.045208 -62.48211) (xy 183.179486 -62.644932)
			(xy 183.307429 -62.812778) (xy 183.428849 -62.9854) (xy 183.543568 -63.162547) (xy 183.651418 -63.343958)
			(xy 183.75224 -63.529367) (xy 183.845887 -63.718502) (xy 183.93222 -63.911084) (xy 184.011114 -64.106832)
			(xy 184.082452 -64.305459) (xy 184.146129 -64.506672) (xy 184.202053 -64.710176) (xy 184.250141 -64.915673)
			(xy 184.290323 -65.122861) (xy 184.32254 -65.331436) (xy 184.346743 -65.541093) (xy 184.362899 -65.751522)
			(xy 184.370983 -65.962416) (xy 184.371488 -66.06794) (xy 184.371488 -74.760836) (xy 287.494472 -74.760836)
			(xy 287.494472 -66.060828) (xy 287.494977 -65.955304) (xy 287.503061 -65.74441) (xy 287.519217 -65.533981)
			(xy 287.54342 -65.324324) (xy 287.575637 -65.115749) (xy 287.615819 -64.908561) (xy 287.663907 -64.703064)
			(xy 287.719831 -64.49956) (xy 287.783508 -64.298347) (xy 287.854846 -64.09972) (xy 287.93374 -63.903972)
			(xy 288.020073 -63.71139) (xy 288.11372 -63.522255) (xy 288.214542 -63.336846) (xy 288.322392 -63.155435)
			(xy 288.437111 -62.978288) (xy 288.558531 -62.805666) (xy 288.686474 -62.63782) (xy 288.820752 -62.474998)
			(xy 288.961168 -62.317439) (xy 289.107516 -62.165374) (xy 289.259581 -62.019026) (xy 289.41714 -61.87861)
			(xy 289.579962 -61.744332) (xy 289.747808 -61.616389) (xy 289.92043 -61.494969) (xy 290.097577 -61.38025)
			(xy 290.278988 -61.2724) (xy 290.464397 -61.171578) (xy 290.653532 -61.077931) (xy 290.846114 -60.991598)
			(xy 291.041862 -60.912704) (xy 291.240489 -60.841366) (xy 291.441702 -60.777689) (xy 291.645206 -60.721765)
			(xy 291.850703 -60.673677) (xy 292.057891 -60.633495) (xy 292.266466 -60.601278) (xy 292.476123 -60.577075)
			(xy 292.686552 -60.560919) (xy 292.897446 -60.552835) (xy 293.108494 -60.552835) (xy 293.319388 -60.560919)
			(xy 293.529817 -60.577075) (xy 293.739474 -60.601278) (xy 293.948049 -60.633495) (xy 294.155237 -60.673677)
			(xy 294.360734 -60.721765) (xy 294.489149 -60.757054) (xy 350.220788 -60.757054) (xy 350.220788 -60.426854)
			(xy 350.221169 -60.414757) (xy 350.228644 -60.391747) (xy 350.242851 -60.372164) (xy 350.262405 -60.357916)
			(xy 350.2854 -60.350394) (xy 350.297496 -60.349892) (xy 350.551496 -60.349892) (xy 350.563604 -60.350319)
			(xy 350.58663 -60.357817) (xy 350.606202 -60.372076) (xy 350.620397 -60.391695) (xy 350.62782 -60.414745)
			(xy 350.628204 -60.426854) (xy 350.628204 -60.757054) (xy 350.754188 -60.757054) (xy 350.754188 -60.426854)
			(xy 350.754569 -60.414757) (xy 350.762044 -60.391747) (xy 350.776251 -60.372164) (xy 350.795805 -60.357916)
			(xy 350.8188 -60.350394) (xy 350.830896 -60.349892) (xy 351.084896 -60.349892) (xy 351.097004 -60.350319)
			(xy 351.12003 -60.357817) (xy 351.139602 -60.372076) (xy 351.153797 -60.391695) (xy 351.16122 -60.414745)
			(xy 351.161604 -60.426854) (xy 351.161604 -60.757054) (xy 351.161054 -60.769137) (xy 351.153616 -60.792129)
			(xy 351.139449 -60.811705) (xy 351.119935 -60.825959) (xy 351.096977 -60.8335) (xy 351.084896 -60.834016)
			(xy 350.830896 -60.834016) (xy 350.818789 -60.833587) (xy 350.795764 -60.826089) (xy 350.776192 -60.81183)
			(xy 350.761997 -60.792212) (xy 350.754573 -60.769163) (xy 350.754188 -60.757054) (xy 350.628204 -60.757054)
			(xy 350.627654 -60.769137) (xy 350.620216 -60.792129) (xy 350.606049 -60.811705) (xy 350.586535 -60.825959)
			(xy 350.563577 -60.8335) (xy 350.551496 -60.834016) (xy 350.297496 -60.834016) (xy 350.285389 -60.833587)
			(xy 350.262364 -60.826089) (xy 350.242792 -60.81183) (xy 350.228597 -60.792212) (xy 350.221173 -60.769163)
			(xy 350.220788 -60.757054) (xy 294.489149 -60.757054) (xy 294.564238 -60.777689) (xy 294.765451 -60.841366)
			(xy 294.964078 -60.912704) (xy 295.159826 -60.991598) (xy 295.352408 -61.077931) (xy 295.541543 -61.171578)
			(xy 295.726952 -61.2724) (xy 295.908363 -61.38025) (xy 296.08551 -61.494969) (xy 296.258132 -61.616389)
			(xy 296.330371 -61.671454) (xy 350.220788 -61.671454) (xy 350.220788 -61.341254) (xy 350.221169 -61.329157)
			(xy 350.228644 -61.306147) (xy 350.242851 -61.286564) (xy 350.262405 -61.272316) (xy 350.2854 -61.264794)
			(xy 350.297496 -61.264292) (xy 350.551496 -61.264292) (xy 350.563604 -61.264719) (xy 350.58663 -61.272217)
			(xy 350.606202 -61.286476) (xy 350.620397 -61.306095) (xy 350.62782 -61.329145) (xy 350.628204 -61.341254)
			(xy 350.628204 -61.671454) (xy 350.754188 -61.671454) (xy 350.754188 -61.341254) (xy 350.754569 -61.329157)
			(xy 350.762044 -61.306147) (xy 350.776251 -61.286564) (xy 350.795805 -61.272316) (xy 350.8188 -61.264794)
			(xy 350.830896 -61.264292) (xy 351.084896 -61.264292) (xy 351.097004 -61.264719) (xy 351.12003 -61.272217)
			(xy 351.139602 -61.286476) (xy 351.153797 -61.306095) (xy 351.16122 -61.329145) (xy 351.161604 -61.341254)
			(xy 351.161604 -61.480954) (xy 351.822512 -61.480954) (xy 351.822512 -60.617354) (xy 351.822998 -60.590103)
			(xy 351.830754 -60.536155) (xy 351.846109 -60.48386) (xy 351.868751 -60.434283) (xy 351.898217 -60.388433)
			(xy 351.933908 -60.347242) (xy 351.975099 -60.311551) (xy 352.020949 -60.282085) (xy 352.070526 -60.259443)
			(xy 352.122821 -60.244088) (xy 352.176769 -60.236332) (xy 352.231271 -60.236332) (xy 352.285219 -60.244088)
			(xy 352.337514 -60.259443) (xy 352.387091 -60.282085) (xy 352.432941 -60.311551) (xy 352.474132 -60.347242)
			(xy 352.509823 -60.388433) (xy 352.539289 -60.434283) (xy 352.561931 -60.48386) (xy 352.577286 -60.536155)
			(xy 352.585042 -60.590103) (xy 352.585528 -60.617354) (xy 352.585528 -61.223271) (xy 355.46889 -61.223271)
			(xy 355.46889 -61.168729) (xy 355.476653 -61.114741) (xy 355.492019 -61.062408) (xy 355.514676 -61.012794)
			(xy 355.544164 -60.966909) (xy 355.579881 -60.925688) (xy 355.621101 -60.88997) (xy 355.666985 -60.860481)
			(xy 355.716598 -60.837822) (xy 355.768931 -60.822455) (xy 355.822919 -60.814691) (xy 355.85019 -60.814204)
			(xy 356.71379 -60.814204) (xy 356.741059 -60.814735) (xy 356.795042 -60.822495) (xy 356.847371 -60.837859)
			(xy 356.896981 -60.860514) (xy 356.942862 -60.889999) (xy 356.98408 -60.925713) (xy 357.019795 -60.96693)
			(xy 357.049281 -61.01281) (xy 357.071937 -61.062419) (xy 357.087303 -61.114748) (xy 357.095065 -61.168731)
			(xy 357.095065 -61.223269) (xy 357.087303 -61.277252) (xy 357.071937 -61.329581) (xy 357.049281 -61.37919)
			(xy 357.019795 -61.42507) (xy 356.98408 -61.466287) (xy 356.942862 -61.502001) (xy 356.896981 -61.531486)
			(xy 356.847371 -61.554141) (xy 356.795042 -61.569505) (xy 356.741059 -61.577265) (xy 356.71379 -61.577728)
			(xy 355.85019 -61.577728) (xy 355.822919 -61.577309) (xy 355.768931 -61.569545) (xy 355.716598 -61.554178)
			(xy 355.666985 -61.531519) (xy 355.621101 -61.50203) (xy 355.579881 -61.466312) (xy 355.544164 -61.425091)
			(xy 355.514676 -61.379206) (xy 355.492019 -61.329592) (xy 355.476653 -61.277259) (xy 355.46889 -61.223271)
			(xy 352.585528 -61.223271) (xy 352.585528 -61.480954) (xy 352.585042 -61.508205) (xy 352.577286 -61.562153)
			(xy 352.561931 -61.614448) (xy 352.539289 -61.664025) (xy 352.509823 -61.709875) (xy 352.474132 -61.751066)
			(xy 352.432941 -61.786757) (xy 352.387091 -61.816223) (xy 352.337514 -61.838865) (xy 352.285219 -61.85422)
			(xy 352.231271 -61.861976) (xy 352.176769 -61.861976) (xy 352.122821 -61.85422) (xy 352.070526 -61.838865)
			(xy 352.020949 -61.816223) (xy 351.975099 -61.786757) (xy 351.933908 -61.751066) (xy 351.898217 -61.709875)
			(xy 351.868751 -61.664025) (xy 351.846109 -61.614448) (xy 351.830754 -61.562153) (xy 351.822998 -61.508205)
			(xy 351.822512 -61.480954) (xy 351.161604 -61.480954) (xy 351.161604 -61.671454) (xy 351.161054 -61.683537)
			(xy 351.153616 -61.706529) (xy 351.139449 -61.726105) (xy 351.119935 -61.740359) (xy 351.096977 -61.7479)
			(xy 351.084896 -61.748416) (xy 350.830896 -61.748416) (xy 350.818789 -61.747987) (xy 350.795764 -61.740489)
			(xy 350.776192 -61.72623) (xy 350.761997 -61.706612) (xy 350.754573 -61.683563) (xy 350.754188 -61.671454)
			(xy 350.628204 -61.671454) (xy 350.627654 -61.683537) (xy 350.620216 -61.706529) (xy 350.606049 -61.726105)
			(xy 350.586535 -61.740359) (xy 350.563577 -61.7479) (xy 350.551496 -61.748416) (xy 350.297496 -61.748416)
			(xy 350.285389 -61.747987) (xy 350.262364 -61.740489) (xy 350.242792 -61.72623) (xy 350.228597 -61.706612)
			(xy 350.221173 -61.683563) (xy 350.220788 -61.671454) (xy 296.330371 -61.671454) (xy 296.425978 -61.744332)
			(xy 296.5888 -61.87861) (xy 296.746359 -62.019026) (xy 296.898424 -62.165374) (xy 297.044772 -62.317439)
			(xy 297.185188 -62.474998) (xy 297.257967 -62.563248) (xy 348.614492 -62.563248) (xy 348.614492 -62.233048)
			(xy 348.614954 -62.220968) (xy 348.622408 -62.197987) (xy 348.636601 -62.178436) (xy 348.656144 -62.16423)
			(xy 348.67912 -62.156761) (xy 348.6912 -62.15634) (xy 348.9452 -62.15634) (xy 348.957288 -62.156713)
			(xy 348.980278 -62.164187) (xy 348.999833 -62.178401) (xy 349.014035 -62.197965) (xy 349.021494 -62.22096)
			(xy 349.021908 -62.233048) (xy 349.021908 -62.563248) (xy 349.147892 -62.563248) (xy 349.147892 -62.233048)
			(xy 349.148354 -62.220968) (xy 349.155808 -62.197987) (xy 349.170001 -62.178436) (xy 349.189544 -62.16423)
			(xy 349.21252 -62.156761) (xy 349.2246 -62.15634) (xy 349.4786 -62.15634) (xy 349.490688 -62.156713)
			(xy 349.513678 -62.164187) (xy 349.533233 -62.178401) (xy 349.547435 -62.197965) (xy 349.554894 -62.22096)
			(xy 349.555308 -62.233048) (xy 349.555308 -62.563248) (xy 349.554877 -62.575325) (xy 349.547401 -62.598294)
			(xy 349.533196 -62.61783) (xy 349.513651 -62.632023) (xy 349.490677 -62.639484) (xy 349.4786 -62.639956)
			(xy 349.2246 -62.639956) (xy 349.21253 -62.639436) (xy 349.189571 -62.63198) (xy 349.170038 -62.617796)
			(xy 349.155842 -62.598272) (xy 349.148371 -62.575317) (xy 349.147892 -62.563248) (xy 349.021908 -62.563248)
			(xy 349.021477 -62.575325) (xy 349.014001 -62.598294) (xy 348.999796 -62.61783) (xy 348.980251 -62.632023)
			(xy 348.957277 -62.639484) (xy 348.9452 -62.639956) (xy 348.6912 -62.639956) (xy 348.67913 -62.639436)
			(xy 348.656171 -62.63198) (xy 348.636638 -62.617796) (xy 348.622442 -62.598272) (xy 348.614971 -62.575317)
			(xy 348.614492 -62.563248) (xy 297.257967 -62.563248) (xy 297.319466 -62.63782) (xy 297.447409 -62.805666)
			(xy 297.568829 -62.978288) (xy 297.683548 -63.155435) (xy 297.791398 -63.336846) (xy 297.867964 -63.477648)
			(xy 348.614492 -63.477648) (xy 348.614492 -63.147448) (xy 348.614954 -63.135368) (xy 348.622408 -63.112387)
			(xy 348.636601 -63.092836) (xy 348.656144 -63.07863) (xy 348.67912 -63.071161) (xy 348.6912 -63.07074)
			(xy 348.9452 -63.07074) (xy 348.957288 -63.071113) (xy 348.980278 -63.078587) (xy 348.999833 -63.092801)
			(xy 349.014035 -63.112365) (xy 349.021494 -63.13536) (xy 349.021908 -63.147448) (xy 349.021908 -63.477648)
			(xy 349.147892 -63.477648) (xy 349.147892 -63.147448) (xy 349.148354 -63.135368) (xy 349.155808 -63.112387)
			(xy 349.170001 -63.092836) (xy 349.189544 -63.07863) (xy 349.21252 -63.071161) (xy 349.2246 -63.07074)
			(xy 349.4786 -63.07074) (xy 349.490688 -63.071113) (xy 349.513678 -63.078587) (xy 349.533233 -63.092801)
			(xy 349.547435 -63.112365) (xy 349.554894 -63.13536) (xy 349.555308 -63.147448) (xy 349.555308 -63.269876)
			(xy 350.300544 -63.269876) (xy 350.300544 -62.406276) (xy 350.30103 -62.379025) (xy 350.308786 -62.325077)
			(xy 350.324141 -62.272782) (xy 350.346783 -62.223205) (xy 350.376249 -62.177355) (xy 350.41194 -62.136164)
			(xy 350.453131 -62.100473) (xy 350.498981 -62.071007) (xy 350.548558 -62.048365) (xy 350.600853 -62.03301)
			(xy 350.654801 -62.025254) (xy 350.709303 -62.025254) (xy 350.763251 -62.03301) (xy 350.815546 -62.048365)
			(xy 350.865123 -62.071007) (xy 350.910973 -62.100473) (xy 350.952164 -62.136164) (xy 350.987855 -62.177355)
			(xy 351.017321 -62.223205) (xy 351.039963 -62.272782) (xy 351.055318 -62.325077) (xy 351.063074 -62.379025)
			(xy 351.06356 -62.406276) (xy 351.06356 -63.269876) (xy 351.063074 -63.297127) (xy 351.055318 -63.351075)
			(xy 351.039963 -63.40337) (xy 351.017321 -63.452947) (xy 350.987855 -63.498797) (xy 350.952164 -63.539988)
			(xy 350.910973 -63.575679) (xy 350.865123 -63.605145) (xy 350.815546 -63.627787) (xy 350.763251 -63.643142)
			(xy 350.709303 -63.650898) (xy 350.654801 -63.650898) (xy 350.600853 -63.643142) (xy 350.548558 -63.627787)
			(xy 350.498981 -63.605145) (xy 350.453131 -63.575679) (xy 350.41194 -63.539988) (xy 350.376249 -63.498797)
			(xy 350.346783 -63.452947) (xy 350.324141 -63.40337) (xy 350.308786 -63.351075) (xy 350.30103 -63.297127)
			(xy 350.300544 -63.269876) (xy 349.555308 -63.269876) (xy 349.555308 -63.477648) (xy 349.554877 -63.489725)
			(xy 349.547401 -63.512694) (xy 349.533196 -63.53223) (xy 349.513651 -63.546423) (xy 349.490677 -63.553884)
			(xy 349.4786 -63.554356) (xy 349.2246 -63.554356) (xy 349.21253 -63.553836) (xy 349.189571 -63.54638)
			(xy 349.170038 -63.532196) (xy 349.155842 -63.512672) (xy 349.148371 -63.489717) (xy 349.147892 -63.477648)
			(xy 349.021908 -63.477648) (xy 349.021477 -63.489725) (xy 349.014001 -63.512694) (xy 348.999796 -63.53223)
			(xy 348.980251 -63.546423) (xy 348.957277 -63.553884) (xy 348.9452 -63.554356) (xy 348.6912 -63.554356)
			(xy 348.67913 -63.553836) (xy 348.656171 -63.54638) (xy 348.636638 -63.532196) (xy 348.622442 -63.512672)
			(xy 348.614971 -63.489717) (xy 348.614492 -63.477648) (xy 297.867964 -63.477648) (xy 297.89222 -63.522255)
			(xy 297.985867 -63.71139) (xy 298.0722 -63.903972) (xy 298.151094 -64.09972) (xy 298.222432 -64.298347)
			(xy 298.286109 -64.49956) (xy 298.342033 -64.703064) (xy 298.390121 -64.908561) (xy 298.396302 -64.940434)
			(xy 325.410068 -64.940434) (xy 325.410068 -64.076834) (xy 325.410554 -64.049565) (xy 325.418316 -63.995581)
			(xy 325.433681 -63.943251) (xy 325.456338 -63.893641) (xy 325.485824 -63.84776) (xy 325.521539 -63.806543)
			(xy 325.562756 -63.770828) (xy 325.608637 -63.741342) (xy 325.658247 -63.718685) (xy 325.710577 -63.70332)
			(xy 325.764561 -63.695558) (xy 325.819099 -63.695558) (xy 325.873083 -63.70332) (xy 325.925413 -63.718685)
			(xy 325.975023 -63.741342) (xy 326.020904 -63.770828) (xy 326.062121 -63.806543) (xy 326.097836 -63.84776)
			(xy 326.127322 -63.893641) (xy 326.149979 -63.943251) (xy 326.165344 -63.995581) (xy 326.173106 -64.049565)
			(xy 326.173592 -64.076834) (xy 326.173592 -64.605662) (xy 351.205292 -64.605662) (xy 351.205292 -64.275462)
			(xy 351.205774 -64.263375) (xy 351.213235 -64.240381) (xy 351.22742 -64.220806) (xy 351.246947 -64.206555)
			(xy 351.269915 -64.199016) (xy 351.282 -64.1985) (xy 351.536 -64.1985) (xy 351.548109 -64.198916)
			(xy 351.571136 -64.206416) (xy 351.590709 -64.220677) (xy 351.604904 -64.240299) (xy 351.612325 -64.263352)
			(xy 351.612708 -64.275462) (xy 351.612708 -64.605662) (xy 351.738692 -64.605662) (xy 351.738692 -64.275462)
			(xy 351.739174 -64.263375) (xy 351.746635 -64.240381) (xy 351.76082 -64.220806) (xy 351.780347 -64.206555)
			(xy 351.803315 -64.199016) (xy 351.8154 -64.1985) (xy 352.0694 -64.1985) (xy 352.081509 -64.198916)
			(xy 352.104536 -64.206416) (xy 352.124109 -64.220677) (xy 352.138304 -64.240299) (xy 352.145725 -64.263352)
			(xy 352.146108 -64.275462) (xy 352.146108 -64.605662) (xy 352.145561 -64.617745) (xy 352.138121 -64.640736)
			(xy 352.123953 -64.660313) (xy 352.104439 -64.674566) (xy 352.081481 -64.682108) (xy 352.0694 -64.682624)
			(xy 351.8154 -64.682624) (xy 351.803294 -64.682184) (xy 351.78027 -64.674688) (xy 351.760699 -64.660431)
			(xy 351.746504 -64.640816) (xy 351.739079 -64.61777) (xy 351.738692 -64.605662) (xy 351.612708 -64.605662)
			(xy 351.612161 -64.617745) (xy 351.604721 -64.640736) (xy 351.590553 -64.660313) (xy 351.571039 -64.674566)
			(xy 351.548081 -64.682108) (xy 351.536 -64.682624) (xy 351.282 -64.682624) (xy 351.269894 -64.682184)
			(xy 351.24687 -64.674688) (xy 351.227299 -64.660431) (xy 351.213104 -64.640816) (xy 351.205679 -64.61777)
			(xy 351.205292 -64.605662) (xy 326.173592 -64.605662) (xy 326.173592 -64.940434) (xy 326.173106 -64.967703)
			(xy 326.165344 -65.021687) (xy 326.149979 -65.074017) (xy 326.127322 -65.123627) (xy 326.097836 -65.169508)
			(xy 326.062121 -65.210725) (xy 326.020904 -65.24644) (xy 325.975023 -65.275926) (xy 325.925413 -65.298583)
			(xy 325.873083 -65.313948) (xy 325.819099 -65.32171) (xy 325.764561 -65.32171) (xy 325.710577 -65.313948)
			(xy 325.658247 -65.298583) (xy 325.608637 -65.275926) (xy 325.562756 -65.24644) (xy 325.521539 -65.210725)
			(xy 325.485824 -65.169508) (xy 325.456338 -65.123627) (xy 325.433681 -65.074017) (xy 325.418316 -65.021687)
			(xy 325.410554 -64.967703) (xy 325.410068 -64.940434) (xy 298.396302 -64.940434) (xy 298.430303 -65.115749)
			(xy 298.46252 -65.324324) (xy 298.485116 -65.520062) (xy 351.205292 -65.520062) (xy 351.205292 -65.189862)
			(xy 351.205774 -65.177775) (xy 351.213235 -65.154781) (xy 351.22742 -65.135206) (xy 351.246947 -65.120955)
			(xy 351.269915 -65.113416) (xy 351.282 -65.1129) (xy 351.536 -65.1129) (xy 351.548109 -65.113316)
			(xy 351.571136 -65.120816) (xy 351.590709 -65.135077) (xy 351.604904 -65.154699) (xy 351.612325 -65.177752)
			(xy 351.612708 -65.189862) (xy 351.612708 -65.520062) (xy 351.738692 -65.520062) (xy 351.738692 -65.189862)
			(xy 351.739174 -65.177775) (xy 351.746635 -65.154781) (xy 351.76082 -65.135206) (xy 351.780347 -65.120955)
			(xy 351.803315 -65.113416) (xy 351.8154 -65.1129) (xy 352.0694 -65.1129) (xy 352.081509 -65.113316)
			(xy 352.104536 -65.120816) (xy 352.124109 -65.135077) (xy 352.138304 -65.154699) (xy 352.145725 -65.177752)
			(xy 352.146108 -65.189862) (xy 352.146108 -65.329562) (xy 352.362008 -65.329562) (xy 352.362008 -64.465962)
			(xy 352.362494 -64.438711) (xy 352.37025 -64.384763) (xy 352.385605 -64.332468) (xy 352.408247 -64.282891)
			(xy 352.437713 -64.237041) (xy 352.473404 -64.19585) (xy 352.514595 -64.160159) (xy 352.560445 -64.130693)
			(xy 352.610022 -64.108051) (xy 352.662317 -64.092696) (xy 352.716265 -64.08494) (xy 352.770767 -64.08494)
			(xy 352.824715 -64.092696) (xy 352.87701 -64.108051) (xy 352.926587 -64.130693) (xy 352.972437 -64.160159)
			(xy 353.013628 -64.19585) (xy 353.049319 -64.237041) (xy 353.078785 -64.282891) (xy 353.101427 -64.332468)
			(xy 353.116782 -64.384763) (xy 353.124538 -64.438711) (xy 353.125024 -64.465962) (xy 353.125024 -65.329562)
			(xy 353.124538 -65.356813) (xy 353.116782 -65.410761) (xy 353.101427 -65.463056) (xy 353.078785 -65.512633)
			(xy 353.049319 -65.558483) (xy 353.013628 -65.599674) (xy 352.972437 -65.635365) (xy 352.926587 -65.664831)
			(xy 352.87701 -65.687473) (xy 352.824715 -65.702828) (xy 352.770767 -65.710584) (xy 352.716265 -65.710584)
			(xy 352.662317 -65.702828) (xy 352.610022 -65.687473) (xy 352.560445 -65.664831) (xy 352.514595 -65.635365)
			(xy 352.473404 -65.599674) (xy 352.437713 -65.558483) (xy 352.408247 -65.512633) (xy 352.385605 -65.463056)
			(xy 352.37025 -65.410761) (xy 352.362494 -65.356813) (xy 352.362008 -65.329562) (xy 352.146108 -65.329562)
			(xy 352.146108 -65.520062) (xy 352.145561 -65.532145) (xy 352.138121 -65.555136) (xy 352.123953 -65.574713)
			(xy 352.104439 -65.588966) (xy 352.081481 -65.596508) (xy 352.0694 -65.597024) (xy 351.8154 -65.597024)
			(xy 351.803294 -65.596584) (xy 351.78027 -65.589088) (xy 351.760699 -65.574831) (xy 351.746504 -65.555216)
			(xy 351.739079 -65.53217) (xy 351.738692 -65.520062) (xy 351.612708 -65.520062) (xy 351.612161 -65.532145)
			(xy 351.604721 -65.555136) (xy 351.590553 -65.574713) (xy 351.571039 -65.588966) (xy 351.548081 -65.596508)
			(xy 351.536 -65.597024) (xy 351.282 -65.597024) (xy 351.269894 -65.596584) (xy 351.24687 -65.589088)
			(xy 351.227299 -65.574831) (xy 351.213104 -65.555216) (xy 351.205679 -65.53217) (xy 351.205292 -65.520062)
			(xy 298.485116 -65.520062) (xy 298.486723 -65.533981) (xy 298.502879 -65.74441) (xy 298.510963 -65.955304)
			(xy 298.511468 -66.060828) (xy 298.511468 -66.239644) (xy 348.491556 -66.239644) (xy 348.491556 -65.909444)
			(xy 348.49205 -65.897367) (xy 348.499501 -65.874392) (xy 348.513687 -65.854844) (xy 348.53322 -65.840637)
			(xy 348.556188 -65.833162) (xy 348.568264 -65.832736) (xy 348.822264 -65.832736) (xy 348.834349 -65.833144)
			(xy 348.857338 -65.840607) (xy 348.876893 -65.854813) (xy 348.891097 -65.874369) (xy 348.898557 -65.897359)
			(xy 348.898972 -65.909444) (xy 348.898972 -66.239644) (xy 349.024956 -66.239644) (xy 349.024956 -65.909444)
			(xy 349.02545 -65.897367) (xy 349.032901 -65.874392) (xy 349.047087 -65.854844) (xy 349.06662 -65.840637)
			(xy 349.089588 -65.833162) (xy 349.101664 -65.832736) (xy 349.355664 -65.832736) (xy 349.367749 -65.833144)
			(xy 349.390738 -65.840607) (xy 349.410293 -65.854813) (xy 349.424497 -65.874369) (xy 349.431957 -65.897359)
			(xy 349.432372 -65.909444) (xy 349.432372 -66.239644) (xy 349.431973 -66.251724) (xy 349.424494 -66.274699)
			(xy 349.410282 -66.294239) (xy 349.390727 -66.30843) (xy 349.367745 -66.315885) (xy 349.355664 -66.316352)
			(xy 349.101664 -66.316352) (xy 349.089592 -66.315867) (xy 349.066631 -66.3084) (xy 349.047098 -66.294207)
			(xy 349.032903 -66.274676) (xy 349.025434 -66.251716) (xy 349.024956 -66.239644) (xy 348.898972 -66.239644)
			(xy 348.898573 -66.251724) (xy 348.891094 -66.274699) (xy 348.876882 -66.294239) (xy 348.857327 -66.30843)
			(xy 348.834345 -66.315885) (xy 348.822264 -66.316352) (xy 348.568264 -66.316352) (xy 348.556192 -66.315867)
			(xy 348.533231 -66.3084) (xy 348.513698 -66.294207) (xy 348.499503 -66.274676) (xy 348.492034 -66.251716)
			(xy 348.491556 -66.239644) (xy 298.511468 -66.239644) (xy 298.511468 -68.449952) (xy 314.840884 -68.449952)
			(xy 314.844867 -68.321934) (xy 314.856802 -68.194412) (xy 314.876641 -68.067878) (xy 314.904308 -67.942822)
			(xy 314.939697 -67.819729) (xy 314.98267 -67.699073) (xy 315.033061 -67.581323) (xy 315.090675 -67.466933)
			(xy 315.155289 -67.356346) (xy 315.226653 -67.24999) (xy 315.304491 -67.148277) (xy 315.388502 -67.051599)
			(xy 315.478361 -66.960332) (xy 315.57372 -66.874827) (xy 315.674211 -66.795417) (xy 315.779444 -66.722407)
			(xy 315.889013 -66.656081) (xy 316.002493 -66.596695) (xy 316.119445 -66.544479) (xy 316.239418 -66.499635)
			(xy 316.361946 -66.462337) (xy 316.486557 -66.432728) (xy 316.612766 -66.410923) (xy 316.740088 -66.397007)
			(xy 316.868028 -66.391033) (xy 316.996092 -66.393025) (xy 317.123785 -66.402975) (xy 317.250612 -66.420844)
			(xy 317.376083 -66.446563) (xy 317.499712 -66.480033) (xy 317.621021 -66.521124) (xy 317.739541 -66.569678)
			(xy 317.854813 -66.625506) (xy 317.966391 -66.688392) (xy 318.073844 -66.758094) (xy 318.176756 -66.834341)
			(xy 318.274728 -66.916838) (xy 318.367382 -67.005267) (xy 318.454359 -67.099285) (xy 318.499032 -67.154044)
			(xy 348.491556 -67.154044) (xy 348.491556 -66.823844) (xy 348.49205 -66.811767) (xy 348.499501 -66.788792)
			(xy 348.513687 -66.769244) (xy 348.53322 -66.755037) (xy 348.556188 -66.747562) (xy 348.568264 -66.747136)
			(xy 348.822264 -66.747136) (xy 348.834349 -66.747544) (xy 348.857338 -66.755007) (xy 348.876893 -66.769213)
			(xy 348.891097 -66.788769) (xy 348.898557 -66.811759) (xy 348.898972 -66.823844) (xy 348.898972 -67.154044)
			(xy 349.024956 -67.154044) (xy 349.024956 -66.823844) (xy 349.02545 -66.811767) (xy 349.032901 -66.788792)
			(xy 349.047087 -66.769244) (xy 349.06662 -66.755037) (xy 349.089588 -66.747562) (xy 349.101664 -66.747136)
			(xy 349.355664 -66.747136) (xy 349.367749 -66.747544) (xy 349.390738 -66.755007) (xy 349.410293 -66.769213)
			(xy 349.424497 -66.788769) (xy 349.431957 -66.811759) (xy 349.432372 -66.823844) (xy 349.432372 -66.963544)
			(xy 350.27108 -66.963544) (xy 350.27108 -66.099944) (xy 350.271566 -66.072693) (xy 350.279322 -66.018745)
			(xy 350.294677 -65.96645) (xy 350.317319 -65.916873) (xy 350.346785 -65.871023) (xy 350.382476 -65.829832)
			(xy 350.423667 -65.794141) (xy 350.469517 -65.764675) (xy 350.519094 -65.742033) (xy 350.571389 -65.726678)
			(xy 350.625337 -65.718922) (xy 350.679839 -65.718922) (xy 350.733787 -65.726678) (xy 350.786082 -65.742033)
			(xy 350.835659 -65.764675) (xy 350.881509 -65.794141) (xy 350.9227 -65.829832) (xy 350.958391 -65.871023)
			(xy 350.987857 -65.916873) (xy 351.010499 -65.96645) (xy 351.025854 -66.018745) (xy 351.03361 -66.072693)
			(xy 351.034096 -66.099944) (xy 351.034096 -66.963544) (xy 351.03361 -66.990795) (xy 351.025854 -67.044743)
			(xy 351.010499 -67.097038) (xy 351.005595 -67.107776) (xy 396.642323 -67.107776) (xy 396.642323 -67.022004)
			(xy 396.650237 -66.936596) (xy 396.665998 -66.852284) (xy 396.689471 -66.769785) (xy 396.720456 -66.689804)
			(xy 396.758688 -66.613023) (xy 396.803842 -66.540098) (xy 396.855532 -66.47165) (xy 396.913317 -66.408263)
			(xy 396.976704 -66.350478) (xy 397.045152 -66.298788) (xy 397.118077 -66.253634) (xy 397.194858 -66.215402)
			(xy 397.274839 -66.184417) (xy 397.357338 -66.160944) (xy 397.44165 -66.145183) (xy 397.527058 -66.137269)
			(xy 397.61283 -66.137269) (xy 397.698238 -66.145183) (xy 397.78255 -66.160944) (xy 397.865049 -66.184417)
			(xy 397.94503 -66.215402) (xy 398.021811 -66.253634) (xy 398.094736 -66.298788) (xy 398.163184 -66.350478)
			(xy 398.226571 -66.408263) (xy 398.284356 -66.47165) (xy 398.336046 -66.540098) (xy 398.3812 -66.613023)
			(xy 398.419432 -66.689804) (xy 398.450417 -66.769785) (xy 398.47389 -66.852284) (xy 398.489651 -66.936596)
			(xy 398.497565 -67.022004) (xy 398.49806 -67.06489) (xy 398.497565 -67.107776) (xy 398.489651 -67.193184)
			(xy 398.47389 -67.277496) (xy 398.450417 -67.359995) (xy 398.419432 -67.439976) (xy 398.3812 -67.516757)
			(xy 398.336046 -67.589682) (xy 398.284356 -67.65813) (xy 398.226571 -67.721517) (xy 398.163184 -67.779302)
			(xy 398.094736 -67.830992) (xy 398.021811 -67.876146) (xy 397.94503 -67.914378) (xy 397.865049 -67.945363)
			(xy 397.78255 -67.968836) (xy 397.698238 -67.984597) (xy 397.61283 -67.992511) (xy 397.527058 -67.992511)
			(xy 397.44165 -67.984597) (xy 397.357338 -67.968836) (xy 397.274839 -67.945363) (xy 397.194858 -67.914378)
			(xy 397.118077 -67.876146) (xy 397.045152 -67.830992) (xy 396.976704 -67.779302) (xy 396.913317 -67.721517)
			(xy 396.855532 -67.65813) (xy 396.803842 -67.589682) (xy 396.758688 -67.516757) (xy 396.720456 -67.439976)
			(xy 396.689471 -67.359995) (xy 396.665998 -67.277496) (xy 396.650237 -67.193184) (xy 396.642323 -67.107776)
			(xy 351.005595 -67.107776) (xy 350.987857 -67.146615) (xy 350.958391 -67.192465) (xy 350.9227 -67.233656)
			(xy 350.881509 -67.269347) (xy 350.835659 -67.298813) (xy 350.786082 -67.321455) (xy 350.733787 -67.33681)
			(xy 350.679839 -67.344566) (xy 350.625337 -67.344566) (xy 350.571389 -67.33681) (xy 350.519094 -67.321455)
			(xy 350.469517 -67.298813) (xy 350.423667 -67.269347) (xy 350.382476 -67.233656) (xy 350.346785 -67.192465)
			(xy 350.317319 -67.146615) (xy 350.294677 -67.097038) (xy 350.279322 -67.044743) (xy 350.271566 -66.990795)
			(xy 350.27108 -66.963544) (xy 349.432372 -66.963544) (xy 349.432372 -67.154044) (xy 349.431973 -67.166124)
			(xy 349.424494 -67.189099) (xy 349.410282 -67.208639) (xy 349.390727 -67.22283) (xy 349.367745 -67.230285)
			(xy 349.355664 -67.230752) (xy 349.101664 -67.230752) (xy 349.089592 -67.230267) (xy 349.066631 -67.2228)
			(xy 349.047098 -67.208607) (xy 349.032903 -67.189076) (xy 349.025434 -67.166116) (xy 349.024956 -67.154044)
			(xy 348.898972 -67.154044) (xy 348.898573 -67.166124) (xy 348.891094 -67.189099) (xy 348.876882 -67.208639)
			(xy 348.857327 -67.22283) (xy 348.834345 -67.230285) (xy 348.822264 -67.230752) (xy 348.568264 -67.230752)
			(xy 348.556192 -67.230267) (xy 348.533231 -67.2228) (xy 348.513698 -67.208607) (xy 348.499503 -67.189076)
			(xy 348.492034 -67.166116) (xy 348.491556 -67.154044) (xy 318.499032 -67.154044) (xy 318.535323 -67.198528)
			(xy 318.60996 -67.302613) (xy 318.677982 -67.411137) (xy 318.739126 -67.52368) (xy 318.793154 -67.639806)
			(xy 318.839859 -67.759067) (xy 318.879059 -67.881) (xy 318.910602 -68.005135) (xy 318.934367 -68.130991)
			(xy 318.950261 -68.25808) (xy 318.957973 -68.38188) (xy 348.543372 -68.38188) (xy 348.543372 -68.05168)
			(xy 348.543799 -68.039573) (xy 348.5513 -68.01655) (xy 348.56556 -67.996979) (xy 348.585178 -67.982784)
			(xy 348.608226 -67.975359) (xy 348.620334 -67.974972) (xy 348.874334 -67.974972) (xy 348.886429 -67.975379)
			(xy 348.909436 -67.982849) (xy 348.929018 -67.99705) (xy 348.943266 -68.016598) (xy 348.950792 -68.039587)
			(xy 348.951296 -68.05168) (xy 348.951296 -68.38188) (xy 349.076772 -68.38188) (xy 349.076772 -68.05168)
			(xy 349.077199 -68.039573) (xy 349.0847 -68.01655) (xy 349.09896 -67.996979) (xy 349.118578 -67.982784)
			(xy 349.141626 -67.975359) (xy 349.153734 -67.974972) (xy 349.407734 -67.974972) (xy 349.419829 -67.975379)
			(xy 349.442836 -67.982849) (xy 349.462418 -67.99705) (xy 349.476666 -68.016598) (xy 349.484192 -68.039587)
			(xy 349.484696 -68.05168) (xy 349.484696 -68.38188) (xy 349.484266 -68.393988) (xy 349.476772 -68.417015)
			(xy 349.462514 -68.436589) (xy 349.442895 -68.450784) (xy 349.419843 -68.458205) (xy 349.407734 -68.458588)
			(xy 349.153734 -68.458588) (xy 349.141649 -68.458064) (xy 349.118654 -68.45062) (xy 349.099076 -68.436447)
			(xy 349.084823 -68.416927) (xy 349.077286 -68.393963) (xy 349.076772 -68.38188) (xy 348.951296 -68.38188)
			(xy 348.950866 -68.393988) (xy 348.943372 -68.417015) (xy 348.929114 -68.436589) (xy 348.909495 -68.450784)
			(xy 348.886443 -68.458205) (xy 348.874334 -68.458588) (xy 348.620334 -68.458588) (xy 348.608249 -68.458064)
			(xy 348.585254 -68.45062) (xy 348.565676 -68.436447) (xy 348.551423 -68.416927) (xy 348.543886 -68.393963)
			(xy 348.543372 -68.38188) (xy 318.957973 -68.38188) (xy 318.958224 -68.385912) (xy 318.958722 -68.449952)
			(xy 318.958224 -68.513992) (xy 318.950261 -68.641824) (xy 318.934367 -68.768913) (xy 318.910602 -68.894769)
			(xy 318.879059 -69.018904) (xy 318.839859 -69.140837) (xy 318.804847 -69.23024) (xy 345.549728 -69.23024)
			(xy 345.549728 -68.97624) (xy 345.550151 -68.96413) (xy 345.557643 -68.9411) (xy 345.571901 -68.921523)
			(xy 345.591524 -68.907328) (xy 345.614579 -68.899912) (xy 345.62669 -68.899532) (xy 345.95689 -68.899532)
			(xy 345.968978 -68.900016) (xy 345.991977 -68.907469) (xy 346.011557 -68.921651) (xy 346.025808 -68.941181)
			(xy 346.033341 -68.964153) (xy 346.033852 -68.97624) (xy 346.033852 -69.23024) (xy 346.464128 -69.23024)
			(xy 346.464128 -68.97624) (xy 346.464551 -68.96413) (xy 346.472043 -68.9411) (xy 346.486301 -68.921523)
			(xy 346.505924 -68.907328) (xy 346.528979 -68.899912) (xy 346.54109 -68.899532) (xy 346.87129 -68.899532)
			(xy 346.883378 -68.900016) (xy 346.906377 -68.907469) (xy 346.925957 -68.921651) (xy 346.940208 -68.941181)
			(xy 346.947741 -68.964153) (xy 346.948252 -68.97624) (xy 346.948252 -69.23024) (xy 346.947818 -69.242346)
			(xy 346.940314 -69.265365) (xy 346.926055 -69.284933) (xy 346.910376 -69.29628) (xy 348.543372 -69.29628)
			(xy 348.543372 -68.96608) (xy 348.543799 -68.953973) (xy 348.5513 -68.93095) (xy 348.56556 -68.911379)
			(xy 348.585178 -68.897184) (xy 348.608226 -68.889759) (xy 348.620334 -68.889372) (xy 348.874334 -68.889372)
			(xy 348.886429 -68.889779) (xy 348.909436 -68.897249) (xy 348.929018 -68.91145) (xy 348.943266 -68.930998)
			(xy 348.950792 -68.953987) (xy 348.951296 -68.96608) (xy 348.951296 -69.29628) (xy 349.076772 -69.29628)
			(xy 349.076772 -68.96608) (xy 349.077199 -68.953973) (xy 349.0847 -68.93095) (xy 349.09896 -68.911379)
			(xy 349.118578 -68.897184) (xy 349.141626 -68.889759) (xy 349.153734 -68.889372) (xy 349.407734 -68.889372)
			(xy 349.419829 -68.889779) (xy 349.442836 -68.897249) (xy 349.462418 -68.91145) (xy 349.476666 -68.930998)
			(xy 349.484192 -68.953987) (xy 349.484696 -68.96608) (xy 349.484696 -69.10578) (xy 351.73158 -69.10578)
			(xy 351.73158 -68.24218) (xy 351.732066 -68.214911) (xy 351.739828 -68.160927) (xy 351.755193 -68.108597)
			(xy 351.77785 -68.058987) (xy 351.807336 -68.013106) (xy 351.843051 -67.971889) (xy 351.884268 -67.936174)
			(xy 351.930149 -67.906688) (xy 351.979759 -67.884031) (xy 352.032089 -67.868666) (xy 352.086073 -67.860904)
			(xy 352.140611 -67.860904) (xy 352.194595 -67.868666) (xy 352.246925 -67.884031) (xy 352.296535 -67.906688)
			(xy 352.342416 -67.936174) (xy 352.383633 -67.971889) (xy 352.419348 -68.013106) (xy 352.448834 -68.058987)
			(xy 352.471491 -68.108597) (xy 352.486856 -68.160927) (xy 352.494618 -68.214911) (xy 352.495104 -68.24218)
			(xy 352.495104 -69.10578) (xy 352.494618 -69.133049) (xy 352.486856 -69.187033) (xy 352.471491 -69.239363)
			(xy 352.448834 -69.288973) (xy 352.419348 -69.334854) (xy 352.383633 -69.376071) (xy 352.342416 -69.411786)
			(xy 352.296535 -69.441272) (xy 352.246925 -69.463929) (xy 352.194595 -69.479294) (xy 352.140611 -69.487056)
			(xy 352.086073 -69.487056) (xy 352.032089 -69.479294) (xy 351.979759 -69.463929) (xy 351.930149 -69.441272)
			(xy 351.884268 -69.411786) (xy 351.843051 -69.376071) (xy 351.807336 -69.334854) (xy 351.77785 -69.288973)
			(xy 351.755193 -69.239363) (xy 351.739828 -69.187033) (xy 351.732066 -69.133049) (xy 351.73158 -69.10578)
			(xy 349.484696 -69.10578) (xy 349.484696 -69.29628) (xy 349.484266 -69.308388) (xy 349.476772 -69.331415)
			(xy 349.462514 -69.350989) (xy 349.442895 -69.365184) (xy 349.419843 -69.372605) (xy 349.407734 -69.372988)
			(xy 349.153734 -69.372988) (xy 349.141649 -69.372464) (xy 349.118654 -69.36502) (xy 349.099076 -69.350847)
			(xy 349.084823 -69.331327) (xy 349.077286 -69.308363) (xy 349.076772 -69.29628) (xy 348.951296 -69.29628)
			(xy 348.950866 -69.308388) (xy 348.943372 -69.331415) (xy 348.929114 -69.350989) (xy 348.909495 -69.365184)
			(xy 348.886443 -69.372605) (xy 348.874334 -69.372988) (xy 348.620334 -69.372988) (xy 348.608249 -69.372464)
			(xy 348.585254 -69.36502) (xy 348.565676 -69.350847) (xy 348.551423 -69.331327) (xy 348.543886 -69.308363)
			(xy 348.543372 -69.29628) (xy 346.910376 -69.29628) (xy 346.906441 -69.299128) (xy 346.883397 -69.306558)
			(xy 346.87129 -69.306948) (xy 346.54109 -69.306948) (xy 346.528999 -69.306501) (xy 346.505996 -69.29904)
			(xy 346.486415 -69.284849) (xy 346.472165 -69.26531) (xy 346.464636 -69.24233) (xy 346.464128 -69.23024)
			(xy 346.033852 -69.23024) (xy 346.033418 -69.242346) (xy 346.025914 -69.265365) (xy 346.011655 -69.284933)
			(xy 345.992041 -69.299128) (xy 345.968997 -69.306558) (xy 345.95689 -69.306948) (xy 345.62669 -69.306948)
			(xy 345.614599 -69.306501) (xy 345.591596 -69.29904) (xy 345.572015 -69.284849) (xy 345.557765 -69.26531)
			(xy 345.550236 -69.24233) (xy 345.549728 -69.23024) (xy 318.804847 -69.23024) (xy 318.793154 -69.260098)
			(xy 318.739126 -69.376224) (xy 318.677982 -69.488767) (xy 318.60996 -69.597291) (xy 318.535323 -69.701376)
			(xy 318.454359 -69.800619) (xy 318.367382 -69.894637) (xy 318.363586 -69.89826) (xy 341.282528 -69.89826)
			(xy 341.282528 -69.64426) (xy 341.282883 -69.632146) (xy 341.290397 -69.609113) (xy 341.304673 -69.589538)
			(xy 341.324309 -69.575346) (xy 341.347375 -69.567931) (xy 341.35949 -69.567552) (xy 341.68969 -69.567552)
			(xy 341.70178 -69.568016) (xy 341.724782 -69.575472) (xy 341.744364 -69.589659) (xy 341.758614 -69.609193)
			(xy 341.766144 -69.632171) (xy 341.766652 -69.64426) (xy 341.766652 -69.89826) (xy 342.196928 -69.89826)
			(xy 342.196928 -69.64426) (xy 342.197283 -69.632146) (xy 342.204797 -69.609113) (xy 342.219073 -69.589538)
			(xy 342.238709 -69.575346) (xy 342.261775 -69.567931) (xy 342.27389 -69.567552) (xy 342.60409 -69.567552)
			(xy 342.61618 -69.568016) (xy 342.639182 -69.575472) (xy 342.658764 -69.589659) (xy 342.673014 -69.609193)
			(xy 342.680544 -69.632171) (xy 342.681052 -69.64426) (xy 342.681052 -69.76364) (xy 345.549728 -69.76364)
			(xy 345.549728 -69.50964) (xy 345.550151 -69.49753) (xy 345.557643 -69.4745) (xy 345.571901 -69.454923)
			(xy 345.591524 -69.440728) (xy 345.614579 -69.433312) (xy 345.62669 -69.432932) (xy 345.95689 -69.432932)
			(xy 345.968978 -69.433416) (xy 345.991977 -69.440869) (xy 346.011557 -69.455051) (xy 346.025808 -69.474581)
			(xy 346.033341 -69.497553) (xy 346.033852 -69.50964) (xy 346.033852 -69.76364) (xy 346.464128 -69.76364)
			(xy 346.464128 -69.50964) (xy 346.464551 -69.49753) (xy 346.472043 -69.4745) (xy 346.486301 -69.454923)
			(xy 346.505924 -69.440728) (xy 346.528979 -69.433312) (xy 346.54109 -69.432932) (xy 346.87129 -69.432932)
			(xy 346.883378 -69.433416) (xy 346.906377 -69.440869) (xy 346.925957 -69.455051) (xy 346.940208 -69.474581)
			(xy 346.947741 -69.497553) (xy 346.948252 -69.50964) (xy 346.948252 -69.76364) (xy 346.947818 -69.775746)
			(xy 346.940314 -69.798765) (xy 346.926055 -69.818333) (xy 346.906441 -69.832528) (xy 346.883397 -69.839958)
			(xy 346.87129 -69.840348) (xy 346.54109 -69.840348) (xy 346.528999 -69.839901) (xy 346.505996 -69.83244)
			(xy 346.486415 -69.818249) (xy 346.472165 -69.79871) (xy 346.464636 -69.77573) (xy 346.464128 -69.76364)
			(xy 346.033852 -69.76364) (xy 346.033418 -69.775746) (xy 346.025914 -69.798765) (xy 346.011655 -69.818333)
			(xy 345.992041 -69.832528) (xy 345.968997 -69.839958) (xy 345.95689 -69.840348) (xy 345.62669 -69.840348)
			(xy 345.614599 -69.839901) (xy 345.591596 -69.83244) (xy 345.572015 -69.818249) (xy 345.557765 -69.79871)
			(xy 345.550236 -69.77573) (xy 345.549728 -69.76364) (xy 342.681052 -69.76364) (xy 342.681052 -69.89826)
			(xy 342.68055 -69.910362) (xy 342.673068 -69.933379) (xy 342.658827 -69.952948) (xy 342.639226 -69.967146)
			(xy 342.616192 -69.974577) (xy 342.60409 -69.974968) (xy 342.27389 -69.974968) (xy 342.261801 -69.974501)
			(xy 342.238801 -69.967043) (xy 342.219222 -69.952856) (xy 342.204972 -69.933323) (xy 342.197439 -69.910348)
			(xy 342.196928 -69.89826) (xy 341.766652 -69.89826) (xy 341.76615 -69.910362) (xy 341.758668 -69.933379)
			(xy 341.744427 -69.952948) (xy 341.724826 -69.967146) (xy 341.701792 -69.974577) (xy 341.68969 -69.974968)
			(xy 341.35949 -69.974968) (xy 341.347401 -69.974501) (xy 341.324401 -69.967043) (xy 341.304822 -69.952856)
			(xy 341.290572 -69.933323) (xy 341.283039 -69.910348) (xy 341.282528 -69.89826) (xy 318.363586 -69.89826)
			(xy 318.274728 -69.983066) (xy 318.176756 -70.065563) (xy 318.073844 -70.14181) (xy 317.966391 -70.211512)
			(xy 317.854813 -70.274398) (xy 317.739541 -70.330226) (xy 317.621021 -70.37878) (xy 317.499712 -70.419871)
			(xy 317.456167 -70.43166) (xy 341.282528 -70.43166) (xy 341.282528 -70.17766) (xy 341.282883 -70.165546)
			(xy 341.290397 -70.142513) (xy 341.304673 -70.122938) (xy 341.324309 -70.108746) (xy 341.347375 -70.101331)
			(xy 341.35949 -70.100952) (xy 341.68969 -70.100952) (xy 341.70178 -70.101416) (xy 341.724782 -70.108872)
			(xy 341.744364 -70.123059) (xy 341.758614 -70.142593) (xy 341.766144 -70.165571) (xy 341.766652 -70.17766)
			(xy 341.766652 -70.43166) (xy 342.196928 -70.43166) (xy 342.196928 -70.17766) (xy 342.197283 -70.165546)
			(xy 342.204797 -70.142513) (xy 342.219073 -70.122938) (xy 342.238709 -70.108746) (xy 342.261775 -70.101331)
			(xy 342.27389 -70.100952) (xy 342.60409 -70.100952) (xy 342.61618 -70.101416) (xy 342.639182 -70.108872)
			(xy 342.658764 -70.123059) (xy 342.673014 -70.142593) (xy 342.680544 -70.165571) (xy 342.681052 -70.17766)
			(xy 342.681052 -70.38086) (xy 343.492328 -70.38086) (xy 343.492328 -70.12686) (xy 343.492683 -70.114746)
			(xy 343.500197 -70.091713) (xy 343.514473 -70.072138) (xy 343.534109 -70.057946) (xy 343.557175 -70.050531)
			(xy 343.56929 -70.050152) (xy 343.89949 -70.050152) (xy 343.91158 -70.050616) (xy 343.934582 -70.058072)
			(xy 343.954164 -70.072259) (xy 343.968414 -70.091793) (xy 343.975944 -70.114771) (xy 343.976452 -70.12686)
			(xy 343.976452 -70.38086) (xy 344.406728 -70.38086) (xy 344.406728 -70.12686) (xy 344.407083 -70.114746)
			(xy 344.414597 -70.091713) (xy 344.428873 -70.072138) (xy 344.448509 -70.057946) (xy 344.471575 -70.050531)
			(xy 344.48369 -70.050152) (xy 344.81389 -70.050152) (xy 344.82598 -70.050616) (xy 344.848982 -70.058072)
			(xy 344.868564 -70.072259) (xy 344.882814 -70.091793) (xy 344.890344 -70.114771) (xy 344.890852 -70.12686)
			(xy 344.890852 -70.38086) (xy 344.89035 -70.392962) (xy 344.882868 -70.415979) (xy 344.868627 -70.435548)
			(xy 344.849026 -70.449746) (xy 344.825992 -70.457177) (xy 344.81389 -70.457568) (xy 344.48369 -70.457568)
			(xy 344.471601 -70.457101) (xy 344.448601 -70.449643) (xy 344.429022 -70.435456) (xy 344.414772 -70.415923)
			(xy 344.407239 -70.392948) (xy 344.406728 -70.38086) (xy 343.976452 -70.38086) (xy 343.97595 -70.392962)
			(xy 343.968468 -70.415979) (xy 343.954227 -70.435548) (xy 343.934626 -70.449746) (xy 343.911592 -70.457177)
			(xy 343.89949 -70.457568) (xy 343.56929 -70.457568) (xy 343.557201 -70.457101) (xy 343.534201 -70.449643)
			(xy 343.514622 -70.435456) (xy 343.500372 -70.415923) (xy 343.492839 -70.392948) (xy 343.492328 -70.38086)
			(xy 342.681052 -70.38086) (xy 342.681052 -70.43166) (xy 342.68055 -70.443762) (xy 342.673068 -70.466779)
			(xy 342.658827 -70.486348) (xy 342.639226 -70.500546) (xy 342.616192 -70.507977) (xy 342.60409 -70.508368)
			(xy 342.27389 -70.508368) (xy 342.261801 -70.507901) (xy 342.238801 -70.500443) (xy 342.219222 -70.486256)
			(xy 342.204972 -70.466723) (xy 342.197439 -70.443748) (xy 342.196928 -70.43166) (xy 341.766652 -70.43166)
			(xy 341.76615 -70.443762) (xy 341.758668 -70.466779) (xy 341.744427 -70.486348) (xy 341.724826 -70.500546)
			(xy 341.701792 -70.507977) (xy 341.68969 -70.508368) (xy 341.35949 -70.508368) (xy 341.347401 -70.507901)
			(xy 341.324401 -70.500443) (xy 341.304822 -70.486256) (xy 341.290572 -70.466723) (xy 341.283039 -70.443748)
			(xy 341.282528 -70.43166) (xy 317.456167 -70.43166) (xy 317.376083 -70.453341) (xy 317.250612 -70.47906)
			(xy 317.123785 -70.496929) (xy 316.996092 -70.506879) (xy 316.868028 -70.508871) (xy 316.740088 -70.502897)
			(xy 316.612766 -70.488981) (xy 316.486557 -70.467176) (xy 316.361946 -70.437567) (xy 316.239418 -70.400269)
			(xy 316.119445 -70.355425) (xy 316.002493 -70.303209) (xy 315.889013 -70.243823) (xy 315.779444 -70.177497)
			(xy 315.674211 -70.104487) (xy 315.57372 -70.025077) (xy 315.478361 -69.939572) (xy 315.388502 -69.848305)
			(xy 315.304491 -69.751627) (xy 315.226653 -69.649914) (xy 315.155289 -69.543558) (xy 315.090675 -69.432971)
			(xy 315.033061 -69.318581) (xy 314.98267 -69.200831) (xy 314.939697 -69.080175) (xy 314.904308 -68.957082)
			(xy 314.876641 -68.832026) (xy 314.856802 -68.705492) (xy 314.844867 -68.57797) (xy 314.840884 -68.449952)
			(xy 298.511468 -68.449952) (xy 298.511468 -71.213074) (xy 341.168388 -71.213074) (xy 341.168388 -71.158526)
			(xy 341.176151 -71.104534) (xy 341.19152 -71.052197) (xy 341.214181 -71.00258) (xy 341.243673 -70.956692)
			(xy 341.279395 -70.91547) (xy 341.320621 -70.879751) (xy 341.366511 -70.850263) (xy 341.416131 -70.827607)
			(xy 341.46847 -70.812243) (xy 341.522462 -70.804485) (xy 341.549736 -70.804024) (xy 342.413336 -70.804024)
			(xy 342.440603 -70.804541) (xy 342.49458 -70.812306) (xy 342.546904 -70.827674) (xy 342.596508 -70.850332)
			(xy 342.642382 -70.879817) (xy 342.682127 -70.91426) (xy 343.492328 -70.91426) (xy 343.492328 -70.66026)
			(xy 343.492683 -70.648146) (xy 343.500197 -70.625113) (xy 343.514473 -70.605538) (xy 343.534109 -70.591346)
			(xy 343.557175 -70.583931) (xy 343.56929 -70.583552) (xy 343.89949 -70.583552) (xy 343.91158 -70.584016)
			(xy 343.934582 -70.591472) (xy 343.954164 -70.605659) (xy 343.968414 -70.625193) (xy 343.975944 -70.648171)
			(xy 343.976452 -70.66026) (xy 343.976452 -70.91426) (xy 344.406728 -70.91426) (xy 344.406728 -70.66026)
			(xy 344.407083 -70.648146) (xy 344.414597 -70.625113) (xy 344.428873 -70.605538) (xy 344.448509 -70.591346)
			(xy 344.471575 -70.583931) (xy 344.48369 -70.583552) (xy 344.81389 -70.583552) (xy 344.82598 -70.584016)
			(xy 344.848982 -70.591472) (xy 344.868564 -70.605659) (xy 344.882814 -70.625193) (xy 344.890344 -70.648171)
			(xy 344.890852 -70.66026) (xy 344.890852 -70.91426) (xy 344.89035 -70.926362) (xy 344.882868 -70.949379)
			(xy 344.868627 -70.968948) (xy 344.849026 -70.983146) (xy 344.825992 -70.990577) (xy 344.81389 -70.990968)
			(xy 344.48369 -70.990968) (xy 344.471601 -70.990501) (xy 344.448601 -70.983043) (xy 344.429022 -70.968856)
			(xy 344.414772 -70.949323) (xy 344.407239 -70.926348) (xy 344.406728 -70.91426) (xy 343.976452 -70.91426)
			(xy 343.97595 -70.926362) (xy 343.968468 -70.949379) (xy 343.954227 -70.968948) (xy 343.934626 -70.983146)
			(xy 343.911592 -70.990577) (xy 343.89949 -70.990968) (xy 343.56929 -70.990968) (xy 343.557201 -70.990501)
			(xy 343.534201 -70.983043) (xy 343.514622 -70.968856) (xy 343.500372 -70.949323) (xy 343.492839 -70.926348)
			(xy 343.492328 -70.91426) (xy 342.682127 -70.91426) (xy 342.683594 -70.915531) (xy 342.719304 -70.956747)
			(xy 342.748786 -71.002624) (xy 342.771438 -71.05223) (xy 342.786801 -71.104555) (xy 342.794562 -71.158533)
			(xy 342.794562 -71.213067) (xy 342.786801 -71.267045) (xy 342.771438 -71.31937) (xy 342.748786 -71.368976)
			(xy 342.719304 -71.414853) (xy 342.683594 -71.456069) (xy 342.642382 -71.491783) (xy 342.596508 -71.521268)
			(xy 342.546904 -71.543926) (xy 342.49458 -71.559294) (xy 342.440603 -71.567059) (xy 342.413336 -71.567548)
			(xy 341.549736 -71.567548) (xy 341.522462 -71.567115) (xy 341.46847 -71.559357) (xy 341.416131 -71.543993)
			(xy 341.366511 -71.521337) (xy 341.320621 -71.491849) (xy 341.279395 -71.45613) (xy 341.243673 -71.414908)
			(xy 341.214181 -71.36902) (xy 341.19152 -71.319403) (xy 341.176151 -71.267066) (xy 341.168388 -71.213074)
			(xy 298.511468 -71.213074) (xy 298.511468 -71.844253) (xy 346.360454 -71.844253) (xy 346.360454 -71.789747)
			(xy 346.368211 -71.735796) (xy 346.383567 -71.683499) (xy 346.406209 -71.633919) (xy 346.435677 -71.588066)
			(xy 346.47137 -71.546873) (xy 346.512562 -71.511179) (xy 346.558415 -71.481711) (xy 346.607995 -71.459068)
			(xy 346.660293 -71.443712) (xy 346.714243 -71.435954) (xy 346.741496 -71.435468) (xy 347.605096 -71.435468)
			(xy 347.632347 -71.435979) (xy 347.686295 -71.443735) (xy 347.73859 -71.45909) (xy 347.788168 -71.481731)
			(xy 347.834019 -71.511197) (xy 347.875209 -71.546888) (xy 347.910901 -71.588078) (xy 347.940367 -71.633929)
			(xy 347.963009 -71.683506) (xy 347.978364 -71.735801) (xy 347.986121 -71.789749) (xy 347.986121 -71.844251)
			(xy 347.978364 -71.898199) (xy 347.963009 -71.950494) (xy 347.940367 -72.000071) (xy 347.910901 -72.045922)
			(xy 347.875209 -72.087112) (xy 347.834019 -72.122803) (xy 347.788168 -72.152269) (xy 347.73859 -72.17491)
			(xy 347.686295 -72.190265) (xy 347.632347 -72.198021) (xy 347.605096 -72.198484) (xy 346.741496 -72.198484)
			(xy 346.714243 -72.198046) (xy 346.660293 -72.190288) (xy 346.607995 -72.174932) (xy 346.558415 -72.152289)
			(xy 346.512562 -72.122821) (xy 346.47137 -72.087127) (xy 346.435677 -72.045934) (xy 346.406209 -72.000081)
			(xy 346.383567 -71.950501) (xy 346.368211 -71.898204) (xy 346.360454 -71.844253) (xy 298.511468 -71.844253)
			(xy 298.511468 -72.404055) (xy 332.037847 -72.404055) (xy 332.037847 -72.349545) (xy 332.045606 -72.295589)
			(xy 332.060964 -72.243286) (xy 332.083611 -72.193702) (xy 332.113083 -72.147846) (xy 332.148782 -72.106651)
			(xy 332.189981 -72.070957) (xy 332.235841 -72.041489) (xy 332.285427 -72.018849) (xy 332.337732 -72.003496)
			(xy 332.391689 -71.995744) (xy 332.418944 -71.995284) (xy 333.282544 -71.995284) (xy 333.309793 -71.995789)
			(xy 333.363734 -72.00355) (xy 333.416023 -72.018909) (xy 333.465593 -72.041552) (xy 333.511437 -72.071019)
			(xy 333.552622 -72.10671) (xy 333.588308 -72.147898) (xy 333.617769 -72.193745) (xy 333.640407 -72.243318)
			(xy 333.655759 -72.295609) (xy 333.660251 -72.326853) (xy 343.845854 -72.326853) (xy 343.845854 -72.272347)
			(xy 343.853611 -72.218396) (xy 343.868967 -72.166099) (xy 343.891609 -72.116519) (xy 343.921077 -72.070666)
			(xy 343.95677 -72.029473) (xy 343.997962 -71.993779) (xy 344.043815 -71.964311) (xy 344.093395 -71.941668)
			(xy 344.145693 -71.926312) (xy 344.199643 -71.918554) (xy 344.226896 -71.918068) (xy 345.090496 -71.918068)
			(xy 345.117747 -71.918579) (xy 345.171695 -71.926335) (xy 345.22399 -71.94169) (xy 345.273568 -71.964331)
			(xy 345.319419 -71.993797) (xy 345.360609 -72.029488) (xy 345.396301 -72.070678) (xy 345.425767 -72.116529)
			(xy 345.448409 -72.166106) (xy 345.463764 -72.218401) (xy 345.471521 -72.272349) (xy 345.471521 -72.326851)
			(xy 345.463764 -72.380799) (xy 345.448409 -72.433094) (xy 345.425767 -72.482671) (xy 345.396301 -72.528522)
			(xy 345.360609 -72.569712) (xy 345.319419 -72.605403) (xy 345.273568 -72.634869) (xy 345.22399 -72.65751)
			(xy 345.171695 -72.672865) (xy 345.117747 -72.680621) (xy 345.090496 -72.681084) (xy 344.226896 -72.681084)
			(xy 344.199643 -72.680646) (xy 344.145693 -72.672888) (xy 344.093395 -72.657532) (xy 344.043815 -72.634889)
			(xy 343.997962 -72.605421) (xy 343.95677 -72.569727) (xy 343.921077 -72.528534) (xy 343.891609 -72.482681)
			(xy 343.868967 -72.433101) (xy 343.853611 -72.380804) (xy 343.845854 -72.326853) (xy 333.660251 -72.326853)
			(xy 333.663514 -72.349551) (xy 333.663514 -72.404049) (xy 333.655759 -72.457991) (xy 333.640407 -72.510282)
			(xy 333.617769 -72.559855) (xy 333.588308 -72.605702) (xy 333.552622 -72.64689) (xy 333.511437 -72.682581)
			(xy 333.465593 -72.712048) (xy 333.416023 -72.734691) (xy 333.363734 -72.75005) (xy 333.309793 -72.757811)
			(xy 333.282544 -72.7583) (xy 332.418944 -72.7583) (xy 332.391689 -72.757856) (xy 332.337732 -72.750104)
			(xy 332.285427 -72.734751) (xy 332.235841 -72.712111) (xy 332.189981 -72.682643) (xy 332.148782 -72.646949)
			(xy 332.113083 -72.605754) (xy 332.083611 -72.559898) (xy 332.060964 -72.510314) (xy 332.045606 -72.458011)
			(xy 332.037847 -72.404055) (xy 298.511468 -72.404055) (xy 298.511468 -74.617072) (xy 327.277726 -74.617072)
			(xy 327.281813 -74.561227) (xy 327.293988 -74.506573) (xy 327.31399 -74.454274) (xy 327.341395 -74.405445)
			(xy 327.375617 -74.361126) (xy 327.415927 -74.322262) (xy 327.461466 -74.289681) (xy 327.511264 -74.264078)
			(xy 327.564259 -74.245999) (xy 327.619321 -74.235828) (xy 327.675278 -74.233783) (xy 327.730936 -74.239908)
			(xy 327.785109 -74.25407) (xy 327.836643 -74.27597) (xy 327.884439 -74.305139) (xy 327.927478 -74.340957)
			(xy 327.941626 -74.356747) (xy 330.744122 -74.356747) (xy 330.744122 -74.302253) (xy 330.751877 -74.248315)
			(xy 330.767229 -74.196029) (xy 330.789865 -74.146459) (xy 330.819325 -74.100616) (xy 330.855009 -74.059431)
			(xy 330.89619 -74.023744) (xy 330.942031 -73.99428) (xy 330.991599 -73.97164) (xy 331.043883 -73.956284)
			(xy 331.097821 -73.948524) (xy 331.125068 -73.948036) (xy 331.988668 -73.948036) (xy 332.015926 -73.948409)
			(xy 332.069886 -73.956163) (xy 332.122194 -73.971518) (xy 332.171784 -73.994161) (xy 332.217646 -74.023632)
			(xy 332.258848 -74.05933) (xy 332.294549 -74.100528) (xy 332.324023 -74.146388) (xy 332.346671 -74.195976)
			(xy 332.36203 -74.248283) (xy 332.369789 -74.302243) (xy 332.369789 -74.356757) (xy 332.36203 -74.410717)
			(xy 332.346671 -74.463024) (xy 332.324023 -74.512612) (xy 332.294549 -74.558472) (xy 332.26684 -74.590448)
			(xy 336.274202 -74.590448) (xy 336.274202 -74.535953) (xy 336.281957 -74.482012) (xy 336.297309 -74.429724)
			(xy 336.319945 -74.380153) (xy 336.349406 -74.334308) (xy 336.38509 -74.293121) (xy 336.426272 -74.257432)
			(xy 336.472114 -74.227966) (xy 336.521683 -74.205324) (xy 336.573969 -74.189966) (xy 336.627909 -74.182205)
			(xy 336.655156 -74.181716) (xy 337.518756 -74.181716) (xy 337.546013 -74.182128) (xy 337.599972 -74.18988)
			(xy 337.652278 -74.205233) (xy 337.701867 -74.227875) (xy 337.747729 -74.257344) (xy 337.788929 -74.29304)
			(xy 337.82463 -74.334236) (xy 337.854104 -74.380094) (xy 337.876751 -74.42968) (xy 337.89211 -74.481985)
			(xy 337.899869 -74.535943) (xy 337.899869 -74.55185) (xy 339.156294 -74.55185) (xy 339.156294 -74.49735)
			(xy 339.16405 -74.443405) (xy 339.179404 -74.391113) (xy 339.202044 -74.341539) (xy 339.231509 -74.29569)
			(xy 339.267198 -74.254502) (xy 339.308386 -74.218812) (xy 339.354233 -74.189347) (xy 339.403808 -74.166707)
			(xy 339.456099 -74.151352) (xy 339.510044 -74.143595) (xy 339.537294 -74.143108) (xy 340.400894 -74.143108)
			(xy 340.428148 -74.143538) (xy 340.482102 -74.151295) (xy 340.534403 -74.166651) (xy 340.583986 -74.189294)
			(xy 340.629842 -74.218763) (xy 340.671037 -74.254459) (xy 340.706733 -74.295653) (xy 340.736203 -74.341509)
			(xy 340.758847 -74.391091) (xy 340.774204 -74.443392) (xy 340.781961 -74.497346) (xy 340.781961 -74.551854)
			(xy 340.774204 -74.605808) (xy 340.758847 -74.658109) (xy 340.736203 -74.707691) (xy 340.706733 -74.753547)
			(xy 340.694254 -74.767948) (xy 421.29456 -74.767948) (xy 421.29456 -66.06794) (xy 421.295065 -65.962416)
			(xy 421.303149 -65.751522) (xy 421.319305 -65.541093) (xy 421.343508 -65.331436) (xy 421.375725 -65.122861)
			(xy 421.415907 -64.915673) (xy 421.463995 -64.710176) (xy 421.519919 -64.506672) (xy 421.583596 -64.305459)
			(xy 421.654934 -64.106832) (xy 421.733828 -63.911084) (xy 421.820161 -63.718502) (xy 421.913808 -63.529367)
			(xy 422.01463 -63.343958) (xy 422.12248 -63.162547) (xy 422.237199 -62.9854) (xy 422.358619 -62.812778)
			(xy 422.486562 -62.644932) (xy 422.62084 -62.48211) (xy 422.761256 -62.324551) (xy 422.907604 -62.172486)
			(xy 423.059669 -62.026138) (xy 423.217228 -61.885722) (xy 423.38005 -61.751444) (xy 423.547896 -61.623501)
			(xy 423.720518 -61.502081) (xy 423.897665 -61.387362) (xy 424.079076 -61.279512) (xy 424.264485 -61.17869)
			(xy 424.45362 -61.085043) (xy 424.646202 -60.99871) (xy 424.84195 -60.919816) (xy 425.040577 -60.848478)
			(xy 425.24179 -60.784801) (xy 425.445294 -60.728877) (xy 425.650791 -60.680789) (xy 425.857979 -60.640607)
			(xy 426.066554 -60.60839) (xy 426.276211 -60.584187) (xy 426.48664 -60.568031) (xy 426.697534 -60.559947)
			(xy 426.908582 -60.559947) (xy 427.119476 -60.568031) (xy 427.329905 -60.584187) (xy 427.539562 -60.60839)
			(xy 427.748137 -60.640607) (xy 427.955325 -60.680789) (xy 428.160822 -60.728877) (xy 428.364326 -60.784801)
			(xy 428.565539 -60.848478) (xy 428.764166 -60.919816) (xy 428.959914 -60.99871) (xy 429.152496 -61.085043)
			(xy 429.341631 -61.17869) (xy 429.52704 -61.279512) (xy 429.708451 -61.387362) (xy 429.885598 -61.502081)
			(xy 430.05822 -61.623501) (xy 430.226066 -61.751444) (xy 430.388888 -61.885722) (xy 430.546447 -62.026138)
			(xy 430.698512 -62.172486) (xy 430.84486 -62.324551) (xy 430.985276 -62.48211) (xy 431.119554 -62.644932)
			(xy 431.247497 -62.812778) (xy 431.368917 -62.9854) (xy 431.483636 -63.162547) (xy 431.591486 -63.343958)
			(xy 431.692308 -63.529367) (xy 431.785955 -63.718502) (xy 431.872288 -63.911084) (xy 431.951182 -64.106832)
			(xy 432.02252 -64.305459) (xy 432.086197 -64.506672) (xy 432.142121 -64.710176) (xy 432.190209 -64.915673)
			(xy 432.230391 -65.122861) (xy 432.262608 -65.331436) (xy 432.286811 -65.541093) (xy 432.302967 -65.751522)
			(xy 432.311051 -65.962416) (xy 432.311556 -66.06794) (xy 432.311556 -74.767948) (xy 432.311051 -74.873472)
			(xy 432.302967 -75.084366) (xy 432.286811 -75.294795) (xy 432.262608 -75.504452) (xy 432.230391 -75.713027)
			(xy 432.190209 -75.920215) (xy 432.142121 -76.125712) (xy 432.086197 -76.329216) (xy 432.02252 -76.530429)
			(xy 431.951182 -76.729056) (xy 431.872288 -76.924804) (xy 431.785955 -77.117386) (xy 431.692308 -77.306521)
			(xy 431.591486 -77.49193) (xy 431.483636 -77.673341) (xy 431.368917 -77.850488) (xy 431.247497 -78.02311)
			(xy 431.119554 -78.190956) (xy 430.985276 -78.353778) (xy 430.84486 -78.511337) (xy 430.698512 -78.663402)
			(xy 430.546447 -78.80975) (xy 430.388888 -78.950166) (xy 430.226066 -79.084444) (xy 430.05822 -79.212387)
			(xy 429.885598 -79.333807) (xy 429.708451 -79.448526) (xy 429.52704 -79.556376) (xy 429.341631 -79.657198)
			(xy 429.152496 -79.750845) (xy 428.959914 -79.837178) (xy 428.764166 -79.916072) (xy 428.565539 -79.98741)
			(xy 428.364326 -80.051087) (xy 428.160822 -80.107011) (xy 427.955325 -80.155099) (xy 427.748137 -80.195281)
			(xy 427.539562 -80.227498) (xy 427.329905 -80.251701) (xy 427.119476 -80.267857) (xy 426.908582 -80.275941)
			(xy 426.697534 -80.275941) (xy 426.48664 -80.267857) (xy 426.276211 -80.251701) (xy 426.066554 -80.227498)
			(xy 425.857979 -80.195281) (xy 425.650791 -80.155099) (xy 425.445294 -80.107011) (xy 425.24179 -80.051087)
			(xy 425.040577 -79.98741) (xy 424.84195 -79.916072) (xy 424.646202 -79.837178) (xy 424.45362 -79.750845)
			(xy 424.264485 -79.657198) (xy 424.079076 -79.556376) (xy 423.897665 -79.448526) (xy 423.720518 -79.333807)
			(xy 423.547896 -79.212387) (xy 423.38005 -79.084444) (xy 423.217228 -78.950166) (xy 423.059669 -78.80975)
			(xy 422.907604 -78.663402) (xy 422.761256 -78.511337) (xy 422.62084 -78.353778) (xy 422.486562 -78.190956)
			(xy 422.358619 -78.02311) (xy 422.237199 -77.850488) (xy 422.12248 -77.673341) (xy 422.01463 -77.49193)
			(xy 421.913808 -77.306521) (xy 421.820161 -77.117386) (xy 421.733828 -76.924804) (xy 421.654934 -76.729056)
			(xy 421.583596 -76.530429) (xy 421.519919 -76.329216) (xy 421.463995 -76.125712) (xy 421.415907 -75.920215)
			(xy 421.375725 -75.713027) (xy 421.343508 -75.504452) (xy 421.319305 -75.294795) (xy 421.303149 -75.084366)
			(xy 421.295065 -74.873472) (xy 421.29456 -74.767948) (xy 340.694254 -74.767948) (xy 340.671037 -74.794741)
			(xy 340.629842 -74.830437) (xy 340.583986 -74.859906) (xy 340.534403 -74.882549) (xy 340.482102 -74.897905)
			(xy 340.428148 -74.905662) (xy 340.400894 -74.906124) (xy 339.537294 -74.906124) (xy 339.510044 -74.905605)
			(xy 339.456099 -74.897848) (xy 339.403808 -74.882493) (xy 339.354233 -74.859853) (xy 339.308386 -74.830388)
			(xy 339.267198 -74.794698) (xy 339.231509 -74.75351) (xy 339.202044 -74.707661) (xy 339.179404 -74.658087)
			(xy 339.16405 -74.605795) (xy 339.156294 -74.55185) (xy 337.899869 -74.55185) (xy 337.899869 -74.590457)
			(xy 337.89211 -74.644415) (xy 337.876751 -74.69672) (xy 337.854104 -74.746306) (xy 337.82463 -74.792164)
			(xy 337.788929 -74.83336) (xy 337.747729 -74.869056) (xy 337.701867 -74.898525) (xy 337.652278 -74.921167)
			(xy 337.599972 -74.93652) (xy 337.546013 -74.944272) (xy 337.518756 -74.944732) (xy 336.655156 -74.944732)
			(xy 336.627909 -74.944195) (xy 336.573969 -74.936434) (xy 336.521683 -74.921076) (xy 336.472114 -74.898434)
			(xy 336.426272 -74.868968) (xy 336.38509 -74.833279) (xy 336.349406 -74.792092) (xy 336.319945 -74.746247)
			(xy 336.297309 -74.696676) (xy 336.281957 -74.644388) (xy 336.274202 -74.590448) (xy 332.26684 -74.590448)
			(xy 332.258848 -74.59967) (xy 332.217646 -74.635368) (xy 332.171784 -74.664839) (xy 332.122194 -74.687482)
			(xy 332.069886 -74.702837) (xy 332.015926 -74.710591) (xy 331.988668 -74.711052) (xy 331.125068 -74.711052)
			(xy 331.097821 -74.710476) (xy 331.043883 -74.702716) (xy 330.991599 -74.68736) (xy 330.942031 -74.66472)
			(xy 330.89619 -74.635256) (xy 330.855009 -74.599569) (xy 330.819325 -74.558384) (xy 330.789865 -74.512541)
			(xy 330.767229 -74.462971) (xy 330.751877 -74.410685) (xy 330.744122 -74.356747) (xy 327.941626 -74.356747)
			(xy 327.964844 -74.38266) (xy 327.99574 -74.429358) (xy 328.019507 -74.480058) (xy 328.035639 -74.533678)
			(xy 328.043791 -74.589075) (xy 328.044302 -74.617072) (xy 328.043791 -74.645069) (xy 328.035639 -74.700466)
			(xy 328.019507 -74.754086) (xy 327.99574 -74.804786) (xy 327.964844 -74.851484) (xy 327.927478 -74.893187)
			(xy 327.884439 -74.929005) (xy 327.836643 -74.958174) (xy 327.785109 -74.980074) (xy 327.730936 -74.994236)
			(xy 327.675278 -75.000361) (xy 327.619321 -74.998316) (xy 327.564259 -74.988145) (xy 327.511264 -74.970066)
			(xy 327.461466 -74.944463) (xy 327.415927 -74.911882) (xy 327.375617 -74.873018) (xy 327.341395 -74.828699)
			(xy 327.31399 -74.77987) (xy 327.293988 -74.727571) (xy 327.281813 -74.672917) (xy 327.277726 -74.617072)
			(xy 298.511468 -74.617072) (xy 298.511468 -74.760836) (xy 298.510963 -74.86636) (xy 298.502879 -75.077254)
			(xy 298.486723 -75.287683) (xy 298.46252 -75.49734) (xy 298.430303 -75.705915) (xy 298.390121 -75.913103)
			(xy 298.342033 -76.1186) (xy 298.333664 -76.149054) (xy 327.558346 -76.149054) (xy 327.558346 -76.094546)
			(xy 327.566103 -76.040594) (xy 327.581459 -75.988295) (xy 327.604102 -75.938714) (xy 327.633571 -75.892859)
			(xy 327.669266 -75.851666) (xy 327.710459 -75.815971) (xy 327.756314 -75.786502) (xy 327.805895 -75.763859)
			(xy 327.858194 -75.748503) (xy 327.912146 -75.740746) (xy 327.9394 -75.74026) (xy 328.803 -75.74026)
			(xy 328.830249 -75.74081) (xy 328.884192 -75.748566) (xy 328.936482 -75.76392) (xy 328.986055 -75.786559)
			(xy 329.031902 -75.816023) (xy 329.073089 -75.851711) (xy 329.108777 -75.892898) (xy 329.138241 -75.938745)
			(xy 329.16088 -75.988318) (xy 329.169581 -76.017949) (xy 334.874382 -76.017949) (xy 334.874382 -75.963451)
			(xy 334.882137 -75.909507) (xy 334.89749 -75.857216) (xy 334.920128 -75.807642) (xy 334.949591 -75.761793)
			(xy 334.985278 -75.720605) (xy 335.026463 -75.684914) (xy 335.072308 -75.655447) (xy 335.12188 -75.632803)
			(xy 335.17417 -75.617445) (xy 335.228113 -75.609684) (xy 335.255362 -75.609196) (xy 336.118962 -75.609196)
			(xy 336.146217 -75.609649) (xy 336.200173 -75.617401) (xy 336.252475 -75.632754) (xy 336.302061 -75.655395)
			(xy 336.347919 -75.684862) (xy 336.389117 -75.720556) (xy 336.424815 -75.76175) (xy 336.454287 -75.807606)
			(xy 336.476932 -75.857189) (xy 336.49229 -75.90949) (xy 336.500049 -75.963445) (xy 336.500049 -76.017955)
			(xy 336.49229 -76.07191) (xy 336.476932 -76.124211) (xy 336.454287 -76.173794) (xy 336.424815 -76.21965)
			(xy 336.389117 -76.260844) (xy 336.347919 -76.296538) (xy 336.302061 -76.326005) (xy 336.252475 -76.348646)
			(xy 336.200173 -76.363999) (xy 336.146217 -76.371751) (xy 336.118962 -76.372212) (xy 335.255362 -76.372212)
			(xy 335.228113 -76.371716) (xy 335.17417 -76.363955) (xy 335.12188 -76.348597) (xy 335.072308 -76.325953)
			(xy 335.026463 -76.296486) (xy 334.985278 -76.260795) (xy 334.949591 -76.219607) (xy 334.920128 -76.173758)
			(xy 334.89749 -76.124184) (xy 334.882137 -76.071893) (xy 334.874382 -76.017949) (xy 329.169581 -76.017949)
			(xy 329.176234 -76.040608) (xy 329.18399 -76.094551) (xy 329.18399 -76.149049) (xy 329.176234 -76.202992)
			(xy 329.16088 -76.255282) (xy 329.138241 -76.304855) (xy 329.108777 -76.350702) (xy 329.073089 -76.391889)
			(xy 329.031902 -76.427577) (xy 328.986055 -76.457041) (xy 328.936482 -76.47968) (xy 328.884192 -76.495034)
			(xy 328.830249 -76.50279) (xy 328.803 -76.503276) (xy 327.9394 -76.503276) (xy 327.912146 -76.502854)
			(xy 327.858194 -76.495097) (xy 327.805895 -76.479741) (xy 327.756314 -76.457098) (xy 327.710459 -76.427629)
			(xy 327.669266 -76.391934) (xy 327.633571 -76.350741) (xy 327.604102 -76.304886) (xy 327.581459 -76.255305)
			(xy 327.566103 -76.203006) (xy 327.558346 -76.149054) (xy 298.333664 -76.149054) (xy 298.286109 -76.322104)
			(xy 298.222432 -76.523317) (xy 298.151094 -76.721944) (xy 298.0722 -76.917692) (xy 297.985867 -77.110274)
			(xy 297.89222 -77.299409) (xy 297.791398 -77.484818) (xy 297.683548 -77.666229) (xy 297.568829 -77.843376)
			(xy 297.455321 -78.00475) (xy 330.84567 -78.00475) (xy 330.84567 -77.95025) (xy 330.853426 -77.896304)
			(xy 330.868779 -77.84401) (xy 330.891419 -77.794434) (xy 330.920883 -77.748584) (xy 330.956571 -77.707394)
			(xy 330.997759 -77.671702) (xy 331.043606 -77.642234) (xy 331.09318 -77.619591) (xy 331.145472 -77.604232)
			(xy 331.199418 -77.596472) (xy 331.226668 -77.595984) (xy 332.090268 -77.595984) (xy 332.117522 -77.596461)
			(xy 332.171475 -77.604214) (xy 332.223776 -77.619567) (xy 332.273359 -77.642207) (xy 332.319215 -77.671674)
			(xy 332.360411 -77.707367) (xy 332.396107 -77.748559) (xy 332.425577 -77.794413) (xy 332.448222 -77.843994)
			(xy 332.463579 -77.896294) (xy 332.471337 -77.950246) (xy 332.471337 -78.004754) (xy 332.463579 -78.058706)
			(xy 332.448222 -78.111006) (xy 332.425577 -78.160587) (xy 332.396107 -78.206441) (xy 332.360411 -78.247633)
			(xy 332.319215 -78.283326) (xy 332.273359 -78.312793) (xy 332.223776 -78.335433) (xy 332.171475 -78.350786)
			(xy 332.117522 -78.358539) (xy 332.090268 -78.359) (xy 331.226668 -78.359) (xy 331.199418 -78.358528)
			(xy 331.145472 -78.350768) (xy 331.09318 -78.335409) (xy 331.043606 -78.312766) (xy 330.997759 -78.283298)
			(xy 330.956571 -78.247606) (xy 330.920883 -78.206416) (xy 330.891419 -78.160566) (xy 330.868779 -78.11099)
			(xy 330.853426 -78.058696) (xy 330.84567 -78.00475) (xy 297.455321 -78.00475) (xy 297.447409 -78.015998)
			(xy 297.319466 -78.183844) (xy 297.185188 -78.346666) (xy 297.044772 -78.504225) (xy 296.898424 -78.65629)
			(xy 296.746359 -78.802638) (xy 296.5888 -78.943054) (xy 296.425978 -79.077332) (xy 296.258132 -79.205275)
			(xy 296.08551 -79.326695) (xy 295.908363 -79.441414) (xy 295.726952 -79.549264) (xy 295.541543 -79.650086)
			(xy 295.352408 -79.743733) (xy 295.159826 -79.830066) (xy 294.964078 -79.90896) (xy 294.765451 -79.980298)
			(xy 294.564238 -80.043975) (xy 294.360734 -80.099899) (xy 294.155237 -80.147987) (xy 293.948049 -80.188169)
			(xy 293.739474 -80.220386) (xy 293.529817 -80.244589) (xy 293.319388 -80.260745) (xy 293.108494 -80.268829)
			(xy 292.897446 -80.268829) (xy 292.686552 -80.260745) (xy 292.476123 -80.244589) (xy 292.266466 -80.220386)
			(xy 292.057891 -80.188169) (xy 291.850703 -80.147987) (xy 291.645206 -80.099899) (xy 291.441702 -80.043975)
			(xy 291.240489 -79.980298) (xy 291.041862 -79.90896) (xy 290.846114 -79.830066) (xy 290.653532 -79.743733)
			(xy 290.464397 -79.650086) (xy 290.278988 -79.549264) (xy 290.097577 -79.441414) (xy 289.92043 -79.326695)
			(xy 289.747808 -79.205275) (xy 289.579962 -79.077332) (xy 289.41714 -78.943054) (xy 289.259581 -78.802638)
			(xy 289.107516 -78.65629) (xy 288.961168 -78.504225) (xy 288.820752 -78.346666) (xy 288.686474 -78.183844)
			(xy 288.558531 -78.015998) (xy 288.437111 -77.843376) (xy 288.322392 -77.666229) (xy 288.214542 -77.484818)
			(xy 288.11372 -77.299409) (xy 288.020073 -77.110274) (xy 287.93374 -76.917692) (xy 287.854846 -76.721944)
			(xy 287.783508 -76.523317) (xy 287.719831 -76.322104) (xy 287.663907 -76.1186) (xy 287.615819 -75.913103)
			(xy 287.575637 -75.705915) (xy 287.54342 -75.49734) (xy 287.519217 -75.287683) (xy 287.503061 -75.077254)
			(xy 287.494977 -74.86636) (xy 287.494472 -74.760836) (xy 184.371488 -74.760836) (xy 184.371488 -74.767948)
			(xy 184.370983 -74.873472) (xy 184.362899 -75.084366) (xy 184.346743 -75.294795) (xy 184.32254 -75.504452)
			(xy 184.290323 -75.713027) (xy 184.250141 -75.920215) (xy 184.202053 -76.125712) (xy 184.146129 -76.329216)
			(xy 184.082452 -76.530429) (xy 184.011114 -76.729056) (xy 183.93222 -76.924804) (xy 183.845887 -77.117386)
			(xy 183.75224 -77.306521) (xy 183.651418 -77.49193) (xy 183.543568 -77.673341) (xy 183.428849 -77.850488)
			(xy 183.307429 -78.02311) (xy 183.179486 -78.190956) (xy 183.045208 -78.353778) (xy 182.904792 -78.511337)
			(xy 182.758444 -78.663402) (xy 182.606379 -78.80975) (xy 182.44882 -78.950166) (xy 182.285998 -79.084444)
			(xy 182.118152 -79.212387) (xy 181.94553 -79.333807) (xy 181.768383 -79.448526) (xy 181.586972 -79.556376)
			(xy 181.401563 -79.657198) (xy 181.212428 -79.750845) (xy 181.019846 -79.837178) (xy 180.824098 -79.916072)
			(xy 180.625471 -79.98741) (xy 180.424258 -80.051087) (xy 180.220754 -80.107011) (xy 180.015257 -80.155099)
			(xy 179.808069 -80.195281) (xy 179.599494 -80.227498) (xy 179.389837 -80.251701) (xy 179.179408 -80.267857)
			(xy 178.968514 -80.275941) (xy 178.757466 -80.275941) (xy 178.546572 -80.267857) (xy 178.336143 -80.251701)
			(xy 178.126486 -80.227498) (xy 177.917911 -80.195281) (xy 177.710723 -80.155099) (xy 177.505226 -80.107011)
			(xy 177.301722 -80.051087) (xy 177.100509 -79.98741) (xy 176.901882 -79.916072) (xy 176.706134 -79.837178)
			(xy 176.513552 -79.750845) (xy 176.324417 -79.657198) (xy 176.139008 -79.556376) (xy 175.957597 -79.448526)
			(xy 175.78045 -79.333807) (xy 175.607828 -79.212387) (xy 175.439982 -79.084444) (xy 175.27716 -78.950166)
			(xy 175.119601 -78.80975) (xy 174.967536 -78.663402) (xy 174.821188 -78.511337) (xy 174.680772 -78.353778)
			(xy 174.546494 -78.190956) (xy 174.418551 -78.02311) (xy 174.297131 -77.850488) (xy 174.182412 -77.673341)
			(xy 174.074562 -77.49193) (xy 173.97374 -77.306521) (xy 173.880093 -77.117386) (xy 173.79376 -76.924804)
			(xy 173.714866 -76.729056) (xy 173.643528 -76.530429) (xy 173.579851 -76.329216) (xy 173.523927 -76.125712)
			(xy 173.475839 -75.920215) (xy 173.435657 -75.713027) (xy 173.40344 -75.504452) (xy 173.379237 -75.294795)
			(xy 173.363081 -75.084366) (xy 173.354997 -74.873472) (xy 173.354492 -74.767948) (xy 50.571366 -74.767948)
			(xy 50.570895 -74.86636) (xy 50.562811 -75.077254) (xy 50.546655 -75.287683) (xy 50.522452 -75.49734)
			(xy 50.490235 -75.705915) (xy 50.450053 -75.913103) (xy 50.401965 -76.1186) (xy 50.346041 -76.322104)
			(xy 50.282364 -76.523317) (xy 50.211026 -76.721944) (xy 50.132132 -76.917692) (xy 50.045799 -77.110274)
			(xy 49.952152 -77.299409) (xy 49.85133 -77.484818) (xy 49.74348 -77.666229) (xy 49.628761 -77.843376)
			(xy 49.507341 -78.015998) (xy 49.379398 -78.183844) (xy 49.24512 -78.346666) (xy 49.104704 -78.504225)
			(xy 48.958356 -78.65629) (xy 48.806291 -78.802638) (xy 48.648732 -78.943054) (xy 48.48591 -79.077332)
			(xy 48.318064 -79.205275) (xy 48.145442 -79.326695) (xy 47.968295 -79.441414) (xy 47.786884 -79.549264)
			(xy 47.601475 -79.650086) (xy 47.41234 -79.743733) (xy 47.219758 -79.830066) (xy 47.02401 -79.90896)
			(xy 46.825383 -79.980298) (xy 46.62417 -80.043975) (xy 46.420666 -80.099899) (xy 46.215169 -80.147987)
			(xy 46.007981 -80.188169) (xy 45.799406 -80.220386) (xy 45.589749 -80.244589) (xy 45.37932 -80.260745)
			(xy 45.168426 -80.268829) (xy 44.957378 -80.268829) (xy 44.746484 -80.260745) (xy 44.536055 -80.244589)
			(xy 44.326398 -80.220386) (xy 44.117823 -80.188169) (xy 43.910635 -80.147987) (xy 43.705138 -80.099899)
			(xy 43.501634 -80.043975) (xy 43.300421 -79.980298) (xy 43.101794 -79.90896) (xy 42.906046 -79.830066)
			(xy 42.713464 -79.743733) (xy 42.524329 -79.650086) (xy 42.33892 -79.549264) (xy 42.157509 -79.441414)
			(xy 41.980362 -79.326695) (xy 41.80774 -79.205275) (xy 41.639894 -79.077332) (xy 41.477072 -78.943054)
			(xy 41.319513 -78.802638) (xy 41.167448 -78.65629) (xy 41.0211 -78.504225) (xy 40.880684 -78.346666)
			(xy 40.746406 -78.183844) (xy 40.618463 -78.015998) (xy 40.497043 -77.843376) (xy 40.382324 -77.666229)
			(xy 40.274474 -77.484818) (xy 40.173652 -77.299409) (xy 40.080005 -77.110274) (xy 39.993672 -76.917692)
			(xy 39.914778 -76.721944) (xy 39.84344 -76.523317) (xy 39.779763 -76.322104) (xy 39.723839 -76.1186)
			(xy 39.675751 -75.913103) (xy 39.635569 -75.705915) (xy 39.603352 -75.49734) (xy 39.579149 -75.287683)
			(xy 39.562993 -75.077254) (xy 39.554909 -74.86636) (xy 39.554404 -74.760836) (xy 0.509016 -74.760836)
			(xy 0.509016 -77.671676) (xy 0.509504 -77.724899) (xy 0.51712 -77.831071) (xy 0.532286 -77.93643)
			(xy 0.554925 -78.04044) (xy 0.584921 -78.142572) (xy 0.622123 -78.242305) (xy 0.666339 -78.339132)
			(xy 0.717347 -78.43256) (xy 0.774885 -78.522114) (xy 0.838661 -78.607338) (xy 0.908351 -78.687799)
			(xy 0.945642 -78.725776) (xy 1.77419 -79.554324) (xy 1.823602 -79.604436) (xy 1.917388 -79.709385)
			(xy 2.005143 -79.819428) (xy 2.08659 -79.934217) (xy 2.161473 -80.053392) (xy 2.229556 -80.176578)
			(xy 2.290626 -80.303388) (xy 2.344491 -80.433422) (xy 2.39098 -80.566271) (xy 2.429948 -80.701518)
			(xy 2.461272 -80.838737) (xy 2.484853 -80.977496) (xy 2.500618 -81.117359) (xy 2.508516 -81.257886)
			(xy 2.509012 -81.32826) (xy 2.509012 -81.69181) (xy 232.140667 -81.69181) (xy 232.145062 -81.517977)
			(xy 232.15749 -81.344533) (xy 232.177927 -81.171849) (xy 232.206328 -81.000295) (xy 232.242632 -80.830238)
			(xy 232.286762 -80.662042) (xy 232.338623 -80.496067) (xy 232.398104 -80.332668) (xy 232.465078 -80.172194)
			(xy 232.539402 -80.01499) (xy 232.620917 -79.86139) (xy 232.709448 -79.711725) (xy 232.804805 -79.566315)
			(xy 232.906785 -79.425469) (xy 233.01517 -79.289491) (xy 233.129727 -79.158671) (xy 233.250212 -79.033288)
			(xy 233.376366 -78.913612) (xy 233.50792 -78.799897) (xy 233.644592 -78.692389) (xy 233.715052 -78.641448)
			(xy 238.08436 -78.641448) (xy 238.15482 -78.692389) (xy 238.291492 -78.799897) (xy 238.423046 -78.913612)
			(xy 238.5492 -79.033288) (xy 238.669685 -79.158671) (xy 238.784242 -79.289491) (xy 238.892627 -79.425469)
			(xy 238.994607 -79.566315) (xy 239.089964 -79.711725) (xy 239.178495 -79.86139) (xy 239.26001 -80.01499)
			(xy 239.334334 -80.172194) (xy 239.401308 -80.332668) (xy 239.460789 -80.496067) (xy 239.51265 -80.662042)
			(xy 239.553507 -80.817765) (xy 333.938166 -80.817765) (xy 333.938166 -80.763235) (xy 333.945926 -80.70926)
			(xy 333.961289 -80.656938) (xy 333.98394 -80.607335) (xy 334.01342 -80.561461) (xy 334.049129 -80.520248)
			(xy 334.090338 -80.484537) (xy 334.136211 -80.455054) (xy 334.185812 -80.432398) (xy 334.238132 -80.417032)
			(xy 334.292107 -80.409268) (xy 334.319372 -80.40878) (xy 335.182972 -80.40878) (xy 335.210247 -80.409158)
			(xy 335.264243 -80.416917) (xy 335.316585 -80.432283) (xy 335.366207 -80.454941) (xy 335.412099 -80.484432)
			(xy 335.453327 -80.520153) (xy 335.489052 -80.561378) (xy 335.518545 -80.607268) (xy 335.541207 -80.656889)
			(xy 335.556577 -80.709229) (xy 335.56434 -80.763225) (xy 335.56434 -80.817775) (xy 335.556577 -80.871771)
			(xy 335.541207 -80.924111) (xy 335.518545 -80.973732) (xy 335.489052 -81.019622) (xy 335.453327 -81.060847)
			(xy 335.412099 -81.096568) (xy 335.366207 -81.126059) (xy 335.316585 -81.148717) (xy 335.264243 -81.164083)
			(xy 335.210247 -81.171842) (xy 335.182972 -81.172304) (xy 334.319372 -81.172304) (xy 334.292107 -81.171732)
			(xy 334.238132 -81.163968) (xy 334.185812 -81.148602) (xy 334.136211 -81.125946) (xy 334.090338 -81.096463)
			(xy 334.049129 -81.060752) (xy 334.01342 -81.019539) (xy 333.98394 -80.973665) (xy 333.961289 -80.924062)
			(xy 333.945926 -80.87174) (xy 333.938166 -80.817765) (xy 239.553507 -80.817765) (xy 239.55678 -80.830238)
			(xy 239.593084 -81.000295) (xy 239.621485 -81.171849) (xy 239.641922 -81.344533) (xy 239.65435 -81.517977)
			(xy 239.658745 -81.69181) (xy 239.655095 -81.865661) (xy 239.643409 -82.039157) (xy 239.640092 -82.06825)
			(xy 331.768962 -82.06825) (xy 331.768962 -82.01375) (xy 331.776717 -81.959803) (xy 331.792071 -81.90751)
			(xy 331.81471 -81.857933) (xy 331.844174 -81.812083) (xy 331.879862 -81.770892) (xy 331.921049 -81.735199)
			(xy 331.966896 -81.70573) (xy 332.01647 -81.683086) (xy 332.068762 -81.667726) (xy 332.122708 -81.659965)
			(xy 332.149958 -81.659476) (xy 333.013558 -81.659476) (xy 333.040812 -81.659968) (xy 333.094765 -81.66772)
			(xy 333.147066 -81.683072) (xy 333.196649 -81.705711) (xy 333.242505 -81.735177) (xy 333.283701 -81.770869)
			(xy 333.319398 -81.812061) (xy 333.348869 -81.857914) (xy 333.371513 -81.907495) (xy 333.386871 -81.959794)
			(xy 333.394629 -82.013746) (xy 333.394629 -82.068254) (xy 333.386871 -82.122206) (xy 333.371513 -82.174505)
			(xy 333.348869 -82.224086) (xy 333.319398 -82.269939) (xy 333.294774 -82.298353) (xy 336.189263 -82.298353)
			(xy 336.189263 -82.243847) (xy 336.197021 -82.189895) (xy 336.212377 -82.137597) (xy 336.235021 -82.088017)
			(xy 336.26449 -82.042163) (xy 336.300185 -82.000971) (xy 336.341379 -81.965278) (xy 336.387234 -81.935811)
			(xy 336.436816 -81.91317) (xy 336.489115 -81.897816) (xy 336.543067 -81.890062) (xy 336.57032 -81.8896)
			(xy 337.43392 -81.8896) (xy 337.461171 -81.890071) (xy 337.515118 -81.89783) (xy 337.567411 -81.913187)
			(xy 337.616987 -81.93583) (xy 337.662836 -81.965298) (xy 337.692804 -81.991267) (xy 339.478646 -81.991267)
			(xy 339.478646 -81.936733) (xy 339.486407 -81.882755) (xy 339.50177 -81.830431) (xy 339.524423 -81.780825)
			(xy 339.553905 -81.734948) (xy 339.589615 -81.693734) (xy 339.630827 -81.65802) (xy 339.676702 -81.628535)
			(xy 339.726306 -81.605879) (xy 339.77863 -81.590512) (xy 339.832607 -81.582748) (xy 339.859874 -81.58226)
			(xy 340.723474 -81.58226) (xy 340.750748 -81.582678) (xy 340.804741 -81.590437) (xy 340.857079 -81.605802)
			(xy 340.906699 -81.62846) (xy 340.952588 -81.657948) (xy 340.993814 -81.693668) (xy 341.029536 -81.734891)
			(xy 341.059028 -81.780778) (xy 341.081689 -81.830396) (xy 341.097057 -81.882734) (xy 341.10482 -81.936726)
			(xy 341.10482 -81.991274) (xy 341.097057 -82.045266) (xy 341.081689 -82.097604) (xy 341.059028 -82.147222)
			(xy 341.029536 -82.193109) (xy 340.993814 -82.234332) (xy 340.952588 -82.270052) (xy 340.906699 -82.29954)
			(xy 340.857079 -82.322198) (xy 340.804741 -82.337563) (xy 340.750748 -82.345322) (xy 340.723474 -82.345784)
			(xy 339.859874 -82.345784) (xy 339.832607 -82.345252) (xy 339.77863 -82.337488) (xy 339.726306 -82.322121)
			(xy 339.676702 -82.299465) (xy 339.630827 -82.26998) (xy 339.589615 -82.234266) (xy 339.553905 -82.193052)
			(xy 339.524423 -82.147175) (xy 339.50177 -82.097569) (xy 339.486407 -82.045245) (xy 339.478646 -81.991267)
			(xy 337.692804 -81.991267) (xy 337.704024 -82.00099) (xy 337.739714 -82.04218) (xy 337.76918 -82.088031)
			(xy 337.79182 -82.137608) (xy 337.807174 -82.189902) (xy 337.81493 -82.243849) (xy 337.81493 -82.298351)
			(xy 337.807174 -82.352298) (xy 337.79182 -82.404592) (xy 337.769179 -82.454169) (xy 337.739714 -82.50002)
			(xy 337.704024 -82.54121) (xy 337.662836 -82.576902) (xy 337.616987 -82.60637) (xy 337.567411 -82.629013)
			(xy 337.515118 -82.64437) (xy 337.461171 -82.652129) (xy 337.43392 -82.652616) (xy 336.57032 -82.652616)
			(xy 336.543067 -82.652138) (xy 336.489115 -82.644384) (xy 336.436816 -82.62903) (xy 336.387234 -82.606389)
			(xy 336.341379 -82.576922) (xy 336.300185 -82.541229) (xy 336.26449 -82.500037) (xy 336.235021 -82.454183)
			(xy 336.212377 -82.404603) (xy 336.197021 -82.352305) (xy 336.189263 -82.298353) (xy 333.294774 -82.298353)
			(xy 333.283701 -82.311131) (xy 333.242505 -82.346823) (xy 333.196649 -82.376289) (xy 333.147066 -82.398928)
			(xy 333.094765 -82.41428) (xy 333.040812 -82.422032) (xy 333.013558 -82.422492) (xy 332.149958 -82.422492)
			(xy 332.122708 -82.422035) (xy 332.068762 -82.414274) (xy 332.01647 -82.398914) (xy 331.966896 -82.37627)
			(xy 331.921049 -82.346801) (xy 331.879862 -82.311108) (xy 331.844174 -82.269917) (xy 331.81471 -82.224067)
			(xy 331.792071 -82.17449) (xy 331.776717 -82.122197) (xy 331.768962 -82.06825) (xy 239.640092 -82.06825)
			(xy 239.623713 -82.211927) (xy 239.596047 -82.383601) (xy 239.560472 -82.553811) (xy 239.517063 -82.722195)
			(xy 239.465913 -82.888391) (xy 239.407133 -83.052043) (xy 239.340846 -83.212802) (xy 239.267197 -83.370324)
			(xy 239.186341 -83.524271) (xy 239.148735 -83.588471) (xy 341.356398 -83.588471) (xy 341.356398 -83.533929)
			(xy 341.364161 -83.479942) (xy 341.379527 -83.427609) (xy 341.402184 -83.377996) (xy 341.431672 -83.332112)
			(xy 341.467389 -83.290892) (xy 341.508609 -83.255174) (xy 341.554492 -83.225686) (xy 341.604106 -83.203028)
			(xy 341.656438 -83.187661) (xy 341.710425 -83.179899) (xy 341.737696 -83.179412) (xy 342.601296 -83.179412)
			(xy 342.628565 -83.179927) (xy 342.682549 -83.187688) (xy 342.734879 -83.203053) (xy 342.784489 -83.225709)
			(xy 342.83037 -83.255194) (xy 342.871588 -83.290909) (xy 342.907303 -83.332127) (xy 342.936789 -83.378008)
			(xy 342.959445 -83.427618) (xy 342.974811 -83.479947) (xy 342.982573 -83.533931) (xy 342.982573 -83.588469)
			(xy 342.974811 -83.642453) (xy 342.959445 -83.694782) (xy 342.936789 -83.744392) (xy 342.907303 -83.790273)
			(xy 342.871588 -83.831491) (xy 342.83037 -83.867206) (xy 342.784489 -83.896691) (xy 342.734879 -83.919347)
			(xy 342.682549 -83.934712) (xy 342.628565 -83.942473) (xy 342.601296 -83.942936) (xy 341.737696 -83.942936)
			(xy 341.710425 -83.942501) (xy 341.656438 -83.934739) (xy 341.604106 -83.919372) (xy 341.554492 -83.896714)
			(xy 341.508609 -83.867226) (xy 341.467389 -83.831508) (xy 341.431672 -83.790288) (xy 341.402184 -83.744404)
			(xy 341.379527 -83.694791) (xy 341.364161 -83.642458) (xy 341.356398 -83.588471) (xy 239.148735 -83.588471)
			(xy 239.098452 -83.674314) (xy 239.003718 -83.820132) (xy 238.902342 -83.961413) (xy 238.794541 -84.097854)
			(xy 238.680545 -84.229164) (xy 238.560599 -84.355062) (xy 238.434958 -84.475277) (xy 238.393119 -84.511757)
			(xy 337.882119 -84.511757) (xy 337.882119 -84.457243) (xy 337.889878 -84.403284) (xy 337.905237 -84.350979)
			(xy 337.927883 -84.301392) (xy 337.957357 -84.255533) (xy 337.993057 -84.214336) (xy 338.034257 -84.178639)
			(xy 338.080119 -84.149169) (xy 338.129707 -84.126526) (xy 338.182014 -84.111171) (xy 338.235973 -84.103417)
			(xy 338.26323 -84.102956) (xy 339.12683 -84.102956) (xy 339.154077 -84.103516) (xy 339.208017 -84.111275)
			(xy 339.260303 -84.126632) (xy 339.309871 -84.149272) (xy 339.355714 -84.178737) (xy 339.396896 -84.214425)
			(xy 339.432581 -84.25561) (xy 339.462042 -84.301455) (xy 339.484679 -84.351025) (xy 339.500031 -84.403313)
			(xy 339.503159 -84.425069) (xy 344.644951 -84.425069) (xy 344.644951 -84.370531) (xy 344.652713 -84.316548)
			(xy 344.668079 -84.26422) (xy 344.690737 -84.214611) (xy 344.720223 -84.168731) (xy 344.75594 -84.127516)
			(xy 344.797159 -84.091803) (xy 344.843041 -84.06232) (xy 344.892652 -84.039668) (xy 344.944981 -84.024306)
			(xy 344.998965 -84.016549) (xy 345.026234 -84.016088) (xy 345.889834 -84.016088) (xy 345.917105 -84.016477)
			(xy 345.971092 -84.024243) (xy 346.023425 -84.039614) (xy 346.073037 -84.062275) (xy 346.11892 -84.091766)
			(xy 346.160139 -84.127485) (xy 346.195855 -84.168708) (xy 346.225341 -84.214593) (xy 346.247998 -84.264207)
			(xy 346.263364 -84.316541) (xy 346.271126 -84.370529) (xy 346.271126 -84.425071) (xy 346.263364 -84.479059)
			(xy 346.247998 -84.531393) (xy 346.225341 -84.581007) (xy 346.195855 -84.626892) (xy 346.160139 -84.668115)
			(xy 346.11892 -84.703834) (xy 346.073037 -84.733325) (xy 346.023425 -84.755986) (xy 345.971092 -84.771357)
			(xy 345.917105 -84.779123) (xy 345.889834 -84.779612) (xy 345.026234 -84.779612) (xy 344.998965 -84.779051)
			(xy 344.944981 -84.771294) (xy 344.892652 -84.755932) (xy 344.843041 -84.73328) (xy 344.797159 -84.703797)
			(xy 344.75594 -84.668084) (xy 344.720223 -84.626869) (xy 344.690737 -84.580989) (xy 344.668079 -84.53138)
			(xy 344.652713 -84.479052) (xy 344.644951 -84.425069) (xy 339.503159 -84.425069) (xy 339.507786 -84.457253)
			(xy 339.507786 -84.511747) (xy 339.500031 -84.565687) (xy 339.484679 -84.617975) (xy 339.462042 -84.667545)
			(xy 339.432581 -84.71339) (xy 339.396896 -84.754575) (xy 339.355714 -84.790263) (xy 339.309871 -84.819728)
			(xy 339.260303 -84.842368) (xy 339.208017 -84.857725) (xy 339.154077 -84.865484) (xy 339.12683 -84.865972)
			(xy 338.26323 -84.865972) (xy 338.235973 -84.865583) (xy 338.182014 -84.857829) (xy 338.129707 -84.842474)
			(xy 338.080119 -84.819831) (xy 338.034257 -84.790361) (xy 337.993057 -84.754664) (xy 337.957357 -84.713467)
			(xy 337.927883 -84.667608) (xy 337.905237 -84.618021) (xy 337.889878 -84.565716) (xy 337.882119 -84.511757)
			(xy 238.393119 -84.511757) (xy 238.303893 -84.589554) (xy 238.167683 -84.697647) (xy 238.02662 -84.799326)
			(xy 237.881005 -84.894371) (xy 237.73115 -84.982581) (xy 237.577377 -85.063767) (xy 237.420014 -85.137754)
			(xy 237.259397 -85.204384) (xy 237.095871 -85.263515) (xy 236.929785 -85.315021) (xy 236.761494 -85.35879)
			(xy 236.59136 -85.39473) (xy 236.419746 -85.422763) (xy 236.247019 -85.44283) (xy 236.073548 -85.454887)
			(xy 235.899706 -85.458909) (xy 235.725864 -85.454887) (xy 235.552393 -85.44283) (xy 235.379666 -85.422763)
			(xy 235.208052 -85.39473) (xy 235.037918 -85.35879) (xy 234.869627 -85.315021) (xy 234.703541 -85.263515)
			(xy 234.540015 -85.204384) (xy 234.379398 -85.137754) (xy 234.222035 -85.063767) (xy 234.068262 -84.982581)
			(xy 233.918407 -84.894371) (xy 233.772792 -84.799326) (xy 233.631729 -84.697647) (xy 233.495519 -84.589554)
			(xy 233.364454 -84.475277) (xy 233.238813 -84.355062) (xy 233.118867 -84.229164) (xy 233.004871 -84.097854)
			(xy 232.89707 -83.961413) (xy 232.795694 -83.820132) (xy 232.70096 -83.674314) (xy 232.613071 -83.524271)
			(xy 232.532215 -83.370324) (xy 232.458566 -83.212802) (xy 232.392279 -83.052043) (xy 232.333499 -82.888391)
			(xy 232.282349 -82.722195) (xy 232.23894 -82.553811) (xy 232.203365 -82.383601) (xy 232.175699 -82.211927)
			(xy 232.156003 -82.039157) (xy 232.144317 -81.865661) (xy 232.140667 -81.69181) (xy 2.509012 -81.69181)
			(xy 2.509012 -85.764678) (xy 10.421355 -85.764678) (xy 10.421355 -85.635538) (xy 10.429305 -85.506643)
			(xy 10.445175 -85.378483) (xy 10.468904 -85.251542) (xy 10.500403 -85.126303) (xy 10.539552 -85.00324)
			(xy 10.586203 -84.882821) (xy 10.640178 -84.765502) (xy 10.701273 -84.651728) (xy 10.769256 -84.541931)
			(xy 10.84387 -84.436528) (xy 10.924831 -84.335918) (xy 11.011831 -84.240483) (xy 11.104542 -84.150584)
			(xy 11.202612 -84.066563) (xy 11.305667 -83.988739) (xy 11.413318 -83.917407) (xy 11.525157 -83.852837)
			(xy 11.640758 -83.795275) (xy 11.759683 -83.744938) (xy 11.881482 -83.702018) (xy 12.005692 -83.666677)
			(xy 12.131841 -83.63905) (xy 12.259453 -83.619241) (xy 12.388042 -83.607325) (xy 12.51712 -83.603349)
			(xy 12.646198 -83.607325) (xy 12.774787 -83.619241) (xy 12.902399 -83.63905) (xy 13.028548 -83.666677)
			(xy 13.152758 -83.702018) (xy 13.274557 -83.744938) (xy 13.393482 -83.795275) (xy 13.509083 -83.852837)
			(xy 13.620922 -83.917407) (xy 13.728573 -83.988739) (xy 13.831628 -84.066563) (xy 13.929698 -84.150584)
			(xy 14.022409 -84.240483) (xy 14.109409 -84.335918) (xy 14.19037 -84.436528) (xy 14.264984 -84.541931)
			(xy 14.332967 -84.651728) (xy 14.394062 -84.765502) (xy 14.448037 -84.882821) (xy 14.494688 -85.00324)
			(xy 14.533837 -85.126303) (xy 14.565336 -85.251542) (xy 14.589065 -85.378483) (xy 14.604935 -85.506643)
			(xy 14.612885 -85.635538) (xy 14.613382 -85.700108) (xy 14.612885 -85.764678) (xy 14.608278 -85.839368)
			(xy 342.975946 -85.839368) (xy 342.975946 -85.784832) (xy 342.983708 -85.730852) (xy 342.999072 -85.678525)
			(xy 343.021727 -85.628918) (xy 343.051211 -85.58304) (xy 343.086924 -85.541824) (xy 343.12814 -85.506111)
			(xy 343.174018 -85.476627) (xy 343.223625 -85.453972) (xy 343.275952 -85.438608) (xy 343.329932 -85.430846)
			(xy 343.3572 -85.43036) (xy 344.2208 -85.43036) (xy 344.248071 -85.430802) (xy 344.302058 -85.438565)
			(xy 344.35439 -85.453931) (xy 344.404003 -85.476588) (xy 344.449887 -85.506076) (xy 344.491107 -85.541793)
			(xy 344.526824 -85.583013) (xy 344.556312 -85.628897) (xy 344.578969 -85.67851) (xy 344.594335 -85.730842)
			(xy 344.602098 -85.784829) (xy 344.602098 -85.839371) (xy 344.594335 -85.893358) (xy 344.578969 -85.94569)
			(xy 344.556312 -85.995303) (xy 344.526824 -86.041187) (xy 344.491107 -86.082407) (xy 344.449887 -86.118124)
			(xy 344.404003 -86.147612) (xy 344.35439 -86.170269) (xy 344.302058 -86.185635) (xy 344.248071 -86.193398)
			(xy 344.2208 -86.193884) (xy 343.3572 -86.193884) (xy 343.329932 -86.193354) (xy 343.275952 -86.185592)
			(xy 343.223625 -86.170228) (xy 343.174018 -86.147573) (xy 343.12814 -86.118089) (xy 343.086924 -86.082376)
			(xy 343.051211 -86.04116) (xy 343.021727 -85.995282) (xy 342.999072 -85.945675) (xy 342.983708 -85.893348)
			(xy 342.975946 -85.839368) (xy 14.608278 -85.839368) (xy 14.604935 -85.893573) (xy 14.589065 -86.021733)
			(xy 14.565336 -86.148674) (xy 14.533837 -86.273913) (xy 14.494688 -86.396976) (xy 14.448037 -86.517395)
			(xy 14.394062 -86.634714) (xy 14.332967 -86.748488) (xy 14.264984 -86.858285) (xy 14.19037 -86.963688)
			(xy 14.109409 -87.064298) (xy 14.022409 -87.159733) (xy 13.929698 -87.249632) (xy 13.831628 -87.333653)
			(xy 13.728573 -87.411477) (xy 13.620922 -87.482809) (xy 13.509083 -87.547379) (xy 13.393482 -87.604941)
			(xy 13.274557 -87.655278) (xy 13.152758 -87.698198) (xy 13.028548 -87.733539) (xy 12.902399 -87.761166)
			(xy 12.774787 -87.780975) (xy 12.646198 -87.792891) (xy 12.51712 -87.796868) (xy 12.388042 -87.792891)
			(xy 12.259453 -87.780975) (xy 12.131841 -87.761166) (xy 12.005692 -87.733539) (xy 11.881482 -87.698198)
			(xy 11.759683 -87.655278) (xy 11.640758 -87.604941) (xy 11.525157 -87.547379) (xy 11.413318 -87.482809)
			(xy 11.305667 -87.411477) (xy 11.202612 -87.333653) (xy 11.104542 -87.249632) (xy 11.011831 -87.159733)
			(xy 10.924831 -87.064298) (xy 10.84387 -86.963688) (xy 10.769256 -86.858285) (xy 10.701273 -86.748488)
			(xy 10.640178 -86.634714) (xy 10.586203 -86.517395) (xy 10.539552 -86.396976) (xy 10.500403 -86.273913)
			(xy 10.468904 -86.148674) (xy 10.445175 -86.021733) (xy 10.429305 -85.893573) (xy 10.421355 -85.764678)
			(xy 2.509012 -85.764678) (xy 2.509012 -87.999824) (xy 394.691362 -87.999824) (xy 394.691362 -87.99957)
			(xy 394.691607 -87.991837) (xy 394.696278 -87.977094) (xy 394.700506 -87.970614) (xy 395.938502 -86.202266)
			(xy 395.946129 -86.192646) (xy 395.9679 -86.181375) (xy 395.980158 -86.180676) (xy 395.990174 -86.181153)
			(xy 396.008685 -86.188805) (xy 396.022858 -86.20296) (xy 396.030534 -86.221461) (xy 396.030958 -86.231476)
			(xy 396.030958 -86.23173) (xy 396.03071 -86.239463) (xy 396.026041 -86.254205) (xy 396.021814 -86.260686)
			(xy 394.813028 -87.987378) (xy 395.36624 -88.374728) (xy 396.575534 -86.647782) (xy 396.583197 -86.638195)
			(xy 396.60494 -86.626906) (xy 396.61719 -86.626192) (xy 396.62721 -86.626627) (xy 396.645725 -86.634293)
			(xy 396.659897 -86.64846) (xy 396.667569 -86.666972) (xy 396.66799 -86.676992) (xy 396.66799 -86.677246)
			(xy 396.6677 -86.684975) (xy 396.66306 -86.699718) (xy 396.658846 -86.706202) (xy 395.659932 -88.132666)
			(xy 396.89405 -88.132666) (xy 396.89405 -88.132412) (xy 396.894315 -88.124681) (xy 396.898972 -88.109938)
			(xy 396.903194 -88.103456) (xy 398.14119 -86.335108) (xy 398.148831 -86.3255) (xy 398.170591 -86.31422)
			(xy 398.182846 -86.313518) (xy 398.192859 -86.313951) (xy 398.211355 -86.321629) (xy 398.225507 -86.335799)
			(xy 398.233162 -86.354305) (xy 398.233646 -86.364318) (xy 398.233646 -86.364572) (xy 398.233375 -86.372303)
			(xy 398.228722 -86.387046) (xy 398.224502 -86.393528) (xy 397.015716 -88.12022) (xy 397.568928 -88.50757)
			(xy 398.778222 -86.780624) (xy 398.785831 -86.770987) (xy 398.807616 -86.759727) (xy 398.819878 -86.759034)
			(xy 398.829902 -86.759439) (xy 398.848425 -86.767108) (xy 398.862599 -86.781285) (xy 398.870264 -86.79981)
			(xy 398.870678 -86.809834) (xy 398.870678 -86.810088) (xy 398.870408 -86.817819) (xy 398.865754 -86.832561)
			(xy 398.861534 -86.839044) (xy 397.62303 -88.607646) (xy 397.61539 -88.617254) (xy 397.593629 -88.628531)
			(xy 397.581374 -88.629236) (xy 397.58112 -88.629236) (xy 397.573389 -88.62897) (xy 397.558646 -88.624314)
			(xy 397.552164 -88.620092) (xy 396.91564 -88.174322) (xy 396.906026 -88.166689) (xy 396.894753 -88.144923)
			(xy 396.89405 -88.132666) (xy 395.659932 -88.132666) (xy 395.420342 -88.474804) (xy 395.412688 -88.484399)
			(xy 395.390938 -88.495685) (xy 395.378686 -88.496394) (xy 395.378432 -88.496394) (xy 395.370702 -88.496113)
			(xy 395.35596 -88.491466) (xy 395.349476 -88.48725) (xy 394.712952 -88.04148) (xy 394.703321 -88.033864)
			(xy 394.692056 -88.012085) (xy 394.691362 -87.999824) (xy 2.509012 -87.999824) (xy 2.509012 -88.770968)
			(xy 398.73047 -88.770968) (xy 398.73047 -88.770714) (xy 398.730732 -88.762983) (xy 398.735391 -88.748239)
			(xy 398.739614 -88.741758) (xy 399.97761 -86.97341) (xy 399.985242 -86.963794) (xy 400.007008 -86.952518)
			(xy 400.019266 -86.95182) (xy 400.029288 -86.952248) (xy 400.047808 -86.95991) (xy 400.061982 -86.974081)
			(xy 400.069649 -86.992599) (xy 400.070066 -87.00262) (xy 400.070066 -87.002874) (xy 400.069792 -87.010604)
			(xy 400.065141 -87.025347) (xy 400.060922 -87.03183) (xy 398.852136 -88.758522) (xy 399.405348 -89.145872)
			(xy 400.614642 -87.418926) (xy 400.62229 -87.409326) (xy 400.644045 -87.398046) (xy 400.656298 -87.397336)
			(xy 400.666324 -87.397722) (xy 400.684847 -87.405398) (xy 400.699021 -87.419581) (xy 400.706685 -87.43811)
			(xy 400.707098 -87.448136) (xy 400.707098 -87.44839) (xy 400.706826 -87.45612) (xy 400.702173 -87.470863)
			(xy 400.697954 -87.477346) (xy 399.45945 -89.245948) (xy 399.451801 -89.255547) (xy 399.430047 -89.266829)
			(xy 399.417794 -89.267538) (xy 399.41754 -89.267538) (xy 399.40981 -89.267263) (xy 399.395067 -89.262613)
			(xy 399.388584 -89.258394) (xy 398.75206 -88.812624) (xy 398.742451 -88.804985) (xy 398.731174 -88.783224)
			(xy 398.73047 -88.770968) (xy 2.509012 -88.770968) (xy 2.509012 -91.044014) (xy 393.707874 -91.044014)
			(xy 393.707874 -91.04376) (xy 393.708156 -91.03603) (xy 393.712801 -91.021287) (xy 393.717018 -91.014804)
			(xy 394.955014 -89.246456) (xy 394.962634 -89.236829) (xy 394.98441 -89.225562) (xy 394.99667 -89.224866)
			(xy 395.006672 -89.225412) (xy 395.025156 -89.233055) (xy 395.039309 -89.24719) (xy 395.046976 -89.265665)
			(xy 395.04747 -89.275666) (xy 395.04747 -89.27592) (xy 395.047215 -89.283652) (xy 395.042551 -89.298395)
			(xy 395.038326 -89.304876) (xy 393.82954 -91.031568) (xy 394.382752 -91.418918) (xy 395.592046 -89.691972)
			(xy 395.599701 -89.682378) (xy 395.62145 -89.671093) (xy 395.633702 -89.670382) (xy 395.643708 -89.670886)
			(xy 395.662196 -89.678543) (xy 395.676348 -89.692691) (xy 395.684011 -89.711177) (xy 395.684502 -89.721182)
			(xy 395.684502 -89.721436) (xy 395.684249 -89.729168) (xy 395.679583 -89.743911) (xy 395.675358 -89.750392)
			(xy 394.436854 -91.518994) (xy 394.429192 -91.528582) (xy 394.407448 -91.539872) (xy 394.395198 -91.540584)
			(xy 394.394944 -91.540584) (xy 394.387215 -91.5403) (xy 394.372472 -91.535655) (xy 394.365988 -91.53144)
			(xy 393.729464 -91.08567) (xy 393.719876 -91.078009) (xy 393.708588 -91.056264) (xy 393.707874 -91.044014)
			(xy 2.509012 -91.044014) (xy 2.509012 -91.946984) (xy 395.358874 -91.946984) (xy 395.358874 -91.94673)
			(xy 395.359142 -91.938999) (xy 395.363796 -91.924256) (xy 395.368018 -91.917774) (xy 396.606014 -90.149426)
			(xy 396.613628 -90.139793) (xy 396.635409 -90.128531) (xy 396.64767 -90.127836) (xy 396.657694 -90.128245)
			(xy 396.676217 -90.135912) (xy 396.690391 -90.150088) (xy 396.698056 -90.168612) (xy 396.69847 -90.178636)
			(xy 396.69847 -90.17889) (xy 396.698203 -90.186621) (xy 396.693547 -90.201364) (xy 396.689326 -90.207846)
			(xy 395.48054 -91.934538) (xy 396.033752 -92.321888) (xy 397.243046 -90.594942) (xy 397.250695 -90.585343)
			(xy 397.272449 -90.574062) (xy 397.284702 -90.573352) (xy 397.294704 -90.573885) (xy 397.313186 -90.581537)
			(xy 397.327338 -90.595675) (xy 397.335006 -90.614151) (xy 397.335502 -90.624152) (xy 397.335502 -90.624406)
			(xy 397.335236 -90.632137) (xy 397.330579 -90.64688) (xy 397.326358 -90.653362) (xy 396.087854 -92.421964)
			(xy 396.080206 -92.431564) (xy 396.058451 -92.442845) (xy 396.046198 -92.443554) (xy 396.045944 -92.443554)
			(xy 396.038214 -92.443275) (xy 396.023471 -92.438628) (xy 396.016988 -92.43441) (xy 395.380464 -91.98864)
			(xy 395.370863 -91.980993) (xy 395.359582 -91.959237) (xy 395.358874 -91.946984) (xy 2.509012 -91.946984)
			(xy 2.509012 -92.801694) (xy 397.043656 -92.801694) (xy 397.043656 -92.80144) (xy 397.043932 -92.79371)
			(xy 397.048581 -92.778967) (xy 397.0528 -92.772484) (xy 398.290796 -91.004136) (xy 398.29842 -90.994513)
			(xy 398.320193 -90.983245) (xy 398.332452 -90.982546) (xy 398.342476 -90.98296) (xy 398.361001 -90.990623)
			(xy 398.375176 -91.004798) (xy 398.38284 -91.023322) (xy 398.383252 -91.033346) (xy 398.383252 -91.0336)
			(xy 398.382992 -91.041332) (xy 398.378332 -91.056074) (xy 398.374108 -91.062556) (xy 397.165322 -92.789248)
			(xy 397.718534 -93.176598) (xy 398.927828 -91.449652) (xy 398.935488 -91.440063) (xy 398.957234 -91.428776)
			(xy 398.969484 -91.428062) (xy 398.979486 -91.4286) (xy 398.99797 -91.436247) (xy 399.012122 -91.450385)
			(xy 399.019789 -91.468861) (xy 399.020284 -91.478862) (xy 399.020284 -91.479116) (xy 399.020025 -91.486848)
			(xy 399.015363 -91.50159) (xy 399.01114 -91.508072) (xy 397.967403 -92.998544) (xy 400.552666 -92.998544)
			(xy 400.552887 -92.991735) (xy 400.556493 -92.978604) (xy 400.559778 -92.972636) (xy 401.66036 -91.115388)
			(xy 401.665124 -91.107988) (xy 401.678695 -91.096795) (xy 401.695252 -91.090857) (xy 401.704048 -91.090496)
			(xy 401.714058 -91.090949) (xy 401.73255 -91.098623) (xy 401.746701 -91.112787) (xy 401.75436 -91.131285)
			(xy 401.754848 -91.141296) (xy 401.754603 -91.148103) (xy 401.751013 -91.161234) (xy 401.747736 -91.167204)
			(xy 400.673062 -92.980764) (xy 401.254214 -93.325188) (xy 402.329142 -91.511628) (xy 402.333929 -91.504244)
			(xy 402.347488 -91.493046) (xy 402.364037 -91.487101) (xy 402.37283 -91.486736) (xy 402.382858 -91.487096)
			(xy 402.401382 -91.494782) (xy 402.415555 -91.508973) (xy 402.423217 -91.527508) (xy 402.42363 -91.537536)
			(xy 402.423402 -91.544344) (xy 402.419801 -91.557476) (xy 402.416518 -91.563444) (xy 401.315682 -93.420692)
			(xy 401.310886 -93.428069) (xy 401.297331 -93.439267) (xy 401.280785 -93.445216) (xy 401.271994 -93.445584)
			(xy 401.265186 -93.44535) (xy 401.252054 -93.441754) (xy 401.246086 -93.438472) (xy 400.577558 -93.042232)
			(xy 400.570169 -93.037452) (xy 400.558969 -93.023892) (xy 400.553027 -93.007338) (xy 400.552666 -92.998544)
			(xy 397.967403 -92.998544) (xy 397.772636 -93.276674) (xy 397.764998 -93.286284) (xy 397.743235 -93.297559)
			(xy 397.73098 -93.298264) (xy 397.730726 -93.298264) (xy 397.722996 -93.297991) (xy 397.708253 -93.293339)
			(xy 397.70177 -93.28912) (xy 397.065246 -92.84335) (xy 397.055646 -92.835702) (xy 397.044365 -92.813947)
			(xy 397.043656 -92.801694) (xy 2.509012 -92.801694) (xy 2.509012 -95.59036) (xy 397.902684 -95.59036)
			(xy 397.902908 -95.583552) (xy 397.906512 -95.57042) (xy 397.909796 -95.564452) (xy 399.010378 -93.707204)
			(xy 399.015197 -93.699845) (xy 399.028742 -93.688644) (xy 399.045278 -93.682687) (xy 399.054066 -93.682312)
			(xy 399.064087 -93.682748) (xy 399.082605 -93.690409) (xy 399.096779 -93.704577) (xy 399.104448 -93.723092)
			(xy 399.104866 -93.733112) (xy 399.104637 -93.73992) (xy 399.101038 -93.753052) (xy 399.097754 -93.75902)
			(xy 398.02308 -95.57258) (xy 398.604232 -95.917004) (xy 399.67916 -94.103444) (xy 399.683941 -94.096055)
			(xy 399.697501 -94.084856) (xy 399.714054 -94.078914) (xy 399.722848 -94.078552) (xy 399.732853 -94.079048)
			(xy 399.751336 -94.086714) (xy 399.765486 -94.100864) (xy 399.773152 -94.119347) (xy 399.773648 -94.129352)
			(xy 399.773424 -94.13616) (xy 399.76982 -94.149292) (xy 399.766536 -94.15526) (xy 399.702853 -94.262702)
			(xy 402.057362 -94.262702) (xy 402.057605 -94.255895) (xy 402.061196 -94.242763) (xy 402.064474 -94.236794)
			(xy 403.165056 -92.379546) (xy 403.16984 -92.37216) (xy 403.183399 -92.36096) (xy 403.199951 -92.355017)
			(xy 403.208744 -92.354654) (xy 403.218749 -92.355151) (xy 403.237233 -92.362816) (xy 403.251382 -92.376966)
			(xy 403.259049 -92.395449) (xy 403.259544 -92.405454) (xy 403.259321 -92.412262) (xy 403.255717 -92.425394)
			(xy 403.252432 -92.431362) (xy 402.177758 -94.244922) (xy 402.75891 -94.589346) (xy 403.833838 -92.775786)
			(xy 403.838615 -92.768395) (xy 403.85218 -92.757201) (xy 403.868732 -92.751258) (xy 403.877526 -92.750894)
			(xy 403.887535 -92.751367) (xy 403.906026 -92.759034) (xy 403.920178 -92.773191) (xy 403.927837 -92.791685)
			(xy 403.928326 -92.801694) (xy 403.928083 -92.808501) (xy 403.924492 -92.821633) (xy 403.921214 -92.827602)
			(xy 402.820378 -94.68485) (xy 402.815572 -94.69222) (xy 402.802023 -94.703423) (xy 402.78548 -94.709374)
			(xy 402.77669 -94.709742) (xy 402.769883 -94.709503) (xy 402.756751 -94.705909) (xy 402.750782 -94.70263)
			(xy 402.082254 -94.30639) (xy 402.07489 -94.301576) (xy 402.063686 -94.28803) (xy 402.057732 -94.271491)
			(xy 402.057362 -94.262702) (xy 399.702853 -94.262702) (xy 398.6657 -96.012508) (xy 398.660898 -96.01988)
			(xy 398.647345 -96.031078) (xy 398.630802 -96.03703) (xy 398.622012 -96.0374) (xy 398.615202 -96.037196)
			(xy 398.60207 -96.033579) (xy 398.596104 -96.030288) (xy 397.927576 -95.634048) (xy 397.920177 -95.629282)
			(xy 397.908985 -95.615712) (xy 397.903046 -95.599155) (xy 397.902684 -95.59036) (xy 2.509012 -95.59036)
			(xy 2.509012 -96.354646) (xy 399.66519 -96.354646) (xy 399.665408 -96.347837) (xy 399.669016 -96.334705)
			(xy 399.672302 -96.328738) (xy 400.772884 -94.47149) (xy 400.777695 -94.464125) (xy 400.791244 -94.452926)
			(xy 400.807783 -94.446971) (xy 400.816572 -94.446598) (xy 400.826591 -94.447043) (xy 400.845107 -94.454703)
			(xy 400.85928 -94.468868) (xy 400.866952 -94.487379) (xy 400.867372 -94.497398) (xy 400.867137 -94.504206)
			(xy 400.863542 -94.517338) (xy 400.86026 -94.523306) (xy 399.785586 -96.336866) (xy 400.366738 -96.68129)
			(xy 401.441666 -94.86773) (xy 401.446439 -94.860336) (xy 401.460004 -94.849139) (xy 401.476559 -94.843199)
			(xy 401.485354 -94.842838) (xy 401.495377 -94.843258) (xy 401.5139 -94.85092) (xy 401.528076 -94.865093)
			(xy 401.53574 -94.883615) (xy 401.536154 -94.893638) (xy 401.535936 -94.900447) (xy 401.532329 -94.913579)
			(xy 401.529042 -94.919546) (xy 401.410106 -95.120206) (xy 403.76602 -95.120206) (xy 403.766258 -95.113399)
			(xy 403.769851 -95.100267) (xy 403.773132 -95.094298) (xy 404.873714 -93.23705) (xy 404.878525 -93.229683)
			(xy 404.892072 -93.21848) (xy 404.908612 -93.212527) (xy 404.917402 -93.212158) (xy 404.927405 -93.212685)
			(xy 404.945888 -93.220338) (xy 404.96004 -93.234478) (xy 404.967707 -93.252956) (xy 404.968202 -93.262958)
			(xy 404.967986 -93.269767) (xy 404.964377 -93.282899) (xy 404.96109 -93.288866) (xy 403.886416 -95.102426)
			(xy 404.467568 -95.44685) (xy 405.542496 -93.63329) (xy 405.5473 -93.625919) (xy 405.560852 -93.614722)
			(xy 405.577394 -93.608769) (xy 405.586184 -93.608398) (xy 405.596204 -93.608832) (xy 405.61472 -93.616497)
			(xy 405.628893 -93.630665) (xy 405.636564 -93.649178) (xy 405.636984 -93.659198) (xy 405.636747 -93.666005)
			(xy 405.633153 -93.679137) (xy 405.629872 -93.685106) (xy 404.529036 -95.542354) (xy 404.524257 -95.549744)
			(xy 404.510696 -95.560943) (xy 404.494142 -95.566885) (xy 404.485348 -95.567246) (xy 404.47854 -95.567022)
			(xy 404.465408 -95.563418) (xy 404.45944 -95.560134) (xy 403.790912 -95.163894) (xy 403.783541 -95.159089)
			(xy 403.772342 -95.145538) (xy 403.76639 -95.128996) (xy 403.76602 -95.120206) (xy 401.410106 -95.120206)
			(xy 400.428206 -96.776794) (xy 400.423396 -96.78416) (xy 400.409847 -96.79536) (xy 400.393307 -96.801314)
			(xy 400.384518 -96.801686) (xy 400.377708 -96.801481) (xy 400.364576 -96.797865) (xy 400.35861 -96.794574)
			(xy 399.690082 -96.398334) (xy 399.682678 -96.393575) (xy 399.671487 -96.380002) (xy 399.66555 -96.363442)
			(xy 399.66519 -96.354646) (xy 2.509012 -96.354646) (xy 2.509012 -98.341434) (xy 261.733792 -98.341434)
			(xy 261.733792 -97.477834) (xy 261.734278 -97.450583) (xy 261.742034 -97.396635) (xy 261.757389 -97.34434)
			(xy 261.780031 -97.294763) (xy 261.809497 -97.248913) (xy 261.845188 -97.207722) (xy 261.886379 -97.172031)
			(xy 261.932229 -97.142565) (xy 261.981806 -97.119923) (xy 262.034101 -97.104568) (xy 262.088049 -97.096812)
			(xy 262.142551 -97.096812) (xy 262.196499 -97.104568) (xy 262.248794 -97.119923) (xy 262.298371 -97.142565)
			(xy 262.344221 -97.172031) (xy 262.380849 -97.203768) (xy 401.423124 -97.203768) (xy 401.423347 -97.196959)
			(xy 401.426951 -97.183828) (xy 401.430236 -97.17786) (xy 402.530818 -95.320612) (xy 402.535615 -95.313236)
			(xy 402.54917 -95.302038) (xy 402.565715 -95.296088) (xy 402.574506 -95.29572) (xy 402.58453 -95.296115)
			(xy 402.603051 -95.303791) (xy 402.617224 -95.317971) (xy 402.62489 -95.336496) (xy 402.625306 -95.34652)
			(xy 402.625075 -95.353328) (xy 402.621476 -95.36646) (xy 402.618194 -95.372428) (xy 401.54352 -97.185988)
			(xy 402.124672 -97.530412) (xy 403.1996 -95.716852) (xy 403.20442 -95.709492) (xy 403.217963 -95.698288)
			(xy 403.2345 -95.692332) (xy 403.243288 -95.69196) (xy 403.25329 -95.692497) (xy 403.271774 -95.700145)
			(xy 403.285926 -95.714283) (xy 403.293593 -95.732759) (xy 403.294088 -95.74276) (xy 403.293875 -95.749569)
			(xy 403.290264 -95.762701) (xy 403.286976 -95.768668) (xy 403.250693 -95.829882) (xy 405.562562 -95.829882)
			(xy 405.562798 -95.823075) (xy 405.566393 -95.809943) (xy 405.569674 -95.803974) (xy 406.670256 -93.946726)
			(xy 406.675034 -93.939336) (xy 406.688597 -93.928138) (xy 406.70515 -93.922196) (xy 406.713944 -93.921834)
			(xy 406.723959 -93.922253) (xy 406.742458 -93.929933) (xy 406.756611 -93.944108) (xy 406.764262 -93.962619)
			(xy 406.764744 -93.972634) (xy 406.764514 -93.979442) (xy 406.760914 -93.992574) (xy 406.757632 -93.998542)
			(xy 405.682958 -95.812102) (xy 406.26411 -96.156526) (xy 407.339038 -94.342966) (xy 407.343839 -94.335592)
			(xy 407.357389 -94.324389) (xy 407.373935 -94.31844) (xy 407.382726 -94.318074) (xy 407.392732 -94.318566)
			(xy 407.41122 -94.326229) (xy 407.425371 -94.34038) (xy 407.433034 -94.358868) (xy 407.433526 -94.368874)
			(xy 407.433313 -94.375683) (xy 407.429702 -94.388815) (xy 407.426414 -94.394782) (xy 406.325578 -96.25203)
			(xy 406.320766 -96.259396) (xy 406.30722 -96.270601) (xy 406.29068 -96.276553) (xy 406.28189 -96.276922)
			(xy 406.275083 -96.276686) (xy 406.261951 -96.273091) (xy 406.255982 -96.26981) (xy 405.587454 -95.87357)
			(xy 405.580081 -95.868768) (xy 405.568879 -95.855217) (xy 405.562929 -95.838673) (xy 405.562562 -95.829882)
			(xy 403.250693 -95.829882) (xy 402.18614 -97.625916) (xy 402.181377 -97.633317) (xy 402.167806 -97.644509)
			(xy 402.151248 -97.650447) (xy 402.142452 -97.650808) (xy 402.135643 -97.650588) (xy 402.122511 -97.646982)
			(xy 402.116544 -97.643696) (xy 401.448016 -97.247456) (xy 401.440629 -97.242674) (xy 401.429432 -97.229113)
			(xy 401.423488 -97.212561) (xy 401.423124 -97.203768) (xy 262.380849 -97.203768) (xy 262.385412 -97.207722)
			(xy 262.421103 -97.248913) (xy 262.450569 -97.294763) (xy 262.473211 -97.34434) (xy 262.488566 -97.396635)
			(xy 262.496322 -97.450583) (xy 262.496808 -97.477834) (xy 262.496808 -97.953068) (xy 403.195536 -97.953068)
			(xy 403.195757 -97.946259) (xy 403.199362 -97.933127) (xy 403.202648 -97.92716) (xy 404.30323 -96.069912)
			(xy 404.30802 -96.062531) (xy 404.321578 -96.051333) (xy 404.338126 -96.045386) (xy 404.346918 -96.04502)
			(xy 404.356943 -96.045405) (xy 404.375464 -96.053085) (xy 404.389636 -96.067268) (xy 404.397302 -96.085795)
			(xy 404.397718 -96.09582) (xy 404.397486 -96.102628) (xy 404.393888 -96.11576) (xy 404.390606 -96.121728)
			(xy 403.315932 -97.935288) (xy 403.897084 -98.279712) (xy 404.972012 -96.466152) (xy 404.976824 -96.458787)
			(xy 404.990371 -96.447583) (xy 405.006911 -96.44163) (xy 405.0157 -96.44126) (xy 405.025703 -96.441787)
			(xy 405.044187 -96.449439) (xy 405.058338 -96.46358) (xy 405.066005 -96.482058) (xy 405.0665 -96.49206)
			(xy 405.066285 -96.498869) (xy 405.062676 -96.512001) (xy 405.059388 -96.517968) (xy 403.958552 -98.375216)
			(xy 403.953782 -98.382611) (xy 403.940214 -98.393804) (xy 403.923659 -98.399745) (xy 403.914864 -98.400108)
			(xy 403.908056 -98.399883) (xy 403.894924 -98.39628) (xy 403.888956 -98.392996) (xy 403.220428 -97.996756)
			(xy 403.213043 -97.99197) (xy 403.201845 -97.978411) (xy 403.1959 -97.961861) (xy 403.195536 -97.953068)
			(xy 262.496808 -97.953068) (xy 262.496808 -98.341434) (xy 262.496322 -98.368685) (xy 262.488566 -98.422633)
			(xy 262.473211 -98.474928) (xy 262.450569 -98.524505) (xy 262.421103 -98.570355) (xy 262.414779 -98.577654)
			(xy 405.042116 -98.577654) (xy 405.042335 -98.570845) (xy 405.045941 -98.557713) (xy 405.049228 -98.551746)
			(xy 406.14981 -96.694498) (xy 406.154608 -96.687123) (xy 406.168163 -96.675925) (xy 406.184707 -96.669975)
			(xy 406.193498 -96.669606) (xy 406.20352 -96.670021) (xy 406.222038 -96.677692) (xy 406.236211 -96.691865)
			(xy 406.24388 -96.710384) (xy 406.244298 -96.720406) (xy 406.244063 -96.727214) (xy 406.242797 -96.731836)
			(xy 407.26106 -96.731836) (xy 407.261279 -96.725027) (xy 407.264886 -96.711896) (xy 407.268172 -96.705928)
			(xy 408.368754 -94.84868) (xy 408.373519 -94.841281) (xy 408.38709 -94.830089) (xy 408.403647 -94.82415)
			(xy 408.412442 -94.823788) (xy 408.422451 -94.824253) (xy 408.440941 -94.831925) (xy 408.455092 -94.846084)
			(xy 408.462752 -94.864579) (xy 408.463242 -94.874588) (xy 408.463032 -94.881397) (xy 408.459419 -94.894529)
			(xy 408.45613 -94.900496) (xy 407.381456 -96.714056) (xy 407.962608 -97.05848) (xy 409.037536 -95.24492)
			(xy 409.042324 -95.237537) (xy 409.055883 -95.226339) (xy 409.072432 -95.220393) (xy 409.081224 -95.220028)
			(xy 409.09125 -95.220401) (xy 409.109773 -95.228084) (xy 409.123945 -95.242271) (xy 409.131609 -95.260801)
			(xy 409.132024 -95.270828) (xy 409.131794 -95.277636) (xy 409.128195 -95.290768) (xy 409.124912 -95.296736)
			(xy 408.024076 -97.153984) (xy 408.019281 -97.161362) (xy 408.005726 -97.17256) (xy 407.98918 -97.178509)
			(xy 407.980388 -97.178876) (xy 407.97358 -97.178646) (xy 407.960448 -97.175047) (xy 407.95448 -97.171764)
			(xy 407.285952 -96.775524) (xy 407.278603 -96.770689) (xy 407.267397 -96.757153) (xy 407.261435 -96.740622)
			(xy 407.26106 -96.731836) (xy 406.242797 -96.731836) (xy 406.240467 -96.740345) (xy 406.237186 -96.746314)
			(xy 405.162512 -98.559874) (xy 405.743664 -98.904298) (xy 406.818592 -97.090738) (xy 406.823413 -97.083379)
			(xy 406.836956 -97.072176) (xy 406.853492 -97.066219) (xy 406.86228 -97.065846) (xy 406.872306 -97.066237)
			(xy 406.890831 -97.073909) (xy 406.905005 -97.088091) (xy 406.912668 -97.10662) (xy 406.91308 -97.116646)
			(xy 406.912862 -97.123455) (xy 406.909255 -97.136587) (xy 406.905968 -97.142554) (xy 405.805132 -98.999802)
			(xy 405.80037 -99.007204) (xy 405.786799 -99.018397) (xy 405.77024 -99.024334) (xy 405.761444 -99.024694)
			(xy 405.754635 -99.024478) (xy 405.741503 -99.02087) (xy 405.735536 -99.017582) (xy 405.067008 -98.621342)
			(xy 405.059613 -98.616571) (xy 405.048418 -98.603004) (xy 405.042478 -98.586449) (xy 405.042116 -98.577654)
			(xy 262.414779 -98.577654) (xy 262.385412 -98.611546) (xy 262.344221 -98.647237) (xy 262.298371 -98.676703)
			(xy 262.248794 -98.699345) (xy 262.196499 -98.7147) (xy 262.142551 -98.722456) (xy 262.088049 -98.722456)
			(xy 262.034101 -98.7147) (xy 261.981806 -98.699345) (xy 261.932229 -98.676703) (xy 261.886379 -98.647237)
			(xy 261.845188 -98.611546) (xy 261.809497 -98.570355) (xy 261.780031 -98.524505) (xy 261.757389 -98.474928)
			(xy 261.742034 -98.422633) (xy 261.734278 -98.368685) (xy 261.733792 -98.341434) (xy 2.509012 -98.341434)
			(xy 2.509012 -101.18344) (xy 13.926312 -101.18344) (xy 14.691868 -101.18344) (xy 14.691868 -101.19106)
			(xy 14.934692 -101.19106) (xy 15.692628 -101.19106) (xy 15.692628 -101.910896) (xy 14.934692 -101.910896)
			(xy 14.934692 -101.19106) (xy 14.691868 -101.19106) (xy 14.691868 -101.915976) (xy 13.926312 -101.915976)
			(xy 13.926312 -101.18344) (xy 2.509012 -101.18344) (xy 2.509012 -103.19004) (xy 12.153897 -103.19004)
			(xy 12.157976 -103.134307) (xy 12.170126 -103.079761) (xy 12.190089 -103.027566) (xy 12.217439 -102.978834)
			(xy 12.251593 -102.934603) (xy 12.291823 -102.895816) (xy 12.337272 -102.8633) (xy 12.38697 -102.837749)
			(xy 12.43986 -102.819705) (xy 12.494813 -102.809555) (xy 12.550658 -102.807514) (xy 12.606205 -102.813626)
			(xy 12.660271 -102.82776) (xy 12.711702 -102.849616) (xy 12.759403 -102.878728) (xy 12.802357 -102.914474)
			(xy 12.839648 -102.956094) (xy 12.870482 -103.0027) (xy 12.894202 -103.053299) (xy 12.894993 -103.055928)
			(xy 14.99057 -103.055928) (xy 14.994643 -103.000269) (xy 15.006778 -102.945796) (xy 15.026714 -102.89367)
			(xy 15.054028 -102.845002) (xy 15.088136 -102.80083) (xy 15.128313 -102.762095) (xy 15.173701 -102.729623)
			(xy 15.223333 -102.704105) (xy 15.276153 -102.686086) (xy 15.331032 -102.675949) (xy 15.386803 -102.673911)
			(xy 15.442277 -102.680014) (xy 15.49627 -102.69413) (xy 15.547633 -102.715957) (xy 15.595271 -102.74503)
			(xy 15.638167 -102.780729) (xy 15.675409 -102.822293) (xy 15.706203 -102.868837) (xy 15.729891 -102.919368)
			(xy 15.745969 -102.97281) (xy 15.754095 -103.028024) (xy 15.754604 -103.055928) (xy 16.10817 -103.055928)
			(xy 16.112243 -103.000269) (xy 16.124378 -102.945796) (xy 16.144314 -102.89367) (xy 16.171628 -102.845002)
			(xy 16.205736 -102.80083) (xy 16.245913 -102.762095) (xy 16.291301 -102.729623) (xy 16.340933 -102.704105)
			(xy 16.393753 -102.686086) (xy 16.448632 -102.675949) (xy 16.504403 -102.673911) (xy 16.559877 -102.680014)
			(xy 16.61387 -102.69413) (xy 16.665233 -102.715957) (xy 16.712871 -102.74503) (xy 16.755767 -102.780729)
			(xy 16.793009 -102.822293) (xy 16.823803 -102.868837) (xy 16.847491 -102.919368) (xy 16.863569 -102.97281)
			(xy 16.871695 -103.028024) (xy 16.872204 -103.055928) (xy 16.871695 -103.083832) (xy 16.863569 -103.139046)
			(xy 16.847491 -103.192488) (xy 16.823803 -103.243019) (xy 16.793009 -103.289563) (xy 16.755767 -103.331127)
			(xy 16.712871 -103.366826) (xy 16.665233 -103.395899) (xy 16.61387 -103.417726) (xy 16.559877 -103.431842)
			(xy 16.504403 -103.437945) (xy 16.448632 -103.435907) (xy 16.393753 -103.42577) (xy 16.340933 -103.407751)
			(xy 16.291301 -103.382233) (xy 16.245913 -103.349761) (xy 16.205736 -103.311026) (xy 16.171628 -103.266854)
			(xy 16.144314 -103.218186) (xy 16.124378 -103.16606) (xy 16.112243 -103.111587) (xy 16.10817 -103.055928)
			(xy 15.754604 -103.055928) (xy 15.754095 -103.083832) (xy 15.745969 -103.139046) (xy 15.729891 -103.192488)
			(xy 15.706203 -103.243019) (xy 15.675409 -103.289563) (xy 15.638167 -103.331127) (xy 15.595271 -103.366826)
			(xy 15.547633 -103.395899) (xy 15.49627 -103.417726) (xy 15.442277 -103.431842) (xy 15.386803 -103.437945)
			(xy 15.331032 -103.435907) (xy 15.276153 -103.42577) (xy 15.223333 -103.407751) (xy 15.173701 -103.382233)
			(xy 15.128313 -103.349761) (xy 15.088136 -103.311026) (xy 15.054028 -103.266854) (xy 15.026714 -103.218186)
			(xy 15.006778 -103.16606) (xy 14.994643 -103.111587) (xy 14.99057 -103.055928) (xy 12.894993 -103.055928)
			(xy 12.910302 -103.106812) (xy 12.918438 -103.162099) (xy 12.918948 -103.19004) (xy 12.918438 -103.217981)
			(xy 12.910302 -103.273268) (xy 12.894202 -103.326781) (xy 12.870482 -103.37738) (xy 12.839648 -103.423986)
			(xy 12.802357 -103.465606) (xy 12.759403 -103.501352) (xy 12.711702 -103.530464) (xy 12.660271 -103.55232)
			(xy 12.606205 -103.566454) (xy 12.550658 -103.572566) (xy 12.494813 -103.570525) (xy 12.43986 -103.560375)
			(xy 12.38697 -103.542331) (xy 12.337272 -103.51678) (xy 12.291823 -103.484264) (xy 12.251593 -103.445477)
			(xy 12.217439 -103.401246) (xy 12.190089 -103.352514) (xy 12.170126 -103.300319) (xy 12.157976 -103.245773)
			(xy 12.153897 -103.19004) (xy 2.509012 -103.19004) (xy 2.509012 -103.908352) (xy 12.872972 -103.908352)
			(xy 12.877045 -103.852693) (xy 12.88918 -103.79822) (xy 12.909116 -103.746094) (xy 12.93643 -103.697426)
			(xy 12.970538 -103.653254) (xy 13.010715 -103.614519) (xy 13.056103 -103.582047) (xy 13.105735 -103.556529)
			(xy 13.158555 -103.53851) (xy 13.213434 -103.528373) (xy 13.269205 -103.526335) (xy 13.324679 -103.532438)
			(xy 13.378672 -103.546554) (xy 13.430035 -103.568381) (xy 13.477673 -103.597454) (xy 13.520569 -103.633153)
			(xy 13.557811 -103.674717) (xy 13.588605 -103.721261) (xy 13.612293 -103.771792) (xy 13.628371 -103.825234)
			(xy 13.636497 -103.880448) (xy 13.637006 -103.908352) (xy 13.636497 -103.936256) (xy 13.628371 -103.99147)
			(xy 13.612293 -104.044912) (xy 13.588605 -104.095443) (xy 13.557811 -104.141987) (xy 13.520569 -104.183551)
			(xy 13.477673 -104.21925) (xy 13.430035 -104.248323) (xy 13.378672 -104.27015) (xy 13.324679 -104.284266)
			(xy 13.269205 -104.290369) (xy 13.213434 -104.288331) (xy 13.158555 -104.278194) (xy 13.105735 -104.260175)
			(xy 13.056103 -104.234657) (xy 13.010715 -104.202185) (xy 12.970538 -104.16345) (xy 12.93643 -104.119278)
			(xy 12.909116 -104.07061) (xy 12.88918 -104.018484) (xy 12.877045 -103.964011) (xy 12.872972 -103.908352)
			(xy 2.509012 -103.908352) (xy 2.509012 -105.999026) (xy 11.169396 -105.999026) (xy 11.169396 -104.929686)
			(xy 11.170061 -104.91731) (xy 11.176615 -104.893419) (xy 11.188804 -104.871852) (xy 11.197082 -104.86263)
			(xy 11.206734 -104.85321) (xy 11.229956 -104.839513) (xy 11.255989 -104.832501) (xy 11.269472 -104.83215)
			(xy 11.269472 -104.832404) (xy 11.576304 -104.832404) (xy 11.590674 -104.833576) (xy 11.617854 -104.843158)
			(xy 11.641152 -104.860122) (xy 11.658616 -104.883046) (xy 11.668786 -104.910012) (xy 11.670284 -104.924352)
			(xy 11.670284 -105.179368) (xy 11.67085 -105.193999) (xy 11.679194 -105.222047) (xy 11.69515 -105.246577)
			(xy 11.717407 -105.265576) (xy 11.744139 -105.277483) (xy 11.773149 -105.281321) (xy 11.802057 -105.276774)
			(xy 11.828489 -105.264217) (xy 11.839702 -105.254806) (xy 11.860821 -105.236392) (xy 11.907473 -105.205359)
			(xy 11.958157 -105.181471) (xy 12.011786 -105.165242) (xy 12.067211 -105.15702) (xy 12.095226 -105.156508)
			(xy 12.124881 -105.157091) (xy 12.183475 -105.166272) (xy 12.239943 -105.184408) (xy 12.292926 -105.211063)
			(xy 12.341146 -105.245595) (xy 12.362688 -105.265982) (xy 12.37367 -105.27612) (xy 12.400112 -105.290028)
			(xy 12.429448 -105.295684) (xy 12.459165 -105.292606) (xy 12.486718 -105.281055) (xy 12.509747 -105.262022)
			(xy 12.526279 -105.237137) (xy 12.534898 -105.208531) (xy 12.535408 -105.193592) (xy 12.535408 -104.97185)
			(xy 12.536072 -104.959456) (xy 12.542724 -104.93555) (xy 12.555019 -104.913996) (xy 12.563348 -104.904794)
			(xy 12.573023 -104.895401) (xy 12.596233 -104.881692) (xy 12.622258 -104.87467) (xy 12.635738 -104.874314)
			(xy 12.635738 -104.874568) (xy 12.94257 -104.874568) (xy 12.956907 -104.875807) (xy 12.984015 -104.885427)
			(xy 13.007244 -104.902392) (xy 13.024656 -104.925287) (xy 13.034799 -104.952204) (xy 13.036296 -104.966516)
			(xy 13.036296 -105.893108) (xy 13.036804 -105.893108) (xy 13.036804 -106.03611) (xy 13.03655 -106.03992)
			(xy 13.036296 -106.041444) (xy 13.036296 -106.074972) (xy 14.014704 -106.074972) (xy 14.014704 -105.005632)
			(xy 14.015359 -104.993237) (xy 14.022015 -104.969331) (xy 14.034313 -104.947778) (xy 14.042644 -104.938576)
			(xy 14.052318 -104.929182) (xy 14.075529 -104.915475) (xy 14.101554 -104.908453) (xy 14.115034 -104.908096)
			(xy 14.421866 -104.908096) (xy 14.436237 -104.909255) (xy 14.463389 -104.918932) (xy 14.486636 -104.935973)
			(xy 14.504035 -104.958954) (xy 14.514131 -104.985952) (xy 14.515592 -105.000298) (xy 14.515592 -105.927144)
			(xy 14.5161 -105.927144) (xy 14.5161 -106.069892) (xy 14.515942 -106.07294) (xy 15.037308 -106.07294)
			(xy 15.037308 -104.2035) (xy 15.037945 -104.191103) (xy 15.044609 -104.167197) (xy 15.056913 -104.145645)
			(xy 15.065248 -104.136444) (xy 15.074916 -104.127043) (xy 15.09813 -104.113339) (xy 15.124157 -104.106319)
			(xy 15.137638 -104.105964) (xy 15.44447 -104.105964) (xy 15.458829 -104.107229) (xy 15.485974 -104.116877)
			(xy 15.509221 -104.133892) (xy 15.526625 -104.156849) (xy 15.53673 -104.183828) (xy 15.538196 -104.198166)
			(xy 15.538196 -104.433624) (xy 15.538656 -104.448152) (xy 15.546788 -104.476046) (xy 15.562443 -104.500523)
			(xy 15.584356 -104.519602) (xy 15.610754 -104.53174) (xy 15.639502 -104.535956) (xy 15.668273 -104.531909)
			(xy 15.694742 -104.519924) (xy 15.70609 -104.51084) (xy 15.726929 -104.493566) (xy 15.772583 -104.464489)
			(xy 15.821888 -104.442155) (xy 15.873854 -104.427012) (xy 15.927438 -104.419364) (xy 15.954502 -104.418892)
			(xy 15.95501 -104.418892) (xy 15.984175 -104.419478) (xy 16.041823 -104.428366) (xy 16.097444 -104.445933)
			(xy 16.14974 -104.471769) (xy 16.197488 -104.505271) (xy 16.218916 -104.525064) (xy 16.229988 -104.53494)
			(xy 16.256403 -104.548416) (xy 16.285577 -104.553733) (xy 16.315048 -104.550441) (xy 16.34233 -104.538819)
			(xy 16.365121 -104.519846) (xy 16.381499 -104.495124) (xy 16.39008 -104.466738) (xy 16.39062 -104.451912)
			(xy 16.39062 -104.226106) (xy 16.391283 -104.213712) (xy 16.39794 -104.189808) (xy 16.410232 -104.168254)
			(xy 16.41856 -104.15905) (xy 16.428224 -104.149644) (xy 16.45144 -104.135941) (xy 16.477468 -104.128924)
			(xy 16.49095 -104.12857) (xy 16.49095 -104.128824) (xy 16.797782 -104.128824) (xy 16.812128 -104.130003)
			(xy 16.839243 -104.139633) (xy 16.862475 -104.156611) (xy 16.879884 -104.179522) (xy 16.890018 -104.206454)
			(xy 16.891508 -104.220772) (xy 16.891508 -105.005886) (xy 16.893032 -105.011982) (xy 16.895572 -105.028746)
			(xy 16.895572 -105.955592) (xy 16.89608 -105.955592) (xy 16.89608 -106.074972) (xy 17.408144 -106.074972)
			(xy 17.408144 -105.005632) (xy 17.408815 -104.993239) (xy 17.415467 -104.969334) (xy 17.427757 -104.94778)
			(xy 17.436084 -104.938576) (xy 17.445742 -104.929163) (xy 17.46896 -104.915461) (xy 17.494991 -104.908447)
			(xy 17.508474 -104.908096) (xy 17.815306 -104.908096) (xy 17.829672 -104.909303) (xy 17.856822 -104.918965)
			(xy 17.880071 -104.935993) (xy 17.897472 -104.958964) (xy 17.90757 -104.985955) (xy 17.909032 -105.000298)
			(xy 17.909032 -105.927144) (xy 17.90954 -105.927144) (xy 17.90954 -106.069892) (xy 17.908886 -106.082287)
			(xy 17.902228 -106.106192) (xy 17.88993 -106.127745) (xy 17.8816 -106.136948) (xy 17.871911 -106.146326)
			(xy 17.848707 -106.160036) (xy 17.822688 -106.167066) (xy 17.80921 -106.167428) (xy 17.502378 -106.167428)
			(xy 17.488633 -106.166336) (xy 17.462535 -106.157465) (xy 17.439873 -106.141774) (xy 17.422384 -106.120467)
			(xy 17.411413 -106.09518) (xy 17.40916 -106.081576) (xy 17.408144 -106.074972) (xy 16.89608 -106.074972)
			(xy 16.89608 -106.09834) (xy 16.895387 -106.110731) (xy 16.888744 -106.134634) (xy 16.876463 -106.15619)
			(xy 16.86814 -106.165396) (xy 16.858468 -106.174793) (xy 16.835257 -106.188501) (xy 16.809231 -106.195521)
			(xy 16.79575 -106.195876) (xy 16.488918 -106.195876) (xy 16.475182 -106.194712) (xy 16.449091 -106.185856)
			(xy 16.42643 -106.170182) (xy 16.408939 -106.148892) (xy 16.397959 -106.123622) (xy 16.3957 -106.110024)
			(xy 16.394684 -106.10342) (xy 16.394684 -106.008678) (xy 16.394139 -105.993758) (xy 16.385481 -105.9652)
			(xy 16.368939 -105.940363) (xy 16.345925 -105.921366) (xy 16.318403 -105.909831) (xy 16.288721 -105.906741)
			(xy 16.259414 -105.912361) (xy 16.232981 -105.926212) (xy 16.221964 -105.936288) (xy 16.20046 -105.956629)
			(xy 16.152319 -105.991068) (xy 16.099436 -106.017657) (xy 16.043081 -106.035757) (xy 15.984605 -106.044933)
			(xy 15.95501 -106.045508) (xy 15.954502 -106.045508) (xy 15.927475 -106.045035) (xy 15.873962 -106.037399)
			(xy 15.82206 -106.022294) (xy 15.772807 -106.000022) (xy 15.727187 -105.971027) (xy 15.706344 -105.953814)
			(xy 15.695005 -105.94477) (xy 15.668568 -105.932872) (xy 15.639853 -105.928882) (xy 15.611174 -105.933123)
			(xy 15.584842 -105.945253) (xy 15.56298 -105.964293) (xy 15.54735 -105.988709) (xy 15.539211 -106.016534)
			(xy 15.538704 -106.03103) (xy 15.538704 -106.06786) (xy 15.538042 -106.080255) (xy 15.531389 -106.10416)
			(xy 15.519094 -106.125714) (xy 15.510764 -106.134916) (xy 15.501085 -106.144305) (xy 15.477877 -106.158014)
			(xy 15.451854 -106.165038) (xy 15.438374 -106.165396) (xy 15.131542 -106.165396) (xy 15.117799 -106.16428)
			(xy 15.091699 -106.155421) (xy 15.069033 -106.139737) (xy 15.051544 -106.118434) (xy 15.040574 -106.093148)
			(xy 15.038324 -106.079544) (xy 15.037308 -106.07294) (xy 14.515942 -106.07294) (xy 14.515457 -106.082288)
			(xy 14.508795 -106.106194) (xy 14.496493 -106.127747) (xy 14.48816 -106.136948) (xy 14.478488 -106.146344)
			(xy 14.455276 -106.16005) (xy 14.429251 -106.167072) (xy 14.41577 -106.167428) (xy 14.108938 -106.167428)
			(xy 14.095198 -106.166288) (xy 14.069102 -106.157431) (xy 14.046438 -106.141753) (xy 14.028948 -106.120456)
			(xy 14.017974 -106.095177) (xy 14.01572 -106.081576) (xy 14.014704 -106.074972) (xy 13.036296 -106.074972)
			(xy 13.036296 -106.693208) (xy 13.036804 -106.693208) (xy 13.036804 -106.83621) (xy 13.036115 -106.848602)
			(xy 13.029473 -106.872506) (xy 13.017189 -106.894062) (xy 13.008864 -106.903266) (xy 12.999193 -106.912663)
			(xy 12.97598 -106.926368) (xy 12.949955 -106.933389) (xy 12.936474 -106.933746) (xy 12.936474 -106.933492)
			(xy 12.629642 -106.933492) (xy 12.615917 -106.932417) (xy 12.58985 -106.923584) (xy 12.567202 -106.907946)
			(xy 12.549706 -106.8867) (xy 12.538702 -106.861473) (xy 12.536424 -106.847894) (xy 12.535408 -106.84129)
			(xy 12.535408 -106.746548) (xy 12.53484 -106.731632) (xy 12.526177 -106.703082) (xy 12.509636 -106.678253)
			(xy 12.486627 -106.659262) (xy 12.459112 -106.647728) (xy 12.429438 -106.644636) (xy 12.400136 -106.650249)
			(xy 12.373706 -106.664088) (xy 12.362688 -106.674158) (xy 12.341132 -106.694532) (xy 12.29292 -106.729075)
			(xy 12.239942 -106.75574) (xy 12.183475 -106.773883) (xy 12.124881 -106.783067) (xy 12.095226 -106.783632)
			(xy 12.067449 -106.783097) (xy 12.012487 -106.775007) (xy 11.959278 -106.759036) (xy 11.908945 -106.735524)
			(xy 11.86255 -106.704965) (xy 11.84148 -106.686858) (xy 11.830247 -106.677475) (xy 11.803807 -106.664954)
			(xy 11.7749 -106.660449) (xy 11.745903 -106.66433) (xy 11.719199 -106.676277) (xy 11.696981 -106.69531)
			(xy 11.681075 -106.719864) (xy 11.67279 -106.747922) (xy 11.672316 -106.76255) (xy 11.672316 -106.81462)
			(xy 11.671629 -106.827012) (xy 11.664986 -106.850916) (xy 11.652701 -106.872472) (xy 11.644376 -106.881676)
			(xy 11.634686 -106.891053) (xy 11.611484 -106.904768) (xy 11.585465 -106.911797) (xy 11.571986 -106.912156)
			(xy 11.265154 -106.912156) (xy 11.251419 -106.910979) (xy 11.225326 -106.90213) (xy 11.202664 -106.88646)
			(xy 11.185172 -106.865172) (xy 11.174194 -106.839901) (xy 11.171936 -106.826304) (xy 11.17092 -106.8197)
			(xy 11.17092 -106.011472) (xy 11.170412 -106.007662) (xy 11.170158 -106.00563) (xy 11.169396 -105.999026)
			(xy 2.509012 -105.999026) (xy 2.509012 -107.273852) (xy 14.256512 -107.273852) (xy 14.256512 -106.96702)
			(xy 14.257604 -106.953274) (xy 14.266469 -106.927172) (xy 14.282159 -106.904507) (xy 14.303468 -106.887019)
			(xy 14.328758 -106.876051) (xy 14.342364 -106.873802) (xy 14.348968 -106.87304) (xy 15.418308 -106.87304)
			(xy 15.430685 -106.873696) (xy 15.454577 -106.880252) (xy 15.476144 -106.892445) (xy 15.485364 -106.900726)
			(xy 15.494756 -106.910402) (xy 15.508462 -106.933612) (xy 15.515486 -106.959636) (xy 15.515844 -106.973116)
			(xy 15.515844 -107.273852) (xy 16.415766 -107.273852) (xy 16.41602 -107.273852) (xy 16.41602 -106.96702)
			(xy 16.417148 -106.9533) (xy 16.425963 -106.927234) (xy 16.441587 -106.904584) (xy 16.462823 -106.887086)
			(xy 16.488042 -106.87608) (xy 16.501618 -106.873802) (xy 16.508222 -106.87304) (xy 17.577562 -106.87304)
			(xy 17.589941 -106.873667) (xy 17.613834 -106.880235) (xy 17.635399 -106.89244) (xy 17.644618 -106.900726)
			(xy 17.654003 -106.910409) (xy 17.667713 -106.933615) (xy 17.674739 -106.959637) (xy 17.675098 -106.973116)
			(xy 17.674844 -106.973116) (xy 17.674844 -107.279948) (xy 17.673664 -107.294315) (xy 17.664077 -107.32149)
			(xy 17.647113 -107.344783) (xy 17.624193 -107.362249) (xy 17.597234 -107.372424) (xy 17.582896 -107.373928)
			(xy 16.513302 -107.373928) (xy 16.50092 -107.373329) (xy 16.477026 -107.36675) (xy 16.455462 -107.354533)
			(xy 16.446246 -107.346242) (xy 16.43684 -107.336578) (xy 16.423138 -107.313362) (xy 16.41612 -107.287334)
			(xy 16.415766 -107.273852) (xy 15.515844 -107.273852) (xy 15.515844 -107.279948) (xy 15.514661 -107.294345)
			(xy 15.505072 -107.32158) (xy 15.48806 -107.34491) (xy 15.46506 -107.362367) (xy 15.438014 -107.372478)
			(xy 15.423642 -107.373928) (xy 14.354048 -107.373928) (xy 14.341669 -107.373304) (xy 14.317775 -107.366736)
			(xy 14.29621 -107.354529) (xy 14.286992 -107.346242) (xy 14.277594 -107.336571) (xy 14.263887 -107.313359)
			(xy 14.256867 -107.287333) (xy 14.256512 -107.273852) (xy 2.509012 -107.273852) (xy 2.509012 -108.943971)
			(xy 11.292822 -108.943971) (xy 11.292822 -108.889469) (xy 11.300578 -108.835522) (xy 11.315933 -108.783228)
			(xy 11.338574 -108.733651) (xy 11.36804 -108.687801) (xy 11.403731 -108.646611) (xy 11.444921 -108.61092)
			(xy 11.490771 -108.581454) (xy 11.540348 -108.558813) (xy 11.592642 -108.543458) (xy 11.646589 -108.535702)
			(xy 11.67384 -108.535216) (xy 12.53744 -108.535216) (xy 12.564692 -108.535694) (xy 12.61864 -108.54345)
			(xy 12.670935 -108.558806) (xy 12.720513 -108.581447) (xy 12.766364 -108.610914) (xy 12.807554 -108.646606)
			(xy 12.843246 -108.687796) (xy 12.872713 -108.733647) (xy 12.895354 -108.783225) (xy 12.91071 -108.83552)
			(xy 12.918466 -108.889468) (xy 12.918466 -108.943972) (xy 12.918466 -108.943973) (xy 15.156389 -108.943973)
			(xy 15.156389 -108.889467) (xy 15.164146 -108.835517) (xy 15.179502 -108.783219) (xy 15.202145 -108.733639)
			(xy 15.231613 -108.687786) (xy 15.267307 -108.646594) (xy 15.308499 -108.610901) (xy 15.354353 -108.581433)
			(xy 15.403933 -108.558791) (xy 15.45623 -108.543435) (xy 15.510181 -108.535679) (xy 15.537434 -108.535216)
			(xy 16.401034 -108.535216) (xy 16.428285 -108.535694) (xy 16.482233 -108.543451) (xy 16.534528 -108.558807)
			(xy 16.584105 -108.581448) (xy 16.629956 -108.610915) (xy 16.671146 -108.646607) (xy 16.706837 -108.687798)
			(xy 16.707863 -108.689394) (xy 238.647224 -108.689394) (xy 238.647224 -107.825794) (xy 238.64771 -107.798525)
			(xy 238.655472 -107.744541) (xy 238.670837 -107.692211) (xy 238.693494 -107.642601) (xy 238.72298 -107.59672)
			(xy 238.758695 -107.555503) (xy 238.799912 -107.519788) (xy 238.845793 -107.490302) (xy 238.895403 -107.467645)
			(xy 238.947733 -107.45228) (xy 239.001717 -107.444518) (xy 239.056255 -107.444518) (xy 239.110239 -107.45228)
			(xy 239.162569 -107.467645) (xy 239.212179 -107.490302) (xy 239.25806 -107.519788) (xy 239.299277 -107.555503)
			(xy 239.334992 -107.59672) (xy 239.364478 -107.642601) (xy 239.387135 -107.692211) (xy 239.4025 -107.744541)
			(xy 239.410262 -107.798525) (xy 239.410748 -107.825794) (xy 239.410748 -108.689394) (xy 239.410262 -108.716663)
			(xy 239.4025 -108.770647) (xy 239.387135 -108.822977) (xy 239.364478 -108.872587) (xy 239.334992 -108.918468)
			(xy 239.299277 -108.959685) (xy 239.25806 -108.9954) (xy 239.212179 -109.024886) (xy 239.162569 -109.047543)
			(xy 239.110239 -109.062908) (xy 239.056255 -109.07067) (xy 239.001717 -109.07067) (xy 238.947733 -109.062908)
			(xy 238.895403 -109.047543) (xy 238.845793 -109.024886) (xy 238.799912 -108.9954) (xy 238.758695 -108.959685)
			(xy 238.72298 -108.918468) (xy 238.693494 -108.872587) (xy 238.670837 -108.822977) (xy 238.655472 -108.770647)
			(xy 238.64771 -108.716663) (xy 238.647224 -108.689394) (xy 16.707863 -108.689394) (xy 16.736304 -108.733648)
			(xy 16.758945 -108.783226) (xy 16.7743 -108.835521) (xy 16.782056 -108.889469) (xy 16.782056 -108.943971)
			(xy 16.7743 -108.997919) (xy 16.758945 -109.050214) (xy 16.736304 -109.099792) (xy 16.706837 -109.145642)
			(xy 16.671146 -109.186833) (xy 16.629956 -109.222525) (xy 16.584105 -109.251992) (xy 16.534528 -109.274633)
			(xy 16.482233 -109.289989) (xy 16.428285 -109.297746) (xy 16.401034 -109.298232) (xy 15.537434 -109.298232)
			(xy 15.510181 -109.297761) (xy 15.45623 -109.290005) (xy 15.403933 -109.274649) (xy 15.354353 -109.252007)
			(xy 15.308499 -109.222539) (xy 15.267307 -109.186846) (xy 15.231613 -109.145654) (xy 15.202145 -109.099801)
			(xy 15.179502 -109.050221) (xy 15.164146 -108.997923) (xy 15.156389 -108.943973) (xy 12.918466 -108.943973)
			(xy 12.91071 -108.99792) (xy 12.895354 -109.050215) (xy 12.872713 -109.099793) (xy 12.843246 -109.145644)
			(xy 12.807554 -109.186834) (xy 12.766364 -109.222526) (xy 12.720513 -109.251993) (xy 12.670935 -109.274634)
			(xy 12.61864 -109.28999) (xy 12.564692 -109.297746) (xy 12.53744 -109.298232) (xy 11.67384 -109.298232)
			(xy 11.646589 -109.297738) (xy 11.592642 -109.289982) (xy 11.540348 -109.274627) (xy 11.490771 -109.251986)
			(xy 11.444921 -109.22252) (xy 11.403731 -109.186829) (xy 11.36804 -109.145639) (xy 11.338574 -109.099789)
			(xy 11.315933 -109.050212) (xy 11.300578 -108.997918) (xy 11.292822 -108.943971) (xy 2.509012 -108.943971)
			(xy 2.509012 -109.550266) (xy 250.428546 -109.550266) (xy 250.428546 -109.495734) (xy 250.436306 -109.441757)
			(xy 250.451669 -109.389434) (xy 250.474321 -109.339829) (xy 250.503801 -109.293953) (xy 250.53951 -109.252739)
			(xy 250.580721 -109.217025) (xy 250.626594 -109.18754) (xy 250.676196 -109.164883) (xy 250.728518 -109.149515)
			(xy 250.782494 -109.141749) (xy 250.80976 -109.14126) (xy 251.67336 -109.14126) (xy 251.700634 -109.141677)
			(xy 251.754629 -109.149435) (xy 251.806969 -109.164798) (xy 251.85659 -109.187455) (xy 251.902482 -109.216943)
			(xy 251.943709 -109.252663) (xy 251.979433 -109.293886) (xy 252.008926 -109.339775) (xy 252.031588 -109.389393)
			(xy 252.046957 -109.441732) (xy 252.05472 -109.495726) (xy 252.05472 -109.550274) (xy 252.046957 -109.604268)
			(xy 252.031588 -109.656607) (xy 252.008926 -109.706225) (xy 251.979433 -109.752114) (xy 251.943709 -109.793337)
			(xy 251.902482 -109.829057) (xy 251.85659 -109.858545) (xy 251.806969 -109.881202) (xy 251.754629 -109.896565)
			(xy 251.700634 -109.904323) (xy 251.67336 -109.904784) (xy 250.80976 -109.904784) (xy 250.782494 -109.904251)
			(xy 250.728518 -109.896485) (xy 250.676196 -109.881117) (xy 250.626594 -109.85846) (xy 250.580721 -109.828975)
			(xy 250.53951 -109.793262) (xy 250.503801 -109.752047) (xy 250.474321 -109.706171) (xy 250.451669 -109.656566)
			(xy 250.436306 -109.604243) (xy 250.428546 -109.550266) (xy 2.509012 -109.550266) (xy 2.509012 -111.158274)
			(xy 239.40262 -111.158274) (xy 239.40262 -110.294674) (xy 239.403106 -110.267423) (xy 239.410862 -110.213475)
			(xy 239.426217 -110.16118) (xy 239.448859 -110.111603) (xy 239.478325 -110.065753) (xy 239.514016 -110.024562)
			(xy 239.555207 -109.988871) (xy 239.601057 -109.959405) (xy 239.650634 -109.936763) (xy 239.702929 -109.921408)
			(xy 239.756877 -109.913652) (xy 239.811379 -109.913652) (xy 239.865327 -109.921408) (xy 239.917622 -109.936763)
			(xy 239.967199 -109.959405) (xy 240.000574 -109.980854) (xy 256.88563 -109.980854) (xy 256.88563 -109.926346)
			(xy 256.893387 -109.872392) (xy 256.908744 -109.820091) (xy 256.931388 -109.770508) (xy 256.960857 -109.724652)
			(xy 256.996552 -109.683457) (xy 257.037747 -109.647761) (xy 257.083602 -109.61829) (xy 257.133185 -109.595646)
			(xy 257.185486 -109.580288) (xy 257.23944 -109.57253) (xy 257.266694 -109.572044) (xy 258.130294 -109.572044)
			(xy 258.157544 -109.572603) (xy 258.211488 -109.580358) (xy 258.26378 -109.595712) (xy 258.313355 -109.618351)
			(xy 258.359203 -109.647815) (xy 258.400391 -109.683504) (xy 258.436081 -109.724692) (xy 258.465546 -109.77054)
			(xy 258.488186 -109.820114) (xy 258.503541 -109.872406) (xy 258.511297 -109.92635) (xy 258.511297 -109.98085)
			(xy 258.503541 -110.034794) (xy 258.488186 -110.087086) (xy 258.465546 -110.13666) (xy 258.436081 -110.182508)
			(xy 258.400391 -110.223696) (xy 258.359203 -110.259385) (xy 258.313355 -110.288849) (xy 258.26378 -110.311488)
			(xy 258.211488 -110.326842) (xy 258.157544 -110.334597) (xy 258.130294 -110.33506) (xy 257.266694 -110.33506)
			(xy 257.23944 -110.33467) (xy 257.185486 -110.326912) (xy 257.133185 -110.311554) (xy 257.083602 -110.28891)
			(xy 257.037747 -110.259439) (xy 256.996552 -110.223743) (xy 256.960857 -110.182548) (xy 256.931388 -110.136692)
			(xy 256.908744 -110.087109) (xy 256.893387 -110.034808) (xy 256.88563 -109.980854) (xy 240.000574 -109.980854)
			(xy 240.013049 -109.988871) (xy 240.05424 -110.024562) (xy 240.089931 -110.065753) (xy 240.119397 -110.111603)
			(xy 240.142039 -110.16118) (xy 240.157394 -110.213475) (xy 240.16515 -110.267423) (xy 240.165636 -110.294674)
			(xy 240.165636 -111.158274) (xy 240.16515 -111.185525) (xy 240.157394 -111.239473) (xy 240.142039 -111.291768)
			(xy 240.119397 -111.341345) (xy 240.089931 -111.387195) (xy 240.05424 -111.428386) (xy 240.013049 -111.464077)
			(xy 239.967199 -111.493543) (xy 239.917622 -111.516185) (xy 239.865327 -111.53154) (xy 239.811379 -111.539296)
			(xy 239.756877 -111.539296) (xy 239.702929 -111.53154) (xy 239.650634 -111.516185) (xy 239.601057 -111.493543)
			(xy 239.555207 -111.464077) (xy 239.514016 -111.428386) (xy 239.478325 -111.387195) (xy 239.448859 -111.341345)
			(xy 239.426217 -111.291768) (xy 239.410862 -111.239473) (xy 239.403106 -111.185525) (xy 239.40262 -111.158274)
			(xy 2.509012 -111.158274) (xy 2.509012 -114.734161) (xy 11.255226 -114.734161) (xy 11.255226 -114.679659)
			(xy 11.262982 -114.625711) (xy 11.278337 -114.573416) (xy 11.300979 -114.523839) (xy 11.330445 -114.477988)
			(xy 11.366136 -114.436798) (xy 11.407326 -114.401106) (xy 11.453177 -114.371639) (xy 11.502754 -114.348998)
			(xy 11.555049 -114.333643) (xy 11.608997 -114.325886) (xy 11.636248 -114.3254) (xy 12.499848 -114.3254)
			(xy 12.527101 -114.325867) (xy 12.581052 -114.333624) (xy 12.633349 -114.34898) (xy 12.68293 -114.371622)
			(xy 12.728783 -114.40109) (xy 12.769975 -114.436783) (xy 12.805669 -114.477976) (xy 12.835137 -114.523829)
			(xy 12.85778 -114.573409) (xy 12.873136 -114.625706) (xy 12.880893 -114.679657) (xy 12.880893 -114.734163)
			(xy 12.873136 -114.788114) (xy 12.85778 -114.840411) (xy 12.835137 -114.889991) (xy 12.805669 -114.935844)
			(xy 12.769975 -114.977037) (xy 12.728783 -115.01273) (xy 12.68293 -115.042198) (xy 12.633349 -115.06484)
			(xy 12.581052 -115.080196) (xy 12.527101 -115.087953) (xy 12.499848 -115.088416) (xy 11.636248 -115.088416)
			(xy 11.608997 -115.087934) (xy 11.555049 -115.080177) (xy 11.502754 -115.064822) (xy 11.453177 -115.042181)
			(xy 11.407326 -115.012714) (xy 11.366136 -114.977022) (xy 11.330445 -114.935832) (xy 11.300979 -114.889981)
			(xy 11.278337 -114.840404) (xy 11.262982 -114.788109) (xy 11.255226 -114.734161) (xy 2.509012 -114.734161)
			(xy 2.509012 -116.393573) (xy 230.652992 -116.393573) (xy 230.652992 -116.339027) (xy 230.660755 -116.285035)
			(xy 230.676123 -116.232698) (xy 230.698784 -116.183081) (xy 230.728276 -116.137195) (xy 230.763998 -116.095973)
			(xy 230.805224 -116.060254) (xy 230.851113 -116.030767) (xy 230.900732 -116.008111) (xy 230.95307 -115.992747)
			(xy 231.007063 -115.984989) (xy 231.034336 -115.984528) (xy 231.897936 -115.984528) (xy 231.925203 -115.985037)
			(xy 231.979181 -115.992802) (xy 232.031505 -116.008171) (xy 232.081109 -116.030828) (xy 232.126985 -116.060314)
			(xy 232.168197 -116.096029) (xy 232.203907 -116.137244) (xy 232.233389 -116.183122) (xy 232.256042 -116.232729)
			(xy 232.271405 -116.285054) (xy 232.277026 -116.324151) (xy 236.866903 -116.324151) (xy 236.866903 -116.269649)
			(xy 236.87466 -116.215701) (xy 236.890016 -116.163407) (xy 236.912659 -116.113831) (xy 236.942127 -116.067981)
			(xy 236.97782 -116.026793) (xy 237.019012 -115.991104) (xy 237.064864 -115.961641) (xy 237.114443 -115.939003)
			(xy 237.166739 -115.923652) (xy 237.220687 -115.915901) (xy 237.247938 -115.91544) (xy 238.111538 -115.91544)
			(xy 238.138791 -115.915832) (xy 238.192741 -115.923594) (xy 238.245038 -115.938955) (xy 238.294617 -115.961601)
			(xy 238.340468 -115.991072) (xy 238.381659 -116.026768) (xy 238.417351 -116.067962) (xy 238.446817 -116.113817)
			(xy 238.469459 -116.163398) (xy 238.484814 -116.215696) (xy 238.49257 -116.269647) (xy 238.49257 -116.324153)
			(xy 238.484814 -116.378104) (xy 238.469459 -116.430402) (xy 238.446817 -116.479983) (xy 238.417351 -116.525838)
			(xy 238.381659 -116.567032) (xy 238.340468 -116.602728) (xy 238.294617 -116.632199) (xy 238.245038 -116.654845)
			(xy 238.192741 -116.670206) (xy 238.138791 -116.677968) (xy 238.111538 -116.678456) (xy 237.247938 -116.678456)
			(xy 237.220687 -116.677899) (xy 237.166739 -116.670148) (xy 237.114443 -116.654797) (xy 237.064864 -116.632159)
			(xy 237.019012 -116.602696) (xy 236.97782 -116.567007) (xy 236.942127 -116.525819) (xy 236.912659 -116.479969)
			(xy 236.890016 -116.430393) (xy 236.87466 -116.378099) (xy 236.866903 -116.324151) (xy 232.277026 -116.324151)
			(xy 232.279166 -116.339033) (xy 232.279166 -116.393567) (xy 232.271405 -116.447546) (xy 232.256042 -116.499871)
			(xy 232.233389 -116.549478) (xy 232.203907 -116.595356) (xy 232.168197 -116.636571) (xy 232.126985 -116.672286)
			(xy 232.081109 -116.701772) (xy 232.031505 -116.724429) (xy 231.979181 -116.739798) (xy 231.925203 -116.747563)
			(xy 231.897936 -116.748052) (xy 231.034336 -116.748052) (xy 231.007063 -116.747611) (xy 230.95307 -116.739853)
			(xy 230.900732 -116.724489) (xy 230.851113 -116.701833) (xy 230.805224 -116.672346) (xy 230.763998 -116.636627)
			(xy 230.728276 -116.595405) (xy 230.698784 -116.549519) (xy 230.676123 -116.499902) (xy 230.660755 -116.447565)
			(xy 230.652992 -116.393573) (xy 2.509012 -116.393573) (xy 2.509012 -117.632251) (xy 233.564903 -117.632251)
			(xy 233.564903 -117.577749) (xy 233.57266 -117.523801) (xy 233.588016 -117.471507) (xy 233.610659 -117.421931)
			(xy 233.640127 -117.376081) (xy 233.67582 -117.334893) (xy 233.717012 -117.299204) (xy 233.762864 -117.269741)
			(xy 233.812443 -117.247103) (xy 233.864739 -117.231752) (xy 233.918687 -117.224001) (xy 233.945938 -117.22354)
			(xy 234.809538 -117.22354) (xy 234.836791 -117.223932) (xy 234.890741 -117.231694) (xy 234.943038 -117.247055)
			(xy 234.992617 -117.269701) (xy 235.038468 -117.299172) (xy 235.079659 -117.334868) (xy 235.115351 -117.376062)
			(xy 235.144817 -117.421917) (xy 235.167459 -117.471498) (xy 235.182814 -117.523796) (xy 235.19057 -117.577747)
			(xy 235.19057 -117.632251) (xy 238.898903 -117.632251) (xy 238.898903 -117.577749) (xy 238.90666 -117.523801)
			(xy 238.922016 -117.471507) (xy 238.944659 -117.421931) (xy 238.974127 -117.376081) (xy 239.00982 -117.334893)
			(xy 239.051012 -117.299204) (xy 239.096864 -117.269741) (xy 239.146443 -117.247103) (xy 239.198739 -117.231752)
			(xy 239.252687 -117.224001) (xy 239.279938 -117.22354) (xy 240.143538 -117.22354) (xy 240.170791 -117.223932)
			(xy 240.224741 -117.231694) (xy 240.277038 -117.247055) (xy 240.326617 -117.269701) (xy 240.372468 -117.299172)
			(xy 240.413659 -117.334868) (xy 240.449351 -117.376062) (xy 240.478817 -117.421917) (xy 240.501459 -117.471498)
			(xy 240.516814 -117.523796) (xy 240.52457 -117.577747) (xy 240.52457 -117.632253) (xy 240.516814 -117.686204)
			(xy 240.501459 -117.738502) (xy 240.478817 -117.788083) (xy 240.449351 -117.833938) (xy 240.413659 -117.875132)
			(xy 240.372468 -117.910828) (xy 240.326617 -117.940299) (xy 240.277038 -117.962945) (xy 240.224741 -117.978306)
			(xy 240.170791 -117.986068) (xy 240.143538 -117.986556) (xy 239.279938 -117.986556) (xy 239.252687 -117.985999)
			(xy 239.198739 -117.978248) (xy 239.146443 -117.962897) (xy 239.096864 -117.940259) (xy 239.051012 -117.910796)
			(xy 239.00982 -117.875107) (xy 238.974127 -117.833919) (xy 238.944659 -117.788069) (xy 238.922016 -117.738493)
			(xy 238.90666 -117.686199) (xy 238.898903 -117.632251) (xy 235.19057 -117.632251) (xy 235.19057 -117.632253)
			(xy 235.182814 -117.686204) (xy 235.167459 -117.738502) (xy 235.144817 -117.788083) (xy 235.115351 -117.833938)
			(xy 235.079659 -117.875132) (xy 235.038468 -117.910828) (xy 234.992617 -117.940299) (xy 234.943038 -117.962945)
			(xy 234.890741 -117.978306) (xy 234.836791 -117.986068) (xy 234.809538 -117.986556) (xy 233.945938 -117.986556)
			(xy 233.918687 -117.985999) (xy 233.864739 -117.978248) (xy 233.812443 -117.962897) (xy 233.762864 -117.940259)
			(xy 233.717012 -117.910796) (xy 233.67582 -117.875107) (xy 233.640127 -117.833919) (xy 233.610659 -117.788069)
			(xy 233.588016 -117.738493) (xy 233.57266 -117.686199) (xy 233.564903 -117.632251) (xy 2.509012 -117.632251)
			(xy 2.509012 -123.093988) (xy 227.217732 -123.093988) (xy 227.217732 -122.230388) (xy 227.218218 -122.203137)
			(xy 227.225974 -122.149189) (xy 227.241329 -122.096894) (xy 227.263971 -122.047317) (xy 227.293437 -122.001467)
			(xy 227.329128 -121.960276) (xy 227.370319 -121.924585) (xy 227.416169 -121.895119) (xy 227.465746 -121.872477)
			(xy 227.518041 -121.857122) (xy 227.571989 -121.849366) (xy 227.626491 -121.849366) (xy 227.680439 -121.857122)
			(xy 227.732734 -121.872477) (xy 227.782311 -121.895119) (xy 227.828161 -121.924585) (xy 227.869352 -121.960276)
			(xy 227.905043 -122.001467) (xy 227.934509 -122.047317) (xy 227.957151 -122.096894) (xy 227.972506 -122.149189)
			(xy 227.980262 -122.203137) (xy 227.980748 -122.230388) (xy 227.980748 -122.921014) (xy 245.563136 -122.921014)
			(xy 245.563136 -122.057414) (xy 245.563622 -122.030163) (xy 245.571378 -121.976215) (xy 245.586733 -121.92392)
			(xy 245.609375 -121.874343) (xy 245.638841 -121.828493) (xy 245.674532 -121.787302) (xy 245.715723 -121.751611)
			(xy 245.761573 -121.722145) (xy 245.81115 -121.699503) (xy 245.863445 -121.684148) (xy 245.917393 -121.676392)
			(xy 245.971895 -121.676392) (xy 246.025843 -121.684148) (xy 246.078138 -121.699503) (xy 246.127715 -121.722145)
			(xy 246.173565 -121.751611) (xy 246.214756 -121.787302) (xy 246.250447 -121.828493) (xy 246.279913 -121.874343)
			(xy 246.302555 -121.92392) (xy 246.31791 -121.976215) (xy 246.325666 -122.030163) (xy 246.326152 -122.057414)
			(xy 246.326152 -122.921014) (xy 246.325666 -122.948265) (xy 246.31791 -123.002213) (xy 246.302555 -123.054508)
			(xy 246.279913 -123.104085) (xy 246.250447 -123.149935) (xy 246.214756 -123.191126) (xy 246.173565 -123.226817)
			(xy 246.127715 -123.256283) (xy 246.078138 -123.278925) (xy 246.025843 -123.29428) (xy 245.971895 -123.302036)
			(xy 245.917393 -123.302036) (xy 245.863445 -123.29428) (xy 245.81115 -123.278925) (xy 245.761573 -123.256283)
			(xy 245.715723 -123.226817) (xy 245.674532 -123.191126) (xy 245.638841 -123.149935) (xy 245.609375 -123.104085)
			(xy 245.586733 -123.054508) (xy 245.571378 -123.002213) (xy 245.563622 -122.948265) (xy 245.563136 -122.921014)
			(xy 227.980748 -122.921014) (xy 227.980748 -123.093988) (xy 227.980262 -123.121239) (xy 227.972506 -123.175187)
			(xy 227.957151 -123.227482) (xy 227.934509 -123.277059) (xy 227.905043 -123.322909) (xy 227.869352 -123.3641)
			(xy 227.828161 -123.399791) (xy 227.782311 -123.429257) (xy 227.732734 -123.451899) (xy 227.680439 -123.467254)
			(xy 227.626491 -123.47501) (xy 227.571989 -123.47501) (xy 227.518041 -123.467254) (xy 227.465746 -123.451899)
			(xy 227.416169 -123.429257) (xy 227.370319 -123.399791) (xy 227.329128 -123.3641) (xy 227.293437 -123.322909)
			(xy 227.263971 -123.277059) (xy 227.241329 -123.227482) (xy 227.225974 -123.175187) (xy 227.218218 -123.121239)
			(xy 227.217732 -123.093988) (xy 2.509012 -123.093988) (xy 2.509012 -125.221746) (xy 225.535744 -125.221746)
			(xy 225.535744 -124.358146) (xy 225.53623 -124.330877) (xy 225.543992 -124.276893) (xy 225.559357 -124.224563)
			(xy 225.582014 -124.174953) (xy 225.6115 -124.129072) (xy 225.647215 -124.087855) (xy 225.688432 -124.05214)
			(xy 225.734313 -124.022654) (xy 225.783923 -123.999997) (xy 225.836253 -123.984632) (xy 225.890237 -123.97687)
			(xy 225.944775 -123.97687) (xy 225.998759 -123.984632) (xy 226.051089 -123.999997) (xy 226.100699 -124.022654)
			(xy 226.14658 -124.05214) (xy 226.187797 -124.087855) (xy 226.223512 -124.129072) (xy 226.252998 -124.174953)
			(xy 226.275655 -124.224563) (xy 226.29102 -124.276893) (xy 226.298782 -124.330877) (xy 226.299268 -124.358146)
			(xy 226.299268 -125.221746) (xy 226.298782 -125.249015) (xy 226.29102 -125.302999) (xy 226.275655 -125.355329)
			(xy 226.252998 -125.404939) (xy 226.223512 -125.45082) (xy 226.187797 -125.492037) (xy 226.14658 -125.527752)
			(xy 226.100699 -125.557238) (xy 226.051089 -125.579895) (xy 225.998759 -125.59526) (xy 225.944775 -125.603022)
			(xy 225.890237 -125.603022) (xy 225.836253 -125.59526) (xy 225.783923 -125.579895) (xy 225.734313 -125.557238)
			(xy 225.688432 -125.527752) (xy 225.647215 -125.492037) (xy 225.6115 -125.45082) (xy 225.582014 -125.404939)
			(xy 225.559357 -125.355329) (xy 225.543992 -125.302999) (xy 225.53623 -125.249015) (xy 225.535744 -125.221746)
			(xy 2.509012 -125.221746) (xy 2.509012 -127.325628) (xy 227.034852 -127.325628) (xy 227.034852 -126.462028)
			(xy 227.035338 -126.434777) (xy 227.043094 -126.380829) (xy 227.058449 -126.328534) (xy 227.081091 -126.278957)
			(xy 227.110557 -126.233107) (xy 227.146248 -126.191916) (xy 227.187439 -126.156225) (xy 227.233289 -126.126759)
			(xy 227.282866 -126.104117) (xy 227.335161 -126.088762) (xy 227.389109 -126.081006) (xy 227.443611 -126.081006)
			(xy 227.497559 -126.088762) (xy 227.549854 -126.104117) (xy 227.599431 -126.126759) (xy 227.645281 -126.156225)
			(xy 227.686472 -126.191916) (xy 227.722163 -126.233107) (xy 227.751629 -126.278957) (xy 227.774271 -126.328534)
			(xy 227.789626 -126.380829) (xy 227.797382 -126.434777) (xy 227.797868 -126.462028) (xy 227.797868 -127.140208)
			(xy 242.041172 -127.140208) (xy 242.041172 -126.276608) (xy 242.041658 -126.249357) (xy 242.049414 -126.195409)
			(xy 242.064769 -126.143114) (xy 242.087411 -126.093537) (xy 242.116877 -126.047687) (xy 242.152568 -126.006496)
			(xy 242.193759 -125.970805) (xy 242.239609 -125.941339) (xy 242.289186 -125.918697) (xy 242.341481 -125.903342)
			(xy 242.395429 -125.895586) (xy 242.449931 -125.895586) (xy 242.503879 -125.903342) (xy 242.556174 -125.918697)
			(xy 242.605751 -125.941339) (xy 242.651601 -125.970805) (xy 242.692792 -126.006496) (xy 242.728483 -126.047687)
			(xy 242.757949 -126.093537) (xy 242.780591 -126.143114) (xy 242.795946 -126.195409) (xy 242.803702 -126.249357)
			(xy 242.804188 -126.276608) (xy 242.804188 -127.140208) (xy 242.803702 -127.167459) (xy 242.795946 -127.221407)
			(xy 242.780591 -127.273702) (xy 242.757949 -127.323279) (xy 242.728483 -127.369129) (xy 242.692792 -127.41032)
			(xy 242.651601 -127.446011) (xy 242.605751 -127.475477) (xy 242.556174 -127.498119) (xy 242.503879 -127.513474)
			(xy 242.449931 -127.52123) (xy 242.395429 -127.52123) (xy 242.341481 -127.513474) (xy 242.289186 -127.498119)
			(xy 242.239609 -127.475477) (xy 242.193759 -127.446011) (xy 242.152568 -127.41032) (xy 242.116877 -127.369129)
			(xy 242.087411 -127.323279) (xy 242.064769 -127.273702) (xy 242.049414 -127.221407) (xy 242.041658 -127.167459)
			(xy 242.041172 -127.140208) (xy 227.797868 -127.140208) (xy 227.797868 -127.325628) (xy 227.797382 -127.352879)
			(xy 227.789626 -127.406827) (xy 227.774271 -127.459122) (xy 227.751629 -127.508699) (xy 227.722163 -127.554549)
			(xy 227.686472 -127.59574) (xy 227.645281 -127.631431) (xy 227.599431 -127.660897) (xy 227.549854 -127.683539)
			(xy 227.519478 -127.692458) (xy 458.401155 -127.692458) (xy 458.401155 -127.563318) (xy 458.409105 -127.434423)
			(xy 458.424975 -127.306263) (xy 458.448704 -127.179322) (xy 458.480203 -127.054083) (xy 458.519352 -126.93102)
			(xy 458.566003 -126.810601) (xy 458.619978 -126.693282) (xy 458.681073 -126.579508) (xy 458.749056 -126.469711)
			(xy 458.82367 -126.364308) (xy 458.904631 -126.263698) (xy 458.991631 -126.168263) (xy 459.084342 -126.078364)
			(xy 459.182412 -125.994343) (xy 459.285467 -125.916519) (xy 459.393118 -125.845187) (xy 459.504957 -125.780617)
			(xy 459.620558 -125.723055) (xy 459.739483 -125.672718) (xy 459.861282 -125.629798) (xy 459.985492 -125.594457)
			(xy 460.111641 -125.56683) (xy 460.239253 -125.547021) (xy 460.367842 -125.535105) (xy 460.49692 -125.531129)
			(xy 460.625998 -125.535105) (xy 460.754587 -125.547021) (xy 460.882199 -125.56683) (xy 461.008348 -125.594457)
			(xy 461.132558 -125.629798) (xy 461.254357 -125.672718) (xy 461.373282 -125.723055) (xy 461.488883 -125.780617)
			(xy 461.600722 -125.845187) (xy 461.708373 -125.916519) (xy 461.811428 -125.994343) (xy 461.909498 -126.078364)
			(xy 462.002209 -126.168263) (xy 462.089209 -126.263698) (xy 462.17017 -126.364308) (xy 462.244784 -126.469711)
			(xy 462.312767 -126.579508) (xy 462.373862 -126.693282) (xy 462.427837 -126.810601) (xy 462.474488 -126.93102)
			(xy 462.513637 -127.054083) (xy 462.545136 -127.179322) (xy 462.568865 -127.306263) (xy 462.584735 -127.434423)
			(xy 462.592685 -127.563318) (xy 462.593182 -127.627888) (xy 462.592685 -127.692458) (xy 462.584735 -127.821353)
			(xy 462.568865 -127.949513) (xy 462.545136 -128.076454) (xy 462.513637 -128.201693) (xy 462.474488 -128.324756)
			(xy 462.427837 -128.445175) (xy 462.373862 -128.562494) (xy 462.312767 -128.676268) (xy 462.244784 -128.786065)
			(xy 462.17017 -128.891468) (xy 462.089209 -128.992078) (xy 462.002209 -129.087513) (xy 461.909498 -129.177412)
			(xy 461.811428 -129.261433) (xy 461.708373 -129.339257) (xy 461.600722 -129.410589) (xy 461.488883 -129.475159)
			(xy 461.373282 -129.532721) (xy 461.254357 -129.583058) (xy 461.132558 -129.625978) (xy 461.008348 -129.661319)
			(xy 460.882199 -129.688946) (xy 460.754587 -129.708755) (xy 460.625998 -129.720671) (xy 460.49692 -129.724648)
			(xy 460.367842 -129.720671) (xy 460.239253 -129.708755) (xy 460.111641 -129.688946) (xy 459.985492 -129.661319)
			(xy 459.861282 -129.625978) (xy 459.739483 -129.583058) (xy 459.620558 -129.532721) (xy 459.504957 -129.475159)
			(xy 459.393118 -129.410589) (xy 459.285467 -129.339257) (xy 459.182412 -129.261433) (xy 459.084342 -129.177412)
			(xy 458.991631 -129.087513) (xy 458.904631 -128.992078) (xy 458.82367 -128.891468) (xy 458.749056 -128.786065)
			(xy 458.681073 -128.676268) (xy 458.619978 -128.562494) (xy 458.566003 -128.445175) (xy 458.519352 -128.324756)
			(xy 458.480203 -128.201693) (xy 458.448704 -128.076454) (xy 458.424975 -127.949513) (xy 458.409105 -127.821353)
			(xy 458.401155 -127.692458) (xy 227.519478 -127.692458) (xy 227.497559 -127.698894) (xy 227.443611 -127.70665)
			(xy 227.389109 -127.70665) (xy 227.335161 -127.698894) (xy 227.282866 -127.683539) (xy 227.233289 -127.660897)
			(xy 227.187439 -127.631431) (xy 227.146248 -127.59574) (xy 227.110557 -127.554549) (xy 227.081091 -127.508699)
			(xy 227.058449 -127.459122) (xy 227.043094 -127.406827) (xy 227.035338 -127.352879) (xy 227.034852 -127.325628)
			(xy 2.509012 -127.325628) (xy 2.509012 -129.073148) (xy 223.562672 -129.073148) (xy 223.562672 -128.209548)
			(xy 223.563115 -128.182788) (xy 223.570596 -128.129795) (xy 223.585403 -128.078365) (xy 223.607247 -128.029506)
			(xy 223.621092 -128.006602) (xy 223.636032 -127.983032) (xy 223.671662 -127.940084) (xy 223.713174 -127.902792)
			(xy 223.759681 -127.871951) (xy 223.810187 -127.848221) (xy 223.863614 -127.832109) (xy 223.918819 -127.823961)
			(xy 223.94672 -127.823468) (xy 223.973934 -127.823967) (xy 224.027808 -127.831715) (xy 224.080031 -127.84705)
			(xy 224.12954 -127.869661) (xy 224.175327 -127.899088) (xy 224.216462 -127.93473) (xy 224.252105 -127.975863)
			(xy 224.281533 -128.02165) (xy 224.304145 -128.071158) (xy 224.319483 -128.123381) (xy 224.327232 -128.177254)
			(xy 224.32772 -128.204468) (xy 224.32772 -128.204722) (xy 224.325942 -128.241552) (xy 224.325688 -128.243838)
			(xy 224.325688 -129.019808) (xy 240.086896 -129.019808) (xy 240.086896 -128.156208) (xy 240.087382 -128.128939)
			(xy 240.095144 -128.074955) (xy 240.110509 -128.022625) (xy 240.133166 -127.973015) (xy 240.162652 -127.927134)
			(xy 240.198367 -127.885917) (xy 240.239584 -127.850202) (xy 240.285465 -127.820716) (xy 240.335075 -127.798059)
			(xy 240.387405 -127.782694) (xy 240.441389 -127.774932) (xy 240.495927 -127.774932) (xy 240.549911 -127.782694)
			(xy 240.602241 -127.798059) (xy 240.651851 -127.820716) (xy 240.697732 -127.850202) (xy 240.738949 -127.885917)
			(xy 240.774664 -127.927134) (xy 240.80415 -127.973015) (xy 240.826807 -128.022625) (xy 240.842172 -128.074955)
			(xy 240.849934 -128.128939) (xy 240.85042 -128.156208) (xy 240.85042 -129.019808) (xy 240.849934 -129.047077)
			(xy 240.842172 -129.101061) (xy 240.826807 -129.153391) (xy 240.80415 -129.203001) (xy 240.774664 -129.248882)
			(xy 240.738949 -129.290099) (xy 240.697732 -129.325814) (xy 240.651851 -129.3553) (xy 240.602241 -129.377957)
			(xy 240.549911 -129.393322) (xy 240.495927 -129.401084) (xy 240.441389 -129.401084) (xy 240.387405 -129.393322)
			(xy 240.335075 -129.377957) (xy 240.285465 -129.3553) (xy 240.239584 -129.325814) (xy 240.198367 -129.290099)
			(xy 240.162652 -129.248882) (xy 240.133166 -129.203001) (xy 240.110509 -129.153391) (xy 240.095144 -129.101061)
			(xy 240.087382 -129.047077) (xy 240.086896 -129.019808) (xy 224.325688 -129.019808) (xy 224.325942 -129.022602)
			(xy 224.327226 -129.033861) (xy 224.328622 -129.056482) (xy 224.328736 -129.067814) (xy 224.328736 -129.068068)
			(xy 224.328226 -129.095352) (xy 224.320425 -129.14936) (xy 224.305035 -129.201713) (xy 224.282367 -129.251351)
			(xy 224.26803 -129.27457) (xy 224.253042 -129.297814) (xy 224.217376 -129.340083) (xy 224.175977 -129.376756)
			(xy 224.129714 -129.407061) (xy 224.079557 -129.430365) (xy 224.026559 -129.446176) (xy 223.971833 -129.454165)
			(xy 223.94418 -129.454656) (xy 223.91693 -129.454141) (xy 223.862986 -129.446383) (xy 223.810695 -129.431028)
			(xy 223.761121 -129.408388) (xy 223.715273 -129.378924) (xy 223.674084 -129.343236) (xy 223.638393 -129.30205)
			(xy 223.608926 -129.256204) (xy 223.586282 -129.206631) (xy 223.570923 -129.154341) (xy 223.563161 -129.100398)
			(xy 223.562672 -129.073148) (xy 2.509012 -129.073148) (xy 2.509012 -131.09702) (xy 228.682804 -131.09702)
			(xy 228.682804 -130.23342) (xy 228.68329 -130.206151) (xy 228.691052 -130.152167) (xy 228.706417 -130.099837)
			(xy 228.729074 -130.050227) (xy 228.75856 -130.004346) (xy 228.794275 -129.963129) (xy 228.835492 -129.927414)
			(xy 228.881373 -129.897928) (xy 228.930983 -129.875271) (xy 228.983313 -129.859906) (xy 229.037297 -129.852144)
			(xy 229.091835 -129.852144) (xy 229.145819 -129.859906) (xy 229.198149 -129.875271) (xy 229.247759 -129.897928)
			(xy 229.29364 -129.927414) (xy 229.334857 -129.963129) (xy 229.370572 -130.004346) (xy 229.400058 -130.050227)
			(xy 229.422715 -130.099837) (xy 229.43808 -130.152167) (xy 229.445842 -130.206151) (xy 229.446328 -130.23342)
			(xy 229.446328 -130.721608) (xy 242.041172 -130.721608) (xy 242.041172 -129.858008) (xy 242.041658 -129.830757)
			(xy 242.049414 -129.776809) (xy 242.064769 -129.724514) (xy 242.087411 -129.674937) (xy 242.116877 -129.629087)
			(xy 242.152568 -129.587896) (xy 242.193759 -129.552205) (xy 242.239609 -129.522739) (xy 242.289186 -129.500097)
			(xy 242.341481 -129.484742) (xy 242.395429 -129.476986) (xy 242.449931 -129.476986) (xy 242.503879 -129.484742)
			(xy 242.556174 -129.500097) (xy 242.605751 -129.522739) (xy 242.651601 -129.552205) (xy 242.692792 -129.587896)
			(xy 242.728483 -129.629087) (xy 242.757949 -129.674937) (xy 242.780591 -129.724514) (xy 242.795946 -129.776809)
			(xy 242.803702 -129.830757) (xy 242.804188 -129.858008) (xy 242.804188 -130.721608) (xy 242.803702 -130.748859)
			(xy 242.795946 -130.802807) (xy 242.780591 -130.855102) (xy 242.757949 -130.904679) (xy 242.728483 -130.950529)
			(xy 242.692792 -130.99172) (xy 242.651601 -131.027411) (xy 242.605751 -131.056877) (xy 242.556174 -131.079519)
			(xy 242.503879 -131.094874) (xy 242.449931 -131.10263) (xy 242.395429 -131.10263) (xy 242.341481 -131.094874)
			(xy 242.289186 -131.079519) (xy 242.239609 -131.056877) (xy 242.193759 -131.027411) (xy 242.152568 -130.99172)
			(xy 242.116877 -130.950529) (xy 242.087411 -130.904679) (xy 242.064769 -130.855102) (xy 242.049414 -130.802807)
			(xy 242.041658 -130.748859) (xy 242.041172 -130.721608) (xy 229.446328 -130.721608) (xy 229.446328 -131.09702)
			(xy 229.445842 -131.124289) (xy 229.43808 -131.178273) (xy 229.422715 -131.230603) (xy 229.400058 -131.280213)
			(xy 229.370572 -131.326094) (xy 229.334857 -131.367311) (xy 229.29364 -131.403026) (xy 229.247759 -131.432512)
			(xy 229.198149 -131.455169) (xy 229.145819 -131.470534) (xy 229.091835 -131.478296) (xy 229.037297 -131.478296)
			(xy 228.983313 -131.470534) (xy 228.930983 -131.455169) (xy 228.881373 -131.432512) (xy 228.835492 -131.403026)
			(xy 228.794275 -131.367311) (xy 228.75856 -131.326094) (xy 228.729074 -131.280213) (xy 228.706417 -131.230603)
			(xy 228.691052 -131.178273) (xy 228.68329 -131.124289) (xy 228.682804 -131.09702) (xy 2.509012 -131.09702)
			(xy 2.509012 -132.529347) (xy 231.621126 -132.529347) (xy 231.621126 -132.474853) (xy 231.628881 -132.420915)
			(xy 231.644233 -132.368628) (xy 231.666869 -132.319059) (xy 231.69633 -132.273216) (xy 231.732014 -132.232031)
			(xy 231.773196 -132.196344) (xy 231.819038 -132.166881) (xy 231.868606 -132.144241) (xy 231.920891 -132.128886)
			(xy 231.974829 -132.121128) (xy 232.002076 -132.12064) (xy 232.865676 -132.12064) (xy 232.892933 -132.121005)
			(xy 232.946894 -132.128761) (xy 232.999201 -132.144116) (xy 233.048791 -132.16676) (xy 233.094653 -132.196231)
			(xy 233.135853 -132.23193) (xy 233.171554 -132.273128) (xy 233.201028 -132.318988) (xy 233.223675 -132.368576)
			(xy 233.239034 -132.420883) (xy 233.246793 -132.474843) (xy 233.246793 -132.529357) (xy 233.239034 -132.583317)
			(xy 233.223675 -132.635624) (xy 233.201028 -132.685212) (xy 233.171554 -132.731072) (xy 233.135853 -132.77227)
			(xy 233.094653 -132.807968) (xy 233.048791 -132.83744) (xy 232.999201 -132.860084) (xy 232.946894 -132.875439)
			(xy 232.892933 -132.883195) (xy 232.865676 -132.883656) (xy 232.002076 -132.883656) (xy 231.974829 -132.883072)
			(xy 231.920891 -132.875314) (xy 231.868606 -132.859959) (xy 231.819038 -132.837319) (xy 231.773196 -132.807856)
			(xy 231.732014 -132.772169) (xy 231.69633 -132.730984) (xy 231.666869 -132.685141) (xy 231.644233 -132.635572)
			(xy 231.628881 -132.583285) (xy 231.621126 -132.529347) (xy 2.509012 -132.529347) (xy 2.509012 -135.31065)
			(xy 225.204003 -135.31065) (xy 225.204003 -135.25615) (xy 225.21176 -135.202204) (xy 225.227115 -135.149911)
			(xy 225.249756 -135.100336) (xy 225.279222 -135.054487) (xy 225.314914 -135.013299) (xy 225.356103 -134.97761)
			(xy 225.401953 -134.948146) (xy 225.45153 -134.925508) (xy 225.503823 -134.910156) (xy 225.55777 -134.902402)
			(xy 225.58502 -134.90194) (xy 226.44862 -134.90194) (xy 226.475874 -134.902331) (xy 226.529826 -134.910091)
			(xy 226.582125 -134.92545) (xy 226.631706 -134.948095) (xy 226.67756 -134.977566) (xy 226.718753 -135.013262)
			(xy 226.754446 -135.054456) (xy 226.755856 -135.05665) (xy 228.531403 -135.05665) (xy 228.531403 -135.00215)
			(xy 228.53916 -134.948204) (xy 228.554515 -134.895911) (xy 228.577156 -134.846336) (xy 228.606622 -134.800487)
			(xy 228.642314 -134.759299) (xy 228.683503 -134.72361) (xy 228.729353 -134.694146) (xy 228.77893 -134.671508)
			(xy 228.831223 -134.656156) (xy 228.88517 -134.648402) (xy 228.91242 -134.64794) (xy 229.77602 -134.64794)
			(xy 229.803274 -134.648331) (xy 229.857226 -134.656091) (xy 229.909525 -134.67145) (xy 229.959106 -134.694095)
			(xy 230.00496 -134.723566) (xy 230.046153 -134.759262) (xy 230.081846 -134.800456) (xy 230.111315 -134.846312)
			(xy 230.133957 -134.895894) (xy 230.149313 -134.948193) (xy 230.15707 -135.002146) (xy 230.15707 -135.056654)
			(xy 230.149313 -135.110607) (xy 230.145996 -135.121904) (xy 234.029504 -135.121904) (xy 234.029504 -134.258304)
			(xy 234.02999 -134.231035) (xy 234.037752 -134.177051) (xy 234.053117 -134.124721) (xy 234.075774 -134.075111)
			(xy 234.10526 -134.02923) (xy 234.140975 -133.988013) (xy 234.182192 -133.952298) (xy 234.228073 -133.922812)
			(xy 234.277683 -133.900155) (xy 234.330013 -133.88479) (xy 234.383997 -133.877028) (xy 234.438535 -133.877028)
			(xy 234.492519 -133.88479) (xy 234.544849 -133.900155) (xy 234.594459 -133.922812) (xy 234.64034 -133.952298)
			(xy 234.681557 -133.988013) (xy 234.717272 -134.02923) (xy 234.746758 -134.075111) (xy 234.769415 -134.124721)
			(xy 234.78478 -134.177051) (xy 234.792542 -134.231035) (xy 234.793028 -134.258304) (xy 234.793028 -134.768971)
			(xy 236.02439 -134.768971) (xy 236.02439 -134.714429) (xy 236.032152 -134.660443) (xy 236.047518 -134.608111)
			(xy 236.070174 -134.558498) (xy 236.09966 -134.512615) (xy 236.135376 -134.471394) (xy 236.176594 -134.435676)
			(xy 236.222475 -134.406186) (xy 236.272087 -134.383527) (xy 236.324418 -134.368158) (xy 236.378403 -134.360392)
			(xy 236.405674 -134.359904) (xy 237.178342 -134.359904) (xy 237.205607 -134.360461) (xy 237.259581 -134.368227)
			(xy 237.311901 -134.383595) (xy 237.361502 -134.406251) (xy 237.407373 -134.435736) (xy 237.448582 -134.471448)
			(xy 237.48429 -134.512661) (xy 237.513769 -134.558535) (xy 237.53642 -134.608138) (xy 237.551782 -134.66046)
			(xy 237.559542 -134.714435) (xy 237.559542 -134.768965) (xy 237.551782 -134.82294) (xy 237.53642 -134.875262)
			(xy 237.513769 -134.924865) (xy 237.48429 -134.970739) (xy 237.448582 -135.011952) (xy 237.407373 -135.047664)
			(xy 237.361502 -135.077149) (xy 237.311901 -135.099805) (xy 237.259581 -135.115173) (xy 237.205607 -135.122939)
			(xy 237.178342 -135.123428) (xy 236.405674 -135.123428) (xy 236.378403 -135.123008) (xy 236.324418 -135.115242)
			(xy 236.272087 -135.099873) (xy 236.222475 -135.077214) (xy 236.176594 -135.047724) (xy 236.135376 -135.012006)
			(xy 236.09966 -134.970785) (xy 236.070174 -134.924902) (xy 236.047518 -134.875289) (xy 236.032152 -134.822957)
			(xy 236.02439 -134.768971) (xy 234.793028 -134.768971) (xy 234.793028 -135.121904) (xy 234.792542 -135.149173)
			(xy 234.786383 -135.192008) (xy 238.645192 -135.192008) (xy 238.645192 -134.328408) (xy 238.645678 -134.301157)
			(xy 238.653434 -134.247209) (xy 238.668789 -134.194914) (xy 238.691431 -134.145337) (xy 238.720897 -134.099487)
			(xy 238.756588 -134.058296) (xy 238.797779 -134.022605) (xy 238.843629 -133.993139) (xy 238.893206 -133.970497)
			(xy 238.945501 -133.955142) (xy 238.999449 -133.947386) (xy 239.053951 -133.947386) (xy 239.107899 -133.955142)
			(xy 239.160194 -133.970497) (xy 239.209771 -133.993139) (xy 239.255621 -134.022605) (xy 239.271831 -134.036651)
			(xy 242.034062 -134.036651) (xy 242.034062 -133.982149) (xy 242.041817 -133.928203) (xy 242.057171 -133.875909)
			(xy 242.07981 -133.826333) (xy 242.109274 -133.780482) (xy 242.144963 -133.739291) (xy 242.18615 -133.703598)
			(xy 242.231997 -133.67413) (xy 242.281572 -133.651485) (xy 242.333864 -133.636126) (xy 242.387809 -133.628365)
			(xy 242.41506 -133.627876) (xy 243.27866 -133.627876) (xy 243.305914 -133.628369) (xy 243.359867 -133.636121)
			(xy 243.412167 -133.651473) (xy 243.46175 -133.674112) (xy 243.507606 -133.703577) (xy 243.548802 -133.73927)
			(xy 243.584499 -133.780462) (xy 243.613969 -133.826315) (xy 243.636613 -133.875895) (xy 243.651971 -133.928194)
			(xy 243.659729 -133.982146) (xy 243.659729 -134.036654) (xy 243.651971 -134.090606) (xy 243.636613 -134.142905)
			(xy 243.613969 -134.192485) (xy 243.584499 -134.238338) (xy 243.548802 -134.27953) (xy 243.507606 -134.315223)
			(xy 243.46175 -134.344688) (xy 243.412167 -134.367327) (xy 243.359867 -134.382679) (xy 243.305914 -134.390431)
			(xy 243.27866 -134.390892) (xy 242.41506 -134.390892) (xy 242.387809 -134.390435) (xy 242.333864 -134.382674)
			(xy 242.281572 -134.367315) (xy 242.231997 -134.34467) (xy 242.18615 -134.315202) (xy 242.144963 -134.279509)
			(xy 242.109274 -134.238318) (xy 242.07981 -134.192467) (xy 242.057171 -134.142891) (xy 242.041817 -134.090597)
			(xy 242.034062 -134.036651) (xy 239.271831 -134.036651) (xy 239.296812 -134.058296) (xy 239.332503 -134.099487)
			(xy 239.361969 -134.145337) (xy 239.384611 -134.194914) (xy 239.399966 -134.247209) (xy 239.407722 -134.301157)
			(xy 239.408208 -134.328408) (xy 239.408208 -135.192008) (xy 239.407722 -135.219259) (xy 239.399966 -135.273207)
			(xy 239.384611 -135.325502) (xy 239.361969 -135.375079) (xy 239.332503 -135.420929) (xy 239.296812 -135.46212)
			(xy 239.255621 -135.497811) (xy 239.250425 -135.50115) (xy 244.457203 -135.50115) (xy 244.457203 -135.44665)
			(xy 244.46496 -135.392704) (xy 244.480315 -135.340411) (xy 244.502956 -135.290836) (xy 244.532422 -135.244987)
			(xy 244.568114 -135.203799) (xy 244.609303 -135.16811) (xy 244.655153 -135.138646) (xy 244.70473 -135.116008)
			(xy 244.757023 -135.100656) (xy 244.81097 -135.092902) (xy 244.83822 -135.09244) (xy 245.70182 -135.09244)
			(xy 245.729074 -135.092831) (xy 245.783026 -135.100591) (xy 245.835325 -135.11595) (xy 245.884906 -135.138595)
			(xy 245.93076 -135.168066) (xy 245.971953 -135.203762) (xy 246.007646 -135.244956) (xy 246.037115 -135.290812)
			(xy 246.059757 -135.340394) (xy 246.075113 -135.392693) (xy 246.08287 -135.446646) (xy 246.08287 -135.501154)
			(xy 246.075113 -135.555107) (xy 246.059757 -135.607406) (xy 246.037115 -135.656988) (xy 246.007646 -135.702844)
			(xy 245.971953 -135.744038) (xy 245.93076 -135.779734) (xy 245.884906 -135.809205) (xy 245.835325 -135.83185)
			(xy 245.783026 -135.847209) (xy 245.729074 -135.854969) (xy 245.70182 -135.855456) (xy 244.83822 -135.855456)
			(xy 244.81097 -135.854898) (xy 244.757023 -135.847144) (xy 244.70473 -135.831792) (xy 244.655153 -135.809154)
			(xy 244.609303 -135.77969) (xy 244.568114 -135.744001) (xy 244.532422 -135.702813) (xy 244.502956 -135.656964)
			(xy 244.480315 -135.607389) (xy 244.46496 -135.555096) (xy 244.457203 -135.50115) (xy 239.250425 -135.50115)
			(xy 239.209771 -135.527277) (xy 239.160194 -135.549919) (xy 239.107899 -135.565274) (xy 239.053951 -135.57303)
			(xy 238.999449 -135.57303) (xy 238.945501 -135.565274) (xy 238.893206 -135.549919) (xy 238.843629 -135.527277)
			(xy 238.797779 -135.497811) (xy 238.756588 -135.46212) (xy 238.720897 -135.420929) (xy 238.691431 -135.375079)
			(xy 238.668789 -135.325502) (xy 238.653434 -135.273207) (xy 238.645678 -135.219259) (xy 238.645192 -135.192008)
			(xy 234.786383 -135.192008) (xy 234.78478 -135.203157) (xy 234.769415 -135.255487) (xy 234.746758 -135.305097)
			(xy 234.717272 -135.350978) (xy 234.681557 -135.392195) (xy 234.64034 -135.42791) (xy 234.594459 -135.457396)
			(xy 234.544849 -135.480053) (xy 234.492519 -135.495418) (xy 234.438535 -135.50318) (xy 234.383997 -135.50318)
			(xy 234.330013 -135.495418) (xy 234.277683 -135.480053) (xy 234.228073 -135.457396) (xy 234.182192 -135.42791)
			(xy 234.140975 -135.392195) (xy 234.10526 -135.350978) (xy 234.075774 -135.305097) (xy 234.053117 -135.255487)
			(xy 234.037752 -135.203157) (xy 234.02999 -135.149173) (xy 234.029504 -135.121904) (xy 230.145996 -135.121904)
			(xy 230.133957 -135.162906) (xy 230.111315 -135.212488) (xy 230.081846 -135.258344) (xy 230.046153 -135.299538)
			(xy 230.00496 -135.335234) (xy 229.959106 -135.364705) (xy 229.909525 -135.38735) (xy 229.857226 -135.402709)
			(xy 229.803274 -135.410469) (xy 229.77602 -135.410956) (xy 228.91242 -135.410956) (xy 228.88517 -135.410398)
			(xy 228.831223 -135.402644) (xy 228.77893 -135.387292) (xy 228.729353 -135.364654) (xy 228.683503 -135.33519)
			(xy 228.642314 -135.299501) (xy 228.606622 -135.258313) (xy 228.577156 -135.212464) (xy 228.554515 -135.162889)
			(xy 228.53916 -135.110596) (xy 228.531403 -135.05665) (xy 226.755856 -135.05665) (xy 226.783915 -135.100312)
			(xy 226.806557 -135.149894) (xy 226.821913 -135.202193) (xy 226.82967 -135.256146) (xy 226.82967 -135.310654)
			(xy 226.821913 -135.364607) (xy 226.806557 -135.416906) (xy 226.783915 -135.466488) (xy 226.754446 -135.512344)
			(xy 226.718753 -135.553538) (xy 226.67756 -135.589234) (xy 226.631706 -135.618705) (xy 226.582125 -135.64135)
			(xy 226.529826 -135.656709) (xy 226.475874 -135.664469) (xy 226.44862 -135.664956) (xy 225.58502 -135.664956)
			(xy 225.55777 -135.664398) (xy 225.503823 -135.656644) (xy 225.45153 -135.641292) (xy 225.401953 -135.618654)
			(xy 225.356103 -135.58919) (xy 225.314914 -135.553501) (xy 225.279222 -135.512313) (xy 225.249756 -135.466464)
			(xy 225.227115 -135.416889) (xy 225.21176 -135.364596) (xy 225.204003 -135.31065) (xy 2.509012 -135.31065)
			(xy 2.509012 -137.199664) (xy 337.46447 -137.199664) (xy 337.46447 -137.145136) (xy 337.47223 -137.091163)
			(xy 337.487591 -137.038843) (xy 337.510241 -136.989242) (xy 337.539719 -136.943369) (xy 337.575425 -136.902158)
			(xy 337.616632 -136.866447) (xy 337.662502 -136.836963) (xy 337.7121 -136.814307) (xy 337.764418 -136.79894)
			(xy 337.81839 -136.791173) (xy 337.845654 -136.790684) (xy 338.618322 -136.790684) (xy 338.645594 -136.79108)
			(xy 338.699581 -136.798845) (xy 338.751915 -136.814214) (xy 338.801528 -136.836874) (xy 338.847412 -136.866364)
			(xy 338.888632 -136.902084) (xy 338.924349 -136.943306) (xy 338.953836 -136.989191) (xy 338.976493 -137.038806)
			(xy 338.991859 -137.09114) (xy 338.999622 -137.145128) (xy 338.999622 -137.199672) (xy 338.991859 -137.25366)
			(xy 338.976493 -137.305994) (xy 338.953836 -137.355609) (xy 338.924349 -137.401494) (xy 338.888632 -137.442716)
			(xy 338.847412 -137.478436) (xy 338.801528 -137.507926) (xy 338.751915 -137.530586) (xy 338.699581 -137.545955)
			(xy 338.645594 -137.55372) (xy 338.618322 -137.554208) (xy 337.845654 -137.554208) (xy 337.81839 -137.553627)
			(xy 337.764418 -137.54586) (xy 337.7121 -137.530493) (xy 337.662502 -137.507837) (xy 337.616632 -137.478353)
			(xy 337.575425 -137.442642) (xy 337.539719 -137.401431) (xy 337.510241 -137.355558) (xy 337.487591 -137.305957)
			(xy 337.47223 -137.253637) (xy 337.46447 -137.199664) (xy 2.509012 -137.199664) (xy 2.509012 -137.622788)
			(xy 340.085172 -137.622788) (xy 340.085172 -136.759188) (xy 340.085658 -136.731937) (xy 340.093414 -136.677989)
			(xy 340.108769 -136.625694) (xy 340.131411 -136.576117) (xy 340.160877 -136.530267) (xy 340.196568 -136.489076)
			(xy 340.237759 -136.453385) (xy 340.283609 -136.423919) (xy 340.333186 -136.401277) (xy 340.385481 -136.385922)
			(xy 340.439429 -136.378166) (xy 340.493931 -136.378166) (xy 340.547879 -136.385922) (xy 340.600174 -136.401277)
			(xy 340.649751 -136.423919) (xy 340.695601 -136.453385) (xy 340.736792 -136.489076) (xy 340.772483 -136.530267)
			(xy 340.801949 -136.576117) (xy 340.824591 -136.625694) (xy 340.839946 -136.677989) (xy 340.847702 -136.731937)
			(xy 340.848188 -136.759188) (xy 340.848188 -137.622788) (xy 340.847702 -137.650039) (xy 340.839946 -137.703987)
			(xy 340.824591 -137.756282) (xy 340.801949 -137.805859) (xy 340.772483 -137.851709) (xy 340.736792 -137.8929)
			(xy 340.695601 -137.928591) (xy 340.649751 -137.958057) (xy 340.600174 -137.980699) (xy 340.547879 -137.996054)
			(xy 340.493931 -138.00381) (xy 340.439429 -138.00381) (xy 340.385481 -137.996054) (xy 340.333186 -137.980699)
			(xy 340.283609 -137.958057) (xy 340.237759 -137.928591) (xy 340.196568 -137.8929) (xy 340.160877 -137.851709)
			(xy 340.131411 -137.805859) (xy 340.108769 -137.756282) (xy 340.093414 -137.703987) (xy 340.085658 -137.650039)
			(xy 340.085172 -137.622788) (xy 2.509012 -137.622788) (xy 2.509012 -153.766012) (xy 24.445731 -153.766012)
			(xy 24.449724 -153.556271) (xy 24.4617 -153.346834) (xy 24.481641 -153.138005) (xy 24.509518 -152.930086)
			(xy 24.54529 -152.723379) (xy 24.588905 -152.518184) (xy 24.640301 -152.314799) (xy 24.699403 -152.113517)
			(xy 24.766125 -151.914631) (xy 24.84037 -151.71843) (xy 24.92203 -151.525198) (xy 25.010988 -151.335214)
			(xy 25.107115 -151.148755) (xy 25.21027 -150.966091) (xy 25.320305 -150.787486) (xy 25.437059 -150.6132)
			(xy 25.560364 -150.443485) (xy 25.690041 -150.278587) (xy 25.825902 -150.118746) (xy 25.967749 -149.964193)
			(xy 26.115378 -149.815153) (xy 26.268573 -149.67184) (xy 26.427114 -149.534464) (xy 26.590769 -149.403223)
			(xy 26.759303 -149.278308) (xy 26.932469 -149.1599) (xy 27.110019 -149.04817) (xy 27.291693 -148.94328)
			(xy 27.477228 -148.845383) (xy 27.666356 -148.754621) (xy 27.858803 -148.671124) (xy 28.054288 -148.595014)
			(xy 28.25253 -148.526402) (xy 28.45324 -148.465387) (xy 28.656127 -148.412058) (xy 28.860897 -148.366491)
			(xy 29.067254 -148.328752) (xy 29.274898 -148.298898) (xy 29.483528 -148.27697) (xy 29.692841 -148.263001)
			(xy 29.902535 -148.25701) (xy 30.112304 -148.259007) (xy 30.321846 -148.268989) (xy 30.530856 -148.286941)
			(xy 30.73903 -148.312837) (xy 30.946068 -148.346639) (xy 31.151669 -148.388299) (xy 31.355535 -148.437757)
			(xy 31.55737 -148.49494) (xy 31.756882 -148.559765) (xy 31.953781 -148.632139) (xy 32.147782 -148.711956)
			(xy 32.338604 -148.799102) (xy 32.52597 -148.893449) (xy 32.709608 -148.99486) (xy 32.889252 -149.10319)
			(xy 33.064642 -149.21828) (xy 33.235523 -149.339964) (xy 33.401647 -149.468065) (xy 33.562774 -149.602398)
			(xy 33.718671 -149.742767) (xy 33.86911 -149.88897) (xy 34.013874 -150.040794) (xy 34.152753 -150.19802)
			(xy 34.285546 -150.360419) (xy 34.41206 -150.527755) (xy 34.532112 -150.699787) (xy 34.645527 -150.876264)
			(xy 34.752141 -151.056932) (xy 34.8518 -151.241527) (xy 34.944359 -151.429782) (xy 35.029684 -151.621425)
			(xy 35.107651 -151.816177) (xy 35.178147 -152.013757) (xy 35.24107 -152.213876) (xy 35.296329 -152.416247)
			(xy 35.343843 -152.620574) (xy 35.383544 -152.826562) (xy 35.415374 -153.033913) (xy 35.439287 -153.242324)
			(xy 35.455248 -153.451495) (xy 35.463235 -153.661122) (xy 35.463734 -153.766012) (xy 35.463235 -153.870902)
			(xy 35.455248 -154.080529) (xy 35.44312 -154.239468) (xy 186.742832 -154.239468) (xy 186.742832 -153.375868)
			(xy 186.743318 -153.348617) (xy 186.751074 -153.294669) (xy 186.766429 -153.242374) (xy 186.789071 -153.192797)
			(xy 186.818537 -153.146947) (xy 186.854228 -153.105756) (xy 186.895419 -153.070065) (xy 186.941269 -153.040599)
			(xy 186.990846 -153.017957) (xy 187.043141 -153.002602) (xy 187.097089 -152.994846) (xy 187.151591 -152.994846)
			(xy 187.205539 -153.002602) (xy 187.257834 -153.017957) (xy 187.307411 -153.040599) (xy 187.353261 -153.070065)
			(xy 187.394452 -153.105756) (xy 187.430143 -153.146947) (xy 187.459609 -153.192797) (xy 187.482251 -153.242374)
			(xy 187.497606 -153.294669) (xy 187.505362 -153.348617) (xy 187.505848 -153.375868) (xy 187.505848 -153.774902)
			(xy 188.445657 -153.774902) (xy 188.44965 -153.565161) (xy 188.461626 -153.355724) (xy 188.481567 -153.146895)
			(xy 188.509444 -152.938976) (xy 188.545216 -152.732269) (xy 188.588831 -152.527074) (xy 188.640227 -152.323689)
			(xy 188.699329 -152.122407) (xy 188.766051 -151.923521) (xy 188.840296 -151.72732) (xy 188.921956 -151.534088)
			(xy 189.010914 -151.344104) (xy 189.107041 -151.157645) (xy 189.210196 -150.974981) (xy 189.320231 -150.796376)
			(xy 189.436985 -150.62209) (xy 189.56029 -150.452375) (xy 189.689967 -150.287477) (xy 189.825828 -150.127636)
			(xy 189.967675 -149.973083) (xy 190.115304 -149.824043) (xy 190.268499 -149.68073) (xy 190.42704 -149.543354)
			(xy 190.590695 -149.412113) (xy 190.759229 -149.287198) (xy 190.932395 -149.16879) (xy 191.109945 -149.05706)
			(xy 191.291619 -148.95217) (xy 191.477154 -148.854273) (xy 191.666282 -148.763511) (xy 191.858729 -148.680014)
			(xy 192.054214 -148.603904) (xy 192.252456 -148.535292) (xy 192.453166 -148.474277) (xy 192.656053 -148.420948)
			(xy 192.860823 -148.375381) (xy 193.06718 -148.337642) (xy 193.274824 -148.307788) (xy 193.483454 -148.28586)
			(xy 193.692767 -148.271891) (xy 193.902461 -148.2659) (xy 194.11223 -148.267897) (xy 194.321772 -148.277879)
			(xy 194.530782 -148.295831) (xy 194.738956 -148.321727) (xy 194.945994 -148.355529) (xy 195.151595 -148.397189)
			(xy 195.355461 -148.446647) (xy 195.557296 -148.50383) (xy 195.756808 -148.568655) (xy 195.953707 -148.641029)
			(xy 196.147708 -148.720846) (xy 196.33853 -148.807992) (xy 196.525896 -148.902339) (xy 196.709534 -149.00375)
			(xy 196.889178 -149.11208) (xy 197.064568 -149.22717) (xy 197.235449 -149.348854) (xy 197.401573 -149.476955)
			(xy 197.5627 -149.611288) (xy 197.718597 -149.751657) (xy 197.869036 -149.89786) (xy 198.0138 -150.049684)
			(xy 198.152679 -150.20691) (xy 198.285472 -150.369309) (xy 198.411986 -150.536645) (xy 198.532038 -150.708677)
			(xy 198.645453 -150.885154) (xy 198.752067 -151.065822) (xy 198.851726 -151.250417) (xy 198.944285 -151.438672)
			(xy 199.02961 -151.630315) (xy 199.107577 -151.825067) (xy 199.178073 -152.022647) (xy 199.240996 -152.222766)
			(xy 199.296255 -152.425137) (xy 199.343769 -152.629464) (xy 199.38347 -152.835452) (xy 199.4153 -153.042803)
			(xy 199.439213 -153.251214) (xy 199.455174 -153.460385) (xy 199.463161 -153.670012) (xy 199.463618 -153.766012)
			(xy 272.385799 -153.766012) (xy 272.389792 -153.556271) (xy 272.401768 -153.346834) (xy 272.421709 -153.138005)
			(xy 272.449586 -152.930086) (xy 272.485358 -152.723379) (xy 272.528973 -152.518184) (xy 272.580369 -152.314799)
			(xy 272.639471 -152.113517) (xy 272.706193 -151.914631) (xy 272.780438 -151.71843) (xy 272.862098 -151.525198)
			(xy 272.951056 -151.335214) (xy 273.047183 -151.148755) (xy 273.150338 -150.966091) (xy 273.260373 -150.787486)
			(xy 273.377127 -150.6132) (xy 273.500432 -150.443485) (xy 273.630109 -150.278587) (xy 273.76597 -150.118746)
			(xy 273.907817 -149.964193) (xy 274.055446 -149.815153) (xy 274.208641 -149.67184) (xy 274.367182 -149.534464)
			(xy 274.530837 -149.403223) (xy 274.699371 -149.278308) (xy 274.872537 -149.1599) (xy 275.050087 -149.04817)
			(xy 275.231761 -148.94328) (xy 275.417296 -148.845383) (xy 275.606424 -148.754621) (xy 275.798871 -148.671124)
			(xy 275.994356 -148.595014) (xy 276.192598 -148.526402) (xy 276.393308 -148.465387) (xy 276.596195 -148.412058)
			(xy 276.800965 -148.366491) (xy 277.007322 -148.328752) (xy 277.214966 -148.298898) (xy 277.423596 -148.27697)
			(xy 277.632909 -148.263001) (xy 277.842603 -148.25701) (xy 278.052372 -148.259007) (xy 278.261914 -148.268989)
			(xy 278.470924 -148.286941) (xy 278.679098 -148.312837) (xy 278.886136 -148.346639) (xy 279.091737 -148.388299)
			(xy 279.295603 -148.437757) (xy 279.497438 -148.49494) (xy 279.69695 -148.559765) (xy 279.893849 -148.632139)
			(xy 280.08785 -148.711956) (xy 280.278672 -148.799102) (xy 280.466038 -148.893449) (xy 280.649676 -148.99486)
			(xy 280.82932 -149.10319) (xy 281.00471 -149.21828) (xy 281.175591 -149.339964) (xy 281.341715 -149.468065)
			(xy 281.502842 -149.602398) (xy 281.658739 -149.742767) (xy 281.809178 -149.88897) (xy 281.953942 -150.040794)
			(xy 282.092821 -150.19802) (xy 282.225614 -150.360419) (xy 282.352128 -150.527755) (xy 282.47218 -150.699787)
			(xy 282.585595 -150.876264) (xy 282.692209 -151.056932) (xy 282.791868 -151.241527) (xy 282.884427 -151.429782)
			(xy 282.969752 -151.621425) (xy 283.047719 -151.816177) (xy 283.118215 -152.013757) (xy 283.181138 -152.213876)
			(xy 283.236397 -152.416247) (xy 283.283911 -152.620574) (xy 283.323612 -152.826562) (xy 283.355442 -153.033913)
			(xy 283.379355 -153.242324) (xy 283.395316 -153.451495) (xy 283.403303 -153.661122) (xy 283.403802 -153.766012)
			(xy 283.40376 -153.774902) (xy 436.385725 -153.774902) (xy 436.389718 -153.565161) (xy 436.401694 -153.355724)
			(xy 436.421635 -153.146895) (xy 436.449512 -152.938976) (xy 436.485284 -152.732269) (xy 436.528899 -152.527074)
			(xy 436.580295 -152.323689) (xy 436.639397 -152.122407) (xy 436.706119 -151.923521) (xy 436.780364 -151.72732)
			(xy 436.862024 -151.534088) (xy 436.950982 -151.344104) (xy 437.047109 -151.157645) (xy 437.150264 -150.974981)
			(xy 437.260299 -150.796376) (xy 437.377053 -150.62209) (xy 437.500358 -150.452375) (xy 437.630035 -150.287477)
			(xy 437.765896 -150.127636) (xy 437.907743 -149.973083) (xy 438.055372 -149.824043) (xy 438.208567 -149.68073)
			(xy 438.367108 -149.543354) (xy 438.530763 -149.412113) (xy 438.699297 -149.287198) (xy 438.872463 -149.16879)
			(xy 439.050013 -149.05706) (xy 439.231687 -148.95217) (xy 439.417222 -148.854273) (xy 439.60635 -148.763511)
			(xy 439.798797 -148.680014) (xy 439.994282 -148.603904) (xy 440.192524 -148.535292) (xy 440.393234 -148.474277)
			(xy 440.596121 -148.420948) (xy 440.800891 -148.375381) (xy 441.007248 -148.337642) (xy 441.214892 -148.307788)
			(xy 441.423522 -148.28586) (xy 441.632835 -148.271891) (xy 441.842529 -148.2659) (xy 442.052298 -148.267897)
			(xy 442.26184 -148.277879) (xy 442.47085 -148.295831) (xy 442.679024 -148.321727) (xy 442.886062 -148.355529)
			(xy 443.091663 -148.397189) (xy 443.295529 -148.446647) (xy 443.497364 -148.50383) (xy 443.696876 -148.568655)
			(xy 443.893775 -148.641029) (xy 444.087776 -148.720846) (xy 444.278598 -148.807992) (xy 444.465964 -148.902339)
			(xy 444.649602 -149.00375) (xy 444.829246 -149.11208) (xy 445.004636 -149.22717) (xy 445.175517 -149.348854)
			(xy 445.341641 -149.476955) (xy 445.502768 -149.611288) (xy 445.658665 -149.751657) (xy 445.809104 -149.89786)
			(xy 445.953868 -150.049684) (xy 446.092747 -150.20691) (xy 446.22554 -150.369309) (xy 446.352054 -150.536645)
			(xy 446.472106 -150.708677) (xy 446.585521 -150.885154) (xy 446.692135 -151.065822) (xy 446.791794 -151.250417)
			(xy 446.884353 -151.438672) (xy 446.969678 -151.630315) (xy 447.047645 -151.825067) (xy 447.118141 -152.022647)
			(xy 447.181064 -152.222766) (xy 447.236323 -152.425137) (xy 447.283837 -152.629464) (xy 447.323538 -152.835452)
			(xy 447.355368 -153.042803) (xy 447.379281 -153.251214) (xy 447.395242 -153.460385) (xy 447.403229 -153.670012)
			(xy 447.403728 -153.774902) (xy 447.403229 -153.879792) (xy 447.395242 -154.089419) (xy 447.379281 -154.29859)
			(xy 447.355368 -154.507001) (xy 447.323538 -154.714352) (xy 447.283837 -154.92034) (xy 447.236323 -155.124667)
			(xy 447.181064 -155.327038) (xy 447.118141 -155.527157) (xy 447.047645 -155.724737) (xy 446.969678 -155.919489)
			(xy 446.884353 -156.111132) (xy 446.791794 -156.299387) (xy 446.692135 -156.483982) (xy 446.585521 -156.66465)
			(xy 446.472106 -156.841127) (xy 446.352054 -157.013159) (xy 446.22554 -157.180495) (xy 446.092747 -157.342894)
			(xy 445.953868 -157.50012) (xy 445.809104 -157.651944) (xy 445.658665 -157.798147) (xy 445.502768 -157.938516)
			(xy 445.341641 -158.072849) (xy 445.175517 -158.20095) (xy 445.004636 -158.322634) (xy 444.829246 -158.437724)
			(xy 444.649602 -158.546054) (xy 444.465964 -158.647465) (xy 444.278598 -158.741812) (xy 444.087776 -158.828958)
			(xy 443.893775 -158.908775) (xy 443.696876 -158.981149) (xy 443.497364 -159.045974) (xy 443.295529 -159.103157)
			(xy 443.091663 -159.152615) (xy 442.886062 -159.194275) (xy 442.679024 -159.228077) (xy 442.47085 -159.253973)
			(xy 442.26184 -159.271925) (xy 442.052298 -159.281907) (xy 441.842529 -159.283904) (xy 441.632835 -159.277913)
			(xy 441.423522 -159.263944) (xy 441.214892 -159.242016) (xy 441.007248 -159.212162) (xy 440.800891 -159.174423)
			(xy 440.596121 -159.128856) (xy 440.393234 -159.075527) (xy 440.192524 -159.014512) (xy 439.994282 -158.9459)
			(xy 439.798797 -158.86979) (xy 439.60635 -158.786293) (xy 439.417222 -158.695531) (xy 439.231687 -158.597634)
			(xy 439.050013 -158.492744) (xy 438.872463 -158.381014) (xy 438.699297 -158.262606) (xy 438.530763 -158.137691)
			(xy 438.367108 -158.00645) (xy 438.208567 -157.869074) (xy 438.055372 -157.725761) (xy 437.907743 -157.576721)
			(xy 437.765896 -157.422168) (xy 437.630035 -157.262327) (xy 437.500358 -157.097429) (xy 437.377053 -156.927714)
			(xy 437.260299 -156.753428) (xy 437.150264 -156.574823) (xy 437.047109 -156.392159) (xy 436.950982 -156.2057)
			(xy 436.862024 -156.015716) (xy 436.780364 -155.822484) (xy 436.706119 -155.626283) (xy 436.639397 -155.427397)
			(xy 436.580295 -155.226115) (xy 436.528899 -155.02273) (xy 436.485284 -154.817535) (xy 436.449512 -154.610828)
			(xy 436.421635 -154.402909) (xy 436.401694 -154.19408) (xy 436.389718 -153.984643) (xy 436.385725 -153.774902)
			(xy 283.40376 -153.774902) (xy 283.403303 -153.870902) (xy 283.395316 -154.080529) (xy 283.379355 -154.2897)
			(xy 283.355442 -154.498111) (xy 283.323612 -154.705462) (xy 283.283911 -154.91145) (xy 283.236397 -155.115777)
			(xy 283.181138 -155.318148) (xy 283.118215 -155.518267) (xy 283.047719 -155.715847) (xy 282.969752 -155.910599)
			(xy 282.884427 -156.102242) (xy 282.791868 -156.290497) (xy 282.692209 -156.475092) (xy 282.585595 -156.65576)
			(xy 282.47218 -156.832237) (xy 282.352128 -157.004269) (xy 282.225614 -157.171605) (xy 282.092821 -157.334004)
			(xy 281.953942 -157.49123) (xy 281.809178 -157.643054) (xy 281.658739 -157.789257) (xy 281.502842 -157.929626)
			(xy 281.341715 -158.063959) (xy 281.175591 -158.19206) (xy 281.00471 -158.313744) (xy 280.82932 -158.428834)
			(xy 280.649676 -158.537164) (xy 280.466038 -158.638575) (xy 280.278672 -158.732922) (xy 280.08785 -158.820068)
			(xy 279.893849 -158.899885) (xy 279.69695 -158.972259) (xy 279.497438 -159.037084) (xy 279.295603 -159.094267)
			(xy 279.091737 -159.143725) (xy 278.886136 -159.185385) (xy 278.679098 -159.219187) (xy 278.470924 -159.245083)
			(xy 278.261914 -159.263035) (xy 278.052372 -159.273017) (xy 277.842603 -159.275014) (xy 277.632909 -159.269023)
			(xy 277.423596 -159.255054) (xy 277.214966 -159.233126) (xy 277.007322 -159.203272) (xy 276.800965 -159.165533)
			(xy 276.596195 -159.119966) (xy 276.393308 -159.066637) (xy 276.192598 -159.005622) (xy 275.994356 -158.93701)
			(xy 275.798871 -158.8609) (xy 275.606424 -158.777403) (xy 275.417296 -158.686641) (xy 275.231761 -158.588744)
			(xy 275.050087 -158.483854) (xy 274.872537 -158.372124) (xy 274.699371 -158.253716) (xy 274.530837 -158.128801)
			(xy 274.367182 -157.99756) (xy 274.208641 -157.860184) (xy 274.055446 -157.716871) (xy 273.907817 -157.567831)
			(xy 273.76597 -157.413278) (xy 273.630109 -157.253437) (xy 273.500432 -157.088539) (xy 273.377127 -156.918824)
			(xy 273.260373 -156.744538) (xy 273.150338 -156.565933) (xy 273.047183 -156.383269) (xy 272.951056 -156.19681)
			(xy 272.862098 -156.006826) (xy 272.780438 -155.813594) (xy 272.706193 -155.617393) (xy 272.639471 -155.418507)
			(xy 272.580369 -155.217225) (xy 272.528973 -155.01384) (xy 272.485358 -154.808645) (xy 272.449586 -154.601938)
			(xy 272.421709 -154.394019) (xy 272.401768 -154.18519) (xy 272.389792 -153.975753) (xy 272.385799 -153.766012)
			(xy 199.463618 -153.766012) (xy 199.46366 -153.774902) (xy 199.463161 -153.879792) (xy 199.455174 -154.089419)
			(xy 199.439213 -154.29859) (xy 199.4153 -154.507001) (xy 199.38347 -154.714352) (xy 199.343769 -154.92034)
			(xy 199.296255 -155.124667) (xy 199.240996 -155.327038) (xy 199.178073 -155.527157) (xy 199.107577 -155.724737)
			(xy 199.02961 -155.919489) (xy 198.944285 -156.111132) (xy 198.851726 -156.299387) (xy 198.752067 -156.483982)
			(xy 198.645453 -156.66465) (xy 198.532038 -156.841127) (xy 198.411986 -157.013159) (xy 198.285472 -157.180495)
			(xy 198.152679 -157.342894) (xy 198.0138 -157.50012) (xy 197.869036 -157.651944) (xy 197.718597 -157.798147)
			(xy 197.5627 -157.938516) (xy 197.401573 -158.072849) (xy 197.235449 -158.20095) (xy 197.064568 -158.322634)
			(xy 196.889178 -158.437724) (xy 196.709534 -158.546054) (xy 196.525896 -158.647465) (xy 196.33853 -158.741812)
			(xy 196.147708 -158.828958) (xy 195.953707 -158.908775) (xy 195.756808 -158.981149) (xy 195.557296 -159.045974)
			(xy 195.355461 -159.103157) (xy 195.151595 -159.152615) (xy 194.945994 -159.194275) (xy 194.738956 -159.228077)
			(xy 194.530782 -159.253973) (xy 194.321772 -159.271925) (xy 194.11223 -159.281907) (xy 193.902461 -159.283904)
			(xy 193.692767 -159.277913) (xy 193.483454 -159.263944) (xy 193.274824 -159.242016) (xy 193.06718 -159.212162)
			(xy 192.860823 -159.174423) (xy 192.656053 -159.128856) (xy 192.453166 -159.075527) (xy 192.252456 -159.014512)
			(xy 192.054214 -158.9459) (xy 191.858729 -158.86979) (xy 191.666282 -158.786293) (xy 191.477154 -158.695531)
			(xy 191.291619 -158.597634) (xy 191.109945 -158.492744) (xy 190.932395 -158.381014) (xy 190.759229 -158.262606)
			(xy 190.590695 -158.137691) (xy 190.42704 -158.00645) (xy 190.268499 -157.869074) (xy 190.115304 -157.725761)
			(xy 189.967675 -157.576721) (xy 189.825828 -157.422168) (xy 189.689967 -157.262327) (xy 189.56029 -157.097429)
			(xy 189.436985 -156.927714) (xy 189.320231 -156.753428) (xy 189.210196 -156.574823) (xy 189.107041 -156.392159)
			(xy 189.010914 -156.2057) (xy 188.921956 -156.015716) (xy 188.840296 -155.822484) (xy 188.766051 -155.626283)
			(xy 188.699329 -155.427397) (xy 188.640227 -155.226115) (xy 188.588831 -155.02273) (xy 188.545216 -154.817535)
			(xy 188.509444 -154.610828) (xy 188.481567 -154.402909) (xy 188.461626 -154.19408) (xy 188.44965 -153.984643)
			(xy 188.445657 -153.774902) (xy 187.505848 -153.774902) (xy 187.505848 -154.239468) (xy 187.505362 -154.266719)
			(xy 187.497606 -154.320667) (xy 187.482251 -154.372962) (xy 187.459609 -154.422539) (xy 187.430143 -154.468389)
			(xy 187.394452 -154.50958) (xy 187.353261 -154.545271) (xy 187.307411 -154.574737) (xy 187.257834 -154.597379)
			(xy 187.205539 -154.612734) (xy 187.151591 -154.62049) (xy 187.097089 -154.62049) (xy 187.043141 -154.612734)
			(xy 186.990846 -154.597379) (xy 186.941269 -154.574737) (xy 186.895419 -154.545271) (xy 186.854228 -154.50958)
			(xy 186.818537 -154.468389) (xy 186.789071 -154.422539) (xy 186.766429 -154.372962) (xy 186.751074 -154.320667)
			(xy 186.743318 -154.266719) (xy 186.742832 -154.239468) (xy 35.44312 -154.239468) (xy 35.439287 -154.2897)
			(xy 35.415374 -154.498111) (xy 35.383544 -154.705462) (xy 35.343843 -154.91145) (xy 35.296329 -155.115777)
			(xy 35.24107 -155.318148) (xy 35.178147 -155.518267) (xy 35.107651 -155.715847) (xy 35.029684 -155.910599)
			(xy 34.944359 -156.102242) (xy 34.8518 -156.290497) (xy 34.752141 -156.475092) (xy 34.645527 -156.65576)
			(xy 34.532112 -156.832237) (xy 34.41206 -157.004269) (xy 34.285546 -157.171605) (xy 34.152753 -157.334004)
			(xy 34.013874 -157.49123) (xy 33.86911 -157.643054) (xy 33.718671 -157.789257) (xy 33.562774 -157.929626)
			(xy 33.401647 -158.063959) (xy 33.235523 -158.19206) (xy 33.064642 -158.313744) (xy 32.889252 -158.428834)
			(xy 32.709608 -158.537164) (xy 32.52597 -158.638575) (xy 32.338604 -158.732922) (xy 32.147782 -158.820068)
			(xy 31.953781 -158.899885) (xy 31.756882 -158.972259) (xy 31.55737 -159.037084) (xy 31.355535 -159.094267)
			(xy 31.151669 -159.143725) (xy 30.946068 -159.185385) (xy 30.73903 -159.219187) (xy 30.530856 -159.245083)
			(xy 30.321846 -159.263035) (xy 30.112304 -159.273017) (xy 29.902535 -159.275014) (xy 29.692841 -159.269023)
			(xy 29.483528 -159.255054) (xy 29.274898 -159.233126) (xy 29.067254 -159.203272) (xy 28.860897 -159.165533)
			(xy 28.656127 -159.119966) (xy 28.45324 -159.066637) (xy 28.25253 -159.005622) (xy 28.054288 -158.93701)
			(xy 27.858803 -158.8609) (xy 27.666356 -158.777403) (xy 27.477228 -158.686641) (xy 27.291693 -158.588744)
			(xy 27.110019 -158.483854) (xy 26.932469 -158.372124) (xy 26.759303 -158.253716) (xy 26.590769 -158.128801)
			(xy 26.427114 -157.99756) (xy 26.268573 -157.860184) (xy 26.115378 -157.716871) (xy 25.967749 -157.567831)
			(xy 25.825902 -157.413278) (xy 25.690041 -157.253437) (xy 25.560364 -157.088539) (xy 25.437059 -156.918824)
			(xy 25.320305 -156.744538) (xy 25.21027 -156.565933) (xy 25.107115 -156.383269) (xy 25.010988 -156.19681)
			(xy 24.92203 -156.006826) (xy 24.84037 -155.813594) (xy 24.766125 -155.617393) (xy 24.699403 -155.418507)
			(xy 24.640301 -155.217225) (xy 24.588905 -155.01384) (xy 24.54529 -154.808645) (xy 24.509518 -154.601938)
			(xy 24.481641 -154.394019) (xy 24.4617 -154.18519) (xy 24.449724 -153.975753) (xy 24.445731 -153.766012)
			(xy 2.509012 -153.766012) (xy 2.509012 -160.911354) (xy 372.506163 -160.911354) (xy 372.506163 -160.856846)
			(xy 372.513921 -160.802893) (xy 372.529279 -160.750593) (xy 372.551924 -160.701011) (xy 372.581395 -160.655157)
			(xy 372.617092 -160.613964) (xy 372.658289 -160.578271) (xy 372.704146 -160.548805) (xy 372.75373 -160.526165)
			(xy 372.806032 -160.510813) (xy 372.859986 -160.503061) (xy 372.88724 -160.5026) (xy 373.75084 -160.5026)
			(xy 373.77809 -160.503073) (xy 373.832034 -160.510834) (xy 373.884326 -160.526193) (xy 373.933899 -160.548837)
			(xy 373.979745 -160.578305) (xy 374.020931 -160.613997) (xy 374.056619 -160.655187) (xy 374.086083 -160.701036)
			(xy 374.108721 -160.750612) (xy 374.124075 -160.802905) (xy 374.13183 -160.85685) (xy 374.13183 -160.91135)
			(xy 374.124075 -160.965295) (xy 374.108721 -161.017588) (xy 374.086083 -161.067164) (xy 374.056619 -161.113013)
			(xy 374.020931 -161.154203) (xy 373.979745 -161.189895) (xy 373.933899 -161.219363) (xy 373.884326 -161.242007)
			(xy 373.832034 -161.257366) (xy 373.77809 -161.265127) (xy 373.75084 -161.265616) (xy 372.88724 -161.265616)
			(xy 372.859986 -161.265139) (xy 372.806032 -161.257387) (xy 372.75373 -161.242035) (xy 372.704146 -161.219395)
			(xy 372.658289 -161.189929) (xy 372.617092 -161.154236) (xy 372.581395 -161.113043) (xy 372.551924 -161.067189)
			(xy 372.529279 -161.017607) (xy 372.513921 -160.965307) (xy 372.506163 -160.911354) (xy 2.509012 -160.911354)
			(xy 2.509012 -161.58445) (xy 296.753286 -161.58445) (xy 296.753286 -161.52995) (xy 296.761042 -161.476005)
			(xy 296.776395 -161.423713) (xy 296.799035 -161.374138) (xy 296.828498 -161.32829) (xy 296.864187 -161.287101)
			(xy 296.905374 -161.25141) (xy 296.951221 -161.221944) (xy 297.000795 -161.199302) (xy 297.053086 -161.183946)
			(xy 297.10703 -161.176187) (xy 297.13428 -161.1757) (xy 297.99788 -161.1757) (xy 298.025134 -161.176146)
			(xy 298.079089 -161.183901) (xy 298.13139 -161.199255) (xy 298.180974 -161.221897) (xy 298.22683 -161.251365)
			(xy 298.268026 -161.28706) (xy 298.303723 -161.328254) (xy 298.333193 -161.374109) (xy 298.355838 -161.423691)
			(xy 298.371195 -161.475992) (xy 298.378953 -161.529946) (xy 298.378953 -161.584454) (xy 298.371195 -161.638408)
			(xy 298.355838 -161.690709) (xy 298.333193 -161.740291) (xy 298.303723 -161.786146) (xy 298.268026 -161.82734)
			(xy 298.22683 -161.863035) (xy 298.180974 -161.892503) (xy 298.13139 -161.915145) (xy 298.079089 -161.930499)
			(xy 298.025134 -161.938254) (xy 297.99788 -161.938716) (xy 297.13428 -161.938716) (xy 297.10703 -161.938213)
			(xy 297.053086 -161.930454) (xy 297.000795 -161.915098) (xy 296.951221 -161.892456) (xy 296.905374 -161.86299)
			(xy 296.864187 -161.827299) (xy 296.828498 -161.78611) (xy 296.799035 -161.740262) (xy 296.776395 -161.690687)
			(xy 296.761042 -161.638395) (xy 296.753286 -161.58445) (xy 2.509012 -161.58445) (xy 2.509012 -162.128053)
			(xy 292.574946 -162.128053) (xy 292.574946 -162.073547) (xy 292.582702 -162.019597) (xy 292.598058 -161.967299)
			(xy 292.620699 -161.917719) (xy 292.650166 -161.871866) (xy 292.685859 -161.830673) (xy 292.72705 -161.794978)
			(xy 292.772902 -161.765509) (xy 292.822481 -161.742865) (xy 292.874777 -161.727507) (xy 292.928727 -161.719747)
			(xy 292.95598 -161.71926) (xy 293.81958 -161.71926) (xy 293.846832 -161.719786) (xy 293.90078 -161.72754)
			(xy 293.953076 -161.742893) (xy 294.002654 -161.765532) (xy 294.048506 -161.794997) (xy 294.089698 -161.830688)
			(xy 294.125391 -161.871878) (xy 294.154858 -161.917728) (xy 294.1775 -161.967305) (xy 294.192856 -162.0196)
			(xy 294.200613 -162.073549) (xy 294.200613 -162.128051) (xy 294.192856 -162.182) (xy 294.1775 -162.234295)
			(xy 294.154858 -162.283872) (xy 294.125391 -162.329722) (xy 294.089698 -162.370912) (xy 294.048506 -162.406603)
			(xy 294.002654 -162.436068) (xy 293.953076 -162.458707) (xy 293.90078 -162.47406) (xy 293.846832 -162.481814)
			(xy 293.81958 -162.482276) (xy 292.95598 -162.482276) (xy 292.928727 -162.481853) (xy 292.874777 -162.474093)
			(xy 292.822481 -162.458735) (xy 292.772902 -162.436091) (xy 292.72705 -162.406622) (xy 292.685859 -162.370927)
			(xy 292.650166 -162.329734) (xy 292.620699 -162.283881) (xy 292.598058 -162.234301) (xy 292.582702 -162.182003)
			(xy 292.574946 -162.128053) (xy 2.509012 -162.128053) (xy 2.509012 -163.123651) (xy 294.731403 -163.123651)
			(xy 294.731403 -163.069149) (xy 294.73916 -163.015201) (xy 294.754516 -162.962907) (xy 294.777159 -162.91333)
			(xy 294.806627 -162.867481) (xy 294.842321 -162.826292) (xy 294.883513 -162.790603) (xy 294.929365 -162.76114)
			(xy 294.978944 -162.738502) (xy 295.03124 -162.723152) (xy 295.085189 -162.7154) (xy 295.11244 -162.71494)
			(xy 295.97604 -162.71494) (xy 296.003293 -162.715333) (xy 296.057243 -162.723095) (xy 296.10954 -162.738455)
			(xy 296.159118 -162.761102) (xy 296.204969 -162.790573) (xy 296.24616 -162.826269) (xy 296.281851 -162.867463)
			(xy 296.311318 -162.913317) (xy 296.333959 -162.962898) (xy 296.349314 -163.015196) (xy 296.35707 -163.069147)
			(xy 296.35707 -163.110951) (xy 300.192403 -163.110951) (xy 300.192403 -163.056449) (xy 300.20016 -163.002501)
			(xy 300.215516 -162.950207) (xy 300.238159 -162.90063) (xy 300.267627 -162.854781) (xy 300.303321 -162.813592)
			(xy 300.344513 -162.777903) (xy 300.390365 -162.74844) (xy 300.439944 -162.725802) (xy 300.49224 -162.710452)
			(xy 300.546189 -162.7027) (xy 300.57344 -162.70224) (xy 301.43704 -162.70224) (xy 301.464293 -162.702633)
			(xy 301.518243 -162.710395) (xy 301.57054 -162.725755) (xy 301.620118 -162.748402) (xy 301.665969 -162.777873)
			(xy 301.70716 -162.813569) (xy 301.742851 -162.854763) (xy 301.772318 -162.900617) (xy 301.794959 -162.950198)
			(xy 301.810314 -163.002496) (xy 301.81807 -163.056447) (xy 301.81807 -163.110953) (xy 301.810314 -163.164904)
			(xy 301.794959 -163.217202) (xy 301.772318 -163.266783) (xy 301.742851 -163.312637) (xy 301.70716 -163.353831)
			(xy 301.665969 -163.389527) (xy 301.620118 -163.418998) (xy 301.57054 -163.441645) (xy 301.518243 -163.457005)
			(xy 301.464293 -163.464767) (xy 301.43704 -163.465256) (xy 300.57344 -163.465256) (xy 300.546189 -163.4647)
			(xy 300.49224 -163.456948) (xy 300.439944 -163.441598) (xy 300.390365 -163.41896) (xy 300.344513 -163.389497)
			(xy 300.303321 -163.353808) (xy 300.267627 -163.312619) (xy 300.238159 -163.26677) (xy 300.215516 -163.217193)
			(xy 300.20016 -163.164899) (xy 300.192403 -163.110951) (xy 296.35707 -163.110951) (xy 296.35707 -163.123653)
			(xy 296.349314 -163.177604) (xy 296.333959 -163.229902) (xy 296.311318 -163.279483) (xy 296.281851 -163.325337)
			(xy 296.24616 -163.366531) (xy 296.204969 -163.402227) (xy 296.159118 -163.431698) (xy 296.10954 -163.454345)
			(xy 296.057243 -163.469705) (xy 296.003293 -163.477467) (xy 295.97604 -163.477956) (xy 295.11244 -163.477956)
			(xy 295.085189 -163.4774) (xy 295.03124 -163.469648) (xy 294.978944 -163.454298) (xy 294.929365 -163.43166)
			(xy 294.883513 -163.402197) (xy 294.842321 -163.366508) (xy 294.806627 -163.325319) (xy 294.777159 -163.27947)
			(xy 294.754516 -163.229893) (xy 294.73916 -163.177599) (xy 294.731403 -163.123651) (xy 2.509012 -163.123651)
			(xy 2.509012 -167.565832) (xy 348.657164 -167.565832) (xy 348.657658 -167.532531) (xy 348.666337 -167.466499)
			(xy 348.683566 -167.402165) (xy 348.709048 -167.340632) (xy 348.742347 -167.282953) (xy 348.782893 -167.230117)
			(xy 348.829992 -167.183027) (xy 348.882836 -167.142492) (xy 348.911418 -167.125396) (xy 349.83547 -166.591742)
			(xy 349.864533 -166.575642) (xy 349.925937 -166.550271) (xy 349.990123 -166.533114) (xy 350.055996 -166.524463)
			(xy 350.089216 -166.523924) (xy 350.089724 -166.523924) (xy 350.120458 -166.524315) (xy 350.181477 -166.531727)
			(xy 350.241158 -166.54644) (xy 350.29863 -166.56824) (xy 350.353056 -166.596808) (xy 350.403641 -166.631729)
			(xy 350.449648 -166.672492) (xy 350.490406 -166.718503) (xy 350.525321 -166.769092) (xy 350.553883 -166.823521)
			(xy 350.57377 -166.875968) (xy 369.614196 -166.875968) (xy 369.614752 -166.84267) (xy 369.623426 -166.776641)
			(xy 369.640648 -166.71231) (xy 369.666122 -166.650779) (xy 369.699412 -166.593101) (xy 369.739949 -166.540263)
			(xy 369.787038 -166.493171) (xy 369.839873 -166.452631) (xy 369.86845 -166.435532) (xy 370.792502 -165.901878)
			(xy 370.82156 -165.885769) (xy 370.882966 -165.8604) (xy 370.947153 -165.843245) (xy 371.013028 -165.834597)
			(xy 371.046248 -165.83406) (xy 371.046756 -165.83406) (xy 371.077486 -165.834579) (xy 371.138498 -165.841982)
			(xy 371.198173 -165.856685) (xy 371.255641 -165.878475) (xy 371.310063 -165.907032) (xy 371.360647 -165.941941)
			(xy 371.406653 -165.982693) (xy 371.447412 -166.028694) (xy 371.482329 -166.079272) (xy 371.510894 -166.133689)
			(xy 371.532692 -166.191154) (xy 371.547404 -166.250827) (xy 371.554816 -166.311838) (xy 371.555264 -166.342568)
			(xy 371.554757 -166.375868) (xy 371.546077 -166.4419) (xy 371.52885 -166.506232) (xy 371.503369 -166.567765)
			(xy 371.470072 -166.625443) (xy 371.429528 -166.67828) (xy 371.382432 -166.72537) (xy 371.329591 -166.765907)
			(xy 371.30101 -166.783004) (xy 370.964111 -166.977568) (xy 373.398796 -166.977568) (xy 373.399226 -166.946836)
			(xy 373.406638 -166.885821) (xy 373.421351 -166.826144) (xy 373.443149 -166.768676) (xy 373.471715 -166.714254)
			(xy 373.506633 -166.663671) (xy 373.547392 -166.617667) (xy 373.5934 -166.57691) (xy 373.643984 -166.541996)
			(xy 373.698409 -166.513434) (xy 373.755879 -166.49164) (xy 373.815556 -166.476932) (xy 373.876572 -166.469524)
			(xy 373.907304 -166.46906) (xy 373.907812 -166.46906) (xy 373.941031 -166.469606) (xy 374.006903 -166.478264)
			(xy 374.071088 -166.495419) (xy 374.132496 -166.520778) (xy 374.161558 -166.536878) (xy 375.08561 -167.070532)
			(xy 375.114171 -167.087654) (xy 375.166997 -167.128201) (xy 375.214079 -167.175295) (xy 375.254613 -167.22813)
			(xy 375.287906 -167.285802) (xy 375.313388 -167.347326) (xy 375.330623 -167.411649) (xy 375.339318 -167.477672)
			(xy 375.339864 -167.510968) (xy 375.339432 -167.541701) (xy 375.332026 -167.60272) (xy 375.317319 -167.6624)
			(xy 375.295524 -167.719873) (xy 375.266961 -167.774299) (xy 375.232044 -167.824885) (xy 375.191284 -167.870893)
			(xy 375.145275 -167.911651) (xy 375.094689 -167.946567) (xy 375.040262 -167.975129) (xy 374.982789 -167.996923)
			(xy 374.923108 -168.011629) (xy 374.862089 -168.019033) (xy 374.831356 -168.019476) (xy 374.830848 -168.019476)
			(xy 374.797629 -168.018942) (xy 374.731757 -168.01028) (xy 374.667571 -167.993122) (xy 374.606164 -167.967759)
			(xy 374.577102 -167.951658) (xy 373.65305 -167.418004) (xy 373.624495 -167.400872) (xy 373.571672 -167.360325)
			(xy 373.524591 -167.313232) (xy 373.484057 -167.260398) (xy 373.450764 -167.202727) (xy 373.42528 -167.141205)
			(xy 373.408042 -167.076884) (xy 373.399344 -167.010863) (xy 373.398796 -166.977568) (xy 370.964111 -166.977568)
			(xy 370.376958 -167.316658) (xy 370.34791 -167.332786) (xy 370.2865 -167.35815) (xy 370.22231 -167.375299)
			(xy 370.156433 -167.383942) (xy 370.123212 -167.384476) (xy 370.122704 -167.384476) (xy 370.091971 -167.384059)
			(xy 370.030952 -167.37665) (xy 369.971272 -167.36194) (xy 369.9138 -167.340143) (xy 369.859375 -167.311577)
			(xy 369.808789 -167.276659) (xy 369.762782 -167.235898) (xy 369.722023 -167.189889) (xy 369.687108 -167.139301)
			(xy 369.658546 -167.084874) (xy 369.636752 -167.027401) (xy 369.622045 -166.96772) (xy 369.61464 -166.906701)
			(xy 369.614196 -166.875968) (xy 350.57377 -166.875968) (xy 350.575676 -166.880996) (xy 350.590383 -166.940678)
			(xy 350.597788 -167.001698) (xy 350.598232 -167.032432) (xy 350.597712 -167.065732) (xy 350.589036 -167.131763)
			(xy 350.571812 -167.196097) (xy 350.546334 -167.25763) (xy 350.513038 -167.315309) (xy 350.472496 -167.368145)
			(xy 350.4254 -167.415235) (xy 350.372559 -167.455772) (xy 350.343978 -167.472868) (xy 349.419926 -168.006522)
			(xy 349.390862 -168.02262) (xy 349.329459 -168.047992) (xy 349.265273 -168.06515) (xy 349.1994 -168.073802)
			(xy 349.16618 -168.07434) (xy 349.165672 -168.07434) (xy 349.134942 -168.07387) (xy 349.073929 -168.066459)
			(xy 349.014255 -168.051748) (xy 348.956789 -168.029953) (xy 348.902369 -168.001389) (xy 348.851788 -167.966475)
			(xy 348.805784 -167.925719) (xy 348.765027 -167.879715) (xy 348.730113 -167.829135) (xy 348.701549 -167.774715)
			(xy 348.679753 -167.717249) (xy 348.665041 -167.657575) (xy 348.65763 -167.596562) (xy 348.657164 -167.565832)
			(xy 2.509012 -167.565832) (xy 2.509012 -168.302432) (xy 352.441764 -168.302432) (xy 352.442268 -168.271702)
			(xy 352.449672 -168.210689) (xy 352.464377 -168.151013) (xy 352.486168 -168.093545) (xy 352.514727 -168.039122)
			(xy 352.549637 -167.988539) (xy 352.59039 -167.942533) (xy 352.636392 -167.901774) (xy 352.686971 -167.866858)
			(xy 352.74139 -167.838292) (xy 352.798856 -167.816495) (xy 352.85853 -167.801783) (xy 352.919542 -167.794371)
			(xy 352.950272 -167.793924) (xy 352.95078 -167.793924) (xy 352.983998 -167.794489) (xy 353.049869 -167.803142)
			(xy 353.114055 -167.820291) (xy 353.175463 -167.845645) (xy 353.204526 -167.861742) (xy 354.128578 -168.395396)
			(xy 354.157139 -168.412518) (xy 354.209962 -168.453067) (xy 354.257042 -168.500162) (xy 354.297574 -168.552998)
			(xy 354.330866 -168.61067) (xy 354.356349 -168.672193) (xy 354.373586 -168.736515) (xy 354.382284 -168.802536)
			(xy 354.382832 -168.835832) (xy 354.382374 -168.866563) (xy 354.374962 -168.927576) (xy 354.360251 -168.987251)
			(xy 354.338454 -169.044717) (xy 354.30989 -169.099138) (xy 354.274975 -169.149719) (xy 354.234218 -169.195723)
			(xy 354.188213 -169.23648) (xy 354.137631 -169.271394) (xy 354.08321 -169.299957) (xy 354.025743 -169.321753)
			(xy 353.966068 -169.336464) (xy 353.905055 -169.343875) (xy 353.874324 -169.34434) (xy 353.873816 -169.34434)
			(xy 353.840597 -169.343782) (xy 353.774726 -169.335127) (xy 353.710541 -169.317976) (xy 353.649132 -169.292621)
			(xy 353.62007 -169.276522) (xy 352.696018 -168.742868) (xy 352.667463 -168.725735) (xy 352.614637 -168.685191)
			(xy 352.567553 -168.638099) (xy 352.527018 -168.585266) (xy 352.493724 -168.527595) (xy 352.468241 -168.466072)
			(xy 352.451005 -168.40175) (xy 352.44231 -168.335728) (xy 352.441764 -168.302432) (xy 2.509012 -168.302432)
			(xy 2.509012 -170.613832) (xy 348.657164 -170.613832) (xy 348.657658 -170.580531) (xy 348.666337 -170.514499)
			(xy 348.683566 -170.450165) (xy 348.709048 -170.388632) (xy 348.742347 -170.330953) (xy 348.782893 -170.278117)
			(xy 348.829992 -170.231027) (xy 348.882836 -170.190492) (xy 348.911418 -170.173396) (xy 349.83547 -169.639742)
			(xy 349.864533 -169.623642) (xy 349.925937 -169.598271) (xy 349.990123 -169.581114) (xy 350.055996 -169.572463)
			(xy 350.089216 -169.571924) (xy 350.089724 -169.571924) (xy 350.120458 -169.572315) (xy 350.181477 -169.579727)
			(xy 350.241158 -169.59444) (xy 350.29863 -169.61624) (xy 350.353056 -169.644808) (xy 350.403641 -169.679729)
			(xy 350.449648 -169.720492) (xy 350.490406 -169.766503) (xy 350.525321 -169.817092) (xy 350.553883 -169.871521)
			(xy 350.57377 -169.923968) (xy 369.614196 -169.923968) (xy 369.614752 -169.89067) (xy 369.623426 -169.824641)
			(xy 369.640648 -169.76031) (xy 369.666122 -169.698779) (xy 369.699412 -169.641101) (xy 369.739949 -169.588263)
			(xy 369.787038 -169.541171) (xy 369.839873 -169.500631) (xy 369.86845 -169.483532) (xy 370.792502 -168.949878)
			(xy 370.82156 -168.933769) (xy 370.882966 -168.9084) (xy 370.947153 -168.891245) (xy 371.013028 -168.882597)
			(xy 371.046248 -168.88206) (xy 371.046756 -168.88206) (xy 371.077486 -168.882579) (xy 371.138498 -168.889982)
			(xy 371.198173 -168.904685) (xy 371.255641 -168.926475) (xy 371.310063 -168.955032) (xy 371.360647 -168.989941)
			(xy 371.406653 -169.030693) (xy 371.447412 -169.076694) (xy 371.482329 -169.127272) (xy 371.510894 -169.181689)
			(xy 371.532692 -169.239154) (xy 371.547404 -169.298827) (xy 371.554816 -169.359838) (xy 371.555264 -169.390568)
			(xy 371.554757 -169.423868) (xy 371.546077 -169.4899) (xy 371.52885 -169.554232) (xy 371.503369 -169.615765)
			(xy 371.470072 -169.673443) (xy 371.429528 -169.72628) (xy 371.382432 -169.77337) (xy 371.329591 -169.813907)
			(xy 371.30101 -169.831004) (xy 370.376958 -170.364658) (xy 370.34791 -170.380786) (xy 370.2865 -170.40615)
			(xy 370.22231 -170.423299) (xy 370.156433 -170.431942) (xy 370.123212 -170.432476) (xy 370.122704 -170.432476)
			(xy 370.091971 -170.432059) (xy 370.030952 -170.42465) (xy 369.971272 -170.40994) (xy 369.9138 -170.388143)
			(xy 369.859375 -170.359577) (xy 369.808789 -170.324659) (xy 369.762782 -170.283898) (xy 369.722023 -170.237889)
			(xy 369.687108 -170.187301) (xy 369.658546 -170.132874) (xy 369.636752 -170.075401) (xy 369.622045 -170.01572)
			(xy 369.61464 -169.954701) (xy 369.614196 -169.923968) (xy 350.57377 -169.923968) (xy 350.575676 -169.928996)
			(xy 350.590383 -169.988678) (xy 350.597788 -170.049698) (xy 350.598232 -170.080432) (xy 350.597712 -170.113732)
			(xy 350.589036 -170.179763) (xy 350.571812 -170.244097) (xy 350.546334 -170.30563) (xy 350.513038 -170.363309)
			(xy 350.472496 -170.416145) (xy 350.4254 -170.463235) (xy 350.372559 -170.503772) (xy 350.343978 -170.520868)
			(xy 350.10208 -170.660568) (xy 373.398796 -170.660568) (xy 373.399226 -170.629836) (xy 373.406638 -170.568821)
			(xy 373.421351 -170.509144) (xy 373.443149 -170.451676) (xy 373.471715 -170.397254) (xy 373.506633 -170.346671)
			(xy 373.547392 -170.300667) (xy 373.5934 -170.25991) (xy 373.643984 -170.224996) (xy 373.698409 -170.196434)
			(xy 373.755879 -170.17464) (xy 373.815556 -170.159932) (xy 373.876572 -170.152524) (xy 373.907304 -170.15206)
			(xy 373.907812 -170.15206) (xy 373.941031 -170.152606) (xy 374.006903 -170.161264) (xy 374.071088 -170.178419)
			(xy 374.132496 -170.203778) (xy 374.161558 -170.219878) (xy 375.08561 -170.753532) (xy 375.114171 -170.770654)
			(xy 375.166997 -170.811201) (xy 375.214079 -170.858295) (xy 375.254613 -170.91113) (xy 375.287906 -170.968802)
			(xy 375.313388 -171.030326) (xy 375.330623 -171.094649) (xy 375.339318 -171.160672) (xy 375.339864 -171.193968)
			(xy 375.339432 -171.224701) (xy 375.332026 -171.28572) (xy 375.317319 -171.3454) (xy 375.295524 -171.402873)
			(xy 375.266961 -171.457299) (xy 375.232044 -171.507885) (xy 375.191284 -171.553893) (xy 375.145275 -171.594651)
			(xy 375.094689 -171.629567) (xy 375.040262 -171.658129) (xy 374.982789 -171.679923) (xy 374.923108 -171.694629)
			(xy 374.862089 -171.702033) (xy 374.831356 -171.702476) (xy 374.830848 -171.702476) (xy 374.797629 -171.701942)
			(xy 374.731757 -171.69328) (xy 374.667571 -171.676122) (xy 374.606164 -171.650759) (xy 374.577102 -171.634658)
			(xy 373.65305 -171.101004) (xy 373.624495 -171.083872) (xy 373.571672 -171.043325) (xy 373.524591 -170.996232)
			(xy 373.484057 -170.943398) (xy 373.450764 -170.885727) (xy 373.42528 -170.824205) (xy 373.408042 -170.759884)
			(xy 373.399344 -170.693863) (xy 373.398796 -170.660568) (xy 350.10208 -170.660568) (xy 349.419926 -171.054522)
			(xy 349.390862 -171.07062) (xy 349.329459 -171.095992) (xy 349.265273 -171.11315) (xy 349.1994 -171.121802)
			(xy 349.16618 -171.12234) (xy 349.165672 -171.12234) (xy 349.134942 -171.12187) (xy 349.073929 -171.114459)
			(xy 349.014255 -171.099748) (xy 348.956789 -171.077953) (xy 348.902369 -171.049389) (xy 348.851788 -171.014475)
			(xy 348.805784 -170.973719) (xy 348.765027 -170.927715) (xy 348.730113 -170.877135) (xy 348.701549 -170.822715)
			(xy 348.679753 -170.765249) (xy 348.665041 -170.705575) (xy 348.65763 -170.644562) (xy 348.657164 -170.613832)
			(xy 2.509012 -170.613832) (xy 2.509012 -171.985432) (xy 352.441764 -171.985432) (xy 352.442268 -171.954702)
			(xy 352.449672 -171.893689) (xy 352.464377 -171.834013) (xy 352.486168 -171.776545) (xy 352.514727 -171.722122)
			(xy 352.549637 -171.671539) (xy 352.59039 -171.625533) (xy 352.636392 -171.584774) (xy 352.686971 -171.549858)
			(xy 352.74139 -171.521292) (xy 352.798856 -171.499495) (xy 352.85853 -171.484783) (xy 352.919542 -171.477371)
			(xy 352.950272 -171.476924) (xy 352.95078 -171.476924) (xy 352.983998 -171.477489) (xy 353.049869 -171.486142)
			(xy 353.114055 -171.503291) (xy 353.175463 -171.528645) (xy 353.204526 -171.544742) (xy 354.128578 -172.078396)
			(xy 354.157139 -172.095518) (xy 354.209962 -172.136067) (xy 354.257042 -172.183162) (xy 354.297574 -172.235998)
			(xy 354.330866 -172.29367) (xy 354.356349 -172.355193) (xy 354.373586 -172.419515) (xy 354.382284 -172.485536)
			(xy 354.382832 -172.518832) (xy 354.382374 -172.549563) (xy 354.374962 -172.610576) (xy 354.360251 -172.670251)
			(xy 354.338454 -172.727717) (xy 354.30989 -172.782138) (xy 354.274975 -172.832719) (xy 354.234218 -172.878723)
			(xy 354.188213 -172.91948) (xy 354.137631 -172.954394) (xy 354.104147 -172.971968) (xy 369.614196 -172.971968)
			(xy 369.614752 -172.93867) (xy 369.623426 -172.872641) (xy 369.640648 -172.80831) (xy 369.666122 -172.746779)
			(xy 369.699412 -172.689101) (xy 369.739949 -172.636263) (xy 369.787038 -172.589171) (xy 369.839873 -172.548631)
			(xy 369.86845 -172.531532) (xy 370.792502 -171.997878) (xy 370.82156 -171.981769) (xy 370.882966 -171.9564)
			(xy 370.947153 -171.939245) (xy 371.013028 -171.930597) (xy 371.046248 -171.93006) (xy 371.046756 -171.93006)
			(xy 371.077486 -171.930579) (xy 371.138498 -171.937982) (xy 371.198173 -171.952685) (xy 371.255641 -171.974475)
			(xy 371.310063 -172.003032) (xy 371.360647 -172.037941) (xy 371.406653 -172.078693) (xy 371.447412 -172.124694)
			(xy 371.482329 -172.175272) (xy 371.510894 -172.229689) (xy 371.532692 -172.287154) (xy 371.547404 -172.346827)
			(xy 371.554816 -172.407838) (xy 371.555264 -172.438568) (xy 371.554757 -172.471868) (xy 371.546077 -172.5379)
			(xy 371.52885 -172.602232) (xy 371.503369 -172.663765) (xy 371.470072 -172.721443) (xy 371.429528 -172.77428)
			(xy 371.382432 -172.82137) (xy 371.329591 -172.861907) (xy 371.30101 -172.879004) (xy 370.376958 -173.412658)
			(xy 370.34791 -173.428786) (xy 370.2865 -173.45415) (xy 370.22231 -173.471299) (xy 370.156433 -173.479942)
			(xy 370.123212 -173.480476) (xy 370.122704 -173.480476) (xy 370.091971 -173.480059) (xy 370.030952 -173.47265)
			(xy 369.971272 -173.45794) (xy 369.9138 -173.436143) (xy 369.859375 -173.407577) (xy 369.808789 -173.372659)
			(xy 369.762782 -173.331898) (xy 369.722023 -173.285889) (xy 369.687108 -173.235301) (xy 369.658546 -173.180874)
			(xy 369.636752 -173.123401) (xy 369.622045 -173.06372) (xy 369.61464 -173.002701) (xy 369.614196 -172.971968)
			(xy 354.104147 -172.971968) (xy 354.08321 -172.982957) (xy 354.025743 -173.004753) (xy 353.966068 -173.019464)
			(xy 353.905055 -173.026875) (xy 353.874324 -173.02734) (xy 353.873816 -173.02734) (xy 353.840597 -173.026782)
			(xy 353.774726 -173.018127) (xy 353.710541 -173.000976) (xy 353.649132 -172.975621) (xy 353.62007 -172.959522)
			(xy 352.696018 -172.425868) (xy 352.667463 -172.408735) (xy 352.614637 -172.368191) (xy 352.567553 -172.321099)
			(xy 352.527018 -172.268266) (xy 352.493724 -172.210595) (xy 352.468241 -172.149072) (xy 352.451005 -172.08475)
			(xy 352.44231 -172.018728) (xy 352.441764 -171.985432) (xy 2.509012 -171.985432) (xy 2.509012 -173.661832)
			(xy 348.657164 -173.661832) (xy 348.657658 -173.628531) (xy 348.666337 -173.562499) (xy 348.683566 -173.498165)
			(xy 348.709048 -173.436632) (xy 348.742347 -173.378953) (xy 348.782893 -173.326117) (xy 348.829992 -173.279027)
			(xy 348.882836 -173.238492) (xy 348.911418 -173.221396) (xy 349.83547 -172.687742) (xy 349.864533 -172.671642)
			(xy 349.925937 -172.646271) (xy 349.990123 -172.629114) (xy 350.055996 -172.620463) (xy 350.089216 -172.619924)
			(xy 350.089724 -172.619924) (xy 350.120458 -172.620315) (xy 350.181477 -172.627727) (xy 350.241158 -172.64244)
			(xy 350.29863 -172.66424) (xy 350.353056 -172.692808) (xy 350.403641 -172.727729) (xy 350.449648 -172.768492)
			(xy 350.490406 -172.814503) (xy 350.525321 -172.865092) (xy 350.553883 -172.919521) (xy 350.575676 -172.976996)
			(xy 350.590383 -173.036678) (xy 350.597788 -173.097698) (xy 350.598232 -173.128432) (xy 350.597712 -173.161732)
			(xy 350.589036 -173.227763) (xy 350.571812 -173.292097) (xy 350.546334 -173.35363) (xy 350.513038 -173.411309)
			(xy 350.472496 -173.464145) (xy 350.4254 -173.511235) (xy 350.372559 -173.551772) (xy 350.343978 -173.568868)
			(xy 349.419926 -174.102522) (xy 349.390862 -174.11862) (xy 349.329459 -174.143992) (xy 349.265273 -174.16115)
			(xy 349.1994 -174.169802) (xy 349.16618 -174.17034) (xy 349.165672 -174.17034) (xy 349.134942 -174.16987)
			(xy 349.073929 -174.162459) (xy 349.014255 -174.147748) (xy 348.956789 -174.125953) (xy 348.902369 -174.097389)
			(xy 348.851788 -174.062475) (xy 348.805784 -174.021719) (xy 348.765027 -173.975715) (xy 348.730113 -173.925135)
			(xy 348.701549 -173.870715) (xy 348.679753 -173.813249) (xy 348.665041 -173.753575) (xy 348.65763 -173.692562)
			(xy 348.657164 -173.661832) (xy 2.509012 -173.661832) (xy 2.509012 -174.343568) (xy 373.398796 -174.343568)
			(xy 373.399226 -174.312836) (xy 373.406638 -174.251821) (xy 373.421351 -174.192144) (xy 373.443149 -174.134676)
			(xy 373.471715 -174.080254) (xy 373.506633 -174.029671) (xy 373.547392 -173.983667) (xy 373.5934 -173.94291)
			(xy 373.643984 -173.907996) (xy 373.698409 -173.879434) (xy 373.755879 -173.85764) (xy 373.815556 -173.842932)
			(xy 373.876572 -173.835524) (xy 373.907304 -173.83506) (xy 373.907812 -173.83506) (xy 373.941031 -173.835606)
			(xy 374.006903 -173.844264) (xy 374.071088 -173.861419) (xy 374.132496 -173.886778) (xy 374.161558 -173.902878)
			(xy 375.08561 -174.436532) (xy 375.114171 -174.453654) (xy 375.166997 -174.494201) (xy 375.214079 -174.541295)
			(xy 375.254613 -174.59413) (xy 375.287906 -174.651802) (xy 375.313388 -174.713326) (xy 375.330623 -174.777649)
			(xy 375.339318 -174.843672) (xy 375.339864 -174.876968) (xy 375.339432 -174.907701) (xy 375.332026 -174.96872)
			(xy 375.317319 -175.0284) (xy 375.295524 -175.085873) (xy 375.266961 -175.140299) (xy 375.232044 -175.190885)
			(xy 375.191284 -175.236893) (xy 375.145275 -175.277651) (xy 375.094689 -175.312567) (xy 375.040262 -175.341129)
			(xy 374.982789 -175.362923) (xy 374.923108 -175.377629) (xy 374.862089 -175.385033) (xy 374.831356 -175.385476)
			(xy 374.830848 -175.385476) (xy 374.797629 -175.384942) (xy 374.731757 -175.37628) (xy 374.667571 -175.359122)
			(xy 374.606164 -175.333759) (xy 374.577102 -175.317658) (xy 373.65305 -174.784004) (xy 373.624495 -174.766872)
			(xy 373.571672 -174.726325) (xy 373.524591 -174.679232) (xy 373.484057 -174.626398) (xy 373.450764 -174.568727)
			(xy 373.42528 -174.507205) (xy 373.408042 -174.442884) (xy 373.399344 -174.376863) (xy 373.398796 -174.343568)
			(xy 2.509012 -174.343568) (xy 2.509012 -175.83404) (xy 23.37714 -175.83404) (xy 23.381229 -175.778158)
			(xy 23.393412 -175.723468) (xy 23.413428 -175.671134) (xy 23.440851 -175.622272) (xy 23.475096 -175.577924)
			(xy 23.515432 -175.539034) (xy 23.561002 -175.506432) (xy 23.610833 -175.480813) (xy 23.663863 -175.462721)
			(xy 23.718961 -175.452544) (xy 23.774955 -175.450498) (xy 23.83065 -175.456626) (xy 23.884859 -175.470798)
			(xy 23.936427 -175.492712) (xy 23.984255 -175.521901) (xy 24.027323 -175.557742) (xy 24.064713 -175.599472)
			(xy 24.095629 -175.646202) (xy 24.119412 -175.696935) (xy 24.135554 -175.750591) (xy 24.143713 -175.806025)
			(xy 24.144224 -175.83404) (xy 24.143713 -175.862055) (xy 24.135554 -175.917489) (xy 24.119412 -175.971145)
			(xy 24.095629 -176.021878) (xy 24.064713 -176.068608) (xy 24.027323 -176.110338) (xy 23.984255 -176.146179)
			(xy 23.936427 -176.175368) (xy 23.884859 -176.197282) (xy 23.83065 -176.211454) (xy 23.774955 -176.217582)
			(xy 23.718961 -176.215536) (xy 23.663863 -176.205359) (xy 23.610833 -176.187267) (xy 23.561002 -176.161648)
			(xy 23.515432 -176.129046) (xy 23.475096 -176.090156) (xy 23.440851 -176.045808) (xy 23.413428 -175.996946)
			(xy 23.393412 -175.944612) (xy 23.381229 -175.889922) (xy 23.37714 -175.83404) (xy 2.509012 -175.83404)
			(xy 2.509012 -176.709832) (xy 348.657164 -176.709832) (xy 348.657658 -176.676531) (xy 348.666337 -176.610499)
			(xy 348.683566 -176.546165) (xy 348.709048 -176.484632) (xy 348.742347 -176.426953) (xy 348.782893 -176.374117)
			(xy 348.829992 -176.327027) (xy 348.882836 -176.286492) (xy 348.911418 -176.269396) (xy 349.83547 -175.735742)
			(xy 349.864533 -175.719642) (xy 349.925937 -175.694271) (xy 349.990123 -175.677114) (xy 350.055996 -175.668463)
			(xy 350.089216 -175.667924) (xy 350.089724 -175.667924) (xy 350.120458 -175.668315) (xy 350.121421 -175.668432)
			(xy 352.441764 -175.668432) (xy 352.442268 -175.637702) (xy 352.449672 -175.576689) (xy 352.464377 -175.517013)
			(xy 352.486168 -175.459545) (xy 352.514727 -175.405122) (xy 352.549637 -175.354539) (xy 352.59039 -175.308533)
			(xy 352.636392 -175.267774) (xy 352.686971 -175.232858) (xy 352.74139 -175.204292) (xy 352.798856 -175.182495)
			(xy 352.85853 -175.167783) (xy 352.919542 -175.160371) (xy 352.950272 -175.159924) (xy 352.95078 -175.159924)
			(xy 352.983998 -175.160489) (xy 353.049869 -175.169142) (xy 353.114055 -175.186291) (xy 353.175463 -175.211645)
			(xy 353.204526 -175.227742) (xy 354.128578 -175.761396) (xy 354.157139 -175.778518) (xy 354.209962 -175.819067)
			(xy 354.257042 -175.866162) (xy 354.297574 -175.918998) (xy 354.330866 -175.97667) (xy 354.3488 -176.019968)
			(xy 369.614196 -176.019968) (xy 369.614752 -175.98667) (xy 369.623426 -175.920641) (xy 369.640648 -175.85631)
			(xy 369.666122 -175.794779) (xy 369.699412 -175.737101) (xy 369.739949 -175.684263) (xy 369.787038 -175.637171)
			(xy 369.839873 -175.596631) (xy 369.86845 -175.579532) (xy 370.792502 -175.045878) (xy 370.82156 -175.029769)
			(xy 370.882966 -175.0044) (xy 370.947153 -174.987245) (xy 371.013028 -174.978597) (xy 371.046248 -174.97806)
			(xy 371.046756 -174.97806) (xy 371.077486 -174.978579) (xy 371.138498 -174.985982) (xy 371.198173 -175.000685)
			(xy 371.255641 -175.022475) (xy 371.310063 -175.051032) (xy 371.360647 -175.085941) (xy 371.406653 -175.126693)
			(xy 371.447412 -175.172694) (xy 371.482329 -175.223272) (xy 371.510894 -175.277689) (xy 371.532692 -175.335154)
			(xy 371.547404 -175.394827) (xy 371.554816 -175.455838) (xy 371.555264 -175.486568) (xy 371.554757 -175.519868)
			(xy 371.546077 -175.5859) (xy 371.543089 -175.597058) (xy 434.095902 -175.597058) (xy 434.099991 -175.541176)
			(xy 434.112174 -175.486486) (xy 434.13219 -175.434152) (xy 434.159613 -175.38529) (xy 434.193858 -175.340942)
			(xy 434.234194 -175.302052) (xy 434.279764 -175.26945) (xy 434.329595 -175.243831) (xy 434.382625 -175.225739)
			(xy 434.437723 -175.215562) (xy 434.493717 -175.213516) (xy 434.549412 -175.219644) (xy 434.603621 -175.233816)
			(xy 434.655189 -175.25573) (xy 434.703017 -175.284919) (xy 434.746085 -175.32076) (xy 434.783475 -175.36249)
			(xy 434.814391 -175.40922) (xy 434.838174 -175.459953) (xy 434.854316 -175.513609) (xy 434.862475 -175.569043)
			(xy 434.862986 -175.597058) (xy 434.862475 -175.625073) (xy 434.854316 -175.680507) (xy 434.838174 -175.734163)
			(xy 434.814391 -175.784896) (xy 434.783475 -175.831626) (xy 434.746085 -175.873356) (xy 434.703017 -175.909197)
			(xy 434.655189 -175.938386) (xy 434.603621 -175.9603) (xy 434.549412 -175.974472) (xy 434.493717 -175.9806)
			(xy 434.437723 -175.978554) (xy 434.382625 -175.968377) (xy 434.329595 -175.950285) (xy 434.279764 -175.924666)
			(xy 434.234194 -175.892064) (xy 434.193858 -175.853174) (xy 434.159613 -175.808826) (xy 434.13219 -175.759964)
			(xy 434.112174 -175.70763) (xy 434.099991 -175.65294) (xy 434.095902 -175.597058) (xy 371.543089 -175.597058)
			(xy 371.52885 -175.650232) (xy 371.503369 -175.711765) (xy 371.470072 -175.769443) (xy 371.429528 -175.82228)
			(xy 371.382432 -175.86937) (xy 371.329591 -175.909907) (xy 371.30101 -175.927004) (xy 370.376958 -176.460658)
			(xy 370.34791 -176.476786) (xy 370.2865 -176.50215) (xy 370.22231 -176.519299) (xy 370.156433 -176.527942)
			(xy 370.123212 -176.528476) (xy 370.122704 -176.528476) (xy 370.091971 -176.528059) (xy 370.030952 -176.52065)
			(xy 369.971272 -176.50594) (xy 369.9138 -176.484143) (xy 369.859375 -176.455577) (xy 369.808789 -176.420659)
			(xy 369.762782 -176.379898) (xy 369.722023 -176.333889) (xy 369.687108 -176.283301) (xy 369.658546 -176.228874)
			(xy 369.636752 -176.171401) (xy 369.622045 -176.11172) (xy 369.61464 -176.050701) (xy 369.614196 -176.019968)
			(xy 354.3488 -176.019968) (xy 354.356349 -176.038193) (xy 354.373586 -176.102515) (xy 354.382284 -176.168536)
			(xy 354.382832 -176.201832) (xy 354.382374 -176.232563) (xy 354.374962 -176.293576) (xy 354.360251 -176.353251)
			(xy 354.338454 -176.410717) (xy 354.30989 -176.465138) (xy 354.274975 -176.515719) (xy 354.234218 -176.561723)
			(xy 354.188213 -176.60248) (xy 354.137631 -176.637394) (xy 354.08321 -176.665957) (xy 354.025743 -176.687753)
			(xy 353.966068 -176.702464) (xy 353.905055 -176.709875) (xy 353.874324 -176.71034) (xy 353.873816 -176.71034)
			(xy 353.840597 -176.709782) (xy 353.774726 -176.701127) (xy 353.710541 -176.683976) (xy 353.649132 -176.658621)
			(xy 353.62007 -176.642522) (xy 352.696018 -176.108868) (xy 352.667463 -176.091735) (xy 352.614637 -176.051191)
			(xy 352.567553 -176.004099) (xy 352.527018 -175.951266) (xy 352.493724 -175.893595) (xy 352.468241 -175.832072)
			(xy 352.451005 -175.76775) (xy 352.44231 -175.701728) (xy 352.441764 -175.668432) (xy 350.121421 -175.668432)
			(xy 350.181477 -175.675727) (xy 350.241158 -175.69044) (xy 350.29863 -175.71224) (xy 350.353056 -175.740808)
			(xy 350.403641 -175.775729) (xy 350.449648 -175.816492) (xy 350.490406 -175.862503) (xy 350.525321 -175.913092)
			(xy 350.553883 -175.967521) (xy 350.575676 -176.024996) (xy 350.590383 -176.084678) (xy 350.597788 -176.145698)
			(xy 350.598232 -176.176432) (xy 350.597712 -176.209732) (xy 350.589036 -176.275763) (xy 350.571812 -176.340097)
			(xy 350.546334 -176.40163) (xy 350.513038 -176.459309) (xy 350.472496 -176.512145) (xy 350.4254 -176.559235)
			(xy 350.372559 -176.599772) (xy 350.343978 -176.616868) (xy 349.419926 -177.150522) (xy 349.390862 -177.16662)
			(xy 349.329459 -177.191992) (xy 349.265273 -177.20915) (xy 349.1994 -177.217802) (xy 349.16618 -177.21834)
			(xy 349.165672 -177.21834) (xy 349.134942 -177.21787) (xy 349.073929 -177.210459) (xy 349.014255 -177.195748)
			(xy 348.956789 -177.173953) (xy 348.902369 -177.145389) (xy 348.851788 -177.110475) (xy 348.805784 -177.069719)
			(xy 348.765027 -177.023715) (xy 348.730113 -176.973135) (xy 348.701549 -176.918715) (xy 348.679753 -176.861249)
			(xy 348.665041 -176.801575) (xy 348.65763 -176.740562) (xy 348.657164 -176.709832) (xy 2.509012 -176.709832)
			(xy 2.509012 -179.757832) (xy 348.657164 -179.757832) (xy 348.657658 -179.724531) (xy 348.666337 -179.658499)
			(xy 348.683566 -179.594165) (xy 348.709048 -179.532632) (xy 348.742347 -179.474953) (xy 348.782893 -179.422117)
			(xy 348.829992 -179.375027) (xy 348.882836 -179.334492) (xy 348.911418 -179.317396) (xy 349.83547 -178.783742)
			(xy 349.864533 -178.767642) (xy 349.925937 -178.742271) (xy 349.990123 -178.725114) (xy 350.055996 -178.716463)
			(xy 350.089216 -178.715924) (xy 350.089724 -178.715924) (xy 350.120458 -178.716315) (xy 350.181477 -178.723727)
			(xy 350.241158 -178.73844) (xy 350.29863 -178.76024) (xy 350.353056 -178.788808) (xy 350.403641 -178.823729)
			(xy 350.449648 -178.864492) (xy 350.490406 -178.910503) (xy 350.525321 -178.961092) (xy 350.553883 -179.015521)
			(xy 350.575676 -179.072996) (xy 350.590383 -179.132678) (xy 350.597788 -179.193698) (xy 350.598232 -179.224432)
			(xy 350.597712 -179.257732) (xy 350.589036 -179.323763) (xy 350.581628 -179.351432) (xy 352.441764 -179.351432)
			(xy 352.442268 -179.320702) (xy 352.449672 -179.259689) (xy 352.464377 -179.200013) (xy 352.486168 -179.142545)
			(xy 352.514727 -179.088122) (xy 352.549637 -179.037539) (xy 352.59039 -178.991533) (xy 352.636392 -178.950774)
			(xy 352.686971 -178.915858) (xy 352.74139 -178.887292) (xy 352.798856 -178.865495) (xy 352.85853 -178.850783)
			(xy 352.919542 -178.843371) (xy 352.950272 -178.842924) (xy 352.95078 -178.842924) (xy 352.983998 -178.843489)
			(xy 353.049869 -178.852142) (xy 353.114055 -178.869291) (xy 353.175463 -178.894645) (xy 353.204526 -178.910742)
			(xy 353.476772 -179.067968) (xy 369.614196 -179.067968) (xy 369.614752 -179.03467) (xy 369.623426 -178.968641)
			(xy 369.640648 -178.90431) (xy 369.666122 -178.842779) (xy 369.699412 -178.785101) (xy 369.739949 -178.732263)
			(xy 369.787038 -178.685171) (xy 369.839873 -178.644631) (xy 369.86845 -178.627532) (xy 370.792502 -178.093878)
			(xy 370.82156 -178.077769) (xy 370.882966 -178.0524) (xy 370.947153 -178.035245) (xy 371.013028 -178.026597)
			(xy 371.046248 -178.02606) (xy 371.046756 -178.02606) (xy 371.076835 -178.026568) (xy 373.398796 -178.026568)
			(xy 373.399226 -177.995836) (xy 373.406638 -177.934821) (xy 373.421351 -177.875144) (xy 373.443149 -177.817676)
			(xy 373.471715 -177.763254) (xy 373.506633 -177.712671) (xy 373.547392 -177.666667) (xy 373.5934 -177.62591)
			(xy 373.643984 -177.590996) (xy 373.698409 -177.562434) (xy 373.755879 -177.54064) (xy 373.815556 -177.525932)
			(xy 373.876572 -177.518524) (xy 373.907304 -177.51806) (xy 373.907812 -177.51806) (xy 373.941031 -177.518606)
			(xy 374.006903 -177.527264) (xy 374.071088 -177.544419) (xy 374.132496 -177.569778) (xy 374.161558 -177.585878)
			(xy 375.08561 -178.119532) (xy 375.114171 -178.136654) (xy 375.166997 -178.177201) (xy 375.214079 -178.224295)
			(xy 375.254613 -178.27713) (xy 375.287906 -178.334802) (xy 375.313388 -178.396326) (xy 375.330623 -178.460649)
			(xy 375.339318 -178.526672) (xy 375.339864 -178.559968) (xy 375.339432 -178.590701) (xy 375.332026 -178.65172)
			(xy 375.317319 -178.7114) (xy 375.295524 -178.768873) (xy 375.266961 -178.823299) (xy 375.232044 -178.873885)
			(xy 375.191284 -178.919893) (xy 375.145275 -178.960651) (xy 375.094689 -178.995567) (xy 375.040262 -179.024129)
			(xy 374.982789 -179.045923) (xy 374.923108 -179.060629) (xy 374.862089 -179.068033) (xy 374.831356 -179.068476)
			(xy 374.830848 -179.068476) (xy 374.797629 -179.067942) (xy 374.731757 -179.05928) (xy 374.667571 -179.042122)
			(xy 374.606164 -179.016759) (xy 374.577102 -179.000658) (xy 373.65305 -178.467004) (xy 373.624495 -178.449872)
			(xy 373.571672 -178.409325) (xy 373.524591 -178.362232) (xy 373.484057 -178.309398) (xy 373.450764 -178.251727)
			(xy 373.42528 -178.190205) (xy 373.408042 -178.125884) (xy 373.399344 -178.059863) (xy 373.398796 -178.026568)
			(xy 371.076835 -178.026568) (xy 371.077486 -178.026579) (xy 371.138498 -178.033982) (xy 371.198173 -178.048685)
			(xy 371.255641 -178.070475) (xy 371.310063 -178.099032) (xy 371.360647 -178.133941) (xy 371.406653 -178.174693)
			(xy 371.447412 -178.220694) (xy 371.482329 -178.271272) (xy 371.510894 -178.325689) (xy 371.532692 -178.383154)
			(xy 371.547404 -178.442827) (xy 371.554816 -178.503838) (xy 371.555264 -178.534568) (xy 371.554757 -178.567868)
			(xy 371.546077 -178.6339) (xy 371.52885 -178.698232) (xy 371.503369 -178.759765) (xy 371.470072 -178.817443)
			(xy 371.429528 -178.87028) (xy 371.382432 -178.91737) (xy 371.329591 -178.957907) (xy 371.30101 -178.975004)
			(xy 370.376958 -179.508658) (xy 370.34791 -179.524786) (xy 370.2865 -179.55015) (xy 370.22231 -179.567299)
			(xy 370.156433 -179.575942) (xy 370.123212 -179.576476) (xy 370.122704 -179.576476) (xy 370.091971 -179.576059)
			(xy 370.030952 -179.56865) (xy 369.971272 -179.55394) (xy 369.9138 -179.532143) (xy 369.859375 -179.503577)
			(xy 369.808789 -179.468659) (xy 369.762782 -179.427898) (xy 369.722023 -179.381889) (xy 369.687108 -179.331301)
			(xy 369.658546 -179.276874) (xy 369.636752 -179.219401) (xy 369.622045 -179.15972) (xy 369.61464 -179.098701)
			(xy 369.614196 -179.067968) (xy 353.476772 -179.067968) (xy 354.128578 -179.444396) (xy 354.157139 -179.461518)
			(xy 354.209962 -179.502067) (xy 354.257042 -179.549162) (xy 354.297574 -179.601998) (xy 354.330866 -179.65967)
			(xy 354.356349 -179.721193) (xy 354.373586 -179.785515) (xy 354.382284 -179.851536) (xy 354.382832 -179.884832)
			(xy 354.382374 -179.915563) (xy 354.374962 -179.976576) (xy 354.360251 -180.036251) (xy 354.338454 -180.093717)
			(xy 354.30989 -180.148138) (xy 354.274975 -180.198719) (xy 354.234218 -180.244723) (xy 354.188213 -180.28548)
			(xy 354.137631 -180.320394) (xy 354.08321 -180.348957) (xy 354.025743 -180.370753) (xy 353.966068 -180.385464)
			(xy 353.905055 -180.392875) (xy 353.874324 -180.39334) (xy 353.873816 -180.39334) (xy 353.840597 -180.392782)
			(xy 353.774726 -180.384127) (xy 353.710541 -180.366976) (xy 353.649132 -180.341621) (xy 353.62007 -180.325522)
			(xy 352.696018 -179.791868) (xy 352.667463 -179.774735) (xy 352.614637 -179.734191) (xy 352.567553 -179.687099)
			(xy 352.527018 -179.634266) (xy 352.493724 -179.576595) (xy 352.468241 -179.515072) (xy 352.451005 -179.45075)
			(xy 352.44231 -179.384728) (xy 352.441764 -179.351432) (xy 350.581628 -179.351432) (xy 350.571812 -179.388097)
			(xy 350.546334 -179.44963) (xy 350.513038 -179.507309) (xy 350.472496 -179.560145) (xy 350.4254 -179.607235)
			(xy 350.372559 -179.647772) (xy 350.343978 -179.664868) (xy 349.419926 -180.198522) (xy 349.390862 -180.21462)
			(xy 349.329459 -180.239992) (xy 349.265273 -180.25715) (xy 349.1994 -180.265802) (xy 349.16618 -180.26634)
			(xy 349.165672 -180.26634) (xy 349.134942 -180.26587) (xy 349.073929 -180.258459) (xy 349.014255 -180.243748)
			(xy 348.956789 -180.221953) (xy 348.902369 -180.193389) (xy 348.851788 -180.158475) (xy 348.805784 -180.117719)
			(xy 348.765027 -180.071715) (xy 348.730113 -180.021135) (xy 348.701549 -179.966715) (xy 348.679753 -179.909249)
			(xy 348.665041 -179.849575) (xy 348.65763 -179.788562) (xy 348.657164 -179.757832) (xy 2.509012 -179.757832)
			(xy 2.509012 -182.805832) (xy 348.657164 -182.805832) (xy 348.657658 -182.772531) (xy 348.666337 -182.706499)
			(xy 348.683566 -182.642165) (xy 348.709048 -182.580632) (xy 348.742347 -182.522953) (xy 348.782893 -182.470117)
			(xy 348.829992 -182.423027) (xy 348.882836 -182.382492) (xy 348.911418 -182.365396) (xy 349.83547 -181.831742)
			(xy 349.864533 -181.815642) (xy 349.925937 -181.790271) (xy 349.990123 -181.773114) (xy 350.055996 -181.764463)
			(xy 350.089216 -181.763924) (xy 350.089724 -181.763924) (xy 350.120458 -181.764315) (xy 350.181477 -181.771727)
			(xy 350.241158 -181.78644) (xy 350.29863 -181.80824) (xy 350.353056 -181.836808) (xy 350.403641 -181.871729)
			(xy 350.449648 -181.912492) (xy 350.490406 -181.958503) (xy 350.525321 -182.009092) (xy 350.553883 -182.063521)
			(xy 350.57377 -182.115968) (xy 369.614196 -182.115968) (xy 369.614752 -182.08267) (xy 369.623426 -182.016641)
			(xy 369.640648 -181.95231) (xy 369.666122 -181.890779) (xy 369.699412 -181.833101) (xy 369.739949 -181.780263)
			(xy 369.787038 -181.733171) (xy 369.839873 -181.692631) (xy 369.86845 -181.675532) (xy 370.792502 -181.141878)
			(xy 370.82156 -181.125769) (xy 370.882966 -181.1004) (xy 370.947153 -181.083245) (xy 371.013028 -181.074597)
			(xy 371.046248 -181.07406) (xy 371.046756 -181.07406) (xy 371.077486 -181.074579) (xy 371.138498 -181.081982)
			(xy 371.198173 -181.096685) (xy 371.255641 -181.118475) (xy 371.310063 -181.147032) (xy 371.360647 -181.181941)
			(xy 371.406653 -181.222693) (xy 371.447412 -181.268694) (xy 371.482329 -181.319272) (xy 371.510894 -181.373689)
			(xy 371.532692 -181.431154) (xy 371.547404 -181.490827) (xy 371.554816 -181.551838) (xy 371.555264 -181.582568)
			(xy 371.554757 -181.615868) (xy 371.546077 -181.6819) (xy 371.538668 -181.709568) (xy 373.398796 -181.709568)
			(xy 373.399226 -181.678836) (xy 373.406638 -181.617821) (xy 373.421351 -181.558144) (xy 373.443149 -181.500676)
			(xy 373.471715 -181.446254) (xy 373.506633 -181.395671) (xy 373.547392 -181.349667) (xy 373.5934 -181.30891)
			(xy 373.643984 -181.273996) (xy 373.698409 -181.245434) (xy 373.755879 -181.22364) (xy 373.815556 -181.208932)
			(xy 373.876572 -181.201524) (xy 373.907304 -181.20106) (xy 373.907812 -181.20106) (xy 373.941031 -181.201606)
			(xy 374.006903 -181.210264) (xy 374.071088 -181.227419) (xy 374.132496 -181.252778) (xy 374.161558 -181.268878)
			(xy 375.08561 -181.802532) (xy 375.114171 -181.819654) (xy 375.166997 -181.860201) (xy 375.214079 -181.907295)
			(xy 375.254613 -181.96013) (xy 375.287906 -182.017802) (xy 375.313388 -182.079326) (xy 375.330623 -182.143649)
			(xy 375.339318 -182.209672) (xy 375.339864 -182.242968) (xy 375.339432 -182.273701) (xy 375.332026 -182.33472)
			(xy 375.317319 -182.3944) (xy 375.295524 -182.451873) (xy 375.266961 -182.506299) (xy 375.232044 -182.556885)
			(xy 375.191284 -182.602893) (xy 375.145275 -182.643651) (xy 375.094689 -182.678567) (xy 375.040262 -182.707129)
			(xy 374.982789 -182.728923) (xy 374.923108 -182.743629) (xy 374.862089 -182.751033) (xy 374.831356 -182.751476)
			(xy 374.830848 -182.751476) (xy 374.797629 -182.750942) (xy 374.731757 -182.74228) (xy 374.667571 -182.725122)
			(xy 374.606164 -182.699759) (xy 374.577102 -182.683658) (xy 373.65305 -182.150004) (xy 373.624495 -182.132872)
			(xy 373.571672 -182.092325) (xy 373.524591 -182.045232) (xy 373.484057 -181.992398) (xy 373.450764 -181.934727)
			(xy 373.42528 -181.873205) (xy 373.408042 -181.808884) (xy 373.399344 -181.742863) (xy 373.398796 -181.709568)
			(xy 371.538668 -181.709568) (xy 371.52885 -181.746232) (xy 371.503369 -181.807765) (xy 371.470072 -181.865443)
			(xy 371.429528 -181.91828) (xy 371.382432 -181.96537) (xy 371.329591 -182.005907) (xy 371.30101 -182.023004)
			(xy 370.376958 -182.556658) (xy 370.34791 -182.572786) (xy 370.2865 -182.59815) (xy 370.22231 -182.615299)
			(xy 370.156433 -182.623942) (xy 370.123212 -182.624476) (xy 370.122704 -182.624476) (xy 370.091971 -182.624059)
			(xy 370.030952 -182.61665) (xy 369.971272 -182.60194) (xy 369.9138 -182.580143) (xy 369.859375 -182.551577)
			(xy 369.808789 -182.516659) (xy 369.762782 -182.475898) (xy 369.722023 -182.429889) (xy 369.687108 -182.379301)
			(xy 369.658546 -182.324874) (xy 369.636752 -182.267401) (xy 369.622045 -182.20772) (xy 369.61464 -182.146701)
			(xy 369.614196 -182.115968) (xy 350.57377 -182.115968) (xy 350.575676 -182.120996) (xy 350.590383 -182.180678)
			(xy 350.597788 -182.241698) (xy 350.598232 -182.272432) (xy 350.597712 -182.305732) (xy 350.589036 -182.371763)
			(xy 350.571812 -182.436097) (xy 350.546334 -182.49763) (xy 350.513038 -182.555309) (xy 350.472496 -182.608145)
			(xy 350.4254 -182.655235) (xy 350.372559 -182.695772) (xy 350.343978 -182.712868) (xy 349.775297 -183.04129)
			(xy 352.441764 -183.04129) (xy 352.442192 -183.010552) (xy 352.449601 -182.949525) (xy 352.46431 -182.889835)
			(xy 352.486105 -182.832352) (xy 352.514667 -182.777914) (xy 352.549581 -182.727315) (xy 352.590338 -182.681292)
			(xy 352.636344 -182.640516) (xy 352.686928 -182.60558) (xy 352.741353 -182.576994) (xy 352.798826 -182.555175)
			(xy 352.85851 -182.540441) (xy 352.919534 -182.533005) (xy 352.950272 -182.532528) (xy 352.95078 -182.532528)
			(xy 352.984007 -182.533118) (xy 353.049889 -182.541823) (xy 353.114077 -182.559036) (xy 353.175475 -182.584464)
			(xy 353.204526 -182.6006) (xy 354.128578 -183.134254) (xy 354.157165 -183.151335) (xy 354.209988 -183.19189)
			(xy 354.257067 -183.238991) (xy 354.297597 -183.291832) (xy 354.330886 -183.34951) (xy 354.356365 -183.411039)
			(xy 354.373597 -183.475367) (xy 354.382288 -183.541392) (xy 354.382832 -183.57469) (xy 354.382389 -183.605428)
			(xy 354.374982 -183.666455) (xy 354.360275 -183.726145) (xy 354.338483 -183.783627) (xy 354.309922 -183.838065)
			(xy 354.275009 -183.888665) (xy 354.234254 -183.934688) (xy 354.188249 -183.975465) (xy 354.137666 -184.010401)
			(xy 354.083241 -184.038987) (xy 354.025768 -184.060806) (xy 353.966085 -184.07554) (xy 353.905061 -184.082975)
			(xy 353.874324 -184.083452) (xy 353.873816 -184.083452) (xy 353.840589 -184.082867) (xy 353.774706 -184.07416)
			(xy 353.710519 -184.056946) (xy 353.649121 -184.031517) (xy 353.62007 -184.01538) (xy 352.696018 -183.481726)
			(xy 352.667489 -183.464552) (xy 352.614663 -183.424014) (xy 352.567578 -183.376928) (xy 352.527041 -183.324101)
			(xy 352.493744 -183.266436) (xy 352.468257 -183.204918) (xy 352.451015 -183.140601) (xy 352.442314 -183.074584)
			(xy 352.441764 -183.04129) (xy 349.775297 -183.04129) (xy 349.419926 -183.246522) (xy 349.390862 -183.26262)
			(xy 349.329459 -183.287992) (xy 349.265273 -183.30515) (xy 349.1994 -183.313802) (xy 349.16618 -183.31434)
			(xy 349.165672 -183.31434) (xy 349.134942 -183.31387) (xy 349.073929 -183.306459) (xy 349.014255 -183.291748)
			(xy 348.956789 -183.269953) (xy 348.902369 -183.241389) (xy 348.851788 -183.206475) (xy 348.805784 -183.165719)
			(xy 348.765027 -183.119715) (xy 348.730113 -183.069135) (xy 348.701549 -183.014715) (xy 348.679753 -182.957249)
			(xy 348.665041 -182.897575) (xy 348.65763 -182.836562) (xy 348.657164 -182.805832) (xy 2.509012 -182.805832)
			(xy 2.509012 -185.011568) (xy 372.585996 -185.011568) (xy 372.586426 -184.980836) (xy 372.593838 -184.919821)
			(xy 372.608551 -184.860144) (xy 372.630349 -184.802676) (xy 372.658915 -184.748254) (xy 372.693833 -184.697671)
			(xy 372.734592 -184.651667) (xy 372.7806 -184.61091) (xy 372.831184 -184.575996) (xy 372.885609 -184.547434)
			(xy 372.943079 -184.52564) (xy 373.002756 -184.510932) (xy 373.063772 -184.503524) (xy 373.094504 -184.50306)
			(xy 373.095012 -184.50306) (xy 373.128231 -184.503606) (xy 373.194103 -184.512264) (xy 373.258288 -184.529419)
			(xy 373.319696 -184.554778) (xy 373.348758 -184.570878) (xy 374.27281 -185.104532) (xy 374.301371 -185.121654)
			(xy 374.354197 -185.162201) (xy 374.401279 -185.209295) (xy 374.441813 -185.26213) (xy 374.475106 -185.319802)
			(xy 374.500588 -185.381326) (xy 374.517823 -185.445649) (xy 374.526518 -185.511672) (xy 374.527064 -185.544968)
			(xy 374.526632 -185.575701) (xy 374.519226 -185.63672) (xy 374.504519 -185.6964) (xy 374.482724 -185.753873)
			(xy 374.454161 -185.808299) (xy 374.419244 -185.858885) (xy 374.378484 -185.904893) (xy 374.332475 -185.945651)
			(xy 374.281889 -185.980567) (xy 374.227462 -186.009129) (xy 374.169989 -186.030923) (xy 374.110308 -186.045629)
			(xy 374.049289 -186.053033) (xy 374.018556 -186.053476) (xy 374.018048 -186.053476) (xy 373.984829 -186.052942)
			(xy 373.918957 -186.04428) (xy 373.854771 -186.027122) (xy 373.793364 -186.001759) (xy 373.764302 -185.985658)
			(xy 372.84025 -185.452004) (xy 372.811695 -185.434872) (xy 372.758872 -185.394325) (xy 372.711791 -185.347232)
			(xy 372.671257 -185.294398) (xy 372.637964 -185.236727) (xy 372.61248 -185.175205) (xy 372.595242 -185.110884)
			(xy 372.586544 -185.044863) (xy 372.585996 -185.011568) (xy 2.509012 -185.011568) (xy 2.509012 -186.714892)
			(xy 351.367344 -186.714892) (xy 351.367848 -186.684163) (xy 351.375257 -186.623152) (xy 351.389965 -186.563479)
			(xy 351.411758 -186.506014) (xy 351.440318 -186.451595) (xy 351.475229 -186.401014) (xy 351.515982 -186.355011)
			(xy 351.561983 -186.314254) (xy 351.612561 -186.279339) (xy 351.666978 -186.250774) (xy 351.724441 -186.228977)
			(xy 351.784113 -186.214264) (xy 351.845123 -186.206851) (xy 351.875852 -186.206384) (xy 351.87636 -186.206384)
			(xy 351.90958 -186.206906) (xy 351.975453 -186.215571) (xy 352.039638 -186.232732) (xy 352.101045 -186.258098)
			(xy 352.130106 -186.274202) (xy 353.054158 -186.807856) (xy 353.082741 -186.824943) (xy 353.135565 -186.865496)
			(xy 353.182645 -186.912596) (xy 353.223176 -186.965436) (xy 353.256466 -187.023114) (xy 353.281945 -187.084642)
			(xy 353.299177 -187.148969) (xy 353.307868 -187.214995) (xy 353.308412 -187.248292) (xy 353.307955 -187.279024)
			(xy 353.300547 -187.340039) (xy 353.285839 -187.399717) (xy 353.264044 -187.457187) (xy 353.235482 -187.51161)
			(xy 353.200567 -187.562194) (xy 353.15981 -187.608201) (xy 353.113804 -187.648959) (xy 353.063221 -187.683875)
			(xy 353.008798 -187.712439) (xy 352.951329 -187.734235) (xy 352.891651 -187.748945) (xy 352.830636 -187.756354)
			(xy 352.799904 -187.7568) (xy 352.799396 -187.7568) (xy 352.766177 -187.756256) (xy 352.700305 -187.747598)
			(xy 352.636119 -187.730443) (xy 352.574711 -187.705083) (xy 352.54565 -187.688982) (xy 351.621598 -187.155328)
			(xy 351.593065 -187.13816) (xy 351.54024 -187.09762) (xy 351.493156 -187.050533) (xy 351.45262 -186.997705)
			(xy 351.419323 -186.940039) (xy 351.393837 -186.878521) (xy 351.376595 -186.814204) (xy 351.367894 -186.748186)
			(xy 351.367344 -186.714892) (xy 2.509012 -186.714892) (xy 2.509012 -195.821554) (xy 11.489436 -195.821554)
			(xy 11.489436 -195.412614) (xy 11.489875 -195.402444) (xy 11.497655 -195.383649) (xy 11.512036 -195.369264)
			(xy 11.530828 -195.361478) (xy 11.540998 -195.361052) (xy 12.940538 -195.361052) (xy 12.9507 -195.361503)
			(xy 12.969473 -195.369292) (xy 12.983837 -195.383671) (xy 12.991608 -195.402452) (xy 12.9921 -195.412614)
			(xy 12.9921 -195.821554) (xy 19.033236 -195.821554) (xy 19.033236 -195.412614) (xy 19.033675 -195.402444)
			(xy 19.041455 -195.383649) (xy 19.055836 -195.369264) (xy 19.074628 -195.361478) (xy 19.084798 -195.361052)
			(xy 20.484338 -195.361052) (xy 20.4945 -195.361503) (xy 20.513273 -195.369292) (xy 20.527637 -195.383671)
			(xy 20.535408 -195.402452) (xy 20.5359 -195.412614) (xy 20.5359 -195.821554) (xy 26.577036 -195.821554)
			(xy 26.577036 -195.412614) (xy 26.577475 -195.402444) (xy 26.585255 -195.383649) (xy 26.599636 -195.369264)
			(xy 26.618428 -195.361478) (xy 26.628598 -195.361052) (xy 28.028138 -195.361052) (xy 28.0383 -195.361503)
			(xy 28.057073 -195.369292) (xy 28.071437 -195.383671) (xy 28.079208 -195.402452) (xy 28.0797 -195.412614)
			(xy 28.0797 -195.821554) (xy 34.120836 -195.821554) (xy 34.120836 -195.412614) (xy 34.121275 -195.402444)
			(xy 34.129055 -195.383649) (xy 34.143436 -195.369264) (xy 34.162228 -195.361478) (xy 34.172398 -195.361052)
			(xy 35.571938 -195.361052) (xy 35.5821 -195.361503) (xy 35.600873 -195.369292) (xy 35.615237 -195.383671)
			(xy 35.623008 -195.402452) (xy 35.6235 -195.412614) (xy 35.6235 -195.821554) (xy 41.664636 -195.821554)
			(xy 41.664636 -195.412614) (xy 41.665075 -195.402444) (xy 41.672855 -195.383649) (xy 41.687236 -195.369264)
			(xy 41.706028 -195.361478) (xy 41.716198 -195.361052) (xy 43.115738 -195.361052) (xy 43.1259 -195.361503)
			(xy 43.144673 -195.369292) (xy 43.159037 -195.383671) (xy 43.166808 -195.402452) (xy 43.1673 -195.412614)
			(xy 43.1673 -195.821554) (xy 49.208436 -195.821554) (xy 49.208436 -195.412614) (xy 49.208875 -195.402444)
			(xy 49.216655 -195.383649) (xy 49.231036 -195.369264) (xy 49.249828 -195.361478) (xy 49.259998 -195.361052)
			(xy 50.659538 -195.361052) (xy 50.6697 -195.361503) (xy 50.688473 -195.369292) (xy 50.702837 -195.383671)
			(xy 50.710608 -195.402452) (xy 50.7111 -195.412614) (xy 50.7111 -195.821554) (xy 56.752236 -195.821554)
			(xy 56.752236 -195.412614) (xy 56.752675 -195.402444) (xy 56.760455 -195.383649) (xy 56.774836 -195.369264)
			(xy 56.793628 -195.361478) (xy 56.803798 -195.361052) (xy 58.203338 -195.361052) (xy 58.2135 -195.361503)
			(xy 58.232273 -195.369292) (xy 58.246637 -195.383671) (xy 58.254408 -195.402452) (xy 58.2549 -195.412614)
			(xy 58.2549 -195.821554) (xy 64.296036 -195.821554) (xy 64.296036 -195.412614) (xy 64.296475 -195.402444)
			(xy 64.304255 -195.383649) (xy 64.318636 -195.369264) (xy 64.337428 -195.361478) (xy 64.347598 -195.361052)
			(xy 65.747138 -195.361052) (xy 65.7573 -195.361503) (xy 65.776073 -195.369292) (xy 65.790437 -195.383671)
			(xy 65.798208 -195.402452) (xy 65.7987 -195.412614) (xy 65.7987 -195.821554) (xy 162.162236 -195.821554)
			(xy 162.162236 -195.412614) (xy 162.162675 -195.402444) (xy 162.170455 -195.383649) (xy 162.184836 -195.369264)
			(xy 162.203628 -195.361478) (xy 162.213798 -195.361052) (xy 163.613338 -195.361052) (xy 163.6235 -195.361503)
			(xy 163.642273 -195.369292) (xy 163.656637 -195.383671) (xy 163.664408 -195.402452) (xy 163.6649 -195.412614)
			(xy 163.6649 -195.821554) (xy 169.706036 -195.821554) (xy 169.706036 -195.412614) (xy 169.706475 -195.402444)
			(xy 169.714255 -195.383649) (xy 169.728636 -195.369264) (xy 169.747428 -195.361478) (xy 169.757598 -195.361052)
			(xy 171.157138 -195.361052) (xy 171.1673 -195.361503) (xy 171.186073 -195.369292) (xy 171.200437 -195.383671)
			(xy 171.208208 -195.402452) (xy 171.2087 -195.412614) (xy 171.2087 -195.821554) (xy 177.249836 -195.821554)
			(xy 177.249836 -195.412614) (xy 177.250275 -195.402444) (xy 177.258055 -195.383649) (xy 177.272436 -195.369264)
			(xy 177.291228 -195.361478) (xy 177.301398 -195.361052) (xy 178.700938 -195.361052) (xy 178.7111 -195.361503)
			(xy 178.729873 -195.369292) (xy 178.744237 -195.383671) (xy 178.752008 -195.402452) (xy 178.7525 -195.412614)
			(xy 178.7525 -195.821554) (xy 184.793636 -195.821554) (xy 184.793636 -195.412614) (xy 184.794075 -195.402444)
			(xy 184.801855 -195.383649) (xy 184.816236 -195.369264) (xy 184.835028 -195.361478) (xy 184.845198 -195.361052)
			(xy 186.244738 -195.361052) (xy 186.2549 -195.361503) (xy 186.273673 -195.369292) (xy 186.288037 -195.383671)
			(xy 186.295808 -195.402452) (xy 186.2963 -195.412614) (xy 186.2963 -195.821554) (xy 192.337436 -195.821554)
			(xy 192.337436 -195.412614) (xy 192.337875 -195.402444) (xy 192.345655 -195.383649) (xy 192.360036 -195.369264)
			(xy 192.378828 -195.361478) (xy 192.388998 -195.361052) (xy 193.788538 -195.361052) (xy 193.7987 -195.361503)
			(xy 193.817473 -195.369292) (xy 193.831837 -195.383671) (xy 193.839608 -195.402452) (xy 193.8401 -195.412614)
			(xy 193.8401 -195.821554) (xy 199.881236 -195.821554) (xy 199.881236 -195.412614) (xy 199.881675 -195.402444)
			(xy 199.889455 -195.383649) (xy 199.903836 -195.369264) (xy 199.922628 -195.361478) (xy 199.932798 -195.361052)
			(xy 201.332338 -195.361052) (xy 201.3425 -195.361503) (xy 201.361273 -195.369292) (xy 201.375637 -195.383671)
			(xy 201.383408 -195.402452) (xy 201.3839 -195.412614) (xy 201.3839 -195.821554) (xy 207.425036 -195.821554)
			(xy 207.425036 -195.412614) (xy 207.425475 -195.402444) (xy 207.433255 -195.383649) (xy 207.447636 -195.369264)
			(xy 207.466428 -195.361478) (xy 207.476598 -195.361052) (xy 208.876138 -195.361052) (xy 208.8863 -195.361503)
			(xy 208.905073 -195.369292) (xy 208.919437 -195.383671) (xy 208.927208 -195.402452) (xy 208.9277 -195.412614)
			(xy 208.9277 -195.821554) (xy 214.968836 -195.821554) (xy 214.968836 -195.412614) (xy 214.969275 -195.402444)
			(xy 214.977055 -195.383649) (xy 214.991436 -195.369264) (xy 215.010228 -195.361478) (xy 215.020398 -195.361052)
			(xy 216.419938 -195.361052) (xy 216.4301 -195.361503) (xy 216.448873 -195.369292) (xy 216.463237 -195.383671)
			(xy 216.471008 -195.402452) (xy 216.4715 -195.412614) (xy 216.4715 -195.821554) (xy 259.429504 -195.821554)
			(xy 259.429504 -195.412614) (xy 259.430044 -195.402461) (xy 259.437807 -195.383699) (xy 259.452159 -195.369334)
			(xy 259.470914 -195.361553) (xy 259.481066 -195.361052) (xy 260.880606 -195.361052) (xy 260.89078 -195.361459)
			(xy 260.909577 -195.369249) (xy 260.923962 -195.38364) (xy 260.931745 -195.40244) (xy 260.932168 -195.412614)
			(xy 260.932168 -195.821554) (xy 266.973304 -195.821554) (xy 266.973304 -195.412614) (xy 266.973844 -195.402461)
			(xy 266.981607 -195.383699) (xy 266.995959 -195.369334) (xy 267.014714 -195.361553) (xy 267.024866 -195.361052)
			(xy 268.424406 -195.361052) (xy 268.43458 -195.361459) (xy 268.453377 -195.369249) (xy 268.467762 -195.38364)
			(xy 268.475545 -195.40244) (xy 268.475968 -195.412614) (xy 268.475968 -195.821554) (xy 274.517104 -195.821554)
			(xy 274.517104 -195.412614) (xy 274.517644 -195.402461) (xy 274.525407 -195.383699) (xy 274.539759 -195.369334)
			(xy 274.558514 -195.361553) (xy 274.568666 -195.361052) (xy 275.968206 -195.361052) (xy 275.97838 -195.361459)
			(xy 275.997177 -195.369249) (xy 276.011562 -195.38364) (xy 276.019345 -195.40244) (xy 276.019768 -195.412614)
			(xy 276.019768 -195.821554) (xy 282.060904 -195.821554) (xy 282.060904 -195.412614) (xy 282.061444 -195.402461)
			(xy 282.069207 -195.383699) (xy 282.083559 -195.369334) (xy 282.102314 -195.361553) (xy 282.112466 -195.361052)
			(xy 283.512006 -195.361052) (xy 283.52218 -195.361459) (xy 283.540977 -195.369249) (xy 283.555362 -195.38364)
			(xy 283.563145 -195.40244) (xy 283.563568 -195.412614) (xy 283.563568 -195.821554) (xy 289.604704 -195.821554)
			(xy 289.604704 -195.412614) (xy 289.605244 -195.402461) (xy 289.613007 -195.383699) (xy 289.627359 -195.369334)
			(xy 289.646114 -195.361553) (xy 289.656266 -195.361052) (xy 291.055806 -195.361052) (xy 291.06598 -195.361459)
			(xy 291.084777 -195.369249) (xy 291.099162 -195.38364) (xy 291.106945 -195.40244) (xy 291.107368 -195.412614)
			(xy 291.107368 -195.821554) (xy 297.148504 -195.821554) (xy 297.148504 -195.412614) (xy 297.149044 -195.402461)
			(xy 297.156807 -195.383699) (xy 297.171159 -195.369334) (xy 297.189914 -195.361553) (xy 297.200066 -195.361052)
			(xy 298.599606 -195.361052) (xy 298.60978 -195.361459) (xy 298.628577 -195.369249) (xy 298.642962 -195.38364)
			(xy 298.650745 -195.40244) (xy 298.651168 -195.412614) (xy 298.651168 -195.821554) (xy 304.692304 -195.821554)
			(xy 304.692304 -195.412614) (xy 304.692844 -195.402461) (xy 304.700607 -195.383699) (xy 304.714959 -195.369334)
			(xy 304.733714 -195.361553) (xy 304.743866 -195.361052) (xy 306.143406 -195.361052) (xy 306.15358 -195.361459)
			(xy 306.172377 -195.369249) (xy 306.186762 -195.38364) (xy 306.194545 -195.40244) (xy 306.194968 -195.412614)
			(xy 306.194968 -195.821554) (xy 312.236104 -195.821554) (xy 312.236104 -195.412614) (xy 312.236644 -195.402461)
			(xy 312.244407 -195.383699) (xy 312.258759 -195.369334) (xy 312.277514 -195.361553) (xy 312.287666 -195.361052)
			(xy 313.687206 -195.361052) (xy 313.69738 -195.361459) (xy 313.716177 -195.369249) (xy 313.730562 -195.38364)
			(xy 313.738345 -195.40244) (xy 313.738768 -195.412614) (xy 313.738768 -195.821554) (xy 410.102304 -195.821554)
			(xy 410.102304 -195.412614) (xy 410.102844 -195.402461) (xy 410.110607 -195.383699) (xy 410.124959 -195.369334)
			(xy 410.143714 -195.361553) (xy 410.153866 -195.361052) (xy 411.553406 -195.361052) (xy 411.56358 -195.361459)
			(xy 411.582377 -195.369249) (xy 411.596762 -195.38364) (xy 411.604545 -195.40244) (xy 411.604968 -195.412614)
			(xy 411.604968 -195.821554) (xy 417.646104 -195.821554) (xy 417.646104 -195.412614) (xy 417.646644 -195.402461)
			(xy 417.654407 -195.383699) (xy 417.668759 -195.369334) (xy 417.687514 -195.361553) (xy 417.697666 -195.361052)
			(xy 419.097206 -195.361052) (xy 419.10738 -195.361459) (xy 419.126177 -195.369249) (xy 419.140562 -195.38364)
			(xy 419.148345 -195.40244) (xy 419.148768 -195.412614) (xy 419.148768 -195.821554) (xy 425.189904 -195.821554)
			(xy 425.189904 -195.412614) (xy 425.190444 -195.402461) (xy 425.198207 -195.383699) (xy 425.212559 -195.369334)
			(xy 425.231314 -195.361553) (xy 425.241466 -195.361052) (xy 426.641006 -195.361052) (xy 426.65118 -195.361459)
			(xy 426.669977 -195.369249) (xy 426.684362 -195.38364) (xy 426.692145 -195.40244) (xy 426.692568 -195.412614)
			(xy 426.692568 -195.821554) (xy 432.733704 -195.821554) (xy 432.733704 -195.412614) (xy 432.734244 -195.402461)
			(xy 432.742007 -195.383699) (xy 432.756359 -195.369334) (xy 432.775114 -195.361553) (xy 432.785266 -195.361052)
			(xy 434.184806 -195.361052) (xy 434.19498 -195.361459) (xy 434.213777 -195.369249) (xy 434.228162 -195.38364)
			(xy 434.235945 -195.40244) (xy 434.236368 -195.412614) (xy 434.236368 -195.821554) (xy 440.277504 -195.821554)
			(xy 440.277504 -195.412614) (xy 440.278044 -195.402461) (xy 440.285807 -195.383699) (xy 440.300159 -195.369334)
			(xy 440.318914 -195.361553) (xy 440.329066 -195.361052) (xy 441.728606 -195.361052) (xy 441.73878 -195.361459)
			(xy 441.757577 -195.369249) (xy 441.771962 -195.38364) (xy 441.779745 -195.40244) (xy 441.780168 -195.412614)
			(xy 441.780168 -195.821554) (xy 447.821304 -195.821554) (xy 447.821304 -195.412614) (xy 447.821844 -195.402461)
			(xy 447.829607 -195.383699) (xy 447.843959 -195.369334) (xy 447.862714 -195.361553) (xy 447.872866 -195.361052)
			(xy 449.272406 -195.361052) (xy 449.28258 -195.361459) (xy 449.301377 -195.369249) (xy 449.315762 -195.38364)
			(xy 449.323545 -195.40244) (xy 449.323968 -195.412614) (xy 449.323968 -195.821554) (xy 455.365104 -195.821554)
			(xy 455.365104 -195.412614) (xy 455.365644 -195.402461) (xy 455.373407 -195.383699) (xy 455.387759 -195.369334)
			(xy 455.406514 -195.361553) (xy 455.416666 -195.361052) (xy 456.816206 -195.361052) (xy 456.82638 -195.361459)
			(xy 456.845177 -195.369249) (xy 456.859562 -195.38364) (xy 456.867345 -195.40244) (xy 456.867768 -195.412614)
			(xy 456.867768 -195.821554) (xy 462.908904 -195.821554) (xy 462.908904 -195.412614) (xy 462.909444 -195.402461)
			(xy 462.917207 -195.383699) (xy 462.931559 -195.369334) (xy 462.950314 -195.361553) (xy 462.960466 -195.361052)
			(xy 464.360006 -195.361052) (xy 464.37018 -195.361459) (xy 464.388977 -195.369249) (xy 464.403362 -195.38364)
			(xy 464.411145 -195.40244) (xy 464.411568 -195.412614) (xy 464.411568 -195.821554) (xy 464.411099 -195.831722)
			(xy 464.40333 -195.850514) (xy 464.388958 -195.864901) (xy 464.370173 -195.872688) (xy 464.360006 -195.873116)
			(xy 462.960466 -195.873116) (xy 462.950286 -195.872763) (xy 462.931482 -195.864958) (xy 462.917097 -195.850551)
			(xy 462.909321 -195.831734) (xy 462.908904 -195.821554) (xy 456.867768 -195.821554) (xy 456.867299 -195.831722)
			(xy 456.85953 -195.850514) (xy 456.845158 -195.864901) (xy 456.826373 -195.872688) (xy 456.816206 -195.873116)
			(xy 455.416666 -195.873116) (xy 455.406486 -195.872763) (xy 455.387682 -195.864958) (xy 455.373297 -195.850551)
			(xy 455.365521 -195.831734) (xy 455.365104 -195.821554) (xy 449.323968 -195.821554) (xy 449.323499 -195.831722)
			(xy 449.31573 -195.850514) (xy 449.301358 -195.864901) (xy 449.282573 -195.872688) (xy 449.272406 -195.873116)
			(xy 447.872866 -195.873116) (xy 447.862686 -195.872763) (xy 447.843882 -195.864958) (xy 447.829497 -195.850551)
			(xy 447.821721 -195.831734) (xy 447.821304 -195.821554) (xy 441.780168 -195.821554) (xy 441.779699 -195.831722)
			(xy 441.77193 -195.850514) (xy 441.757558 -195.864901) (xy 441.738773 -195.872688) (xy 441.728606 -195.873116)
			(xy 440.329066 -195.873116) (xy 440.318886 -195.872763) (xy 440.300082 -195.864958) (xy 440.285697 -195.850551)
			(xy 440.277921 -195.831734) (xy 440.277504 -195.821554) (xy 434.236368 -195.821554) (xy 434.235899 -195.831722)
			(xy 434.22813 -195.850514) (xy 434.213758 -195.864901) (xy 434.194973 -195.872688) (xy 434.184806 -195.873116)
			(xy 432.785266 -195.873116) (xy 432.775086 -195.872763) (xy 432.756282 -195.864958) (xy 432.741897 -195.850551)
			(xy 432.734121 -195.831734) (xy 432.733704 -195.821554) (xy 426.692568 -195.821554) (xy 426.692099 -195.831722)
			(xy 426.68433 -195.850514) (xy 426.669958 -195.864901) (xy 426.651173 -195.872688) (xy 426.641006 -195.873116)
			(xy 425.241466 -195.873116) (xy 425.231286 -195.872763) (xy 425.212482 -195.864958) (xy 425.198097 -195.850551)
			(xy 425.190321 -195.831734) (xy 425.189904 -195.821554) (xy 419.148768 -195.821554) (xy 419.148299 -195.831722)
			(xy 419.14053 -195.850514) (xy 419.126158 -195.864901) (xy 419.107373 -195.872688) (xy 419.097206 -195.873116)
			(xy 417.697666 -195.873116) (xy 417.687486 -195.872763) (xy 417.668682 -195.864958) (xy 417.654297 -195.850551)
			(xy 417.646521 -195.831734) (xy 417.646104 -195.821554) (xy 411.604968 -195.821554) (xy 411.604499 -195.831722)
			(xy 411.59673 -195.850514) (xy 411.582358 -195.864901) (xy 411.563573 -195.872688) (xy 411.553406 -195.873116)
			(xy 410.153866 -195.873116) (xy 410.143686 -195.872763) (xy 410.124882 -195.864958) (xy 410.110497 -195.850551)
			(xy 410.102721 -195.831734) (xy 410.102304 -195.821554) (xy 313.738768 -195.821554) (xy 313.738299 -195.831722)
			(xy 313.73053 -195.850514) (xy 313.716158 -195.864901) (xy 313.697373 -195.872688) (xy 313.687206 -195.873116)
			(xy 312.287666 -195.873116) (xy 312.277486 -195.872763) (xy 312.258682 -195.864958) (xy 312.244297 -195.850551)
			(xy 312.236521 -195.831734) (xy 312.236104 -195.821554) (xy 306.194968 -195.821554) (xy 306.194499 -195.831722)
			(xy 306.18673 -195.850514) (xy 306.172358 -195.864901) (xy 306.153573 -195.872688) (xy 306.143406 -195.873116)
			(xy 304.743866 -195.873116) (xy 304.733686 -195.872763) (xy 304.714882 -195.864958) (xy 304.700497 -195.850551)
			(xy 304.692721 -195.831734) (xy 304.692304 -195.821554) (xy 298.651168 -195.821554) (xy 298.650699 -195.831722)
			(xy 298.64293 -195.850514) (xy 298.628558 -195.864901) (xy 298.609773 -195.872688) (xy 298.599606 -195.873116)
			(xy 297.200066 -195.873116) (xy 297.189886 -195.872763) (xy 297.171082 -195.864958) (xy 297.156697 -195.850551)
			(xy 297.148921 -195.831734) (xy 297.148504 -195.821554) (xy 291.107368 -195.821554) (xy 291.106899 -195.831722)
			(xy 291.09913 -195.850514) (xy 291.084758 -195.864901) (xy 291.065973 -195.872688) (xy 291.055806 -195.873116)
			(xy 289.656266 -195.873116) (xy 289.646086 -195.872763) (xy 289.627282 -195.864958) (xy 289.612897 -195.850551)
			(xy 289.605121 -195.831734) (xy 289.604704 -195.821554) (xy 283.563568 -195.821554) (xy 283.563099 -195.831722)
			(xy 283.55533 -195.850514) (xy 283.540958 -195.864901) (xy 283.522173 -195.872688) (xy 283.512006 -195.873116)
			(xy 282.112466 -195.873116) (xy 282.102286 -195.872763) (xy 282.083482 -195.864958) (xy 282.069097 -195.850551)
			(xy 282.061321 -195.831734) (xy 282.060904 -195.821554) (xy 276.019768 -195.821554) (xy 276.019299 -195.831722)
			(xy 276.01153 -195.850514) (xy 275.997158 -195.864901) (xy 275.978373 -195.872688) (xy 275.968206 -195.873116)
			(xy 274.568666 -195.873116) (xy 274.558486 -195.872763) (xy 274.539682 -195.864958) (xy 274.525297 -195.850551)
			(xy 274.517521 -195.831734) (xy 274.517104 -195.821554) (xy 268.475968 -195.821554) (xy 268.475499 -195.831722)
			(xy 268.46773 -195.850514) (xy 268.453358 -195.864901) (xy 268.434573 -195.872688) (xy 268.424406 -195.873116)
			(xy 267.024866 -195.873116) (xy 267.014686 -195.872763) (xy 266.995882 -195.864958) (xy 266.981497 -195.850551)
			(xy 266.973721 -195.831734) (xy 266.973304 -195.821554) (xy 260.932168 -195.821554) (xy 260.931699 -195.831722)
			(xy 260.92393 -195.850514) (xy 260.909558 -195.864901) (xy 260.890773 -195.872688) (xy 260.880606 -195.873116)
			(xy 259.481066 -195.873116) (xy 259.470886 -195.872763) (xy 259.452082 -195.864958) (xy 259.437697 -195.850551)
			(xy 259.429921 -195.831734) (xy 259.429504 -195.821554) (xy 216.4715 -195.821554) (xy 216.470999 -195.831718)
			(xy 216.463237 -195.850504) (xy 216.448875 -195.864889) (xy 216.430101 -195.872683) (xy 216.419938 -195.873116)
			(xy 215.020398 -195.873116) (xy 215.010221 -195.872737) (xy 214.991417 -195.864942) (xy 214.977031 -195.850543)
			(xy 214.969254 -195.831732) (xy 214.968836 -195.821554) (xy 208.9277 -195.821554) (xy 208.927199 -195.831718)
			(xy 208.919437 -195.850504) (xy 208.905075 -195.864889) (xy 208.886301 -195.872683) (xy 208.876138 -195.873116)
			(xy 207.476598 -195.873116) (xy 207.466421 -195.872737) (xy 207.447617 -195.864942) (xy 207.433231 -195.850543)
			(xy 207.425454 -195.831732) (xy 207.425036 -195.821554) (xy 201.3839 -195.821554) (xy 201.383399 -195.831718)
			(xy 201.375637 -195.850504) (xy 201.361275 -195.864889) (xy 201.342501 -195.872683) (xy 201.332338 -195.873116)
			(xy 199.932798 -195.873116) (xy 199.922621 -195.872737) (xy 199.903817 -195.864942) (xy 199.889431 -195.850543)
			(xy 199.881654 -195.831732) (xy 199.881236 -195.821554) (xy 193.8401 -195.821554) (xy 193.839599 -195.831718)
			(xy 193.831837 -195.850504) (xy 193.817475 -195.864889) (xy 193.798701 -195.872683) (xy 193.788538 -195.873116)
			(xy 192.388998 -195.873116) (xy 192.378821 -195.872737) (xy 192.360017 -195.864942) (xy 192.345631 -195.850543)
			(xy 192.337854 -195.831732) (xy 192.337436 -195.821554) (xy 186.2963 -195.821554) (xy 186.295799 -195.831718)
			(xy 186.288037 -195.850504) (xy 186.273675 -195.864889) (xy 186.254901 -195.872683) (xy 186.244738 -195.873116)
			(xy 184.845198 -195.873116) (xy 184.835021 -195.872737) (xy 184.816217 -195.864942) (xy 184.801831 -195.850543)
			(xy 184.794054 -195.831732) (xy 184.793636 -195.821554) (xy 178.7525 -195.821554) (xy 178.751999 -195.831718)
			(xy 178.744237 -195.850504) (xy 178.729875 -195.864889) (xy 178.711101 -195.872683) (xy 178.700938 -195.873116)
			(xy 177.301398 -195.873116) (xy 177.291221 -195.872737) (xy 177.272417 -195.864942) (xy 177.258031 -195.850543)
			(xy 177.250254 -195.831732) (xy 177.249836 -195.821554) (xy 171.2087 -195.821554) (xy 171.208199 -195.831718)
			(xy 171.200437 -195.850504) (xy 171.186075 -195.864889) (xy 171.167301 -195.872683) (xy 171.157138 -195.873116)
			(xy 169.757598 -195.873116) (xy 169.747421 -195.872737) (xy 169.728617 -195.864942) (xy 169.714231 -195.850543)
			(xy 169.706454 -195.831732) (xy 169.706036 -195.821554) (xy 163.6649 -195.821554) (xy 163.664399 -195.831718)
			(xy 163.656637 -195.850504) (xy 163.642275 -195.864889) (xy 163.623501 -195.872683) (xy 163.613338 -195.873116)
			(xy 162.213798 -195.873116) (xy 162.203621 -195.872737) (xy 162.184817 -195.864942) (xy 162.170431 -195.850543)
			(xy 162.162654 -195.831732) (xy 162.162236 -195.821554) (xy 65.7987 -195.821554) (xy 65.798199 -195.831718)
			(xy 65.790437 -195.850504) (xy 65.776075 -195.864889) (xy 65.757301 -195.872683) (xy 65.747138 -195.873116)
			(xy 64.347598 -195.873116) (xy 64.337421 -195.872737) (xy 64.318617 -195.864942) (xy 64.304231 -195.850543)
			(xy 64.296454 -195.831732) (xy 64.296036 -195.821554) (xy 58.2549 -195.821554) (xy 58.254399 -195.831718)
			(xy 58.246637 -195.850504) (xy 58.232275 -195.864889) (xy 58.213501 -195.872683) (xy 58.203338 -195.873116)
			(xy 56.803798 -195.873116) (xy 56.793621 -195.872737) (xy 56.774817 -195.864942) (xy 56.760431 -195.850543)
			(xy 56.752654 -195.831732) (xy 56.752236 -195.821554) (xy 50.7111 -195.821554) (xy 50.710599 -195.831718)
			(xy 50.702837 -195.850504) (xy 50.688475 -195.864889) (xy 50.669701 -195.872683) (xy 50.659538 -195.873116)
			(xy 49.259998 -195.873116) (xy 49.249821 -195.872737) (xy 49.231017 -195.864942) (xy 49.216631 -195.850543)
			(xy 49.208854 -195.831732) (xy 49.208436 -195.821554) (xy 43.1673 -195.821554) (xy 43.166799 -195.831718)
			(xy 43.159037 -195.850504) (xy 43.144675 -195.864889) (xy 43.125901 -195.872683) (xy 43.115738 -195.873116)
			(xy 41.716198 -195.873116) (xy 41.706021 -195.872737) (xy 41.687217 -195.864942) (xy 41.672831 -195.850543)
			(xy 41.665054 -195.831732) (xy 41.664636 -195.821554) (xy 35.6235 -195.821554) (xy 35.622999 -195.831718)
			(xy 35.615237 -195.850504) (xy 35.600875 -195.864889) (xy 35.582101 -195.872683) (xy 35.571938 -195.873116)
			(xy 34.172398 -195.873116) (xy 34.162221 -195.872737) (xy 34.143417 -195.864942) (xy 34.129031 -195.850543)
			(xy 34.121254 -195.831732) (xy 34.120836 -195.821554) (xy 28.0797 -195.821554) (xy 28.079199 -195.831718)
			(xy 28.071437 -195.850504) (xy 28.057075 -195.864889) (xy 28.038301 -195.872683) (xy 28.028138 -195.873116)
			(xy 26.628598 -195.873116) (xy 26.618421 -195.872737) (xy 26.599617 -195.864942) (xy 26.585231 -195.850543)
			(xy 26.577454 -195.831732) (xy 26.577036 -195.821554) (xy 20.5359 -195.821554) (xy 20.535399 -195.831718)
			(xy 20.527637 -195.850504) (xy 20.513275 -195.864889) (xy 20.494501 -195.872683) (xy 20.484338 -195.873116)
			(xy 19.084798 -195.873116) (xy 19.074621 -195.872737) (xy 19.055817 -195.864942) (xy 19.041431 -195.850543)
			(xy 19.033654 -195.831732) (xy 19.033236 -195.821554) (xy 12.9921 -195.821554) (xy 12.991599 -195.831718)
			(xy 12.983837 -195.850504) (xy 12.969475 -195.864889) (xy 12.950701 -195.872683) (xy 12.940538 -195.873116)
			(xy 11.540998 -195.873116) (xy 11.530821 -195.872737) (xy 11.512017 -195.864942) (xy 11.497631 -195.850543)
			(xy 11.489854 -195.831732) (xy 11.489436 -195.821554) (xy 2.509012 -195.821554) (xy 2.509012 -196.671438)
			(xy 7.389368 -196.671438) (xy 7.389368 -196.262498) (xy 7.389763 -196.252323) (xy 7.397554 -196.233522)
			(xy 7.411949 -196.219136) (xy 7.430754 -196.211357) (xy 7.44093 -196.210936) (xy 8.84047 -196.210936)
			(xy 8.850639 -196.211389) (xy 8.869433 -196.219163) (xy 8.883819 -196.23354) (xy 8.891605 -196.252329)
			(xy 8.892032 -196.262498) (xy 8.892032 -196.671438) (xy 14.933168 -196.671438) (xy 14.933168 -196.262498)
			(xy 14.933563 -196.252323) (xy 14.941354 -196.233522) (xy 14.955749 -196.219136) (xy 14.974554 -196.211357)
			(xy 14.98473 -196.210936) (xy 16.38427 -196.210936) (xy 16.394439 -196.211389) (xy 16.413233 -196.219163)
			(xy 16.427619 -196.23354) (xy 16.435405 -196.252329) (xy 16.435832 -196.262498) (xy 16.435832 -196.671438)
			(xy 22.476968 -196.671438) (xy 22.476968 -196.262498) (xy 22.477363 -196.252323) (xy 22.485154 -196.233522)
			(xy 22.499549 -196.219136) (xy 22.518354 -196.211357) (xy 22.52853 -196.210936) (xy 23.92807 -196.210936)
			(xy 23.938239 -196.211389) (xy 23.957033 -196.219163) (xy 23.971419 -196.23354) (xy 23.979205 -196.252329)
			(xy 23.979632 -196.262498) (xy 23.979632 -196.671438) (xy 30.020768 -196.671438) (xy 30.020768 -196.262498)
			(xy 30.021163 -196.252323) (xy 30.028954 -196.233522) (xy 30.043349 -196.219136) (xy 30.062154 -196.211357)
			(xy 30.07233 -196.210936) (xy 31.47187 -196.210936) (xy 31.482039 -196.211389) (xy 31.500833 -196.219163)
			(xy 31.515219 -196.23354) (xy 31.523005 -196.252329) (xy 31.523432 -196.262498) (xy 31.523432 -196.671438)
			(xy 37.564568 -196.671438) (xy 37.564568 -196.262498) (xy 37.564963 -196.252323) (xy 37.572754 -196.233522)
			(xy 37.587149 -196.219136) (xy 37.605954 -196.211357) (xy 37.61613 -196.210936) (xy 39.01567 -196.210936)
			(xy 39.025839 -196.211389) (xy 39.044633 -196.219163) (xy 39.059019 -196.23354) (xy 39.066805 -196.252329)
			(xy 39.067232 -196.262498) (xy 39.067232 -196.671438) (xy 45.108368 -196.671438) (xy 45.108368 -196.262498)
			(xy 45.108763 -196.252323) (xy 45.116554 -196.233522) (xy 45.130949 -196.219136) (xy 45.149754 -196.211357)
			(xy 45.15993 -196.210936) (xy 46.55947 -196.210936) (xy 46.569639 -196.211389) (xy 46.588433 -196.219163)
			(xy 46.602819 -196.23354) (xy 46.610605 -196.252329) (xy 46.611032 -196.262498) (xy 46.611032 -196.671438)
			(xy 52.652168 -196.671438) (xy 52.652168 -196.262498) (xy 52.652563 -196.252323) (xy 52.660354 -196.233522)
			(xy 52.674749 -196.219136) (xy 52.693554 -196.211357) (xy 52.70373 -196.210936) (xy 54.10327 -196.210936)
			(xy 54.113439 -196.211389) (xy 54.132233 -196.219163) (xy 54.146619 -196.23354) (xy 54.154405 -196.252329)
			(xy 54.154832 -196.262498) (xy 54.154832 -196.671438) (xy 60.195968 -196.671438) (xy 60.195968 -196.262498)
			(xy 60.196363 -196.252323) (xy 60.204154 -196.233522) (xy 60.218549 -196.219136) (xy 60.237354 -196.211357)
			(xy 60.24753 -196.210936) (xy 61.64707 -196.210936) (xy 61.657239 -196.211389) (xy 61.676033 -196.219163)
			(xy 61.690419 -196.23354) (xy 61.698205 -196.252329) (xy 61.698632 -196.262498) (xy 61.698632 -196.671438)
			(xy 158.062168 -196.671438) (xy 158.062168 -196.262498) (xy 158.062563 -196.252323) (xy 158.070354 -196.233522)
			(xy 158.084749 -196.219136) (xy 158.103554 -196.211357) (xy 158.11373 -196.210936) (xy 159.51327 -196.210936)
			(xy 159.523439 -196.211389) (xy 159.542233 -196.219163) (xy 159.556619 -196.23354) (xy 159.564405 -196.252329)
			(xy 159.564832 -196.262498) (xy 159.564832 -196.671438) (xy 165.605968 -196.671438) (xy 165.605968 -196.262498)
			(xy 165.606363 -196.252323) (xy 165.614154 -196.233522) (xy 165.628549 -196.219136) (xy 165.647354 -196.211357)
			(xy 165.65753 -196.210936) (xy 167.05707 -196.210936) (xy 167.067239 -196.211389) (xy 167.086033 -196.219163)
			(xy 167.100419 -196.23354) (xy 167.108205 -196.252329) (xy 167.108632 -196.262498) (xy 167.108632 -196.671438)
			(xy 173.149768 -196.671438) (xy 173.149768 -196.262498) (xy 173.150163 -196.252323) (xy 173.157954 -196.233522)
			(xy 173.172349 -196.219136) (xy 173.191154 -196.211357) (xy 173.20133 -196.210936) (xy 174.60087 -196.210936)
			(xy 174.611039 -196.211389) (xy 174.629833 -196.219163) (xy 174.644219 -196.23354) (xy 174.652005 -196.252329)
			(xy 174.652432 -196.262498) (xy 174.652432 -196.671438) (xy 180.693568 -196.671438) (xy 180.693568 -196.262498)
			(xy 180.693963 -196.252323) (xy 180.701754 -196.233522) (xy 180.716149 -196.219136) (xy 180.734954 -196.211357)
			(xy 180.74513 -196.210936) (xy 182.14467 -196.210936) (xy 182.154839 -196.211389) (xy 182.173633 -196.219163)
			(xy 182.188019 -196.23354) (xy 182.195805 -196.252329) (xy 182.196232 -196.262498) (xy 182.196232 -196.671438)
			(xy 188.237368 -196.671438) (xy 188.237368 -196.262498) (xy 188.237763 -196.252323) (xy 188.245554 -196.233522)
			(xy 188.259949 -196.219136) (xy 188.278754 -196.211357) (xy 188.28893 -196.210936) (xy 189.68847 -196.210936)
			(xy 189.698639 -196.211389) (xy 189.717433 -196.219163) (xy 189.731819 -196.23354) (xy 189.739605 -196.252329)
			(xy 189.740032 -196.262498) (xy 189.740032 -196.671438) (xy 195.781168 -196.671438) (xy 195.781168 -196.262498)
			(xy 195.781563 -196.252323) (xy 195.789354 -196.233522) (xy 195.803749 -196.219136) (xy 195.822554 -196.211357)
			(xy 195.83273 -196.210936) (xy 197.23227 -196.210936) (xy 197.242439 -196.211389) (xy 197.261233 -196.219163)
			(xy 197.275619 -196.23354) (xy 197.283405 -196.252329) (xy 197.283832 -196.262498) (xy 197.283832 -196.671438)
			(xy 203.324968 -196.671438) (xy 203.324968 -196.262498) (xy 203.325363 -196.252323) (xy 203.333154 -196.233522)
			(xy 203.347549 -196.219136) (xy 203.366354 -196.211357) (xy 203.37653 -196.210936) (xy 204.77607 -196.210936)
			(xy 204.786239 -196.211389) (xy 204.805033 -196.219163) (xy 204.819419 -196.23354) (xy 204.827205 -196.252329)
			(xy 204.827632 -196.262498) (xy 204.827632 -196.671438) (xy 210.868768 -196.671438) (xy 210.868768 -196.262498)
			(xy 210.869163 -196.252323) (xy 210.876954 -196.233522) (xy 210.891349 -196.219136) (xy 210.910154 -196.211357)
			(xy 210.92033 -196.210936) (xy 212.31987 -196.210936) (xy 212.330039 -196.211389) (xy 212.348833 -196.219163)
			(xy 212.363219 -196.23354) (xy 212.371005 -196.252329) (xy 212.371432 -196.262498) (xy 212.371432 -196.671438)
			(xy 255.329436 -196.671438) (xy 255.329436 -196.262498) (xy 255.329932 -196.25234) (xy 255.337706 -196.233572)
			(xy 255.352072 -196.219206) (xy 255.37084 -196.211432) (xy 255.380998 -196.210936) (xy 256.780538 -196.210936)
			(xy 256.790698 -196.211402) (xy 256.809468 -196.219189) (xy 256.823831 -196.233563) (xy 256.831605 -196.252338)
			(xy 256.8321 -196.262498) (xy 256.8321 -196.671438) (xy 262.873236 -196.671438) (xy 262.873236 -196.262498)
			(xy 262.873732 -196.25234) (xy 262.881506 -196.233572) (xy 262.895872 -196.219206) (xy 262.91464 -196.211432)
			(xy 262.924798 -196.210936) (xy 264.324338 -196.210936) (xy 264.334498 -196.211402) (xy 264.353268 -196.219189)
			(xy 264.367631 -196.233563) (xy 264.375405 -196.252338) (xy 264.3759 -196.262498) (xy 264.3759 -196.671438)
			(xy 270.417036 -196.671438) (xy 270.417036 -196.262498) (xy 270.417532 -196.25234) (xy 270.425306 -196.233572)
			(xy 270.439672 -196.219206) (xy 270.45844 -196.211432) (xy 270.468598 -196.210936) (xy 271.868138 -196.210936)
			(xy 271.878298 -196.211402) (xy 271.897068 -196.219189) (xy 271.911431 -196.233563) (xy 271.919205 -196.252338)
			(xy 271.9197 -196.262498) (xy 271.9197 -196.671438) (xy 277.960836 -196.671438) (xy 277.960836 -196.262498)
			(xy 277.961332 -196.25234) (xy 277.969106 -196.233572) (xy 277.983472 -196.219206) (xy 278.00224 -196.211432)
			(xy 278.012398 -196.210936) (xy 279.411938 -196.210936) (xy 279.422098 -196.211402) (xy 279.440868 -196.219189)
			(xy 279.455231 -196.233563) (xy 279.463005 -196.252338) (xy 279.4635 -196.262498) (xy 279.4635 -196.671438)
			(xy 285.504636 -196.671438) (xy 285.504636 -196.262498) (xy 285.505132 -196.25234) (xy 285.512906 -196.233572)
			(xy 285.527272 -196.219206) (xy 285.54604 -196.211432) (xy 285.556198 -196.210936) (xy 286.955738 -196.210936)
			(xy 286.965898 -196.211402) (xy 286.984668 -196.219189) (xy 286.999031 -196.233563) (xy 287.006805 -196.252338)
			(xy 287.0073 -196.262498) (xy 287.0073 -196.671438) (xy 293.048436 -196.671438) (xy 293.048436 -196.262498)
			(xy 293.048932 -196.25234) (xy 293.056706 -196.233572) (xy 293.071072 -196.219206) (xy 293.08984 -196.211432)
			(xy 293.099998 -196.210936) (xy 294.499538 -196.210936) (xy 294.509698 -196.211402) (xy 294.528468 -196.219189)
			(xy 294.542831 -196.233563) (xy 294.550605 -196.252338) (xy 294.5511 -196.262498) (xy 294.5511 -196.671438)
			(xy 300.592236 -196.671438) (xy 300.592236 -196.262498) (xy 300.592732 -196.25234) (xy 300.600506 -196.233572)
			(xy 300.614872 -196.219206) (xy 300.63364 -196.211432) (xy 300.643798 -196.210936) (xy 302.043338 -196.210936)
			(xy 302.053498 -196.211402) (xy 302.072268 -196.219189) (xy 302.086631 -196.233563) (xy 302.094405 -196.252338)
			(xy 302.0949 -196.262498) (xy 302.0949 -196.671438) (xy 308.136036 -196.671438) (xy 308.136036 -196.262498)
			(xy 308.136532 -196.25234) (xy 308.144306 -196.233572) (xy 308.158672 -196.219206) (xy 308.17744 -196.211432)
			(xy 308.187598 -196.210936) (xy 309.587138 -196.210936) (xy 309.597298 -196.211402) (xy 309.616068 -196.219189)
			(xy 309.630431 -196.233563) (xy 309.638205 -196.252338) (xy 309.6387 -196.262498) (xy 309.6387 -196.671438)
			(xy 406.002236 -196.671438) (xy 406.002236 -196.262498) (xy 406.002732 -196.25234) (xy 406.010506 -196.233572)
			(xy 406.024872 -196.219206) (xy 406.04364 -196.211432) (xy 406.053798 -196.210936) (xy 407.453338 -196.210936)
			(xy 407.463498 -196.211402) (xy 407.482268 -196.219189) (xy 407.496631 -196.233563) (xy 407.504405 -196.252338)
			(xy 407.5049 -196.262498) (xy 407.5049 -196.671438) (xy 413.546036 -196.671438) (xy 413.546036 -196.262498)
			(xy 413.546532 -196.25234) (xy 413.554306 -196.233572) (xy 413.568672 -196.219206) (xy 413.58744 -196.211432)
			(xy 413.597598 -196.210936) (xy 414.997138 -196.210936) (xy 415.007298 -196.211402) (xy 415.026068 -196.219189)
			(xy 415.040431 -196.233563) (xy 415.048205 -196.252338) (xy 415.0487 -196.262498) (xy 415.0487 -196.671438)
			(xy 421.089836 -196.671438) (xy 421.089836 -196.262498) (xy 421.090332 -196.25234) (xy 421.098106 -196.233572)
			(xy 421.112472 -196.219206) (xy 421.13124 -196.211432) (xy 421.141398 -196.210936) (xy 422.540938 -196.210936)
			(xy 422.551098 -196.211402) (xy 422.569868 -196.219189) (xy 422.584231 -196.233563) (xy 422.592005 -196.252338)
			(xy 422.5925 -196.262498) (xy 422.5925 -196.671438) (xy 428.633636 -196.671438) (xy 428.633636 -196.262498)
			(xy 428.634132 -196.25234) (xy 428.641906 -196.233572) (xy 428.656272 -196.219206) (xy 428.67504 -196.211432)
			(xy 428.685198 -196.210936) (xy 430.084738 -196.210936) (xy 430.094898 -196.211402) (xy 430.113668 -196.219189)
			(xy 430.128031 -196.233563) (xy 430.135805 -196.252338) (xy 430.1363 -196.262498) (xy 430.1363 -196.671438)
			(xy 436.177436 -196.671438) (xy 436.177436 -196.262498) (xy 436.177932 -196.25234) (xy 436.185706 -196.233572)
			(xy 436.200072 -196.219206) (xy 436.21884 -196.211432) (xy 436.228998 -196.210936) (xy 437.628538 -196.210936)
			(xy 437.638698 -196.211402) (xy 437.657468 -196.219189) (xy 437.671831 -196.233563) (xy 437.679605 -196.252338)
			(xy 437.6801 -196.262498) (xy 437.6801 -196.671438) (xy 443.721236 -196.671438) (xy 443.721236 -196.262498)
			(xy 443.721732 -196.25234) (xy 443.729506 -196.233572) (xy 443.743872 -196.219206) (xy 443.76264 -196.211432)
			(xy 443.772798 -196.210936) (xy 445.172338 -196.210936) (xy 445.182498 -196.211402) (xy 445.201268 -196.219189)
			(xy 445.215631 -196.233563) (xy 445.223405 -196.252338) (xy 445.2239 -196.262498) (xy 445.2239 -196.671438)
			(xy 451.265036 -196.671438) (xy 451.265036 -196.262498) (xy 451.265532 -196.25234) (xy 451.273306 -196.233572)
			(xy 451.287672 -196.219206) (xy 451.30644 -196.211432) (xy 451.316598 -196.210936) (xy 452.716138 -196.210936)
			(xy 452.726298 -196.211402) (xy 452.745068 -196.219189) (xy 452.759431 -196.233563) (xy 452.767205 -196.252338)
			(xy 452.7677 -196.262498) (xy 452.7677 -196.671438) (xy 458.808836 -196.671438) (xy 458.808836 -196.262498)
			(xy 458.809332 -196.25234) (xy 458.817106 -196.233572) (xy 458.831472 -196.219206) (xy 458.85024 -196.211432)
			(xy 458.860398 -196.210936) (xy 460.259938 -196.210936) (xy 460.270098 -196.211402) (xy 460.288868 -196.219189)
			(xy 460.303231 -196.233563) (xy 460.311005 -196.252338) (xy 460.3115 -196.262498) (xy 460.3115 -196.671438)
			(xy 460.310999 -196.681594) (xy 460.303219 -196.700356) (xy 460.288856 -196.714719) (xy 460.270094 -196.722499)
			(xy 460.259938 -196.723) (xy 458.860398 -196.723) (xy 458.850245 -196.722469) (xy 458.831483 -196.714701)
			(xy 458.817119 -196.700347) (xy 458.809338 -196.681591) (xy 458.808836 -196.671438) (xy 452.7677 -196.671438)
			(xy 452.767199 -196.681594) (xy 452.759419 -196.700356) (xy 452.745056 -196.714719) (xy 452.726294 -196.722499)
			(xy 452.716138 -196.723) (xy 451.316598 -196.723) (xy 451.306445 -196.722469) (xy 451.287683 -196.714701)
			(xy 451.273319 -196.700347) (xy 451.265538 -196.681591) (xy 451.265036 -196.671438) (xy 445.2239 -196.671438)
			(xy 445.223399 -196.681594) (xy 445.215619 -196.700356) (xy 445.201256 -196.714719) (xy 445.182494 -196.722499)
			(xy 445.172338 -196.723) (xy 443.772798 -196.723) (xy 443.762645 -196.722469) (xy 443.743883 -196.714701)
			(xy 443.729519 -196.700347) (xy 443.721738 -196.681591) (xy 443.721236 -196.671438) (xy 437.6801 -196.671438)
			(xy 437.679599 -196.681594) (xy 437.671819 -196.700356) (xy 437.657456 -196.714719) (xy 437.638694 -196.722499)
			(xy 437.628538 -196.723) (xy 436.228998 -196.723) (xy 436.218845 -196.722469) (xy 436.200083 -196.714701)
			(xy 436.185719 -196.700347) (xy 436.177938 -196.681591) (xy 436.177436 -196.671438) (xy 430.1363 -196.671438)
			(xy 430.135799 -196.681594) (xy 430.128019 -196.700356) (xy 430.113656 -196.714719) (xy 430.094894 -196.722499)
			(xy 430.084738 -196.723) (xy 428.685198 -196.723) (xy 428.675045 -196.722469) (xy 428.656283 -196.714701)
			(xy 428.641919 -196.700347) (xy 428.634138 -196.681591) (xy 428.633636 -196.671438) (xy 422.5925 -196.671438)
			(xy 422.591999 -196.681594) (xy 422.584219 -196.700356) (xy 422.569856 -196.714719) (xy 422.551094 -196.722499)
			(xy 422.540938 -196.723) (xy 421.141398 -196.723) (xy 421.131245 -196.722469) (xy 421.112483 -196.714701)
			(xy 421.098119 -196.700347) (xy 421.090338 -196.681591) (xy 421.089836 -196.671438) (xy 415.0487 -196.671438)
			(xy 415.048199 -196.681594) (xy 415.040419 -196.700356) (xy 415.026056 -196.714719) (xy 415.007294 -196.722499)
			(xy 414.997138 -196.723) (xy 413.597598 -196.723) (xy 413.587445 -196.722469) (xy 413.568683 -196.714701)
			(xy 413.554319 -196.700347) (xy 413.546538 -196.681591) (xy 413.546036 -196.671438) (xy 407.5049 -196.671438)
			(xy 407.504399 -196.681594) (xy 407.496619 -196.700356) (xy 407.482256 -196.714719) (xy 407.463494 -196.722499)
			(xy 407.453338 -196.723) (xy 406.053798 -196.723) (xy 406.043645 -196.722469) (xy 406.024883 -196.714701)
			(xy 406.010519 -196.700347) (xy 406.002738 -196.681591) (xy 406.002236 -196.671438) (xy 309.6387 -196.671438)
			(xy 309.638199 -196.681594) (xy 309.630419 -196.700356) (xy 309.616056 -196.714719) (xy 309.597294 -196.722499)
			(xy 309.587138 -196.723) (xy 308.187598 -196.723) (xy 308.177445 -196.722469) (xy 308.158683 -196.714701)
			(xy 308.144319 -196.700347) (xy 308.136538 -196.681591) (xy 308.136036 -196.671438) (xy 302.0949 -196.671438)
			(xy 302.094399 -196.681594) (xy 302.086619 -196.700356) (xy 302.072256 -196.714719) (xy 302.053494 -196.722499)
			(xy 302.043338 -196.723) (xy 300.643798 -196.723) (xy 300.633645 -196.722469) (xy 300.614883 -196.714701)
			(xy 300.600519 -196.700347) (xy 300.592738 -196.681591) (xy 300.592236 -196.671438) (xy 294.5511 -196.671438)
			(xy 294.550599 -196.681594) (xy 294.542819 -196.700356) (xy 294.528456 -196.714719) (xy 294.509694 -196.722499)
			(xy 294.499538 -196.723) (xy 293.099998 -196.723) (xy 293.089845 -196.722469) (xy 293.071083 -196.714701)
			(xy 293.056719 -196.700347) (xy 293.048938 -196.681591) (xy 293.048436 -196.671438) (xy 287.0073 -196.671438)
			(xy 287.006799 -196.681594) (xy 286.999019 -196.700356) (xy 286.984656 -196.714719) (xy 286.965894 -196.722499)
			(xy 286.955738 -196.723) (xy 285.556198 -196.723) (xy 285.546045 -196.722469) (xy 285.527283 -196.714701)
			(xy 285.512919 -196.700347) (xy 285.505138 -196.681591) (xy 285.504636 -196.671438) (xy 279.4635 -196.671438)
			(xy 279.462999 -196.681594) (xy 279.455219 -196.700356) (xy 279.440856 -196.714719) (xy 279.422094 -196.722499)
			(xy 279.411938 -196.723) (xy 278.012398 -196.723) (xy 278.002245 -196.722469) (xy 277.983483 -196.714701)
			(xy 277.969119 -196.700347) (xy 277.961338 -196.681591) (xy 277.960836 -196.671438) (xy 271.9197 -196.671438)
			(xy 271.919199 -196.681594) (xy 271.911419 -196.700356) (xy 271.897056 -196.714719) (xy 271.878294 -196.722499)
			(xy 271.868138 -196.723) (xy 270.468598 -196.723) (xy 270.458445 -196.722469) (xy 270.439683 -196.714701)
			(xy 270.425319 -196.700347) (xy 270.417538 -196.681591) (xy 270.417036 -196.671438) (xy 264.3759 -196.671438)
			(xy 264.375399 -196.681594) (xy 264.367619 -196.700356) (xy 264.353256 -196.714719) (xy 264.334494 -196.722499)
			(xy 264.324338 -196.723) (xy 262.924798 -196.723) (xy 262.914645 -196.722469) (xy 262.895883 -196.714701)
			(xy 262.881519 -196.700347) (xy 262.873738 -196.681591) (xy 262.873236 -196.671438) (xy 256.8321 -196.671438)
			(xy 256.831599 -196.681594) (xy 256.823819 -196.700356) (xy 256.809456 -196.714719) (xy 256.790694 -196.722499)
			(xy 256.780538 -196.723) (xy 255.380998 -196.723) (xy 255.370845 -196.722469) (xy 255.352083 -196.714701)
			(xy 255.337719 -196.700347) (xy 255.329938 -196.681591) (xy 255.329436 -196.671438) (xy 212.371432 -196.671438)
			(xy 212.370997 -196.681602) (xy 212.363204 -196.700378) (xy 212.348821 -196.714743) (xy 212.330035 -196.72251)
			(xy 212.31987 -196.723) (xy 210.92033 -196.723) (xy 210.910179 -196.722443) (xy 210.891417 -196.714686)
			(xy 210.877052 -196.70034) (xy 210.86927 -196.681589) (xy 210.868768 -196.671438) (xy 204.827632 -196.671438)
			(xy 204.827197 -196.681602) (xy 204.819404 -196.700378) (xy 204.805021 -196.714743) (xy 204.786235 -196.72251)
			(xy 204.77607 -196.723) (xy 203.37653 -196.723) (xy 203.366379 -196.722443) (xy 203.347617 -196.714686)
			(xy 203.333252 -196.70034) (xy 203.32547 -196.681589) (xy 203.324968 -196.671438) (xy 197.283832 -196.671438)
			(xy 197.283397 -196.681602) (xy 197.275604 -196.700378) (xy 197.261221 -196.714743) (xy 197.242435 -196.72251)
			(xy 197.23227 -196.723) (xy 195.83273 -196.723) (xy 195.822579 -196.722443) (xy 195.803817 -196.714686)
			(xy 195.789452 -196.70034) (xy 195.78167 -196.681589) (xy 195.781168 -196.671438) (xy 189.740032 -196.671438)
			(xy 189.739597 -196.681602) (xy 189.731804 -196.700378) (xy 189.717421 -196.714743) (xy 189.698635 -196.72251)
			(xy 189.68847 -196.723) (xy 188.28893 -196.723) (xy 188.278779 -196.722443) (xy 188.260017 -196.714686)
			(xy 188.245652 -196.70034) (xy 188.23787 -196.681589) (xy 188.237368 -196.671438) (xy 182.196232 -196.671438)
			(xy 182.195797 -196.681602) (xy 182.188004 -196.700378) (xy 182.173621 -196.714743) (xy 182.154835 -196.72251)
			(xy 182.14467 -196.723) (xy 180.74513 -196.723) (xy 180.734979 -196.722443) (xy 180.716217 -196.714686)
			(xy 180.701852 -196.70034) (xy 180.69407 -196.681589) (xy 180.693568 -196.671438) (xy 174.652432 -196.671438)
			(xy 174.651997 -196.681602) (xy 174.644204 -196.700378) (xy 174.629821 -196.714743) (xy 174.611035 -196.72251)
			(xy 174.60087 -196.723) (xy 173.20133 -196.723) (xy 173.191179 -196.722443) (xy 173.172417 -196.714686)
			(xy 173.158052 -196.70034) (xy 173.15027 -196.681589) (xy 173.149768 -196.671438) (xy 167.108632 -196.671438)
			(xy 167.108197 -196.681602) (xy 167.100404 -196.700378) (xy 167.086021 -196.714743) (xy 167.067235 -196.72251)
			(xy 167.05707 -196.723) (xy 165.65753 -196.723) (xy 165.647379 -196.722443) (xy 165.628617 -196.714686)
			(xy 165.614252 -196.70034) (xy 165.60647 -196.681589) (xy 165.605968 -196.671438) (xy 159.564832 -196.671438)
			(xy 159.564397 -196.681602) (xy 159.556604 -196.700378) (xy 159.542221 -196.714743) (xy 159.523435 -196.72251)
			(xy 159.51327 -196.723) (xy 158.11373 -196.723) (xy 158.103579 -196.722443) (xy 158.084817 -196.714686)
			(xy 158.070452 -196.70034) (xy 158.06267 -196.681589) (xy 158.062168 -196.671438) (xy 61.698632 -196.671438)
			(xy 61.698197 -196.681602) (xy 61.690404 -196.700378) (xy 61.676021 -196.714743) (xy 61.657235 -196.72251)
			(xy 61.64707 -196.723) (xy 60.24753 -196.723) (xy 60.237379 -196.722443) (xy 60.218617 -196.714686)
			(xy 60.204252 -196.70034) (xy 60.19647 -196.681589) (xy 60.195968 -196.671438) (xy 54.154832 -196.671438)
			(xy 54.154397 -196.681602) (xy 54.146604 -196.700378) (xy 54.132221 -196.714743) (xy 54.113435 -196.72251)
			(xy 54.10327 -196.723) (xy 52.70373 -196.723) (xy 52.693579 -196.722443) (xy 52.674817 -196.714686)
			(xy 52.660452 -196.70034) (xy 52.65267 -196.681589) (xy 52.652168 -196.671438) (xy 46.611032 -196.671438)
			(xy 46.610597 -196.681602) (xy 46.602804 -196.700378) (xy 46.588421 -196.714743) (xy 46.569635 -196.72251)
			(xy 46.55947 -196.723) (xy 45.15993 -196.723) (xy 45.149779 -196.722443) (xy 45.131017 -196.714686)
			(xy 45.116652 -196.70034) (xy 45.10887 -196.681589) (xy 45.108368 -196.671438) (xy 39.067232 -196.671438)
			(xy 39.066797 -196.681602) (xy 39.059004 -196.700378) (xy 39.044621 -196.714743) (xy 39.025835 -196.72251)
			(xy 39.01567 -196.723) (xy 37.61613 -196.723) (xy 37.605979 -196.722443) (xy 37.587217 -196.714686)
			(xy 37.572852 -196.70034) (xy 37.56507 -196.681589) (xy 37.564568 -196.671438) (xy 31.523432 -196.671438)
			(xy 31.522997 -196.681602) (xy 31.515204 -196.700378) (xy 31.500821 -196.714743) (xy 31.482035 -196.72251)
			(xy 31.47187 -196.723) (xy 30.07233 -196.723) (xy 30.062179 -196.722443) (xy 30.043417 -196.714686)
			(xy 30.029052 -196.70034) (xy 30.02127 -196.681589) (xy 30.020768 -196.671438) (xy 23.979632 -196.671438)
			(xy 23.979197 -196.681602) (xy 23.971404 -196.700378) (xy 23.957021 -196.714743) (xy 23.938235 -196.72251)
			(xy 23.92807 -196.723) (xy 22.52853 -196.723) (xy 22.518379 -196.722443) (xy 22.499617 -196.714686)
			(xy 22.485252 -196.70034) (xy 22.47747 -196.681589) (xy 22.476968 -196.671438) (xy 16.435832 -196.671438)
			(xy 16.435397 -196.681602) (xy 16.427604 -196.700378) (xy 16.413221 -196.714743) (xy 16.394435 -196.72251)
			(xy 16.38427 -196.723) (xy 14.98473 -196.723) (xy 14.974579 -196.722443) (xy 14.955817 -196.714686)
			(xy 14.941452 -196.70034) (xy 14.93367 -196.681589) (xy 14.933168 -196.671438) (xy 8.892032 -196.671438)
			(xy 8.891597 -196.681602) (xy 8.883804 -196.700378) (xy 8.869421 -196.714743) (xy 8.850635 -196.72251)
			(xy 8.84047 -196.723) (xy 7.44093 -196.723) (xy 7.430779 -196.722443) (xy 7.412017 -196.714686) (xy 7.397652 -196.70034)
			(xy 7.38987 -196.681589) (xy 7.389368 -196.671438) (xy 2.509012 -196.671438) (xy 2.509012 -197.521322)
			(xy 11.489436 -197.521322) (xy 11.489436 -197.112382) (xy 11.489918 -197.102223) (xy 11.497698 -197.083454)
			(xy 11.512067 -197.069089) (xy 11.530839 -197.061315) (xy 11.540998 -197.06082) (xy 12.940538 -197.06082)
			(xy 12.950696 -197.061302) (xy 12.969463 -197.069085) (xy 12.983826 -197.083454) (xy 12.991602 -197.102224)
			(xy 12.9921 -197.112382) (xy 12.9921 -197.521322) (xy 19.033236 -197.521322) (xy 19.033236 -197.112382)
			(xy 19.033718 -197.102223) (xy 19.041498 -197.083454) (xy 19.055867 -197.069089) (xy 19.074639 -197.061315)
			(xy 19.084798 -197.06082) (xy 20.484338 -197.06082) (xy 20.494496 -197.061302) (xy 20.513263 -197.069085)
			(xy 20.527626 -197.083454) (xy 20.535402 -197.102224) (xy 20.5359 -197.112382) (xy 20.5359 -197.521322)
			(xy 26.577036 -197.521322) (xy 26.577036 -197.112382) (xy 26.577518 -197.102223) (xy 26.585298 -197.083454)
			(xy 26.599667 -197.069089) (xy 26.618439 -197.061315) (xy 26.628598 -197.06082) (xy 28.028138 -197.06082)
			(xy 28.038296 -197.061302) (xy 28.057063 -197.069085) (xy 28.071426 -197.083454) (xy 28.079202 -197.102224)
			(xy 28.0797 -197.112382) (xy 28.0797 -197.521322) (xy 34.120836 -197.521322) (xy 34.120836 -197.112382)
			(xy 34.121318 -197.102223) (xy 34.129098 -197.083454) (xy 34.143467 -197.069089) (xy 34.162239 -197.061315)
			(xy 34.172398 -197.06082) (xy 35.571938 -197.06082) (xy 35.582096 -197.061302) (xy 35.600863 -197.069085)
			(xy 35.615226 -197.083454) (xy 35.623002 -197.102224) (xy 35.6235 -197.112382) (xy 35.6235 -197.521322)
			(xy 41.664636 -197.521322) (xy 41.664636 -197.112382) (xy 41.665118 -197.102223) (xy 41.672898 -197.083454)
			(xy 41.687267 -197.069089) (xy 41.706039 -197.061315) (xy 41.716198 -197.06082) (xy 43.115738 -197.06082)
			(xy 43.125896 -197.061302) (xy 43.144663 -197.069085) (xy 43.159026 -197.083454) (xy 43.166802 -197.102224)
			(xy 43.1673 -197.112382) (xy 43.1673 -197.521322) (xy 49.208436 -197.521322) (xy 49.208436 -197.112382)
			(xy 49.208918 -197.102223) (xy 49.216698 -197.083454) (xy 49.231067 -197.069089) (xy 49.249839 -197.061315)
			(xy 49.259998 -197.06082) (xy 50.659538 -197.06082) (xy 50.669696 -197.061302) (xy 50.688463 -197.069085)
			(xy 50.702826 -197.083454) (xy 50.710602 -197.102224) (xy 50.7111 -197.112382) (xy 50.7111 -197.521322)
			(xy 56.752236 -197.521322) (xy 56.752236 -197.112382) (xy 56.752718 -197.102223) (xy 56.760498 -197.083454)
			(xy 56.774867 -197.069089) (xy 56.793639 -197.061315) (xy 56.803798 -197.06082) (xy 58.203338 -197.06082)
			(xy 58.213496 -197.061302) (xy 58.232263 -197.069085) (xy 58.246626 -197.083454) (xy 58.254402 -197.102224)
			(xy 58.2549 -197.112382) (xy 58.2549 -197.521322) (xy 64.296036 -197.521322) (xy 64.296036 -197.112382)
			(xy 64.296518 -197.102223) (xy 64.304298 -197.083454) (xy 64.318667 -197.069089) (xy 64.337439 -197.061315)
			(xy 64.347598 -197.06082) (xy 65.747138 -197.06082) (xy 65.757296 -197.061302) (xy 65.776063 -197.069085)
			(xy 65.790426 -197.083454) (xy 65.798202 -197.102224) (xy 65.7987 -197.112382) (xy 65.7987 -197.521322)
			(xy 162.162236 -197.521322) (xy 162.162236 -197.112382) (xy 162.162718 -197.102223) (xy 162.170498 -197.083454)
			(xy 162.184867 -197.069089) (xy 162.203639 -197.061315) (xy 162.213798 -197.06082) (xy 163.613338 -197.06082)
			(xy 163.623496 -197.061302) (xy 163.642263 -197.069085) (xy 163.656626 -197.083454) (xy 163.664402 -197.102224)
			(xy 163.6649 -197.112382) (xy 163.6649 -197.521322) (xy 169.706036 -197.521322) (xy 169.706036 -197.112382)
			(xy 169.706518 -197.102223) (xy 169.714298 -197.083454) (xy 169.728667 -197.069089) (xy 169.747439 -197.061315)
			(xy 169.757598 -197.06082) (xy 171.157138 -197.06082) (xy 171.167296 -197.061302) (xy 171.186063 -197.069085)
			(xy 171.200426 -197.083454) (xy 171.208202 -197.102224) (xy 171.2087 -197.112382) (xy 171.2087 -197.521322)
			(xy 177.249836 -197.521322) (xy 177.249836 -197.112382) (xy 177.250318 -197.102223) (xy 177.258098 -197.083454)
			(xy 177.272467 -197.069089) (xy 177.291239 -197.061315) (xy 177.301398 -197.06082) (xy 178.700938 -197.06082)
			(xy 178.711096 -197.061302) (xy 178.729863 -197.069085) (xy 178.744226 -197.083454) (xy 178.752002 -197.102224)
			(xy 178.7525 -197.112382) (xy 178.7525 -197.521322) (xy 184.793636 -197.521322) (xy 184.793636 -197.112382)
			(xy 184.794118 -197.102223) (xy 184.801898 -197.083454) (xy 184.816267 -197.069089) (xy 184.835039 -197.061315)
			(xy 184.845198 -197.06082) (xy 186.244738 -197.06082) (xy 186.254896 -197.061302) (xy 186.273663 -197.069085)
			(xy 186.288026 -197.083454) (xy 186.295802 -197.102224) (xy 186.2963 -197.112382) (xy 186.2963 -197.521322)
			(xy 192.337436 -197.521322) (xy 192.337436 -197.112382) (xy 192.337918 -197.102223) (xy 192.345698 -197.083454)
			(xy 192.360067 -197.069089) (xy 192.378839 -197.061315) (xy 192.388998 -197.06082) (xy 193.788538 -197.06082)
			(xy 193.798696 -197.061302) (xy 193.817463 -197.069085) (xy 193.831826 -197.083454) (xy 193.839602 -197.102224)
			(xy 193.8401 -197.112382) (xy 193.8401 -197.521322) (xy 199.881236 -197.521322) (xy 199.881236 -197.112382)
			(xy 199.881718 -197.102223) (xy 199.889498 -197.083454) (xy 199.903867 -197.069089) (xy 199.922639 -197.061315)
			(xy 199.932798 -197.06082) (xy 201.332338 -197.06082) (xy 201.342496 -197.061302) (xy 201.361263 -197.069085)
			(xy 201.375626 -197.083454) (xy 201.383402 -197.102224) (xy 201.3839 -197.112382) (xy 201.3839 -197.521322)
			(xy 207.425036 -197.521322) (xy 207.425036 -197.112382) (xy 207.425518 -197.102223) (xy 207.433298 -197.083454)
			(xy 207.447667 -197.069089) (xy 207.466439 -197.061315) (xy 207.476598 -197.06082) (xy 208.876138 -197.06082)
			(xy 208.886296 -197.061302) (xy 208.905063 -197.069085) (xy 208.919426 -197.083454) (xy 208.927202 -197.102224)
			(xy 208.9277 -197.112382) (xy 208.9277 -197.521322) (xy 214.968836 -197.521322) (xy 214.968836 -197.112382)
			(xy 214.969318 -197.102223) (xy 214.977098 -197.083454) (xy 214.991467 -197.069089) (xy 215.010239 -197.061315)
			(xy 215.020398 -197.06082) (xy 216.419938 -197.06082) (xy 216.430096 -197.061302) (xy 216.448863 -197.069085)
			(xy 216.463226 -197.083454) (xy 216.471002 -197.102224) (xy 216.4715 -197.112382) (xy 216.4715 -197.521322)
			(xy 259.429504 -197.521322) (xy 259.429504 -197.112382) (xy 259.430018 -197.102227) (xy 259.437792 -197.083464)
			(xy 259.452151 -197.069101) (xy 259.470911 -197.061321) (xy 259.481066 -197.06082) (xy 260.880606 -197.06082)
			(xy 260.890762 -197.061328) (xy 260.909528 -197.069101) (xy 260.923892 -197.083462) (xy 260.931669 -197.102226)
			(xy 260.932168 -197.112382) (xy 260.932168 -197.521322) (xy 266.973304 -197.521322) (xy 266.973304 -197.112382)
			(xy 266.973818 -197.102227) (xy 266.981592 -197.083464) (xy 266.995951 -197.069101) (xy 267.014711 -197.061321)
			(xy 267.024866 -197.06082) (xy 268.424406 -197.06082) (xy 268.434562 -197.061328) (xy 268.453328 -197.069101)
			(xy 268.467692 -197.083462) (xy 268.475469 -197.102226) (xy 268.475968 -197.112382) (xy 268.475968 -197.521322)
			(xy 274.517104 -197.521322) (xy 274.517104 -197.112382) (xy 274.517618 -197.102227) (xy 274.525392 -197.083464)
			(xy 274.539751 -197.069101) (xy 274.558511 -197.061321) (xy 274.568666 -197.06082) (xy 275.968206 -197.06082)
			(xy 275.978362 -197.061328) (xy 275.997128 -197.069101) (xy 276.011492 -197.083462) (xy 276.019269 -197.102226)
			(xy 276.019768 -197.112382) (xy 276.019768 -197.521322) (xy 282.060904 -197.521322) (xy 282.060904 -197.112382)
			(xy 282.061418 -197.102227) (xy 282.069192 -197.083464) (xy 282.083551 -197.069101) (xy 282.102311 -197.061321)
			(xy 282.112466 -197.06082) (xy 283.512006 -197.06082) (xy 283.522162 -197.061328) (xy 283.540928 -197.069101)
			(xy 283.555292 -197.083462) (xy 283.563069 -197.102226) (xy 283.563568 -197.112382) (xy 283.563568 -197.521322)
			(xy 289.604704 -197.521322) (xy 289.604704 -197.112382) (xy 289.605218 -197.102227) (xy 289.612992 -197.083464)
			(xy 289.627351 -197.069101) (xy 289.646111 -197.061321) (xy 289.656266 -197.06082) (xy 291.055806 -197.06082)
			(xy 291.065962 -197.061328) (xy 291.084728 -197.069101) (xy 291.099092 -197.083462) (xy 291.106869 -197.102226)
			(xy 291.107368 -197.112382) (xy 291.107368 -197.521322) (xy 297.148504 -197.521322) (xy 297.148504 -197.112382)
			(xy 297.149018 -197.102227) (xy 297.156792 -197.083464) (xy 297.171151 -197.069101) (xy 297.189911 -197.061321)
			(xy 297.200066 -197.06082) (xy 298.599606 -197.06082) (xy 298.609762 -197.061328) (xy 298.628528 -197.069101)
			(xy 298.642892 -197.083462) (xy 298.650669 -197.102226) (xy 298.651168 -197.112382) (xy 298.651168 -197.521322)
			(xy 304.692304 -197.521322) (xy 304.692304 -197.112382) (xy 304.692818 -197.102227) (xy 304.700592 -197.083464)
			(xy 304.714951 -197.069101) (xy 304.733711 -197.061321) (xy 304.743866 -197.06082) (xy 306.143406 -197.06082)
			(xy 306.153562 -197.061328) (xy 306.172328 -197.069101) (xy 306.186692 -197.083462) (xy 306.194469 -197.102226)
			(xy 306.194968 -197.112382) (xy 306.194968 -197.521322) (xy 312.236104 -197.521322) (xy 312.236104 -197.112382)
			(xy 312.236618 -197.102227) (xy 312.244392 -197.083464) (xy 312.258751 -197.069101) (xy 312.277511 -197.061321)
			(xy 312.287666 -197.06082) (xy 313.687206 -197.06082) (xy 313.697362 -197.061328) (xy 313.716128 -197.069101)
			(xy 313.730492 -197.083462) (xy 313.738269 -197.102226) (xy 313.738768 -197.112382) (xy 313.738768 -197.521322)
			(xy 410.102304 -197.521322) (xy 410.102304 -197.112382) (xy 410.102818 -197.102227) (xy 410.110592 -197.083464)
			(xy 410.124951 -197.069101) (xy 410.143711 -197.061321) (xy 410.153866 -197.06082) (xy 411.553406 -197.06082)
			(xy 411.563562 -197.061328) (xy 411.582328 -197.069101) (xy 411.596692 -197.083462) (xy 411.604469 -197.102226)
			(xy 411.604968 -197.112382) (xy 411.604968 -197.521322) (xy 417.646104 -197.521322) (xy 417.646104 -197.112382)
			(xy 417.646618 -197.102227) (xy 417.654392 -197.083464) (xy 417.668751 -197.069101) (xy 417.687511 -197.061321)
			(xy 417.697666 -197.06082) (xy 419.097206 -197.06082) (xy 419.107362 -197.061328) (xy 419.126128 -197.069101)
			(xy 419.140492 -197.083462) (xy 419.148269 -197.102226) (xy 419.148768 -197.112382) (xy 419.148768 -197.521322)
			(xy 425.189904 -197.521322) (xy 425.189904 -197.112382) (xy 425.190418 -197.102227) (xy 425.198192 -197.083464)
			(xy 425.212551 -197.069101) (xy 425.231311 -197.061321) (xy 425.241466 -197.06082) (xy 426.641006 -197.06082)
			(xy 426.651162 -197.061328) (xy 426.669928 -197.069101) (xy 426.684292 -197.083462) (xy 426.692069 -197.102226)
			(xy 426.692568 -197.112382) (xy 426.692568 -197.521322) (xy 432.733704 -197.521322) (xy 432.733704 -197.112382)
			(xy 432.734218 -197.102227) (xy 432.741992 -197.083464) (xy 432.756351 -197.069101) (xy 432.775111 -197.061321)
			(xy 432.785266 -197.06082) (xy 434.184806 -197.06082) (xy 434.194962 -197.061328) (xy 434.213728 -197.069101)
			(xy 434.228092 -197.083462) (xy 434.235869 -197.102226) (xy 434.236368 -197.112382) (xy 434.236368 -197.521322)
			(xy 440.277504 -197.521322) (xy 440.277504 -197.112382) (xy 440.278018 -197.102227) (xy 440.285792 -197.083464)
			(xy 440.300151 -197.069101) (xy 440.318911 -197.061321) (xy 440.329066 -197.06082) (xy 441.728606 -197.06082)
			(xy 441.738762 -197.061328) (xy 441.757528 -197.069101) (xy 441.771892 -197.083462) (xy 441.779669 -197.102226)
			(xy 441.780168 -197.112382) (xy 441.780168 -197.521322) (xy 447.821304 -197.521322) (xy 447.821304 -197.112382)
			(xy 447.821818 -197.102227) (xy 447.829592 -197.083464) (xy 447.843951 -197.069101) (xy 447.862711 -197.061321)
			(xy 447.872866 -197.06082) (xy 449.272406 -197.06082) (xy 449.282562 -197.061328) (xy 449.301328 -197.069101)
			(xy 449.315692 -197.083462) (xy 449.323469 -197.102226) (xy 449.323968 -197.112382) (xy 449.323968 -197.521322)
			(xy 455.365104 -197.521322) (xy 455.365104 -197.112382) (xy 455.365618 -197.102227) (xy 455.373392 -197.083464)
			(xy 455.387751 -197.069101) (xy 455.406511 -197.061321) (xy 455.416666 -197.06082) (xy 456.816206 -197.06082)
			(xy 456.826362 -197.061328) (xy 456.845128 -197.069101) (xy 456.859492 -197.083462) (xy 456.867269 -197.102226)
			(xy 456.867768 -197.112382) (xy 456.867768 -197.521322) (xy 462.908904 -197.521322) (xy 462.908904 -197.112382)
			(xy 462.909418 -197.102227) (xy 462.917192 -197.083464) (xy 462.931551 -197.069101) (xy 462.950311 -197.061321)
			(xy 462.960466 -197.06082) (xy 464.360006 -197.06082) (xy 464.370162 -197.061328) (xy 464.388928 -197.069101)
			(xy 464.403292 -197.083462) (xy 464.411069 -197.102226) (xy 464.411568 -197.112382) (xy 464.411568 -197.521322)
			(xy 464.411085 -197.53148) (xy 464.403304 -197.550249) (xy 464.388936 -197.564613) (xy 464.370165 -197.572388)
			(xy 464.360006 -197.572884) (xy 462.960466 -197.572884) (xy 462.950309 -197.572395) (xy 462.931543 -197.564614)
			(xy 462.91718 -197.550247) (xy 462.909403 -197.531479) (xy 462.908904 -197.521322) (xy 456.867768 -197.521322)
			(xy 456.867285 -197.53148) (xy 456.859504 -197.550249) (xy 456.845136 -197.564613) (xy 456.826365 -197.572388)
			(xy 456.816206 -197.572884) (xy 455.416666 -197.572884) (xy 455.406509 -197.572395) (xy 455.387743 -197.564614)
			(xy 455.37338 -197.550247) (xy 455.365603 -197.531479) (xy 455.365104 -197.521322) (xy 449.323968 -197.521322)
			(xy 449.323485 -197.53148) (xy 449.315704 -197.550249) (xy 449.301336 -197.564613) (xy 449.282565 -197.572388)
			(xy 449.272406 -197.572884) (xy 447.872866 -197.572884) (xy 447.862709 -197.572395) (xy 447.843943 -197.564614)
			(xy 447.82958 -197.550247) (xy 447.821803 -197.531479) (xy 447.821304 -197.521322) (xy 441.780168 -197.521322)
			(xy 441.779685 -197.53148) (xy 441.771904 -197.550249) (xy 441.757536 -197.564613) (xy 441.738765 -197.572388)
			(xy 441.728606 -197.572884) (xy 440.329066 -197.572884) (xy 440.318909 -197.572395) (xy 440.300143 -197.564614)
			(xy 440.28578 -197.550247) (xy 440.278003 -197.531479) (xy 440.277504 -197.521322) (xy 434.236368 -197.521322)
			(xy 434.235885 -197.53148) (xy 434.228104 -197.550249) (xy 434.213736 -197.564613) (xy 434.194965 -197.572388)
			(xy 434.184806 -197.572884) (xy 432.785266 -197.572884) (xy 432.775109 -197.572395) (xy 432.756343 -197.564614)
			(xy 432.74198 -197.550247) (xy 432.734203 -197.531479) (xy 432.733704 -197.521322) (xy 426.692568 -197.521322)
			(xy 426.692085 -197.53148) (xy 426.684304 -197.550249) (xy 426.669936 -197.564613) (xy 426.651165 -197.572388)
			(xy 426.641006 -197.572884) (xy 425.241466 -197.572884) (xy 425.231309 -197.572395) (xy 425.212543 -197.564614)
			(xy 425.19818 -197.550247) (xy 425.190403 -197.531479) (xy 425.189904 -197.521322) (xy 419.148768 -197.521322)
			(xy 419.148285 -197.53148) (xy 419.140504 -197.550249) (xy 419.126136 -197.564613) (xy 419.107365 -197.572388)
			(xy 419.097206 -197.572884) (xy 417.697666 -197.572884) (xy 417.687509 -197.572395) (xy 417.668743 -197.564614)
			(xy 417.65438 -197.550247) (xy 417.646603 -197.531479) (xy 417.646104 -197.521322) (xy 411.604968 -197.521322)
			(xy 411.604485 -197.53148) (xy 411.596704 -197.550249) (xy 411.582336 -197.564613) (xy 411.563565 -197.572388)
			(xy 411.553406 -197.572884) (xy 410.153866 -197.572884) (xy 410.143709 -197.572395) (xy 410.124943 -197.564614)
			(xy 410.11058 -197.550247) (xy 410.102803 -197.531479) (xy 410.102304 -197.521322) (xy 313.738768 -197.521322)
			(xy 313.738285 -197.53148) (xy 313.730504 -197.550249) (xy 313.716136 -197.564613) (xy 313.697365 -197.572388)
			(xy 313.687206 -197.572884) (xy 312.287666 -197.572884) (xy 312.277509 -197.572395) (xy 312.258743 -197.564614)
			(xy 312.24438 -197.550247) (xy 312.236603 -197.531479) (xy 312.236104 -197.521322) (xy 306.194968 -197.521322)
			(xy 306.194485 -197.53148) (xy 306.186704 -197.550249) (xy 306.172336 -197.564613) (xy 306.153565 -197.572388)
			(xy 306.143406 -197.572884) (xy 304.743866 -197.572884) (xy 304.733709 -197.572395) (xy 304.714943 -197.564614)
			(xy 304.70058 -197.550247) (xy 304.692803 -197.531479) (xy 304.692304 -197.521322) (xy 298.651168 -197.521322)
			(xy 298.650685 -197.53148) (xy 298.642904 -197.550249) (xy 298.628536 -197.564613) (xy 298.609765 -197.572388)
			(xy 298.599606 -197.572884) (xy 297.200066 -197.572884) (xy 297.189909 -197.572395) (xy 297.171143 -197.564614)
			(xy 297.15678 -197.550247) (xy 297.149003 -197.531479) (xy 297.148504 -197.521322) (xy 291.107368 -197.521322)
			(xy 291.106885 -197.53148) (xy 291.099104 -197.550249) (xy 291.084736 -197.564613) (xy 291.065965 -197.572388)
			(xy 291.055806 -197.572884) (xy 289.656266 -197.572884) (xy 289.646109 -197.572395) (xy 289.627343 -197.564614)
			(xy 289.61298 -197.550247) (xy 289.605203 -197.531479) (xy 289.604704 -197.521322) (xy 283.563568 -197.521322)
			(xy 283.563085 -197.53148) (xy 283.555304 -197.550249) (xy 283.540936 -197.564613) (xy 283.522165 -197.572388)
			(xy 283.512006 -197.572884) (xy 282.112466 -197.572884) (xy 282.102309 -197.572395) (xy 282.083543 -197.564614)
			(xy 282.06918 -197.550247) (xy 282.061403 -197.531479) (xy 282.060904 -197.521322) (xy 276.019768 -197.521322)
			(xy 276.019285 -197.53148) (xy 276.011504 -197.550249) (xy 275.997136 -197.564613) (xy 275.978365 -197.572388)
			(xy 275.968206 -197.572884) (xy 274.568666 -197.572884) (xy 274.558509 -197.572395) (xy 274.539743 -197.564614)
			(xy 274.52538 -197.550247) (xy 274.517603 -197.531479) (xy 274.517104 -197.521322) (xy 268.475968 -197.521322)
			(xy 268.475485 -197.53148) (xy 268.467704 -197.550249) (xy 268.453336 -197.564613) (xy 268.434565 -197.572388)
			(xy 268.424406 -197.572884) (xy 267.024866 -197.572884) (xy 267.014709 -197.572395) (xy 266.995943 -197.564614)
			(xy 266.98158 -197.550247) (xy 266.973803 -197.531479) (xy 266.973304 -197.521322) (xy 260.932168 -197.521322)
			(xy 260.931685 -197.53148) (xy 260.923904 -197.550249) (xy 260.909536 -197.564613) (xy 260.890765 -197.572388)
			(xy 260.880606 -197.572884) (xy 259.481066 -197.572884) (xy 259.470909 -197.572395) (xy 259.452143 -197.564614)
			(xy 259.43778 -197.550247) (xy 259.430003 -197.531479) (xy 259.429504 -197.521322) (xy 216.4715 -197.521322)
			(xy 216.470986 -197.531477) (xy 216.463211 -197.550239) (xy 216.448852 -197.564602) (xy 216.430092 -197.572383)
			(xy 216.419938 -197.572884) (xy 215.020398 -197.572884) (xy 215.010243 -197.572369) (xy 214.991478 -197.564598)
			(xy 214.977113 -197.550239) (xy 214.969335 -197.531477) (xy 214.968836 -197.521322) (xy 208.9277 -197.521322)
			(xy 208.927186 -197.531477) (xy 208.919411 -197.550239) (xy 208.905052 -197.564602) (xy 208.886292 -197.572383)
			(xy 208.876138 -197.572884) (xy 207.476598 -197.572884) (xy 207.466443 -197.572369) (xy 207.447678 -197.564598)
			(xy 207.433313 -197.550239) (xy 207.425535 -197.531477) (xy 207.425036 -197.521322) (xy 201.3839 -197.521322)
			(xy 201.383386 -197.531477) (xy 201.375611 -197.550239) (xy 201.361252 -197.564602) (xy 201.342492 -197.572383)
			(xy 201.332338 -197.572884) (xy 199.932798 -197.572884) (xy 199.922643 -197.572369) (xy 199.903878 -197.564598)
			(xy 199.889513 -197.550239) (xy 199.881735 -197.531477) (xy 199.881236 -197.521322) (xy 193.8401 -197.521322)
			(xy 193.839586 -197.531477) (xy 193.831811 -197.550239) (xy 193.817452 -197.564602) (xy 193.798692 -197.572383)
			(xy 193.788538 -197.572884) (xy 192.388998 -197.572884) (xy 192.378843 -197.572369) (xy 192.360078 -197.564598)
			(xy 192.345713 -197.550239) (xy 192.337935 -197.531477) (xy 192.337436 -197.521322) (xy 186.2963 -197.521322)
			(xy 186.295786 -197.531477) (xy 186.288011 -197.550239) (xy 186.273652 -197.564602) (xy 186.254892 -197.572383)
			(xy 186.244738 -197.572884) (xy 184.845198 -197.572884) (xy 184.835043 -197.572369) (xy 184.816278 -197.564598)
			(xy 184.801913 -197.550239) (xy 184.794135 -197.531477) (xy 184.793636 -197.521322) (xy 178.7525 -197.521322)
			(xy 178.751986 -197.531477) (xy 178.744211 -197.550239) (xy 178.729852 -197.564602) (xy 178.711092 -197.572383)
			(xy 178.700938 -197.572884) (xy 177.301398 -197.572884) (xy 177.291243 -197.572369) (xy 177.272478 -197.564598)
			(xy 177.258113 -197.550239) (xy 177.250335 -197.531477) (xy 177.249836 -197.521322) (xy 171.2087 -197.521322)
			(xy 171.208186 -197.531477) (xy 171.200411 -197.550239) (xy 171.186052 -197.564602) (xy 171.167292 -197.572383)
			(xy 171.157138 -197.572884) (xy 169.757598 -197.572884) (xy 169.747443 -197.572369) (xy 169.728678 -197.564598)
			(xy 169.714313 -197.550239) (xy 169.706535 -197.531477) (xy 169.706036 -197.521322) (xy 163.6649 -197.521322)
			(xy 163.664386 -197.531477) (xy 163.656611 -197.550239) (xy 163.642252 -197.564602) (xy 163.623492 -197.572383)
			(xy 163.613338 -197.572884) (xy 162.213798 -197.572884) (xy 162.203643 -197.572369) (xy 162.184878 -197.564598)
			(xy 162.170513 -197.550239) (xy 162.162735 -197.531477) (xy 162.162236 -197.521322) (xy 65.7987 -197.521322)
			(xy 65.798186 -197.531477) (xy 65.790411 -197.550239) (xy 65.776052 -197.564602) (xy 65.757292 -197.572383)
			(xy 65.747138 -197.572884) (xy 64.347598 -197.572884) (xy 64.337443 -197.572369) (xy 64.318678 -197.564598)
			(xy 64.304313 -197.550239) (xy 64.296535 -197.531477) (xy 64.296036 -197.521322) (xy 58.2549 -197.521322)
			(xy 58.254386 -197.531477) (xy 58.246611 -197.550239) (xy 58.232252 -197.564602) (xy 58.213492 -197.572383)
			(xy 58.203338 -197.572884) (xy 56.803798 -197.572884) (xy 56.793643 -197.572369) (xy 56.774878 -197.564598)
			(xy 56.760513 -197.550239) (xy 56.752735 -197.531477) (xy 56.752236 -197.521322) (xy 50.7111 -197.521322)
			(xy 50.710586 -197.531477) (xy 50.702811 -197.550239) (xy 50.688452 -197.564602) (xy 50.669692 -197.572383)
			(xy 50.659538 -197.572884) (xy 49.259998 -197.572884) (xy 49.249843 -197.572369) (xy 49.231078 -197.564598)
			(xy 49.216713 -197.550239) (xy 49.208935 -197.531477) (xy 49.208436 -197.521322) (xy 43.1673 -197.521322)
			(xy 43.166786 -197.531477) (xy 43.159011 -197.550239) (xy 43.144652 -197.564602) (xy 43.125892 -197.572383)
			(xy 43.115738 -197.572884) (xy 41.716198 -197.572884) (xy 41.706043 -197.572369) (xy 41.687278 -197.564598)
			(xy 41.672913 -197.550239) (xy 41.665135 -197.531477) (xy 41.664636 -197.521322) (xy 35.6235 -197.521322)
			(xy 35.622986 -197.531477) (xy 35.615211 -197.550239) (xy 35.600852 -197.564602) (xy 35.582092 -197.572383)
			(xy 35.571938 -197.572884) (xy 34.172398 -197.572884) (xy 34.162243 -197.572369) (xy 34.143478 -197.564598)
			(xy 34.129113 -197.550239) (xy 34.121335 -197.531477) (xy 34.120836 -197.521322) (xy 28.0797 -197.521322)
			(xy 28.079186 -197.531477) (xy 28.071411 -197.550239) (xy 28.057052 -197.564602) (xy 28.038292 -197.572383)
			(xy 28.028138 -197.572884) (xy 26.628598 -197.572884) (xy 26.618443 -197.572369) (xy 26.599678 -197.564598)
			(xy 26.585313 -197.550239) (xy 26.577535 -197.531477) (xy 26.577036 -197.521322) (xy 20.5359 -197.521322)
			(xy 20.535386 -197.531477) (xy 20.527611 -197.550239) (xy 20.513252 -197.564602) (xy 20.494492 -197.572383)
			(xy 20.484338 -197.572884) (xy 19.084798 -197.572884) (xy 19.074643 -197.572369) (xy 19.055878 -197.564598)
			(xy 19.041513 -197.550239) (xy 19.033735 -197.531477) (xy 19.033236 -197.521322) (xy 12.9921 -197.521322)
			(xy 12.991586 -197.531477) (xy 12.983811 -197.550239) (xy 12.969452 -197.564602) (xy 12.950692 -197.572383)
			(xy 12.940538 -197.572884) (xy 11.540998 -197.572884) (xy 11.530843 -197.572369) (xy 11.512078 -197.564598)
			(xy 11.497713 -197.550239) (xy 11.489935 -197.531477) (xy 11.489436 -197.521322) (xy 2.509012 -197.521322)
			(xy 2.509012 -198.37146) (xy 7.389368 -198.37146) (xy 7.389368 -197.96252) (xy 7.389837 -197.952371)
			(xy 7.39762 -197.933625) (xy 7.412002 -197.919302) (xy 7.43078 -197.911596) (xy 7.44093 -197.911212)
			(xy 8.84047 -197.911212) (xy 8.850591 -197.91175) (xy 8.869307 -197.919463) (xy 8.883663 -197.933733)
			(xy 8.891488 -197.952402) (xy 8.892032 -197.96252) (xy 8.892032 -198.37146) (xy 14.933168 -198.37146)
			(xy 14.933168 -197.96252) (xy 14.933637 -197.952371) (xy 14.94142 -197.933625) (xy 14.955802 -197.919302)
			(xy 14.97458 -197.911596) (xy 14.98473 -197.911212) (xy 16.38427 -197.911212) (xy 16.394391 -197.91175)
			(xy 16.413107 -197.919463) (xy 16.427463 -197.933733) (xy 16.435288 -197.952402) (xy 16.435832 -197.96252)
			(xy 16.435832 -198.37146) (xy 22.476968 -198.37146) (xy 22.476968 -197.96252) (xy 22.477437 -197.952371)
			(xy 22.48522 -197.933625) (xy 22.499602 -197.919302) (xy 22.51838 -197.911596) (xy 22.52853 -197.911212)
			(xy 23.92807 -197.911212) (xy 23.938191 -197.91175) (xy 23.956907 -197.919463) (xy 23.971263 -197.933733)
			(xy 23.979088 -197.952402) (xy 23.979632 -197.96252) (xy 23.979632 -198.37146) (xy 30.020768 -198.37146)
			(xy 30.020768 -197.96252) (xy 30.021237 -197.952371) (xy 30.02902 -197.933625) (xy 30.043402 -197.919302)
			(xy 30.06218 -197.911596) (xy 30.07233 -197.911212) (xy 31.47187 -197.911212) (xy 31.481991 -197.91175)
			(xy 31.500707 -197.919463) (xy 31.515063 -197.933733) (xy 31.522888 -197.952402) (xy 31.523432 -197.96252)
			(xy 31.523432 -198.37146) (xy 37.564568 -198.37146) (xy 37.564568 -197.96252) (xy 37.565037 -197.952371)
			(xy 37.57282 -197.933625) (xy 37.587202 -197.919302) (xy 37.60598 -197.911596) (xy 37.61613 -197.911212)
			(xy 39.01567 -197.911212) (xy 39.025791 -197.91175) (xy 39.044507 -197.919463) (xy 39.058863 -197.933733)
			(xy 39.066688 -197.952402) (xy 39.067232 -197.96252) (xy 39.067232 -198.37146) (xy 45.108368 -198.37146)
			(xy 45.108368 -197.96252) (xy 45.108837 -197.952371) (xy 45.11662 -197.933625) (xy 45.131002 -197.919302)
			(xy 45.14978 -197.911596) (xy 45.15993 -197.911212) (xy 46.55947 -197.911212) (xy 46.569591 -197.91175)
			(xy 46.588307 -197.919463) (xy 46.602663 -197.933733) (xy 46.610488 -197.952402) (xy 46.611032 -197.96252)
			(xy 46.611032 -198.37146) (xy 52.652168 -198.37146) (xy 52.652168 -197.96252) (xy 52.652637 -197.952371)
			(xy 52.66042 -197.933625) (xy 52.674802 -197.919302) (xy 52.69358 -197.911596) (xy 52.70373 -197.911212)
			(xy 54.10327 -197.911212) (xy 54.113391 -197.91175) (xy 54.132107 -197.919463) (xy 54.146463 -197.933733)
			(xy 54.154288 -197.952402) (xy 54.154832 -197.96252) (xy 54.154832 -198.37146) (xy 60.195968 -198.37146)
			(xy 60.195968 -197.96252) (xy 60.196437 -197.952371) (xy 60.20422 -197.933625) (xy 60.218602 -197.919302)
			(xy 60.23738 -197.911596) (xy 60.24753 -197.911212) (xy 61.64707 -197.911212) (xy 61.657191 -197.91175)
			(xy 61.675907 -197.919463) (xy 61.690263 -197.933733) (xy 61.698088 -197.952402) (xy 61.698632 -197.96252)
			(xy 61.698632 -198.37146) (xy 158.062168 -198.37146) (xy 158.062168 -197.96252) (xy 158.062637 -197.952371)
			(xy 158.07042 -197.933625) (xy 158.084802 -197.919302) (xy 158.10358 -197.911596) (xy 158.11373 -197.911212)
			(xy 159.51327 -197.911212) (xy 159.523391 -197.91175) (xy 159.542107 -197.919463) (xy 159.556463 -197.933733)
			(xy 159.564288 -197.952402) (xy 159.564832 -197.96252) (xy 159.564832 -198.37146) (xy 165.605968 -198.37146)
			(xy 165.605968 -197.96252) (xy 165.606437 -197.952371) (xy 165.61422 -197.933625) (xy 165.628602 -197.919302)
			(xy 165.64738 -197.911596) (xy 165.65753 -197.911212) (xy 167.05707 -197.911212) (xy 167.067191 -197.91175)
			(xy 167.085907 -197.919463) (xy 167.100263 -197.933733) (xy 167.108088 -197.952402) (xy 167.108632 -197.96252)
			(xy 167.108632 -198.37146) (xy 173.149768 -198.37146) (xy 173.149768 -197.96252) (xy 173.150237 -197.952371)
			(xy 173.15802 -197.933625) (xy 173.172402 -197.919302) (xy 173.19118 -197.911596) (xy 173.20133 -197.911212)
			(xy 174.60087 -197.911212) (xy 174.610991 -197.91175) (xy 174.629707 -197.919463) (xy 174.644063 -197.933733)
			(xy 174.651888 -197.952402) (xy 174.652432 -197.96252) (xy 174.652432 -198.37146) (xy 180.693568 -198.37146)
			(xy 180.693568 -197.96252) (xy 180.694037 -197.952371) (xy 180.70182 -197.933625) (xy 180.716202 -197.919302)
			(xy 180.73498 -197.911596) (xy 180.74513 -197.911212) (xy 182.14467 -197.911212) (xy 182.154791 -197.91175)
			(xy 182.173507 -197.919463) (xy 182.187863 -197.933733) (xy 182.195688 -197.952402) (xy 182.196232 -197.96252)
			(xy 182.196232 -198.37146) (xy 188.237368 -198.37146) (xy 188.237368 -197.96252) (xy 188.237837 -197.952371)
			(xy 188.24562 -197.933625) (xy 188.260002 -197.919302) (xy 188.27878 -197.911596) (xy 188.28893 -197.911212)
			(xy 189.68847 -197.911212) (xy 189.698591 -197.91175) (xy 189.717307 -197.919463) (xy 189.731663 -197.933733)
			(xy 189.739488 -197.952402) (xy 189.740032 -197.96252) (xy 189.740032 -198.37146) (xy 195.781168 -198.37146)
			(xy 195.781168 -197.96252) (xy 195.781637 -197.952371) (xy 195.78942 -197.933625) (xy 195.803802 -197.919302)
			(xy 195.82258 -197.911596) (xy 195.83273 -197.911212) (xy 197.23227 -197.911212) (xy 197.242391 -197.91175)
			(xy 197.261107 -197.919463) (xy 197.275463 -197.933733) (xy 197.283288 -197.952402) (xy 197.283832 -197.96252)
			(xy 197.283832 -198.37146) (xy 203.324968 -198.37146) (xy 203.324968 -197.96252) (xy 203.325437 -197.952371)
			(xy 203.33322 -197.933625) (xy 203.347602 -197.919302) (xy 203.36638 -197.911596) (xy 203.37653 -197.911212)
			(xy 204.77607 -197.911212) (xy 204.786191 -197.91175) (xy 204.804907 -197.919463) (xy 204.819263 -197.933733)
			(xy 204.827088 -197.952402) (xy 204.827632 -197.96252) (xy 204.827632 -198.37146) (xy 210.868768 -198.37146)
			(xy 210.868768 -197.96252) (xy 210.869237 -197.952371) (xy 210.87702 -197.933625) (xy 210.891402 -197.919302)
			(xy 210.91018 -197.911596) (xy 210.92033 -197.911212) (xy 212.31987 -197.911212) (xy 212.329991 -197.91175)
			(xy 212.348707 -197.919463) (xy 212.363063 -197.933733) (xy 212.370888 -197.952402) (xy 212.371432 -197.96252)
			(xy 212.371432 -198.37146) (xy 255.329436 -198.37146) (xy 255.329436 -197.96252) (xy 255.329839 -197.952363)
			(xy 255.337634 -197.933604) (xy 255.352038 -197.919278) (xy 255.370838 -197.911584) (xy 255.380998 -197.911212)
			(xy 256.780538 -197.911212) (xy 256.790664 -197.911695) (xy 256.80938 -197.91943) (xy 256.823734 -197.933716)
			(xy 256.831557 -197.952397) (xy 256.8321 -197.96252) (xy 256.8321 -198.37146) (xy 262.873236 -198.37146)
			(xy 262.873236 -197.96252) (xy 262.873639 -197.952363) (xy 262.881434 -197.933604) (xy 262.895838 -197.919278)
			(xy 262.914638 -197.911584) (xy 262.924798 -197.911212) (xy 264.324338 -197.911212) (xy 264.334464 -197.911695)
			(xy 264.35318 -197.91943) (xy 264.367534 -197.933716) (xy 264.375357 -197.952397) (xy 264.3759 -197.96252)
			(xy 264.3759 -198.37146) (xy 270.417036 -198.37146) (xy 270.417036 -197.96252) (xy 270.417439 -197.952363)
			(xy 270.425234 -197.933604) (xy 270.439638 -197.919278) (xy 270.458438 -197.911584) (xy 270.468598 -197.911212)
			(xy 271.868138 -197.911212) (xy 271.878264 -197.911695) (xy 271.89698 -197.91943) (xy 271.911334 -197.933716)
			(xy 271.919157 -197.952397) (xy 271.9197 -197.96252) (xy 271.9197 -198.37146) (xy 277.960836 -198.37146)
			(xy 277.960836 -197.96252) (xy 277.961239 -197.952363) (xy 277.969034 -197.933604) (xy 277.983438 -197.919278)
			(xy 278.002238 -197.911584) (xy 278.012398 -197.911212) (xy 279.411938 -197.911212) (xy 279.422064 -197.911695)
			(xy 279.44078 -197.91943) (xy 279.455134 -197.933716) (xy 279.462957 -197.952397) (xy 279.4635 -197.96252)
			(xy 279.4635 -198.37146) (xy 285.504636 -198.37146) (xy 285.504636 -197.96252) (xy 285.505039 -197.952363)
			(xy 285.512834 -197.933604) (xy 285.527238 -197.919278) (xy 285.546038 -197.911584) (xy 285.556198 -197.911212)
			(xy 286.955738 -197.911212) (xy 286.965864 -197.911695) (xy 286.98458 -197.91943) (xy 286.998934 -197.933716)
			(xy 287.006757 -197.952397) (xy 287.0073 -197.96252) (xy 287.0073 -198.37146) (xy 293.048436 -198.37146)
			(xy 293.048436 -197.96252) (xy 293.048839 -197.952363) (xy 293.056634 -197.933604) (xy 293.071038 -197.919278)
			(xy 293.089838 -197.911584) (xy 293.099998 -197.911212) (xy 294.499538 -197.911212) (xy 294.509664 -197.911695)
			(xy 294.52838 -197.91943) (xy 294.542734 -197.933716) (xy 294.550557 -197.952397) (xy 294.5511 -197.96252)
			(xy 294.5511 -198.37146) (xy 300.592236 -198.37146) (xy 300.592236 -197.96252) (xy 300.592639 -197.952363)
			(xy 300.600434 -197.933604) (xy 300.614838 -197.919278) (xy 300.633638 -197.911584) (xy 300.643798 -197.911212)
			(xy 302.043338 -197.911212) (xy 302.053464 -197.911695) (xy 302.07218 -197.91943) (xy 302.086534 -197.933716)
			(xy 302.094357 -197.952397) (xy 302.0949 -197.96252) (xy 302.0949 -198.37146) (xy 308.136036 -198.37146)
			(xy 308.136036 -197.96252) (xy 308.136439 -197.952363) (xy 308.144234 -197.933604) (xy 308.158638 -197.919278)
			(xy 308.177438 -197.911584) (xy 308.187598 -197.911212) (xy 309.587138 -197.911212) (xy 309.597264 -197.911695)
			(xy 309.61598 -197.91943) (xy 309.630334 -197.933716) (xy 309.638157 -197.952397) (xy 309.6387 -197.96252)
			(xy 309.6387 -198.37146) (xy 406.002236 -198.37146) (xy 406.002236 -197.96252) (xy 406.002639 -197.952363)
			(xy 406.010434 -197.933604) (xy 406.024838 -197.919278) (xy 406.043638 -197.911584) (xy 406.053798 -197.911212)
			(xy 407.453338 -197.911212) (xy 407.463464 -197.911695) (xy 407.48218 -197.91943) (xy 407.496534 -197.933716)
			(xy 407.504357 -197.952397) (xy 407.5049 -197.96252) (xy 407.5049 -198.37146) (xy 413.546036 -198.37146)
			(xy 413.546036 -197.96252) (xy 413.546439 -197.952363) (xy 413.554234 -197.933604) (xy 413.568638 -197.919278)
			(xy 413.587438 -197.911584) (xy 413.597598 -197.911212) (xy 414.997138 -197.911212) (xy 415.007264 -197.911695)
			(xy 415.02598 -197.91943) (xy 415.040334 -197.933716) (xy 415.048157 -197.952397) (xy 415.0487 -197.96252)
			(xy 415.0487 -198.37146) (xy 421.089836 -198.37146) (xy 421.089836 -197.96252) (xy 421.090239 -197.952363)
			(xy 421.098034 -197.933604) (xy 421.112438 -197.919278) (xy 421.131238 -197.911584) (xy 421.141398 -197.911212)
			(xy 422.540938 -197.911212) (xy 422.551064 -197.911695) (xy 422.56978 -197.91943) (xy 422.584134 -197.933716)
			(xy 422.591957 -197.952397) (xy 422.5925 -197.96252) (xy 422.5925 -198.37146) (xy 428.633636 -198.37146)
			(xy 428.633636 -197.96252) (xy 428.634039 -197.952363) (xy 428.641834 -197.933604) (xy 428.656238 -197.919278)
			(xy 428.675038 -197.911584) (xy 428.685198 -197.911212) (xy 430.084738 -197.911212) (xy 430.094864 -197.911695)
			(xy 430.11358 -197.91943) (xy 430.127934 -197.933716) (xy 430.135757 -197.952397) (xy 430.1363 -197.96252)
			(xy 430.1363 -198.37146) (xy 436.177436 -198.37146) (xy 436.177436 -197.96252) (xy 436.177839 -197.952363)
			(xy 436.185634 -197.933604) (xy 436.200038 -197.919278) (xy 436.218838 -197.911584) (xy 436.228998 -197.911212)
			(xy 437.628538 -197.911212) (xy 437.638664 -197.911695) (xy 437.65738 -197.91943) (xy 437.671734 -197.933716)
			(xy 437.679557 -197.952397) (xy 437.6801 -197.96252) (xy 437.6801 -198.37146) (xy 443.721236 -198.37146)
			(xy 443.721236 -197.96252) (xy 443.721639 -197.952363) (xy 443.729434 -197.933604) (xy 443.743838 -197.919278)
			(xy 443.762638 -197.911584) (xy 443.772798 -197.911212) (xy 445.172338 -197.911212) (xy 445.182464 -197.911695)
			(xy 445.20118 -197.91943) (xy 445.215534 -197.933716) (xy 445.223357 -197.952397) (xy 445.2239 -197.96252)
			(xy 445.2239 -198.37146) (xy 451.265036 -198.37146) (xy 451.265036 -197.96252) (xy 451.265439 -197.952363)
			(xy 451.273234 -197.933604) (xy 451.287638 -197.919278) (xy 451.306438 -197.911584) (xy 451.316598 -197.911212)
			(xy 452.716138 -197.911212) (xy 452.726264 -197.911695) (xy 452.74498 -197.91943) (xy 452.759334 -197.933716)
			(xy 452.767157 -197.952397) (xy 452.7677 -197.96252) (xy 452.7677 -198.37146) (xy 458.808836 -198.37146)
			(xy 458.808836 -197.96252) (xy 458.809239 -197.952363) (xy 458.817034 -197.933604) (xy 458.831438 -197.919278)
			(xy 458.850238 -197.911584) (xy 458.860398 -197.911212) (xy 460.259938 -197.911212) (xy 460.270064 -197.911695)
			(xy 460.28878 -197.91943) (xy 460.303134 -197.933716) (xy 460.310957 -197.952397) (xy 460.3115 -197.96252)
			(xy 460.3115 -198.37146) (xy 460.311045 -198.381612) (xy 460.303263 -198.400363) (xy 460.288876 -198.414688)
			(xy 460.270091 -198.422389) (xy 460.259938 -198.422768) (xy 458.860398 -198.422768) (xy 458.850272 -198.422275)
			(xy 458.831553 -198.414548) (xy 458.817197 -198.400264) (xy 458.809376 -198.381583) (xy 458.808836 -198.37146)
			(xy 452.7677 -198.37146) (xy 452.767245 -198.381612) (xy 452.759463 -198.400363) (xy 452.745076 -198.414688)
			(xy 452.726291 -198.422389) (xy 452.716138 -198.422768) (xy 451.316598 -198.422768) (xy 451.306472 -198.422275)
			(xy 451.287753 -198.414548) (xy 451.273397 -198.400264) (xy 451.265576 -198.381583) (xy 451.265036 -198.37146)
			(xy 445.2239 -198.37146) (xy 445.223445 -198.381612) (xy 445.215663 -198.400363) (xy 445.201276 -198.414688)
			(xy 445.182491 -198.422389) (xy 445.172338 -198.422768) (xy 443.772798 -198.422768) (xy 443.762672 -198.422275)
			(xy 443.743953 -198.414548) (xy 443.729597 -198.400264) (xy 443.721776 -198.381583) (xy 443.721236 -198.37146)
			(xy 437.6801 -198.37146) (xy 437.679645 -198.381612) (xy 437.671863 -198.400363) (xy 437.657476 -198.414688)
			(xy 437.638691 -198.422389) (xy 437.628538 -198.422768) (xy 436.228998 -198.422768) (xy 436.218872 -198.422275)
			(xy 436.200153 -198.414548) (xy 436.185797 -198.400264) (xy 436.177976 -198.381583) (xy 436.177436 -198.37146)
			(xy 430.1363 -198.37146) (xy 430.135845 -198.381612) (xy 430.128063 -198.400363) (xy 430.113676 -198.414688)
			(xy 430.094891 -198.422389) (xy 430.084738 -198.422768) (xy 428.685198 -198.422768) (xy 428.675072 -198.422275)
			(xy 428.656353 -198.414548) (xy 428.641997 -198.400264) (xy 428.634176 -198.381583) (xy 428.633636 -198.37146)
			(xy 422.5925 -198.37146) (xy 422.592045 -198.381612) (xy 422.584263 -198.400363) (xy 422.569876 -198.414688)
			(xy 422.551091 -198.422389) (xy 422.540938 -198.422768) (xy 421.141398 -198.422768) (xy 421.131272 -198.422275)
			(xy 421.112553 -198.414548) (xy 421.098197 -198.400264) (xy 421.090376 -198.381583) (xy 421.089836 -198.37146)
			(xy 415.0487 -198.37146) (xy 415.048245 -198.381612) (xy 415.040463 -198.400363) (xy 415.026076 -198.414688)
			(xy 415.007291 -198.422389) (xy 414.997138 -198.422768) (xy 413.597598 -198.422768) (xy 413.587472 -198.422275)
			(xy 413.568753 -198.414548) (xy 413.554397 -198.400264) (xy 413.546576 -198.381583) (xy 413.546036 -198.37146)
			(xy 407.5049 -198.37146) (xy 407.504445 -198.381612) (xy 407.496663 -198.400363) (xy 407.482276 -198.414688)
			(xy 407.463491 -198.422389) (xy 407.453338 -198.422768) (xy 406.053798 -198.422768) (xy 406.043672 -198.422275)
			(xy 406.024953 -198.414548) (xy 406.010597 -198.400264) (xy 406.002776 -198.381583) (xy 406.002236 -198.37146)
			(xy 309.6387 -198.37146) (xy 309.638245 -198.381612) (xy 309.630463 -198.400363) (xy 309.616076 -198.414688)
			(xy 309.597291 -198.422389) (xy 309.587138 -198.422768) (xy 308.187598 -198.422768) (xy 308.177472 -198.422275)
			(xy 308.158753 -198.414548) (xy 308.144397 -198.400264) (xy 308.136576 -198.381583) (xy 308.136036 -198.37146)
			(xy 302.0949 -198.37146) (xy 302.094445 -198.381612) (xy 302.086663 -198.400363) (xy 302.072276 -198.414688)
			(xy 302.053491 -198.422389) (xy 302.043338 -198.422768) (xy 300.643798 -198.422768) (xy 300.633672 -198.422275)
			(xy 300.614953 -198.414548) (xy 300.600597 -198.400264) (xy 300.592776 -198.381583) (xy 300.592236 -198.37146)
			(xy 294.5511 -198.37146) (xy 294.550645 -198.381612) (xy 294.542863 -198.400363) (xy 294.528476 -198.414688)
			(xy 294.509691 -198.422389) (xy 294.499538 -198.422768) (xy 293.099998 -198.422768) (xy 293.089872 -198.422275)
			(xy 293.071153 -198.414548) (xy 293.056797 -198.400264) (xy 293.048976 -198.381583) (xy 293.048436 -198.37146)
			(xy 287.0073 -198.37146) (xy 287.006845 -198.381612) (xy 286.999063 -198.400363) (xy 286.984676 -198.414688)
			(xy 286.965891 -198.422389) (xy 286.955738 -198.422768) (xy 285.556198 -198.422768) (xy 285.546072 -198.422275)
			(xy 285.527353 -198.414548) (xy 285.512997 -198.400264) (xy 285.505176 -198.381583) (xy 285.504636 -198.37146)
			(xy 279.4635 -198.37146) (xy 279.463045 -198.381612) (xy 279.455263 -198.400363) (xy 279.440876 -198.414688)
			(xy 279.422091 -198.422389) (xy 279.411938 -198.422768) (xy 278.012398 -198.422768) (xy 278.002272 -198.422275)
			(xy 277.983553 -198.414548) (xy 277.969197 -198.400264) (xy 277.961376 -198.381583) (xy 277.960836 -198.37146)
			(xy 271.9197 -198.37146) (xy 271.919245 -198.381612) (xy 271.911463 -198.400363) (xy 271.897076 -198.414688)
			(xy 271.878291 -198.422389) (xy 271.868138 -198.422768) (xy 270.468598 -198.422768) (xy 270.458472 -198.422275)
			(xy 270.439753 -198.414548) (xy 270.425397 -198.400264) (xy 270.417576 -198.381583) (xy 270.417036 -198.37146)
			(xy 264.3759 -198.37146) (xy 264.375445 -198.381612) (xy 264.367663 -198.400363) (xy 264.353276 -198.414688)
			(xy 264.334491 -198.422389) (xy 264.324338 -198.422768) (xy 262.924798 -198.422768) (xy 262.914672 -198.422275)
			(xy 262.895953 -198.414548) (xy 262.881597 -198.400264) (xy 262.873776 -198.381583) (xy 262.873236 -198.37146)
			(xy 256.8321 -198.37146) (xy 256.831645 -198.381612) (xy 256.823863 -198.400363) (xy 256.809476 -198.414688)
			(xy 256.790691 -198.422389) (xy 256.780538 -198.422768) (xy 255.380998 -198.422768) (xy 255.370872 -198.422275)
			(xy 255.352153 -198.414548) (xy 255.337797 -198.400264) (xy 255.329976 -198.381583) (xy 255.329436 -198.37146)
			(xy 212.371432 -198.37146) (xy 212.370946 -198.381608) (xy 212.36317 -198.400353) (xy 212.348793 -198.414676)
			(xy 212.330019 -198.422383) (xy 212.31987 -198.422768) (xy 210.92033 -198.422768) (xy 210.910206 -198.422249)
			(xy 210.891487 -198.414533) (xy 210.87713 -198.400256) (xy 210.869308 -198.381581) (xy 210.868768 -198.37146)
			(xy 204.827632 -198.37146) (xy 204.827146 -198.381608) (xy 204.81937 -198.400353) (xy 204.804993 -198.414676)
			(xy 204.786219 -198.422383) (xy 204.77607 -198.422768) (xy 203.37653 -198.422768) (xy 203.366406 -198.422249)
			(xy 203.347687 -198.414533) (xy 203.33333 -198.400256) (xy 203.325508 -198.381581) (xy 203.324968 -198.37146)
			(xy 197.283832 -198.37146) (xy 197.283346 -198.381608) (xy 197.27557 -198.400353) (xy 197.261193 -198.414676)
			(xy 197.242419 -198.422383) (xy 197.23227 -198.422768) (xy 195.83273 -198.422768) (xy 195.822606 -198.422249)
			(xy 195.803887 -198.414533) (xy 195.78953 -198.400256) (xy 195.781708 -198.381581) (xy 195.781168 -198.37146)
			(xy 189.740032 -198.37146) (xy 189.739546 -198.381608) (xy 189.73177 -198.400353) (xy 189.717393 -198.414676)
			(xy 189.698619 -198.422383) (xy 189.68847 -198.422768) (xy 188.28893 -198.422768) (xy 188.278806 -198.422249)
			(xy 188.260087 -198.414533) (xy 188.24573 -198.400256) (xy 188.237908 -198.381581) (xy 188.237368 -198.37146)
			(xy 182.196232 -198.37146) (xy 182.195746 -198.381608) (xy 182.18797 -198.400353) (xy 182.173593 -198.414676)
			(xy 182.154819 -198.422383) (xy 182.14467 -198.422768) (xy 180.74513 -198.422768) (xy 180.735006 -198.422249)
			(xy 180.716287 -198.414533) (xy 180.70193 -198.400256) (xy 180.694108 -198.381581) (xy 180.693568 -198.37146)
			(xy 174.652432 -198.37146) (xy 174.651946 -198.381608) (xy 174.64417 -198.400353) (xy 174.629793 -198.414676)
			(xy 174.611019 -198.422383) (xy 174.60087 -198.422768) (xy 173.20133 -198.422768) (xy 173.191206 -198.422249)
			(xy 173.172487 -198.414533) (xy 173.15813 -198.400256) (xy 173.150308 -198.381581) (xy 173.149768 -198.37146)
			(xy 167.108632 -198.37146) (xy 167.108146 -198.381608) (xy 167.10037 -198.400353) (xy 167.085993 -198.414676)
			(xy 167.067219 -198.422383) (xy 167.05707 -198.422768) (xy 165.65753 -198.422768) (xy 165.647406 -198.422249)
			(xy 165.628687 -198.414533) (xy 165.61433 -198.400256) (xy 165.606508 -198.381581) (xy 165.605968 -198.37146)
			(xy 159.564832 -198.37146) (xy 159.564346 -198.381608) (xy 159.55657 -198.400353) (xy 159.542193 -198.414676)
			(xy 159.523419 -198.422383) (xy 159.51327 -198.422768) (xy 158.11373 -198.422768) (xy 158.103606 -198.422249)
			(xy 158.084887 -198.414533) (xy 158.07053 -198.400256) (xy 158.062708 -198.381581) (xy 158.062168 -198.37146)
			(xy 61.698632 -198.37146) (xy 61.698146 -198.381608) (xy 61.69037 -198.400353) (xy 61.675993 -198.414676)
			(xy 61.657219 -198.422383) (xy 61.64707 -198.422768) (xy 60.24753 -198.422768) (xy 60.237406 -198.422249)
			(xy 60.218687 -198.414533) (xy 60.20433 -198.400256) (xy 60.196508 -198.381581) (xy 60.195968 -198.37146)
			(xy 54.154832 -198.37146) (xy 54.154346 -198.381608) (xy 54.14657 -198.400353) (xy 54.132193 -198.414676)
			(xy 54.113419 -198.422383) (xy 54.10327 -198.422768) (xy 52.70373 -198.422768) (xy 52.693606 -198.422249)
			(xy 52.674887 -198.414533) (xy 52.66053 -198.400256) (xy 52.652708 -198.381581) (xy 52.652168 -198.37146)
			(xy 46.611032 -198.37146) (xy 46.610546 -198.381608) (xy 46.60277 -198.400353) (xy 46.588393 -198.414676)
			(xy 46.569619 -198.422383) (xy 46.55947 -198.422768) (xy 45.15993 -198.422768) (xy 45.149806 -198.422249)
			(xy 45.131087 -198.414533) (xy 45.11673 -198.400256) (xy 45.108908 -198.381581) (xy 45.108368 -198.37146)
			(xy 39.067232 -198.37146) (xy 39.066746 -198.381608) (xy 39.05897 -198.400353) (xy 39.044593 -198.414676)
			(xy 39.025819 -198.422383) (xy 39.01567 -198.422768) (xy 37.61613 -198.422768) (xy 37.606006 -198.422249)
			(xy 37.587287 -198.414533) (xy 37.57293 -198.400256) (xy 37.565108 -198.381581) (xy 37.564568 -198.37146)
			(xy 31.523432 -198.37146) (xy 31.522946 -198.381608) (xy 31.51517 -198.400353) (xy 31.500793 -198.414676)
			(xy 31.482019 -198.422383) (xy 31.47187 -198.422768) (xy 30.07233 -198.422768) (xy 30.062206 -198.422249)
			(xy 30.043487 -198.414533) (xy 30.02913 -198.400256) (xy 30.021308 -198.381581) (xy 30.020768 -198.37146)
			(xy 23.979632 -198.37146) (xy 23.979146 -198.381608) (xy 23.97137 -198.400353) (xy 23.956993 -198.414676)
			(xy 23.938219 -198.422383) (xy 23.92807 -198.422768) (xy 22.52853 -198.422768) (xy 22.518406 -198.422249)
			(xy 22.499687 -198.414533) (xy 22.48533 -198.400256) (xy 22.477508 -198.381581) (xy 22.476968 -198.37146)
			(xy 16.435832 -198.37146) (xy 16.435346 -198.381608) (xy 16.42757 -198.400353) (xy 16.413193 -198.414676)
			(xy 16.394419 -198.422383) (xy 16.38427 -198.422768) (xy 14.98473 -198.422768) (xy 14.974606 -198.422249)
			(xy 14.955887 -198.414533) (xy 14.94153 -198.400256) (xy 14.933708 -198.381581) (xy 14.933168 -198.37146)
			(xy 8.892032 -198.37146) (xy 8.891546 -198.381608) (xy 8.88377 -198.400353) (xy 8.869393 -198.414676)
			(xy 8.850619 -198.422383) (xy 8.84047 -198.422768) (xy 7.44093 -198.422768) (xy 7.430806 -198.422249)
			(xy 7.412087 -198.414533) (xy 7.39773 -198.400256) (xy 7.389908 -198.381581) (xy 7.389368 -198.37146)
			(xy 2.509012 -198.37146) (xy 2.509012 -199.221344) (xy 11.489436 -199.221344) (xy 11.489436 -198.812404)
			(xy 11.489826 -198.802246) (xy 11.497627 -198.783486) (xy 11.512034 -198.769162) (xy 11.530837 -198.761468)
			(xy 11.540998 -198.761096) (xy 12.940538 -198.761096) (xy 12.950662 -198.761594) (xy 12.969375 -198.769326)
			(xy 12.983729 -198.783608) (xy 12.991554 -198.802283) (xy 12.9921 -198.812404) (xy 12.9921 -199.221344)
			(xy 19.033236 -199.221344) (xy 19.033236 -198.812404) (xy 19.033626 -198.802246) (xy 19.041427 -198.783486)
			(xy 19.055834 -198.769162) (xy 19.074637 -198.761468) (xy 19.084798 -198.761096) (xy 20.484338 -198.761096)
			(xy 20.494462 -198.761594) (xy 20.513175 -198.769326) (xy 20.527529 -198.783608) (xy 20.535354 -198.802283)
			(xy 20.5359 -198.812404) (xy 20.5359 -199.221344) (xy 26.577036 -199.221344) (xy 26.577036 -198.812404)
			(xy 26.577426 -198.802246) (xy 26.585227 -198.783486) (xy 26.599634 -198.769162) (xy 26.618437 -198.761468)
			(xy 26.628598 -198.761096) (xy 28.028138 -198.761096) (xy 28.038262 -198.761594) (xy 28.056975 -198.769326)
			(xy 28.071329 -198.783608) (xy 28.079154 -198.802283) (xy 28.0797 -198.812404) (xy 28.0797 -199.221344)
			(xy 34.120836 -199.221344) (xy 34.120836 -198.812404) (xy 34.121226 -198.802246) (xy 34.129027 -198.783486)
			(xy 34.143434 -198.769162) (xy 34.162237 -198.761468) (xy 34.172398 -198.761096) (xy 35.571938 -198.761096)
			(xy 35.582062 -198.761594) (xy 35.600775 -198.769326) (xy 35.615129 -198.783608) (xy 35.622954 -198.802283)
			(xy 35.6235 -198.812404) (xy 35.6235 -199.221344) (xy 41.664636 -199.221344) (xy 41.664636 -198.812404)
			(xy 41.665026 -198.802246) (xy 41.672827 -198.783486) (xy 41.687234 -198.769162) (xy 41.706037 -198.761468)
			(xy 41.716198 -198.761096) (xy 43.115738 -198.761096) (xy 43.125862 -198.761594) (xy 43.144575 -198.769326)
			(xy 43.158929 -198.783608) (xy 43.166754 -198.802283) (xy 43.1673 -198.812404) (xy 43.1673 -199.221344)
			(xy 49.208436 -199.221344) (xy 49.208436 -198.812404) (xy 49.208826 -198.802246) (xy 49.216627 -198.783486)
			(xy 49.231034 -198.769162) (xy 49.249837 -198.761468) (xy 49.259998 -198.761096) (xy 50.659538 -198.761096)
			(xy 50.669662 -198.761594) (xy 50.688375 -198.769326) (xy 50.702729 -198.783608) (xy 50.710554 -198.802283)
			(xy 50.7111 -198.812404) (xy 50.7111 -199.221344) (xy 56.752236 -199.221344) (xy 56.752236 -198.812404)
			(xy 56.752626 -198.802246) (xy 56.760427 -198.783486) (xy 56.774834 -198.769162) (xy 56.793637 -198.761468)
			(xy 56.803798 -198.761096) (xy 58.203338 -198.761096) (xy 58.213462 -198.761594) (xy 58.232175 -198.769326)
			(xy 58.246529 -198.783608) (xy 58.254354 -198.802283) (xy 58.2549 -198.812404) (xy 58.2549 -199.221344)
			(xy 64.296036 -199.221344) (xy 64.296036 -198.812404) (xy 64.296426 -198.802246) (xy 64.304227 -198.783486)
			(xy 64.318634 -198.769162) (xy 64.337437 -198.761468) (xy 64.347598 -198.761096) (xy 65.747138 -198.761096)
			(xy 65.757262 -198.761594) (xy 65.775975 -198.769326) (xy 65.790329 -198.783608) (xy 65.798154 -198.802283)
			(xy 65.7987 -198.812404) (xy 65.7987 -199.221344) (xy 162.162236 -199.221344) (xy 162.162236 -198.812404)
			(xy 162.162626 -198.802246) (xy 162.170427 -198.783486) (xy 162.184834 -198.769162) (xy 162.203637 -198.761468)
			(xy 162.213798 -198.761096) (xy 163.613338 -198.761096) (xy 163.623462 -198.761594) (xy 163.642175 -198.769326)
			(xy 163.656529 -198.783608) (xy 163.664354 -198.802283) (xy 163.6649 -198.812404) (xy 163.6649 -199.221344)
			(xy 169.706036 -199.221344) (xy 169.706036 -198.812404) (xy 169.706426 -198.802246) (xy 169.714227 -198.783486)
			(xy 169.728634 -198.769162) (xy 169.747437 -198.761468) (xy 169.757598 -198.761096) (xy 171.157138 -198.761096)
			(xy 171.167262 -198.761594) (xy 171.185975 -198.769326) (xy 171.200329 -198.783608) (xy 171.208154 -198.802283)
			(xy 171.2087 -198.812404) (xy 171.2087 -199.221344) (xy 177.249836 -199.221344) (xy 177.249836 -198.812404)
			(xy 177.250226 -198.802246) (xy 177.258027 -198.783486) (xy 177.272434 -198.769162) (xy 177.291237 -198.761468)
			(xy 177.301398 -198.761096) (xy 178.700938 -198.761096) (xy 178.711062 -198.761594) (xy 178.729775 -198.769326)
			(xy 178.744129 -198.783608) (xy 178.751954 -198.802283) (xy 178.7525 -198.812404) (xy 178.7525 -199.221344)
			(xy 184.793636 -199.221344) (xy 184.793636 -198.812404) (xy 184.794026 -198.802246) (xy 184.801827 -198.783486)
			(xy 184.816234 -198.769162) (xy 184.835037 -198.761468) (xy 184.845198 -198.761096) (xy 186.244738 -198.761096)
			(xy 186.254862 -198.761594) (xy 186.273575 -198.769326) (xy 186.287929 -198.783608) (xy 186.295754 -198.802283)
			(xy 186.2963 -198.812404) (xy 186.2963 -199.221344) (xy 192.337436 -199.221344) (xy 192.337436 -198.812404)
			(xy 192.337826 -198.802246) (xy 192.345627 -198.783486) (xy 192.360034 -198.769162) (xy 192.378837 -198.761468)
			(xy 192.388998 -198.761096) (xy 193.788538 -198.761096) (xy 193.798662 -198.761594) (xy 193.817375 -198.769326)
			(xy 193.831729 -198.783608) (xy 193.839554 -198.802283) (xy 193.8401 -198.812404) (xy 193.8401 -199.221344)
			(xy 199.881236 -199.221344) (xy 199.881236 -198.812404) (xy 199.881626 -198.802246) (xy 199.889427 -198.783486)
			(xy 199.903834 -198.769162) (xy 199.922637 -198.761468) (xy 199.932798 -198.761096) (xy 201.332338 -198.761096)
			(xy 201.342462 -198.761594) (xy 201.361175 -198.769326) (xy 201.375529 -198.783608) (xy 201.383354 -198.802283)
			(xy 201.3839 -198.812404) (xy 201.3839 -199.221344) (xy 207.425036 -199.221344) (xy 207.425036 -198.812404)
			(xy 207.425426 -198.802246) (xy 207.433227 -198.783486) (xy 207.447634 -198.769162) (xy 207.466437 -198.761468)
			(xy 207.476598 -198.761096) (xy 208.876138 -198.761096) (xy 208.886262 -198.761594) (xy 208.904975 -198.769326)
			(xy 208.919329 -198.783608) (xy 208.927154 -198.802283) (xy 208.9277 -198.812404) (xy 208.9277 -199.221344)
			(xy 214.968836 -199.221344) (xy 214.968836 -198.812404) (xy 214.969226 -198.802246) (xy 214.977027 -198.783486)
			(xy 214.991434 -198.769162) (xy 215.010237 -198.761468) (xy 215.020398 -198.761096) (xy 216.419938 -198.761096)
			(xy 216.430062 -198.761594) (xy 216.448775 -198.769326) (xy 216.463129 -198.783608) (xy 216.470954 -198.802283)
			(xy 216.4715 -198.812404) (xy 216.4715 -199.221344) (xy 259.429504 -199.221344) (xy 259.429504 -198.812404)
			(xy 259.429925 -198.80225) (xy 259.43772 -198.783497) (xy 259.452117 -198.769173) (xy 259.47091 -198.761474)
			(xy 259.481066 -198.761096) (xy 260.880606 -198.761096) (xy 260.890728 -198.76162) (xy 260.909441 -198.769342)
			(xy 260.923795 -198.783616) (xy 260.931622 -198.802285) (xy 260.932168 -198.812404) (xy 260.932168 -199.221344)
			(xy 266.973304 -199.221344) (xy 266.973304 -198.812404) (xy 266.973725 -198.80225) (xy 266.98152 -198.783497)
			(xy 266.995917 -198.769173) (xy 267.01471 -198.761474) (xy 267.024866 -198.761096) (xy 268.424406 -198.761096)
			(xy 268.434528 -198.76162) (xy 268.453241 -198.769342) (xy 268.467595 -198.783616) (xy 268.475422 -198.802285)
			(xy 268.475968 -198.812404) (xy 268.475968 -199.221344) (xy 274.517104 -199.221344) (xy 274.517104 -198.812404)
			(xy 274.517525 -198.80225) (xy 274.52532 -198.783497) (xy 274.539717 -198.769173) (xy 274.55851 -198.761474)
			(xy 274.568666 -198.761096) (xy 275.968206 -198.761096) (xy 275.978328 -198.76162) (xy 275.997041 -198.769342)
			(xy 276.011395 -198.783616) (xy 276.019222 -198.802285) (xy 276.019768 -198.812404) (xy 276.019768 -199.221344)
			(xy 282.060904 -199.221344) (xy 282.060904 -198.812404) (xy 282.061325 -198.80225) (xy 282.06912 -198.783497)
			(xy 282.083517 -198.769173) (xy 282.10231 -198.761474) (xy 282.112466 -198.761096) (xy 283.512006 -198.761096)
			(xy 283.522128 -198.76162) (xy 283.540841 -198.769342) (xy 283.555195 -198.783616) (xy 283.563022 -198.802285)
			(xy 283.563568 -198.812404) (xy 283.563568 -199.221344) (xy 289.604704 -199.221344) (xy 289.604704 -198.812404)
			(xy 289.605125 -198.80225) (xy 289.61292 -198.783497) (xy 289.627317 -198.769173) (xy 289.64611 -198.761474)
			(xy 289.656266 -198.761096) (xy 291.055806 -198.761096) (xy 291.065928 -198.76162) (xy 291.084641 -198.769342)
			(xy 291.098995 -198.783616) (xy 291.106822 -198.802285) (xy 291.107368 -198.812404) (xy 291.107368 -199.221344)
			(xy 297.148504 -199.221344) (xy 297.148504 -198.812404) (xy 297.148925 -198.80225) (xy 297.15672 -198.783497)
			(xy 297.171117 -198.769173) (xy 297.18991 -198.761474) (xy 297.200066 -198.761096) (xy 298.599606 -198.761096)
			(xy 298.609728 -198.76162) (xy 298.628441 -198.769342) (xy 298.642795 -198.783616) (xy 298.650622 -198.802285)
			(xy 298.651168 -198.812404) (xy 298.651168 -199.221344) (xy 304.692304 -199.221344) (xy 304.692304 -198.812404)
			(xy 304.692725 -198.80225) (xy 304.70052 -198.783497) (xy 304.714917 -198.769173) (xy 304.73371 -198.761474)
			(xy 304.743866 -198.761096) (xy 306.143406 -198.761096) (xy 306.153528 -198.76162) (xy 306.172241 -198.769342)
			(xy 306.186595 -198.783616) (xy 306.194422 -198.802285) (xy 306.194968 -198.812404) (xy 306.194968 -199.221344)
			(xy 312.236104 -199.221344) (xy 312.236104 -198.812404) (xy 312.236525 -198.80225) (xy 312.24432 -198.783497)
			(xy 312.258717 -198.769173) (xy 312.27751 -198.761474) (xy 312.287666 -198.761096) (xy 313.687206 -198.761096)
			(xy 313.697328 -198.76162) (xy 313.716041 -198.769342) (xy 313.730395 -198.783616) (xy 313.738222 -198.802285)
			(xy 313.738768 -198.812404) (xy 313.738768 -199.221344) (xy 410.102304 -199.221344) (xy 410.102304 -198.812404)
			(xy 410.102725 -198.80225) (xy 410.11052 -198.783497) (xy 410.124917 -198.769173) (xy 410.14371 -198.761474)
			(xy 410.153866 -198.761096) (xy 411.553406 -198.761096) (xy 411.563528 -198.76162) (xy 411.582241 -198.769342)
			(xy 411.596595 -198.783616) (xy 411.604422 -198.802285) (xy 411.604968 -198.812404) (xy 411.604968 -199.221344)
			(xy 417.646104 -199.221344) (xy 417.646104 -198.812404) (xy 417.646525 -198.80225) (xy 417.65432 -198.783497)
			(xy 417.668717 -198.769173) (xy 417.68751 -198.761474) (xy 417.697666 -198.761096) (xy 419.097206 -198.761096)
			(xy 419.107328 -198.76162) (xy 419.126041 -198.769342) (xy 419.140395 -198.783616) (xy 419.148222 -198.802285)
			(xy 419.148768 -198.812404) (xy 419.148768 -199.221344) (xy 425.189904 -199.221344) (xy 425.189904 -198.812404)
			(xy 425.190325 -198.80225) (xy 425.19812 -198.783497) (xy 425.212517 -198.769173) (xy 425.23131 -198.761474)
			(xy 425.241466 -198.761096) (xy 426.641006 -198.761096) (xy 426.651128 -198.76162) (xy 426.669841 -198.769342)
			(xy 426.684195 -198.783616) (xy 426.692022 -198.802285) (xy 426.692568 -198.812404) (xy 426.692568 -199.221344)
			(xy 432.733704 -199.221344) (xy 432.733704 -198.812404) (xy 432.734125 -198.80225) (xy 432.74192 -198.783497)
			(xy 432.756317 -198.769173) (xy 432.77511 -198.761474) (xy 432.785266 -198.761096) (xy 434.184806 -198.761096)
			(xy 434.194928 -198.76162) (xy 434.213641 -198.769342) (xy 434.227995 -198.783616) (xy 434.235822 -198.802285)
			(xy 434.236368 -198.812404) (xy 434.236368 -199.221344) (xy 440.277504 -199.221344) (xy 440.277504 -198.812404)
			(xy 440.277925 -198.80225) (xy 440.28572 -198.783497) (xy 440.300117 -198.769173) (xy 440.31891 -198.761474)
			(xy 440.329066 -198.761096) (xy 441.728606 -198.761096) (xy 441.738728 -198.76162) (xy 441.757441 -198.769342)
			(xy 441.771795 -198.783616) (xy 441.779622 -198.802285) (xy 441.780168 -198.812404) (xy 441.780168 -199.221344)
			(xy 447.821304 -199.221344) (xy 447.821304 -198.812404) (xy 447.821725 -198.80225) (xy 447.82952 -198.783497)
			(xy 447.843917 -198.769173) (xy 447.86271 -198.761474) (xy 447.872866 -198.761096) (xy 449.272406 -198.761096)
			(xy 449.282528 -198.76162) (xy 449.301241 -198.769342) (xy 449.315595 -198.783616) (xy 449.323422 -198.802285)
			(xy 449.323968 -198.812404) (xy 449.323968 -199.221344) (xy 455.365104 -199.221344) (xy 455.365104 -198.812404)
			(xy 455.365525 -198.80225) (xy 455.37332 -198.783497) (xy 455.387717 -198.769173) (xy 455.40651 -198.761474)
			(xy 455.416666 -198.761096) (xy 456.816206 -198.761096) (xy 456.826328 -198.76162) (xy 456.845041 -198.769342)
			(xy 456.859395 -198.783616) (xy 456.867222 -198.802285) (xy 456.867768 -198.812404) (xy 456.867768 -199.221344)
			(xy 462.908904 -199.221344) (xy 462.908904 -198.812404) (xy 462.909325 -198.80225) (xy 462.91712 -198.783497)
			(xy 462.931517 -198.769173) (xy 462.95031 -198.761474) (xy 462.960466 -198.761096) (xy 464.360006 -198.761096)
			(xy 464.370128 -198.76162) (xy 464.388841 -198.769342) (xy 464.403195 -198.783616) (xy 464.411022 -198.802285)
			(xy 464.411568 -198.812404) (xy 464.411568 -199.221344) (xy 464.411214 -199.231505) (xy 464.403398 -199.250264)
			(xy 464.38898 -199.264587) (xy 464.37017 -199.27228) (xy 464.360006 -199.272652) (xy 462.960466 -199.272652)
			(xy 462.950336 -199.272201) (xy 462.931613 -199.264461) (xy 462.917257 -199.250164) (xy 462.909441 -199.231472)
			(xy 462.908904 -199.221344) (xy 456.867768 -199.221344) (xy 456.867414 -199.231505) (xy 456.859598 -199.250264)
			(xy 456.84518 -199.264587) (xy 456.82637 -199.27228) (xy 456.816206 -199.272652) (xy 455.416666 -199.272652)
			(xy 455.406536 -199.272201) (xy 455.387813 -199.264461) (xy 455.373457 -199.250164) (xy 455.365641 -199.231472)
			(xy 455.365104 -199.221344) (xy 449.323968 -199.221344) (xy 449.323614 -199.231505) (xy 449.315798 -199.250264)
			(xy 449.30138 -199.264587) (xy 449.28257 -199.27228) (xy 449.272406 -199.272652) (xy 447.872866 -199.272652)
			(xy 447.862736 -199.272201) (xy 447.844013 -199.264461) (xy 447.829657 -199.250164) (xy 447.821841 -199.231472)
			(xy 447.821304 -199.221344) (xy 441.780168 -199.221344) (xy 441.779814 -199.231505) (xy 441.771998 -199.250264)
			(xy 441.75758 -199.264587) (xy 441.73877 -199.27228) (xy 441.728606 -199.272652) (xy 440.329066 -199.272652)
			(xy 440.318936 -199.272201) (xy 440.300213 -199.264461) (xy 440.285857 -199.250164) (xy 440.278041 -199.231472)
			(xy 440.277504 -199.221344) (xy 434.236368 -199.221344) (xy 434.236014 -199.231505) (xy 434.228198 -199.250264)
			(xy 434.21378 -199.264587) (xy 434.19497 -199.27228) (xy 434.184806 -199.272652) (xy 432.785266 -199.272652)
			(xy 432.775136 -199.272201) (xy 432.756413 -199.264461) (xy 432.742057 -199.250164) (xy 432.734241 -199.231472)
			(xy 432.733704 -199.221344) (xy 426.692568 -199.221344) (xy 426.692214 -199.231505) (xy 426.684398 -199.250264)
			(xy 426.66998 -199.264587) (xy 426.65117 -199.27228) (xy 426.641006 -199.272652) (xy 425.241466 -199.272652)
			(xy 425.231336 -199.272201) (xy 425.212613 -199.264461) (xy 425.198257 -199.250164) (xy 425.190441 -199.231472)
			(xy 425.189904 -199.221344) (xy 419.148768 -199.221344) (xy 419.148414 -199.231505) (xy 419.140598 -199.250264)
			(xy 419.12618 -199.264587) (xy 419.10737 -199.27228) (xy 419.097206 -199.272652) (xy 417.697666 -199.272652)
			(xy 417.687536 -199.272201) (xy 417.668813 -199.264461) (xy 417.654457 -199.250164) (xy 417.646641 -199.231472)
			(xy 417.646104 -199.221344) (xy 411.604968 -199.221344) (xy 411.604614 -199.231505) (xy 411.596798 -199.250264)
			(xy 411.58238 -199.264587) (xy 411.56357 -199.27228) (xy 411.553406 -199.272652) (xy 410.153866 -199.272652)
			(xy 410.143736 -199.272201) (xy 410.125013 -199.264461) (xy 410.110657 -199.250164) (xy 410.102841 -199.231472)
			(xy 410.102304 -199.221344) (xy 313.738768 -199.221344) (xy 313.738414 -199.231505) (xy 313.730598 -199.250264)
			(xy 313.71618 -199.264587) (xy 313.69737 -199.27228) (xy 313.687206 -199.272652) (xy 312.287666 -199.272652)
			(xy 312.277536 -199.272201) (xy 312.258813 -199.264461) (xy 312.244457 -199.250164) (xy 312.236641 -199.231472)
			(xy 312.236104 -199.221344) (xy 306.194968 -199.221344) (xy 306.194614 -199.231505) (xy 306.186798 -199.250264)
			(xy 306.17238 -199.264587) (xy 306.15357 -199.27228) (xy 306.143406 -199.272652) (xy 304.743866 -199.272652)
			(xy 304.733736 -199.272201) (xy 304.715013 -199.264461) (xy 304.700657 -199.250164) (xy 304.692841 -199.231472)
			(xy 304.692304 -199.221344) (xy 298.651168 -199.221344) (xy 298.650814 -199.231505) (xy 298.642998 -199.250264)
			(xy 298.62858 -199.264587) (xy 298.60977 -199.27228) (xy 298.599606 -199.272652) (xy 297.200066 -199.272652)
			(xy 297.189936 -199.272201) (xy 297.171213 -199.264461) (xy 297.156857 -199.250164) (xy 297.149041 -199.231472)
			(xy 297.148504 -199.221344) (xy 291.107368 -199.221344) (xy 291.107014 -199.231505) (xy 291.099198 -199.250264)
			(xy 291.08478 -199.264587) (xy 291.06597 -199.27228) (xy 291.055806 -199.272652) (xy 289.656266 -199.272652)
			(xy 289.646136 -199.272201) (xy 289.627413 -199.264461) (xy 289.613057 -199.250164) (xy 289.605241 -199.231472)
			(xy 289.604704 -199.221344) (xy 283.563568 -199.221344) (xy 283.563214 -199.231505) (xy 283.555398 -199.250264)
			(xy 283.54098 -199.264587) (xy 283.52217 -199.27228) (xy 283.512006 -199.272652) (xy 282.112466 -199.272652)
			(xy 282.102336 -199.272201) (xy 282.083613 -199.264461) (xy 282.069257 -199.250164) (xy 282.061441 -199.231472)
			(xy 282.060904 -199.221344) (xy 276.019768 -199.221344) (xy 276.019414 -199.231505) (xy 276.011598 -199.250264)
			(xy 275.99718 -199.264587) (xy 275.97837 -199.27228) (xy 275.968206 -199.272652) (xy 274.568666 -199.272652)
			(xy 274.558536 -199.272201) (xy 274.539813 -199.264461) (xy 274.525457 -199.250164) (xy 274.517641 -199.231472)
			(xy 274.517104 -199.221344) (xy 268.475968 -199.221344) (xy 268.475614 -199.231505) (xy 268.467798 -199.250264)
			(xy 268.45338 -199.264587) (xy 268.43457 -199.27228) (xy 268.424406 -199.272652) (xy 267.024866 -199.272652)
			(xy 267.014736 -199.272201) (xy 266.996013 -199.264461) (xy 266.981657 -199.250164) (xy 266.973841 -199.231472)
			(xy 266.973304 -199.221344) (xy 260.932168 -199.221344) (xy 260.931814 -199.231505) (xy 260.923998 -199.250264)
			(xy 260.90958 -199.264587) (xy 260.89077 -199.27228) (xy 260.880606 -199.272652) (xy 259.481066 -199.272652)
			(xy 259.470936 -199.272201) (xy 259.452213 -199.264461) (xy 259.437857 -199.250164) (xy 259.430041 -199.231472)
			(xy 259.429504 -199.221344) (xy 216.4715 -199.221344) (xy 216.471114 -199.231501) (xy 216.463304 -199.250254)
			(xy 216.448897 -199.264576) (xy 216.430097 -199.272274) (xy 216.419938 -199.272652) (xy 215.020398 -199.272652)
			(xy 215.01027 -199.272175) (xy 214.991548 -199.264445) (xy 214.977191 -199.250156) (xy 214.969373 -199.231469)
			(xy 214.968836 -199.221344) (xy 208.9277 -199.221344) (xy 208.927314 -199.231501) (xy 208.919504 -199.250254)
			(xy 208.905097 -199.264576) (xy 208.886297 -199.272274) (xy 208.876138 -199.272652) (xy 207.476598 -199.272652)
			(xy 207.46647 -199.272175) (xy 207.447748 -199.264445) (xy 207.433391 -199.250156) (xy 207.425573 -199.231469)
			(xy 207.425036 -199.221344) (xy 201.3839 -199.221344) (xy 201.383514 -199.231501) (xy 201.375704 -199.250254)
			(xy 201.361297 -199.264576) (xy 201.342497 -199.272274) (xy 201.332338 -199.272652) (xy 199.932798 -199.272652)
			(xy 199.92267 -199.272175) (xy 199.903948 -199.264445) (xy 199.889591 -199.250156) (xy 199.881773 -199.231469)
			(xy 199.881236 -199.221344) (xy 193.8401 -199.221344) (xy 193.839714 -199.231501) (xy 193.831904 -199.250254)
			(xy 193.817497 -199.264576) (xy 193.798697 -199.272274) (xy 193.788538 -199.272652) (xy 192.388998 -199.272652)
			(xy 192.37887 -199.272175) (xy 192.360148 -199.264445) (xy 192.345791 -199.250156) (xy 192.337973 -199.231469)
			(xy 192.337436 -199.221344) (xy 186.2963 -199.221344) (xy 186.295914 -199.231501) (xy 186.288104 -199.250254)
			(xy 186.273697 -199.264576) (xy 186.254897 -199.272274) (xy 186.244738 -199.272652) (xy 184.845198 -199.272652)
			(xy 184.83507 -199.272175) (xy 184.816348 -199.264445) (xy 184.801991 -199.250156) (xy 184.794173 -199.231469)
			(xy 184.793636 -199.221344) (xy 178.7525 -199.221344) (xy 178.752114 -199.231501) (xy 178.744304 -199.250254)
			(xy 178.729897 -199.264576) (xy 178.711097 -199.272274) (xy 178.700938 -199.272652) (xy 177.301398 -199.272652)
			(xy 177.29127 -199.272175) (xy 177.272548 -199.264445) (xy 177.258191 -199.250156) (xy 177.250373 -199.231469)
			(xy 177.249836 -199.221344) (xy 171.2087 -199.221344) (xy 171.208314 -199.231501) (xy 171.200504 -199.250254)
			(xy 171.186097 -199.264576) (xy 171.167297 -199.272274) (xy 171.157138 -199.272652) (xy 169.757598 -199.272652)
			(xy 169.74747 -199.272175) (xy 169.728748 -199.264445) (xy 169.714391 -199.250156) (xy 169.706573 -199.231469)
			(xy 169.706036 -199.221344) (xy 163.6649 -199.221344) (xy 163.664514 -199.231501) (xy 163.656704 -199.250254)
			(xy 163.642297 -199.264576) (xy 163.623497 -199.272274) (xy 163.613338 -199.272652) (xy 162.213798 -199.272652)
			(xy 162.20367 -199.272175) (xy 162.184948 -199.264445) (xy 162.170591 -199.250156) (xy 162.162773 -199.231469)
			(xy 162.162236 -199.221344) (xy 65.7987 -199.221344) (xy 65.798314 -199.231501) (xy 65.790504 -199.250254)
			(xy 65.776097 -199.264576) (xy 65.757297 -199.272274) (xy 65.747138 -199.272652) (xy 64.347598 -199.272652)
			(xy 64.33747 -199.272175) (xy 64.318748 -199.264445) (xy 64.304391 -199.250156) (xy 64.296573 -199.231469)
			(xy 64.296036 -199.221344) (xy 58.2549 -199.221344) (xy 58.254514 -199.231501) (xy 58.246704 -199.250254)
			(xy 58.232297 -199.264576) (xy 58.213497 -199.272274) (xy 58.203338 -199.272652) (xy 56.803798 -199.272652)
			(xy 56.79367 -199.272175) (xy 56.774948 -199.264445) (xy 56.760591 -199.250156) (xy 56.752773 -199.231469)
			(xy 56.752236 -199.221344) (xy 50.7111 -199.221344) (xy 50.710714 -199.231501) (xy 50.702904 -199.250254)
			(xy 50.688497 -199.264576) (xy 50.669697 -199.272274) (xy 50.659538 -199.272652) (xy 49.259998 -199.272652)
			(xy 49.24987 -199.272175) (xy 49.231148 -199.264445) (xy 49.216791 -199.250156) (xy 49.208973 -199.231469)
			(xy 49.208436 -199.221344) (xy 43.1673 -199.221344) (xy 43.166914 -199.231501) (xy 43.159104 -199.250254)
			(xy 43.144697 -199.264576) (xy 43.125897 -199.272274) (xy 43.115738 -199.272652) (xy 41.716198 -199.272652)
			(xy 41.70607 -199.272175) (xy 41.687348 -199.264445) (xy 41.672991 -199.250156) (xy 41.665173 -199.231469)
			(xy 41.664636 -199.221344) (xy 35.6235 -199.221344) (xy 35.623114 -199.231501) (xy 35.615304 -199.250254)
			(xy 35.600897 -199.264576) (xy 35.582097 -199.272274) (xy 35.571938 -199.272652) (xy 34.172398 -199.272652)
			(xy 34.16227 -199.272175) (xy 34.143548 -199.264445) (xy 34.129191 -199.250156) (xy 34.121373 -199.231469)
			(xy 34.120836 -199.221344) (xy 28.0797 -199.221344) (xy 28.079314 -199.231501) (xy 28.071504 -199.250254)
			(xy 28.057097 -199.264576) (xy 28.038297 -199.272274) (xy 28.028138 -199.272652) (xy 26.628598 -199.272652)
			(xy 26.61847 -199.272175) (xy 26.599748 -199.264445) (xy 26.585391 -199.250156) (xy 26.577573 -199.231469)
			(xy 26.577036 -199.221344) (xy 20.5359 -199.221344) (xy 20.535514 -199.231501) (xy 20.527704 -199.250254)
			(xy 20.513297 -199.264576) (xy 20.494497 -199.272274) (xy 20.484338 -199.272652) (xy 19.084798 -199.272652)
			(xy 19.07467 -199.272175) (xy 19.055948 -199.264445) (xy 19.041591 -199.250156) (xy 19.033773 -199.231469)
			(xy 19.033236 -199.221344) (xy 12.9921 -199.221344) (xy 12.991714 -199.231501) (xy 12.983904 -199.250254)
			(xy 12.969497 -199.264576) (xy 12.950697 -199.272274) (xy 12.940538 -199.272652) (xy 11.540998 -199.272652)
			(xy 11.53087 -199.272175) (xy 11.512148 -199.264445) (xy 11.497791 -199.250156) (xy 11.489973 -199.231469)
			(xy 11.489436 -199.221344) (xy 2.509012 -199.221344) (xy 2.509012 -200.071482) (xy 7.389368 -200.071482)
			(xy 7.389368 -199.662542) (xy 7.389799 -199.652369) (xy 7.397576 -199.63357) (xy 7.41196 -199.619182)
			(xy 7.430757 -199.611401) (xy 7.44093 -199.61098) (xy 8.84047 -199.61098) (xy 8.850645 -199.61139)
			(xy 8.869447 -199.619172) (xy 8.883834 -199.633563) (xy 8.891613 -199.652367) (xy 8.892032 -199.662542)
			(xy 8.892032 -200.071482) (xy 11.489436 -200.071482) (xy 11.489436 -199.662542) (xy 11.489898 -199.652373)
			(xy 11.497669 -199.63358) (xy 11.512043 -199.619194) (xy 11.53083 -199.611407) (xy 11.540998 -199.61098)
			(xy 12.940538 -199.61098) (xy 12.950717 -199.611334) (xy 12.969521 -199.619139) (xy 12.983906 -199.633546)
			(xy 12.991682 -199.652362) (xy 12.9921 -199.662542) (xy 12.9921 -200.071482) (xy 14.933168 -200.071482)
			(xy 14.933168 -199.662542) (xy 14.933599 -199.652369) (xy 14.941376 -199.63357) (xy 14.95576 -199.619182)
			(xy 14.974557 -199.611401) (xy 14.98473 -199.61098) (xy 16.38427 -199.61098) (xy 16.394445 -199.61139)
			(xy 16.413247 -199.619172) (xy 16.427634 -199.633563) (xy 16.435413 -199.652367) (xy 16.435832 -199.662542)
			(xy 16.435832 -200.071482) (xy 19.033236 -200.071482) (xy 19.033236 -199.662542) (xy 19.033698 -199.652373)
			(xy 19.041469 -199.63358) (xy 19.055843 -199.619194) (xy 19.07463 -199.611407) (xy 19.084798 -199.61098)
			(xy 20.484338 -199.61098) (xy 20.494517 -199.611334) (xy 20.513321 -199.619139) (xy 20.527706 -199.633546)
			(xy 20.535482 -199.652362) (xy 20.5359 -199.662542) (xy 20.5359 -200.071482) (xy 22.476968 -200.071482)
			(xy 22.476968 -199.662542) (xy 22.477399 -199.652369) (xy 22.485176 -199.63357) (xy 22.49956 -199.619182)
			(xy 22.518357 -199.611401) (xy 22.52853 -199.61098) (xy 23.92807 -199.61098) (xy 23.938245 -199.61139)
			(xy 23.957047 -199.619172) (xy 23.971434 -199.633563) (xy 23.979213 -199.652367) (xy 23.979632 -199.662542)
			(xy 23.979632 -200.071482) (xy 26.577036 -200.071482) (xy 26.577036 -199.662542) (xy 26.577498 -199.652373)
			(xy 26.585269 -199.63358) (xy 26.599643 -199.619194) (xy 26.61843 -199.611407) (xy 26.628598 -199.61098)
			(xy 28.028138 -199.61098) (xy 28.038317 -199.611334) (xy 28.057121 -199.619139) (xy 28.071506 -199.633546)
			(xy 28.079282 -199.652362) (xy 28.0797 -199.662542) (xy 28.0797 -200.071482) (xy 30.020768 -200.071482)
			(xy 30.020768 -199.662542) (xy 30.021199 -199.652369) (xy 30.028976 -199.63357) (xy 30.04336 -199.619182)
			(xy 30.062157 -199.611401) (xy 30.07233 -199.61098) (xy 31.47187 -199.61098) (xy 31.482045 -199.61139)
			(xy 31.500847 -199.619172) (xy 31.515234 -199.633563) (xy 31.523013 -199.652367) (xy 31.523432 -199.662542)
			(xy 31.523432 -200.071482) (xy 34.120836 -200.071482) (xy 34.120836 -199.662542) (xy 34.121298 -199.652373)
			(xy 34.129069 -199.63358) (xy 34.143443 -199.619194) (xy 34.16223 -199.611407) (xy 34.172398 -199.61098)
			(xy 35.571938 -199.61098) (xy 35.582117 -199.611334) (xy 35.600921 -199.619139) (xy 35.615306 -199.633546)
			(xy 35.623082 -199.652362) (xy 35.6235 -199.662542) (xy 35.6235 -200.071482) (xy 37.564568 -200.071482)
			(xy 37.564568 -199.662542) (xy 37.564999 -199.652369) (xy 37.572776 -199.63357) (xy 37.58716 -199.619182)
			(xy 37.605957 -199.611401) (xy 37.61613 -199.61098) (xy 39.01567 -199.61098) (xy 39.025845 -199.61139)
			(xy 39.044647 -199.619172) (xy 39.059034 -199.633563) (xy 39.066813 -199.652367) (xy 39.067232 -199.662542)
			(xy 39.067232 -200.071482) (xy 41.664636 -200.071482) (xy 41.664636 -199.662542) (xy 41.665098 -199.652373)
			(xy 41.672869 -199.63358) (xy 41.687243 -199.619194) (xy 41.70603 -199.611407) (xy 41.716198 -199.61098)
			(xy 43.115738 -199.61098) (xy 43.125917 -199.611334) (xy 43.144721 -199.619139) (xy 43.159106 -199.633546)
			(xy 43.166882 -199.652362) (xy 43.1673 -199.662542) (xy 43.1673 -200.071482) (xy 45.108368 -200.071482)
			(xy 45.108368 -199.662542) (xy 45.108799 -199.652369) (xy 45.116576 -199.63357) (xy 45.13096 -199.619182)
			(xy 45.149757 -199.611401) (xy 45.15993 -199.61098) (xy 46.55947 -199.61098) (xy 46.569645 -199.61139)
			(xy 46.588447 -199.619172) (xy 46.602834 -199.633563) (xy 46.610613 -199.652367) (xy 46.611032 -199.662542)
			(xy 46.611032 -200.071482) (xy 49.208436 -200.071482) (xy 49.208436 -199.662542) (xy 49.208898 -199.652373)
			(xy 49.216669 -199.63358) (xy 49.231043 -199.619194) (xy 49.24983 -199.611407) (xy 49.259998 -199.61098)
			(xy 50.659538 -199.61098) (xy 50.669717 -199.611334) (xy 50.688521 -199.619139) (xy 50.702906 -199.633546)
			(xy 50.710682 -199.652362) (xy 50.7111 -199.662542) (xy 50.7111 -200.071482) (xy 52.652168 -200.071482)
			(xy 52.652168 -199.662542) (xy 52.652599 -199.652369) (xy 52.660376 -199.63357) (xy 52.67476 -199.619182)
			(xy 52.693557 -199.611401) (xy 52.70373 -199.61098) (xy 54.10327 -199.61098) (xy 54.113445 -199.61139)
			(xy 54.132247 -199.619172) (xy 54.146634 -199.633563) (xy 54.154413 -199.652367) (xy 54.154832 -199.662542)
			(xy 54.154832 -200.071482) (xy 56.752236 -200.071482) (xy 56.752236 -199.662542) (xy 56.752698 -199.652373)
			(xy 56.760469 -199.63358) (xy 56.774843 -199.619194) (xy 56.79363 -199.611407) (xy 56.803798 -199.61098)
			(xy 58.203338 -199.61098) (xy 58.213517 -199.611334) (xy 58.232321 -199.619139) (xy 58.246706 -199.633546)
			(xy 58.254482 -199.652362) (xy 58.2549 -199.662542) (xy 58.2549 -200.071482) (xy 60.195968 -200.071482)
			(xy 60.195968 -199.662542) (xy 60.196399 -199.652369) (xy 60.204176 -199.63357) (xy 60.21856 -199.619182)
			(xy 60.237357 -199.611401) (xy 60.24753 -199.61098) (xy 61.64707 -199.61098) (xy 61.657245 -199.61139)
			(xy 61.676047 -199.619172) (xy 61.690434 -199.633563) (xy 61.698213 -199.652367) (xy 61.698632 -199.662542)
			(xy 61.698632 -200.071482) (xy 64.296036 -200.071482) (xy 64.296036 -199.662542) (xy 64.296498 -199.652373)
			(xy 64.304269 -199.63358) (xy 64.318643 -199.619194) (xy 64.33743 -199.611407) (xy 64.347598 -199.61098)
			(xy 65.747138 -199.61098) (xy 65.757317 -199.611334) (xy 65.776121 -199.619139) (xy 65.790506 -199.633546)
			(xy 65.798282 -199.652362) (xy 65.7987 -199.662542) (xy 65.7987 -200.071482) (xy 158.062168 -200.071482)
			(xy 158.062168 -199.662542) (xy 158.062599 -199.652369) (xy 158.070376 -199.63357) (xy 158.08476 -199.619182)
			(xy 158.103557 -199.611401) (xy 158.11373 -199.61098) (xy 159.51327 -199.61098) (xy 159.523445 -199.61139)
			(xy 159.542247 -199.619172) (xy 159.556634 -199.633563) (xy 159.564413 -199.652367) (xy 159.564832 -199.662542)
			(xy 159.564832 -200.071482) (xy 162.162236 -200.071482) (xy 162.162236 -199.662542) (xy 162.162698 -199.652373)
			(xy 162.170469 -199.63358) (xy 162.184843 -199.619194) (xy 162.20363 -199.611407) (xy 162.213798 -199.61098)
			(xy 163.613338 -199.61098) (xy 163.623517 -199.611334) (xy 163.642321 -199.619139) (xy 163.656706 -199.633546)
			(xy 163.664482 -199.652362) (xy 163.6649 -199.662542) (xy 163.6649 -200.071482) (xy 165.605968 -200.071482)
			(xy 165.605968 -199.662542) (xy 165.606399 -199.652369) (xy 165.614176 -199.63357) (xy 165.62856 -199.619182)
			(xy 165.647357 -199.611401) (xy 165.65753 -199.61098) (xy 167.05707 -199.61098) (xy 167.067245 -199.61139)
			(xy 167.086047 -199.619172) (xy 167.100434 -199.633563) (xy 167.108213 -199.652367) (xy 167.108632 -199.662542)
			(xy 167.108632 -200.071482) (xy 169.706036 -200.071482) (xy 169.706036 -199.662542) (xy 169.706498 -199.652373)
			(xy 169.714269 -199.63358) (xy 169.728643 -199.619194) (xy 169.74743 -199.611407) (xy 169.757598 -199.61098)
			(xy 171.157138 -199.61098) (xy 171.167317 -199.611334) (xy 171.186121 -199.619139) (xy 171.200506 -199.633546)
			(xy 171.208282 -199.652362) (xy 171.2087 -199.662542) (xy 171.2087 -200.071482) (xy 173.149768 -200.071482)
			(xy 173.149768 -199.662542) (xy 173.150199 -199.652369) (xy 173.157976 -199.63357) (xy 173.17236 -199.619182)
			(xy 173.191157 -199.611401) (xy 173.20133 -199.61098) (xy 174.60087 -199.61098) (xy 174.611045 -199.61139)
			(xy 174.629847 -199.619172) (xy 174.644234 -199.633563) (xy 174.652013 -199.652367) (xy 174.652432 -199.662542)
			(xy 174.652432 -200.071482) (xy 177.249836 -200.071482) (xy 177.249836 -199.662542) (xy 177.250298 -199.652373)
			(xy 177.258069 -199.63358) (xy 177.272443 -199.619194) (xy 177.29123 -199.611407) (xy 177.301398 -199.61098)
			(xy 178.700938 -199.61098) (xy 178.711117 -199.611334) (xy 178.729921 -199.619139) (xy 178.744306 -199.633546)
			(xy 178.752082 -199.652362) (xy 178.7525 -199.662542) (xy 178.7525 -200.071482) (xy 180.693568 -200.071482)
			(xy 180.693568 -199.662542) (xy 180.693999 -199.652369) (xy 180.701776 -199.63357) (xy 180.71616 -199.619182)
			(xy 180.734957 -199.611401) (xy 180.74513 -199.61098) (xy 182.14467 -199.61098) (xy 182.154845 -199.61139)
			(xy 182.173647 -199.619172) (xy 182.188034 -199.633563) (xy 182.195813 -199.652367) (xy 182.196232 -199.662542)
			(xy 182.196232 -200.071482) (xy 184.793636 -200.071482) (xy 184.793636 -199.662542) (xy 184.794098 -199.652373)
			(xy 184.801869 -199.63358) (xy 184.816243 -199.619194) (xy 184.83503 -199.611407) (xy 184.845198 -199.61098)
			(xy 186.244738 -199.61098) (xy 186.254917 -199.611334) (xy 186.273721 -199.619139) (xy 186.288106 -199.633546)
			(xy 186.295882 -199.652362) (xy 186.2963 -199.662542) (xy 186.2963 -200.071482) (xy 188.237368 -200.071482)
			(xy 188.237368 -199.662542) (xy 188.237799 -199.652369) (xy 188.245576 -199.63357) (xy 188.25996 -199.619182)
			(xy 188.278757 -199.611401) (xy 188.28893 -199.61098) (xy 189.68847 -199.61098) (xy 189.698645 -199.61139)
			(xy 189.717447 -199.619172) (xy 189.731834 -199.633563) (xy 189.739613 -199.652367) (xy 189.740032 -199.662542)
			(xy 189.740032 -200.071482) (xy 192.337436 -200.071482) (xy 192.337436 -199.662542) (xy 192.337898 -199.652373)
			(xy 192.345669 -199.63358) (xy 192.360043 -199.619194) (xy 192.37883 -199.611407) (xy 192.388998 -199.61098)
			(xy 193.788538 -199.61098) (xy 193.798717 -199.611334) (xy 193.817521 -199.619139) (xy 193.831906 -199.633546)
			(xy 193.839682 -199.652362) (xy 193.8401 -199.662542) (xy 193.8401 -200.071482) (xy 195.781168 -200.071482)
			(xy 195.781168 -199.662542) (xy 195.781599 -199.652369) (xy 195.789376 -199.63357) (xy 195.80376 -199.619182)
			(xy 195.822557 -199.611401) (xy 195.83273 -199.61098) (xy 197.23227 -199.61098) (xy 197.242445 -199.61139)
			(xy 197.261247 -199.619172) (xy 197.275634 -199.633563) (xy 197.283413 -199.652367) (xy 197.283832 -199.662542)
			(xy 197.283832 -200.071482) (xy 199.881236 -200.071482) (xy 199.881236 -199.662542) (xy 199.881698 -199.652373)
			(xy 199.889469 -199.63358) (xy 199.903843 -199.619194) (xy 199.92263 -199.611407) (xy 199.932798 -199.61098)
			(xy 201.332338 -199.61098) (xy 201.342517 -199.611334) (xy 201.361321 -199.619139) (xy 201.375706 -199.633546)
			(xy 201.383482 -199.652362) (xy 201.3839 -199.662542) (xy 201.3839 -200.071482) (xy 203.324968 -200.071482)
			(xy 203.324968 -199.662542) (xy 203.325399 -199.652369) (xy 203.333176 -199.63357) (xy 203.34756 -199.619182)
			(xy 203.366357 -199.611401) (xy 203.37653 -199.61098) (xy 204.77607 -199.61098) (xy 204.786245 -199.61139)
			(xy 204.805047 -199.619172) (xy 204.819434 -199.633563) (xy 204.827213 -199.652367) (xy 204.827632 -199.662542)
			(xy 204.827632 -200.071482) (xy 207.425036 -200.071482) (xy 207.425036 -199.662542) (xy 207.425498 -199.652373)
			(xy 207.433269 -199.63358) (xy 207.447643 -199.619194) (xy 207.46643 -199.611407) (xy 207.476598 -199.61098)
			(xy 208.876138 -199.61098) (xy 208.886317 -199.611334) (xy 208.905121 -199.619139) (xy 208.919506 -199.633546)
			(xy 208.927282 -199.652362) (xy 208.9277 -199.662542) (xy 208.9277 -200.071482) (xy 210.868768 -200.071482)
			(xy 210.868768 -199.662542) (xy 210.869199 -199.652369) (xy 210.876976 -199.63357) (xy 210.89136 -199.619182)
			(xy 210.910157 -199.611401) (xy 210.92033 -199.61098) (xy 212.31987 -199.61098) (xy 212.330045 -199.61139)
			(xy 212.348847 -199.619172) (xy 212.363234 -199.633563) (xy 212.371013 -199.652367) (xy 212.371432 -199.662542)
			(xy 212.371432 -200.071482) (xy 214.968836 -200.071482) (xy 214.968836 -199.662542) (xy 214.969298 -199.652373)
			(xy 214.977069 -199.63358) (xy 214.991443 -199.619194) (xy 215.01023 -199.611407) (xy 215.020398 -199.61098)
			(xy 216.419938 -199.61098) (xy 216.430117 -199.611334) (xy 216.448921 -199.619139) (xy 216.463306 -199.633546)
			(xy 216.471082 -199.652362) (xy 216.4715 -199.662542) (xy 216.4715 -200.071482) (xy 255.329436 -200.071482)
			(xy 255.329436 -199.662542) (xy 255.329898 -199.652373) (xy 255.337669 -199.63358) (xy 255.352043 -199.619194)
			(xy 255.37083 -199.611407) (xy 255.380998 -199.61098) (xy 256.780538 -199.61098) (xy 256.790717 -199.611334)
			(xy 256.809521 -199.619139) (xy 256.823906 -199.633546) (xy 256.831682 -199.652362) (xy 256.8321 -199.662542)
			(xy 256.8321 -200.071482) (xy 259.429504 -200.071482) (xy 259.429504 -199.662542) (xy 259.429997 -199.652377)
			(xy 259.437762 -199.63359) (xy 259.452126 -199.619205) (xy 259.470902 -199.611412) (xy 259.481066 -199.61098)
			(xy 260.880606 -199.61098) (xy 260.890783 -199.61136) (xy 260.909586 -199.619155) (xy 260.923972 -199.633554)
			(xy 260.931749 -199.652364) (xy 260.932168 -199.662542) (xy 260.932168 -200.071482) (xy 262.873236 -200.071482)
			(xy 262.873236 -199.662542) (xy 262.873698 -199.652373) (xy 262.881469 -199.63358) (xy 262.895843 -199.619194)
			(xy 262.91463 -199.611407) (xy 262.924798 -199.61098) (xy 264.324338 -199.61098) (xy 264.334517 -199.611334)
			(xy 264.353321 -199.619139) (xy 264.367706 -199.633546) (xy 264.375482 -199.652362) (xy 264.3759 -199.662542)
			(xy 264.3759 -200.071482) (xy 266.973304 -200.071482) (xy 266.973304 -199.662542) (xy 266.973797 -199.652377)
			(xy 266.981562 -199.63359) (xy 266.995926 -199.619205) (xy 267.014702 -199.611412) (xy 267.024866 -199.61098)
			(xy 268.424406 -199.61098) (xy 268.434583 -199.61136) (xy 268.453386 -199.619155) (xy 268.467772 -199.633554)
			(xy 268.475549 -199.652364) (xy 268.475968 -199.662542) (xy 268.475968 -200.071482) (xy 270.417036 -200.071482)
			(xy 270.417036 -199.662542) (xy 270.417498 -199.652373) (xy 270.425269 -199.63358) (xy 270.439643 -199.619194)
			(xy 270.45843 -199.611407) (xy 270.468598 -199.61098) (xy 271.868138 -199.61098) (xy 271.878317 -199.611334)
			(xy 271.897121 -199.619139) (xy 271.911506 -199.633546) (xy 271.919282 -199.652362) (xy 271.9197 -199.662542)
			(xy 271.9197 -200.071482) (xy 274.517104 -200.071482) (xy 274.517104 -199.662542) (xy 274.517597 -199.652377)
			(xy 274.525362 -199.63359) (xy 274.539726 -199.619205) (xy 274.558502 -199.611412) (xy 274.568666 -199.61098)
			(xy 275.968206 -199.61098) (xy 275.978383 -199.61136) (xy 275.997186 -199.619155) (xy 276.011572 -199.633554)
			(xy 276.019349 -199.652364) (xy 276.019768 -199.662542) (xy 276.019768 -200.071482) (xy 277.960836 -200.071482)
			(xy 277.960836 -199.662542) (xy 277.961298 -199.652373) (xy 277.969069 -199.63358) (xy 277.983443 -199.619194)
			(xy 278.00223 -199.611407) (xy 278.012398 -199.61098) (xy 279.411938 -199.61098) (xy 279.422117 -199.611334)
			(xy 279.440921 -199.619139) (xy 279.455306 -199.633546) (xy 279.463082 -199.652362) (xy 279.4635 -199.662542)
			(xy 279.4635 -200.071482) (xy 282.060904 -200.071482) (xy 282.060904 -199.662542) (xy 282.061397 -199.652377)
			(xy 282.069162 -199.63359) (xy 282.083526 -199.619205) (xy 282.102302 -199.611412) (xy 282.112466 -199.61098)
			(xy 283.512006 -199.61098) (xy 283.522183 -199.61136) (xy 283.540986 -199.619155) (xy 283.555372 -199.633554)
			(xy 283.563149 -199.652364) (xy 283.563568 -199.662542) (xy 283.563568 -200.071482) (xy 285.504636 -200.071482)
			(xy 285.504636 -199.662542) (xy 285.505098 -199.652373) (xy 285.512869 -199.63358) (xy 285.527243 -199.619194)
			(xy 285.54603 -199.611407) (xy 285.556198 -199.61098) (xy 286.955738 -199.61098) (xy 286.965917 -199.611334)
			(xy 286.984721 -199.619139) (xy 286.999106 -199.633546) (xy 287.006882 -199.652362) (xy 287.0073 -199.662542)
			(xy 287.0073 -200.071482) (xy 289.604704 -200.071482) (xy 289.604704 -199.662542) (xy 289.605197 -199.652377)
			(xy 289.612962 -199.63359) (xy 289.627326 -199.619205) (xy 289.646102 -199.611412) (xy 289.656266 -199.61098)
			(xy 291.055806 -199.61098) (xy 291.065983 -199.61136) (xy 291.084786 -199.619155) (xy 291.099172 -199.633554)
			(xy 291.106949 -199.652364) (xy 291.107368 -199.662542) (xy 291.107368 -200.071482) (xy 293.048436 -200.071482)
			(xy 293.048436 -199.662542) (xy 293.048898 -199.652373) (xy 293.056669 -199.63358) (xy 293.071043 -199.619194)
			(xy 293.08983 -199.611407) (xy 293.099998 -199.61098) (xy 294.499538 -199.61098) (xy 294.509717 -199.611334)
			(xy 294.528521 -199.619139) (xy 294.542906 -199.633546) (xy 294.550682 -199.652362) (xy 294.5511 -199.662542)
			(xy 294.5511 -200.071482) (xy 297.148504 -200.071482) (xy 297.148504 -199.662542) (xy 297.148997 -199.652377)
			(xy 297.156762 -199.63359) (xy 297.171126 -199.619205) (xy 297.189902 -199.611412) (xy 297.200066 -199.61098)
			(xy 298.599606 -199.61098) (xy 298.609783 -199.61136) (xy 298.628586 -199.619155) (xy 298.642972 -199.633554)
			(xy 298.650749 -199.652364) (xy 298.651168 -199.662542) (xy 298.651168 -200.071482) (xy 300.592236 -200.071482)
			(xy 300.592236 -199.662542) (xy 300.592698 -199.652373) (xy 300.600469 -199.63358) (xy 300.614843 -199.619194)
			(xy 300.63363 -199.611407) (xy 300.643798 -199.61098) (xy 302.043338 -199.61098) (xy 302.053517 -199.611334)
			(xy 302.072321 -199.619139) (xy 302.086706 -199.633546) (xy 302.094482 -199.652362) (xy 302.0949 -199.662542)
			(xy 302.0949 -200.071482) (xy 304.692304 -200.071482) (xy 304.692304 -199.662542) (xy 304.692797 -199.652377)
			(xy 304.700562 -199.63359) (xy 304.714926 -199.619205) (xy 304.733702 -199.611412) (xy 304.743866 -199.61098)
			(xy 306.143406 -199.61098) (xy 306.153583 -199.61136) (xy 306.172386 -199.619155) (xy 306.186772 -199.633554)
			(xy 306.194549 -199.652364) (xy 306.194968 -199.662542) (xy 306.194968 -200.071482) (xy 308.136036 -200.071482)
			(xy 308.136036 -199.662542) (xy 308.136498 -199.652373) (xy 308.144269 -199.63358) (xy 308.158643 -199.619194)
			(xy 308.17743 -199.611407) (xy 308.187598 -199.61098) (xy 309.587138 -199.61098) (xy 309.597317 -199.611334)
			(xy 309.616121 -199.619139) (xy 309.630506 -199.633546) (xy 309.638282 -199.652362) (xy 309.6387 -199.662542)
			(xy 309.6387 -200.071482) (xy 312.236104 -200.071482) (xy 312.236104 -199.662542) (xy 312.236597 -199.652377)
			(xy 312.244362 -199.63359) (xy 312.258726 -199.619205) (xy 312.277502 -199.611412) (xy 312.287666 -199.61098)
			(xy 313.687206 -199.61098) (xy 313.697383 -199.61136) (xy 313.716186 -199.619155) (xy 313.730572 -199.633554)
			(xy 313.738349 -199.652364) (xy 313.738768 -199.662542) (xy 313.738768 -200.071482) (xy 406.002236 -200.071482)
			(xy 406.002236 -199.662542) (xy 406.002698 -199.652373) (xy 406.010469 -199.63358) (xy 406.024843 -199.619194)
			(xy 406.04363 -199.611407) (xy 406.053798 -199.61098) (xy 407.453338 -199.61098) (xy 407.463517 -199.611334)
			(xy 407.482321 -199.619139) (xy 407.496706 -199.633546) (xy 407.504482 -199.652362) (xy 407.5049 -199.662542)
			(xy 407.5049 -200.071482) (xy 410.102304 -200.071482) (xy 410.102304 -199.662542) (xy 410.102797 -199.652377)
			(xy 410.110562 -199.63359) (xy 410.124926 -199.619205) (xy 410.143702 -199.611412) (xy 410.153866 -199.61098)
			(xy 411.553406 -199.61098) (xy 411.563583 -199.61136) (xy 411.582386 -199.619155) (xy 411.596772 -199.633554)
			(xy 411.604549 -199.652364) (xy 411.604968 -199.662542) (xy 411.604968 -200.071482) (xy 413.546036 -200.071482)
			(xy 413.546036 -199.662542) (xy 413.546498 -199.652373) (xy 413.554269 -199.63358) (xy 413.568643 -199.619194)
			(xy 413.58743 -199.611407) (xy 413.597598 -199.61098) (xy 414.997138 -199.61098) (xy 415.007317 -199.611334)
			(xy 415.026121 -199.619139) (xy 415.040506 -199.633546) (xy 415.048282 -199.652362) (xy 415.0487 -199.662542)
			(xy 415.0487 -200.071482) (xy 417.646104 -200.071482) (xy 417.646104 -199.662542) (xy 417.646597 -199.652377)
			(xy 417.654362 -199.63359) (xy 417.668726 -199.619205) (xy 417.687502 -199.611412) (xy 417.697666 -199.61098)
			(xy 419.097206 -199.61098) (xy 419.107383 -199.61136) (xy 419.126186 -199.619155) (xy 419.140572 -199.633554)
			(xy 419.148349 -199.652364) (xy 419.148768 -199.662542) (xy 419.148768 -200.071482) (xy 421.089836 -200.071482)
			(xy 421.089836 -199.662542) (xy 421.090298 -199.652373) (xy 421.098069 -199.63358) (xy 421.112443 -199.619194)
			(xy 421.13123 -199.611407) (xy 421.141398 -199.61098) (xy 422.540938 -199.61098) (xy 422.551117 -199.611334)
			(xy 422.569921 -199.619139) (xy 422.584306 -199.633546) (xy 422.592082 -199.652362) (xy 422.5925 -199.662542)
			(xy 422.5925 -200.071482) (xy 425.189904 -200.071482) (xy 425.189904 -199.662542) (xy 425.190397 -199.652377)
			(xy 425.198162 -199.63359) (xy 425.212526 -199.619205) (xy 425.231302 -199.611412) (xy 425.241466 -199.61098)
			(xy 426.641006 -199.61098) (xy 426.651183 -199.61136) (xy 426.669986 -199.619155) (xy 426.684372 -199.633554)
			(xy 426.692149 -199.652364) (xy 426.692568 -199.662542) (xy 426.692568 -200.071482) (xy 428.633636 -200.071482)
			(xy 428.633636 -199.662542) (xy 428.634098 -199.652373) (xy 428.641869 -199.63358) (xy 428.656243 -199.619194)
			(xy 428.67503 -199.611407) (xy 428.685198 -199.61098) (xy 430.084738 -199.61098) (xy 430.094917 -199.611334)
			(xy 430.113721 -199.619139) (xy 430.128106 -199.633546) (xy 430.135882 -199.652362) (xy 430.1363 -199.662542)
			(xy 430.1363 -200.071482) (xy 432.733704 -200.071482) (xy 432.733704 -199.662542) (xy 432.734197 -199.652377)
			(xy 432.741962 -199.63359) (xy 432.756326 -199.619205) (xy 432.775102 -199.611412) (xy 432.785266 -199.61098)
			(xy 434.184806 -199.61098) (xy 434.194983 -199.61136) (xy 434.213786 -199.619155) (xy 434.228172 -199.633554)
			(xy 434.235949 -199.652364) (xy 434.236368 -199.662542) (xy 434.236368 -200.071482) (xy 436.177436 -200.071482)
			(xy 436.177436 -199.662542) (xy 436.177898 -199.652373) (xy 436.185669 -199.63358) (xy 436.200043 -199.619194)
			(xy 436.21883 -199.611407) (xy 436.228998 -199.61098) (xy 437.628538 -199.61098) (xy 437.638717 -199.611334)
			(xy 437.657521 -199.619139) (xy 437.671906 -199.633546) (xy 437.679682 -199.652362) (xy 437.6801 -199.662542)
			(xy 437.6801 -200.071482) (xy 440.277504 -200.071482) (xy 440.277504 -199.662542) (xy 440.277997 -199.652377)
			(xy 440.285762 -199.63359) (xy 440.300126 -199.619205) (xy 440.318902 -199.611412) (xy 440.329066 -199.61098)
			(xy 441.728606 -199.61098) (xy 441.738783 -199.61136) (xy 441.757586 -199.619155) (xy 441.771972 -199.633554)
			(xy 441.779749 -199.652364) (xy 441.780168 -199.662542) (xy 441.780168 -200.071482) (xy 443.721236 -200.071482)
			(xy 443.721236 -199.662542) (xy 443.721698 -199.652373) (xy 443.729469 -199.63358) (xy 443.743843 -199.619194)
			(xy 443.76263 -199.611407) (xy 443.772798 -199.61098) (xy 445.172338 -199.61098) (xy 445.182517 -199.611334)
			(xy 445.201321 -199.619139) (xy 445.215706 -199.633546) (xy 445.223482 -199.652362) (xy 445.2239 -199.662542)
			(xy 445.2239 -200.071482) (xy 447.821304 -200.071482) (xy 447.821304 -199.662542) (xy 447.821797 -199.652377)
			(xy 447.829562 -199.63359) (xy 447.843926 -199.619205) (xy 447.862702 -199.611412) (xy 447.872866 -199.61098)
			(xy 449.272406 -199.61098) (xy 449.282583 -199.61136) (xy 449.301386 -199.619155) (xy 449.315772 -199.633554)
			(xy 449.323549 -199.652364) (xy 449.323968 -199.662542) (xy 449.323968 -200.071482) (xy 451.265036 -200.071482)
			(xy 451.265036 -199.662542) (xy 451.265498 -199.652373) (xy 451.273269 -199.63358) (xy 451.287643 -199.619194)
			(xy 451.30643 -199.611407) (xy 451.316598 -199.61098) (xy 452.716138 -199.61098) (xy 452.726317 -199.611334)
			(xy 452.745121 -199.619139) (xy 452.759506 -199.633546) (xy 452.767282 -199.652362) (xy 452.7677 -199.662542)
			(xy 452.7677 -200.071482) (xy 455.365104 -200.071482) (xy 455.365104 -199.662542) (xy 455.365597 -199.652377)
			(xy 455.373362 -199.63359) (xy 455.387726 -199.619205) (xy 455.406502 -199.611412) (xy 455.416666 -199.61098)
			(xy 456.816206 -199.61098) (xy 456.826383 -199.61136) (xy 456.845186 -199.619155) (xy 456.859572 -199.633554)
			(xy 456.867349 -199.652364) (xy 456.867768 -199.662542) (xy 456.867768 -200.071482) (xy 458.808836 -200.071482)
			(xy 458.808836 -199.662542) (xy 458.809298 -199.652373) (xy 458.817069 -199.63358) (xy 458.831443 -199.619194)
			(xy 458.85023 -199.611407) (xy 458.860398 -199.61098) (xy 460.259938 -199.61098) (xy 460.270117 -199.611334)
			(xy 460.288921 -199.619139) (xy 460.303306 -199.633546) (xy 460.311082 -199.652362) (xy 460.3115 -199.662542)
			(xy 460.3115 -200.071482) (xy 462.908904 -200.071482) (xy 462.908904 -199.662542) (xy 462.909397 -199.652377)
			(xy 462.917162 -199.63359) (xy 462.931526 -199.619205) (xy 462.950302 -199.611412) (xy 462.960466 -199.61098)
			(xy 464.360006 -199.61098) (xy 464.370183 -199.61136) (xy 464.388986 -199.619155) (xy 464.403372 -199.633554)
			(xy 464.411149 -199.652364) (xy 464.411568 -199.662542) (xy 464.411568 -200.071482) (xy 464.411122 -200.081652)
			(xy 464.403344 -200.100445) (xy 464.388965 -200.11483) (xy 464.370176 -200.122617) (xy 464.360006 -200.123044)
			(xy 462.960466 -200.123044) (xy 462.950304 -200.122594) (xy 462.93153 -200.114805) (xy 462.917166 -200.100426)
			(xy 462.909396 -200.081645) (xy 462.908904 -200.071482) (xy 460.3115 -200.071482) (xy 460.310953 -200.081634)
			(xy 460.303191 -200.100395) (xy 460.288842 -200.11476) (xy 460.270089 -200.122542) (xy 460.259938 -200.123044)
			(xy 458.860398 -200.123044) (xy 458.850224 -200.122637) (xy 458.831426 -200.114848) (xy 458.81704 -200.100457)
			(xy 458.809259 -200.081656) (xy 458.808836 -200.071482) (xy 456.867768 -200.071482) (xy 456.867322 -200.081652)
			(xy 456.859544 -200.100445) (xy 456.845165 -200.11483) (xy 456.826376 -200.122617) (xy 456.816206 -200.123044)
			(xy 455.416666 -200.123044) (xy 455.406504 -200.122594) (xy 455.38773 -200.114805) (xy 455.373366 -200.100426)
			(xy 455.365596 -200.081645) (xy 455.365104 -200.071482) (xy 452.7677 -200.071482) (xy 452.767153 -200.081634)
			(xy 452.759391 -200.100395) (xy 452.745042 -200.11476) (xy 452.726289 -200.122542) (xy 452.716138 -200.123044)
			(xy 451.316598 -200.123044) (xy 451.306424 -200.122637) (xy 451.287626 -200.114848) (xy 451.27324 -200.100457)
			(xy 451.265459 -200.081656) (xy 451.265036 -200.071482) (xy 449.323968 -200.071482) (xy 449.323522 -200.081652)
			(xy 449.315744 -200.100445) (xy 449.301365 -200.11483) (xy 449.282576 -200.122617) (xy 449.272406 -200.123044)
			(xy 447.872866 -200.123044) (xy 447.862704 -200.122594) (xy 447.84393 -200.114805) (xy 447.829566 -200.100426)
			(xy 447.821796 -200.081645) (xy 447.821304 -200.071482) (xy 445.2239 -200.071482) (xy 445.223353 -200.081634)
			(xy 445.215591 -200.100395) (xy 445.201242 -200.11476) (xy 445.182489 -200.122542) (xy 445.172338 -200.123044)
			(xy 443.772798 -200.123044) (xy 443.762624 -200.122637) (xy 443.743826 -200.114848) (xy 443.72944 -200.100457)
			(xy 443.721659 -200.081656) (xy 443.721236 -200.071482) (xy 441.780168 -200.071482) (xy 441.779722 -200.081652)
			(xy 441.771944 -200.100445) (xy 441.757565 -200.11483) (xy 441.738776 -200.122617) (xy 441.728606 -200.123044)
			(xy 440.329066 -200.123044) (xy 440.318904 -200.122594) (xy 440.30013 -200.114805) (xy 440.285766 -200.100426)
			(xy 440.277996 -200.081645) (xy 440.277504 -200.071482) (xy 437.6801 -200.071482) (xy 437.679553 -200.081634)
			(xy 437.671791 -200.100395) (xy 437.657442 -200.11476) (xy 437.638689 -200.122542) (xy 437.628538 -200.123044)
			(xy 436.228998 -200.123044) (xy 436.218824 -200.122637) (xy 436.200026 -200.114848) (xy 436.18564 -200.100457)
			(xy 436.177859 -200.081656) (xy 436.177436 -200.071482) (xy 434.236368 -200.071482) (xy 434.235922 -200.081652)
			(xy 434.228144 -200.100445) (xy 434.213765 -200.11483) (xy 434.194976 -200.122617) (xy 434.184806 -200.123044)
			(xy 432.785266 -200.123044) (xy 432.775104 -200.122594) (xy 432.75633 -200.114805) (xy 432.741966 -200.100426)
			(xy 432.734196 -200.081645) (xy 432.733704 -200.071482) (xy 430.1363 -200.071482) (xy 430.135753 -200.081634)
			(xy 430.127991 -200.100395) (xy 430.113642 -200.11476) (xy 430.094889 -200.122542) (xy 430.084738 -200.123044)
			(xy 428.685198 -200.123044) (xy 428.675024 -200.122637) (xy 428.656226 -200.114848) (xy 428.64184 -200.100457)
			(xy 428.634059 -200.081656) (xy 428.633636 -200.071482) (xy 426.692568 -200.071482) (xy 426.692122 -200.081652)
			(xy 426.684344 -200.100445) (xy 426.669965 -200.11483) (xy 426.651176 -200.122617) (xy 426.641006 -200.123044)
			(xy 425.241466 -200.123044) (xy 425.231304 -200.122594) (xy 425.21253 -200.114805) (xy 425.198166 -200.100426)
			(xy 425.190396 -200.081645) (xy 425.189904 -200.071482) (xy 422.5925 -200.071482) (xy 422.591953 -200.081634)
			(xy 422.584191 -200.100395) (xy 422.569842 -200.11476) (xy 422.551089 -200.122542) (xy 422.540938 -200.123044)
			(xy 421.141398 -200.123044) (xy 421.131224 -200.122637) (xy 421.112426 -200.114848) (xy 421.09804 -200.100457)
			(xy 421.090259 -200.081656) (xy 421.089836 -200.071482) (xy 419.148768 -200.071482) (xy 419.148322 -200.081652)
			(xy 419.140544 -200.100445) (xy 419.126165 -200.11483) (xy 419.107376 -200.122617) (xy 419.097206 -200.123044)
			(xy 417.697666 -200.123044) (xy 417.687504 -200.122594) (xy 417.66873 -200.114805) (xy 417.654366 -200.100426)
			(xy 417.646596 -200.081645) (xy 417.646104 -200.071482) (xy 415.0487 -200.071482) (xy 415.048153 -200.081634)
			(xy 415.040391 -200.100395) (xy 415.026042 -200.11476) (xy 415.007289 -200.122542) (xy 414.997138 -200.123044)
			(xy 413.597598 -200.123044) (xy 413.587424 -200.122637) (xy 413.568626 -200.114848) (xy 413.55424 -200.100457)
			(xy 413.546459 -200.081656) (xy 413.546036 -200.071482) (xy 411.604968 -200.071482) (xy 411.604522 -200.081652)
			(xy 411.596744 -200.100445) (xy 411.582365 -200.11483) (xy 411.563576 -200.122617) (xy 411.553406 -200.123044)
			(xy 410.153866 -200.123044) (xy 410.143704 -200.122594) (xy 410.12493 -200.114805) (xy 410.110566 -200.100426)
			(xy 410.102796 -200.081645) (xy 410.102304 -200.071482) (xy 407.5049 -200.071482) (xy 407.504353 -200.081634)
			(xy 407.496591 -200.100395) (xy 407.482242 -200.11476) (xy 407.463489 -200.122542) (xy 407.453338 -200.123044)
			(xy 406.053798 -200.123044) (xy 406.043624 -200.122637) (xy 406.024826 -200.114848) (xy 406.01044 -200.100457)
			(xy 406.002659 -200.081656) (xy 406.002236 -200.071482) (xy 313.738768 -200.071482) (xy 313.738322 -200.081652)
			(xy 313.730544 -200.100445) (xy 313.716165 -200.11483) (xy 313.697376 -200.122617) (xy 313.687206 -200.123044)
			(xy 312.287666 -200.123044) (xy 312.277504 -200.122594) (xy 312.25873 -200.114805) (xy 312.244366 -200.100426)
			(xy 312.236596 -200.081645) (xy 312.236104 -200.071482) (xy 309.6387 -200.071482) (xy 309.638153 -200.081634)
			(xy 309.630391 -200.100395) (xy 309.616042 -200.11476) (xy 309.597289 -200.122542) (xy 309.587138 -200.123044)
			(xy 308.187598 -200.123044) (xy 308.177424 -200.122637) (xy 308.158626 -200.114848) (xy 308.14424 -200.100457)
			(xy 308.136459 -200.081656) (xy 308.136036 -200.071482) (xy 306.194968 -200.071482) (xy 306.194522 -200.081652)
			(xy 306.186744 -200.100445) (xy 306.172365 -200.11483) (xy 306.153576 -200.122617) (xy 306.143406 -200.123044)
			(xy 304.743866 -200.123044) (xy 304.733704 -200.122594) (xy 304.71493 -200.114805) (xy 304.700566 -200.100426)
			(xy 304.692796 -200.081645) (xy 304.692304 -200.071482) (xy 302.0949 -200.071482) (xy 302.094353 -200.081634)
			(xy 302.086591 -200.100395) (xy 302.072242 -200.11476) (xy 302.053489 -200.122542) (xy 302.043338 -200.123044)
			(xy 300.643798 -200.123044) (xy 300.633624 -200.122637) (xy 300.614826 -200.114848) (xy 300.60044 -200.100457)
			(xy 300.592659 -200.081656) (xy 300.592236 -200.071482) (xy 298.651168 -200.071482) (xy 298.650722 -200.081652)
			(xy 298.642944 -200.100445) (xy 298.628565 -200.11483) (xy 298.609776 -200.122617) (xy 298.599606 -200.123044)
			(xy 297.200066 -200.123044) (xy 297.189904 -200.122594) (xy 297.17113 -200.114805) (xy 297.156766 -200.100426)
			(xy 297.148996 -200.081645) (xy 297.148504 -200.071482) (xy 294.5511 -200.071482) (xy 294.550553 -200.081634)
			(xy 294.542791 -200.100395) (xy 294.528442 -200.11476) (xy 294.509689 -200.122542) (xy 294.499538 -200.123044)
			(xy 293.099998 -200.123044) (xy 293.089824 -200.122637) (xy 293.071026 -200.114848) (xy 293.05664 -200.100457)
			(xy 293.048859 -200.081656) (xy 293.048436 -200.071482) (xy 291.107368 -200.071482) (xy 291.106922 -200.081652)
			(xy 291.099144 -200.100445) (xy 291.084765 -200.11483) (xy 291.065976 -200.122617) (xy 291.055806 -200.123044)
			(xy 289.656266 -200.123044) (xy 289.646104 -200.122594) (xy 289.62733 -200.114805) (xy 289.612966 -200.100426)
			(xy 289.605196 -200.081645) (xy 289.604704 -200.071482) (xy 287.0073 -200.071482) (xy 287.006753 -200.081634)
			(xy 286.998991 -200.100395) (xy 286.984642 -200.11476) (xy 286.965889 -200.122542) (xy 286.955738 -200.123044)
			(xy 285.556198 -200.123044) (xy 285.546024 -200.122637) (xy 285.527226 -200.114848) (xy 285.51284 -200.100457)
			(xy 285.505059 -200.081656) (xy 285.504636 -200.071482) (xy 283.563568 -200.071482) (xy 283.563122 -200.081652)
			(xy 283.555344 -200.100445) (xy 283.540965 -200.11483) (xy 283.522176 -200.122617) (xy 283.512006 -200.123044)
			(xy 282.112466 -200.123044) (xy 282.102304 -200.122594) (xy 282.08353 -200.114805) (xy 282.069166 -200.100426)
			(xy 282.061396 -200.081645) (xy 282.060904 -200.071482) (xy 279.4635 -200.071482) (xy 279.462953 -200.081634)
			(xy 279.455191 -200.100395) (xy 279.440842 -200.11476) (xy 279.422089 -200.122542) (xy 279.411938 -200.123044)
			(xy 278.012398 -200.123044) (xy 278.002224 -200.122637) (xy 277.983426 -200.114848) (xy 277.96904 -200.100457)
			(xy 277.961259 -200.081656) (xy 277.960836 -200.071482) (xy 276.019768 -200.071482) (xy 276.019322 -200.081652)
			(xy 276.011544 -200.100445) (xy 275.997165 -200.11483) (xy 275.978376 -200.122617) (xy 275.968206 -200.123044)
			(xy 274.568666 -200.123044) (xy 274.558504 -200.122594) (xy 274.53973 -200.114805) (xy 274.525366 -200.100426)
			(xy 274.517596 -200.081645) (xy 274.517104 -200.071482) (xy 271.9197 -200.071482) (xy 271.919153 -200.081634)
			(xy 271.911391 -200.100395) (xy 271.897042 -200.11476) (xy 271.878289 -200.122542) (xy 271.868138 -200.123044)
			(xy 270.468598 -200.123044) (xy 270.458424 -200.122637) (xy 270.439626 -200.114848) (xy 270.42524 -200.100457)
			(xy 270.417459 -200.081656) (xy 270.417036 -200.071482) (xy 268.475968 -200.071482) (xy 268.475522 -200.081652)
			(xy 268.467744 -200.100445) (xy 268.453365 -200.11483) (xy 268.434576 -200.122617) (xy 268.424406 -200.123044)
			(xy 267.024866 -200.123044) (xy 267.014704 -200.122594) (xy 266.99593 -200.114805) (xy 266.981566 -200.100426)
			(xy 266.973796 -200.081645) (xy 266.973304 -200.071482) (xy 264.3759 -200.071482) (xy 264.375353 -200.081634)
			(xy 264.367591 -200.100395) (xy 264.353242 -200.11476) (xy 264.334489 -200.122542) (xy 264.324338 -200.123044)
			(xy 262.924798 -200.123044) (xy 262.914624 -200.122637) (xy 262.895826 -200.114848) (xy 262.88144 -200.100457)
			(xy 262.873659 -200.081656) (xy 262.873236 -200.071482) (xy 260.932168 -200.071482) (xy 260.931722 -200.081652)
			(xy 260.923944 -200.100445) (xy 260.909565 -200.11483) (xy 260.890776 -200.122617) (xy 260.880606 -200.123044)
			(xy 259.481066 -200.123044) (xy 259.470904 -200.122594) (xy 259.45213 -200.114805) (xy 259.437766 -200.100426)
			(xy 259.429996 -200.081645) (xy 259.429504 -200.071482) (xy 256.8321 -200.071482) (xy 256.831553 -200.081634)
			(xy 256.823791 -200.100395) (xy 256.809442 -200.11476) (xy 256.790689 -200.122542) (xy 256.780538 -200.123044)
			(xy 255.380998 -200.123044) (xy 255.370824 -200.122637) (xy 255.352026 -200.114848) (xy 255.33764 -200.100457)
			(xy 255.329859 -200.081656) (xy 255.329436 -200.071482) (xy 216.4715 -200.071482) (xy 216.470953 -200.081634)
			(xy 216.463191 -200.100395) (xy 216.448842 -200.11476) (xy 216.430089 -200.122542) (xy 216.419938 -200.123044)
			(xy 215.020398 -200.123044) (xy 215.010224 -200.122637) (xy 214.991426 -200.114848) (xy 214.97704 -200.100457)
			(xy 214.969259 -200.081656) (xy 214.968836 -200.071482) (xy 212.371432 -200.071482) (xy 212.371021 -200.081656)
			(xy 212.363236 -200.100456) (xy 212.348846 -200.114843) (xy 212.330044 -200.122623) (xy 212.31987 -200.123044)
			(xy 210.92033 -200.123044) (xy 210.910158 -200.122611) (xy 210.891361 -200.114833) (xy 210.876974 -200.100449)
			(xy 210.869191 -200.081654) (xy 210.868768 -200.071482) (xy 208.9277 -200.071482) (xy 208.927153 -200.081634)
			(xy 208.919391 -200.100395) (xy 208.905042 -200.11476) (xy 208.886289 -200.122542) (xy 208.876138 -200.123044)
			(xy 207.476598 -200.123044) (xy 207.466424 -200.122637) (xy 207.447626 -200.114848) (xy 207.43324 -200.100457)
			(xy 207.425459 -200.081656) (xy 207.425036 -200.071482) (xy 204.827632 -200.071482) (xy 204.827221 -200.081656)
			(xy 204.819436 -200.100456) (xy 204.805046 -200.114843) (xy 204.786244 -200.122623) (xy 204.77607 -200.123044)
			(xy 203.37653 -200.123044) (xy 203.366358 -200.122611) (xy 203.347561 -200.114833) (xy 203.333174 -200.100449)
			(xy 203.325391 -200.081654) (xy 203.324968 -200.071482) (xy 201.3839 -200.071482) (xy 201.383353 -200.081634)
			(xy 201.375591 -200.100395) (xy 201.361242 -200.11476) (xy 201.342489 -200.122542) (xy 201.332338 -200.123044)
			(xy 199.932798 -200.123044) (xy 199.922624 -200.122637) (xy 199.903826 -200.114848) (xy 199.88944 -200.100457)
			(xy 199.881659 -200.081656) (xy 199.881236 -200.071482) (xy 197.283832 -200.071482) (xy 197.283421 -200.081656)
			(xy 197.275636 -200.100456) (xy 197.261246 -200.114843) (xy 197.242444 -200.122623) (xy 197.23227 -200.123044)
			(xy 195.83273 -200.123044) (xy 195.822558 -200.122611) (xy 195.803761 -200.114833) (xy 195.789374 -200.100449)
			(xy 195.781591 -200.081654) (xy 195.781168 -200.071482) (xy 193.8401 -200.071482) (xy 193.839553 -200.081634)
			(xy 193.831791 -200.100395) (xy 193.817442 -200.11476) (xy 193.798689 -200.122542) (xy 193.788538 -200.123044)
			(xy 192.388998 -200.123044) (xy 192.378824 -200.122637) (xy 192.360026 -200.114848) (xy 192.34564 -200.100457)
			(xy 192.337859 -200.081656) (xy 192.337436 -200.071482) (xy 189.740032 -200.071482) (xy 189.739621 -200.081656)
			(xy 189.731836 -200.100456) (xy 189.717446 -200.114843) (xy 189.698644 -200.122623) (xy 189.68847 -200.123044)
			(xy 188.28893 -200.123044) (xy 188.278758 -200.122611) (xy 188.259961 -200.114833) (xy 188.245574 -200.100449)
			(xy 188.237791 -200.081654) (xy 188.237368 -200.071482) (xy 186.2963 -200.071482) (xy 186.295753 -200.081634)
			(xy 186.287991 -200.100395) (xy 186.273642 -200.11476) (xy 186.254889 -200.122542) (xy 186.244738 -200.123044)
			(xy 184.845198 -200.123044) (xy 184.835024 -200.122637) (xy 184.816226 -200.114848) (xy 184.80184 -200.100457)
			(xy 184.794059 -200.081656) (xy 184.793636 -200.071482) (xy 182.196232 -200.071482) (xy 182.195821 -200.081656)
			(xy 182.188036 -200.100456) (xy 182.173646 -200.114843) (xy 182.154844 -200.122623) (xy 182.14467 -200.123044)
			(xy 180.74513 -200.123044) (xy 180.734958 -200.122611) (xy 180.716161 -200.114833) (xy 180.701774 -200.100449)
			(xy 180.693991 -200.081654) (xy 180.693568 -200.071482) (xy 178.7525 -200.071482) (xy 178.751953 -200.081634)
			(xy 178.744191 -200.100395) (xy 178.729842 -200.11476) (xy 178.711089 -200.122542) (xy 178.700938 -200.123044)
			(xy 177.301398 -200.123044) (xy 177.291224 -200.122637) (xy 177.272426 -200.114848) (xy 177.25804 -200.100457)
			(xy 177.250259 -200.081656) (xy 177.249836 -200.071482) (xy 174.652432 -200.071482) (xy 174.652021 -200.081656)
			(xy 174.644236 -200.100456) (xy 174.629846 -200.114843) (xy 174.611044 -200.122623) (xy 174.60087 -200.123044)
			(xy 173.20133 -200.123044) (xy 173.191158 -200.122611) (xy 173.172361 -200.114833) (xy 173.157974 -200.100449)
			(xy 173.150191 -200.081654) (xy 173.149768 -200.071482) (xy 171.2087 -200.071482) (xy 171.208153 -200.081634)
			(xy 171.200391 -200.100395) (xy 171.186042 -200.11476) (xy 171.167289 -200.122542) (xy 171.157138 -200.123044)
			(xy 169.757598 -200.123044) (xy 169.747424 -200.122637) (xy 169.728626 -200.114848) (xy 169.71424 -200.100457)
			(xy 169.706459 -200.081656) (xy 169.706036 -200.071482) (xy 167.108632 -200.071482) (xy 167.108221 -200.081656)
			(xy 167.100436 -200.100456) (xy 167.086046 -200.114843) (xy 167.067244 -200.122623) (xy 167.05707 -200.123044)
			(xy 165.65753 -200.123044) (xy 165.647358 -200.122611) (xy 165.628561 -200.114833) (xy 165.614174 -200.100449)
			(xy 165.606391 -200.081654) (xy 165.605968 -200.071482) (xy 163.6649 -200.071482) (xy 163.664353 -200.081634)
			(xy 163.656591 -200.100395) (xy 163.642242 -200.11476) (xy 163.623489 -200.122542) (xy 163.613338 -200.123044)
			(xy 162.213798 -200.123044) (xy 162.203624 -200.122637) (xy 162.184826 -200.114848) (xy 162.17044 -200.100457)
			(xy 162.162659 -200.081656) (xy 162.162236 -200.071482) (xy 159.564832 -200.071482) (xy 159.564421 -200.081656)
			(xy 159.556636 -200.100456) (xy 159.542246 -200.114843) (xy 159.523444 -200.122623) (xy 159.51327 -200.123044)
			(xy 158.11373 -200.123044) (xy 158.103558 -200.122611) (xy 158.084761 -200.114833) (xy 158.070374 -200.100449)
			(xy 158.062591 -200.081654) (xy 158.062168 -200.071482) (xy 65.7987 -200.071482) (xy 65.798153 -200.081634)
			(xy 65.790391 -200.100395) (xy 65.776042 -200.11476) (xy 65.757289 -200.122542) (xy 65.747138 -200.123044)
			(xy 64.347598 -200.123044) (xy 64.337424 -200.122637) (xy 64.318626 -200.114848) (xy 64.30424 -200.100457)
			(xy 64.296459 -200.081656) (xy 64.296036 -200.071482) (xy 61.698632 -200.071482) (xy 61.698221 -200.081656)
			(xy 61.690436 -200.100456) (xy 61.676046 -200.114843) (xy 61.657244 -200.122623) (xy 61.64707 -200.123044)
			(xy 60.24753 -200.123044) (xy 60.237358 -200.122611) (xy 60.218561 -200.114833) (xy 60.204174 -200.100449)
			(xy 60.196391 -200.081654) (xy 60.195968 -200.071482) (xy 58.2549 -200.071482) (xy 58.254353 -200.081634)
			(xy 58.246591 -200.100395) (xy 58.232242 -200.11476) (xy 58.213489 -200.122542) (xy 58.203338 -200.123044)
			(xy 56.803798 -200.123044) (xy 56.793624 -200.122637) (xy 56.774826 -200.114848) (xy 56.76044 -200.100457)
			(xy 56.752659 -200.081656) (xy 56.752236 -200.071482) (xy 54.154832 -200.071482) (xy 54.154421 -200.081656)
			(xy 54.146636 -200.100456) (xy 54.132246 -200.114843) (xy 54.113444 -200.122623) (xy 54.10327 -200.123044)
			(xy 52.70373 -200.123044) (xy 52.693558 -200.122611) (xy 52.674761 -200.114833) (xy 52.660374 -200.100449)
			(xy 52.652591 -200.081654) (xy 52.652168 -200.071482) (xy 50.7111 -200.071482) (xy 50.710553 -200.081634)
			(xy 50.702791 -200.100395) (xy 50.688442 -200.11476) (xy 50.669689 -200.122542) (xy 50.659538 -200.123044)
			(xy 49.259998 -200.123044) (xy 49.249824 -200.122637) (xy 49.231026 -200.114848) (xy 49.21664 -200.100457)
			(xy 49.208859 -200.081656) (xy 49.208436 -200.071482) (xy 46.611032 -200.071482) (xy 46.610621 -200.081656)
			(xy 46.602836 -200.100456) (xy 46.588446 -200.114843) (xy 46.569644 -200.122623) (xy 46.55947 -200.123044)
			(xy 45.15993 -200.123044) (xy 45.149758 -200.122611) (xy 45.130961 -200.114833) (xy 45.116574 -200.100449)
			(xy 45.108791 -200.081654) (xy 45.108368 -200.071482) (xy 43.1673 -200.071482) (xy 43.166753 -200.081634)
			(xy 43.158991 -200.100395) (xy 43.144642 -200.11476) (xy 43.125889 -200.122542) (xy 43.115738 -200.123044)
			(xy 41.716198 -200.123044) (xy 41.706024 -200.122637) (xy 41.687226 -200.114848) (xy 41.67284 -200.100457)
			(xy 41.665059 -200.081656) (xy 41.664636 -200.071482) (xy 39.067232 -200.071482) (xy 39.066821 -200.081656)
			(xy 39.059036 -200.100456) (xy 39.044646 -200.114843) (xy 39.025844 -200.122623) (xy 39.01567 -200.123044)
			(xy 37.61613 -200.123044) (xy 37.605958 -200.122611) (xy 37.587161 -200.114833) (xy 37.572774 -200.100449)
			(xy 37.564991 -200.081654) (xy 37.564568 -200.071482) (xy 35.6235 -200.071482) (xy 35.622953 -200.081634)
			(xy 35.615191 -200.100395) (xy 35.600842 -200.11476) (xy 35.582089 -200.122542) (xy 35.571938 -200.123044)
			(xy 34.172398 -200.123044) (xy 34.162224 -200.122637) (xy 34.143426 -200.114848) (xy 34.12904 -200.100457)
			(xy 34.121259 -200.081656) (xy 34.120836 -200.071482) (xy 31.523432 -200.071482) (xy 31.523021 -200.081656)
			(xy 31.515236 -200.100456) (xy 31.500846 -200.114843) (xy 31.482044 -200.122623) (xy 31.47187 -200.123044)
			(xy 30.07233 -200.123044) (xy 30.062158 -200.122611) (xy 30.043361 -200.114833) (xy 30.028974 -200.100449)
			(xy 30.021191 -200.081654) (xy 30.020768 -200.071482) (xy 28.0797 -200.071482) (xy 28.079153 -200.081634)
			(xy 28.071391 -200.100395) (xy 28.057042 -200.11476) (xy 28.038289 -200.122542) (xy 28.028138 -200.123044)
			(xy 26.628598 -200.123044) (xy 26.618424 -200.122637) (xy 26.599626 -200.114848) (xy 26.58524 -200.100457)
			(xy 26.577459 -200.081656) (xy 26.577036 -200.071482) (xy 23.979632 -200.071482) (xy 23.979221 -200.081656)
			(xy 23.971436 -200.100456) (xy 23.957046 -200.114843) (xy 23.938244 -200.122623) (xy 23.92807 -200.123044)
			(xy 22.52853 -200.123044) (xy 22.518358 -200.122611) (xy 22.499561 -200.114833) (xy 22.485174 -200.100449)
			(xy 22.477391 -200.081654) (xy 22.476968 -200.071482) (xy 20.5359 -200.071482) (xy 20.535353 -200.081634)
			(xy 20.527591 -200.100395) (xy 20.513242 -200.11476) (xy 20.494489 -200.122542) (xy 20.484338 -200.123044)
			(xy 19.084798 -200.123044) (xy 19.074624 -200.122637) (xy 19.055826 -200.114848) (xy 19.04144 -200.100457)
			(xy 19.033659 -200.081656) (xy 19.033236 -200.071482) (xy 16.435832 -200.071482) (xy 16.435421 -200.081656)
			(xy 16.427636 -200.100456) (xy 16.413246 -200.114843) (xy 16.394444 -200.122623) (xy 16.38427 -200.123044)
			(xy 14.98473 -200.123044) (xy 14.974558 -200.122611) (xy 14.955761 -200.114833) (xy 14.941374 -200.100449)
			(xy 14.933591 -200.081654) (xy 14.933168 -200.071482) (xy 12.9921 -200.071482) (xy 12.991553 -200.081634)
			(xy 12.983791 -200.100395) (xy 12.969442 -200.11476) (xy 12.950689 -200.122542) (xy 12.940538 -200.123044)
			(xy 11.540998 -200.123044) (xy 11.530824 -200.122637) (xy 11.512026 -200.114848) (xy 11.49764 -200.100457)
			(xy 11.489859 -200.081656) (xy 11.489436 -200.071482) (xy 8.892032 -200.071482) (xy 8.891621 -200.081656)
			(xy 8.883836 -200.100456) (xy 8.869446 -200.114843) (xy 8.850644 -200.122623) (xy 8.84047 -200.123044)
			(xy 7.44093 -200.123044) (xy 7.430758 -200.122611) (xy 7.411961 -200.114833) (xy 7.397574 -200.100449)
			(xy 7.389791 -200.081654) (xy 7.389368 -200.071482) (xy 2.509012 -200.071482) (xy 2.509012 -200.921366)
			(xy 7.389368 -200.921366) (xy 7.389368 -200.512426) (xy 7.389786 -200.502252) (xy 7.397568 -200.483453)
			(xy 7.411956 -200.469066) (xy 7.430756 -200.461285) (xy 7.44093 -200.460864) (xy 8.84047 -200.460864)
			(xy 8.850643 -200.461289) (xy 8.869442 -200.469069) (xy 8.883829 -200.483455) (xy 8.89161 -200.502253)
			(xy 8.892032 -200.512426) (xy 8.892032 -200.921366) (xy 14.933168 -200.921366) (xy 14.933168 -200.512426)
			(xy 14.933586 -200.502252) (xy 14.941368 -200.483453) (xy 14.955756 -200.469066) (xy 14.974556 -200.461285)
			(xy 14.98473 -200.460864) (xy 16.38427 -200.460864) (xy 16.394443 -200.461289) (xy 16.413242 -200.469069)
			(xy 16.427629 -200.483455) (xy 16.43541 -200.502253) (xy 16.435832 -200.512426) (xy 16.435832 -200.921366)
			(xy 22.476968 -200.921366) (xy 22.476968 -200.512426) (xy 22.477386 -200.502252) (xy 22.485168 -200.483453)
			(xy 22.499556 -200.469066) (xy 22.518356 -200.461285) (xy 22.52853 -200.460864) (xy 23.92807 -200.460864)
			(xy 23.938243 -200.461289) (xy 23.957042 -200.469069) (xy 23.971429 -200.483455) (xy 23.97921 -200.502253)
			(xy 23.979632 -200.512426) (xy 23.979632 -200.921366) (xy 30.020768 -200.921366) (xy 30.020768 -200.512426)
			(xy 30.021186 -200.502252) (xy 30.028968 -200.483453) (xy 30.043356 -200.469066) (xy 30.062156 -200.461285)
			(xy 30.07233 -200.460864) (xy 31.47187 -200.460864) (xy 31.482043 -200.461289) (xy 31.500842 -200.469069)
			(xy 31.515229 -200.483455) (xy 31.52301 -200.502253) (xy 31.523432 -200.512426) (xy 31.523432 -200.921366)
			(xy 37.564568 -200.921366) (xy 37.564568 -200.512426) (xy 37.564986 -200.502252) (xy 37.572768 -200.483453)
			(xy 37.587156 -200.469066) (xy 37.605956 -200.461285) (xy 37.61613 -200.460864) (xy 39.01567 -200.460864)
			(xy 39.025843 -200.461289) (xy 39.044642 -200.469069) (xy 39.059029 -200.483455) (xy 39.06681 -200.502253)
			(xy 39.067232 -200.512426) (xy 39.067232 -200.921366) (xy 45.108368 -200.921366) (xy 45.108368 -200.512426)
			(xy 45.108786 -200.502252) (xy 45.116568 -200.483453) (xy 45.130956 -200.469066) (xy 45.149756 -200.461285)
			(xy 45.15993 -200.460864) (xy 46.55947 -200.460864) (xy 46.569643 -200.461289) (xy 46.588442 -200.469069)
			(xy 46.602829 -200.483455) (xy 46.61061 -200.502253) (xy 46.611032 -200.512426) (xy 46.611032 -200.921366)
			(xy 52.652168 -200.921366) (xy 52.652168 -200.512426) (xy 52.652586 -200.502252) (xy 52.660368 -200.483453)
			(xy 52.674756 -200.469066) (xy 52.693556 -200.461285) (xy 52.70373 -200.460864) (xy 54.10327 -200.460864)
			(xy 54.113443 -200.461289) (xy 54.132242 -200.469069) (xy 54.146629 -200.483455) (xy 54.15441 -200.502253)
			(xy 54.154832 -200.512426) (xy 54.154832 -200.921366) (xy 60.195968 -200.921366) (xy 60.195968 -200.512426)
			(xy 60.196386 -200.502252) (xy 60.204168 -200.483453) (xy 60.218556 -200.469066) (xy 60.237356 -200.461285)
			(xy 60.24753 -200.460864) (xy 61.64707 -200.460864) (xy 61.657243 -200.461289) (xy 61.676042 -200.469069)
			(xy 61.690429 -200.483455) (xy 61.69821 -200.502253) (xy 61.698632 -200.512426) (xy 61.698632 -200.921366)
			(xy 158.062168 -200.921366) (xy 158.062168 -200.512426) (xy 158.062586 -200.502252) (xy 158.070368 -200.483453)
			(xy 158.084756 -200.469066) (xy 158.103556 -200.461285) (xy 158.11373 -200.460864) (xy 159.51327 -200.460864)
			(xy 159.523443 -200.461289) (xy 159.542242 -200.469069) (xy 159.556629 -200.483455) (xy 159.56441 -200.502253)
			(xy 159.564832 -200.512426) (xy 159.564832 -200.921366) (xy 165.605968 -200.921366) (xy 165.605968 -200.512426)
			(xy 165.606386 -200.502252) (xy 165.614168 -200.483453) (xy 165.628556 -200.469066) (xy 165.647356 -200.461285)
			(xy 165.65753 -200.460864) (xy 167.05707 -200.460864) (xy 167.067243 -200.461289) (xy 167.086042 -200.469069)
			(xy 167.100429 -200.483455) (xy 167.10821 -200.502253) (xy 167.108632 -200.512426) (xy 167.108632 -200.921366)
			(xy 173.149768 -200.921366) (xy 173.149768 -200.512426) (xy 173.150186 -200.502252) (xy 173.157968 -200.483453)
			(xy 173.172356 -200.469066) (xy 173.191156 -200.461285) (xy 173.20133 -200.460864) (xy 174.60087 -200.460864)
			(xy 174.611043 -200.461289) (xy 174.629842 -200.469069) (xy 174.644229 -200.483455) (xy 174.65201 -200.502253)
			(xy 174.652432 -200.512426) (xy 174.652432 -200.921366) (xy 180.693568 -200.921366) (xy 180.693568 -200.512426)
			(xy 180.693986 -200.502252) (xy 180.701768 -200.483453) (xy 180.716156 -200.469066) (xy 180.734956 -200.461285)
			(xy 180.74513 -200.460864) (xy 182.14467 -200.460864) (xy 182.154843 -200.461289) (xy 182.173642 -200.469069)
			(xy 182.188029 -200.483455) (xy 182.19581 -200.502253) (xy 182.196232 -200.512426) (xy 182.196232 -200.921366)
			(xy 188.237368 -200.921366) (xy 188.237368 -200.512426) (xy 188.237786 -200.502252) (xy 188.245568 -200.483453)
			(xy 188.259956 -200.469066) (xy 188.278756 -200.461285) (xy 188.28893 -200.460864) (xy 189.68847 -200.460864)
			(xy 189.698643 -200.461289) (xy 189.717442 -200.469069) (xy 189.731829 -200.483455) (xy 189.73961 -200.502253)
			(xy 189.740032 -200.512426) (xy 189.740032 -200.921366) (xy 195.781168 -200.921366) (xy 195.781168 -200.512426)
			(xy 195.781586 -200.502252) (xy 195.789368 -200.483453) (xy 195.803756 -200.469066) (xy 195.822556 -200.461285)
			(xy 195.83273 -200.460864) (xy 197.23227 -200.460864) (xy 197.242443 -200.461289) (xy 197.261242 -200.469069)
			(xy 197.275629 -200.483455) (xy 197.28341 -200.502253) (xy 197.283832 -200.512426) (xy 197.283832 -200.921366)
			(xy 203.324968 -200.921366) (xy 203.324968 -200.512426) (xy 203.325386 -200.502252) (xy 203.333168 -200.483453)
			(xy 203.347556 -200.469066) (xy 203.366356 -200.461285) (xy 203.37653 -200.460864) (xy 204.77607 -200.460864)
			(xy 204.786243 -200.461289) (xy 204.805042 -200.469069) (xy 204.819429 -200.483455) (xy 204.82721 -200.502253)
			(xy 204.827632 -200.512426) (xy 204.827632 -200.921366) (xy 210.868768 -200.921366) (xy 210.868768 -200.512426)
			(xy 210.869186 -200.502252) (xy 210.876968 -200.483453) (xy 210.891356 -200.469066) (xy 210.910156 -200.461285)
			(xy 210.92033 -200.460864) (xy 212.31987 -200.460864) (xy 212.330043 -200.461289) (xy 212.348842 -200.469069)
			(xy 212.363229 -200.483455) (xy 212.37101 -200.502253) (xy 212.371432 -200.512426) (xy 212.371432 -200.921366)
			(xy 255.329436 -200.921366) (xy 255.329436 -200.512426) (xy 255.329885 -200.502256) (xy 255.337661 -200.483463)
			(xy 255.352039 -200.469077) (xy 255.370829 -200.461291) (xy 255.380998 -200.460864) (xy 256.780538 -200.460864)
			(xy 256.790701 -200.461303) (xy 256.809476 -200.469095) (xy 256.823841 -200.483477) (xy 256.83161 -200.502262)
			(xy 256.8321 -200.512426) (xy 256.8321 -200.921366) (xy 262.873236 -200.921366) (xy 262.873236 -200.512426)
			(xy 262.873685 -200.502256) (xy 262.881461 -200.483463) (xy 262.895839 -200.469077) (xy 262.914629 -200.461291)
			(xy 262.924798 -200.460864) (xy 264.324338 -200.460864) (xy 264.334501 -200.461303) (xy 264.353276 -200.469095)
			(xy 264.367641 -200.483477) (xy 264.37541 -200.502262) (xy 264.3759 -200.512426) (xy 264.3759 -200.921366)
			(xy 270.417036 -200.921366) (xy 270.417036 -200.512426) (xy 270.417485 -200.502256) (xy 270.425261 -200.483463)
			(xy 270.439639 -200.469077) (xy 270.458429 -200.461291) (xy 270.468598 -200.460864) (xy 271.868138 -200.460864)
			(xy 271.878301 -200.461303) (xy 271.897076 -200.469095) (xy 271.911441 -200.483477) (xy 271.91921 -200.502262)
			(xy 271.9197 -200.512426) (xy 271.9197 -200.921366) (xy 277.960836 -200.921366) (xy 277.960836 -200.512426)
			(xy 277.961285 -200.502256) (xy 277.969061 -200.483463) (xy 277.983439 -200.469077) (xy 278.002229 -200.461291)
			(xy 278.012398 -200.460864) (xy 279.411938 -200.460864) (xy 279.422101 -200.461303) (xy 279.440876 -200.469095)
			(xy 279.455241 -200.483477) (xy 279.46301 -200.502262) (xy 279.4635 -200.512426) (xy 279.4635 -200.921366)
			(xy 285.504636 -200.921366) (xy 285.504636 -200.512426) (xy 285.505085 -200.502256) (xy 285.512861 -200.483463)
			(xy 285.527239 -200.469077) (xy 285.546029 -200.461291) (xy 285.556198 -200.460864) (xy 286.955738 -200.460864)
			(xy 286.965901 -200.461303) (xy 286.984676 -200.469095) (xy 286.999041 -200.483477) (xy 287.00681 -200.502262)
			(xy 287.0073 -200.512426) (xy 287.0073 -200.921366) (xy 293.048436 -200.921366) (xy 293.048436 -200.512426)
			(xy 293.048885 -200.502256) (xy 293.056661 -200.483463) (xy 293.071039 -200.469077) (xy 293.089829 -200.461291)
			(xy 293.099998 -200.460864) (xy 294.499538 -200.460864) (xy 294.509701 -200.461303) (xy 294.528476 -200.469095)
			(xy 294.542841 -200.483477) (xy 294.55061 -200.502262) (xy 294.5511 -200.512426) (xy 294.5511 -200.921366)
			(xy 300.592236 -200.921366) (xy 300.592236 -200.512426) (xy 300.592685 -200.502256) (xy 300.600461 -200.483463)
			(xy 300.614839 -200.469077) (xy 300.633629 -200.461291) (xy 300.643798 -200.460864) (xy 302.043338 -200.460864)
			(xy 302.053501 -200.461303) (xy 302.072276 -200.469095) (xy 302.086641 -200.483477) (xy 302.09441 -200.502262)
			(xy 302.0949 -200.512426) (xy 302.0949 -200.921366) (xy 308.136036 -200.921366) (xy 308.136036 -200.512426)
			(xy 308.136485 -200.502256) (xy 308.144261 -200.483463) (xy 308.158639 -200.469077) (xy 308.177429 -200.461291)
			(xy 308.187598 -200.460864) (xy 309.587138 -200.460864) (xy 309.597301 -200.461303) (xy 309.616076 -200.469095)
			(xy 309.630441 -200.483477) (xy 309.63821 -200.502262) (xy 309.6387 -200.512426) (xy 309.6387 -200.921366)
			(xy 406.002236 -200.921366) (xy 406.002236 -200.512426) (xy 406.002685 -200.502256) (xy 406.010461 -200.483463)
			(xy 406.024839 -200.469077) (xy 406.043629 -200.461291) (xy 406.053798 -200.460864) (xy 407.453338 -200.460864)
			(xy 407.463501 -200.461303) (xy 407.482276 -200.469095) (xy 407.496641 -200.483477) (xy 407.50441 -200.502262)
			(xy 407.5049 -200.512426) (xy 407.5049 -200.921366) (xy 413.546036 -200.921366) (xy 413.546036 -200.512426)
			(xy 413.546485 -200.502256) (xy 413.554261 -200.483463) (xy 413.568639 -200.469077) (xy 413.587429 -200.461291)
			(xy 413.597598 -200.460864) (xy 414.997138 -200.460864) (xy 415.007301 -200.461303) (xy 415.026076 -200.469095)
			(xy 415.040441 -200.483477) (xy 415.04821 -200.502262) (xy 415.0487 -200.512426) (xy 415.0487 -200.921366)
			(xy 421.089836 -200.921366) (xy 421.089836 -200.512426) (xy 421.090285 -200.502256) (xy 421.098061 -200.483463)
			(xy 421.112439 -200.469077) (xy 421.131229 -200.461291) (xy 421.141398 -200.460864) (xy 422.540938 -200.460864)
			(xy 422.551101 -200.461303) (xy 422.569876 -200.469095) (xy 422.584241 -200.483477) (xy 422.59201 -200.502262)
			(xy 422.5925 -200.512426) (xy 422.5925 -200.921366) (xy 428.633636 -200.921366) (xy 428.633636 -200.512426)
			(xy 428.634085 -200.502256) (xy 428.641861 -200.483463) (xy 428.656239 -200.469077) (xy 428.675029 -200.461291)
			(xy 428.685198 -200.460864) (xy 430.084738 -200.460864) (xy 430.094901 -200.461303) (xy 430.113676 -200.469095)
			(xy 430.128041 -200.483477) (xy 430.13581 -200.502262) (xy 430.1363 -200.512426) (xy 430.1363 -200.921366)
			(xy 436.177436 -200.921366) (xy 436.177436 -200.512426) (xy 436.177885 -200.502256) (xy 436.185661 -200.483463)
			(xy 436.200039 -200.469077) (xy 436.218829 -200.461291) (xy 436.228998 -200.460864) (xy 437.628538 -200.460864)
			(xy 437.638701 -200.461303) (xy 437.657476 -200.469095) (xy 437.671841 -200.483477) (xy 437.67961 -200.502262)
			(xy 437.6801 -200.512426) (xy 437.6801 -200.921366) (xy 443.721236 -200.921366) (xy 443.721236 -200.512426)
			(xy 443.721685 -200.502256) (xy 443.729461 -200.483463) (xy 443.743839 -200.469077) (xy 443.762629 -200.461291)
			(xy 443.772798 -200.460864) (xy 445.172338 -200.460864) (xy 445.182501 -200.461303) (xy 445.201276 -200.469095)
			(xy 445.215641 -200.483477) (xy 445.22341 -200.502262) (xy 445.2239 -200.512426) (xy 445.2239 -200.921366)
			(xy 451.265036 -200.921366) (xy 451.265036 -200.512426) (xy 451.265485 -200.502256) (xy 451.273261 -200.483463)
			(xy 451.287639 -200.469077) (xy 451.306429 -200.461291) (xy 451.316598 -200.460864) (xy 452.716138 -200.460864)
			(xy 452.726301 -200.461303) (xy 452.745076 -200.469095) (xy 452.759441 -200.483477) (xy 452.76721 -200.502262)
			(xy 452.7677 -200.512426) (xy 452.7677 -200.921366) (xy 458.808836 -200.921366) (xy 458.808836 -200.512426)
			(xy 458.809285 -200.502256) (xy 458.817061 -200.483463) (xy 458.831439 -200.469077) (xy 458.850229 -200.461291)
			(xy 458.860398 -200.460864) (xy 460.259938 -200.460864) (xy 460.270101 -200.461303) (xy 460.288876 -200.469095)
			(xy 460.303241 -200.483477) (xy 460.31101 -200.502262) (xy 460.3115 -200.512426) (xy 460.3115 -200.921366)
			(xy 460.31094 -200.931517) (xy 460.303183 -200.950278) (xy 460.288838 -200.964643) (xy 460.270088 -200.972425)
			(xy 460.259938 -200.972928) (xy 458.860398 -200.972928) (xy 458.850222 -200.972537) (xy 458.831421 -200.964745)
			(xy 458.817035 -200.950349) (xy 458.809256 -200.931542) (xy 458.808836 -200.921366) (xy 452.7677 -200.921366)
			(xy 452.76714 -200.931517) (xy 452.759383 -200.950278) (xy 452.745038 -200.964643) (xy 452.726288 -200.972425)
			(xy 452.716138 -200.972928) (xy 451.316598 -200.972928) (xy 451.306422 -200.972537) (xy 451.287621 -200.964745)
			(xy 451.273235 -200.950349) (xy 451.265456 -200.931542) (xy 451.265036 -200.921366) (xy 445.2239 -200.921366)
			(xy 445.22334 -200.931517) (xy 445.215583 -200.950278) (xy 445.201238 -200.964643) (xy 445.182488 -200.972425)
			(xy 445.172338 -200.972928) (xy 443.772798 -200.972928) (xy 443.762622 -200.972537) (xy 443.743821 -200.964745)
			(xy 443.729435 -200.950349) (xy 443.721656 -200.931542) (xy 443.721236 -200.921366) (xy 437.6801 -200.921366)
			(xy 437.67954 -200.931517) (xy 437.671783 -200.950278) (xy 437.657438 -200.964643) (xy 437.638688 -200.972425)
			(xy 437.628538 -200.972928) (xy 436.228998 -200.972928) (xy 436.218822 -200.972537) (xy 436.200021 -200.964745)
			(xy 436.185635 -200.950349) (xy 436.177856 -200.931542) (xy 436.177436 -200.921366) (xy 430.1363 -200.921366)
			(xy 430.13574 -200.931517) (xy 430.127983 -200.950278) (xy 430.113638 -200.964643) (xy 430.094888 -200.972425)
			(xy 430.084738 -200.972928) (xy 428.685198 -200.972928) (xy 428.675022 -200.972537) (xy 428.656221 -200.964745)
			(xy 428.641835 -200.950349) (xy 428.634056 -200.931542) (xy 428.633636 -200.921366) (xy 422.5925 -200.921366)
			(xy 422.59194 -200.931517) (xy 422.584183 -200.950278) (xy 422.569838 -200.964643) (xy 422.551088 -200.972425)
			(xy 422.540938 -200.972928) (xy 421.141398 -200.972928) (xy 421.131222 -200.972537) (xy 421.112421 -200.964745)
			(xy 421.098035 -200.950349) (xy 421.090256 -200.931542) (xy 421.089836 -200.921366) (xy 415.0487 -200.921366)
			(xy 415.04814 -200.931517) (xy 415.040383 -200.950278) (xy 415.026038 -200.964643) (xy 415.007288 -200.972425)
			(xy 414.997138 -200.972928) (xy 413.597598 -200.972928) (xy 413.587422 -200.972537) (xy 413.568621 -200.964745)
			(xy 413.554235 -200.950349) (xy 413.546456 -200.931542) (xy 413.546036 -200.921366) (xy 407.5049 -200.921366)
			(xy 407.50434 -200.931517) (xy 407.496583 -200.950278) (xy 407.482238 -200.964643) (xy 407.463488 -200.972425)
			(xy 407.453338 -200.972928) (xy 406.053798 -200.972928) (xy 406.043622 -200.972537) (xy 406.024821 -200.964745)
			(xy 406.010435 -200.950349) (xy 406.002656 -200.931542) (xy 406.002236 -200.921366) (xy 309.6387 -200.921366)
			(xy 309.63814 -200.931517) (xy 309.630383 -200.950278) (xy 309.616038 -200.964643) (xy 309.597288 -200.972425)
			(xy 309.587138 -200.972928) (xy 308.187598 -200.972928) (xy 308.177422 -200.972537) (xy 308.158621 -200.964745)
			(xy 308.144235 -200.950349) (xy 308.136456 -200.931542) (xy 308.136036 -200.921366) (xy 302.0949 -200.921366)
			(xy 302.09434 -200.931517) (xy 302.086583 -200.950278) (xy 302.072238 -200.964643) (xy 302.053488 -200.972425)
			(xy 302.043338 -200.972928) (xy 300.643798 -200.972928) (xy 300.633622 -200.972537) (xy 300.614821 -200.964745)
			(xy 300.600435 -200.950349) (xy 300.592656 -200.931542) (xy 300.592236 -200.921366) (xy 294.5511 -200.921366)
			(xy 294.55054 -200.931517) (xy 294.542783 -200.950278) (xy 294.528438 -200.964643) (xy 294.509688 -200.972425)
			(xy 294.499538 -200.972928) (xy 293.099998 -200.972928) (xy 293.089822 -200.972537) (xy 293.071021 -200.964745)
			(xy 293.056635 -200.950349) (xy 293.048856 -200.931542) (xy 293.048436 -200.921366) (xy 287.0073 -200.921366)
			(xy 287.00674 -200.931517) (xy 286.998983 -200.950278) (xy 286.984638 -200.964643) (xy 286.965888 -200.972425)
			(xy 286.955738 -200.972928) (xy 285.556198 -200.972928) (xy 285.546022 -200.972537) (xy 285.527221 -200.964745)
			(xy 285.512835 -200.950349) (xy 285.505056 -200.931542) (xy 285.504636 -200.921366) (xy 279.4635 -200.921366)
			(xy 279.46294 -200.931517) (xy 279.455183 -200.950278) (xy 279.440838 -200.964643) (xy 279.422088 -200.972425)
			(xy 279.411938 -200.972928) (xy 278.012398 -200.972928) (xy 278.002222 -200.972537) (xy 277.983421 -200.964745)
			(xy 277.969035 -200.950349) (xy 277.961256 -200.931542) (xy 277.960836 -200.921366) (xy 271.9197 -200.921366)
			(xy 271.91914 -200.931517) (xy 271.911383 -200.950278) (xy 271.897038 -200.964643) (xy 271.878288 -200.972425)
			(xy 271.868138 -200.972928) (xy 270.468598 -200.972928) (xy 270.458422 -200.972537) (xy 270.439621 -200.964745)
			(xy 270.425235 -200.950349) (xy 270.417456 -200.931542) (xy 270.417036 -200.921366) (xy 264.3759 -200.921366)
			(xy 264.37534 -200.931517) (xy 264.367583 -200.950278) (xy 264.353238 -200.964643) (xy 264.334488 -200.972425)
			(xy 264.324338 -200.972928) (xy 262.924798 -200.972928) (xy 262.914622 -200.972537) (xy 262.895821 -200.964745)
			(xy 262.881435 -200.950349) (xy 262.873656 -200.931542) (xy 262.873236 -200.921366) (xy 256.8321 -200.921366)
			(xy 256.83154 -200.931517) (xy 256.823783 -200.950278) (xy 256.809438 -200.964643) (xy 256.790688 -200.972425)
			(xy 256.780538 -200.972928) (xy 255.380998 -200.972928) (xy 255.370822 -200.972537) (xy 255.352021 -200.964745)
			(xy 255.337635 -200.950349) (xy 255.329856 -200.931542) (xy 255.329436 -200.921366) (xy 212.371432 -200.921366)
			(xy 212.371007 -200.931539) (xy 212.363228 -200.950339) (xy 212.348842 -200.964726) (xy 212.330043 -200.972507)
			(xy 212.31987 -200.972928) (xy 210.92033 -200.972928) (xy 210.910156 -200.972511) (xy 210.891356 -200.964729)
			(xy 210.876969 -200.950341) (xy 210.869189 -200.93154) (xy 210.868768 -200.921366) (xy 204.827632 -200.921366)
			(xy 204.827207 -200.931539) (xy 204.819428 -200.950339) (xy 204.805042 -200.964726) (xy 204.786243 -200.972507)
			(xy 204.77607 -200.972928) (xy 203.37653 -200.972928) (xy 203.366356 -200.972511) (xy 203.347556 -200.964729)
			(xy 203.333169 -200.950341) (xy 203.325389 -200.93154) (xy 203.324968 -200.921366) (xy 197.283832 -200.921366)
			(xy 197.283407 -200.931539) (xy 197.275628 -200.950339) (xy 197.261242 -200.964726) (xy 197.242443 -200.972507)
			(xy 197.23227 -200.972928) (xy 195.83273 -200.972928) (xy 195.822556 -200.972511) (xy 195.803756 -200.964729)
			(xy 195.789369 -200.950341) (xy 195.781589 -200.93154) (xy 195.781168 -200.921366) (xy 189.740032 -200.921366)
			(xy 189.739607 -200.931539) (xy 189.731828 -200.950339) (xy 189.717442 -200.964726) (xy 189.698643 -200.972507)
			(xy 189.68847 -200.972928) (xy 188.28893 -200.972928) (xy 188.278756 -200.972511) (xy 188.259956 -200.964729)
			(xy 188.245569 -200.950341) (xy 188.237789 -200.93154) (xy 188.237368 -200.921366) (xy 182.196232 -200.921366)
			(xy 182.195807 -200.931539) (xy 182.188028 -200.950339) (xy 182.173642 -200.964726) (xy 182.154843 -200.972507)
			(xy 182.14467 -200.972928) (xy 180.74513 -200.972928) (xy 180.734956 -200.972511) (xy 180.716156 -200.964729)
			(xy 180.701769 -200.950341) (xy 180.693989 -200.93154) (xy 180.693568 -200.921366) (xy 174.652432 -200.921366)
			(xy 174.652007 -200.931539) (xy 174.644228 -200.950339) (xy 174.629842 -200.964726) (xy 174.611043 -200.972507)
			(xy 174.60087 -200.972928) (xy 173.20133 -200.972928) (xy 173.191156 -200.972511) (xy 173.172356 -200.964729)
			(xy 173.157969 -200.950341) (xy 173.150189 -200.93154) (xy 173.149768 -200.921366) (xy 167.108632 -200.921366)
			(xy 167.108207 -200.931539) (xy 167.100428 -200.950339) (xy 167.086042 -200.964726) (xy 167.067243 -200.972507)
			(xy 167.05707 -200.972928) (xy 165.65753 -200.972928) (xy 165.647356 -200.972511) (xy 165.628556 -200.964729)
			(xy 165.614169 -200.950341) (xy 165.606389 -200.93154) (xy 165.605968 -200.921366) (xy 159.564832 -200.921366)
			(xy 159.564407 -200.931539) (xy 159.556628 -200.950339) (xy 159.542242 -200.964726) (xy 159.523443 -200.972507)
			(xy 159.51327 -200.972928) (xy 158.11373 -200.972928) (xy 158.103556 -200.972511) (xy 158.084756 -200.964729)
			(xy 158.070369 -200.950341) (xy 158.062589 -200.93154) (xy 158.062168 -200.921366) (xy 61.698632 -200.921366)
			(xy 61.698207 -200.931539) (xy 61.690428 -200.950339) (xy 61.676042 -200.964726) (xy 61.657243 -200.972507)
			(xy 61.64707 -200.972928) (xy 60.24753 -200.972928) (xy 60.237356 -200.972511) (xy 60.218556 -200.964729)
			(xy 60.204169 -200.950341) (xy 60.196389 -200.93154) (xy 60.195968 -200.921366) (xy 54.154832 -200.921366)
			(xy 54.154407 -200.931539) (xy 54.146628 -200.950339) (xy 54.132242 -200.964726) (xy 54.113443 -200.972507)
			(xy 54.10327 -200.972928) (xy 52.70373 -200.972928) (xy 52.693556 -200.972511) (xy 52.674756 -200.964729)
			(xy 52.660369 -200.950341) (xy 52.652589 -200.93154) (xy 52.652168 -200.921366) (xy 46.611032 -200.921366)
			(xy 46.610607 -200.931539) (xy 46.602828 -200.950339) (xy 46.588442 -200.964726) (xy 46.569643 -200.972507)
			(xy 46.55947 -200.972928) (xy 45.15993 -200.972928) (xy 45.149756 -200.972511) (xy 45.130956 -200.964729)
			(xy 45.116569 -200.950341) (xy 45.108789 -200.93154) (xy 45.108368 -200.921366) (xy 39.067232 -200.921366)
			(xy 39.066807 -200.931539) (xy 39.059028 -200.950339) (xy 39.044642 -200.964726) (xy 39.025843 -200.972507)
			(xy 39.01567 -200.972928) (xy 37.61613 -200.972928) (xy 37.605956 -200.972511) (xy 37.587156 -200.964729)
			(xy 37.572769 -200.950341) (xy 37.564989 -200.93154) (xy 37.564568 -200.921366) (xy 31.523432 -200.921366)
			(xy 31.523007 -200.931539) (xy 31.515228 -200.950339) (xy 31.500842 -200.964726) (xy 31.482043 -200.972507)
			(xy 31.47187 -200.972928) (xy 30.07233 -200.972928) (xy 30.062156 -200.972511) (xy 30.043356 -200.964729)
			(xy 30.028969 -200.950341) (xy 30.021189 -200.93154) (xy 30.020768 -200.921366) (xy 23.979632 -200.921366)
			(xy 23.979207 -200.931539) (xy 23.971428 -200.950339) (xy 23.957042 -200.964726) (xy 23.938243 -200.972507)
			(xy 23.92807 -200.972928) (xy 22.52853 -200.972928) (xy 22.518356 -200.972511) (xy 22.499556 -200.964729)
			(xy 22.485169 -200.950341) (xy 22.477389 -200.93154) (xy 22.476968 -200.921366) (xy 16.435832 -200.921366)
			(xy 16.435407 -200.931539) (xy 16.427628 -200.950339) (xy 16.413242 -200.964726) (xy 16.394443 -200.972507)
			(xy 16.38427 -200.972928) (xy 14.98473 -200.972928) (xy 14.974556 -200.972511) (xy 14.955756 -200.964729)
			(xy 14.941369 -200.950341) (xy 14.933589 -200.93154) (xy 14.933168 -200.921366) (xy 8.892032 -200.921366)
			(xy 8.891607 -200.931539) (xy 8.883828 -200.950339) (xy 8.869442 -200.964726) (xy 8.850643 -200.972507)
			(xy 8.84047 -200.972928) (xy 7.44093 -200.972928) (xy 7.430756 -200.972511) (xy 7.411956 -200.964729)
			(xy 7.397569 -200.950341) (xy 7.389789 -200.93154) (xy 7.389368 -200.921366) (xy 2.509012 -200.921366)
			(xy 2.509012 -201.771504) (xy 11.489436 -201.771504) (xy 11.489436 -201.362564) (xy 11.489793 -201.352403)
			(xy 11.497607 -201.333643) (xy 11.512024 -201.31932) (xy 11.530834 -201.311628) (xy 11.540998 -201.311256)
			(xy 12.940538 -201.311256) (xy 12.950669 -201.311696) (xy 12.969394 -201.319439) (xy 12.98375 -201.33374)
			(xy 12.991565 -201.352435) (xy 12.9921 -201.362564) (xy 12.9921 -201.771504) (xy 19.033236 -201.771504)
			(xy 19.033236 -201.362564) (xy 19.033593 -201.352403) (xy 19.041407 -201.333643) (xy 19.055824 -201.31932)
			(xy 19.074634 -201.311628) (xy 19.084798 -201.311256) (xy 20.484338 -201.311256) (xy 20.494469 -201.311696)
			(xy 20.513194 -201.319439) (xy 20.52755 -201.33374) (xy 20.535365 -201.352435) (xy 20.5359 -201.362564)
			(xy 20.5359 -201.771504) (xy 26.577036 -201.771504) (xy 26.577036 -201.362564) (xy 26.577393 -201.352403)
			(xy 26.585207 -201.333643) (xy 26.599624 -201.31932) (xy 26.618434 -201.311628) (xy 26.628598 -201.311256)
			(xy 28.028138 -201.311256) (xy 28.038269 -201.311696) (xy 28.056994 -201.319439) (xy 28.07135 -201.33374)
			(xy 28.079165 -201.352435) (xy 28.0797 -201.362564) (xy 28.0797 -201.771504) (xy 34.120836 -201.771504)
			(xy 34.120836 -201.362564) (xy 34.121193 -201.352403) (xy 34.129007 -201.333643) (xy 34.143424 -201.31932)
			(xy 34.162234 -201.311628) (xy 34.172398 -201.311256) (xy 35.571938 -201.311256) (xy 35.582069 -201.311696)
			(xy 35.600794 -201.319439) (xy 35.61515 -201.33374) (xy 35.622965 -201.352435) (xy 35.6235 -201.362564)
			(xy 35.6235 -201.771504) (xy 41.664636 -201.771504) (xy 41.664636 -201.362564) (xy 41.664993 -201.352403)
			(xy 41.672807 -201.333643) (xy 41.687224 -201.31932) (xy 41.706034 -201.311628) (xy 41.716198 -201.311256)
			(xy 43.115738 -201.311256) (xy 43.125869 -201.311696) (xy 43.144594 -201.319439) (xy 43.15895 -201.33374)
			(xy 43.166765 -201.352435) (xy 43.1673 -201.362564) (xy 43.1673 -201.771504) (xy 49.208436 -201.771504)
			(xy 49.208436 -201.362564) (xy 49.208793 -201.352403) (xy 49.216607 -201.333643) (xy 49.231024 -201.31932)
			(xy 49.249834 -201.311628) (xy 49.259998 -201.311256) (xy 50.659538 -201.311256) (xy 50.669669 -201.311696)
			(xy 50.688394 -201.319439) (xy 50.70275 -201.33374) (xy 50.710565 -201.352435) (xy 50.7111 -201.362564)
			(xy 50.7111 -201.771504) (xy 56.752236 -201.771504) (xy 56.752236 -201.362564) (xy 56.752593 -201.352403)
			(xy 56.760407 -201.333643) (xy 56.774824 -201.31932) (xy 56.793634 -201.311628) (xy 56.803798 -201.311256)
			(xy 58.203338 -201.311256) (xy 58.213469 -201.311696) (xy 58.232194 -201.319439) (xy 58.24655 -201.33374)
			(xy 58.254365 -201.352435) (xy 58.2549 -201.362564) (xy 58.2549 -201.771504) (xy 64.296036 -201.771504)
			(xy 64.296036 -201.362564) (xy 64.296393 -201.352403) (xy 64.304207 -201.333643) (xy 64.318624 -201.31932)
			(xy 64.337434 -201.311628) (xy 64.347598 -201.311256) (xy 65.747138 -201.311256) (xy 65.757269 -201.311696)
			(xy 65.775994 -201.319439) (xy 65.79035 -201.33374) (xy 65.798165 -201.352435) (xy 65.7987 -201.362564)
			(xy 65.7987 -201.771504) (xy 162.162236 -201.771504) (xy 162.162236 -201.362564) (xy 162.162593 -201.352403)
			(xy 162.170407 -201.333643) (xy 162.184824 -201.31932) (xy 162.203634 -201.311628) (xy 162.213798 -201.311256)
			(xy 163.613338 -201.311256) (xy 163.623469 -201.311696) (xy 163.642194 -201.319439) (xy 163.65655 -201.33374)
			(xy 163.664365 -201.352435) (xy 163.6649 -201.362564) (xy 163.6649 -201.771504) (xy 169.706036 -201.771504)
			(xy 169.706036 -201.362564) (xy 169.706393 -201.352403) (xy 169.714207 -201.333643) (xy 169.728624 -201.31932)
			(xy 169.747434 -201.311628) (xy 169.757598 -201.311256) (xy 171.157138 -201.311256) (xy 171.167269 -201.311696)
			(xy 171.185994 -201.319439) (xy 171.20035 -201.33374) (xy 171.208165 -201.352435) (xy 171.2087 -201.362564)
			(xy 171.2087 -201.771504) (xy 177.249836 -201.771504) (xy 177.249836 -201.362564) (xy 177.250193 -201.352403)
			(xy 177.258007 -201.333643) (xy 177.272424 -201.31932) (xy 177.291234 -201.311628) (xy 177.301398 -201.311256)
			(xy 178.700938 -201.311256) (xy 178.711069 -201.311696) (xy 178.729794 -201.319439) (xy 178.74415 -201.33374)
			(xy 178.751965 -201.352435) (xy 178.7525 -201.362564) (xy 178.7525 -201.771504) (xy 184.793636 -201.771504)
			(xy 184.793636 -201.362564) (xy 184.793993 -201.352403) (xy 184.801807 -201.333643) (xy 184.816224 -201.31932)
			(xy 184.835034 -201.311628) (xy 184.845198 -201.311256) (xy 186.244738 -201.311256) (xy 186.254869 -201.311696)
			(xy 186.273594 -201.319439) (xy 186.28795 -201.33374) (xy 186.295765 -201.352435) (xy 186.2963 -201.362564)
			(xy 186.2963 -201.771504) (xy 192.337436 -201.771504) (xy 192.337436 -201.362564) (xy 192.337793 -201.352403)
			(xy 192.345607 -201.333643) (xy 192.360024 -201.31932) (xy 192.378834 -201.311628) (xy 192.388998 -201.311256)
			(xy 193.788538 -201.311256) (xy 193.798669 -201.311696) (xy 193.817394 -201.319439) (xy 193.83175 -201.33374)
			(xy 193.839565 -201.352435) (xy 193.8401 -201.362564) (xy 193.8401 -201.771504) (xy 199.881236 -201.771504)
			(xy 199.881236 -201.362564) (xy 199.881593 -201.352403) (xy 199.889407 -201.333643) (xy 199.903824 -201.31932)
			(xy 199.922634 -201.311628) (xy 199.932798 -201.311256) (xy 201.332338 -201.311256) (xy 201.342469 -201.311696)
			(xy 201.361194 -201.319439) (xy 201.37555 -201.33374) (xy 201.383365 -201.352435) (xy 201.3839 -201.362564)
			(xy 201.3839 -201.771504) (xy 207.425036 -201.771504) (xy 207.425036 -201.362564) (xy 207.425393 -201.352403)
			(xy 207.433207 -201.333643) (xy 207.447624 -201.31932) (xy 207.466434 -201.311628) (xy 207.476598 -201.311256)
			(xy 208.876138 -201.311256) (xy 208.886269 -201.311696) (xy 208.904994 -201.319439) (xy 208.91935 -201.33374)
			(xy 208.927165 -201.352435) (xy 208.9277 -201.362564) (xy 208.9277 -201.771504) (xy 214.968836 -201.771504)
			(xy 214.968836 -201.362564) (xy 214.969193 -201.352403) (xy 214.977007 -201.333643) (xy 214.991424 -201.31932)
			(xy 215.010234 -201.311628) (xy 215.020398 -201.311256) (xy 216.419938 -201.311256) (xy 216.430069 -201.311696)
			(xy 216.448794 -201.319439) (xy 216.46315 -201.33374) (xy 216.470965 -201.352435) (xy 216.4715 -201.362564)
			(xy 216.4715 -201.771504) (xy 259.429504 -201.771504) (xy 259.429504 -201.362564) (xy 259.429892 -201.352407)
			(xy 259.4377 -201.333653) (xy 259.452107 -201.319331) (xy 259.470907 -201.311633) (xy 259.481066 -201.311256)
			(xy 260.880606 -201.311256) (xy 260.890735 -201.311722) (xy 260.909459 -201.319455) (xy 260.923816 -201.333748)
			(xy 260.931632 -201.352437) (xy 260.932168 -201.362564) (xy 260.932168 -201.771504) (xy 266.973304 -201.771504)
			(xy 266.973304 -201.362564) (xy 266.973692 -201.352407) (xy 266.9815 -201.333653) (xy 266.995907 -201.319331)
			(xy 267.014707 -201.311633) (xy 267.024866 -201.311256) (xy 268.424406 -201.311256) (xy 268.434535 -201.311722)
			(xy 268.453259 -201.319455) (xy 268.467616 -201.333748) (xy 268.475432 -201.352437) (xy 268.475968 -201.362564)
			(xy 268.475968 -201.771504) (xy 274.517104 -201.771504) (xy 274.517104 -201.362564) (xy 274.517492 -201.352407)
			(xy 274.5253 -201.333653) (xy 274.539707 -201.319331) (xy 274.558507 -201.311633) (xy 274.568666 -201.311256)
			(xy 275.968206 -201.311256) (xy 275.978335 -201.311722) (xy 275.997059 -201.319455) (xy 276.011416 -201.333748)
			(xy 276.019232 -201.352437) (xy 276.019768 -201.362564) (xy 276.019768 -201.771504) (xy 282.060904 -201.771504)
			(xy 282.060904 -201.362564) (xy 282.061292 -201.352407) (xy 282.0691 -201.333653) (xy 282.083507 -201.319331)
			(xy 282.102307 -201.311633) (xy 282.112466 -201.311256) (xy 283.512006 -201.311256) (xy 283.522135 -201.311722)
			(xy 283.540859 -201.319455) (xy 283.555216 -201.333748) (xy 283.563032 -201.352437) (xy 283.563568 -201.362564)
			(xy 283.563568 -201.771504) (xy 289.604704 -201.771504) (xy 289.604704 -201.362564) (xy 289.605092 -201.352407)
			(xy 289.6129 -201.333653) (xy 289.627307 -201.319331) (xy 289.646107 -201.311633) (xy 289.656266 -201.311256)
			(xy 291.055806 -201.311256) (xy 291.065935 -201.311722) (xy 291.084659 -201.319455) (xy 291.099016 -201.333748)
			(xy 291.106832 -201.352437) (xy 291.107368 -201.362564) (xy 291.107368 -201.771504) (xy 297.148504 -201.771504)
			(xy 297.148504 -201.362564) (xy 297.148892 -201.352407) (xy 297.1567 -201.333653) (xy 297.171107 -201.319331)
			(xy 297.189907 -201.311633) (xy 297.200066 -201.311256) (xy 298.599606 -201.311256) (xy 298.609735 -201.311722)
			(xy 298.628459 -201.319455) (xy 298.642816 -201.333748) (xy 298.650632 -201.352437) (xy 298.651168 -201.362564)
			(xy 298.651168 -201.771504) (xy 304.692304 -201.771504) (xy 304.692304 -201.362564) (xy 304.692692 -201.352407)
			(xy 304.7005 -201.333653) (xy 304.714907 -201.319331) (xy 304.733707 -201.311633) (xy 304.743866 -201.311256)
			(xy 306.143406 -201.311256) (xy 306.153535 -201.311722) (xy 306.172259 -201.319455) (xy 306.186616 -201.333748)
			(xy 306.194432 -201.352437) (xy 306.194968 -201.362564) (xy 306.194968 -201.771504) (xy 312.236104 -201.771504)
			(xy 312.236104 -201.362564) (xy 312.236492 -201.352407) (xy 312.2443 -201.333653) (xy 312.258707 -201.319331)
			(xy 312.277507 -201.311633) (xy 312.287666 -201.311256) (xy 313.687206 -201.311256) (xy 313.697335 -201.311722)
			(xy 313.716059 -201.319455) (xy 313.730416 -201.333748) (xy 313.738232 -201.352437) (xy 313.738768 -201.362564)
			(xy 313.738768 -201.771504) (xy 410.102304 -201.771504) (xy 410.102304 -201.362564) (xy 410.102692 -201.352407)
			(xy 410.1105 -201.333653) (xy 410.124907 -201.319331) (xy 410.143707 -201.311633) (xy 410.153866 -201.311256)
			(xy 411.553406 -201.311256) (xy 411.563535 -201.311722) (xy 411.582259 -201.319455) (xy 411.596616 -201.333748)
			(xy 411.604432 -201.352437) (xy 411.604968 -201.362564) (xy 411.604968 -201.771504) (xy 417.646104 -201.771504)
			(xy 417.646104 -201.362564) (xy 417.646492 -201.352407) (xy 417.6543 -201.333653) (xy 417.668707 -201.319331)
			(xy 417.687507 -201.311633) (xy 417.697666 -201.311256) (xy 419.097206 -201.311256) (xy 419.107335 -201.311722)
			(xy 419.126059 -201.319455) (xy 419.140416 -201.333748) (xy 419.148232 -201.352437) (xy 419.148768 -201.362564)
			(xy 419.148768 -201.771504) (xy 425.189904 -201.771504) (xy 425.189904 -201.362564) (xy 425.190292 -201.352407)
			(xy 425.1981 -201.333653) (xy 425.212507 -201.319331) (xy 425.231307 -201.311633) (xy 425.241466 -201.311256)
			(xy 426.641006 -201.311256) (xy 426.651135 -201.311722) (xy 426.669859 -201.319455) (xy 426.684216 -201.333748)
			(xy 426.692032 -201.352437) (xy 426.692568 -201.362564) (xy 426.692568 -201.771504) (xy 432.733704 -201.771504)
			(xy 432.733704 -201.362564) (xy 432.734092 -201.352407) (xy 432.7419 -201.333653) (xy 432.756307 -201.319331)
			(xy 432.775107 -201.311633) (xy 432.785266 -201.311256) (xy 434.184806 -201.311256) (xy 434.194935 -201.311722)
			(xy 434.213659 -201.319455) (xy 434.228016 -201.333748) (xy 434.235832 -201.352437) (xy 434.236368 -201.362564)
			(xy 434.236368 -201.771504) (xy 440.277504 -201.771504) (xy 440.277504 -201.362564) (xy 440.277892 -201.352407)
			(xy 440.2857 -201.333653) (xy 440.300107 -201.319331) (xy 440.318907 -201.311633) (xy 440.329066 -201.311256)
			(xy 441.728606 -201.311256) (xy 441.738735 -201.311722) (xy 441.757459 -201.319455) (xy 441.771816 -201.333748)
			(xy 441.779632 -201.352437) (xy 441.780168 -201.362564) (xy 441.780168 -201.771504) (xy 447.821304 -201.771504)
			(xy 447.821304 -201.362564) (xy 447.821692 -201.352407) (xy 447.8295 -201.333653) (xy 447.843907 -201.319331)
			(xy 447.862707 -201.311633) (xy 447.872866 -201.311256) (xy 449.272406 -201.311256) (xy 449.282535 -201.311722)
			(xy 449.301259 -201.319455) (xy 449.315616 -201.333748) (xy 449.323432 -201.352437) (xy 449.323968 -201.362564)
			(xy 449.323968 -201.771504) (xy 455.365104 -201.771504) (xy 455.365104 -201.362564) (xy 455.365492 -201.352407)
			(xy 455.3733 -201.333653) (xy 455.387707 -201.319331) (xy 455.406507 -201.311633) (xy 455.416666 -201.311256)
			(xy 456.816206 -201.311256) (xy 456.826335 -201.311722) (xy 456.845059 -201.319455) (xy 456.859416 -201.333748)
			(xy 456.867232 -201.352437) (xy 456.867768 -201.362564) (xy 456.867768 -201.771504) (xy 462.908904 -201.771504)
			(xy 462.908904 -201.362564) (xy 462.909292 -201.352407) (xy 462.9171 -201.333653) (xy 462.931507 -201.319331)
			(xy 462.950307 -201.311633) (xy 462.960466 -201.311256) (xy 464.360006 -201.311256) (xy 464.370135 -201.311722)
			(xy 464.388859 -201.319455) (xy 464.403216 -201.333748) (xy 464.411032 -201.352437) (xy 464.411568 -201.362564)
			(xy 464.411568 -201.771504) (xy 464.411181 -201.781662) (xy 464.403378 -201.800421) (xy 464.38897 -201.814745)
			(xy 464.370167 -201.822439) (xy 464.360006 -201.822812) (xy 462.960466 -201.822812) (xy 462.950344 -201.822303)
			(xy 462.931631 -201.814574) (xy 462.917278 -201.800295) (xy 462.909451 -201.781624) (xy 462.908904 -201.771504)
			(xy 456.867768 -201.771504) (xy 456.867381 -201.781662) (xy 456.859578 -201.800421) (xy 456.84517 -201.814745)
			(xy 456.826367 -201.822439) (xy 456.816206 -201.822812) (xy 455.416666 -201.822812) (xy 455.406544 -201.822303)
			(xy 455.387831 -201.814574) (xy 455.373478 -201.800295) (xy 455.365651 -201.781624) (xy 455.365104 -201.771504)
			(xy 449.323968 -201.771504) (xy 449.323581 -201.781662) (xy 449.315778 -201.800421) (xy 449.30137 -201.814745)
			(xy 449.282567 -201.822439) (xy 449.272406 -201.822812) (xy 447.872866 -201.822812) (xy 447.862744 -201.822303)
			(xy 447.844031 -201.814574) (xy 447.829678 -201.800295) (xy 447.821851 -201.781624) (xy 447.821304 -201.771504)
			(xy 441.780168 -201.771504) (xy 441.779781 -201.781662) (xy 441.771978 -201.800421) (xy 441.75757 -201.814745)
			(xy 441.738767 -201.822439) (xy 441.728606 -201.822812) (xy 440.329066 -201.822812) (xy 440.318944 -201.822303)
			(xy 440.300231 -201.814574) (xy 440.285878 -201.800295) (xy 440.278051 -201.781624) (xy 440.277504 -201.771504)
			(xy 434.236368 -201.771504) (xy 434.235981 -201.781662) (xy 434.228178 -201.800421) (xy 434.21377 -201.814745)
			(xy 434.194967 -201.822439) (xy 434.184806 -201.822812) (xy 432.785266 -201.822812) (xy 432.775144 -201.822303)
			(xy 432.756431 -201.814574) (xy 432.742078 -201.800295) (xy 432.734251 -201.781624) (xy 432.733704 -201.771504)
			(xy 426.692568 -201.771504) (xy 426.692181 -201.781662) (xy 426.684378 -201.800421) (xy 426.66997 -201.814745)
			(xy 426.651167 -201.822439) (xy 426.641006 -201.822812) (xy 425.241466 -201.822812) (xy 425.231344 -201.822303)
			(xy 425.212631 -201.814574) (xy 425.198278 -201.800295) (xy 425.190451 -201.781624) (xy 425.189904 -201.771504)
			(xy 419.148768 -201.771504) (xy 419.148381 -201.781662) (xy 419.140578 -201.800421) (xy 419.12617 -201.814745)
			(xy 419.107367 -201.822439) (xy 419.097206 -201.822812) (xy 417.697666 -201.822812) (xy 417.687544 -201.822303)
			(xy 417.668831 -201.814574) (xy 417.654478 -201.800295) (xy 417.646651 -201.781624) (xy 417.646104 -201.771504)
			(xy 411.604968 -201.771504) (xy 411.604581 -201.781662) (xy 411.596778 -201.800421) (xy 411.58237 -201.814745)
			(xy 411.563567 -201.822439) (xy 411.553406 -201.822812) (xy 410.153866 -201.822812) (xy 410.143744 -201.822303)
			(xy 410.125031 -201.814574) (xy 410.110678 -201.800295) (xy 410.102851 -201.781624) (xy 410.102304 -201.771504)
			(xy 313.738768 -201.771504) (xy 313.738381 -201.781662) (xy 313.730578 -201.800421) (xy 313.71617 -201.814745)
			(xy 313.697367 -201.822439) (xy 313.687206 -201.822812) (xy 312.287666 -201.822812) (xy 312.277544 -201.822303)
			(xy 312.258831 -201.814574) (xy 312.244478 -201.800295) (xy 312.236651 -201.781624) (xy 312.236104 -201.771504)
			(xy 306.194968 -201.771504) (xy 306.194581 -201.781662) (xy 306.186778 -201.800421) (xy 306.17237 -201.814745)
			(xy 306.153567 -201.822439) (xy 306.143406 -201.822812) (xy 304.743866 -201.822812) (xy 304.733744 -201.822303)
			(xy 304.715031 -201.814574) (xy 304.700678 -201.800295) (xy 304.692851 -201.781624) (xy 304.692304 -201.771504)
			(xy 298.651168 -201.771504) (xy 298.650781 -201.781662) (xy 298.642978 -201.800421) (xy 298.62857 -201.814745)
			(xy 298.609767 -201.822439) (xy 298.599606 -201.822812) (xy 297.200066 -201.822812) (xy 297.189944 -201.822303)
			(xy 297.171231 -201.814574) (xy 297.156878 -201.800295) (xy 297.149051 -201.781624) (xy 297.148504 -201.771504)
			(xy 291.107368 -201.771504) (xy 291.106981 -201.781662) (xy 291.099178 -201.800421) (xy 291.08477 -201.814745)
			(xy 291.065967 -201.822439) (xy 291.055806 -201.822812) (xy 289.656266 -201.822812) (xy 289.646144 -201.822303)
			(xy 289.627431 -201.814574) (xy 289.613078 -201.800295) (xy 289.605251 -201.781624) (xy 289.604704 -201.771504)
			(xy 283.563568 -201.771504) (xy 283.563181 -201.781662) (xy 283.555378 -201.800421) (xy 283.54097 -201.814745)
			(xy 283.522167 -201.822439) (xy 283.512006 -201.822812) (xy 282.112466 -201.822812) (xy 282.102344 -201.822303)
			(xy 282.083631 -201.814574) (xy 282.069278 -201.800295) (xy 282.061451 -201.781624) (xy 282.060904 -201.771504)
			(xy 276.019768 -201.771504) (xy 276.019381 -201.781662) (xy 276.011578 -201.800421) (xy 275.99717 -201.814745)
			(xy 275.978367 -201.822439) (xy 275.968206 -201.822812) (xy 274.568666 -201.822812) (xy 274.558544 -201.822303)
			(xy 274.539831 -201.814574) (xy 274.525478 -201.800295) (xy 274.517651 -201.781624) (xy 274.517104 -201.771504)
			(xy 268.475968 -201.771504) (xy 268.475581 -201.781662) (xy 268.467778 -201.800421) (xy 268.45337 -201.814745)
			(xy 268.434567 -201.822439) (xy 268.424406 -201.822812) (xy 267.024866 -201.822812) (xy 267.014744 -201.822303)
			(xy 266.996031 -201.814574) (xy 266.981678 -201.800295) (xy 266.973851 -201.781624) (xy 266.973304 -201.771504)
			(xy 260.932168 -201.771504) (xy 260.931781 -201.781662) (xy 260.923978 -201.800421) (xy 260.90957 -201.814745)
			(xy 260.890767 -201.822439) (xy 260.880606 -201.822812) (xy 259.481066 -201.822812) (xy 259.470944 -201.822303)
			(xy 259.452231 -201.814574) (xy 259.437878 -201.800295) (xy 259.430051 -201.781624) (xy 259.429504 -201.771504)
			(xy 216.4715 -201.771504) (xy 216.471082 -201.781658) (xy 216.463285 -201.800411) (xy 216.448887 -201.814734)
			(xy 216.430094 -201.822434) (xy 216.419938 -201.822812) (xy 215.020398 -201.822812) (xy 215.010278 -201.822277)
			(xy 214.991566 -201.814558) (xy 214.977212 -201.800287) (xy 214.969384 -201.781621) (xy 214.968836 -201.771504)
			(xy 208.9277 -201.771504) (xy 208.927282 -201.781658) (xy 208.919485 -201.800411) (xy 208.905087 -201.814734)
			(xy 208.886294 -201.822434) (xy 208.876138 -201.822812) (xy 207.476598 -201.822812) (xy 207.466478 -201.822277)
			(xy 207.447766 -201.814558) (xy 207.433412 -201.800287) (xy 207.425584 -201.781621) (xy 207.425036 -201.771504)
			(xy 201.3839 -201.771504) (xy 201.383482 -201.781658) (xy 201.375685 -201.800411) (xy 201.361287 -201.814734)
			(xy 201.342494 -201.822434) (xy 201.332338 -201.822812) (xy 199.932798 -201.822812) (xy 199.922678 -201.822277)
			(xy 199.903966 -201.814558) (xy 199.889612 -201.800287) (xy 199.881784 -201.781621) (xy 199.881236 -201.771504)
			(xy 193.8401 -201.771504) (xy 193.839682 -201.781658) (xy 193.831885 -201.800411) (xy 193.817487 -201.814734)
			(xy 193.798694 -201.822434) (xy 193.788538 -201.822812) (xy 192.388998 -201.822812) (xy 192.378878 -201.822277)
			(xy 192.360166 -201.814558) (xy 192.345812 -201.800287) (xy 192.337984 -201.781621) (xy 192.337436 -201.771504)
			(xy 186.2963 -201.771504) (xy 186.295882 -201.781658) (xy 186.288085 -201.800411) (xy 186.273687 -201.814734)
			(xy 186.254894 -201.822434) (xy 186.244738 -201.822812) (xy 184.845198 -201.822812) (xy 184.835078 -201.822277)
			(xy 184.816366 -201.814558) (xy 184.802012 -201.800287) (xy 184.794184 -201.781621) (xy 184.793636 -201.771504)
			(xy 178.7525 -201.771504) (xy 178.752082 -201.781658) (xy 178.744285 -201.800411) (xy 178.729887 -201.814734)
			(xy 178.711094 -201.822434) (xy 178.700938 -201.822812) (xy 177.301398 -201.822812) (xy 177.291278 -201.822277)
			(xy 177.272566 -201.814558) (xy 177.258212 -201.800287) (xy 177.250384 -201.781621) (xy 177.249836 -201.771504)
			(xy 171.2087 -201.771504) (xy 171.208282 -201.781658) (xy 171.200485 -201.800411) (xy 171.186087 -201.814734)
			(xy 171.167294 -201.822434) (xy 171.157138 -201.822812) (xy 169.757598 -201.822812) (xy 169.747478 -201.822277)
			(xy 169.728766 -201.814558) (xy 169.714412 -201.800287) (xy 169.706584 -201.781621) (xy 169.706036 -201.771504)
			(xy 163.6649 -201.771504) (xy 163.664482 -201.781658) (xy 163.656685 -201.800411) (xy 163.642287 -201.814734)
			(xy 163.623494 -201.822434) (xy 163.613338 -201.822812) (xy 162.213798 -201.822812) (xy 162.203678 -201.822277)
			(xy 162.184966 -201.814558) (xy 162.170612 -201.800287) (xy 162.162784 -201.781621) (xy 162.162236 -201.771504)
			(xy 65.7987 -201.771504) (xy 65.798282 -201.781658) (xy 65.790485 -201.800411) (xy 65.776087 -201.814734)
			(xy 65.757294 -201.822434) (xy 65.747138 -201.822812) (xy 64.347598 -201.822812) (xy 64.337478 -201.822277)
			(xy 64.318766 -201.814558) (xy 64.304412 -201.800287) (xy 64.296584 -201.781621) (xy 64.296036 -201.771504)
			(xy 58.2549 -201.771504) (xy 58.254482 -201.781658) (xy 58.246685 -201.800411) (xy 58.232287 -201.814734)
			(xy 58.213494 -201.822434) (xy 58.203338 -201.822812) (xy 56.803798 -201.822812) (xy 56.793678 -201.822277)
			(xy 56.774966 -201.814558) (xy 56.760612 -201.800287) (xy 56.752784 -201.781621) (xy 56.752236 -201.771504)
			(xy 50.7111 -201.771504) (xy 50.710682 -201.781658) (xy 50.702885 -201.800411) (xy 50.688487 -201.814734)
			(xy 50.669694 -201.822434) (xy 50.659538 -201.822812) (xy 49.259998 -201.822812) (xy 49.249878 -201.822277)
			(xy 49.231166 -201.814558) (xy 49.216812 -201.800287) (xy 49.208984 -201.781621) (xy 49.208436 -201.771504)
			(xy 43.1673 -201.771504) (xy 43.166882 -201.781658) (xy 43.159085 -201.800411) (xy 43.144687 -201.814734)
			(xy 43.125894 -201.822434) (xy 43.115738 -201.822812) (xy 41.716198 -201.822812) (xy 41.706078 -201.822277)
			(xy 41.687366 -201.814558) (xy 41.673012 -201.800287) (xy 41.665184 -201.781621) (xy 41.664636 -201.771504)
			(xy 35.6235 -201.771504) (xy 35.623082 -201.781658) (xy 35.615285 -201.800411) (xy 35.600887 -201.814734)
			(xy 35.582094 -201.822434) (xy 35.571938 -201.822812) (xy 34.172398 -201.822812) (xy 34.162278 -201.822277)
			(xy 34.143566 -201.814558) (xy 34.129212 -201.800287) (xy 34.121384 -201.781621) (xy 34.120836 -201.771504)
			(xy 28.0797 -201.771504) (xy 28.079282 -201.781658) (xy 28.071485 -201.800411) (xy 28.057087 -201.814734)
			(xy 28.038294 -201.822434) (xy 28.028138 -201.822812) (xy 26.628598 -201.822812) (xy 26.618478 -201.822277)
			(xy 26.599766 -201.814558) (xy 26.585412 -201.800287) (xy 26.577584 -201.781621) (xy 26.577036 -201.771504)
			(xy 20.5359 -201.771504) (xy 20.535482 -201.781658) (xy 20.527685 -201.800411) (xy 20.513287 -201.814734)
			(xy 20.494494 -201.822434) (xy 20.484338 -201.822812) (xy 19.084798 -201.822812) (xy 19.074678 -201.822277)
			(xy 19.055966 -201.814558) (xy 19.041612 -201.800287) (xy 19.033784 -201.781621) (xy 19.033236 -201.771504)
			(xy 12.9921 -201.771504) (xy 12.991682 -201.781658) (xy 12.983885 -201.800411) (xy 12.969487 -201.814734)
			(xy 12.950694 -201.822434) (xy 12.940538 -201.822812) (xy 11.540998 -201.822812) (xy 11.530878 -201.822277)
			(xy 11.512166 -201.814558) (xy 11.497812 -201.800287) (xy 11.489984 -201.781621) (xy 11.489436 -201.771504)
			(xy 2.509012 -201.771504) (xy 2.509012 -202.621388) (xy 7.389368 -202.621388) (xy 7.389368 -202.212448)
			(xy 7.38986 -202.202301) (xy 7.397634 -202.183556) (xy 7.412009 -202.169232) (xy 7.430782 -202.161525)
			(xy 7.44093 -202.16114) (xy 8.84047 -202.16114) (xy 8.850595 -202.161651) (xy 8.869315 -202.169369)
			(xy 8.883673 -202.183648) (xy 8.891493 -202.202326) (xy 8.892032 -202.212448) (xy 8.892032 -202.621388)
			(xy 14.933168 -202.621388) (xy 14.933168 -202.212448) (xy 14.93366 -202.202301) (xy 14.941434 -202.183556)
			(xy 14.955809 -202.169232) (xy 14.974582 -202.161525) (xy 14.98473 -202.16114) (xy 16.38427 -202.16114)
			(xy 16.394395 -202.161651) (xy 16.413115 -202.169369) (xy 16.427473 -202.183648) (xy 16.435293 -202.202326)
			(xy 16.435832 -202.212448) (xy 16.435832 -202.621388) (xy 22.476968 -202.621388) (xy 22.476968 -202.212448)
			(xy 22.47746 -202.202301) (xy 22.485234 -202.183556) (xy 22.499609 -202.169232) (xy 22.518382 -202.161525)
			(xy 22.52853 -202.16114) (xy 23.92807 -202.16114) (xy 23.938195 -202.161651) (xy 23.956915 -202.169369)
			(xy 23.971273 -202.183648) (xy 23.979093 -202.202326) (xy 23.979632 -202.212448) (xy 23.979632 -202.621388)
			(xy 30.020768 -202.621388) (xy 30.020768 -202.212448) (xy 30.02126 -202.202301) (xy 30.029034 -202.183556)
			(xy 30.043409 -202.169232) (xy 30.062182 -202.161525) (xy 30.07233 -202.16114) (xy 31.47187 -202.16114)
			(xy 31.481995 -202.161651) (xy 31.500715 -202.169369) (xy 31.515073 -202.183648) (xy 31.522893 -202.202326)
			(xy 31.523432 -202.212448) (xy 31.523432 -202.621388) (xy 37.564568 -202.621388) (xy 37.564568 -202.212448)
			(xy 37.56506 -202.202301) (xy 37.572834 -202.183556) (xy 37.587209 -202.169232) (xy 37.605982 -202.161525)
			(xy 37.61613 -202.16114) (xy 39.01567 -202.16114) (xy 39.025795 -202.161651) (xy 39.044515 -202.169369)
			(xy 39.058873 -202.183648) (xy 39.066693 -202.202326) (xy 39.067232 -202.212448) (xy 39.067232 -202.621388)
			(xy 45.108368 -202.621388) (xy 45.108368 -202.212448) (xy 45.10886 -202.202301) (xy 45.116634 -202.183556)
			(xy 45.131009 -202.169232) (xy 45.149782 -202.161525) (xy 45.15993 -202.16114) (xy 46.55947 -202.16114)
			(xy 46.569595 -202.161651) (xy 46.588315 -202.169369) (xy 46.602673 -202.183648) (xy 46.610493 -202.202326)
			(xy 46.611032 -202.212448) (xy 46.611032 -202.621388) (xy 52.652168 -202.621388) (xy 52.652168 -202.212448)
			(xy 52.65266 -202.202301) (xy 52.660434 -202.183556) (xy 52.674809 -202.169232) (xy 52.693582 -202.161525)
			(xy 52.70373 -202.16114) (xy 54.10327 -202.16114) (xy 54.113395 -202.161651) (xy 54.132115 -202.169369)
			(xy 54.146473 -202.183648) (xy 54.154293 -202.202326) (xy 54.154832 -202.212448) (xy 54.154832 -202.621388)
			(xy 60.195968 -202.621388) (xy 60.195968 -202.212448) (xy 60.19646 -202.202301) (xy 60.204234 -202.183556)
			(xy 60.218609 -202.169232) (xy 60.237382 -202.161525) (xy 60.24753 -202.16114) (xy 61.64707 -202.16114)
			(xy 61.657195 -202.161651) (xy 61.675915 -202.169369) (xy 61.690273 -202.183648) (xy 61.698093 -202.202326)
			(xy 61.698632 -202.212448) (xy 61.698632 -202.621388) (xy 158.062168 -202.621388) (xy 158.062168 -202.212448)
			(xy 158.06266 -202.202301) (xy 158.070434 -202.183556) (xy 158.084809 -202.169232) (xy 158.103582 -202.161525)
			(xy 158.11373 -202.16114) (xy 159.51327 -202.16114) (xy 159.523395 -202.161651) (xy 159.542115 -202.169369)
			(xy 159.556473 -202.183648) (xy 159.564293 -202.202326) (xy 159.564832 -202.212448) (xy 159.564832 -202.621388)
			(xy 165.605968 -202.621388) (xy 165.605968 -202.212448) (xy 165.60646 -202.202301) (xy 165.614234 -202.183556)
			(xy 165.628609 -202.169232) (xy 165.647382 -202.161525) (xy 165.65753 -202.16114) (xy 167.05707 -202.16114)
			(xy 167.067195 -202.161651) (xy 167.085915 -202.169369) (xy 167.100273 -202.183648) (xy 167.108093 -202.202326)
			(xy 167.108632 -202.212448) (xy 167.108632 -202.621388) (xy 173.149768 -202.621388) (xy 173.149768 -202.212448)
			(xy 173.15026 -202.202301) (xy 173.158034 -202.183556) (xy 173.172409 -202.169232) (xy 173.191182 -202.161525)
			(xy 173.20133 -202.16114) (xy 174.60087 -202.16114) (xy 174.610995 -202.161651) (xy 174.629715 -202.169369)
			(xy 174.644073 -202.183648) (xy 174.651893 -202.202326) (xy 174.652432 -202.212448) (xy 174.652432 -202.621388)
			(xy 180.693568 -202.621388) (xy 180.693568 -202.212448) (xy 180.69406 -202.202301) (xy 180.701834 -202.183556)
			(xy 180.716209 -202.169232) (xy 180.734982 -202.161525) (xy 180.74513 -202.16114) (xy 182.14467 -202.16114)
			(xy 182.154795 -202.161651) (xy 182.173515 -202.169369) (xy 182.187873 -202.183648) (xy 182.195693 -202.202326)
			(xy 182.196232 -202.212448) (xy 182.196232 -202.621388) (xy 188.237368 -202.621388) (xy 188.237368 -202.212448)
			(xy 188.23786 -202.202301) (xy 188.245634 -202.183556) (xy 188.260009 -202.169232) (xy 188.278782 -202.161525)
			(xy 188.28893 -202.16114) (xy 189.68847 -202.16114) (xy 189.698595 -202.161651) (xy 189.717315 -202.169369)
			(xy 189.731673 -202.183648) (xy 189.739493 -202.202326) (xy 189.740032 -202.212448) (xy 189.740032 -202.621388)
			(xy 195.781168 -202.621388) (xy 195.781168 -202.212448) (xy 195.78166 -202.202301) (xy 195.789434 -202.183556)
			(xy 195.803809 -202.169232) (xy 195.822582 -202.161525) (xy 195.83273 -202.16114) (xy 197.23227 -202.16114)
			(xy 197.242395 -202.161651) (xy 197.261115 -202.169369) (xy 197.275473 -202.183648) (xy 197.283293 -202.202326)
			(xy 197.283832 -202.212448) (xy 197.283832 -202.621388) (xy 203.324968 -202.621388) (xy 203.324968 -202.212448)
			(xy 203.32546 -202.202301) (xy 203.333234 -202.183556) (xy 203.347609 -202.169232) (xy 203.366382 -202.161525)
			(xy 203.37653 -202.16114) (xy 204.77607 -202.16114) (xy 204.786195 -202.161651) (xy 204.804915 -202.169369)
			(xy 204.819273 -202.183648) (xy 204.827093 -202.202326) (xy 204.827632 -202.212448) (xy 204.827632 -202.621388)
			(xy 210.868768 -202.621388) (xy 210.868768 -202.212448) (xy 210.86926 -202.202301) (xy 210.877034 -202.183556)
			(xy 210.891409 -202.169232) (xy 210.910182 -202.161525) (xy 210.92033 -202.16114) (xy 212.31987 -202.16114)
			(xy 212.329995 -202.161651) (xy 212.348715 -202.169369) (xy 212.363073 -202.183648) (xy 212.370893 -202.202326)
			(xy 212.371432 -202.212448) (xy 212.371432 -202.621388) (xy 255.329436 -202.621388) (xy 255.329436 -202.212448)
			(xy 255.329862 -202.202293) (xy 255.337648 -202.183534) (xy 255.352045 -202.169208) (xy 255.370841 -202.161513)
			(xy 255.380998 -202.16114) (xy 256.780538 -202.16114) (xy 256.790667 -202.161595) (xy 256.809389 -202.169336)
			(xy 256.823744 -202.183631) (xy 256.831562 -202.202321) (xy 256.8321 -202.212448) (xy 256.8321 -202.621388)
			(xy 262.873236 -202.621388) (xy 262.873236 -202.212448) (xy 262.873662 -202.202293) (xy 262.881448 -202.183534)
			(xy 262.895845 -202.169208) (xy 262.914641 -202.161513) (xy 262.924798 -202.16114) (xy 264.324338 -202.16114)
			(xy 264.334467 -202.161595) (xy 264.353189 -202.169336) (xy 264.367544 -202.183631) (xy 264.375362 -202.202321)
			(xy 264.3759 -202.212448) (xy 264.3759 -202.621388) (xy 270.417036 -202.621388) (xy 270.417036 -202.212448)
			(xy 270.417462 -202.202293) (xy 270.425248 -202.183534) (xy 270.439645 -202.169208) (xy 270.458441 -202.161513)
			(xy 270.468598 -202.16114) (xy 271.868138 -202.16114) (xy 271.878267 -202.161595) (xy 271.896989 -202.169336)
			(xy 271.911344 -202.183631) (xy 271.919162 -202.202321) (xy 271.9197 -202.212448) (xy 271.9197 -202.621388)
			(xy 277.960836 -202.621388) (xy 277.960836 -202.212448) (xy 277.961262 -202.202293) (xy 277.969048 -202.183534)
			(xy 277.983445 -202.169208) (xy 278.002241 -202.161513) (xy 278.012398 -202.16114) (xy 279.411938 -202.16114)
			(xy 279.422067 -202.161595) (xy 279.440789 -202.169336) (xy 279.455144 -202.183631) (xy 279.462962 -202.202321)
			(xy 279.4635 -202.212448) (xy 279.4635 -202.621388) (xy 285.504636 -202.621388) (xy 285.504636 -202.212448)
			(xy 285.505062 -202.202293) (xy 285.512848 -202.183534) (xy 285.527245 -202.169208) (xy 285.546041 -202.161513)
			(xy 285.556198 -202.16114) (xy 286.955738 -202.16114) (xy 286.965867 -202.161595) (xy 286.984589 -202.169336)
			(xy 286.998944 -202.183631) (xy 287.006762 -202.202321) (xy 287.0073 -202.212448) (xy 287.0073 -202.621388)
			(xy 293.048436 -202.621388) (xy 293.048436 -202.212448) (xy 293.048862 -202.202293) (xy 293.056648 -202.183534)
			(xy 293.071045 -202.169208) (xy 293.089841 -202.161513) (xy 293.099998 -202.16114) (xy 294.499538 -202.16114)
			(xy 294.509667 -202.161595) (xy 294.528389 -202.169336) (xy 294.542744 -202.183631) (xy 294.550562 -202.202321)
			(xy 294.5511 -202.212448) (xy 294.5511 -202.621388) (xy 300.592236 -202.621388) (xy 300.592236 -202.212448)
			(xy 300.592662 -202.202293) (xy 300.600448 -202.183534) (xy 300.614845 -202.169208) (xy 300.633641 -202.161513)
			(xy 300.643798 -202.16114) (xy 302.043338 -202.16114) (xy 302.053467 -202.161595) (xy 302.072189 -202.169336)
			(xy 302.086544 -202.183631) (xy 302.094362 -202.202321) (xy 302.0949 -202.212448) (xy 302.0949 -202.621388)
			(xy 308.136036 -202.621388) (xy 308.136036 -202.212448) (xy 308.136462 -202.202293) (xy 308.144248 -202.183534)
			(xy 308.158645 -202.169208) (xy 308.177441 -202.161513) (xy 308.187598 -202.16114) (xy 309.587138 -202.16114)
			(xy 309.597267 -202.161595) (xy 309.615989 -202.169336) (xy 309.630344 -202.183631) (xy 309.638162 -202.202321)
			(xy 309.6387 -202.212448) (xy 309.6387 -202.621388) (xy 406.002236 -202.621388) (xy 406.002236 -202.212448)
			(xy 406.002662 -202.202293) (xy 406.010448 -202.183534) (xy 406.024845 -202.169208) (xy 406.043641 -202.161513)
			(xy 406.053798 -202.16114) (xy 407.453338 -202.16114) (xy 407.463467 -202.161595) (xy 407.482189 -202.169336)
			(xy 407.496544 -202.183631) (xy 407.504362 -202.202321) (xy 407.5049 -202.212448) (xy 407.5049 -202.621388)
			(xy 413.546036 -202.621388) (xy 413.546036 -202.212448) (xy 413.546462 -202.202293) (xy 413.554248 -202.183534)
			(xy 413.568645 -202.169208) (xy 413.587441 -202.161513) (xy 413.597598 -202.16114) (xy 414.997138 -202.16114)
			(xy 415.007267 -202.161595) (xy 415.025989 -202.169336) (xy 415.040344 -202.183631) (xy 415.048162 -202.202321)
			(xy 415.0487 -202.212448) (xy 415.0487 -202.621388) (xy 421.089836 -202.621388) (xy 421.089836 -202.212448)
			(xy 421.090262 -202.202293) (xy 421.098048 -202.183534) (xy 421.112445 -202.169208) (xy 421.131241 -202.161513)
			(xy 421.141398 -202.16114) (xy 422.540938 -202.16114) (xy 422.551067 -202.161595) (xy 422.569789 -202.169336)
			(xy 422.584144 -202.183631) (xy 422.591962 -202.202321) (xy 422.5925 -202.212448) (xy 422.5925 -202.621388)
			(xy 428.633636 -202.621388) (xy 428.633636 -202.212448) (xy 428.634062 -202.202293) (xy 428.641848 -202.183534)
			(xy 428.656245 -202.169208) (xy 428.675041 -202.161513) (xy 428.685198 -202.16114) (xy 430.084738 -202.16114)
			(xy 430.094867 -202.161595) (xy 430.113589 -202.169336) (xy 430.127944 -202.183631) (xy 430.135762 -202.202321)
			(xy 430.1363 -202.212448) (xy 430.1363 -202.621388) (xy 436.177436 -202.621388) (xy 436.177436 -202.212448)
			(xy 436.177862 -202.202293) (xy 436.185648 -202.183534) (xy 436.200045 -202.169208) (xy 436.218841 -202.161513)
			(xy 436.228998 -202.16114) (xy 437.628538 -202.16114) (xy 437.638667 -202.161595) (xy 437.657389 -202.169336)
			(xy 437.671744 -202.183631) (xy 437.679562 -202.202321) (xy 437.6801 -202.212448) (xy 437.6801 -202.621388)
			(xy 443.721236 -202.621388) (xy 443.721236 -202.212448) (xy 443.721662 -202.202293) (xy 443.729448 -202.183534)
			(xy 443.743845 -202.169208) (xy 443.762641 -202.161513) (xy 443.772798 -202.16114) (xy 445.172338 -202.16114)
			(xy 445.182467 -202.161595) (xy 445.201189 -202.169336) (xy 445.215544 -202.183631) (xy 445.223362 -202.202321)
			(xy 445.2239 -202.212448) (xy 445.2239 -202.621388) (xy 451.265036 -202.621388) (xy 451.265036 -202.212448)
			(xy 451.265462 -202.202293) (xy 451.273248 -202.183534) (xy 451.287645 -202.169208) (xy 451.306441 -202.161513)
			(xy 451.316598 -202.16114) (xy 452.716138 -202.16114) (xy 452.726267 -202.161595) (xy 452.744989 -202.169336)
			(xy 452.759344 -202.183631) (xy 452.767162 -202.202321) (xy 452.7677 -202.212448) (xy 452.7677 -202.621388)
			(xy 458.808836 -202.621388) (xy 458.808836 -202.212448) (xy 458.809262 -202.202293) (xy 458.817048 -202.183534)
			(xy 458.831445 -202.169208) (xy 458.850241 -202.161513) (xy 458.860398 -202.16114) (xy 460.259938 -202.16114)
			(xy 460.270067 -202.161595) (xy 460.288789 -202.169336) (xy 460.303144 -202.183631) (xy 460.310962 -202.202321)
			(xy 460.3115 -202.212448) (xy 460.3115 -202.621388) (xy 460.311069 -202.631541) (xy 460.303277 -202.650293)
			(xy 460.288883 -202.664617) (xy 460.270093 -202.672317) (xy 460.259938 -202.672696) (xy 458.860398 -202.672696)
			(xy 458.850276 -202.672176) (xy 458.831561 -202.664454) (xy 458.817206 -202.650179) (xy 458.809381 -202.631508)
			(xy 458.808836 -202.621388) (xy 452.7677 -202.621388) (xy 452.767269 -202.631541) (xy 452.759477 -202.650293)
			(xy 452.745083 -202.664617) (xy 452.726293 -202.672317) (xy 452.716138 -202.672696) (xy 451.316598 -202.672696)
			(xy 451.306476 -202.672176) (xy 451.287761 -202.664454) (xy 451.273406 -202.650179) (xy 451.265581 -202.631508)
			(xy 451.265036 -202.621388) (xy 445.2239 -202.621388) (xy 445.223469 -202.631541) (xy 445.215677 -202.650293)
			(xy 445.201283 -202.664617) (xy 445.182493 -202.672317) (xy 445.172338 -202.672696) (xy 443.772798 -202.672696)
			(xy 443.762676 -202.672176) (xy 443.743961 -202.664454) (xy 443.729606 -202.650179) (xy 443.721781 -202.631508)
			(xy 443.721236 -202.621388) (xy 437.6801 -202.621388) (xy 437.679669 -202.631541) (xy 437.671877 -202.650293)
			(xy 437.657483 -202.664617) (xy 437.638693 -202.672317) (xy 437.628538 -202.672696) (xy 436.228998 -202.672696)
			(xy 436.218876 -202.672176) (xy 436.200161 -202.664454) (xy 436.185806 -202.650179) (xy 436.177981 -202.631508)
			(xy 436.177436 -202.621388) (xy 430.1363 -202.621388) (xy 430.135869 -202.631541) (xy 430.128077 -202.650293)
			(xy 430.113683 -202.664617) (xy 430.094893 -202.672317) (xy 430.084738 -202.672696) (xy 428.685198 -202.672696)
			(xy 428.675076 -202.672176) (xy 428.656361 -202.664454) (xy 428.642006 -202.650179) (xy 428.634181 -202.631508)
			(xy 428.633636 -202.621388) (xy 422.5925 -202.621388) (xy 422.592069 -202.631541) (xy 422.584277 -202.650293)
			(xy 422.569883 -202.664617) (xy 422.551093 -202.672317) (xy 422.540938 -202.672696) (xy 421.141398 -202.672696)
			(xy 421.131276 -202.672176) (xy 421.112561 -202.664454) (xy 421.098206 -202.650179) (xy 421.090381 -202.631508)
			(xy 421.089836 -202.621388) (xy 415.0487 -202.621388) (xy 415.048269 -202.631541) (xy 415.040477 -202.650293)
			(xy 415.026083 -202.664617) (xy 415.007293 -202.672317) (xy 414.997138 -202.672696) (xy 413.597598 -202.672696)
			(xy 413.587476 -202.672176) (xy 413.568761 -202.664454) (xy 413.554406 -202.650179) (xy 413.546581 -202.631508)
			(xy 413.546036 -202.621388) (xy 407.5049 -202.621388) (xy 407.504469 -202.631541) (xy 407.496677 -202.650293)
			(xy 407.482283 -202.664617) (xy 407.463493 -202.672317) (xy 407.453338 -202.672696) (xy 406.053798 -202.672696)
			(xy 406.043676 -202.672176) (xy 406.024961 -202.664454) (xy 406.010606 -202.650179) (xy 406.002781 -202.631508)
			(xy 406.002236 -202.621388) (xy 309.6387 -202.621388) (xy 309.638269 -202.631541) (xy 309.630477 -202.650293)
			(xy 309.616083 -202.664617) (xy 309.597293 -202.672317) (xy 309.587138 -202.672696) (xy 308.187598 -202.672696)
			(xy 308.177476 -202.672176) (xy 308.158761 -202.664454) (xy 308.144406 -202.650179) (xy 308.136581 -202.631508)
			(xy 308.136036 -202.621388) (xy 302.0949 -202.621388) (xy 302.094469 -202.631541) (xy 302.086677 -202.650293)
			(xy 302.072283 -202.664617) (xy 302.053493 -202.672317) (xy 302.043338 -202.672696) (xy 300.643798 -202.672696)
			(xy 300.633676 -202.672176) (xy 300.614961 -202.664454) (xy 300.600606 -202.650179) (xy 300.592781 -202.631508)
			(xy 300.592236 -202.621388) (xy 294.5511 -202.621388) (xy 294.550669 -202.631541) (xy 294.542877 -202.650293)
			(xy 294.528483 -202.664617) (xy 294.509693 -202.672317) (xy 294.499538 -202.672696) (xy 293.099998 -202.672696)
			(xy 293.089876 -202.672176) (xy 293.071161 -202.664454) (xy 293.056806 -202.650179) (xy 293.048981 -202.631508)
			(xy 293.048436 -202.621388) (xy 287.0073 -202.621388) (xy 287.006869 -202.631541) (xy 286.999077 -202.650293)
			(xy 286.984683 -202.664617) (xy 286.965893 -202.672317) (xy 286.955738 -202.672696) (xy 285.556198 -202.672696)
			(xy 285.546076 -202.672176) (xy 285.527361 -202.664454) (xy 285.513006 -202.650179) (xy 285.505181 -202.631508)
			(xy 285.504636 -202.621388) (xy 279.4635 -202.621388) (xy 279.463069 -202.631541) (xy 279.455277 -202.650293)
			(xy 279.440883 -202.664617) (xy 279.422093 -202.672317) (xy 279.411938 -202.672696) (xy 278.012398 -202.672696)
			(xy 278.002276 -202.672176) (xy 277.983561 -202.664454) (xy 277.969206 -202.650179) (xy 277.961381 -202.631508)
			(xy 277.960836 -202.621388) (xy 271.9197 -202.621388) (xy 271.919269 -202.631541) (xy 271.911477 -202.650293)
			(xy 271.897083 -202.664617) (xy 271.878293 -202.672317) (xy 271.868138 -202.672696) (xy 270.468598 -202.672696)
			(xy 270.458476 -202.672176) (xy 270.439761 -202.664454) (xy 270.425406 -202.650179) (xy 270.417581 -202.631508)
			(xy 270.417036 -202.621388) (xy 264.3759 -202.621388) (xy 264.375469 -202.631541) (xy 264.367677 -202.650293)
			(xy 264.353283 -202.664617) (xy 264.334493 -202.672317) (xy 264.324338 -202.672696) (xy 262.924798 -202.672696)
			(xy 262.914676 -202.672176) (xy 262.895961 -202.664454) (xy 262.881606 -202.650179) (xy 262.873781 -202.631508)
			(xy 262.873236 -202.621388) (xy 256.8321 -202.621388) (xy 256.831669 -202.631541) (xy 256.823877 -202.650293)
			(xy 256.809483 -202.664617) (xy 256.790693 -202.672317) (xy 256.780538 -202.672696) (xy 255.380998 -202.672696)
			(xy 255.370876 -202.672176) (xy 255.352161 -202.664454) (xy 255.337806 -202.650179) (xy 255.329981 -202.631508)
			(xy 255.329436 -202.621388) (xy 212.371432 -202.621388) (xy 212.370969 -202.631537) (xy 212.363184 -202.650283)
			(xy 212.3488 -202.664606) (xy 212.330021 -202.672312) (xy 212.31987 -202.672696) (xy 210.92033 -202.672696)
			(xy 210.91021 -202.67215) (xy 210.891496 -202.664439) (xy 210.87714 -202.650171) (xy 210.869313 -202.631505)
			(xy 210.868768 -202.621388) (xy 204.827632 -202.621388) (xy 204.827169 -202.631537) (xy 204.819384 -202.650283)
			(xy 204.805 -202.664606) (xy 204.786221 -202.672312) (xy 204.77607 -202.672696) (xy 203.37653 -202.672696)
			(xy 203.36641 -202.67215) (xy 203.347696 -202.664439) (xy 203.33334 -202.650171) (xy 203.325513 -202.631505)
			(xy 203.324968 -202.621388) (xy 197.283832 -202.621388) (xy 197.283369 -202.631537) (xy 197.275584 -202.650283)
			(xy 197.2612 -202.664606) (xy 197.242421 -202.672312) (xy 197.23227 -202.672696) (xy 195.83273 -202.672696)
			(xy 195.82261 -202.67215) (xy 195.803896 -202.664439) (xy 195.78954 -202.650171) (xy 195.781713 -202.631505)
			(xy 195.781168 -202.621388) (xy 189.740032 -202.621388) (xy 189.739569 -202.631537) (xy 189.731784 -202.650283)
			(xy 189.7174 -202.664606) (xy 189.698621 -202.672312) (xy 189.68847 -202.672696) (xy 188.28893 -202.672696)
			(xy 188.27881 -202.67215) (xy 188.260096 -202.664439) (xy 188.24574 -202.650171) (xy 188.237913 -202.631505)
			(xy 188.237368 -202.621388) (xy 182.196232 -202.621388) (xy 182.195769 -202.631537) (xy 182.187984 -202.650283)
			(xy 182.1736 -202.664606) (xy 182.154821 -202.672312) (xy 182.14467 -202.672696) (xy 180.74513 -202.672696)
			(xy 180.73501 -202.67215) (xy 180.716296 -202.664439) (xy 180.70194 -202.650171) (xy 180.694113 -202.631505)
			(xy 180.693568 -202.621388) (xy 174.652432 -202.621388) (xy 174.651969 -202.631537) (xy 174.644184 -202.650283)
			(xy 174.6298 -202.664606) (xy 174.611021 -202.672312) (xy 174.60087 -202.672696) (xy 173.20133 -202.672696)
			(xy 173.19121 -202.67215) (xy 173.172496 -202.664439) (xy 173.15814 -202.650171) (xy 173.150313 -202.631505)
			(xy 173.149768 -202.621388) (xy 167.108632 -202.621388) (xy 167.108169 -202.631537) (xy 167.100384 -202.650283)
			(xy 167.086 -202.664606) (xy 167.067221 -202.672312) (xy 167.05707 -202.672696) (xy 165.65753 -202.672696)
			(xy 165.64741 -202.67215) (xy 165.628696 -202.664439) (xy 165.61434 -202.650171) (xy 165.606513 -202.631505)
			(xy 165.605968 -202.621388) (xy 159.564832 -202.621388) (xy 159.564369 -202.631537) (xy 159.556584 -202.650283)
			(xy 159.5422 -202.664606) (xy 159.523421 -202.672312) (xy 159.51327 -202.672696) (xy 158.11373 -202.672696)
			(xy 158.10361 -202.67215) (xy 158.084896 -202.664439) (xy 158.07054 -202.650171) (xy 158.062713 -202.631505)
			(xy 158.062168 -202.621388) (xy 61.698632 -202.621388) (xy 61.698169 -202.631537) (xy 61.690384 -202.650283)
			(xy 61.676 -202.664606) (xy 61.657221 -202.672312) (xy 61.64707 -202.672696) (xy 60.24753 -202.672696)
			(xy 60.23741 -202.67215) (xy 60.218696 -202.664439) (xy 60.20434 -202.650171) (xy 60.196513 -202.631505)
			(xy 60.195968 -202.621388) (xy 54.154832 -202.621388) (xy 54.154369 -202.631537) (xy 54.146584 -202.650283)
			(xy 54.1322 -202.664606) (xy 54.113421 -202.672312) (xy 54.10327 -202.672696) (xy 52.70373 -202.672696)
			(xy 52.69361 -202.67215) (xy 52.674896 -202.664439) (xy 52.66054 -202.650171) (xy 52.652713 -202.631505)
			(xy 52.652168 -202.621388) (xy 46.611032 -202.621388) (xy 46.610569 -202.631537) (xy 46.602784 -202.650283)
			(xy 46.5884 -202.664606) (xy 46.569621 -202.672312) (xy 46.55947 -202.672696) (xy 45.15993 -202.672696)
			(xy 45.14981 -202.67215) (xy 45.131096 -202.664439) (xy 45.11674 -202.650171) (xy 45.108913 -202.631505)
			(xy 45.108368 -202.621388) (xy 39.067232 -202.621388) (xy 39.066769 -202.631537) (xy 39.058984 -202.650283)
			(xy 39.0446 -202.664606) (xy 39.025821 -202.672312) (xy 39.01567 -202.672696) (xy 37.61613 -202.672696)
			(xy 37.60601 -202.67215) (xy 37.587296 -202.664439) (xy 37.57294 -202.650171) (xy 37.565113 -202.631505)
			(xy 37.564568 -202.621388) (xy 31.523432 -202.621388) (xy 31.522969 -202.631537) (xy 31.515184 -202.650283)
			(xy 31.5008 -202.664606) (xy 31.482021 -202.672312) (xy 31.47187 -202.672696) (xy 30.07233 -202.672696)
			(xy 30.06221 -202.67215) (xy 30.043496 -202.664439) (xy 30.02914 -202.650171) (xy 30.021313 -202.631505)
			(xy 30.020768 -202.621388) (xy 23.979632 -202.621388) (xy 23.979169 -202.631537) (xy 23.971384 -202.650283)
			(xy 23.957 -202.664606) (xy 23.938221 -202.672312) (xy 23.92807 -202.672696) (xy 22.52853 -202.672696)
			(xy 22.51841 -202.67215) (xy 22.499696 -202.664439) (xy 22.48534 -202.650171) (xy 22.477513 -202.631505)
			(xy 22.476968 -202.621388) (xy 16.435832 -202.621388) (xy 16.435369 -202.631537) (xy 16.427584 -202.650283)
			(xy 16.4132 -202.664606) (xy 16.394421 -202.672312) (xy 16.38427 -202.672696) (xy 14.98473 -202.672696)
			(xy 14.97461 -202.67215) (xy 14.955896 -202.664439) (xy 14.94154 -202.650171) (xy 14.933713 -202.631505)
			(xy 14.933168 -202.621388) (xy 8.892032 -202.621388) (xy 8.891569 -202.631537) (xy 8.883784 -202.650283)
			(xy 8.8694 -202.664606) (xy 8.850621 -202.672312) (xy 8.84047 -202.672696) (xy 7.44093 -202.672696)
			(xy 7.43081 -202.67215) (xy 7.412096 -202.664439) (xy 7.39774 -202.650171) (xy 7.389913 -202.631505)
			(xy 7.389368 -202.621388) (xy 2.509012 -202.621388) (xy 2.509012 -203.471526) (xy 11.489436 -203.471526)
			(xy 11.489436 -203.062586) (xy 11.489922 -203.052428) (xy 11.497701 -203.033659) (xy 11.512069 -203.019294)
			(xy 11.53084 -203.01152) (xy 11.540998 -203.011024) (xy 12.940538 -203.011024) (xy 12.950696 -203.011502)
			(xy 12.969464 -203.019286) (xy 12.983827 -203.033656) (xy 12.991603 -203.052427) (xy 12.9921 -203.062586)
			(xy 12.9921 -203.471526) (xy 19.033236 -203.471526) (xy 19.033236 -203.062586) (xy 19.033722 -203.052428)
			(xy 19.041501 -203.033659) (xy 19.055869 -203.019294) (xy 19.07464 -203.01152) (xy 19.084798 -203.011024)
			(xy 20.484338 -203.011024) (xy 20.494496 -203.011502) (xy 20.513264 -203.019286) (xy 20.527627 -203.033656)
			(xy 20.535403 -203.052427) (xy 20.5359 -203.062586) (xy 20.5359 -203.471526) (xy 26.577036 -203.471526)
			(xy 26.577036 -203.062586) (xy 26.577522 -203.052428) (xy 26.585301 -203.033659) (xy 26.599669 -203.019294)
			(xy 26.61844 -203.01152) (xy 26.628598 -203.011024) (xy 28.028138 -203.011024) (xy 28.038296 -203.011502)
			(xy 28.057064 -203.019286) (xy 28.071427 -203.033656) (xy 28.079203 -203.052427) (xy 28.0797 -203.062586)
			(xy 28.0797 -203.471526) (xy 34.120836 -203.471526) (xy 34.120836 -203.062586) (xy 34.121322 -203.052428)
			(xy 34.129101 -203.033659) (xy 34.143469 -203.019294) (xy 34.16224 -203.01152) (xy 34.172398 -203.011024)
			(xy 35.571938 -203.011024) (xy 35.582096 -203.011502) (xy 35.600864 -203.019286) (xy 35.615227 -203.033656)
			(xy 35.623003 -203.052427) (xy 35.6235 -203.062586) (xy 35.6235 -203.471526) (xy 41.664636 -203.471526)
			(xy 41.664636 -203.062586) (xy 41.665122 -203.052428) (xy 41.672901 -203.033659) (xy 41.687269 -203.019294)
			(xy 41.70604 -203.01152) (xy 41.716198 -203.011024) (xy 43.115738 -203.011024) (xy 43.125896 -203.011502)
			(xy 43.144664 -203.019286) (xy 43.159027 -203.033656) (xy 43.166803 -203.052427) (xy 43.1673 -203.062586)
			(xy 43.1673 -203.471526) (xy 49.208436 -203.471526) (xy 49.208436 -203.062586) (xy 49.208922 -203.052428)
			(xy 49.216701 -203.033659) (xy 49.231069 -203.019294) (xy 49.24984 -203.01152) (xy 49.259998 -203.011024)
			(xy 50.659538 -203.011024) (xy 50.669696 -203.011502) (xy 50.688464 -203.019286) (xy 50.702827 -203.033656)
			(xy 50.710603 -203.052427) (xy 50.7111 -203.062586) (xy 50.7111 -203.471526) (xy 56.752236 -203.471526)
			(xy 56.752236 -203.062586) (xy 56.752722 -203.052428) (xy 56.760501 -203.033659) (xy 56.774869 -203.019294)
			(xy 56.79364 -203.01152) (xy 56.803798 -203.011024) (xy 58.203338 -203.011024) (xy 58.213496 -203.011502)
			(xy 58.232264 -203.019286) (xy 58.246627 -203.033656) (xy 58.254403 -203.052427) (xy 58.2549 -203.062586)
			(xy 58.2549 -203.471526) (xy 64.296036 -203.471526) (xy 64.296036 -203.062586) (xy 64.296522 -203.052428)
			(xy 64.304301 -203.033659) (xy 64.318669 -203.019294) (xy 64.33744 -203.01152) (xy 64.347598 -203.011024)
			(xy 65.747138 -203.011024) (xy 65.757296 -203.011502) (xy 65.776064 -203.019286) (xy 65.790427 -203.033656)
			(xy 65.798203 -203.052427) (xy 65.7987 -203.062586) (xy 65.7987 -203.471526) (xy 162.162236 -203.471526)
			(xy 162.162236 -203.062586) (xy 162.162722 -203.052428) (xy 162.170501 -203.033659) (xy 162.184869 -203.019294)
			(xy 162.20364 -203.01152) (xy 162.213798 -203.011024) (xy 163.613338 -203.011024) (xy 163.623496 -203.011502)
			(xy 163.642264 -203.019286) (xy 163.656627 -203.033656) (xy 163.664403 -203.052427) (xy 163.6649 -203.062586)
			(xy 163.6649 -203.471526) (xy 169.706036 -203.471526) (xy 169.706036 -203.062586) (xy 169.706522 -203.052428)
			(xy 169.714301 -203.033659) (xy 169.728669 -203.019294) (xy 169.74744 -203.01152) (xy 169.757598 -203.011024)
			(xy 171.157138 -203.011024) (xy 171.167296 -203.011502) (xy 171.186064 -203.019286) (xy 171.200427 -203.033656)
			(xy 171.208203 -203.052427) (xy 171.2087 -203.062586) (xy 171.2087 -203.471526) (xy 177.249836 -203.471526)
			(xy 177.249836 -203.062586) (xy 177.250322 -203.052428) (xy 177.258101 -203.033659) (xy 177.272469 -203.019294)
			(xy 177.29124 -203.01152) (xy 177.301398 -203.011024) (xy 178.700938 -203.011024) (xy 178.711096 -203.011502)
			(xy 178.729864 -203.019286) (xy 178.744227 -203.033656) (xy 178.752003 -203.052427) (xy 178.7525 -203.062586)
			(xy 178.7525 -203.471526) (xy 184.793636 -203.471526) (xy 184.793636 -203.062586) (xy 184.794122 -203.052428)
			(xy 184.801901 -203.033659) (xy 184.816269 -203.019294) (xy 184.83504 -203.01152) (xy 184.845198 -203.011024)
			(xy 186.244738 -203.011024) (xy 186.254896 -203.011502) (xy 186.273664 -203.019286) (xy 186.288027 -203.033656)
			(xy 186.295803 -203.052427) (xy 186.2963 -203.062586) (xy 186.2963 -203.471526) (xy 192.337436 -203.471526)
			(xy 192.337436 -203.062586) (xy 192.337922 -203.052428) (xy 192.345701 -203.033659) (xy 192.360069 -203.019294)
			(xy 192.37884 -203.01152) (xy 192.388998 -203.011024) (xy 193.788538 -203.011024) (xy 193.798696 -203.011502)
			(xy 193.817464 -203.019286) (xy 193.831827 -203.033656) (xy 193.839603 -203.052427) (xy 193.8401 -203.062586)
			(xy 193.8401 -203.471526) (xy 199.881236 -203.471526) (xy 199.881236 -203.062586) (xy 199.881722 -203.052428)
			(xy 199.889501 -203.033659) (xy 199.903869 -203.019294) (xy 199.92264 -203.01152) (xy 199.932798 -203.011024)
			(xy 201.332338 -203.011024) (xy 201.342496 -203.011502) (xy 201.361264 -203.019286) (xy 201.375627 -203.033656)
			(xy 201.383403 -203.052427) (xy 201.3839 -203.062586) (xy 201.3839 -203.471526) (xy 207.425036 -203.471526)
			(xy 207.425036 -203.062586) (xy 207.425522 -203.052428) (xy 207.433301 -203.033659) (xy 207.447669 -203.019294)
			(xy 207.46644 -203.01152) (xy 207.476598 -203.011024) (xy 208.876138 -203.011024) (xy 208.886296 -203.011502)
			(xy 208.905064 -203.019286) (xy 208.919427 -203.033656) (xy 208.927203 -203.052427) (xy 208.9277 -203.062586)
			(xy 208.9277 -203.471526) (xy 214.968836 -203.471526) (xy 214.968836 -203.062586) (xy 214.969322 -203.052428)
			(xy 214.977101 -203.033659) (xy 214.991469 -203.019294) (xy 215.01024 -203.01152) (xy 215.020398 -203.011024)
			(xy 216.419938 -203.011024) (xy 216.430096 -203.011502) (xy 216.448864 -203.019286) (xy 216.463227 -203.033656)
			(xy 216.471003 -203.052427) (xy 216.4715 -203.062586) (xy 216.4715 -203.471526) (xy 259.429504 -203.471526)
			(xy 259.429504 -203.062586) (xy 259.430021 -203.052432) (xy 259.437794 -203.033669) (xy 259.452152 -203.019305)
			(xy 259.470912 -203.011525) (xy 259.481066 -203.011024) (xy 260.880606 -203.011024) (xy 260.890762 -203.011528)
			(xy 260.909529 -203.019302) (xy 260.923893 -203.033664) (xy 260.93167 -203.05243) (xy 260.932168 -203.062586)
			(xy 260.932168 -203.471526) (xy 266.973304 -203.471526) (xy 266.973304 -203.062586) (xy 266.973821 -203.052432)
			(xy 266.981594 -203.033669) (xy 266.995952 -203.019305) (xy 267.014712 -203.011525) (xy 267.024866 -203.011024)
			(xy 268.424406 -203.011024) (xy 268.434562 -203.011528) (xy 268.453329 -203.019302) (xy 268.467693 -203.033664)
			(xy 268.47547 -203.05243) (xy 268.475968 -203.062586) (xy 268.475968 -203.471526) (xy 274.517104 -203.471526)
			(xy 274.517104 -203.062586) (xy 274.517621 -203.052432) (xy 274.525394 -203.033669) (xy 274.539752 -203.019305)
			(xy 274.558512 -203.011525) (xy 274.568666 -203.011024) (xy 275.968206 -203.011024) (xy 275.978362 -203.011528)
			(xy 275.997129 -203.019302) (xy 276.011493 -203.033664) (xy 276.01927 -203.05243) (xy 276.019768 -203.062586)
			(xy 276.019768 -203.471526) (xy 282.060904 -203.471526) (xy 282.060904 -203.062586) (xy 282.061421 -203.052432)
			(xy 282.069194 -203.033669) (xy 282.083552 -203.019305) (xy 282.102312 -203.011525) (xy 282.112466 -203.011024)
			(xy 283.512006 -203.011024) (xy 283.522162 -203.011528) (xy 283.540929 -203.019302) (xy 283.555293 -203.033664)
			(xy 283.56307 -203.05243) (xy 283.563568 -203.062586) (xy 283.563568 -203.471526) (xy 289.604704 -203.471526)
			(xy 289.604704 -203.062586) (xy 289.605221 -203.052432) (xy 289.612994 -203.033669) (xy 289.627352 -203.019305)
			(xy 289.646112 -203.011525) (xy 289.656266 -203.011024) (xy 291.055806 -203.011024) (xy 291.065962 -203.011528)
			(xy 291.084729 -203.019302) (xy 291.099093 -203.033664) (xy 291.10687 -203.05243) (xy 291.107368 -203.062586)
			(xy 291.107368 -203.471526) (xy 297.148504 -203.471526) (xy 297.148504 -203.062586) (xy 297.149021 -203.052432)
			(xy 297.156794 -203.033669) (xy 297.171152 -203.019305) (xy 297.189912 -203.011525) (xy 297.200066 -203.011024)
			(xy 298.599606 -203.011024) (xy 298.609762 -203.011528) (xy 298.628529 -203.019302) (xy 298.642893 -203.033664)
			(xy 298.65067 -203.05243) (xy 298.651168 -203.062586) (xy 298.651168 -203.471526) (xy 304.692304 -203.471526)
			(xy 304.692304 -203.062586) (xy 304.692821 -203.052432) (xy 304.700594 -203.033669) (xy 304.714952 -203.019305)
			(xy 304.733712 -203.011525) (xy 304.743866 -203.011024) (xy 306.143406 -203.011024) (xy 306.153562 -203.011528)
			(xy 306.172329 -203.019302) (xy 306.186693 -203.033664) (xy 306.19447 -203.05243) (xy 306.194968 -203.062586)
			(xy 306.194968 -203.471526) (xy 312.236104 -203.471526) (xy 312.236104 -203.062586) (xy 312.236621 -203.052432)
			(xy 312.244394 -203.033669) (xy 312.258752 -203.019305) (xy 312.277512 -203.011525) (xy 312.287666 -203.011024)
			(xy 313.687206 -203.011024) (xy 313.697362 -203.011528) (xy 313.716129 -203.019302) (xy 313.730493 -203.033664)
			(xy 313.73827 -203.05243) (xy 313.738768 -203.062586) (xy 313.738768 -203.471526) (xy 410.102304 -203.471526)
			(xy 410.102304 -203.062586) (xy 410.102821 -203.052432) (xy 410.110594 -203.033669) (xy 410.124952 -203.019305)
			(xy 410.143712 -203.011525) (xy 410.153866 -203.011024) (xy 411.553406 -203.011024) (xy 411.563562 -203.011528)
			(xy 411.582329 -203.019302) (xy 411.596693 -203.033664) (xy 411.60447 -203.05243) (xy 411.604968 -203.062586)
			(xy 411.604968 -203.471526) (xy 417.646104 -203.471526) (xy 417.646104 -203.062586) (xy 417.646621 -203.052432)
			(xy 417.654394 -203.033669) (xy 417.668752 -203.019305) (xy 417.687512 -203.011525) (xy 417.697666 -203.011024)
			(xy 419.097206 -203.011024) (xy 419.107362 -203.011528) (xy 419.126129 -203.019302) (xy 419.140493 -203.033664)
			(xy 419.14827 -203.05243) (xy 419.148768 -203.062586) (xy 419.148768 -203.471526) (xy 425.189904 -203.471526)
			(xy 425.189904 -203.062586) (xy 425.190421 -203.052432) (xy 425.198194 -203.033669) (xy 425.212552 -203.019305)
			(xy 425.231312 -203.011525) (xy 425.241466 -203.011024) (xy 426.641006 -203.011024) (xy 426.651162 -203.011528)
			(xy 426.669929 -203.019302) (xy 426.684293 -203.033664) (xy 426.69207 -203.05243) (xy 426.692568 -203.062586)
			(xy 426.692568 -203.471526) (xy 432.733704 -203.471526) (xy 432.733704 -203.062586) (xy 432.734221 -203.052432)
			(xy 432.741994 -203.033669) (xy 432.756352 -203.019305) (xy 432.775112 -203.011525) (xy 432.785266 -203.011024)
			(xy 434.184806 -203.011024) (xy 434.194962 -203.011528) (xy 434.213729 -203.019302) (xy 434.228093 -203.033664)
			(xy 434.23587 -203.05243) (xy 434.236368 -203.062586) (xy 434.236368 -203.471526) (xy 440.277504 -203.471526)
			(xy 440.277504 -203.062586) (xy 440.278021 -203.052432) (xy 440.285794 -203.033669) (xy 440.300152 -203.019305)
			(xy 440.318912 -203.011525) (xy 440.329066 -203.011024) (xy 441.728606 -203.011024) (xy 441.738762 -203.011528)
			(xy 441.757529 -203.019302) (xy 441.771893 -203.033664) (xy 441.77967 -203.05243) (xy 441.780168 -203.062586)
			(xy 441.780168 -203.471526) (xy 447.821304 -203.471526) (xy 447.821304 -203.062586) (xy 447.821821 -203.052432)
			(xy 447.829594 -203.033669) (xy 447.843952 -203.019305) (xy 447.862712 -203.011525) (xy 447.872866 -203.011024)
			(xy 449.272406 -203.011024) (xy 449.282562 -203.011528) (xy 449.301329 -203.019302) (xy 449.315693 -203.033664)
			(xy 449.32347 -203.05243) (xy 449.323968 -203.062586) (xy 449.323968 -203.471526) (xy 455.365104 -203.471526)
			(xy 455.365104 -203.062586) (xy 455.365621 -203.052432) (xy 455.373394 -203.033669) (xy 455.387752 -203.019305)
			(xy 455.406512 -203.011525) (xy 455.416666 -203.011024) (xy 456.816206 -203.011024) (xy 456.826362 -203.011528)
			(xy 456.845129 -203.019302) (xy 456.859493 -203.033664) (xy 456.86727 -203.05243) (xy 456.867768 -203.062586)
			(xy 456.867768 -203.471526) (xy 462.908904 -203.471526) (xy 462.908904 -203.062586) (xy 462.909421 -203.052432)
			(xy 462.917194 -203.033669) (xy 462.931552 -203.019305) (xy 462.950312 -203.011525) (xy 462.960466 -203.011024)
			(xy 464.360006 -203.011024) (xy 464.370162 -203.011528) (xy 464.388929 -203.019302) (xy 464.403293 -203.033664)
			(xy 464.41107 -203.05243) (xy 464.411568 -203.062586) (xy 464.411568 -203.471526) (xy 464.411088 -203.481685)
			(xy 464.403306 -203.500453) (xy 464.388937 -203.514818) (xy 464.370165 -203.522592) (xy 464.360006 -203.523088)
			(xy 462.960466 -203.523088) (xy 462.950309 -203.522595) (xy 462.931544 -203.514814) (xy 462.917181 -203.500449)
			(xy 462.909403 -203.481683) (xy 462.908904 -203.471526) (xy 456.867768 -203.471526) (xy 456.867288 -203.481685)
			(xy 456.859506 -203.500453) (xy 456.845137 -203.514818) (xy 456.826365 -203.522592) (xy 456.816206 -203.523088)
			(xy 455.416666 -203.523088) (xy 455.406509 -203.522595) (xy 455.387744 -203.514814) (xy 455.373381 -203.500449)
			(xy 455.365603 -203.481683) (xy 455.365104 -203.471526) (xy 449.323968 -203.471526) (xy 449.323488 -203.481685)
			(xy 449.315706 -203.500453) (xy 449.301337 -203.514818) (xy 449.282565 -203.522592) (xy 449.272406 -203.523088)
			(xy 447.872866 -203.523088) (xy 447.862709 -203.522595) (xy 447.843944 -203.514814) (xy 447.829581 -203.500449)
			(xy 447.821803 -203.481683) (xy 447.821304 -203.471526) (xy 441.780168 -203.471526) (xy 441.779688 -203.481685)
			(xy 441.771906 -203.500453) (xy 441.757537 -203.514818) (xy 441.738765 -203.522592) (xy 441.728606 -203.523088)
			(xy 440.329066 -203.523088) (xy 440.318909 -203.522595) (xy 440.300144 -203.514814) (xy 440.285781 -203.500449)
			(xy 440.278003 -203.481683) (xy 440.277504 -203.471526) (xy 434.236368 -203.471526) (xy 434.235888 -203.481685)
			(xy 434.228106 -203.500453) (xy 434.213737 -203.514818) (xy 434.194965 -203.522592) (xy 434.184806 -203.523088)
			(xy 432.785266 -203.523088) (xy 432.775109 -203.522595) (xy 432.756344 -203.514814) (xy 432.741981 -203.500449)
			(xy 432.734203 -203.481683) (xy 432.733704 -203.471526) (xy 426.692568 -203.471526) (xy 426.692088 -203.481685)
			(xy 426.684306 -203.500453) (xy 426.669937 -203.514818) (xy 426.651165 -203.522592) (xy 426.641006 -203.523088)
			(xy 425.241466 -203.523088) (xy 425.231309 -203.522595) (xy 425.212544 -203.514814) (xy 425.198181 -203.500449)
			(xy 425.190403 -203.481683) (xy 425.189904 -203.471526) (xy 419.148768 -203.471526) (xy 419.148288 -203.481685)
			(xy 419.140506 -203.500453) (xy 419.126137 -203.514818) (xy 419.107365 -203.522592) (xy 419.097206 -203.523088)
			(xy 417.697666 -203.523088) (xy 417.687509 -203.522595) (xy 417.668744 -203.514814) (xy 417.654381 -203.500449)
			(xy 417.646603 -203.481683) (xy 417.646104 -203.471526) (xy 411.604968 -203.471526) (xy 411.604488 -203.481685)
			(xy 411.596706 -203.500453) (xy 411.582337 -203.514818) (xy 411.563565 -203.522592) (xy 411.553406 -203.523088)
			(xy 410.153866 -203.523088) (xy 410.143709 -203.522595) (xy 410.124944 -203.514814) (xy 410.110581 -203.500449)
			(xy 410.102803 -203.481683) (xy 410.102304 -203.471526) (xy 313.738768 -203.471526) (xy 313.738288 -203.481685)
			(xy 313.730506 -203.500453) (xy 313.716137 -203.514818) (xy 313.697365 -203.522592) (xy 313.687206 -203.523088)
			(xy 312.287666 -203.523088) (xy 312.277509 -203.522595) (xy 312.258744 -203.514814) (xy 312.244381 -203.500449)
			(xy 312.236603 -203.481683) (xy 312.236104 -203.471526) (xy 306.194968 -203.471526) (xy 306.194488 -203.481685)
			(xy 306.186706 -203.500453) (xy 306.172337 -203.514818) (xy 306.153565 -203.522592) (xy 306.143406 -203.523088)
			(xy 304.743866 -203.523088) (xy 304.733709 -203.522595) (xy 304.714944 -203.514814) (xy 304.700581 -203.500449)
			(xy 304.692803 -203.481683) (xy 304.692304 -203.471526) (xy 298.651168 -203.471526) (xy 298.650688 -203.481685)
			(xy 298.642906 -203.500453) (xy 298.628537 -203.514818) (xy 298.609765 -203.522592) (xy 298.599606 -203.523088)
			(xy 297.200066 -203.523088) (xy 297.189909 -203.522595) (xy 297.171144 -203.514814) (xy 297.156781 -203.500449)
			(xy 297.149003 -203.481683) (xy 297.148504 -203.471526) (xy 291.107368 -203.471526) (xy 291.106888 -203.481685)
			(xy 291.099106 -203.500453) (xy 291.084737 -203.514818) (xy 291.065965 -203.522592) (xy 291.055806 -203.523088)
			(xy 289.656266 -203.523088) (xy 289.646109 -203.522595) (xy 289.627344 -203.514814) (xy 289.612981 -203.500449)
			(xy 289.605203 -203.481683) (xy 289.604704 -203.471526) (xy 283.563568 -203.471526) (xy 283.563088 -203.481685)
			(xy 283.555306 -203.500453) (xy 283.540937 -203.514818) (xy 283.522165 -203.522592) (xy 283.512006 -203.523088)
			(xy 282.112466 -203.523088) (xy 282.102309 -203.522595) (xy 282.083544 -203.514814) (xy 282.069181 -203.500449)
			(xy 282.061403 -203.481683) (xy 282.060904 -203.471526) (xy 276.019768 -203.471526) (xy 276.019288 -203.481685)
			(xy 276.011506 -203.500453) (xy 275.997137 -203.514818) (xy 275.978365 -203.522592) (xy 275.968206 -203.523088)
			(xy 274.568666 -203.523088) (xy 274.558509 -203.522595) (xy 274.539744 -203.514814) (xy 274.525381 -203.500449)
			(xy 274.517603 -203.481683) (xy 274.517104 -203.471526) (xy 268.475968 -203.471526) (xy 268.475488 -203.481685)
			(xy 268.467706 -203.500453) (xy 268.453337 -203.514818) (xy 268.434565 -203.522592) (xy 268.424406 -203.523088)
			(xy 267.024866 -203.523088) (xy 267.014709 -203.522595) (xy 266.995944 -203.514814) (xy 266.981581 -203.500449)
			(xy 266.973803 -203.481683) (xy 266.973304 -203.471526) (xy 260.932168 -203.471526) (xy 260.931688 -203.481685)
			(xy 260.923906 -203.500453) (xy 260.909537 -203.514818) (xy 260.890765 -203.522592) (xy 260.880606 -203.523088)
			(xy 259.481066 -203.523088) (xy 259.470909 -203.522595) (xy 259.452144 -203.514814) (xy 259.437781 -203.500449)
			(xy 259.430003 -203.481683) (xy 259.429504 -203.471526) (xy 216.4715 -203.471526) (xy 216.470989 -203.481681)
			(xy 216.463213 -203.500443) (xy 216.448853 -203.514806) (xy 216.430093 -203.522587) (xy 216.419938 -203.523088)
			(xy 215.020398 -203.523088) (xy 215.010243 -203.522569) (xy 214.991479 -203.514799) (xy 214.977115 -203.500441)
			(xy 214.969336 -203.48168) (xy 214.968836 -203.471526) (xy 208.9277 -203.471526) (xy 208.927189 -203.481681)
			(xy 208.919413 -203.500443) (xy 208.905053 -203.514806) (xy 208.886293 -203.522587) (xy 208.876138 -203.523088)
			(xy 207.476598 -203.523088) (xy 207.466443 -203.522569) (xy 207.447679 -203.514799) (xy 207.433315 -203.500441)
			(xy 207.425536 -203.48168) (xy 207.425036 -203.471526) (xy 201.3839 -203.471526) (xy 201.383389 -203.481681)
			(xy 201.375613 -203.500443) (xy 201.361253 -203.514806) (xy 201.342493 -203.522587) (xy 201.332338 -203.523088)
			(xy 199.932798 -203.523088) (xy 199.922643 -203.522569) (xy 199.903879 -203.514799) (xy 199.889515 -203.500441)
			(xy 199.881736 -203.48168) (xy 199.881236 -203.471526) (xy 193.8401 -203.471526) (xy 193.839589 -203.481681)
			(xy 193.831813 -203.500443) (xy 193.817453 -203.514806) (xy 193.798693 -203.522587) (xy 193.788538 -203.523088)
			(xy 192.388998 -203.523088) (xy 192.378843 -203.522569) (xy 192.360079 -203.514799) (xy 192.345715 -203.500441)
			(xy 192.337936 -203.48168) (xy 192.337436 -203.471526) (xy 186.2963 -203.471526) (xy 186.295789 -203.481681)
			(xy 186.288013 -203.500443) (xy 186.273653 -203.514806) (xy 186.254893 -203.522587) (xy 186.244738 -203.523088)
			(xy 184.845198 -203.523088) (xy 184.835043 -203.522569) (xy 184.816279 -203.514799) (xy 184.801915 -203.500441)
			(xy 184.794136 -203.48168) (xy 184.793636 -203.471526) (xy 178.7525 -203.471526) (xy 178.751989 -203.481681)
			(xy 178.744213 -203.500443) (xy 178.729853 -203.514806) (xy 178.711093 -203.522587) (xy 178.700938 -203.523088)
			(xy 177.301398 -203.523088) (xy 177.291243 -203.522569) (xy 177.272479 -203.514799) (xy 177.258115 -203.500441)
			(xy 177.250336 -203.48168) (xy 177.249836 -203.471526) (xy 171.2087 -203.471526) (xy 171.208189 -203.481681)
			(xy 171.200413 -203.500443) (xy 171.186053 -203.514806) (xy 171.167293 -203.522587) (xy 171.157138 -203.523088)
			(xy 169.757598 -203.523088) (xy 169.747443 -203.522569) (xy 169.728679 -203.514799) (xy 169.714315 -203.500441)
			(xy 169.706536 -203.48168) (xy 169.706036 -203.471526) (xy 163.6649 -203.471526) (xy 163.664389 -203.481681)
			(xy 163.656613 -203.500443) (xy 163.642253 -203.514806) (xy 163.623493 -203.522587) (xy 163.613338 -203.523088)
			(xy 162.213798 -203.523088) (xy 162.203643 -203.522569) (xy 162.184879 -203.514799) (xy 162.170515 -203.500441)
			(xy 162.162736 -203.48168) (xy 162.162236 -203.471526) (xy 65.7987 -203.471526) (xy 65.798189 -203.481681)
			(xy 65.790413 -203.500443) (xy 65.776053 -203.514806) (xy 65.757293 -203.522587) (xy 65.747138 -203.523088)
			(xy 64.347598 -203.523088) (xy 64.337443 -203.522569) (xy 64.318679 -203.514799) (xy 64.304315 -203.500441)
			(xy 64.296536 -203.48168) (xy 64.296036 -203.471526) (xy 58.2549 -203.471526) (xy 58.254389 -203.481681)
			(xy 58.246613 -203.500443) (xy 58.232253 -203.514806) (xy 58.213493 -203.522587) (xy 58.203338 -203.523088)
			(xy 56.803798 -203.523088) (xy 56.793643 -203.522569) (xy 56.774879 -203.514799) (xy 56.760515 -203.500441)
			(xy 56.752736 -203.48168) (xy 56.752236 -203.471526) (xy 50.7111 -203.471526) (xy 50.710589 -203.481681)
			(xy 50.702813 -203.500443) (xy 50.688453 -203.514806) (xy 50.669693 -203.522587) (xy 50.659538 -203.523088)
			(xy 49.259998 -203.523088) (xy 49.249843 -203.522569) (xy 49.231079 -203.514799) (xy 49.216715 -203.500441)
			(xy 49.208936 -203.48168) (xy 49.208436 -203.471526) (xy 43.1673 -203.471526) (xy 43.166789 -203.481681)
			(xy 43.159013 -203.500443) (xy 43.144653 -203.514806) (xy 43.125893 -203.522587) (xy 43.115738 -203.523088)
			(xy 41.716198 -203.523088) (xy 41.706043 -203.522569) (xy 41.687279 -203.514799) (xy 41.672915 -203.500441)
			(xy 41.665136 -203.48168) (xy 41.664636 -203.471526) (xy 35.6235 -203.471526) (xy 35.622989 -203.481681)
			(xy 35.615213 -203.500443) (xy 35.600853 -203.514806) (xy 35.582093 -203.522587) (xy 35.571938 -203.523088)
			(xy 34.172398 -203.523088) (xy 34.162243 -203.522569) (xy 34.143479 -203.514799) (xy 34.129115 -203.500441)
			(xy 34.121336 -203.48168) (xy 34.120836 -203.471526) (xy 28.0797 -203.471526) (xy 28.079189 -203.481681)
			(xy 28.071413 -203.500443) (xy 28.057053 -203.514806) (xy 28.038293 -203.522587) (xy 28.028138 -203.523088)
			(xy 26.628598 -203.523088) (xy 26.618443 -203.522569) (xy 26.599679 -203.514799) (xy 26.585315 -203.500441)
			(xy 26.577536 -203.48168) (xy 26.577036 -203.471526) (xy 20.5359 -203.471526) (xy 20.535389 -203.481681)
			(xy 20.527613 -203.500443) (xy 20.513253 -203.514806) (xy 20.494493 -203.522587) (xy 20.484338 -203.523088)
			(xy 19.084798 -203.523088) (xy 19.074643 -203.522569) (xy 19.055879 -203.514799) (xy 19.041515 -203.500441)
			(xy 19.033736 -203.48168) (xy 19.033236 -203.471526) (xy 12.9921 -203.471526) (xy 12.991589 -203.481681)
			(xy 12.983813 -203.500443) (xy 12.969453 -203.514806) (xy 12.950693 -203.522587) (xy 12.940538 -203.523088)
			(xy 11.540998 -203.523088) (xy 11.530843 -203.522569) (xy 11.512079 -203.514799) (xy 11.497715 -203.500441)
			(xy 11.489936 -203.48168) (xy 11.489436 -203.471526) (xy 2.509012 -203.471526) (xy 2.509012 -204.32141)
			(xy 7.389368 -204.32141) (xy 7.389368 -203.91247) (xy 7.389809 -203.902307) (xy 7.397599 -203.883531)
			(xy 7.411981 -203.869166) (xy 7.430766 -203.861398) (xy 7.44093 -203.860908) (xy 8.84047 -203.860908)
			(xy 8.850622 -203.861457) (xy 8.869385 -203.869216) (xy 8.88375 -203.883565) (xy 8.891531 -203.902318)
			(xy 8.892032 -203.91247) (xy 8.892032 -204.32141) (xy 14.933168 -204.32141) (xy 14.933168 -203.91247)
			(xy 14.933609 -203.902307) (xy 14.941399 -203.883531) (xy 14.955781 -203.869166) (xy 14.974566 -203.861398)
			(xy 14.98473 -203.860908) (xy 16.38427 -203.860908) (xy 16.394422 -203.861457) (xy 16.413185 -203.869216)
			(xy 16.42755 -203.883565) (xy 16.435331 -203.902318) (xy 16.435832 -203.91247) (xy 16.435832 -204.32141)
			(xy 22.476968 -204.32141) (xy 22.476968 -203.91247) (xy 22.477409 -203.902307) (xy 22.485199 -203.883531)
			(xy 22.499581 -203.869166) (xy 22.518366 -203.861398) (xy 22.52853 -203.860908) (xy 23.92807 -203.860908)
			(xy 23.938222 -203.861457) (xy 23.956985 -203.869216) (xy 23.97135 -203.883565) (xy 23.979131 -203.902318)
			(xy 23.979632 -203.91247) (xy 23.979632 -204.32141) (xy 30.020768 -204.32141) (xy 30.020768 -203.91247)
			(xy 30.021209 -203.902307) (xy 30.028999 -203.883531) (xy 30.043381 -203.869166) (xy 30.062166 -203.861398)
			(xy 30.07233 -203.860908) (xy 31.47187 -203.860908) (xy 31.482022 -203.861457) (xy 31.500785 -203.869216)
			(xy 31.51515 -203.883565) (xy 31.522931 -203.902318) (xy 31.523432 -203.91247) (xy 31.523432 -204.32141)
			(xy 37.564568 -204.32141) (xy 37.564568 -203.91247) (xy 37.565009 -203.902307) (xy 37.572799 -203.883531)
			(xy 37.587181 -203.869166) (xy 37.605966 -203.861398) (xy 37.61613 -203.860908) (xy 39.01567 -203.860908)
			(xy 39.025822 -203.861457) (xy 39.044585 -203.869216) (xy 39.05895 -203.883565) (xy 39.066731 -203.902318)
			(xy 39.067232 -203.91247) (xy 39.067232 -204.32141) (xy 45.108368 -204.32141) (xy 45.108368 -203.91247)
			(xy 45.108809 -203.902307) (xy 45.116599 -203.883531) (xy 45.130981 -203.869166) (xy 45.149766 -203.861398)
			(xy 45.15993 -203.860908) (xy 46.55947 -203.860908) (xy 46.569622 -203.861457) (xy 46.588385 -203.869216)
			(xy 46.60275 -203.883565) (xy 46.610531 -203.902318) (xy 46.611032 -203.91247) (xy 46.611032 -204.32141)
			(xy 52.652168 -204.32141) (xy 52.652168 -203.91247) (xy 52.652609 -203.902307) (xy 52.660399 -203.883531)
			(xy 52.674781 -203.869166) (xy 52.693566 -203.861398) (xy 52.70373 -203.860908) (xy 54.10327 -203.860908)
			(xy 54.113422 -203.861457) (xy 54.132185 -203.869216) (xy 54.14655 -203.883565) (xy 54.154331 -203.902318)
			(xy 54.154832 -203.91247) (xy 54.154832 -204.32141) (xy 60.195968 -204.32141) (xy 60.195968 -203.91247)
			(xy 60.196409 -203.902307) (xy 60.204199 -203.883531) (xy 60.218581 -203.869166) (xy 60.237366 -203.861398)
			(xy 60.24753 -203.860908) (xy 61.64707 -203.860908) (xy 61.657222 -203.861457) (xy 61.675985 -203.869216)
			(xy 61.69035 -203.883565) (xy 61.698131 -203.902318) (xy 61.698632 -203.91247) (xy 61.698632 -204.32141)
			(xy 61.698244 -204.331586) (xy 61.69045 -204.350387) (xy 61.676053 -204.364772) (xy 61.657246 -204.372551)
			(xy 61.64707 -204.372972) (xy 60.24753 -204.372972) (xy 60.237362 -204.372512) (xy 60.21857 -204.364738)
			(xy 60.204184 -204.350364) (xy 60.196396 -204.331578) (xy 60.195968 -204.32141) (xy 54.154832 -204.32141)
			(xy 54.154444 -204.331586) (xy 54.14665 -204.350387) (xy 54.132253 -204.364772) (xy 54.113446 -204.372551)
			(xy 54.10327 -204.372972) (xy 52.70373 -204.372972) (xy 52.693562 -204.372512) (xy 52.67477 -204.364738)
			(xy 52.660384 -204.350364) (xy 52.652596 -204.331578) (xy 52.652168 -204.32141) (xy 46.611032 -204.32141)
			(xy 46.610644 -204.331586) (xy 46.60285 -204.350387) (xy 46.588453 -204.364772) (xy 46.569646 -204.372551)
			(xy 46.55947 -204.372972) (xy 45.15993 -204.372972) (xy 45.149762 -204.372512) (xy 45.13097 -204.364738)
			(xy 45.116584 -204.350364) (xy 45.108796 -204.331578) (xy 45.108368 -204.32141) (xy 39.067232 -204.32141)
			(xy 39.066844 -204.331586) (xy 39.05905 -204.350387) (xy 39.044653 -204.364772) (xy 39.025846 -204.372551)
			(xy 39.01567 -204.372972) (xy 37.61613 -204.372972) (xy 37.605962 -204.372512) (xy 37.58717 -204.364738)
			(xy 37.572784 -204.350364) (xy 37.564996 -204.331578) (xy 37.564568 -204.32141) (xy 31.523432 -204.32141)
			(xy 31.523044 -204.331586) (xy 31.51525 -204.350387) (xy 31.500853 -204.364772) (xy 31.482046 -204.372551)
			(xy 31.47187 -204.372972) (xy 30.07233 -204.372972) (xy 30.062162 -204.372512) (xy 30.04337 -204.364738)
			(xy 30.028984 -204.350364) (xy 30.021196 -204.331578) (xy 30.020768 -204.32141) (xy 23.979632 -204.32141)
			(xy 23.979244 -204.331586) (xy 23.97145 -204.350387) (xy 23.957053 -204.364772) (xy 23.938246 -204.372551)
			(xy 23.92807 -204.372972) (xy 22.52853 -204.372972) (xy 22.518362 -204.372512) (xy 22.49957 -204.364738)
			(xy 22.485184 -204.350364) (xy 22.477396 -204.331578) (xy 22.476968 -204.32141) (xy 16.435832 -204.32141)
			(xy 16.435444 -204.331586) (xy 16.42765 -204.350387) (xy 16.413253 -204.364772) (xy 16.394446 -204.372551)
			(xy 16.38427 -204.372972) (xy 14.98473 -204.372972) (xy 14.974562 -204.372512) (xy 14.95577 -204.364738)
			(xy 14.941384 -204.350364) (xy 14.933596 -204.331578) (xy 14.933168 -204.32141) (xy 8.892032 -204.32141)
			(xy 8.891644 -204.331586) (xy 8.88385 -204.350387) (xy 8.869453 -204.364772) (xy 8.850646 -204.372551)
			(xy 8.84047 -204.372972) (xy 7.44093 -204.372972) (xy 7.430762 -204.372512) (xy 7.41197 -204.364738)
			(xy 7.397584 -204.350364) (xy 7.389796 -204.331578) (xy 7.389368 -204.32141) (xy 2.509012 -204.32141)
			(xy 2.509012 -205.171548) (xy 11.489436 -205.171548) (xy 11.489436 -204.762608) (xy 11.489829 -204.75245)
			(xy 11.497629 -204.733691) (xy 11.512035 -204.719366) (xy 11.530838 -204.711672) (xy 11.540998 -204.7113)
			(xy 12.940538 -204.7113) (xy 12.950662 -204.711794) (xy 12.969377 -204.719527) (xy 12.98373 -204.73381)
			(xy 12.991555 -204.752486) (xy 12.9921 -204.762608) (xy 12.9921 -205.171548) (xy 19.033236 -205.171548)
			(xy 19.033236 -204.762608) (xy 19.033629 -204.75245) (xy 19.041429 -204.733691) (xy 19.055835 -204.719366)
			(xy 19.074638 -204.711672) (xy 19.084798 -204.7113) (xy 20.484338 -204.7113) (xy 20.494462 -204.711794)
			(xy 20.513177 -204.719527) (xy 20.52753 -204.73381) (xy 20.535355 -204.752486) (xy 20.5359 -204.762608)
			(xy 20.5359 -205.171548) (xy 26.577036 -205.171548) (xy 26.577036 -204.762608) (xy 26.577429 -204.75245)
			(xy 26.585229 -204.733691) (xy 26.599635 -204.719366) (xy 26.618438 -204.711672) (xy 26.628598 -204.7113)
			(xy 28.028138 -204.7113) (xy 28.038262 -204.711794) (xy 28.056977 -204.719527) (xy 28.07133 -204.73381)
			(xy 28.079155 -204.752486) (xy 28.0797 -204.762608) (xy 28.0797 -205.171548) (xy 34.120836 -205.171548)
			(xy 34.120836 -204.762608) (xy 34.121229 -204.75245) (xy 34.129029 -204.733691) (xy 34.143435 -204.719366)
			(xy 34.162238 -204.711672) (xy 34.172398 -204.7113) (xy 35.571938 -204.7113) (xy 35.582062 -204.711794)
			(xy 35.600777 -204.719527) (xy 35.61513 -204.73381) (xy 35.622955 -204.752486) (xy 35.6235 -204.762608)
			(xy 35.6235 -205.171548) (xy 41.664636 -205.171548) (xy 41.664636 -204.762608) (xy 41.665029 -204.75245)
			(xy 41.672829 -204.733691) (xy 41.687235 -204.719366) (xy 41.706038 -204.711672) (xy 41.716198 -204.7113)
			(xy 43.115738 -204.7113) (xy 43.125862 -204.711794) (xy 43.144577 -204.719527) (xy 43.15893 -204.73381)
			(xy 43.166755 -204.752486) (xy 43.1673 -204.762608) (xy 43.1673 -205.171548) (xy 49.208436 -205.171548)
			(xy 49.208436 -204.762608) (xy 49.208829 -204.75245) (xy 49.216629 -204.733691) (xy 49.231035 -204.719366)
			(xy 49.249838 -204.711672) (xy 49.259998 -204.7113) (xy 50.659538 -204.7113) (xy 50.669662 -204.711794)
			(xy 50.688377 -204.719527) (xy 50.70273 -204.73381) (xy 50.710555 -204.752486) (xy 50.7111 -204.762608)
			(xy 50.7111 -205.171548) (xy 56.752236 -205.171548) (xy 56.752236 -204.762608) (xy 56.752629 -204.75245)
			(xy 56.760429 -204.733691) (xy 56.774835 -204.719366) (xy 56.793638 -204.711672) (xy 56.803798 -204.7113)
			(xy 58.203338 -204.7113) (xy 58.213462 -204.711794) (xy 58.232177 -204.719527) (xy 58.24653 -204.73381)
			(xy 58.254355 -204.752486) (xy 58.2549 -204.762608) (xy 58.2549 -205.171548) (xy 64.296036 -205.171548)
			(xy 64.296036 -204.762608) (xy 64.296429 -204.75245) (xy 64.304229 -204.733691) (xy 64.318635 -204.719366)
			(xy 64.337438 -204.711672) (xy 64.347598 -204.7113) (xy 65.747138 -204.7113) (xy 65.757262 -204.711794)
			(xy 65.775977 -204.719527) (xy 65.79033 -204.73381) (xy 65.798155 -204.752486) (xy 65.7987 -204.762608)
			(xy 65.7987 -205.171548) (xy 65.798318 -205.181705) (xy 65.790506 -205.200459) (xy 65.776098 -205.21478)
			(xy 65.757298 -205.222478) (xy 65.747138 -205.222856) (xy 64.347598 -205.222856) (xy 64.337471 -205.222375)
			(xy 64.318749 -205.214646) (xy 64.304392 -205.200358) (xy 64.296574 -205.181673) (xy 64.296036 -205.171548)
			(xy 58.2549 -205.171548) (xy 58.254518 -205.181705) (xy 58.246706 -205.200459) (xy 58.232298 -205.21478)
			(xy 58.213498 -205.222478) (xy 58.203338 -205.222856) (xy 56.803798 -205.222856) (xy 56.793671 -205.222375)
			(xy 56.774949 -205.214646) (xy 56.760592 -205.200358) (xy 56.752774 -205.181673) (xy 56.752236 -205.171548)
			(xy 50.7111 -205.171548) (xy 50.710718 -205.181705) (xy 50.702906 -205.200459) (xy 50.688498 -205.21478)
			(xy 50.669698 -205.222478) (xy 50.659538 -205.222856) (xy 49.259998 -205.222856) (xy 49.249871 -205.222375)
			(xy 49.231149 -205.214646) (xy 49.216792 -205.200358) (xy 49.208974 -205.181673) (xy 49.208436 -205.171548)
			(xy 43.1673 -205.171548) (xy 43.166918 -205.181705) (xy 43.159106 -205.200459) (xy 43.144698 -205.21478)
			(xy 43.125898 -205.222478) (xy 43.115738 -205.222856) (xy 41.716198 -205.222856) (xy 41.706071 -205.222375)
			(xy 41.687349 -205.214646) (xy 41.672992 -205.200358) (xy 41.665174 -205.181673) (xy 41.664636 -205.171548)
			(xy 35.6235 -205.171548) (xy 35.623118 -205.181705) (xy 35.615306 -205.200459) (xy 35.600898 -205.21478)
			(xy 35.582098 -205.222478) (xy 35.571938 -205.222856) (xy 34.172398 -205.222856) (xy 34.162271 -205.222375)
			(xy 34.143549 -205.214646) (xy 34.129192 -205.200358) (xy 34.121374 -205.181673) (xy 34.120836 -205.171548)
			(xy 28.0797 -205.171548) (xy 28.079318 -205.181705) (xy 28.071506 -205.200459) (xy 28.057098 -205.21478)
			(xy 28.038298 -205.222478) (xy 28.028138 -205.222856) (xy 26.628598 -205.222856) (xy 26.618471 -205.222375)
			(xy 26.599749 -205.214646) (xy 26.585392 -205.200358) (xy 26.577574 -205.181673) (xy 26.577036 -205.171548)
			(xy 20.5359 -205.171548) (xy 20.535518 -205.181705) (xy 20.527706 -205.200459) (xy 20.513298 -205.21478)
			(xy 20.494498 -205.222478) (xy 20.484338 -205.222856) (xy 19.084798 -205.222856) (xy 19.074671 -205.222375)
			(xy 19.055949 -205.214646) (xy 19.041592 -205.200358) (xy 19.033774 -205.181673) (xy 19.033236 -205.171548)
			(xy 12.9921 -205.171548) (xy 12.991718 -205.181705) (xy 12.983906 -205.200459) (xy 12.969498 -205.21478)
			(xy 12.950698 -205.222478) (xy 12.940538 -205.222856) (xy 11.540998 -205.222856) (xy 11.530871 -205.222375)
			(xy 11.512149 -205.214646) (xy 11.497792 -205.200358) (xy 11.489974 -205.181673) (xy 11.489436 -205.171548)
			(xy 2.509012 -205.171548) (xy 2.509012 -206.021432) (xy 7.389368 -206.021432) (xy 7.389368 -205.612492)
			(xy 7.389815 -205.602341) (xy 7.397607 -205.583595) (xy 7.411995 -205.569273) (xy 7.430778 -205.561568)
			(xy 7.44093 -205.561184) (xy 8.84047 -205.561184) (xy 8.8506 -205.561652) (xy 8.869329 -205.569378)
			(xy 8.883688 -205.583671) (xy 8.891501 -205.602364) (xy 8.892032 -205.612492) (xy 8.892032 -206.021432)
			(xy 14.933168 -206.021432) (xy 14.933168 -205.612492) (xy 14.933615 -205.602341) (xy 14.941407 -205.583595)
			(xy 14.955795 -205.569273) (xy 14.974578 -205.561568) (xy 14.98473 -205.561184) (xy 16.38427 -205.561184)
			(xy 16.3944 -205.561652) (xy 16.413129 -205.569378) (xy 16.427488 -205.583671) (xy 16.435301 -205.602364)
			(xy 16.435832 -205.612492) (xy 16.435832 -206.021432) (xy 22.476968 -206.021432) (xy 22.476968 -205.612492)
			(xy 22.477415 -205.602341) (xy 22.485207 -205.583595) (xy 22.499595 -205.569273) (xy 22.518378 -205.561568)
			(xy 22.52853 -205.561184) (xy 23.92807 -205.561184) (xy 23.9382 -205.561652) (xy 23.956929 -205.569378)
			(xy 23.971288 -205.583671) (xy 23.979101 -205.602364) (xy 23.979632 -205.612492) (xy 23.979632 -206.021432)
			(xy 30.020768 -206.021432) (xy 30.020768 -205.612492) (xy 30.021215 -205.602341) (xy 30.029007 -205.583595)
			(xy 30.043395 -205.569273) (xy 30.062178 -205.561568) (xy 30.07233 -205.561184) (xy 31.47187 -205.561184)
			(xy 31.482 -205.561652) (xy 31.500729 -205.569378) (xy 31.515088 -205.583671) (xy 31.522901 -205.602364)
			(xy 31.523432 -205.612492) (xy 31.523432 -206.021432) (xy 37.564568 -206.021432) (xy 37.564568 -205.612492)
			(xy 37.565015 -205.602341) (xy 37.572807 -205.583595) (xy 37.587195 -205.569273) (xy 37.605978 -205.561568)
			(xy 37.61613 -205.561184) (xy 39.01567 -205.561184) (xy 39.0258 -205.561652) (xy 39.044529 -205.569378)
			(xy 39.058888 -205.583671) (xy 39.066701 -205.602364) (xy 39.067232 -205.612492) (xy 39.067232 -206.021432)
			(xy 45.108368 -206.021432) (xy 45.108368 -205.612492) (xy 45.108815 -205.602341) (xy 45.116607 -205.583595)
			(xy 45.130995 -205.569273) (xy 45.149778 -205.561568) (xy 45.15993 -205.561184) (xy 46.55947 -205.561184)
			(xy 46.5696 -205.561652) (xy 46.588329 -205.569378) (xy 46.602688 -205.583671) (xy 46.610501 -205.602364)
			(xy 46.611032 -205.612492) (xy 46.611032 -206.021432) (xy 52.652168 -206.021432) (xy 52.652168 -205.612492)
			(xy 52.652615 -205.602341) (xy 52.660407 -205.583595) (xy 52.674795 -205.569273) (xy 52.693578 -205.561568)
			(xy 52.70373 -205.561184) (xy 54.10327 -205.561184) (xy 54.1134 -205.561652) (xy 54.132129 -205.569378)
			(xy 54.146488 -205.583671) (xy 54.154301 -205.602364) (xy 54.154832 -205.612492) (xy 54.154832 -206.021432)
			(xy 60.195968 -206.021432) (xy 60.195968 -205.612492) (xy 60.196415 -205.602341) (xy 60.204207 -205.583595)
			(xy 60.218595 -205.569273) (xy 60.237378 -205.561568) (xy 60.24753 -205.561184) (xy 61.64707 -205.561184)
			(xy 61.6572 -205.561652) (xy 61.675929 -205.569378) (xy 61.690288 -205.583671) (xy 61.698101 -205.602364)
			(xy 61.698632 -205.612492) (xy 61.698632 -206.021432) (xy 61.698482 -206.024988) (xy 86.700624 -206.024988)
			(xy 86.704605 -205.891968) (xy 86.716534 -205.759423) (xy 86.736369 -205.62783) (xy 86.764038 -205.497658)
			(xy 86.799442 -205.369373) (xy 86.842455 -205.243436) (xy 86.892922 -205.120297) (xy 86.950663 -205.000396)
			(xy 87.015472 -204.884163) (xy 87.087116 -204.772013) (xy 87.165338 -204.664349) (xy 87.249859 -204.561556)
			(xy 87.340377 -204.464001) (xy 87.436566 -204.372035) (xy 87.538084 -204.285985) (xy 87.644565 -204.206161)
			(xy 87.75563 -204.132848) (xy 87.870881 -204.066308) (xy 87.989905 -204.006779) (xy 88.112276 -203.954475)
			(xy 88.237555 -203.909583) (xy 88.365296 -203.872264) (xy 88.495039 -203.842651) (xy 88.626321 -203.82085)
			(xy 88.758672 -203.80694) (xy 88.891618 -203.800969) (xy 89.024683 -203.80296) (xy 89.157391 -203.812905)
			(xy 89.289267 -203.830769) (xy 89.419838 -203.856487) (xy 89.548638 -203.889968) (xy 89.675204 -203.931092)
			(xy 89.799085 -203.979712) (xy 89.919836 -204.035653) (xy 90.037026 -204.098715) (xy 90.150235 -204.168673)
			(xy 90.259057 -204.245277) (xy 90.363103 -204.328251) (xy 90.462001 -204.417299) (xy 90.555396 -204.512102)
			(xy 90.642954 -204.61232) (xy 90.724363 -204.717596) (xy 90.799329 -204.827552) (xy 90.867586 -204.941794)
			(xy 90.928888 -205.059914) (xy 90.983017 -205.181489) (xy 91.029778 -205.306083) (xy 91.069004 -205.433251)
			(xy 91.100554 -205.562537) (xy 91.124317 -205.693478) (xy 91.140206 -205.825606) (xy 91.148164 -205.958448)
			(xy 91.148662 -206.024988) (xy 132.710692 -206.024988) (xy 132.714673 -205.891968) (xy 132.726602 -205.759423)
			(xy 132.746437 -205.62783) (xy 132.774106 -205.497658) (xy 132.80951 -205.369373) (xy 132.852523 -205.243436)
			(xy 132.90299 -205.120297) (xy 132.960731 -205.000396) (xy 133.02554 -204.884163) (xy 133.097184 -204.772013)
			(xy 133.175406 -204.664349) (xy 133.259927 -204.561556) (xy 133.350445 -204.464001) (xy 133.446634 -204.372035)
			(xy 133.548152 -204.285985) (xy 133.654633 -204.206161) (xy 133.765698 -204.132848) (xy 133.880949 -204.066308)
			(xy 133.999973 -204.006779) (xy 134.122344 -203.954475) (xy 134.247623 -203.909583) (xy 134.375364 -203.872264)
			(xy 134.505107 -203.842651) (xy 134.636389 -203.82085) (xy 134.76874 -203.80694) (xy 134.901686 -203.800969)
			(xy 135.034751 -203.80296) (xy 135.167459 -203.812905) (xy 135.299335 -203.830769) (xy 135.429906 -203.856487)
			(xy 135.558706 -203.889968) (xy 135.685272 -203.931092) (xy 135.809153 -203.979712) (xy 135.929904 -204.035653)
			(xy 136.047094 -204.098715) (xy 136.160303 -204.168673) (xy 136.269125 -204.245277) (xy 136.364593 -204.32141)
			(xy 158.062168 -204.32141) (xy 158.062168 -203.91247) (xy 158.062609 -203.902307) (xy 158.070399 -203.883531)
			(xy 158.084781 -203.869166) (xy 158.103566 -203.861398) (xy 158.11373 -203.860908) (xy 159.51327 -203.860908)
			(xy 159.523422 -203.861457) (xy 159.542185 -203.869216) (xy 159.55655 -203.883565) (xy 159.564331 -203.902318)
			(xy 159.564832 -203.91247) (xy 159.564832 -204.32141) (xy 165.605968 -204.32141) (xy 165.605968 -203.91247)
			(xy 165.606409 -203.902307) (xy 165.614199 -203.883531) (xy 165.628581 -203.869166) (xy 165.647366 -203.861398)
			(xy 165.65753 -203.860908) (xy 167.05707 -203.860908) (xy 167.067222 -203.861457) (xy 167.085985 -203.869216)
			(xy 167.10035 -203.883565) (xy 167.108131 -203.902318) (xy 167.108632 -203.91247) (xy 167.108632 -204.32141)
			(xy 173.149768 -204.32141) (xy 173.149768 -203.91247) (xy 173.150209 -203.902307) (xy 173.157999 -203.883531)
			(xy 173.172381 -203.869166) (xy 173.191166 -203.861398) (xy 173.20133 -203.860908) (xy 174.60087 -203.860908)
			(xy 174.611022 -203.861457) (xy 174.629785 -203.869216) (xy 174.64415 -203.883565) (xy 174.651931 -203.902318)
			(xy 174.652432 -203.91247) (xy 174.652432 -204.32141) (xy 180.693568 -204.32141) (xy 180.693568 -203.91247)
			(xy 180.694009 -203.902307) (xy 180.701799 -203.883531) (xy 180.716181 -203.869166) (xy 180.734966 -203.861398)
			(xy 180.74513 -203.860908) (xy 182.14467 -203.860908) (xy 182.154822 -203.861457) (xy 182.173585 -203.869216)
			(xy 182.18795 -203.883565) (xy 182.195731 -203.902318) (xy 182.196232 -203.91247) (xy 182.196232 -204.32141)
			(xy 188.237368 -204.32141) (xy 188.237368 -203.91247) (xy 188.237809 -203.902307) (xy 188.245599 -203.883531)
			(xy 188.259981 -203.869166) (xy 188.278766 -203.861398) (xy 188.28893 -203.860908) (xy 189.68847 -203.860908)
			(xy 189.698622 -203.861457) (xy 189.717385 -203.869216) (xy 189.73175 -203.883565) (xy 189.739531 -203.902318)
			(xy 189.740032 -203.91247) (xy 189.740032 -204.32141) (xy 195.781168 -204.32141) (xy 195.781168 -203.91247)
			(xy 195.781609 -203.902307) (xy 195.789399 -203.883531) (xy 195.803781 -203.869166) (xy 195.822566 -203.861398)
			(xy 195.83273 -203.860908) (xy 197.23227 -203.860908) (xy 197.242422 -203.861457) (xy 197.261185 -203.869216)
			(xy 197.27555 -203.883565) (xy 197.283331 -203.902318) (xy 197.283832 -203.91247) (xy 197.283832 -204.32141)
			(xy 203.324968 -204.32141) (xy 203.324968 -203.91247) (xy 203.325409 -203.902307) (xy 203.333199 -203.883531)
			(xy 203.347581 -203.869166) (xy 203.366366 -203.861398) (xy 203.37653 -203.860908) (xy 204.77607 -203.860908)
			(xy 204.786222 -203.861457) (xy 204.804985 -203.869216) (xy 204.81935 -203.883565) (xy 204.827131 -203.902318)
			(xy 204.827632 -203.91247) (xy 204.827632 -204.32141) (xy 210.868768 -204.32141) (xy 210.868768 -203.91247)
			(xy 210.869209 -203.902307) (xy 210.876999 -203.883531) (xy 210.891381 -203.869166) (xy 210.910166 -203.861398)
			(xy 210.92033 -203.860908) (xy 212.31987 -203.860908) (xy 212.330022 -203.861457) (xy 212.348785 -203.869216)
			(xy 212.36315 -203.883565) (xy 212.370931 -203.902318) (xy 212.371432 -203.91247) (xy 212.371432 -204.32141)
			(xy 255.329436 -204.32141) (xy 255.329436 -203.91247) (xy 255.329909 -203.902311) (xy 255.337693 -203.883541)
			(xy 255.352065 -203.869177) (xy 255.370838 -203.861403) (xy 255.380998 -203.860908) (xy 256.780538 -203.860908)
			(xy 256.790695 -203.861402) (xy 256.809459 -203.869183) (xy 256.823822 -203.883548) (xy 256.8316 -203.902313)
			(xy 256.8321 -203.91247) (xy 256.8321 -204.32141) (xy 262.873236 -204.32141) (xy 262.873236 -203.91247)
			(xy 262.873709 -203.902311) (xy 262.881493 -203.883541) (xy 262.895865 -203.869177) (xy 262.914638 -203.861403)
			(xy 262.924798 -203.860908) (xy 264.324338 -203.860908) (xy 264.334495 -203.861402) (xy 264.353259 -203.869183)
			(xy 264.367622 -203.883548) (xy 264.3754 -203.902313) (xy 264.3759 -203.91247) (xy 264.3759 -204.32141)
			(xy 270.417036 -204.32141) (xy 270.417036 -203.91247) (xy 270.417509 -203.902311) (xy 270.425293 -203.883541)
			(xy 270.439665 -203.869177) (xy 270.458438 -203.861403) (xy 270.468598 -203.860908) (xy 271.868138 -203.860908)
			(xy 271.878295 -203.861402) (xy 271.897059 -203.869183) (xy 271.911422 -203.883548) (xy 271.9192 -203.902313)
			(xy 271.9197 -203.91247) (xy 271.9197 -204.32141) (xy 277.960836 -204.32141) (xy 277.960836 -203.91247)
			(xy 277.961309 -203.902311) (xy 277.969093 -203.883541) (xy 277.983465 -203.869177) (xy 278.002238 -203.861403)
			(xy 278.012398 -203.860908) (xy 279.411938 -203.860908) (xy 279.422095 -203.861402) (xy 279.440859 -203.869183)
			(xy 279.455222 -203.883548) (xy 279.463 -203.902313) (xy 279.4635 -203.91247) (xy 279.4635 -204.32141)
			(xy 285.504636 -204.32141) (xy 285.504636 -203.91247) (xy 285.505109 -203.902311) (xy 285.512893 -203.883541)
			(xy 285.527265 -203.869177) (xy 285.546038 -203.861403) (xy 285.556198 -203.860908) (xy 286.955738 -203.860908)
			(xy 286.965895 -203.861402) (xy 286.984659 -203.869183) (xy 286.999022 -203.883548) (xy 287.0068 -203.902313)
			(xy 287.0073 -203.91247) (xy 287.0073 -204.32141) (xy 293.048436 -204.32141) (xy 293.048436 -203.91247)
			(xy 293.048909 -203.902311) (xy 293.056693 -203.883541) (xy 293.071065 -203.869177) (xy 293.089838 -203.861403)
			(xy 293.099998 -203.860908) (xy 294.499538 -203.860908) (xy 294.509695 -203.861402) (xy 294.528459 -203.869183)
			(xy 294.542822 -203.883548) (xy 294.5506 -203.902313) (xy 294.5511 -203.91247) (xy 294.5511 -204.32141)
			(xy 300.592236 -204.32141) (xy 300.592236 -203.91247) (xy 300.592709 -203.902311) (xy 300.600493 -203.883541)
			(xy 300.614865 -203.869177) (xy 300.633638 -203.861403) (xy 300.643798 -203.860908) (xy 302.043338 -203.860908)
			(xy 302.053495 -203.861402) (xy 302.072259 -203.869183) (xy 302.086622 -203.883548) (xy 302.0944 -203.902313)
			(xy 302.0949 -203.91247) (xy 302.0949 -204.32141) (xy 308.136036 -204.32141) (xy 308.136036 -203.91247)
			(xy 308.136509 -203.902311) (xy 308.144293 -203.883541) (xy 308.158665 -203.869177) (xy 308.177438 -203.861403)
			(xy 308.187598 -203.860908) (xy 309.587138 -203.860908) (xy 309.597295 -203.861402) (xy 309.616059 -203.869183)
			(xy 309.630422 -203.883548) (xy 309.6382 -203.902313) (xy 309.6387 -203.91247) (xy 309.6387 -204.32141)
			(xy 309.638176 -204.331564) (xy 309.630405 -204.350326) (xy 309.616049 -204.364689) (xy 309.597291 -204.37247)
			(xy 309.587138 -204.372972) (xy 308.187598 -204.372972) (xy 308.177441 -204.372468) (xy 308.158674 -204.364695)
			(xy 308.144309 -204.350333) (xy 308.136533 -204.331567) (xy 308.136036 -204.32141) (xy 302.0949 -204.32141)
			(xy 302.094376 -204.331564) (xy 302.086605 -204.350326) (xy 302.072249 -204.364689) (xy 302.053491 -204.37247)
			(xy 302.043338 -204.372972) (xy 300.643798 -204.372972) (xy 300.633641 -204.372468) (xy 300.614874 -204.364695)
			(xy 300.600509 -204.350333) (xy 300.592733 -204.331567) (xy 300.592236 -204.32141) (xy 294.5511 -204.32141)
			(xy 294.550576 -204.331564) (xy 294.542805 -204.350326) (xy 294.528449 -204.364689) (xy 294.509691 -204.37247)
			(xy 294.499538 -204.372972) (xy 293.099998 -204.372972) (xy 293.089841 -204.372468) (xy 293.071074 -204.364695)
			(xy 293.056709 -204.350333) (xy 293.048933 -204.331567) (xy 293.048436 -204.32141) (xy 287.0073 -204.32141)
			(xy 287.006776 -204.331564) (xy 286.999005 -204.350326) (xy 286.984649 -204.364689) (xy 286.965891 -204.37247)
			(xy 286.955738 -204.372972) (xy 285.556198 -204.372972) (xy 285.546041 -204.372468) (xy 285.527274 -204.364695)
			(xy 285.512909 -204.350333) (xy 285.505133 -204.331567) (xy 285.504636 -204.32141) (xy 279.4635 -204.32141)
			(xy 279.462976 -204.331564) (xy 279.455205 -204.350326) (xy 279.440849 -204.364689) (xy 279.422091 -204.37247)
			(xy 279.411938 -204.372972) (xy 278.012398 -204.372972) (xy 278.002241 -204.372468) (xy 277.983474 -204.364695)
			(xy 277.969109 -204.350333) (xy 277.961333 -204.331567) (xy 277.960836 -204.32141) (xy 271.9197 -204.32141)
			(xy 271.919176 -204.331564) (xy 271.911405 -204.350326) (xy 271.897049 -204.364689) (xy 271.878291 -204.37247)
			(xy 271.868138 -204.372972) (xy 270.468598 -204.372972) (xy 270.458441 -204.372468) (xy 270.439674 -204.364695)
			(xy 270.425309 -204.350333) (xy 270.417533 -204.331567) (xy 270.417036 -204.32141) (xy 264.3759 -204.32141)
			(xy 264.375376 -204.331564) (xy 264.367605 -204.350326) (xy 264.353249 -204.364689) (xy 264.334491 -204.37247)
			(xy 264.324338 -204.372972) (xy 262.924798 -204.372972) (xy 262.914641 -204.372468) (xy 262.895874 -204.364695)
			(xy 262.881509 -204.350333) (xy 262.873733 -204.331567) (xy 262.873236 -204.32141) (xy 256.8321 -204.32141)
			(xy 256.831576 -204.331564) (xy 256.823805 -204.350326) (xy 256.809449 -204.364689) (xy 256.790691 -204.37247)
			(xy 256.780538 -204.372972) (xy 255.380998 -204.372972) (xy 255.370841 -204.372468) (xy 255.352074 -204.364695)
			(xy 255.337709 -204.350333) (xy 255.329933 -204.331567) (xy 255.329436 -204.32141) (xy 212.371432 -204.32141)
			(xy 212.371044 -204.331586) (xy 212.36325 -204.350387) (xy 212.348853 -204.364772) (xy 212.330046 -204.372551)
			(xy 212.31987 -204.372972) (xy 210.92033 -204.372972) (xy 210.910162 -204.372512) (xy 210.89137 -204.364738)
			(xy 210.876984 -204.350364) (xy 210.869196 -204.331578) (xy 210.868768 -204.32141) (xy 204.827632 -204.32141)
			(xy 204.827244 -204.331586) (xy 204.81945 -204.350387) (xy 204.805053 -204.364772) (xy 204.786246 -204.372551)
			(xy 204.77607 -204.372972) (xy 203.37653 -204.372972) (xy 203.366362 -204.372512) (xy 203.34757 -204.364738)
			(xy 203.333184 -204.350364) (xy 203.325396 -204.331578) (xy 203.324968 -204.32141) (xy 197.283832 -204.32141)
			(xy 197.283444 -204.331586) (xy 197.27565 -204.350387) (xy 197.261253 -204.364772) (xy 197.242446 -204.372551)
			(xy 197.23227 -204.372972) (xy 195.83273 -204.372972) (xy 195.822562 -204.372512) (xy 195.80377 -204.364738)
			(xy 195.789384 -204.350364) (xy 195.781596 -204.331578) (xy 195.781168 -204.32141) (xy 189.740032 -204.32141)
			(xy 189.739644 -204.331586) (xy 189.73185 -204.350387) (xy 189.717453 -204.364772) (xy 189.698646 -204.372551)
			(xy 189.68847 -204.372972) (xy 188.28893 -204.372972) (xy 188.278762 -204.372512) (xy 188.25997 -204.364738)
			(xy 188.245584 -204.350364) (xy 188.237796 -204.331578) (xy 188.237368 -204.32141) (xy 182.196232 -204.32141)
			(xy 182.195844 -204.331586) (xy 182.18805 -204.350387) (xy 182.173653 -204.364772) (xy 182.154846 -204.372551)
			(xy 182.14467 -204.372972) (xy 180.74513 -204.372972) (xy 180.734962 -204.372512) (xy 180.71617 -204.364738)
			(xy 180.701784 -204.350364) (xy 180.693996 -204.331578) (xy 180.693568 -204.32141) (xy 174.652432 -204.32141)
			(xy 174.652044 -204.331586) (xy 174.64425 -204.350387) (xy 174.629853 -204.364772) (xy 174.611046 -204.372551)
			(xy 174.60087 -204.372972) (xy 173.20133 -204.372972) (xy 173.191162 -204.372512) (xy 173.17237 -204.364738)
			(xy 173.157984 -204.350364) (xy 173.150196 -204.331578) (xy 173.149768 -204.32141) (xy 167.108632 -204.32141)
			(xy 167.108244 -204.331586) (xy 167.10045 -204.350387) (xy 167.086053 -204.364772) (xy 167.067246 -204.372551)
			(xy 167.05707 -204.372972) (xy 165.65753 -204.372972) (xy 165.647362 -204.372512) (xy 165.62857 -204.364738)
			(xy 165.614184 -204.350364) (xy 165.606396 -204.331578) (xy 165.605968 -204.32141) (xy 159.564832 -204.32141)
			(xy 159.564444 -204.331586) (xy 159.55665 -204.350387) (xy 159.542253 -204.364772) (xy 159.523446 -204.372551)
			(xy 159.51327 -204.372972) (xy 158.11373 -204.372972) (xy 158.103562 -204.372512) (xy 158.08477 -204.364738)
			(xy 158.070384 -204.350364) (xy 158.062596 -204.331578) (xy 158.062168 -204.32141) (xy 136.364593 -204.32141)
			(xy 136.373171 -204.328251) (xy 136.472069 -204.417299) (xy 136.565464 -204.512102) (xy 136.653022 -204.61232)
			(xy 136.734431 -204.717596) (xy 136.809397 -204.827552) (xy 136.877654 -204.941794) (xy 136.938956 -205.059914)
			(xy 136.988659 -205.171548) (xy 162.162236 -205.171548) (xy 162.162236 -204.762608) (xy 162.162629 -204.75245)
			(xy 162.170429 -204.733691) (xy 162.184835 -204.719366) (xy 162.203638 -204.711672) (xy 162.213798 -204.7113)
			(xy 163.613338 -204.7113) (xy 163.623462 -204.711794) (xy 163.642177 -204.719527) (xy 163.65653 -204.73381)
			(xy 163.664355 -204.752486) (xy 163.6649 -204.762608) (xy 163.6649 -205.171548) (xy 169.706036 -205.171548)
			(xy 169.706036 -204.762608) (xy 169.706429 -204.75245) (xy 169.714229 -204.733691) (xy 169.728635 -204.719366)
			(xy 169.747438 -204.711672) (xy 169.757598 -204.7113) (xy 171.157138 -204.7113) (xy 171.167262 -204.711794)
			(xy 171.185977 -204.719527) (xy 171.20033 -204.73381) (xy 171.208155 -204.752486) (xy 171.2087 -204.762608)
			(xy 171.2087 -205.171548) (xy 177.249836 -205.171548) (xy 177.249836 -204.762608) (xy 177.250229 -204.75245)
			(xy 177.258029 -204.733691) (xy 177.272435 -204.719366) (xy 177.291238 -204.711672) (xy 177.301398 -204.7113)
			(xy 178.700938 -204.7113) (xy 178.711062 -204.711794) (xy 178.729777 -204.719527) (xy 178.74413 -204.73381)
			(xy 178.751955 -204.752486) (xy 178.7525 -204.762608) (xy 178.7525 -205.171548) (xy 184.793636 -205.171548)
			(xy 184.793636 -204.762608) (xy 184.794029 -204.75245) (xy 184.801829 -204.733691) (xy 184.816235 -204.719366)
			(xy 184.835038 -204.711672) (xy 184.845198 -204.7113) (xy 186.244738 -204.7113) (xy 186.254862 -204.711794)
			(xy 186.273577 -204.719527) (xy 186.28793 -204.73381) (xy 186.295755 -204.752486) (xy 186.2963 -204.762608)
			(xy 186.2963 -205.171548) (xy 192.337436 -205.171548) (xy 192.337436 -204.762608) (xy 192.337829 -204.75245)
			(xy 192.345629 -204.733691) (xy 192.360035 -204.719366) (xy 192.378838 -204.711672) (xy 192.388998 -204.7113)
			(xy 193.788538 -204.7113) (xy 193.798662 -204.711794) (xy 193.817377 -204.719527) (xy 193.83173 -204.73381)
			(xy 193.839555 -204.752486) (xy 193.8401 -204.762608) (xy 193.8401 -205.171548) (xy 199.881236 -205.171548)
			(xy 199.881236 -204.762608) (xy 199.881629 -204.75245) (xy 199.889429 -204.733691) (xy 199.903835 -204.719366)
			(xy 199.922638 -204.711672) (xy 199.932798 -204.7113) (xy 201.332338 -204.7113) (xy 201.342462 -204.711794)
			(xy 201.361177 -204.719527) (xy 201.37553 -204.73381) (xy 201.383355 -204.752486) (xy 201.3839 -204.762608)
			(xy 201.3839 -205.171548) (xy 207.425036 -205.171548) (xy 207.425036 -204.762608) (xy 207.425429 -204.75245)
			(xy 207.433229 -204.733691) (xy 207.447635 -204.719366) (xy 207.466438 -204.711672) (xy 207.476598 -204.7113)
			(xy 208.876138 -204.7113) (xy 208.886262 -204.711794) (xy 208.904977 -204.719527) (xy 208.91933 -204.73381)
			(xy 208.927155 -204.752486) (xy 208.9277 -204.762608) (xy 208.9277 -205.171548) (xy 214.968836 -205.171548)
			(xy 214.968836 -204.762608) (xy 214.969229 -204.75245) (xy 214.977029 -204.733691) (xy 214.991435 -204.719366)
			(xy 215.010238 -204.711672) (xy 215.020398 -204.7113) (xy 216.419938 -204.7113) (xy 216.430062 -204.711794)
			(xy 216.448777 -204.719527) (xy 216.46313 -204.73381) (xy 216.470955 -204.752486) (xy 216.4715 -204.762608)
			(xy 216.4715 -205.171548) (xy 259.429504 -205.171548) (xy 259.429504 -204.762608) (xy 259.429928 -204.752454)
			(xy 259.437722 -204.733701) (xy 259.452118 -204.719377) (xy 259.47091 -204.711678) (xy 259.481066 -204.7113)
			(xy 260.880606 -204.7113) (xy 260.890728 -204.711821) (xy 260.909442 -204.719543) (xy 260.923796 -204.733818)
			(xy 260.931622 -204.752489) (xy 260.932168 -204.762608) (xy 260.932168 -205.171548) (xy 266.973304 -205.171548)
			(xy 266.973304 -204.762608) (xy 266.973728 -204.752454) (xy 266.981522 -204.733701) (xy 266.995918 -204.719377)
			(xy 267.01471 -204.711678) (xy 267.024866 -204.7113) (xy 268.424406 -204.7113) (xy 268.434528 -204.711821)
			(xy 268.453242 -204.719543) (xy 268.467596 -204.733818) (xy 268.475422 -204.752489) (xy 268.475968 -204.762608)
			(xy 268.475968 -205.171548) (xy 274.517104 -205.171548) (xy 274.517104 -204.762608) (xy 274.517528 -204.752454)
			(xy 274.525322 -204.733701) (xy 274.539718 -204.719377) (xy 274.55851 -204.711678) (xy 274.568666 -204.7113)
			(xy 275.968206 -204.7113) (xy 275.978328 -204.711821) (xy 275.997042 -204.719543) (xy 276.011396 -204.733818)
			(xy 276.019222 -204.752489) (xy 276.019768 -204.762608) (xy 276.019768 -205.171548) (xy 282.060904 -205.171548)
			(xy 282.060904 -204.762608) (xy 282.061328 -204.752454) (xy 282.069122 -204.733701) (xy 282.083518 -204.719377)
			(xy 282.10231 -204.711678) (xy 282.112466 -204.7113) (xy 283.512006 -204.7113) (xy 283.522128 -204.711821)
			(xy 283.540842 -204.719543) (xy 283.555196 -204.733818) (xy 283.563022 -204.752489) (xy 283.563568 -204.762608)
			(xy 283.563568 -205.171548) (xy 289.604704 -205.171548) (xy 289.604704 -204.762608) (xy 289.605128 -204.752454)
			(xy 289.612922 -204.733701) (xy 289.627318 -204.719377) (xy 289.64611 -204.711678) (xy 289.656266 -204.7113)
			(xy 291.055806 -204.7113) (xy 291.065928 -204.711821) (xy 291.084642 -204.719543) (xy 291.098996 -204.733818)
			(xy 291.106822 -204.752489) (xy 291.107368 -204.762608) (xy 291.107368 -205.171548) (xy 297.148504 -205.171548)
			(xy 297.148504 -204.762608) (xy 297.148928 -204.752454) (xy 297.156722 -204.733701) (xy 297.171118 -204.719377)
			(xy 297.18991 -204.711678) (xy 297.200066 -204.7113) (xy 298.599606 -204.7113) (xy 298.609728 -204.711821)
			(xy 298.628442 -204.719543) (xy 298.642796 -204.733818) (xy 298.650622 -204.752489) (xy 298.651168 -204.762608)
			(xy 298.651168 -205.171548) (xy 304.692304 -205.171548) (xy 304.692304 -204.762608) (xy 304.692728 -204.752454)
			(xy 304.700522 -204.733701) (xy 304.714918 -204.719377) (xy 304.73371 -204.711678) (xy 304.743866 -204.7113)
			(xy 306.143406 -204.7113) (xy 306.153528 -204.711821) (xy 306.172242 -204.719543) (xy 306.186596 -204.733818)
			(xy 306.194422 -204.752489) (xy 306.194968 -204.762608) (xy 306.194968 -205.171548) (xy 312.236104 -205.171548)
			(xy 312.236104 -204.762608) (xy 312.236528 -204.752454) (xy 312.244322 -204.733701) (xy 312.258718 -204.719377)
			(xy 312.27751 -204.711678) (xy 312.287666 -204.7113) (xy 313.687206 -204.7113) (xy 313.697328 -204.711821)
			(xy 313.716042 -204.719543) (xy 313.730396 -204.733818) (xy 313.738222 -204.752489) (xy 313.738768 -204.762608)
			(xy 313.738768 -205.171548) (xy 313.738417 -205.181709) (xy 313.7306 -205.200469) (xy 313.716181 -205.214792)
			(xy 313.69737 -205.222484) (xy 313.687206 -205.222856) (xy 312.287666 -205.222856) (xy 312.277537 -205.222401)
			(xy 312.258814 -205.214662) (xy 312.244459 -205.200366) (xy 312.236641 -205.181675) (xy 312.236104 -205.171548)
			(xy 306.194968 -205.171548) (xy 306.194617 -205.181709) (xy 306.1868 -205.200469) (xy 306.172381 -205.214792)
			(xy 306.15357 -205.222484) (xy 306.143406 -205.222856) (xy 304.743866 -205.222856) (xy 304.733737 -205.222401)
			(xy 304.715014 -205.214662) (xy 304.700659 -205.200366) (xy 304.692841 -205.181675) (xy 304.692304 -205.171548)
			(xy 298.651168 -205.171548) (xy 298.650817 -205.181709) (xy 298.643 -205.200469) (xy 298.628581 -205.214792)
			(xy 298.60977 -205.222484) (xy 298.599606 -205.222856) (xy 297.200066 -205.222856) (xy 297.189937 -205.222401)
			(xy 297.171214 -205.214662) (xy 297.156859 -205.200366) (xy 297.149041 -205.181675) (xy 297.148504 -205.171548)
			(xy 291.107368 -205.171548) (xy 291.107017 -205.181709) (xy 291.0992 -205.200469) (xy 291.084781 -205.214792)
			(xy 291.06597 -205.222484) (xy 291.055806 -205.222856) (xy 289.656266 -205.222856) (xy 289.646137 -205.222401)
			(xy 289.627414 -205.214662) (xy 289.613059 -205.200366) (xy 289.605241 -205.181675) (xy 289.604704 -205.171548)
			(xy 283.563568 -205.171548) (xy 283.563217 -205.181709) (xy 283.5554 -205.200469) (xy 283.540981 -205.214792)
			(xy 283.52217 -205.222484) (xy 283.512006 -205.222856) (xy 282.112466 -205.222856) (xy 282.102337 -205.222401)
			(xy 282.083614 -205.214662) (xy 282.069259 -205.200366) (xy 282.061441 -205.181675) (xy 282.060904 -205.171548)
			(xy 276.019768 -205.171548) (xy 276.019417 -205.181709) (xy 276.0116 -205.200469) (xy 275.997181 -205.214792)
			(xy 275.97837 -205.222484) (xy 275.968206 -205.222856) (xy 274.568666 -205.222856) (xy 274.558537 -205.222401)
			(xy 274.539814 -205.214662) (xy 274.525459 -205.200366) (xy 274.517641 -205.181675) (xy 274.517104 -205.171548)
			(xy 268.475968 -205.171548) (xy 268.475617 -205.181709) (xy 268.4678 -205.200469) (xy 268.453381 -205.214792)
			(xy 268.43457 -205.222484) (xy 268.424406 -205.222856) (xy 267.024866 -205.222856) (xy 267.014737 -205.222401)
			(xy 266.996014 -205.214662) (xy 266.981659 -205.200366) (xy 266.973841 -205.181675) (xy 266.973304 -205.171548)
			(xy 260.932168 -205.171548) (xy 260.931817 -205.181709) (xy 260.924 -205.200469) (xy 260.909581 -205.214792)
			(xy 260.89077 -205.222484) (xy 260.880606 -205.222856) (xy 259.481066 -205.222856) (xy 259.470937 -205.222401)
			(xy 259.452214 -205.214662) (xy 259.437859 -205.200366) (xy 259.430041 -205.181675) (xy 259.429504 -205.171548)
			(xy 216.4715 -205.171548) (xy 216.471118 -205.181705) (xy 216.463306 -205.200459) (xy 216.448898 -205.21478)
			(xy 216.430098 -205.222478) (xy 216.419938 -205.222856) (xy 215.020398 -205.222856) (xy 215.010271 -205.222375)
			(xy 214.991549 -205.214646) (xy 214.977192 -205.200358) (xy 214.969374 -205.181673) (xy 214.968836 -205.171548)
			(xy 208.9277 -205.171548) (xy 208.927318 -205.181705) (xy 208.919506 -205.200459) (xy 208.905098 -205.21478)
			(xy 208.886298 -205.222478) (xy 208.876138 -205.222856) (xy 207.476598 -205.222856) (xy 207.466471 -205.222375)
			(xy 207.447749 -205.214646) (xy 207.433392 -205.200358) (xy 207.425574 -205.181673) (xy 207.425036 -205.171548)
			(xy 201.3839 -205.171548) (xy 201.383518 -205.181705) (xy 201.375706 -205.200459) (xy 201.361298 -205.21478)
			(xy 201.342498 -205.222478) (xy 201.332338 -205.222856) (xy 199.932798 -205.222856) (xy 199.922671 -205.222375)
			(xy 199.903949 -205.214646) (xy 199.889592 -205.200358) (xy 199.881774 -205.181673) (xy 199.881236 -205.171548)
			(xy 193.8401 -205.171548) (xy 193.839718 -205.181705) (xy 193.831906 -205.200459) (xy 193.817498 -205.21478)
			(xy 193.798698 -205.222478) (xy 193.788538 -205.222856) (xy 192.388998 -205.222856) (xy 192.378871 -205.222375)
			(xy 192.360149 -205.214646) (xy 192.345792 -205.200358) (xy 192.337974 -205.181673) (xy 192.337436 -205.171548)
			(xy 186.2963 -205.171548) (xy 186.295918 -205.181705) (xy 186.288106 -205.200459) (xy 186.273698 -205.21478)
			(xy 186.254898 -205.222478) (xy 186.244738 -205.222856) (xy 184.845198 -205.222856) (xy 184.835071 -205.222375)
			(xy 184.816349 -205.214646) (xy 184.801992 -205.200358) (xy 184.794174 -205.181673) (xy 184.793636 -205.171548)
			(xy 178.7525 -205.171548) (xy 178.752118 -205.181705) (xy 178.744306 -205.200459) (xy 178.729898 -205.21478)
			(xy 178.711098 -205.222478) (xy 178.700938 -205.222856) (xy 177.301398 -205.222856) (xy 177.291271 -205.222375)
			(xy 177.272549 -205.214646) (xy 177.258192 -205.200358) (xy 177.250374 -205.181673) (xy 177.249836 -205.171548)
			(xy 171.2087 -205.171548) (xy 171.208318 -205.181705) (xy 171.200506 -205.200459) (xy 171.186098 -205.21478)
			(xy 171.167298 -205.222478) (xy 171.157138 -205.222856) (xy 169.757598 -205.222856) (xy 169.747471 -205.222375)
			(xy 169.728749 -205.214646) (xy 169.714392 -205.200358) (xy 169.706574 -205.181673) (xy 169.706036 -205.171548)
			(xy 163.6649 -205.171548) (xy 163.664518 -205.181705) (xy 163.656706 -205.200459) (xy 163.642298 -205.21478)
			(xy 163.623498 -205.222478) (xy 163.613338 -205.222856) (xy 162.213798 -205.222856) (xy 162.203671 -205.222375)
			(xy 162.184949 -205.214646) (xy 162.170592 -205.200358) (xy 162.162774 -205.181673) (xy 162.162236 -205.171548)
			(xy 136.988659 -205.171548) (xy 136.993085 -205.181489) (xy 137.039846 -205.306083) (xy 137.079072 -205.433251)
			(xy 137.110622 -205.562537) (xy 137.134385 -205.693478) (xy 137.150274 -205.825606) (xy 137.158232 -205.958448)
			(xy 137.158703 -206.021432) (xy 158.062168 -206.021432) (xy 158.062168 -205.612492) (xy 158.062615 -205.602341)
			(xy 158.070407 -205.583595) (xy 158.084795 -205.569273) (xy 158.103578 -205.561568) (xy 158.11373 -205.561184)
			(xy 159.51327 -205.561184) (xy 159.5234 -205.561652) (xy 159.542129 -205.569378) (xy 159.556488 -205.583671)
			(xy 159.564301 -205.602364) (xy 159.564832 -205.612492) (xy 159.564832 -206.021432) (xy 165.605968 -206.021432)
			(xy 165.605968 -205.612492) (xy 165.606415 -205.602341) (xy 165.614207 -205.583595) (xy 165.628595 -205.569273)
			(xy 165.647378 -205.561568) (xy 165.65753 -205.561184) (xy 167.05707 -205.561184) (xy 167.0672 -205.561652)
			(xy 167.085929 -205.569378) (xy 167.100288 -205.583671) (xy 167.108101 -205.602364) (xy 167.108632 -205.612492)
			(xy 167.108632 -206.021432) (xy 173.149768 -206.021432) (xy 173.149768 -205.612492) (xy 173.150215 -205.602341)
			(xy 173.158007 -205.583595) (xy 173.172395 -205.569273) (xy 173.191178 -205.561568) (xy 173.20133 -205.561184)
			(xy 174.60087 -205.561184) (xy 174.611 -205.561652) (xy 174.629729 -205.569378) (xy 174.644088 -205.583671)
			(xy 174.651901 -205.602364) (xy 174.652432 -205.612492) (xy 174.652432 -206.021432) (xy 180.693568 -206.021432)
			(xy 180.693568 -205.612492) (xy 180.694015 -205.602341) (xy 180.701807 -205.583595) (xy 180.716195 -205.569273)
			(xy 180.734978 -205.561568) (xy 180.74513 -205.561184) (xy 182.14467 -205.561184) (xy 182.1548 -205.561652)
			(xy 182.173529 -205.569378) (xy 182.187888 -205.583671) (xy 182.195701 -205.602364) (xy 182.196232 -205.612492)
			(xy 182.196232 -206.021432) (xy 188.237368 -206.021432) (xy 188.237368 -205.612492) (xy 188.237815 -205.602341)
			(xy 188.245607 -205.583595) (xy 188.259995 -205.569273) (xy 188.278778 -205.561568) (xy 188.28893 -205.561184)
			(xy 189.68847 -205.561184) (xy 189.6986 -205.561652) (xy 189.717329 -205.569378) (xy 189.731688 -205.583671)
			(xy 189.739501 -205.602364) (xy 189.740032 -205.612492) (xy 189.740032 -206.021432) (xy 195.781168 -206.021432)
			(xy 195.781168 -205.612492) (xy 195.781615 -205.602341) (xy 195.789407 -205.583595) (xy 195.803795 -205.569273)
			(xy 195.822578 -205.561568) (xy 195.83273 -205.561184) (xy 197.23227 -205.561184) (xy 197.2424 -205.561652)
			(xy 197.261129 -205.569378) (xy 197.275488 -205.583671) (xy 197.283301 -205.602364) (xy 197.283832 -205.612492)
			(xy 197.283832 -206.021432) (xy 203.324968 -206.021432) (xy 203.324968 -205.612492) (xy 203.325415 -205.602341)
			(xy 203.333207 -205.583595) (xy 203.347595 -205.569273) (xy 203.366378 -205.561568) (xy 203.37653 -205.561184)
			(xy 204.77607 -205.561184) (xy 204.7862 -205.561652) (xy 204.804929 -205.569378) (xy 204.819288 -205.583671)
			(xy 204.827101 -205.602364) (xy 204.827632 -205.612492) (xy 204.827632 -206.021432) (xy 210.868768 -206.021432)
			(xy 210.868768 -205.612492) (xy 210.869215 -205.602341) (xy 210.877007 -205.583595) (xy 210.891395 -205.569273)
			(xy 210.910178 -205.561568) (xy 210.92033 -205.561184) (xy 212.31987 -205.561184) (xy 212.33 -205.561652)
			(xy 212.348729 -205.569378) (xy 212.363088 -205.583671) (xy 212.370901 -205.602364) (xy 212.371432 -205.612492)
			(xy 212.371432 -206.021432) (xy 255.329436 -206.021432) (xy 255.329436 -205.612492) (xy 255.329816 -205.602333)
			(xy 255.337621 -205.583573) (xy 255.352031 -205.569249) (xy 255.370837 -205.561556) (xy 255.380998 -205.561184)
			(xy 256.780538 -205.561184) (xy 256.790673 -205.561597) (xy 256.809403 -205.569345) (xy 256.823759 -205.583654)
			(xy 256.83157 -205.602359) (xy 256.8321 -205.612492) (xy 256.8321 -206.021432) (xy 262.873236 -206.021432)
			(xy 262.873236 -205.612492) (xy 262.873616 -205.602333) (xy 262.881421 -205.583573) (xy 262.895831 -205.569249)
			(xy 262.914637 -205.561556) (xy 262.924798 -205.561184) (xy 264.324338 -205.561184) (xy 264.334473 -205.561597)
			(xy 264.353203 -205.569345) (xy 264.367559 -205.583654) (xy 264.37537 -205.602359) (xy 264.3759 -205.612492)
			(xy 264.3759 -206.021432) (xy 270.417036 -206.021432) (xy 270.417036 -205.612492) (xy 270.417416 -205.602333)
			(xy 270.425221 -205.583573) (xy 270.439631 -205.569249) (xy 270.458437 -205.561556) (xy 270.468598 -205.561184)
			(xy 271.868138 -205.561184) (xy 271.878273 -205.561597) (xy 271.897003 -205.569345) (xy 271.911359 -205.583654)
			(xy 271.91917 -205.602359) (xy 271.9197 -205.612492) (xy 271.9197 -206.021432) (xy 277.960836 -206.021432)
			(xy 277.960836 -205.612492) (xy 277.961216 -205.602333) (xy 277.969021 -205.583573) (xy 277.983431 -205.569249)
			(xy 278.002237 -205.561556) (xy 278.012398 -205.561184) (xy 279.411938 -205.561184) (xy 279.422073 -205.561597)
			(xy 279.440803 -205.569345) (xy 279.455159 -205.583654) (xy 279.46297 -205.602359) (xy 279.4635 -205.612492)
			(xy 279.4635 -206.021432) (xy 285.504636 -206.021432) (xy 285.504636 -205.612492) (xy 285.505016 -205.602333)
			(xy 285.512821 -205.583573) (xy 285.527231 -205.569249) (xy 285.546037 -205.561556) (xy 285.556198 -205.561184)
			(xy 286.955738 -205.561184) (xy 286.965873 -205.561597) (xy 286.984603 -205.569345) (xy 286.998959 -205.583654)
			(xy 287.00677 -205.602359) (xy 287.0073 -205.612492) (xy 287.0073 -206.021432) (xy 293.048436 -206.021432)
			(xy 293.048436 -205.612492) (xy 293.048816 -205.602333) (xy 293.056621 -205.583573) (xy 293.071031 -205.569249)
			(xy 293.089837 -205.561556) (xy 293.099998 -205.561184) (xy 294.499538 -205.561184) (xy 294.509673 -205.561597)
			(xy 294.528403 -205.569345) (xy 294.542759 -205.583654) (xy 294.55057 -205.602359) (xy 294.5511 -205.612492)
			(xy 294.5511 -206.021432) (xy 300.592236 -206.021432) (xy 300.592236 -205.612492) (xy 300.592616 -205.602333)
			(xy 300.600421 -205.583573) (xy 300.614831 -205.569249) (xy 300.633637 -205.561556) (xy 300.643798 -205.561184)
			(xy 302.043338 -205.561184) (xy 302.053473 -205.561597) (xy 302.072203 -205.569345) (xy 302.086559 -205.583654)
			(xy 302.09437 -205.602359) (xy 302.0949 -205.612492) (xy 302.0949 -206.021432) (xy 308.136036 -206.021432)
			(xy 308.136036 -205.612492) (xy 308.136416 -205.602333) (xy 308.144221 -205.583573) (xy 308.158631 -205.569249)
			(xy 308.177437 -205.561556) (xy 308.187598 -205.561184) (xy 309.587138 -205.561184) (xy 309.597273 -205.561597)
			(xy 309.616003 -205.569345) (xy 309.630359 -205.583654) (xy 309.63817 -205.602359) (xy 309.6387 -205.612492)
			(xy 309.6387 -206.021432) (xy 309.638562 -206.024988) (xy 334.640692 -206.024988) (xy 334.644673 -205.891968)
			(xy 334.656602 -205.759423) (xy 334.676437 -205.62783) (xy 334.704106 -205.497658) (xy 334.73951 -205.369373)
			(xy 334.782523 -205.243436) (xy 334.83299 -205.120297) (xy 334.890731 -205.000396) (xy 334.95554 -204.884163)
			(xy 335.027184 -204.772013) (xy 335.105406 -204.664349) (xy 335.189927 -204.561556) (xy 335.280445 -204.464001)
			(xy 335.376634 -204.372035) (xy 335.478152 -204.285985) (xy 335.584633 -204.206161) (xy 335.695698 -204.132848)
			(xy 335.810949 -204.066308) (xy 335.929973 -204.006779) (xy 336.052344 -203.954475) (xy 336.177623 -203.909583)
			(xy 336.305364 -203.872264) (xy 336.435107 -203.842651) (xy 336.566389 -203.82085) (xy 336.69874 -203.80694)
			(xy 336.831686 -203.800969) (xy 336.964751 -203.80296) (xy 337.097459 -203.812905) (xy 337.229335 -203.830769)
			(xy 337.359906 -203.856487) (xy 337.488706 -203.889968) (xy 337.615272 -203.931092) (xy 337.739153 -203.979712)
			(xy 337.859904 -204.035653) (xy 337.977094 -204.098715) (xy 338.090303 -204.168673) (xy 338.199125 -204.245277)
			(xy 338.303171 -204.328251) (xy 338.402069 -204.417299) (xy 338.495464 -204.512102) (xy 338.583022 -204.61232)
			(xy 338.664431 -204.717596) (xy 338.739397 -204.827552) (xy 338.807654 -204.941794) (xy 338.868956 -205.059914)
			(xy 338.923085 -205.181489) (xy 338.969846 -205.306083) (xy 339.009072 -205.433251) (xy 339.040622 -205.562537)
			(xy 339.064385 -205.693478) (xy 339.080274 -205.825606) (xy 339.088232 -205.958448) (xy 339.08873 -206.024988)
			(xy 380.650506 -206.024988) (xy 380.654487 -205.891968) (xy 380.666416 -205.759423) (xy 380.686251 -205.62783)
			(xy 380.71392 -205.497658) (xy 380.749324 -205.369373) (xy 380.792337 -205.243436) (xy 380.842804 -205.120297)
			(xy 380.900545 -205.000396) (xy 380.965354 -204.884163) (xy 381.036998 -204.772013) (xy 381.11522 -204.664349)
			(xy 381.199741 -204.561556) (xy 381.290259 -204.464001) (xy 381.386448 -204.372035) (xy 381.487966 -204.285985)
			(xy 381.594447 -204.206161) (xy 381.705512 -204.132848) (xy 381.820763 -204.066308) (xy 381.939787 -204.006779)
			(xy 382.062158 -203.954475) (xy 382.187437 -203.909583) (xy 382.315178 -203.872264) (xy 382.444921 -203.842651)
			(xy 382.576203 -203.82085) (xy 382.708554 -203.80694) (xy 382.8415 -203.800969) (xy 382.974565 -203.80296)
			(xy 383.107273 -203.812905) (xy 383.239149 -203.830769) (xy 383.36972 -203.856487) (xy 383.49852 -203.889968)
			(xy 383.625086 -203.931092) (xy 383.748967 -203.979712) (xy 383.869718 -204.035653) (xy 383.986908 -204.098715)
			(xy 384.100117 -204.168673) (xy 384.208939 -204.245277) (xy 384.304407 -204.32141) (xy 406.002236 -204.32141)
			(xy 406.002236 -203.91247) (xy 406.002709 -203.902311) (xy 406.010493 -203.883541) (xy 406.024865 -203.869177)
			(xy 406.043638 -203.861403) (xy 406.053798 -203.860908) (xy 407.453338 -203.860908) (xy 407.463495 -203.861402)
			(xy 407.482259 -203.869183) (xy 407.496622 -203.883548) (xy 407.5044 -203.902313) (xy 407.5049 -203.91247)
			(xy 407.5049 -204.32141) (xy 413.546036 -204.32141) (xy 413.546036 -203.91247) (xy 413.546509 -203.902311)
			(xy 413.554293 -203.883541) (xy 413.568665 -203.869177) (xy 413.587438 -203.861403) (xy 413.597598 -203.860908)
			(xy 414.997138 -203.860908) (xy 415.007295 -203.861402) (xy 415.026059 -203.869183) (xy 415.040422 -203.883548)
			(xy 415.0482 -203.902313) (xy 415.0487 -203.91247) (xy 415.0487 -204.32141) (xy 421.089836 -204.32141)
			(xy 421.089836 -203.91247) (xy 421.090309 -203.902311) (xy 421.098093 -203.883541) (xy 421.112465 -203.869177)
			(xy 421.131238 -203.861403) (xy 421.141398 -203.860908) (xy 422.540938 -203.860908) (xy 422.551095 -203.861402)
			(xy 422.569859 -203.869183) (xy 422.584222 -203.883548) (xy 422.592 -203.902313) (xy 422.5925 -203.91247)
			(xy 422.5925 -204.32141) (xy 428.633636 -204.32141) (xy 428.633636 -203.91247) (xy 428.634109 -203.902311)
			(xy 428.641893 -203.883541) (xy 428.656265 -203.869177) (xy 428.675038 -203.861403) (xy 428.685198 -203.860908)
			(xy 430.084738 -203.860908) (xy 430.094895 -203.861402) (xy 430.113659 -203.869183) (xy 430.128022 -203.883548)
			(xy 430.1358 -203.902313) (xy 430.1363 -203.91247) (xy 430.1363 -204.32141) (xy 436.177436 -204.32141)
			(xy 436.177436 -203.91247) (xy 436.177909 -203.902311) (xy 436.185693 -203.883541) (xy 436.200065 -203.869177)
			(xy 436.218838 -203.861403) (xy 436.228998 -203.860908) (xy 437.628538 -203.860908) (xy 437.638695 -203.861402)
			(xy 437.657459 -203.869183) (xy 437.671822 -203.883548) (xy 437.6796 -203.902313) (xy 437.6801 -203.91247)
			(xy 437.6801 -204.32141) (xy 443.721236 -204.32141) (xy 443.721236 -203.91247) (xy 443.721709 -203.902311)
			(xy 443.729493 -203.883541) (xy 443.743865 -203.869177) (xy 443.762638 -203.861403) (xy 443.772798 -203.860908)
			(xy 445.172338 -203.860908) (xy 445.182495 -203.861402) (xy 445.201259 -203.869183) (xy 445.215622 -203.883548)
			(xy 445.2234 -203.902313) (xy 445.2239 -203.91247) (xy 445.2239 -204.32141) (xy 451.265036 -204.32141)
			(xy 451.265036 -203.91247) (xy 451.265509 -203.902311) (xy 451.273293 -203.883541) (xy 451.287665 -203.869177)
			(xy 451.306438 -203.861403) (xy 451.316598 -203.860908) (xy 452.716138 -203.860908) (xy 452.726295 -203.861402)
			(xy 452.745059 -203.869183) (xy 452.759422 -203.883548) (xy 452.7672 -203.902313) (xy 452.7677 -203.91247)
			(xy 452.7677 -204.32141) (xy 458.808836 -204.32141) (xy 458.808836 -203.91247) (xy 458.809309 -203.902311)
			(xy 458.817093 -203.883541) (xy 458.831465 -203.869177) (xy 458.850238 -203.861403) (xy 458.860398 -203.860908)
			(xy 460.259938 -203.860908) (xy 460.270095 -203.861402) (xy 460.288859 -203.869183) (xy 460.303222 -203.883548)
			(xy 460.311 -203.902313) (xy 460.3115 -203.91247) (xy 460.3115 -204.32141) (xy 460.310976 -204.331564)
			(xy 460.303205 -204.350326) (xy 460.288849 -204.364689) (xy 460.270091 -204.37247) (xy 460.259938 -204.372972)
			(xy 458.860398 -204.372972) (xy 458.850241 -204.372468) (xy 458.831474 -204.364695) (xy 458.817109 -204.350333)
			(xy 458.809333 -204.331567) (xy 458.808836 -204.32141) (xy 452.7677 -204.32141) (xy 452.767176 -204.331564)
			(xy 452.759405 -204.350326) (xy 452.745049 -204.364689) (xy 452.726291 -204.37247) (xy 452.716138 -204.372972)
			(xy 451.316598 -204.372972) (xy 451.306441 -204.372468) (xy 451.287674 -204.364695) (xy 451.273309 -204.350333)
			(xy 451.265533 -204.331567) (xy 451.265036 -204.32141) (xy 445.2239 -204.32141) (xy 445.223376 -204.331564)
			(xy 445.215605 -204.350326) (xy 445.201249 -204.364689) (xy 445.182491 -204.37247) (xy 445.172338 -204.372972)
			(xy 443.772798 -204.372972) (xy 443.762641 -204.372468) (xy 443.743874 -204.364695) (xy 443.729509 -204.350333)
			(xy 443.721733 -204.331567) (xy 443.721236 -204.32141) (xy 437.6801 -204.32141) (xy 437.679576 -204.331564)
			(xy 437.671805 -204.350326) (xy 437.657449 -204.364689) (xy 437.638691 -204.37247) (xy 437.628538 -204.372972)
			(xy 436.228998 -204.372972) (xy 436.218841 -204.372468) (xy 436.200074 -204.364695) (xy 436.185709 -204.350333)
			(xy 436.177933 -204.331567) (xy 436.177436 -204.32141) (xy 430.1363 -204.32141) (xy 430.135776 -204.331564)
			(xy 430.128005 -204.350326) (xy 430.113649 -204.364689) (xy 430.094891 -204.37247) (xy 430.084738 -204.372972)
			(xy 428.685198 -204.372972) (xy 428.675041 -204.372468) (xy 428.656274 -204.364695) (xy 428.641909 -204.350333)
			(xy 428.634133 -204.331567) (xy 428.633636 -204.32141) (xy 422.5925 -204.32141) (xy 422.591976 -204.331564)
			(xy 422.584205 -204.350326) (xy 422.569849 -204.364689) (xy 422.551091 -204.37247) (xy 422.540938 -204.372972)
			(xy 421.141398 -204.372972) (xy 421.131241 -204.372468) (xy 421.112474 -204.364695) (xy 421.098109 -204.350333)
			(xy 421.090333 -204.331567) (xy 421.089836 -204.32141) (xy 415.0487 -204.32141) (xy 415.048176 -204.331564)
			(xy 415.040405 -204.350326) (xy 415.026049 -204.364689) (xy 415.007291 -204.37247) (xy 414.997138 -204.372972)
			(xy 413.597598 -204.372972) (xy 413.587441 -204.372468) (xy 413.568674 -204.364695) (xy 413.554309 -204.350333)
			(xy 413.546533 -204.331567) (xy 413.546036 -204.32141) (xy 407.5049 -204.32141) (xy 407.504376 -204.331564)
			(xy 407.496605 -204.350326) (xy 407.482249 -204.364689) (xy 407.463491 -204.37247) (xy 407.453338 -204.372972)
			(xy 406.053798 -204.372972) (xy 406.043641 -204.372468) (xy 406.024874 -204.364695) (xy 406.010509 -204.350333)
			(xy 406.002733 -204.331567) (xy 406.002236 -204.32141) (xy 384.304407 -204.32141) (xy 384.312985 -204.328251)
			(xy 384.411883 -204.417299) (xy 384.505278 -204.512102) (xy 384.592836 -204.61232) (xy 384.674245 -204.717596)
			(xy 384.749211 -204.827552) (xy 384.817468 -204.941794) (xy 384.87877 -205.059914) (xy 384.928473 -205.171548)
			(xy 410.102304 -205.171548) (xy 410.102304 -204.762608) (xy 410.102728 -204.752454) (xy 410.110522 -204.733701)
			(xy 410.124918 -204.719377) (xy 410.14371 -204.711678) (xy 410.153866 -204.7113) (xy 411.553406 -204.7113)
			(xy 411.563528 -204.711821) (xy 411.582242 -204.719543) (xy 411.596596 -204.733818) (xy 411.604422 -204.752489)
			(xy 411.604968 -204.762608) (xy 411.604968 -205.171548) (xy 417.646104 -205.171548) (xy 417.646104 -204.762608)
			(xy 417.646528 -204.752454) (xy 417.654322 -204.733701) (xy 417.668718 -204.719377) (xy 417.68751 -204.711678)
			(xy 417.697666 -204.7113) (xy 419.097206 -204.7113) (xy 419.107328 -204.711821) (xy 419.126042 -204.719543)
			(xy 419.140396 -204.733818) (xy 419.148222 -204.752489) (xy 419.148768 -204.762608) (xy 419.148768 -205.171548)
			(xy 425.189904 -205.171548) (xy 425.189904 -204.762608) (xy 425.190328 -204.752454) (xy 425.198122 -204.733701)
			(xy 425.212518 -204.719377) (xy 425.23131 -204.711678) (xy 425.241466 -204.7113) (xy 426.641006 -204.7113)
			(xy 426.651128 -204.711821) (xy 426.669842 -204.719543) (xy 426.684196 -204.733818) (xy 426.692022 -204.752489)
			(xy 426.692568 -204.762608) (xy 426.692568 -205.171548) (xy 432.733704 -205.171548) (xy 432.733704 -204.762608)
			(xy 432.734128 -204.752454) (xy 432.741922 -204.733701) (xy 432.756318 -204.719377) (xy 432.77511 -204.711678)
			(xy 432.785266 -204.7113) (xy 434.184806 -204.7113) (xy 434.194928 -204.711821) (xy 434.213642 -204.719543)
			(xy 434.227996 -204.733818) (xy 434.235822 -204.752489) (xy 434.236368 -204.762608) (xy 434.236368 -205.171548)
			(xy 440.277504 -205.171548) (xy 440.277504 -204.762608) (xy 440.277928 -204.752454) (xy 440.285722 -204.733701)
			(xy 440.300118 -204.719377) (xy 440.31891 -204.711678) (xy 440.329066 -204.7113) (xy 441.728606 -204.7113)
			(xy 441.738728 -204.711821) (xy 441.757442 -204.719543) (xy 441.771796 -204.733818) (xy 441.779622 -204.752489)
			(xy 441.780168 -204.762608) (xy 441.780168 -205.171548) (xy 447.821304 -205.171548) (xy 447.821304 -204.762608)
			(xy 447.821728 -204.752454) (xy 447.829522 -204.733701) (xy 447.843918 -204.719377) (xy 447.86271 -204.711678)
			(xy 447.872866 -204.7113) (xy 449.272406 -204.7113) (xy 449.282528 -204.711821) (xy 449.301242 -204.719543)
			(xy 449.315596 -204.733818) (xy 449.323422 -204.752489) (xy 449.323968 -204.762608) (xy 449.323968 -205.171548)
			(xy 455.365104 -205.171548) (xy 455.365104 -204.762608) (xy 455.365528 -204.752454) (xy 455.373322 -204.733701)
			(xy 455.387718 -204.719377) (xy 455.40651 -204.711678) (xy 455.416666 -204.7113) (xy 456.816206 -204.7113)
			(xy 456.826328 -204.711821) (xy 456.845042 -204.719543) (xy 456.859396 -204.733818) (xy 456.867222 -204.752489)
			(xy 456.867768 -204.762608) (xy 456.867768 -205.171548) (xy 462.908904 -205.171548) (xy 462.908904 -204.762608)
			(xy 462.909328 -204.752454) (xy 462.917122 -204.733701) (xy 462.931518 -204.719377) (xy 462.95031 -204.711678)
			(xy 462.960466 -204.7113) (xy 464.360006 -204.7113) (xy 464.370128 -204.711821) (xy 464.388842 -204.719543)
			(xy 464.403196 -204.733818) (xy 464.411022 -204.752489) (xy 464.411568 -204.762608) (xy 464.411568 -205.171548)
			(xy 464.411217 -205.181709) (xy 464.4034 -205.200469) (xy 464.388981 -205.214792) (xy 464.37017 -205.222484)
			(xy 464.360006 -205.222856) (xy 462.960466 -205.222856) (xy 462.950337 -205.222401) (xy 462.931614 -205.214662)
			(xy 462.917259 -205.200366) (xy 462.909441 -205.181675) (xy 462.908904 -205.171548) (xy 456.867768 -205.171548)
			(xy 456.867417 -205.181709) (xy 456.8596 -205.200469) (xy 456.845181 -205.214792) (xy 456.82637 -205.222484)
			(xy 456.816206 -205.222856) (xy 455.416666 -205.222856) (xy 455.406537 -205.222401) (xy 455.387814 -205.214662)
			(xy 455.373459 -205.200366) (xy 455.365641 -205.181675) (xy 455.365104 -205.171548) (xy 449.323968 -205.171548)
			(xy 449.323617 -205.181709) (xy 449.3158 -205.200469) (xy 449.301381 -205.214792) (xy 449.28257 -205.222484)
			(xy 449.272406 -205.222856) (xy 447.872866 -205.222856) (xy 447.862737 -205.222401) (xy 447.844014 -205.214662)
			(xy 447.829659 -205.200366) (xy 447.821841 -205.181675) (xy 447.821304 -205.171548) (xy 441.780168 -205.171548)
			(xy 441.779817 -205.181709) (xy 441.772 -205.200469) (xy 441.757581 -205.214792) (xy 441.73877 -205.222484)
			(xy 441.728606 -205.222856) (xy 440.329066 -205.222856) (xy 440.318937 -205.222401) (xy 440.300214 -205.214662)
			(xy 440.285859 -205.200366) (xy 440.278041 -205.181675) (xy 440.277504 -205.171548) (xy 434.236368 -205.171548)
			(xy 434.236017 -205.181709) (xy 434.2282 -205.200469) (xy 434.213781 -205.214792) (xy 434.19497 -205.222484)
			(xy 434.184806 -205.222856) (xy 432.785266 -205.222856) (xy 432.775137 -205.222401) (xy 432.756414 -205.214662)
			(xy 432.742059 -205.200366) (xy 432.734241 -205.181675) (xy 432.733704 -205.171548) (xy 426.692568 -205.171548)
			(xy 426.692217 -205.181709) (xy 426.6844 -205.200469) (xy 426.669981 -205.214792) (xy 426.65117 -205.222484)
			(xy 426.641006 -205.222856) (xy 425.241466 -205.222856) (xy 425.231337 -205.222401) (xy 425.212614 -205.214662)
			(xy 425.198259 -205.200366) (xy 425.190441 -205.181675) (xy 425.189904 -205.171548) (xy 419.148768 -205.171548)
			(xy 419.148417 -205.181709) (xy 419.1406 -205.200469) (xy 419.126181 -205.214792) (xy 419.10737 -205.222484)
			(xy 419.097206 -205.222856) (xy 417.697666 -205.222856) (xy 417.687537 -205.222401) (xy 417.668814 -205.214662)
			(xy 417.654459 -205.200366) (xy 417.646641 -205.181675) (xy 417.646104 -205.171548) (xy 411.604968 -205.171548)
			(xy 411.604617 -205.181709) (xy 411.5968 -205.200469) (xy 411.582381 -205.214792) (xy 411.56357 -205.222484)
			(xy 411.553406 -205.222856) (xy 410.153866 -205.222856) (xy 410.143737 -205.222401) (xy 410.125014 -205.214662)
			(xy 410.110659 -205.200366) (xy 410.102841 -205.181675) (xy 410.102304 -205.171548) (xy 384.928473 -205.171548)
			(xy 384.932899 -205.181489) (xy 384.97966 -205.306083) (xy 385.018886 -205.433251) (xy 385.050436 -205.562537)
			(xy 385.074199 -205.693478) (xy 385.090088 -205.825606) (xy 385.098046 -205.958448) (xy 385.098517 -206.021432)
			(xy 406.002236 -206.021432) (xy 406.002236 -205.612492) (xy 406.002616 -205.602333) (xy 406.010421 -205.583573)
			(xy 406.024831 -205.569249) (xy 406.043637 -205.561556) (xy 406.053798 -205.561184) (xy 407.453338 -205.561184)
			(xy 407.463473 -205.561597) (xy 407.482203 -205.569345) (xy 407.496559 -205.583654) (xy 407.50437 -205.602359)
			(xy 407.5049 -205.612492) (xy 407.5049 -206.021432) (xy 413.546036 -206.021432) (xy 413.546036 -205.612492)
			(xy 413.546416 -205.602333) (xy 413.554221 -205.583573) (xy 413.568631 -205.569249) (xy 413.587437 -205.561556)
			(xy 413.597598 -205.561184) (xy 414.997138 -205.561184) (xy 415.007273 -205.561597) (xy 415.026003 -205.569345)
			(xy 415.040359 -205.583654) (xy 415.04817 -205.602359) (xy 415.0487 -205.612492) (xy 415.0487 -206.021432)
			(xy 421.089836 -206.021432) (xy 421.089836 -205.612492) (xy 421.090216 -205.602333) (xy 421.098021 -205.583573)
			(xy 421.112431 -205.569249) (xy 421.131237 -205.561556) (xy 421.141398 -205.561184) (xy 422.540938 -205.561184)
			(xy 422.551073 -205.561597) (xy 422.569803 -205.569345) (xy 422.584159 -205.583654) (xy 422.59197 -205.602359)
			(xy 422.5925 -205.612492) (xy 422.5925 -206.021432) (xy 428.633636 -206.021432) (xy 428.633636 -205.612492)
			(xy 428.634016 -205.602333) (xy 428.641821 -205.583573) (xy 428.656231 -205.569249) (xy 428.675037 -205.561556)
			(xy 428.685198 -205.561184) (xy 430.084738 -205.561184) (xy 430.094873 -205.561597) (xy 430.113603 -205.569345)
			(xy 430.127959 -205.583654) (xy 430.13577 -205.602359) (xy 430.1363 -205.612492) (xy 430.1363 -206.021432)
			(xy 436.177436 -206.021432) (xy 436.177436 -205.612492) (xy 436.177816 -205.602333) (xy 436.185621 -205.583573)
			(xy 436.200031 -205.569249) (xy 436.218837 -205.561556) (xy 436.228998 -205.561184) (xy 437.628538 -205.561184)
			(xy 437.638673 -205.561597) (xy 437.657403 -205.569345) (xy 437.671759 -205.583654) (xy 437.67957 -205.602359)
			(xy 437.6801 -205.612492) (xy 437.6801 -206.021432) (xy 443.721236 -206.021432) (xy 443.721236 -205.612492)
			(xy 443.721616 -205.602333) (xy 443.729421 -205.583573) (xy 443.743831 -205.569249) (xy 443.762637 -205.561556)
			(xy 443.772798 -205.561184) (xy 445.172338 -205.561184) (xy 445.182473 -205.561597) (xy 445.201203 -205.569345)
			(xy 445.215559 -205.583654) (xy 445.22337 -205.602359) (xy 445.2239 -205.612492) (xy 445.2239 -206.021432)
			(xy 451.265036 -206.021432) (xy 451.265036 -205.612492) (xy 451.265416 -205.602333) (xy 451.273221 -205.583573)
			(xy 451.287631 -205.569249) (xy 451.306437 -205.561556) (xy 451.316598 -205.561184) (xy 452.716138 -205.561184)
			(xy 452.726273 -205.561597) (xy 452.745003 -205.569345) (xy 452.759359 -205.583654) (xy 452.76717 -205.602359)
			(xy 452.7677 -205.612492) (xy 452.7677 -206.021432) (xy 458.808836 -206.021432) (xy 458.808836 -205.612492)
			(xy 458.809216 -205.602333) (xy 458.817021 -205.583573) (xy 458.831431 -205.569249) (xy 458.850237 -205.561556)
			(xy 458.860398 -205.561184) (xy 460.259938 -205.561184) (xy 460.270073 -205.561597) (xy 460.288803 -205.569345)
			(xy 460.303159 -205.583654) (xy 460.31097 -205.602359) (xy 460.3115 -205.612492) (xy 460.3115 -206.021432)
			(xy 460.311105 -206.031588) (xy 460.303298 -206.050341) (xy 460.288894 -206.064664) (xy 460.270097 -206.072362)
			(xy 460.259938 -206.07274) (xy 458.860398 -206.07274) (xy 458.850269 -206.072274) (xy 458.831544 -206.064542)
			(xy 458.817187 -206.050249) (xy 458.809371 -206.031559) (xy 458.808836 -206.021432) (xy 452.7677 -206.021432)
			(xy 452.767305 -206.031588) (xy 452.759498 -206.050341) (xy 452.745094 -206.064664) (xy 452.726297 -206.072362)
			(xy 452.716138 -206.07274) (xy 451.316598 -206.07274) (xy 451.306469 -206.072274) (xy 451.287744 -206.064542)
			(xy 451.273387 -206.050249) (xy 451.265571 -206.031559) (xy 451.265036 -206.021432) (xy 445.2239 -206.021432)
			(xy 445.223505 -206.031588) (xy 445.215698 -206.050341) (xy 445.201294 -206.064664) (xy 445.182497 -206.072362)
			(xy 445.172338 -206.07274) (xy 443.772798 -206.07274) (xy 443.762669 -206.072274) (xy 443.743944 -206.064542)
			(xy 443.729587 -206.050249) (xy 443.721771 -206.031559) (xy 443.721236 -206.021432) (xy 437.6801 -206.021432)
			(xy 437.679705 -206.031588) (xy 437.671898 -206.050341) (xy 437.657494 -206.064664) (xy 437.638697 -206.072362)
			(xy 437.628538 -206.07274) (xy 436.228998 -206.07274) (xy 436.218869 -206.072274) (xy 436.200144 -206.064542)
			(xy 436.185787 -206.050249) (xy 436.177971 -206.031559) (xy 436.177436 -206.021432) (xy 430.1363 -206.021432)
			(xy 430.135905 -206.031588) (xy 430.128098 -206.050341) (xy 430.113694 -206.064664) (xy 430.094897 -206.072362)
			(xy 430.084738 -206.07274) (xy 428.685198 -206.07274) (xy 428.675069 -206.072274) (xy 428.656344 -206.064542)
			(xy 428.641987 -206.050249) (xy 428.634171 -206.031559) (xy 428.633636 -206.021432) (xy 422.5925 -206.021432)
			(xy 422.592105 -206.031588) (xy 422.584298 -206.050341) (xy 422.569894 -206.064664) (xy 422.551097 -206.072362)
			(xy 422.540938 -206.07274) (xy 421.141398 -206.07274) (xy 421.131269 -206.072274) (xy 421.112544 -206.064542)
			(xy 421.098187 -206.050249) (xy 421.090371 -206.031559) (xy 421.089836 -206.021432) (xy 415.0487 -206.021432)
			(xy 415.048305 -206.031588) (xy 415.040498 -206.050341) (xy 415.026094 -206.064664) (xy 415.007297 -206.072362)
			(xy 414.997138 -206.07274) (xy 413.597598 -206.07274) (xy 413.587469 -206.072274) (xy 413.568744 -206.064542)
			(xy 413.554387 -206.050249) (xy 413.546571 -206.031559) (xy 413.546036 -206.021432) (xy 407.5049 -206.021432)
			(xy 407.504505 -206.031588) (xy 407.496698 -206.050341) (xy 407.482294 -206.064664) (xy 407.463497 -206.072362)
			(xy 407.453338 -206.07274) (xy 406.053798 -206.07274) (xy 406.043669 -206.072274) (xy 406.024944 -206.064542)
			(xy 406.010587 -206.050249) (xy 406.002771 -206.031559) (xy 406.002236 -206.021432) (xy 385.098517 -206.021432)
			(xy 385.098544 -206.024988) (xy 385.098046 -206.091528) (xy 385.090088 -206.22437) (xy 385.074199 -206.356498)
			(xy 385.050436 -206.487439) (xy 385.018886 -206.616725) (xy 384.97966 -206.743893) (xy 384.932899 -206.868487)
			(xy 384.931639 -206.871316) (xy 410.102304 -206.871316) (xy 410.102304 -206.462376) (xy 410.102702 -206.45222)
			(xy 410.110506 -206.433466) (xy 410.12491 -206.419143) (xy 410.143708 -206.411445) (xy 410.153866 -206.411068)
			(xy 411.553406 -206.411068) (xy 411.563537 -206.411523) (xy 411.582263 -206.419258) (xy 411.59662 -206.433554)
			(xy 411.604434 -206.452248) (xy 411.604968 -206.462376) (xy 411.604968 -206.871316) (xy 417.646104 -206.871316)
			(xy 417.646104 -206.462376) (xy 417.646502 -206.45222) (xy 417.654306 -206.433466) (xy 417.66871 -206.419143)
			(xy 417.687508 -206.411445) (xy 417.697666 -206.411068) (xy 419.097206 -206.411068) (xy 419.107337 -206.411523)
			(xy 419.126063 -206.419258) (xy 419.14042 -206.433554) (xy 419.148234 -206.452248) (xy 419.148768 -206.462376)
			(xy 419.148768 -206.871316) (xy 425.189904 -206.871316) (xy 425.189904 -206.462376) (xy 425.190302 -206.45222)
			(xy 425.198106 -206.433466) (xy 425.21251 -206.419143) (xy 425.231308 -206.411445) (xy 425.241466 -206.411068)
			(xy 426.641006 -206.411068) (xy 426.651137 -206.411523) (xy 426.669863 -206.419258) (xy 426.68422 -206.433554)
			(xy 426.692034 -206.452248) (xy 426.692568 -206.462376) (xy 426.692568 -206.871316) (xy 432.733704 -206.871316)
			(xy 432.733704 -206.462376) (xy 432.734102 -206.45222) (xy 432.741906 -206.433466) (xy 432.75631 -206.419143)
			(xy 432.775108 -206.411445) (xy 432.785266 -206.411068) (xy 434.184806 -206.411068) (xy 434.194937 -206.411523)
			(xy 434.213663 -206.419258) (xy 434.22802 -206.433554) (xy 434.235834 -206.452248) (xy 434.236368 -206.462376)
			(xy 434.236368 -206.871316) (xy 440.277504 -206.871316) (xy 440.277504 -206.462376) (xy 440.277902 -206.45222)
			(xy 440.285706 -206.433466) (xy 440.30011 -206.419143) (xy 440.318908 -206.411445) (xy 440.329066 -206.411068)
			(xy 441.728606 -206.411068) (xy 441.738737 -206.411523) (xy 441.757463 -206.419258) (xy 441.77182 -206.433554)
			(xy 441.779634 -206.452248) (xy 441.780168 -206.462376) (xy 441.780168 -206.871316) (xy 447.821304 -206.871316)
			(xy 447.821304 -206.462376) (xy 447.821702 -206.45222) (xy 447.829506 -206.433466) (xy 447.84391 -206.419143)
			(xy 447.862708 -206.411445) (xy 447.872866 -206.411068) (xy 449.272406 -206.411068) (xy 449.282537 -206.411523)
			(xy 449.301263 -206.419258) (xy 449.31562 -206.433554) (xy 449.323434 -206.452248) (xy 449.323968 -206.462376)
			(xy 449.323968 -206.871316) (xy 455.365104 -206.871316) (xy 455.365104 -206.462376) (xy 455.365502 -206.45222)
			(xy 455.373306 -206.433466) (xy 455.38771 -206.419143) (xy 455.406508 -206.411445) (xy 455.416666 -206.411068)
			(xy 456.816206 -206.411068) (xy 456.826337 -206.411523) (xy 456.845063 -206.419258) (xy 456.85942 -206.433554)
			(xy 456.867234 -206.452248) (xy 456.867768 -206.462376) (xy 456.867768 -206.871316) (xy 462.908904 -206.871316)
			(xy 462.908904 -206.462376) (xy 462.909302 -206.45222) (xy 462.917106 -206.433466) (xy 462.93151 -206.419143)
			(xy 462.950308 -206.411445) (xy 462.960466 -206.411068) (xy 464.360006 -206.411068) (xy 464.370137 -206.411523)
			(xy 464.388863 -206.419258) (xy 464.40322 -206.433554) (xy 464.411034 -206.452248) (xy 464.411568 -206.462376)
			(xy 464.411568 -206.871316) (xy 464.411191 -206.881475) (xy 464.403384 -206.900234) (xy 464.388973 -206.914558)
			(xy 464.370168 -206.922252) (xy 464.360006 -206.922624) (xy 462.960466 -206.922624) (xy 462.950333 -206.9222)
			(xy 462.931604 -206.914455) (xy 462.917248 -206.900149) (xy 462.909436 -206.881447) (xy 462.908904 -206.871316)
			(xy 456.867768 -206.871316) (xy 456.867391 -206.881475) (xy 456.859584 -206.900234) (xy 456.845173 -206.914558)
			(xy 456.826368 -206.922252) (xy 456.816206 -206.922624) (xy 455.416666 -206.922624) (xy 455.406533 -206.9222)
			(xy 455.387804 -206.914455) (xy 455.373448 -206.900149) (xy 455.365636 -206.881447) (xy 455.365104 -206.871316)
			(xy 449.323968 -206.871316) (xy 449.323591 -206.881475) (xy 449.315784 -206.900234) (xy 449.301373 -206.914558)
			(xy 449.282568 -206.922252) (xy 449.272406 -206.922624) (xy 447.872866 -206.922624) (xy 447.862733 -206.9222)
			(xy 447.844004 -206.914455) (xy 447.829648 -206.900149) (xy 447.821836 -206.881447) (xy 447.821304 -206.871316)
			(xy 441.780168 -206.871316) (xy 441.779791 -206.881475) (xy 441.771984 -206.900234) (xy 441.757573 -206.914558)
			(xy 441.738768 -206.922252) (xy 441.728606 -206.922624) (xy 440.329066 -206.922624) (xy 440.318933 -206.9222)
			(xy 440.300204 -206.914455) (xy 440.285848 -206.900149) (xy 440.278036 -206.881447) (xy 440.277504 -206.871316)
			(xy 434.236368 -206.871316) (xy 434.235991 -206.881475) (xy 434.228184 -206.900234) (xy 434.213773 -206.914558)
			(xy 434.194968 -206.922252) (xy 434.184806 -206.922624) (xy 432.785266 -206.922624) (xy 432.775133 -206.9222)
			(xy 432.756404 -206.914455) (xy 432.742048 -206.900149) (xy 432.734236 -206.881447) (xy 432.733704 -206.871316)
			(xy 426.692568 -206.871316) (xy 426.692191 -206.881475) (xy 426.684384 -206.900234) (xy 426.669973 -206.914558)
			(xy 426.651168 -206.922252) (xy 426.641006 -206.922624) (xy 425.241466 -206.922624) (xy 425.231333 -206.9222)
			(xy 425.212604 -206.914455) (xy 425.198248 -206.900149) (xy 425.190436 -206.881447) (xy 425.189904 -206.871316)
			(xy 419.148768 -206.871316) (xy 419.148391 -206.881475) (xy 419.140584 -206.900234) (xy 419.126173 -206.914558)
			(xy 419.107368 -206.922252) (xy 419.097206 -206.922624) (xy 417.697666 -206.922624) (xy 417.687533 -206.9222)
			(xy 417.668804 -206.914455) (xy 417.654448 -206.900149) (xy 417.646636 -206.881447) (xy 417.646104 -206.871316)
			(xy 411.604968 -206.871316) (xy 411.604591 -206.881475) (xy 411.596784 -206.900234) (xy 411.582373 -206.914558)
			(xy 411.563568 -206.922252) (xy 411.553406 -206.922624) (xy 410.153866 -206.922624) (xy 410.143733 -206.9222)
			(xy 410.125004 -206.914455) (xy 410.110648 -206.900149) (xy 410.102836 -206.881447) (xy 410.102304 -206.871316)
			(xy 384.931639 -206.871316) (xy 384.87877 -206.990062) (xy 384.817468 -207.108182) (xy 384.749211 -207.222424)
			(xy 384.674245 -207.33238) (xy 384.592836 -207.437656) (xy 384.505278 -207.537874) (xy 384.411883 -207.632677)
			(xy 384.313286 -207.721454) (xy 406.002236 -207.721454) (xy 406.002236 -207.312514) (xy 406.002675 -207.302344)
			(xy 406.010455 -207.283549) (xy 406.024836 -207.269164) (xy 406.043628 -207.261378) (xy 406.053798 -207.260952)
			(xy 407.453338 -207.260952) (xy 407.4635 -207.261403) (xy 407.482273 -207.269192) (xy 407.496637 -207.283571)
			(xy 407.504408 -207.302352) (xy 407.5049 -207.312514) (xy 407.5049 -207.721454) (xy 413.546036 -207.721454)
			(xy 413.546036 -207.312514) (xy 413.546475 -207.302344) (xy 413.554255 -207.283549) (xy 413.568636 -207.269164)
			(xy 413.587428 -207.261378) (xy 413.597598 -207.260952) (xy 414.997138 -207.260952) (xy 415.0073 -207.261403)
			(xy 415.026073 -207.269192) (xy 415.040437 -207.283571) (xy 415.048208 -207.302352) (xy 415.0487 -207.312514)
			(xy 415.0487 -207.721454) (xy 421.089836 -207.721454) (xy 421.089836 -207.312514) (xy 421.090275 -207.302344)
			(xy 421.098055 -207.283549) (xy 421.112436 -207.269164) (xy 421.131228 -207.261378) (xy 421.141398 -207.260952)
			(xy 422.540938 -207.260952) (xy 422.5511 -207.261403) (xy 422.569873 -207.269192) (xy 422.584237 -207.283571)
			(xy 422.592008 -207.302352) (xy 422.5925 -207.312514) (xy 422.5925 -207.721454) (xy 428.633636 -207.721454)
			(xy 428.633636 -207.312514) (xy 428.634075 -207.302344) (xy 428.641855 -207.283549) (xy 428.656236 -207.269164)
			(xy 428.675028 -207.261378) (xy 428.685198 -207.260952) (xy 430.084738 -207.260952) (xy 430.0949 -207.261403)
			(xy 430.113673 -207.269192) (xy 430.128037 -207.283571) (xy 430.135808 -207.302352) (xy 430.1363 -207.312514)
			(xy 430.1363 -207.721454) (xy 436.177436 -207.721454) (xy 436.177436 -207.312514) (xy 436.177875 -207.302344)
			(xy 436.185655 -207.283549) (xy 436.200036 -207.269164) (xy 436.218828 -207.261378) (xy 436.228998 -207.260952)
			(xy 437.628538 -207.260952) (xy 437.6387 -207.261403) (xy 437.657473 -207.269192) (xy 437.671837 -207.283571)
			(xy 437.679608 -207.302352) (xy 437.6801 -207.312514) (xy 437.6801 -207.721454) (xy 443.721236 -207.721454)
			(xy 443.721236 -207.312514) (xy 443.721675 -207.302344) (xy 443.729455 -207.283549) (xy 443.743836 -207.269164)
			(xy 443.762628 -207.261378) (xy 443.772798 -207.260952) (xy 445.172338 -207.260952) (xy 445.1825 -207.261403)
			(xy 445.201273 -207.269192) (xy 445.215637 -207.283571) (xy 445.223408 -207.302352) (xy 445.2239 -207.312514)
			(xy 445.2239 -207.721454) (xy 451.265036 -207.721454) (xy 451.265036 -207.312514) (xy 451.265475 -207.302344)
			(xy 451.273255 -207.283549) (xy 451.287636 -207.269164) (xy 451.306428 -207.261378) (xy 451.316598 -207.260952)
			(xy 452.716138 -207.260952) (xy 452.7263 -207.261403) (xy 452.745073 -207.269192) (xy 452.759437 -207.283571)
			(xy 452.767208 -207.302352) (xy 452.7677 -207.312514) (xy 452.7677 -207.721454) (xy 458.808836 -207.721454)
			(xy 458.808836 -207.312514) (xy 458.809275 -207.302344) (xy 458.817055 -207.283549) (xy 458.831436 -207.269164)
			(xy 458.850228 -207.261378) (xy 458.860398 -207.260952) (xy 460.259938 -207.260952) (xy 460.2701 -207.261403)
			(xy 460.288873 -207.269192) (xy 460.303237 -207.283571) (xy 460.311008 -207.302352) (xy 460.3115 -207.312514)
			(xy 460.3115 -207.721454) (xy 460.310999 -207.731618) (xy 460.303237 -207.750404) (xy 460.288875 -207.764789)
			(xy 460.270101 -207.772583) (xy 460.259938 -207.773016) (xy 458.860398 -207.773016) (xy 458.850221 -207.772637)
			(xy 458.831417 -207.764842) (xy 458.817031 -207.750443) (xy 458.809254 -207.731632) (xy 458.808836 -207.721454)
			(xy 452.7677 -207.721454) (xy 452.767199 -207.731618) (xy 452.759437 -207.750404) (xy 452.745075 -207.764789)
			(xy 452.726301 -207.772583) (xy 452.716138 -207.773016) (xy 451.316598 -207.773016) (xy 451.306421 -207.772637)
			(xy 451.287617 -207.764842) (xy 451.273231 -207.750443) (xy 451.265454 -207.731632) (xy 451.265036 -207.721454)
			(xy 445.2239 -207.721454) (xy 445.223399 -207.731618) (xy 445.215637 -207.750404) (xy 445.201275 -207.764789)
			(xy 445.182501 -207.772583) (xy 445.172338 -207.773016) (xy 443.772798 -207.773016) (xy 443.762621 -207.772637)
			(xy 443.743817 -207.764842) (xy 443.729431 -207.750443) (xy 443.721654 -207.731632) (xy 443.721236 -207.721454)
			(xy 437.6801 -207.721454) (xy 437.679599 -207.731618) (xy 437.671837 -207.750404) (xy 437.657475 -207.764789)
			(xy 437.638701 -207.772583) (xy 437.628538 -207.773016) (xy 436.228998 -207.773016) (xy 436.218821 -207.772637)
			(xy 436.200017 -207.764842) (xy 436.185631 -207.750443) (xy 436.177854 -207.731632) (xy 436.177436 -207.721454)
			(xy 430.1363 -207.721454) (xy 430.135799 -207.731618) (xy 430.128037 -207.750404) (xy 430.113675 -207.764789)
			(xy 430.094901 -207.772583) (xy 430.084738 -207.773016) (xy 428.685198 -207.773016) (xy 428.675021 -207.772637)
			(xy 428.656217 -207.764842) (xy 428.641831 -207.750443) (xy 428.634054 -207.731632) (xy 428.633636 -207.721454)
			(xy 422.5925 -207.721454) (xy 422.591999 -207.731618) (xy 422.584237 -207.750404) (xy 422.569875 -207.764789)
			(xy 422.551101 -207.772583) (xy 422.540938 -207.773016) (xy 421.141398 -207.773016) (xy 421.131221 -207.772637)
			(xy 421.112417 -207.764842) (xy 421.098031 -207.750443) (xy 421.090254 -207.731632) (xy 421.089836 -207.721454)
			(xy 415.0487 -207.721454) (xy 415.048199 -207.731618) (xy 415.040437 -207.750404) (xy 415.026075 -207.764789)
			(xy 415.007301 -207.772583) (xy 414.997138 -207.773016) (xy 413.597598 -207.773016) (xy 413.587421 -207.772637)
			(xy 413.568617 -207.764842) (xy 413.554231 -207.750443) (xy 413.546454 -207.731632) (xy 413.546036 -207.721454)
			(xy 407.5049 -207.721454) (xy 407.504399 -207.731618) (xy 407.496637 -207.750404) (xy 407.482275 -207.764789)
			(xy 407.463501 -207.772583) (xy 407.453338 -207.773016) (xy 406.053798 -207.773016) (xy 406.043621 -207.772637)
			(xy 406.024817 -207.764842) (xy 406.010431 -207.750443) (xy 406.002654 -207.731632) (xy 406.002236 -207.721454)
			(xy 384.313286 -207.721454) (xy 384.312985 -207.721725) (xy 384.208939 -207.804699) (xy 384.100117 -207.881303)
			(xy 383.986908 -207.951261) (xy 383.869718 -208.014323) (xy 383.748967 -208.070264) (xy 383.625086 -208.118884)
			(xy 383.49852 -208.160008) (xy 383.36972 -208.193489) (xy 383.239149 -208.219207) (xy 383.107273 -208.237071)
			(xy 382.974565 -208.247016) (xy 382.8415 -208.249007) (xy 382.708554 -208.243036) (xy 382.576203 -208.229126)
			(xy 382.444921 -208.207325) (xy 382.315178 -208.177712) (xy 382.187437 -208.140393) (xy 382.062158 -208.095501)
			(xy 381.939787 -208.043197) (xy 381.820763 -207.983668) (xy 381.705512 -207.917128) (xy 381.594447 -207.843815)
			(xy 381.487966 -207.763991) (xy 381.386448 -207.677941) (xy 381.290259 -207.585975) (xy 381.199741 -207.48842)
			(xy 381.11522 -207.385627) (xy 381.036998 -207.277963) (xy 380.965354 -207.165813) (xy 380.900545 -207.04958)
			(xy 380.842804 -206.929679) (xy 380.792337 -206.80654) (xy 380.749324 -206.680603) (xy 380.71392 -206.552318)
			(xy 380.686251 -206.422146) (xy 380.666416 -206.290553) (xy 380.654487 -206.158008) (xy 380.650506 -206.024988)
			(xy 339.08873 -206.024988) (xy 339.088232 -206.091528) (xy 339.080274 -206.22437) (xy 339.064385 -206.356498)
			(xy 339.040622 -206.487439) (xy 339.009072 -206.616725) (xy 338.969846 -206.743893) (xy 338.923085 -206.868487)
			(xy 338.868956 -206.990062) (xy 338.807654 -207.108182) (xy 338.739397 -207.222424) (xy 338.664431 -207.33238)
			(xy 338.583022 -207.437656) (xy 338.495464 -207.537874) (xy 338.402069 -207.632677) (xy 338.303171 -207.721725)
			(xy 338.199125 -207.804699) (xy 338.090303 -207.881303) (xy 337.977094 -207.951261) (xy 337.859904 -208.014323)
			(xy 337.739153 -208.070264) (xy 337.615272 -208.118884) (xy 337.488706 -208.160008) (xy 337.359906 -208.193489)
			(xy 337.229335 -208.219207) (xy 337.097459 -208.237071) (xy 336.964751 -208.247016) (xy 336.831686 -208.249007)
			(xy 336.69874 -208.243036) (xy 336.566389 -208.229126) (xy 336.435107 -208.207325) (xy 336.305364 -208.177712)
			(xy 336.177623 -208.140393) (xy 336.052344 -208.095501) (xy 335.929973 -208.043197) (xy 335.810949 -207.983668)
			(xy 335.695698 -207.917128) (xy 335.584633 -207.843815) (xy 335.478152 -207.763991) (xy 335.376634 -207.677941)
			(xy 335.280445 -207.585975) (xy 335.189927 -207.48842) (xy 335.105406 -207.385627) (xy 335.027184 -207.277963)
			(xy 334.95554 -207.165813) (xy 334.890731 -207.04958) (xy 334.83299 -206.929679) (xy 334.782523 -206.80654)
			(xy 334.73951 -206.680603) (xy 334.704106 -206.552318) (xy 334.676437 -206.422146) (xy 334.656602 -206.290553)
			(xy 334.644673 -206.158008) (xy 334.640692 -206.024988) (xy 309.638562 -206.024988) (xy 309.638305 -206.031588)
			(xy 309.630498 -206.050341) (xy 309.616094 -206.064664) (xy 309.597297 -206.072362) (xy 309.587138 -206.07274)
			(xy 308.187598 -206.07274) (xy 308.177469 -206.072274) (xy 308.158744 -206.064542) (xy 308.144387 -206.050249)
			(xy 308.136571 -206.031559) (xy 308.136036 -206.021432) (xy 302.0949 -206.021432) (xy 302.094505 -206.031588)
			(xy 302.086698 -206.050341) (xy 302.072294 -206.064664) (xy 302.053497 -206.072362) (xy 302.043338 -206.07274)
			(xy 300.643798 -206.07274) (xy 300.633669 -206.072274) (xy 300.614944 -206.064542) (xy 300.600587 -206.050249)
			(xy 300.592771 -206.031559) (xy 300.592236 -206.021432) (xy 294.5511 -206.021432) (xy 294.550705 -206.031588)
			(xy 294.542898 -206.050341) (xy 294.528494 -206.064664) (xy 294.509697 -206.072362) (xy 294.499538 -206.07274)
			(xy 293.099998 -206.07274) (xy 293.089869 -206.072274) (xy 293.071144 -206.064542) (xy 293.056787 -206.050249)
			(xy 293.048971 -206.031559) (xy 293.048436 -206.021432) (xy 287.0073 -206.021432) (xy 287.006905 -206.031588)
			(xy 286.999098 -206.050341) (xy 286.984694 -206.064664) (xy 286.965897 -206.072362) (xy 286.955738 -206.07274)
			(xy 285.556198 -206.07274) (xy 285.546069 -206.072274) (xy 285.527344 -206.064542) (xy 285.512987 -206.050249)
			(xy 285.505171 -206.031559) (xy 285.504636 -206.021432) (xy 279.4635 -206.021432) (xy 279.463105 -206.031588)
			(xy 279.455298 -206.050341) (xy 279.440894 -206.064664) (xy 279.422097 -206.072362) (xy 279.411938 -206.07274)
			(xy 278.012398 -206.07274) (xy 278.002269 -206.072274) (xy 277.983544 -206.064542) (xy 277.969187 -206.050249)
			(xy 277.961371 -206.031559) (xy 277.960836 -206.021432) (xy 271.9197 -206.021432) (xy 271.919305 -206.031588)
			(xy 271.911498 -206.050341) (xy 271.897094 -206.064664) (xy 271.878297 -206.072362) (xy 271.868138 -206.07274)
			(xy 270.468598 -206.07274) (xy 270.458469 -206.072274) (xy 270.439744 -206.064542) (xy 270.425387 -206.050249)
			(xy 270.417571 -206.031559) (xy 270.417036 -206.021432) (xy 264.3759 -206.021432) (xy 264.375505 -206.031588)
			(xy 264.367698 -206.050341) (xy 264.353294 -206.064664) (xy 264.334497 -206.072362) (xy 264.324338 -206.07274)
			(xy 262.924798 -206.07274) (xy 262.914669 -206.072274) (xy 262.895944 -206.064542) (xy 262.881587 -206.050249)
			(xy 262.873771 -206.031559) (xy 262.873236 -206.021432) (xy 256.8321 -206.021432) (xy 256.831705 -206.031588)
			(xy 256.823898 -206.050341) (xy 256.809494 -206.064664) (xy 256.790697 -206.072362) (xy 256.780538 -206.07274)
			(xy 255.380998 -206.07274) (xy 255.370869 -206.072274) (xy 255.352144 -206.064542) (xy 255.337787 -206.050249)
			(xy 255.329971 -206.031559) (xy 255.329436 -206.021432) (xy 212.371432 -206.021432) (xy 212.371005 -206.031584)
			(xy 212.363205 -206.050331) (xy 212.348811 -206.064652) (xy 212.330024 -206.072357) (xy 212.31987 -206.07274)
			(xy 210.92033 -206.07274) (xy 210.910203 -206.072248) (xy 210.891478 -206.064527) (xy 210.87712 -206.050242)
			(xy 210.869304 -206.031557) (xy 210.868768 -206.021432) (xy 204.827632 -206.021432) (xy 204.827205 -206.031584)
			(xy 204.819405 -206.050331) (xy 204.805011 -206.064652) (xy 204.786224 -206.072357) (xy 204.77607 -206.07274)
			(xy 203.37653 -206.07274) (xy 203.366403 -206.072248) (xy 203.347678 -206.064527) (xy 203.33332 -206.050242)
			(xy 203.325504 -206.031557) (xy 203.324968 -206.021432) (xy 197.283832 -206.021432) (xy 197.283405 -206.031584)
			(xy 197.275605 -206.050331) (xy 197.261211 -206.064652) (xy 197.242424 -206.072357) (xy 197.23227 -206.07274)
			(xy 195.83273 -206.07274) (xy 195.822603 -206.072248) (xy 195.803878 -206.064527) (xy 195.78952 -206.050242)
			(xy 195.781704 -206.031557) (xy 195.781168 -206.021432) (xy 189.740032 -206.021432) (xy 189.739605 -206.031584)
			(xy 189.731805 -206.050331) (xy 189.717411 -206.064652) (xy 189.698624 -206.072357) (xy 189.68847 -206.07274)
			(xy 188.28893 -206.07274) (xy 188.278803 -206.072248) (xy 188.260078 -206.064527) (xy 188.24572 -206.050242)
			(xy 188.237904 -206.031557) (xy 188.237368 -206.021432) (xy 182.196232 -206.021432) (xy 182.195805 -206.031584)
			(xy 182.188005 -206.050331) (xy 182.173611 -206.064652) (xy 182.154824 -206.072357) (xy 182.14467 -206.07274)
			(xy 180.74513 -206.07274) (xy 180.735003 -206.072248) (xy 180.716278 -206.064527) (xy 180.70192 -206.050242)
			(xy 180.694104 -206.031557) (xy 180.693568 -206.021432) (xy 174.652432 -206.021432) (xy 174.652005 -206.031584)
			(xy 174.644205 -206.050331) (xy 174.629811 -206.064652) (xy 174.611024 -206.072357) (xy 174.60087 -206.07274)
			(xy 173.20133 -206.07274) (xy 173.191203 -206.072248) (xy 173.172478 -206.064527) (xy 173.15812 -206.050242)
			(xy 173.150304 -206.031557) (xy 173.149768 -206.021432) (xy 167.108632 -206.021432) (xy 167.108205 -206.031584)
			(xy 167.100405 -206.050331) (xy 167.086011 -206.064652) (xy 167.067224 -206.072357) (xy 167.05707 -206.07274)
			(xy 165.65753 -206.07274) (xy 165.647403 -206.072248) (xy 165.628678 -206.064527) (xy 165.61432 -206.050242)
			(xy 165.606504 -206.031557) (xy 165.605968 -206.021432) (xy 159.564832 -206.021432) (xy 159.564405 -206.031584)
			(xy 159.556605 -206.050331) (xy 159.542211 -206.064652) (xy 159.523424 -206.072357) (xy 159.51327 -206.07274)
			(xy 158.11373 -206.07274) (xy 158.103603 -206.072248) (xy 158.084878 -206.064527) (xy 158.07052 -206.050242)
			(xy 158.062704 -206.031557) (xy 158.062168 -206.021432) (xy 137.158703 -206.021432) (xy 137.15873 -206.024988)
			(xy 137.158232 -206.091528) (xy 137.150274 -206.22437) (xy 137.134385 -206.356498) (xy 137.110622 -206.487439)
			(xy 137.079072 -206.616725) (xy 137.039846 -206.743893) (xy 136.993085 -206.868487) (xy 136.991825 -206.871316)
			(xy 162.162236 -206.871316) (xy 162.162236 -206.462376) (xy 162.162603 -206.452216) (xy 162.170413 -206.433456)
			(xy 162.184827 -206.419132) (xy 162.203635 -206.41144) (xy 162.213798 -206.411068) (xy 163.613338 -206.411068)
			(xy 163.623471 -206.411496) (xy 163.642198 -206.419242) (xy 163.656554 -206.433546) (xy 163.664367 -206.452245)
			(xy 163.6649 -206.462376) (xy 163.6649 -206.871316) (xy 169.706036 -206.871316) (xy 169.706036 -206.462376)
			(xy 169.706403 -206.452216) (xy 169.714213 -206.433456) (xy 169.728627 -206.419132) (xy 169.747435 -206.41144)
			(xy 169.757598 -206.411068) (xy 171.157138 -206.411068) (xy 171.167271 -206.411496) (xy 171.185998 -206.419242)
			(xy 171.200354 -206.433546) (xy 171.208167 -206.452245) (xy 171.2087 -206.462376) (xy 171.2087 -206.871316)
			(xy 177.249836 -206.871316) (xy 177.249836 -206.462376) (xy 177.250203 -206.452216) (xy 177.258013 -206.433456)
			(xy 177.272427 -206.419132) (xy 177.291235 -206.41144) (xy 177.301398 -206.411068) (xy 178.700938 -206.411068)
			(xy 178.711071 -206.411496) (xy 178.729798 -206.419242) (xy 178.744154 -206.433546) (xy 178.751967 -206.452245)
			(xy 178.7525 -206.462376) (xy 178.7525 -206.871316) (xy 184.793636 -206.871316) (xy 184.793636 -206.462376)
			(xy 184.794003 -206.452216) (xy 184.801813 -206.433456) (xy 184.816227 -206.419132) (xy 184.835035 -206.41144)
			(xy 184.845198 -206.411068) (xy 186.244738 -206.411068) (xy 186.254871 -206.411496) (xy 186.273598 -206.419242)
			(xy 186.287954 -206.433546) (xy 186.295767 -206.452245) (xy 186.2963 -206.462376) (xy 186.2963 -206.871316)
			(xy 192.337436 -206.871316) (xy 192.337436 -206.462376) (xy 192.337803 -206.452216) (xy 192.345613 -206.433456)
			(xy 192.360027 -206.419132) (xy 192.378835 -206.41144) (xy 192.388998 -206.411068) (xy 193.788538 -206.411068)
			(xy 193.798671 -206.411496) (xy 193.817398 -206.419242) (xy 193.831754 -206.433546) (xy 193.839567 -206.452245)
			(xy 193.8401 -206.462376) (xy 193.8401 -206.871316) (xy 199.881236 -206.871316) (xy 199.881236 -206.462376)
			(xy 199.881603 -206.452216) (xy 199.889413 -206.433456) (xy 199.903827 -206.419132) (xy 199.922635 -206.41144)
			(xy 199.932798 -206.411068) (xy 201.332338 -206.411068) (xy 201.342471 -206.411496) (xy 201.361198 -206.419242)
			(xy 201.375554 -206.433546) (xy 201.383367 -206.452245) (xy 201.3839 -206.462376) (xy 201.3839 -206.871316)
			(xy 207.425036 -206.871316) (xy 207.425036 -206.462376) (xy 207.425403 -206.452216) (xy 207.433213 -206.433456)
			(xy 207.447627 -206.419132) (xy 207.466435 -206.41144) (xy 207.476598 -206.411068) (xy 208.876138 -206.411068)
			(xy 208.886271 -206.411496) (xy 208.904998 -206.419242) (xy 208.919354 -206.433546) (xy 208.927167 -206.452245)
			(xy 208.9277 -206.462376) (xy 208.9277 -206.871316) (xy 214.968836 -206.871316) (xy 214.968836 -206.462376)
			(xy 214.969203 -206.452216) (xy 214.977013 -206.433456) (xy 214.991427 -206.419132) (xy 215.010235 -206.41144)
			(xy 215.020398 -206.411068) (xy 216.419938 -206.411068) (xy 216.430071 -206.411496) (xy 216.448798 -206.419242)
			(xy 216.463154 -206.433546) (xy 216.470967 -206.452245) (xy 216.4715 -206.462376) (xy 216.4715 -206.871316)
			(xy 259.429504 -206.871316) (xy 259.429504 -206.462376) (xy 259.429902 -206.45222) (xy 259.437706 -206.433466)
			(xy 259.45211 -206.419143) (xy 259.470908 -206.411445) (xy 259.481066 -206.411068) (xy 260.880606 -206.411068)
			(xy 260.890737 -206.411523) (xy 260.909463 -206.419258) (xy 260.92382 -206.433554) (xy 260.931634 -206.452248)
			(xy 260.932168 -206.462376) (xy 260.932168 -206.871316) (xy 266.973304 -206.871316) (xy 266.973304 -206.462376)
			(xy 266.973702 -206.45222) (xy 266.981506 -206.433466) (xy 266.99591 -206.419143) (xy 267.014708 -206.411445)
			(xy 267.024866 -206.411068) (xy 268.424406 -206.411068) (xy 268.434537 -206.411523) (xy 268.453263 -206.419258)
			(xy 268.46762 -206.433554) (xy 268.475434 -206.452248) (xy 268.475968 -206.462376) (xy 268.475968 -206.871316)
			(xy 274.517104 -206.871316) (xy 274.517104 -206.462376) (xy 274.517502 -206.45222) (xy 274.525306 -206.433466)
			(xy 274.53971 -206.419143) (xy 274.558508 -206.411445) (xy 274.568666 -206.411068) (xy 275.968206 -206.411068)
			(xy 275.978337 -206.411523) (xy 275.997063 -206.419258) (xy 276.01142 -206.433554) (xy 276.019234 -206.452248)
			(xy 276.019768 -206.462376) (xy 276.019768 -206.871316) (xy 282.060904 -206.871316) (xy 282.060904 -206.462376)
			(xy 282.061302 -206.45222) (xy 282.069106 -206.433466) (xy 282.08351 -206.419143) (xy 282.102308 -206.411445)
			(xy 282.112466 -206.411068) (xy 283.512006 -206.411068) (xy 283.522137 -206.411523) (xy 283.540863 -206.419258)
			(xy 283.55522 -206.433554) (xy 283.563034 -206.452248) (xy 283.563568 -206.462376) (xy 283.563568 -206.871316)
			(xy 289.604704 -206.871316) (xy 289.604704 -206.462376) (xy 289.605102 -206.45222) (xy 289.612906 -206.433466)
			(xy 289.62731 -206.419143) (xy 289.646108 -206.411445) (xy 289.656266 -206.411068) (xy 291.055806 -206.411068)
			(xy 291.065937 -206.411523) (xy 291.084663 -206.419258) (xy 291.09902 -206.433554) (xy 291.106834 -206.452248)
			(xy 291.107368 -206.462376) (xy 291.107368 -206.871316) (xy 297.148504 -206.871316) (xy 297.148504 -206.462376)
			(xy 297.148902 -206.45222) (xy 297.156706 -206.433466) (xy 297.17111 -206.419143) (xy 297.189908 -206.411445)
			(xy 297.200066 -206.411068) (xy 298.599606 -206.411068) (xy 298.609737 -206.411523) (xy 298.628463 -206.419258)
			(xy 298.64282 -206.433554) (xy 298.650634 -206.452248) (xy 298.651168 -206.462376) (xy 298.651168 -206.871316)
			(xy 304.692304 -206.871316) (xy 304.692304 -206.462376) (xy 304.692702 -206.45222) (xy 304.700506 -206.433466)
			(xy 304.71491 -206.419143) (xy 304.733708 -206.411445) (xy 304.743866 -206.411068) (xy 306.143406 -206.411068)
			(xy 306.153537 -206.411523) (xy 306.172263 -206.419258) (xy 306.18662 -206.433554) (xy 306.194434 -206.452248)
			(xy 306.194968 -206.462376) (xy 306.194968 -206.871316) (xy 312.236104 -206.871316) (xy 312.236104 -206.462376)
			(xy 312.236502 -206.45222) (xy 312.244306 -206.433466) (xy 312.25871 -206.419143) (xy 312.277508 -206.411445)
			(xy 312.287666 -206.411068) (xy 313.687206 -206.411068) (xy 313.697337 -206.411523) (xy 313.716063 -206.419258)
			(xy 313.73042 -206.433554) (xy 313.738234 -206.452248) (xy 313.738768 -206.462376) (xy 313.738768 -206.871316)
			(xy 313.738391 -206.881475) (xy 313.730584 -206.900234) (xy 313.716173 -206.914558) (xy 313.697368 -206.922252)
			(xy 313.687206 -206.922624) (xy 312.287666 -206.922624) (xy 312.277533 -206.9222) (xy 312.258804 -206.914455)
			(xy 312.244448 -206.900149) (xy 312.236636 -206.881447) (xy 312.236104 -206.871316) (xy 306.194968 -206.871316)
			(xy 306.194591 -206.881475) (xy 306.186784 -206.900234) (xy 306.172373 -206.914558) (xy 306.153568 -206.922252)
			(xy 306.143406 -206.922624) (xy 304.743866 -206.922624) (xy 304.733733 -206.9222) (xy 304.715004 -206.914455)
			(xy 304.700648 -206.900149) (xy 304.692836 -206.881447) (xy 304.692304 -206.871316) (xy 298.651168 -206.871316)
			(xy 298.650791 -206.881475) (xy 298.642984 -206.900234) (xy 298.628573 -206.914558) (xy 298.609768 -206.922252)
			(xy 298.599606 -206.922624) (xy 297.200066 -206.922624) (xy 297.189933 -206.9222) (xy 297.171204 -206.914455)
			(xy 297.156848 -206.900149) (xy 297.149036 -206.881447) (xy 297.148504 -206.871316) (xy 291.107368 -206.871316)
			(xy 291.106991 -206.881475) (xy 291.099184 -206.900234) (xy 291.084773 -206.914558) (xy 291.065968 -206.922252)
			(xy 291.055806 -206.922624) (xy 289.656266 -206.922624) (xy 289.646133 -206.9222) (xy 289.627404 -206.914455)
			(xy 289.613048 -206.900149) (xy 289.605236 -206.881447) (xy 289.604704 -206.871316) (xy 283.563568 -206.871316)
			(xy 283.563191 -206.881475) (xy 283.555384 -206.900234) (xy 283.540973 -206.914558) (xy 283.522168 -206.922252)
			(xy 283.512006 -206.922624) (xy 282.112466 -206.922624) (xy 282.102333 -206.9222) (xy 282.083604 -206.914455)
			(xy 282.069248 -206.900149) (xy 282.061436 -206.881447) (xy 282.060904 -206.871316) (xy 276.019768 -206.871316)
			(xy 276.019391 -206.881475) (xy 276.011584 -206.900234) (xy 275.997173 -206.914558) (xy 275.978368 -206.922252)
			(xy 275.968206 -206.922624) (xy 274.568666 -206.922624) (xy 274.558533 -206.9222) (xy 274.539804 -206.914455)
			(xy 274.525448 -206.900149) (xy 274.517636 -206.881447) (xy 274.517104 -206.871316) (xy 268.475968 -206.871316)
			(xy 268.475591 -206.881475) (xy 268.467784 -206.900234) (xy 268.453373 -206.914558) (xy 268.434568 -206.922252)
			(xy 268.424406 -206.922624) (xy 267.024866 -206.922624) (xy 267.014733 -206.9222) (xy 266.996004 -206.914455)
			(xy 266.981648 -206.900149) (xy 266.973836 -206.881447) (xy 266.973304 -206.871316) (xy 260.932168 -206.871316)
			(xy 260.931791 -206.881475) (xy 260.923984 -206.900234) (xy 260.909573 -206.914558) (xy 260.890768 -206.922252)
			(xy 260.880606 -206.922624) (xy 259.481066 -206.922624) (xy 259.470933 -206.9222) (xy 259.452204 -206.914455)
			(xy 259.437848 -206.900149) (xy 259.430036 -206.881447) (xy 259.429504 -206.871316) (xy 216.4715 -206.871316)
			(xy 216.471092 -206.881471) (xy 216.463291 -206.900224) (xy 216.44889 -206.914547) (xy 216.430095 -206.922246)
			(xy 216.419938 -206.922624) (xy 215.020398 -206.922624) (xy 215.010267 -206.922174) (xy 214.991539 -206.914439)
			(xy 214.977181 -206.900141) (xy 214.969369 -206.881445) (xy 214.968836 -206.871316) (xy 208.9277 -206.871316)
			(xy 208.927292 -206.881471) (xy 208.919491 -206.900224) (xy 208.90509 -206.914547) (xy 208.886295 -206.922246)
			(xy 208.876138 -206.922624) (xy 207.476598 -206.922624) (xy 207.466467 -206.922174) (xy 207.447739 -206.914439)
			(xy 207.433381 -206.900141) (xy 207.425569 -206.881445) (xy 207.425036 -206.871316) (xy 201.3839 -206.871316)
			(xy 201.383492 -206.881471) (xy 201.375691 -206.900224) (xy 201.36129 -206.914547) (xy 201.342495 -206.922246)
			(xy 201.332338 -206.922624) (xy 199.932798 -206.922624) (xy 199.922667 -206.922174) (xy 199.903939 -206.914439)
			(xy 199.889581 -206.900141) (xy 199.881769 -206.881445) (xy 199.881236 -206.871316) (xy 193.8401 -206.871316)
			(xy 193.839692 -206.881471) (xy 193.831891 -206.900224) (xy 193.81749 -206.914547) (xy 193.798695 -206.922246)
			(xy 193.788538 -206.922624) (xy 192.388998 -206.922624) (xy 192.378867 -206.922174) (xy 192.360139 -206.914439)
			(xy 192.345781 -206.900141) (xy 192.337969 -206.881445) (xy 192.337436 -206.871316) (xy 186.2963 -206.871316)
			(xy 186.295892 -206.881471) (xy 186.288091 -206.900224) (xy 186.27369 -206.914547) (xy 186.254895 -206.922246)
			(xy 186.244738 -206.922624) (xy 184.845198 -206.922624) (xy 184.835067 -206.922174) (xy 184.816339 -206.914439)
			(xy 184.801981 -206.900141) (xy 184.794169 -206.881445) (xy 184.793636 -206.871316) (xy 178.7525 -206.871316)
			(xy 178.752092 -206.881471) (xy 178.744291 -206.900224) (xy 178.72989 -206.914547) (xy 178.711095 -206.922246)
			(xy 178.700938 -206.922624) (xy 177.301398 -206.922624) (xy 177.291267 -206.922174) (xy 177.272539 -206.914439)
			(xy 177.258181 -206.900141) (xy 177.250369 -206.881445) (xy 177.249836 -206.871316) (xy 171.2087 -206.871316)
			(xy 171.208292 -206.881471) (xy 171.200491 -206.900224) (xy 171.18609 -206.914547) (xy 171.167295 -206.922246)
			(xy 171.157138 -206.922624) (xy 169.757598 -206.922624) (xy 169.747467 -206.922174) (xy 169.728739 -206.914439)
			(xy 169.714381 -206.900141) (xy 169.706569 -206.881445) (xy 169.706036 -206.871316) (xy 163.6649 -206.871316)
			(xy 163.664492 -206.881471) (xy 163.656691 -206.900224) (xy 163.64229 -206.914547) (xy 163.623495 -206.922246)
			(xy 163.613338 -206.922624) (xy 162.213798 -206.922624) (xy 162.203667 -206.922174) (xy 162.184939 -206.914439)
			(xy 162.170581 -206.900141) (xy 162.162769 -206.881445) (xy 162.162236 -206.871316) (xy 136.991825 -206.871316)
			(xy 136.938956 -206.990062) (xy 136.877654 -207.108182) (xy 136.809397 -207.222424) (xy 136.734431 -207.33238)
			(xy 136.653022 -207.437656) (xy 136.565464 -207.537874) (xy 136.472069 -207.632677) (xy 136.373472 -207.721454)
			(xy 158.062168 -207.721454) (xy 158.062168 -207.312514) (xy 158.062576 -207.30234) (xy 158.070362 -207.283539)
			(xy 158.084753 -207.269153) (xy 158.103555 -207.261373) (xy 158.11373 -207.260952) (xy 159.51327 -207.260952)
			(xy 159.523441 -207.261389) (xy 159.542238 -207.269167) (xy 159.556624 -207.283549) (xy 159.564408 -207.302343)
			(xy 159.564832 -207.312514) (xy 159.564832 -207.721454) (xy 165.605968 -207.721454) (xy 165.605968 -207.312514)
			(xy 165.606376 -207.30234) (xy 165.614162 -207.283539) (xy 165.628553 -207.269153) (xy 165.647355 -207.261373)
			(xy 165.65753 -207.260952) (xy 167.05707 -207.260952) (xy 167.067241 -207.261389) (xy 167.086038 -207.269167)
			(xy 167.100424 -207.283549) (xy 167.108208 -207.302343) (xy 167.108632 -207.312514) (xy 167.108632 -207.721454)
			(xy 173.149768 -207.721454) (xy 173.149768 -207.312514) (xy 173.150176 -207.30234) (xy 173.157962 -207.283539)
			(xy 173.172353 -207.269153) (xy 173.191155 -207.261373) (xy 173.20133 -207.260952) (xy 174.60087 -207.260952)
			(xy 174.611041 -207.261389) (xy 174.629838 -207.269167) (xy 174.644224 -207.283549) (xy 174.652008 -207.302343)
			(xy 174.652432 -207.312514) (xy 174.652432 -207.721454) (xy 180.693568 -207.721454) (xy 180.693568 -207.312514)
			(xy 180.693976 -207.30234) (xy 180.701762 -207.283539) (xy 180.716153 -207.269153) (xy 180.734955 -207.261373)
			(xy 180.74513 -207.260952) (xy 182.14467 -207.260952) (xy 182.154841 -207.261389) (xy 182.173638 -207.269167)
			(xy 182.188024 -207.283549) (xy 182.195808 -207.302343) (xy 182.196232 -207.312514) (xy 182.196232 -207.721454)
			(xy 188.237368 -207.721454) (xy 188.237368 -207.312514) (xy 188.237776 -207.30234) (xy 188.245562 -207.283539)
			(xy 188.259953 -207.269153) (xy 188.278755 -207.261373) (xy 188.28893 -207.260952) (xy 189.68847 -207.260952)
			(xy 189.698641 -207.261389) (xy 189.717438 -207.269167) (xy 189.731824 -207.283549) (xy 189.739608 -207.302343)
			(xy 189.740032 -207.312514) (xy 189.740032 -207.721454) (xy 195.781168 -207.721454) (xy 195.781168 -207.312514)
			(xy 195.781576 -207.30234) (xy 195.789362 -207.283539) (xy 195.803753 -207.269153) (xy 195.822555 -207.261373)
			(xy 195.83273 -207.260952) (xy 197.23227 -207.260952) (xy 197.242441 -207.261389) (xy 197.261238 -207.269167)
			(xy 197.275624 -207.283549) (xy 197.283408 -207.302343) (xy 197.283832 -207.312514) (xy 197.283832 -207.721454)
			(xy 203.324968 -207.721454) (xy 203.324968 -207.312514) (xy 203.325376 -207.30234) (xy 203.333162 -207.283539)
			(xy 203.347553 -207.269153) (xy 203.366355 -207.261373) (xy 203.37653 -207.260952) (xy 204.77607 -207.260952)
			(xy 204.786241 -207.261389) (xy 204.805038 -207.269167) (xy 204.819424 -207.283549) (xy 204.827208 -207.302343)
			(xy 204.827632 -207.312514) (xy 204.827632 -207.721454) (xy 210.868768 -207.721454) (xy 210.868768 -207.312514)
			(xy 210.869176 -207.30234) (xy 210.876962 -207.283539) (xy 210.891353 -207.269153) (xy 210.910155 -207.261373)
			(xy 210.92033 -207.260952) (xy 212.31987 -207.260952) (xy 212.330041 -207.261389) (xy 212.348838 -207.269167)
			(xy 212.363224 -207.283549) (xy 212.371008 -207.302343) (xy 212.371432 -207.312514) (xy 212.371432 -207.721454)
			(xy 255.329436 -207.721454) (xy 255.329436 -207.312514) (xy 255.329875 -207.302344) (xy 255.337655 -207.283549)
			(xy 255.352036 -207.269164) (xy 255.370828 -207.261378) (xy 255.380998 -207.260952) (xy 256.780538 -207.260952)
			(xy 256.7907 -207.261403) (xy 256.809473 -207.269192) (xy 256.823837 -207.283571) (xy 256.831608 -207.302352)
			(xy 256.8321 -207.312514) (xy 256.8321 -207.721454) (xy 262.873236 -207.721454) (xy 262.873236 -207.312514)
			(xy 262.873675 -207.302344) (xy 262.881455 -207.283549) (xy 262.895836 -207.269164) (xy 262.914628 -207.261378)
			(xy 262.924798 -207.260952) (xy 264.324338 -207.260952) (xy 264.3345 -207.261403) (xy 264.353273 -207.269192)
			(xy 264.367637 -207.283571) (xy 264.375408 -207.302352) (xy 264.3759 -207.312514) (xy 264.3759 -207.721454)
			(xy 270.417036 -207.721454) (xy 270.417036 -207.312514) (xy 270.417475 -207.302344) (xy 270.425255 -207.283549)
			(xy 270.439636 -207.269164) (xy 270.458428 -207.261378) (xy 270.468598 -207.260952) (xy 271.868138 -207.260952)
			(xy 271.8783 -207.261403) (xy 271.897073 -207.269192) (xy 271.911437 -207.283571) (xy 271.919208 -207.302352)
			(xy 271.9197 -207.312514) (xy 271.9197 -207.721454) (xy 277.960836 -207.721454) (xy 277.960836 -207.312514)
			(xy 277.961275 -207.302344) (xy 277.969055 -207.283549) (xy 277.983436 -207.269164) (xy 278.002228 -207.261378)
			(xy 278.012398 -207.260952) (xy 279.411938 -207.260952) (xy 279.4221 -207.261403) (xy 279.440873 -207.269192)
			(xy 279.455237 -207.283571) (xy 279.463008 -207.302352) (xy 279.4635 -207.312514) (xy 279.4635 -207.721454)
			(xy 285.504636 -207.721454) (xy 285.504636 -207.312514) (xy 285.505075 -207.302344) (xy 285.512855 -207.283549)
			(xy 285.527236 -207.269164) (xy 285.546028 -207.261378) (xy 285.556198 -207.260952) (xy 286.955738 -207.260952)
			(xy 286.9659 -207.261403) (xy 286.984673 -207.269192) (xy 286.999037 -207.283571) (xy 287.006808 -207.302352)
			(xy 287.0073 -207.312514) (xy 287.0073 -207.721454) (xy 293.048436 -207.721454) (xy 293.048436 -207.312514)
			(xy 293.048875 -207.302344) (xy 293.056655 -207.283549) (xy 293.071036 -207.269164) (xy 293.089828 -207.261378)
			(xy 293.099998 -207.260952) (xy 294.499538 -207.260952) (xy 294.5097 -207.261403) (xy 294.528473 -207.269192)
			(xy 294.542837 -207.283571) (xy 294.550608 -207.302352) (xy 294.5511 -207.312514) (xy 294.5511 -207.721454)
			(xy 300.592236 -207.721454) (xy 300.592236 -207.312514) (xy 300.592675 -207.302344) (xy 300.600455 -207.283549)
			(xy 300.614836 -207.269164) (xy 300.633628 -207.261378) (xy 300.643798 -207.260952) (xy 302.043338 -207.260952)
			(xy 302.0535 -207.261403) (xy 302.072273 -207.269192) (xy 302.086637 -207.283571) (xy 302.094408 -207.302352)
			(xy 302.0949 -207.312514) (xy 302.0949 -207.721454) (xy 308.136036 -207.721454) (xy 308.136036 -207.312514)
			(xy 308.136475 -207.302344) (xy 308.144255 -207.283549) (xy 308.158636 -207.269164) (xy 308.177428 -207.261378)
			(xy 308.187598 -207.260952) (xy 309.587138 -207.260952) (xy 309.5973 -207.261403) (xy 309.616073 -207.269192)
			(xy 309.630437 -207.283571) (xy 309.638208 -207.302352) (xy 309.6387 -207.312514) (xy 309.6387 -207.721454)
			(xy 309.638199 -207.731618) (xy 309.630437 -207.750404) (xy 309.616075 -207.764789) (xy 309.597301 -207.772583)
			(xy 309.587138 -207.773016) (xy 308.187598 -207.773016) (xy 308.177421 -207.772637) (xy 308.158617 -207.764842)
			(xy 308.144231 -207.750443) (xy 308.136454 -207.731632) (xy 308.136036 -207.721454) (xy 302.0949 -207.721454)
			(xy 302.094399 -207.731618) (xy 302.086637 -207.750404) (xy 302.072275 -207.764789) (xy 302.053501 -207.772583)
			(xy 302.043338 -207.773016) (xy 300.643798 -207.773016) (xy 300.633621 -207.772637) (xy 300.614817 -207.764842)
			(xy 300.600431 -207.750443) (xy 300.592654 -207.731632) (xy 300.592236 -207.721454) (xy 294.5511 -207.721454)
			(xy 294.550599 -207.731618) (xy 294.542837 -207.750404) (xy 294.528475 -207.764789) (xy 294.509701 -207.772583)
			(xy 294.499538 -207.773016) (xy 293.099998 -207.773016) (xy 293.089821 -207.772637) (xy 293.071017 -207.764842)
			(xy 293.056631 -207.750443) (xy 293.048854 -207.731632) (xy 293.048436 -207.721454) (xy 287.0073 -207.721454)
			(xy 287.006799 -207.731618) (xy 286.999037 -207.750404) (xy 286.984675 -207.764789) (xy 286.965901 -207.772583)
			(xy 286.955738 -207.773016) (xy 285.556198 -207.773016) (xy 285.546021 -207.772637) (xy 285.527217 -207.764842)
			(xy 285.512831 -207.750443) (xy 285.505054 -207.731632) (xy 285.504636 -207.721454) (xy 279.4635 -207.721454)
			(xy 279.462999 -207.731618) (xy 279.455237 -207.750404) (xy 279.440875 -207.764789) (xy 279.422101 -207.772583)
			(xy 279.411938 -207.773016) (xy 278.012398 -207.773016) (xy 278.002221 -207.772637) (xy 277.983417 -207.764842)
			(xy 277.969031 -207.750443) (xy 277.961254 -207.731632) (xy 277.960836 -207.721454) (xy 271.9197 -207.721454)
			(xy 271.919199 -207.731618) (xy 271.911437 -207.750404) (xy 271.897075 -207.764789) (xy 271.878301 -207.772583)
			(xy 271.868138 -207.773016) (xy 270.468598 -207.773016) (xy 270.458421 -207.772637) (xy 270.439617 -207.764842)
			(xy 270.425231 -207.750443) (xy 270.417454 -207.731632) (xy 270.417036 -207.721454) (xy 264.3759 -207.721454)
			(xy 264.375399 -207.731618) (xy 264.367637 -207.750404) (xy 264.353275 -207.764789) (xy 264.334501 -207.772583)
			(xy 264.324338 -207.773016) (xy 262.924798 -207.773016) (xy 262.914621 -207.772637) (xy 262.895817 -207.764842)
			(xy 262.881431 -207.750443) (xy 262.873654 -207.731632) (xy 262.873236 -207.721454) (xy 256.8321 -207.721454)
			(xy 256.831599 -207.731618) (xy 256.823837 -207.750404) (xy 256.809475 -207.764789) (xy 256.790701 -207.772583)
			(xy 256.780538 -207.773016) (xy 255.380998 -207.773016) (xy 255.370821 -207.772637) (xy 255.352017 -207.764842)
			(xy 255.337631 -207.750443) (xy 255.329854 -207.731632) (xy 255.329436 -207.721454) (xy 212.371432 -207.721454)
			(xy 212.370998 -207.731626) (xy 212.363222 -207.750426) (xy 212.348839 -207.764813) (xy 212.330042 -207.772595)
			(xy 212.31987 -207.773016) (xy 210.92033 -207.773016) (xy 210.910155 -207.77261) (xy 210.891352 -207.764827)
			(xy 210.876964 -207.750435) (xy 210.869187 -207.731629) (xy 210.868768 -207.721454) (xy 204.827632 -207.721454)
			(xy 204.827198 -207.731626) (xy 204.819422 -207.750426) (xy 204.805039 -207.764813) (xy 204.786242 -207.772595)
			(xy 204.77607 -207.773016) (xy 203.37653 -207.773016) (xy 203.366355 -207.77261) (xy 203.347552 -207.764827)
			(xy 203.333164 -207.750435) (xy 203.325387 -207.731629) (xy 203.324968 -207.721454) (xy 197.283832 -207.721454)
			(xy 197.283398 -207.731626) (xy 197.275622 -207.750426) (xy 197.261239 -207.764813) (xy 197.242442 -207.772595)
			(xy 197.23227 -207.773016) (xy 195.83273 -207.773016) (xy 195.822555 -207.77261) (xy 195.803752 -207.764827)
			(xy 195.789364 -207.750435) (xy 195.781587 -207.731629) (xy 195.781168 -207.721454) (xy 189.740032 -207.721454)
			(xy 189.739598 -207.731626) (xy 189.731822 -207.750426) (xy 189.717439 -207.764813) (xy 189.698642 -207.772595)
			(xy 189.68847 -207.773016) (xy 188.28893 -207.773016) (xy 188.278755 -207.77261) (xy 188.259952 -207.764827)
			(xy 188.245564 -207.750435) (xy 188.237787 -207.731629) (xy 188.237368 -207.721454) (xy 182.196232 -207.721454)
			(xy 182.195798 -207.731626) (xy 182.188022 -207.750426) (xy 182.173639 -207.764813) (xy 182.154842 -207.772595)
			(xy 182.14467 -207.773016) (xy 180.74513 -207.773016) (xy 180.734955 -207.77261) (xy 180.716152 -207.764827)
			(xy 180.701764 -207.750435) (xy 180.693987 -207.731629) (xy 180.693568 -207.721454) (xy 174.652432 -207.721454)
			(xy 174.651998 -207.731626) (xy 174.644222 -207.750426) (xy 174.629839 -207.764813) (xy 174.611042 -207.772595)
			(xy 174.60087 -207.773016) (xy 173.20133 -207.773016) (xy 173.191155 -207.77261) (xy 173.172352 -207.764827)
			(xy 173.157964 -207.750435) (xy 173.150187 -207.731629) (xy 173.149768 -207.721454) (xy 167.108632 -207.721454)
			(xy 167.108198 -207.731626) (xy 167.100422 -207.750426) (xy 167.086039 -207.764813) (xy 167.067242 -207.772595)
			(xy 167.05707 -207.773016) (xy 165.65753 -207.773016) (xy 165.647355 -207.77261) (xy 165.628552 -207.764827)
			(xy 165.614164 -207.750435) (xy 165.606387 -207.731629) (xy 165.605968 -207.721454) (xy 159.564832 -207.721454)
			(xy 159.564398 -207.731626) (xy 159.556622 -207.750426) (xy 159.542239 -207.764813) (xy 159.523442 -207.772595)
			(xy 159.51327 -207.773016) (xy 158.11373 -207.773016) (xy 158.103555 -207.77261) (xy 158.084752 -207.764827)
			(xy 158.070364 -207.750435) (xy 158.062587 -207.731629) (xy 158.062168 -207.721454) (xy 136.373472 -207.721454)
			(xy 136.373171 -207.721725) (xy 136.269125 -207.804699) (xy 136.160303 -207.881303) (xy 136.047094 -207.951261)
			(xy 135.929904 -208.014323) (xy 135.809153 -208.070264) (xy 135.685272 -208.118884) (xy 135.558706 -208.160008)
			(xy 135.429906 -208.193489) (xy 135.299335 -208.219207) (xy 135.167459 -208.237071) (xy 135.034751 -208.247016)
			(xy 134.901686 -208.249007) (xy 134.76874 -208.243036) (xy 134.636389 -208.229126) (xy 134.505107 -208.207325)
			(xy 134.375364 -208.177712) (xy 134.247623 -208.140393) (xy 134.122344 -208.095501) (xy 133.999973 -208.043197)
			(xy 133.880949 -207.983668) (xy 133.765698 -207.917128) (xy 133.654633 -207.843815) (xy 133.548152 -207.763991)
			(xy 133.446634 -207.677941) (xy 133.350445 -207.585975) (xy 133.259927 -207.48842) (xy 133.175406 -207.385627)
			(xy 133.097184 -207.277963) (xy 133.02554 -207.165813) (xy 132.960731 -207.04958) (xy 132.90299 -206.929679)
			(xy 132.852523 -206.80654) (xy 132.80951 -206.680603) (xy 132.774106 -206.552318) (xy 132.746437 -206.422146)
			(xy 132.726602 -206.290553) (xy 132.714673 -206.158008) (xy 132.710692 -206.024988) (xy 91.148662 -206.024988)
			(xy 91.148164 -206.091528) (xy 91.140206 -206.22437) (xy 91.124317 -206.356498) (xy 91.100554 -206.487439)
			(xy 91.069004 -206.616725) (xy 91.029778 -206.743893) (xy 90.983017 -206.868487) (xy 90.928888 -206.990062)
			(xy 90.867586 -207.108182) (xy 90.799329 -207.222424) (xy 90.724363 -207.33238) (xy 90.642954 -207.437656)
			(xy 90.555396 -207.537874) (xy 90.462001 -207.632677) (xy 90.363103 -207.721725) (xy 90.259057 -207.804699)
			(xy 90.150235 -207.881303) (xy 90.037026 -207.951261) (xy 89.919836 -208.014323) (xy 89.799085 -208.070264)
			(xy 89.675204 -208.118884) (xy 89.548638 -208.160008) (xy 89.419838 -208.193489) (xy 89.289267 -208.219207)
			(xy 89.157391 -208.237071) (xy 89.024683 -208.247016) (xy 88.891618 -208.249007) (xy 88.758672 -208.243036)
			(xy 88.626321 -208.229126) (xy 88.495039 -208.207325) (xy 88.365296 -208.177712) (xy 88.237555 -208.140393)
			(xy 88.112276 -208.095501) (xy 87.989905 -208.043197) (xy 87.870881 -207.983668) (xy 87.75563 -207.917128)
			(xy 87.644565 -207.843815) (xy 87.538084 -207.763991) (xy 87.436566 -207.677941) (xy 87.340377 -207.585975)
			(xy 87.249859 -207.48842) (xy 87.165338 -207.385627) (xy 87.087116 -207.277963) (xy 87.015472 -207.165813)
			(xy 86.950663 -207.04958) (xy 86.892922 -206.929679) (xy 86.842455 -206.80654) (xy 86.799442 -206.680603)
			(xy 86.764038 -206.552318) (xy 86.736369 -206.422146) (xy 86.716534 -206.290553) (xy 86.704605 -206.158008)
			(xy 86.700624 -206.024988) (xy 61.698482 -206.024988) (xy 61.698205 -206.031584) (xy 61.690405 -206.050331)
			(xy 61.676011 -206.064652) (xy 61.657224 -206.072357) (xy 61.64707 -206.07274) (xy 60.24753 -206.07274)
			(xy 60.237403 -206.072248) (xy 60.218678 -206.064527) (xy 60.20432 -206.050242) (xy 60.196504 -206.031557)
			(xy 60.195968 -206.021432) (xy 54.154832 -206.021432) (xy 54.154405 -206.031584) (xy 54.146605 -206.050331)
			(xy 54.132211 -206.064652) (xy 54.113424 -206.072357) (xy 54.10327 -206.07274) (xy 52.70373 -206.07274)
			(xy 52.693603 -206.072248) (xy 52.674878 -206.064527) (xy 52.66052 -206.050242) (xy 52.652704 -206.031557)
			(xy 52.652168 -206.021432) (xy 46.611032 -206.021432) (xy 46.610605 -206.031584) (xy 46.602805 -206.050331)
			(xy 46.588411 -206.064652) (xy 46.569624 -206.072357) (xy 46.55947 -206.07274) (xy 45.15993 -206.07274)
			(xy 45.149803 -206.072248) (xy 45.131078 -206.064527) (xy 45.11672 -206.050242) (xy 45.108904 -206.031557)
			(xy 45.108368 -206.021432) (xy 39.067232 -206.021432) (xy 39.066805 -206.031584) (xy 39.059005 -206.050331)
			(xy 39.044611 -206.064652) (xy 39.025824 -206.072357) (xy 39.01567 -206.07274) (xy 37.61613 -206.07274)
			(xy 37.606003 -206.072248) (xy 37.587278 -206.064527) (xy 37.57292 -206.050242) (xy 37.565104 -206.031557)
			(xy 37.564568 -206.021432) (xy 31.523432 -206.021432) (xy 31.523005 -206.031584) (xy 31.515205 -206.050331)
			(xy 31.500811 -206.064652) (xy 31.482024 -206.072357) (xy 31.47187 -206.07274) (xy 30.07233 -206.07274)
			(xy 30.062203 -206.072248) (xy 30.043478 -206.064527) (xy 30.02912 -206.050242) (xy 30.021304 -206.031557)
			(xy 30.020768 -206.021432) (xy 23.979632 -206.021432) (xy 23.979205 -206.031584) (xy 23.971405 -206.050331)
			(xy 23.957011 -206.064652) (xy 23.938224 -206.072357) (xy 23.92807 -206.07274) (xy 22.52853 -206.07274)
			(xy 22.518403 -206.072248) (xy 22.499678 -206.064527) (xy 22.48532 -206.050242) (xy 22.477504 -206.031557)
			(xy 22.476968 -206.021432) (xy 16.435832 -206.021432) (xy 16.435405 -206.031584) (xy 16.427605 -206.050331)
			(xy 16.413211 -206.064652) (xy 16.394424 -206.072357) (xy 16.38427 -206.07274) (xy 14.98473 -206.07274)
			(xy 14.974603 -206.072248) (xy 14.955878 -206.064527) (xy 14.94152 -206.050242) (xy 14.933704 -206.031557)
			(xy 14.933168 -206.021432) (xy 8.892032 -206.021432) (xy 8.891605 -206.031584) (xy 8.883805 -206.050331)
			(xy 8.869411 -206.064652) (xy 8.850624 -206.072357) (xy 8.84047 -206.07274) (xy 7.44093 -206.07274)
			(xy 7.430803 -206.072248) (xy 7.412078 -206.064527) (xy 7.39772 -206.050242) (xy 7.389904 -206.031557)
			(xy 7.389368 -206.021432) (xy 2.509012 -206.021432) (xy 2.509012 -206.871316) (xy 11.489436 -206.871316)
			(xy 11.489436 -206.462376) (xy 11.489803 -206.452216) (xy 11.497613 -206.433456) (xy 11.512027 -206.419132)
			(xy 11.530835 -206.41144) (xy 11.540998 -206.411068) (xy 12.940538 -206.411068) (xy 12.950671 -206.411496)
			(xy 12.969398 -206.419242) (xy 12.983754 -206.433546) (xy 12.991567 -206.452245) (xy 12.9921 -206.462376)
			(xy 12.9921 -206.871316) (xy 19.033236 -206.871316) (xy 19.033236 -206.462376) (xy 19.033603 -206.452216)
			(xy 19.041413 -206.433456) (xy 19.055827 -206.419132) (xy 19.074635 -206.41144) (xy 19.084798 -206.411068)
			(xy 20.484338 -206.411068) (xy 20.494471 -206.411496) (xy 20.513198 -206.419242) (xy 20.527554 -206.433546)
			(xy 20.535367 -206.452245) (xy 20.5359 -206.462376) (xy 20.5359 -206.871316) (xy 26.577036 -206.871316)
			(xy 26.577036 -206.462376) (xy 26.577403 -206.452216) (xy 26.585213 -206.433456) (xy 26.599627 -206.419132)
			(xy 26.618435 -206.41144) (xy 26.628598 -206.411068) (xy 28.028138 -206.411068) (xy 28.038271 -206.411496)
			(xy 28.056998 -206.419242) (xy 28.071354 -206.433546) (xy 28.079167 -206.452245) (xy 28.0797 -206.462376)
			(xy 28.0797 -206.871316) (xy 34.120836 -206.871316) (xy 34.120836 -206.462376) (xy 34.121203 -206.452216)
			(xy 34.129013 -206.433456) (xy 34.143427 -206.419132) (xy 34.162235 -206.41144) (xy 34.172398 -206.411068)
			(xy 35.571938 -206.411068) (xy 35.582071 -206.411496) (xy 35.600798 -206.419242) (xy 35.615154 -206.433546)
			(xy 35.622967 -206.452245) (xy 35.6235 -206.462376) (xy 35.6235 -206.871316) (xy 41.664636 -206.871316)
			(xy 41.664636 -206.462376) (xy 41.665003 -206.452216) (xy 41.672813 -206.433456) (xy 41.687227 -206.419132)
			(xy 41.706035 -206.41144) (xy 41.716198 -206.411068) (xy 43.115738 -206.411068) (xy 43.125871 -206.411496)
			(xy 43.144598 -206.419242) (xy 43.158954 -206.433546) (xy 43.166767 -206.452245) (xy 43.1673 -206.462376)
			(xy 43.1673 -206.871316) (xy 49.208436 -206.871316) (xy 49.208436 -206.462376) (xy 49.208803 -206.452216)
			(xy 49.216613 -206.433456) (xy 49.231027 -206.419132) (xy 49.249835 -206.41144) (xy 49.259998 -206.411068)
			(xy 50.659538 -206.411068) (xy 50.669671 -206.411496) (xy 50.688398 -206.419242) (xy 50.702754 -206.433546)
			(xy 50.710567 -206.452245) (xy 50.7111 -206.462376) (xy 50.7111 -206.871316) (xy 56.752236 -206.871316)
			(xy 56.752236 -206.462376) (xy 56.752603 -206.452216) (xy 56.760413 -206.433456) (xy 56.774827 -206.419132)
			(xy 56.793635 -206.41144) (xy 56.803798 -206.411068) (xy 58.203338 -206.411068) (xy 58.213471 -206.411496)
			(xy 58.232198 -206.419242) (xy 58.246554 -206.433546) (xy 58.254367 -206.452245) (xy 58.2549 -206.462376)
			(xy 58.2549 -206.871316) (xy 64.296036 -206.871316) (xy 64.296036 -206.462376) (xy 64.296403 -206.452216)
			(xy 64.304213 -206.433456) (xy 64.318627 -206.419132) (xy 64.337435 -206.41144) (xy 64.347598 -206.411068)
			(xy 65.747138 -206.411068) (xy 65.757271 -206.411496) (xy 65.775998 -206.419242) (xy 65.790354 -206.433546)
			(xy 65.798167 -206.452245) (xy 65.7987 -206.462376) (xy 65.7987 -206.871316) (xy 65.798292 -206.881471)
			(xy 65.790491 -206.900224) (xy 65.77609 -206.914547) (xy 65.757295 -206.922246) (xy 65.747138 -206.922624)
			(xy 64.347598 -206.922624) (xy 64.337467 -206.922174) (xy 64.318739 -206.914439) (xy 64.304381 -206.900141)
			(xy 64.296569 -206.881445) (xy 64.296036 -206.871316) (xy 58.2549 -206.871316) (xy 58.254492 -206.881471)
			(xy 58.246691 -206.900224) (xy 58.23229 -206.914547) (xy 58.213495 -206.922246) (xy 58.203338 -206.922624)
			(xy 56.803798 -206.922624) (xy 56.793667 -206.922174) (xy 56.774939 -206.914439) (xy 56.760581 -206.900141)
			(xy 56.752769 -206.881445) (xy 56.752236 -206.871316) (xy 50.7111 -206.871316) (xy 50.710692 -206.881471)
			(xy 50.702891 -206.900224) (xy 50.68849 -206.914547) (xy 50.669695 -206.922246) (xy 50.659538 -206.922624)
			(xy 49.259998 -206.922624) (xy 49.249867 -206.922174) (xy 49.231139 -206.914439) (xy 49.216781 -206.900141)
			(xy 49.208969 -206.881445) (xy 49.208436 -206.871316) (xy 43.1673 -206.871316) (xy 43.166892 -206.881471)
			(xy 43.159091 -206.900224) (xy 43.14469 -206.914547) (xy 43.125895 -206.922246) (xy 43.115738 -206.922624)
			(xy 41.716198 -206.922624) (xy 41.706067 -206.922174) (xy 41.687339 -206.914439) (xy 41.672981 -206.900141)
			(xy 41.665169 -206.881445) (xy 41.664636 -206.871316) (xy 35.6235 -206.871316) (xy 35.623092 -206.881471)
			(xy 35.615291 -206.900224) (xy 35.60089 -206.914547) (xy 35.582095 -206.922246) (xy 35.571938 -206.922624)
			(xy 34.172398 -206.922624) (xy 34.162267 -206.922174) (xy 34.143539 -206.914439) (xy 34.129181 -206.900141)
			(xy 34.121369 -206.881445) (xy 34.120836 -206.871316) (xy 28.0797 -206.871316) (xy 28.079292 -206.881471)
			(xy 28.071491 -206.900224) (xy 28.05709 -206.914547) (xy 28.038295 -206.922246) (xy 28.028138 -206.922624)
			(xy 26.628598 -206.922624) (xy 26.618467 -206.922174) (xy 26.599739 -206.914439) (xy 26.585381 -206.900141)
			(xy 26.577569 -206.881445) (xy 26.577036 -206.871316) (xy 20.5359 -206.871316) (xy 20.535492 -206.881471)
			(xy 20.527691 -206.900224) (xy 20.51329 -206.914547) (xy 20.494495 -206.922246) (xy 20.484338 -206.922624)
			(xy 19.084798 -206.922624) (xy 19.074667 -206.922174) (xy 19.055939 -206.914439) (xy 19.041581 -206.900141)
			(xy 19.033769 -206.881445) (xy 19.033236 -206.871316) (xy 12.9921 -206.871316) (xy 12.991692 -206.881471)
			(xy 12.983891 -206.900224) (xy 12.96949 -206.914547) (xy 12.950695 -206.922246) (xy 12.940538 -206.922624)
			(xy 11.540998 -206.922624) (xy 11.530867 -206.922174) (xy 11.512139 -206.914439) (xy 11.497781 -206.900141)
			(xy 11.489969 -206.881445) (xy 11.489436 -206.871316) (xy 2.509012 -206.871316) (xy 2.509012 -207.721454)
			(xy 7.389368 -207.721454) (xy 7.389368 -207.312514) (xy 7.389776 -207.30234) (xy 7.397562 -207.283539)
			(xy 7.411953 -207.269153) (xy 7.430755 -207.261373) (xy 7.44093 -207.260952) (xy 8.84047 -207.260952)
			(xy 8.850641 -207.261389) (xy 8.869438 -207.269167) (xy 8.883824 -207.283549) (xy 8.891608 -207.302343)
			(xy 8.892032 -207.312514) (xy 8.892032 -207.721454) (xy 14.933168 -207.721454) (xy 14.933168 -207.312514)
			(xy 14.933576 -207.30234) (xy 14.941362 -207.283539) (xy 14.955753 -207.269153) (xy 14.974555 -207.261373)
			(xy 14.98473 -207.260952) (xy 16.38427 -207.260952) (xy 16.394441 -207.261389) (xy 16.413238 -207.269167)
			(xy 16.427624 -207.283549) (xy 16.435408 -207.302343) (xy 16.435832 -207.312514) (xy 16.435832 -207.721454)
			(xy 22.476968 -207.721454) (xy 22.476968 -207.312514) (xy 22.477376 -207.30234) (xy 22.485162 -207.283539)
			(xy 22.499553 -207.269153) (xy 22.518355 -207.261373) (xy 22.52853 -207.260952) (xy 23.92807 -207.260952)
			(xy 23.938241 -207.261389) (xy 23.957038 -207.269167) (xy 23.971424 -207.283549) (xy 23.979208 -207.302343)
			(xy 23.979632 -207.312514) (xy 23.979632 -207.721454) (xy 30.020768 -207.721454) (xy 30.020768 -207.312514)
			(xy 30.021176 -207.30234) (xy 30.028962 -207.283539) (xy 30.043353 -207.269153) (xy 30.062155 -207.261373)
			(xy 30.07233 -207.260952) (xy 31.47187 -207.260952) (xy 31.482041 -207.261389) (xy 31.500838 -207.269167)
			(xy 31.515224 -207.283549) (xy 31.523008 -207.302343) (xy 31.523432 -207.312514) (xy 31.523432 -207.721454)
			(xy 37.564568 -207.721454) (xy 37.564568 -207.312514) (xy 37.564976 -207.30234) (xy 37.572762 -207.283539)
			(xy 37.587153 -207.269153) (xy 37.605955 -207.261373) (xy 37.61613 -207.260952) (xy 39.01567 -207.260952)
			(xy 39.025841 -207.261389) (xy 39.044638 -207.269167) (xy 39.059024 -207.283549) (xy 39.066808 -207.302343)
			(xy 39.067232 -207.312514) (xy 39.067232 -207.721454) (xy 45.108368 -207.721454) (xy 45.108368 -207.312514)
			(xy 45.108776 -207.30234) (xy 45.116562 -207.283539) (xy 45.130953 -207.269153) (xy 45.149755 -207.261373)
			(xy 45.15993 -207.260952) (xy 46.55947 -207.260952) (xy 46.569641 -207.261389) (xy 46.588438 -207.269167)
			(xy 46.602824 -207.283549) (xy 46.610608 -207.302343) (xy 46.611032 -207.312514) (xy 46.611032 -207.721454)
			(xy 52.652168 -207.721454) (xy 52.652168 -207.312514) (xy 52.652576 -207.30234) (xy 52.660362 -207.283539)
			(xy 52.674753 -207.269153) (xy 52.693555 -207.261373) (xy 52.70373 -207.260952) (xy 54.10327 -207.260952)
			(xy 54.113441 -207.261389) (xy 54.132238 -207.269167) (xy 54.146624 -207.283549) (xy 54.154408 -207.302343)
			(xy 54.154832 -207.312514) (xy 54.154832 -207.721454) (xy 60.195968 -207.721454) (xy 60.195968 -207.312514)
			(xy 60.196376 -207.30234) (xy 60.204162 -207.283539) (xy 60.218553 -207.269153) (xy 60.237355 -207.261373)
			(xy 60.24753 -207.260952) (xy 61.64707 -207.260952) (xy 61.657241 -207.261389) (xy 61.676038 -207.269167)
			(xy 61.690424 -207.283549) (xy 61.698208 -207.302343) (xy 61.698632 -207.312514) (xy 61.698632 -207.721454)
			(xy 61.698198 -207.731626) (xy 61.690422 -207.750426) (xy 61.676039 -207.764813) (xy 61.657242 -207.772595)
			(xy 61.64707 -207.773016) (xy 60.24753 -207.773016) (xy 60.237355 -207.77261) (xy 60.218552 -207.764827)
			(xy 60.204164 -207.750435) (xy 60.196387 -207.731629) (xy 60.195968 -207.721454) (xy 54.154832 -207.721454)
			(xy 54.154398 -207.731626) (xy 54.146622 -207.750426) (xy 54.132239 -207.764813) (xy 54.113442 -207.772595)
			(xy 54.10327 -207.773016) (xy 52.70373 -207.773016) (xy 52.693555 -207.77261) (xy 52.674752 -207.764827)
			(xy 52.660364 -207.750435) (xy 52.652587 -207.731629) (xy 52.652168 -207.721454) (xy 46.611032 -207.721454)
			(xy 46.610598 -207.731626) (xy 46.602822 -207.750426) (xy 46.588439 -207.764813) (xy 46.569642 -207.772595)
			(xy 46.55947 -207.773016) (xy 45.15993 -207.773016) (xy 45.149755 -207.77261) (xy 45.130952 -207.764827)
			(xy 45.116564 -207.750435) (xy 45.108787 -207.731629) (xy 45.108368 -207.721454) (xy 39.067232 -207.721454)
			(xy 39.066798 -207.731626) (xy 39.059022 -207.750426) (xy 39.044639 -207.764813) (xy 39.025842 -207.772595)
			(xy 39.01567 -207.773016) (xy 37.61613 -207.773016) (xy 37.605955 -207.77261) (xy 37.587152 -207.764827)
			(xy 37.572764 -207.750435) (xy 37.564987 -207.731629) (xy 37.564568 -207.721454) (xy 31.523432 -207.721454)
			(xy 31.522998 -207.731626) (xy 31.515222 -207.750426) (xy 31.500839 -207.764813) (xy 31.482042 -207.772595)
			(xy 31.47187 -207.773016) (xy 30.07233 -207.773016) (xy 30.062155 -207.77261) (xy 30.043352 -207.764827)
			(xy 30.028964 -207.750435) (xy 30.021187 -207.731629) (xy 30.020768 -207.721454) (xy 23.979632 -207.721454)
			(xy 23.979198 -207.731626) (xy 23.971422 -207.750426) (xy 23.957039 -207.764813) (xy 23.938242 -207.772595)
			(xy 23.92807 -207.773016) (xy 22.52853 -207.773016) (xy 22.518355 -207.77261) (xy 22.499552 -207.764827)
			(xy 22.485164 -207.750435) (xy 22.477387 -207.731629) (xy 22.476968 -207.721454) (xy 16.435832 -207.721454)
			(xy 16.435398 -207.731626) (xy 16.427622 -207.750426) (xy 16.413239 -207.764813) (xy 16.394442 -207.772595)
			(xy 16.38427 -207.773016) (xy 14.98473 -207.773016) (xy 14.974555 -207.77261) (xy 14.955752 -207.764827)
			(xy 14.941364 -207.750435) (xy 14.933587 -207.731629) (xy 14.933168 -207.721454) (xy 8.892032 -207.721454)
			(xy 8.891598 -207.731626) (xy 8.883822 -207.750426) (xy 8.869439 -207.764813) (xy 8.850642 -207.772595)
			(xy 8.84047 -207.773016) (xy 7.44093 -207.773016) (xy 7.430755 -207.77261) (xy 7.411952 -207.764827)
			(xy 7.397564 -207.750435) (xy 7.389787 -207.731629) (xy 7.389368 -207.721454) (xy 2.509012 -207.721454)
			(xy 2.509012 -208.571338) (xy 11.489436 -208.571338) (xy 11.489436 -208.162398) (xy 11.489932 -208.15224)
			(xy 11.497706 -208.133472) (xy 11.512072 -208.119106) (xy 11.53084 -208.111332) (xy 11.540998 -208.110836)
			(xy 12.940538 -208.110836) (xy 12.950698 -208.111302) (xy 12.969468 -208.119089) (xy 12.983831 -208.133463)
			(xy 12.991605 -208.152238) (xy 12.9921 -208.162398) (xy 12.9921 -208.571338) (xy 19.033236 -208.571338)
			(xy 19.033236 -208.162398) (xy 19.033732 -208.15224) (xy 19.041506 -208.133472) (xy 19.055872 -208.119106)
			(xy 19.07464 -208.111332) (xy 19.084798 -208.110836) (xy 20.484338 -208.110836) (xy 20.494498 -208.111302)
			(xy 20.513268 -208.119089) (xy 20.527631 -208.133463) (xy 20.535405 -208.152238) (xy 20.5359 -208.162398)
			(xy 20.5359 -208.571338) (xy 26.577036 -208.571338) (xy 26.577036 -208.162398) (xy 26.577532 -208.15224)
			(xy 26.585306 -208.133472) (xy 26.599672 -208.119106) (xy 26.61844 -208.111332) (xy 26.628598 -208.110836)
			(xy 28.028138 -208.110836) (xy 28.038298 -208.111302) (xy 28.057068 -208.119089) (xy 28.071431 -208.133463)
			(xy 28.079205 -208.152238) (xy 28.0797 -208.162398) (xy 28.0797 -208.571338) (xy 34.120836 -208.571338)
			(xy 34.120836 -208.162398) (xy 34.121332 -208.15224) (xy 34.129106 -208.133472) (xy 34.143472 -208.119106)
			(xy 34.16224 -208.111332) (xy 34.172398 -208.110836) (xy 35.571938 -208.110836) (xy 35.582098 -208.111302)
			(xy 35.600868 -208.119089) (xy 35.615231 -208.133463) (xy 35.623005 -208.152238) (xy 35.6235 -208.162398)
			(xy 35.6235 -208.571338) (xy 41.664636 -208.571338) (xy 41.664636 -208.162398) (xy 41.665132 -208.15224)
			(xy 41.672906 -208.133472) (xy 41.687272 -208.119106) (xy 41.70604 -208.111332) (xy 41.716198 -208.110836)
			(xy 43.115738 -208.110836) (xy 43.125898 -208.111302) (xy 43.144668 -208.119089) (xy 43.159031 -208.133463)
			(xy 43.166805 -208.152238) (xy 43.1673 -208.162398) (xy 43.1673 -208.571338) (xy 49.208436 -208.571338)
			(xy 49.208436 -208.162398) (xy 49.208932 -208.15224) (xy 49.216706 -208.133472) (xy 49.231072 -208.119106)
			(xy 49.24984 -208.111332) (xy 49.259998 -208.110836) (xy 50.659538 -208.110836) (xy 50.669698 -208.111302)
			(xy 50.688468 -208.119089) (xy 50.702831 -208.133463) (xy 50.710605 -208.152238) (xy 50.7111 -208.162398)
			(xy 50.7111 -208.571338) (xy 56.752236 -208.571338) (xy 56.752236 -208.162398) (xy 56.752732 -208.15224)
			(xy 56.760506 -208.133472) (xy 56.774872 -208.119106) (xy 56.79364 -208.111332) (xy 56.803798 -208.110836)
			(xy 58.203338 -208.110836) (xy 58.213498 -208.111302) (xy 58.232268 -208.119089) (xy 58.246631 -208.133463)
			(xy 58.254405 -208.152238) (xy 58.2549 -208.162398) (xy 58.2549 -208.571338) (xy 64.296036 -208.571338)
			(xy 64.296036 -208.162398) (xy 64.296532 -208.15224) (xy 64.304306 -208.133472) (xy 64.318672 -208.119106)
			(xy 64.33744 -208.111332) (xy 64.347598 -208.110836) (xy 65.747138 -208.110836) (xy 65.757298 -208.111302)
			(xy 65.776068 -208.119089) (xy 65.790431 -208.133463) (xy 65.798205 -208.152238) (xy 65.7987 -208.162398)
			(xy 65.7987 -208.571338) (xy 162.162236 -208.571338) (xy 162.162236 -208.162398) (xy 162.162732 -208.15224)
			(xy 162.170506 -208.133472) (xy 162.184872 -208.119106) (xy 162.20364 -208.111332) (xy 162.213798 -208.110836)
			(xy 163.613338 -208.110836) (xy 163.623498 -208.111302) (xy 163.642268 -208.119089) (xy 163.656631 -208.133463)
			(xy 163.664405 -208.152238) (xy 163.6649 -208.162398) (xy 163.6649 -208.571338) (xy 169.706036 -208.571338)
			(xy 169.706036 -208.162398) (xy 169.706532 -208.15224) (xy 169.714306 -208.133472) (xy 169.728672 -208.119106)
			(xy 169.74744 -208.111332) (xy 169.757598 -208.110836) (xy 171.157138 -208.110836) (xy 171.167298 -208.111302)
			(xy 171.186068 -208.119089) (xy 171.200431 -208.133463) (xy 171.208205 -208.152238) (xy 171.2087 -208.162398)
			(xy 171.2087 -208.571338) (xy 177.249836 -208.571338) (xy 177.249836 -208.162398) (xy 177.250332 -208.15224)
			(xy 177.258106 -208.133472) (xy 177.272472 -208.119106) (xy 177.29124 -208.111332) (xy 177.301398 -208.110836)
			(xy 178.700938 -208.110836) (xy 178.711098 -208.111302) (xy 178.729868 -208.119089) (xy 178.744231 -208.133463)
			(xy 178.752005 -208.152238) (xy 178.7525 -208.162398) (xy 178.7525 -208.571338) (xy 184.793636 -208.571338)
			(xy 184.793636 -208.162398) (xy 184.794132 -208.15224) (xy 184.801906 -208.133472) (xy 184.816272 -208.119106)
			(xy 184.83504 -208.111332) (xy 184.845198 -208.110836) (xy 186.244738 -208.110836) (xy 186.254898 -208.111302)
			(xy 186.273668 -208.119089) (xy 186.288031 -208.133463) (xy 186.295805 -208.152238) (xy 186.2963 -208.162398)
			(xy 186.2963 -208.571338) (xy 192.337436 -208.571338) (xy 192.337436 -208.162398) (xy 192.337932 -208.15224)
			(xy 192.345706 -208.133472) (xy 192.360072 -208.119106) (xy 192.37884 -208.111332) (xy 192.388998 -208.110836)
			(xy 193.788538 -208.110836) (xy 193.798698 -208.111302) (xy 193.817468 -208.119089) (xy 193.831831 -208.133463)
			(xy 193.839605 -208.152238) (xy 193.8401 -208.162398) (xy 193.8401 -208.571338) (xy 199.881236 -208.571338)
			(xy 199.881236 -208.162398) (xy 199.881732 -208.15224) (xy 199.889506 -208.133472) (xy 199.903872 -208.119106)
			(xy 199.92264 -208.111332) (xy 199.932798 -208.110836) (xy 201.332338 -208.110836) (xy 201.342498 -208.111302)
			(xy 201.361268 -208.119089) (xy 201.375631 -208.133463) (xy 201.383405 -208.152238) (xy 201.3839 -208.162398)
			(xy 201.3839 -208.571338) (xy 207.425036 -208.571338) (xy 207.425036 -208.162398) (xy 207.425532 -208.15224)
			(xy 207.433306 -208.133472) (xy 207.447672 -208.119106) (xy 207.46644 -208.111332) (xy 207.476598 -208.110836)
			(xy 208.876138 -208.110836) (xy 208.886298 -208.111302) (xy 208.905068 -208.119089) (xy 208.919431 -208.133463)
			(xy 208.927205 -208.152238) (xy 208.9277 -208.162398) (xy 208.9277 -208.571338) (xy 214.968836 -208.571338)
			(xy 214.968836 -208.162398) (xy 214.969332 -208.15224) (xy 214.977106 -208.133472) (xy 214.991472 -208.119106)
			(xy 215.01024 -208.111332) (xy 215.020398 -208.110836) (xy 216.419938 -208.110836) (xy 216.430098 -208.111302)
			(xy 216.448868 -208.119089) (xy 216.463231 -208.133463) (xy 216.471005 -208.152238) (xy 216.4715 -208.162398)
			(xy 216.4715 -208.571338) (xy 259.429504 -208.571338) (xy 259.429504 -208.162398) (xy 259.430031 -208.152244)
			(xy 259.4378 -208.133482) (xy 259.452155 -208.119118) (xy 259.470913 -208.111337) (xy 259.481066 -208.110836)
			(xy 260.880606 -208.110836) (xy 260.890764 -208.111329) (xy 260.909533 -208.119105) (xy 260.923898 -208.133471)
			(xy 260.931672 -208.15224) (xy 260.932168 -208.162398) (xy 260.932168 -208.571338) (xy 266.973304 -208.571338)
			(xy 266.973304 -208.162398) (xy 266.973831 -208.152244) (xy 266.9816 -208.133482) (xy 266.995955 -208.119118)
			(xy 267.014713 -208.111337) (xy 267.024866 -208.110836) (xy 268.424406 -208.110836) (xy 268.434564 -208.111329)
			(xy 268.453333 -208.119105) (xy 268.467698 -208.133471) (xy 268.475472 -208.15224) (xy 268.475968 -208.162398)
			(xy 268.475968 -208.571338) (xy 274.517104 -208.571338) (xy 274.517104 -208.162398) (xy 274.517631 -208.152244)
			(xy 274.5254 -208.133482) (xy 274.539755 -208.119118) (xy 274.558513 -208.111337) (xy 274.568666 -208.110836)
			(xy 275.968206 -208.110836) (xy 275.978364 -208.111329) (xy 275.997133 -208.119105) (xy 276.011498 -208.133471)
			(xy 276.019272 -208.15224) (xy 276.019768 -208.162398) (xy 276.019768 -208.571338) (xy 282.060904 -208.571338)
			(xy 282.060904 -208.162398) (xy 282.061431 -208.152244) (xy 282.0692 -208.133482) (xy 282.083555 -208.119118)
			(xy 282.102313 -208.111337) (xy 282.112466 -208.110836) (xy 283.512006 -208.110836) (xy 283.522164 -208.111329)
			(xy 283.540933 -208.119105) (xy 283.555298 -208.133471) (xy 283.563072 -208.15224) (xy 283.563568 -208.162398)
			(xy 283.563568 -208.571338) (xy 289.604704 -208.571338) (xy 289.604704 -208.162398) (xy 289.605231 -208.152244)
			(xy 289.613 -208.133482) (xy 289.627355 -208.119118) (xy 289.646113 -208.111337) (xy 289.656266 -208.110836)
			(xy 291.055806 -208.110836) (xy 291.065964 -208.111329) (xy 291.084733 -208.119105) (xy 291.099098 -208.133471)
			(xy 291.106872 -208.15224) (xy 291.107368 -208.162398) (xy 291.107368 -208.571338) (xy 297.148504 -208.571338)
			(xy 297.148504 -208.162398) (xy 297.149031 -208.152244) (xy 297.1568 -208.133482) (xy 297.171155 -208.119118)
			(xy 297.189913 -208.111337) (xy 297.200066 -208.110836) (xy 298.599606 -208.110836) (xy 298.609764 -208.111329)
			(xy 298.628533 -208.119105) (xy 298.642898 -208.133471) (xy 298.650672 -208.15224) (xy 298.651168 -208.162398)
			(xy 298.651168 -208.571338) (xy 304.692304 -208.571338) (xy 304.692304 -208.162398) (xy 304.692831 -208.152244)
			(xy 304.7006 -208.133482) (xy 304.714955 -208.119118) (xy 304.733713 -208.111337) (xy 304.743866 -208.110836)
			(xy 306.143406 -208.110836) (xy 306.153564 -208.111329) (xy 306.172333 -208.119105) (xy 306.186698 -208.133471)
			(xy 306.194472 -208.15224) (xy 306.194968 -208.162398) (xy 306.194968 -208.571338) (xy 312.236104 -208.571338)
			(xy 312.236104 -208.162398) (xy 312.236631 -208.152244) (xy 312.2444 -208.133482) (xy 312.258755 -208.119118)
			(xy 312.277513 -208.111337) (xy 312.287666 -208.110836) (xy 313.687206 -208.110836) (xy 313.697364 -208.111329)
			(xy 313.716133 -208.119105) (xy 313.730498 -208.133471) (xy 313.738272 -208.15224) (xy 313.738768 -208.162398)
			(xy 313.738768 -208.571338) (xy 410.102304 -208.571338) (xy 410.102304 -208.162398) (xy 410.102831 -208.152244)
			(xy 410.1106 -208.133482) (xy 410.124955 -208.119118) (xy 410.143713 -208.111337) (xy 410.153866 -208.110836)
			(xy 411.553406 -208.110836) (xy 411.563564 -208.111329) (xy 411.582333 -208.119105) (xy 411.596698 -208.133471)
			(xy 411.604472 -208.15224) (xy 411.604968 -208.162398) (xy 411.604968 -208.571338) (xy 417.646104 -208.571338)
			(xy 417.646104 -208.162398) (xy 417.646631 -208.152244) (xy 417.6544 -208.133482) (xy 417.668755 -208.119118)
			(xy 417.687513 -208.111337) (xy 417.697666 -208.110836) (xy 419.097206 -208.110836) (xy 419.107364 -208.111329)
			(xy 419.126133 -208.119105) (xy 419.140498 -208.133471) (xy 419.148272 -208.15224) (xy 419.148768 -208.162398)
			(xy 419.148768 -208.571338) (xy 425.189904 -208.571338) (xy 425.189904 -208.162398) (xy 425.190431 -208.152244)
			(xy 425.1982 -208.133482) (xy 425.212555 -208.119118) (xy 425.231313 -208.111337) (xy 425.241466 -208.110836)
			(xy 426.641006 -208.110836) (xy 426.651164 -208.111329) (xy 426.669933 -208.119105) (xy 426.684298 -208.133471)
			(xy 426.692072 -208.15224) (xy 426.692568 -208.162398) (xy 426.692568 -208.571338) (xy 432.733704 -208.571338)
			(xy 432.733704 -208.162398) (xy 432.734231 -208.152244) (xy 432.742 -208.133482) (xy 432.756355 -208.119118)
			(xy 432.775113 -208.111337) (xy 432.785266 -208.110836) (xy 434.184806 -208.110836) (xy 434.194964 -208.111329)
			(xy 434.213733 -208.119105) (xy 434.228098 -208.133471) (xy 434.235872 -208.15224) (xy 434.236368 -208.162398)
			(xy 434.236368 -208.571338) (xy 440.277504 -208.571338) (xy 440.277504 -208.162398) (xy 440.278031 -208.152244)
			(xy 440.2858 -208.133482) (xy 440.300155 -208.119118) (xy 440.318913 -208.111337) (xy 440.329066 -208.110836)
			(xy 441.728606 -208.110836) (xy 441.738764 -208.111329) (xy 441.757533 -208.119105) (xy 441.771898 -208.133471)
			(xy 441.779672 -208.15224) (xy 441.780168 -208.162398) (xy 441.780168 -208.571338) (xy 447.821304 -208.571338)
			(xy 447.821304 -208.162398) (xy 447.821831 -208.152244) (xy 447.8296 -208.133482) (xy 447.843955 -208.119118)
			(xy 447.862713 -208.111337) (xy 447.872866 -208.110836) (xy 449.272406 -208.110836) (xy 449.282564 -208.111329)
			(xy 449.301333 -208.119105) (xy 449.315698 -208.133471) (xy 449.323472 -208.15224) (xy 449.323968 -208.162398)
			(xy 449.323968 -208.571338) (xy 455.365104 -208.571338) (xy 455.365104 -208.162398) (xy 455.365631 -208.152244)
			(xy 455.3734 -208.133482) (xy 455.387755 -208.119118) (xy 455.406513 -208.111337) (xy 455.416666 -208.110836)
			(xy 456.816206 -208.110836) (xy 456.826364 -208.111329) (xy 456.845133 -208.119105) (xy 456.859498 -208.133471)
			(xy 456.867272 -208.15224) (xy 456.867768 -208.162398) (xy 456.867768 -208.571338) (xy 462.908904 -208.571338)
			(xy 462.908904 -208.162398) (xy 462.909431 -208.152244) (xy 462.9172 -208.133482) (xy 462.931555 -208.119118)
			(xy 462.950313 -208.111337) (xy 462.960466 -208.110836) (xy 464.360006 -208.110836) (xy 464.370164 -208.111329)
			(xy 464.388933 -208.119105) (xy 464.403298 -208.133471) (xy 464.411072 -208.15224) (xy 464.411568 -208.162398)
			(xy 464.411568 -208.571338) (xy 464.411098 -208.581497) (xy 464.403312 -208.600266) (xy 464.388939 -208.61463)
			(xy 464.370166 -208.622404) (xy 464.360006 -208.6229) (xy 462.960466 -208.6229) (xy 462.950311 -208.622395)
			(xy 462.931548 -208.614617) (xy 462.917185 -208.600255) (xy 462.909405 -208.581493) (xy 462.908904 -208.571338)
			(xy 456.867768 -208.571338) (xy 456.867298 -208.581497) (xy 456.859512 -208.600266) (xy 456.845139 -208.61463)
			(xy 456.826366 -208.622404) (xy 456.816206 -208.6229) (xy 455.416666 -208.6229) (xy 455.406511 -208.622395)
			(xy 455.387748 -208.614617) (xy 455.373385 -208.600255) (xy 455.365605 -208.581493) (xy 455.365104 -208.571338)
			(xy 449.323968 -208.571338) (xy 449.323498 -208.581497) (xy 449.315712 -208.600266) (xy 449.301339 -208.61463)
			(xy 449.282566 -208.622404) (xy 449.272406 -208.6229) (xy 447.872866 -208.6229) (xy 447.862711 -208.622395)
			(xy 447.843948 -208.614617) (xy 447.829585 -208.600255) (xy 447.821805 -208.581493) (xy 447.821304 -208.571338)
			(xy 441.780168 -208.571338) (xy 441.779698 -208.581497) (xy 441.771912 -208.600266) (xy 441.757539 -208.61463)
			(xy 441.738766 -208.622404) (xy 441.728606 -208.6229) (xy 440.329066 -208.6229) (xy 440.318911 -208.622395)
			(xy 440.300148 -208.614617) (xy 440.285785 -208.600255) (xy 440.278005 -208.581493) (xy 440.277504 -208.571338)
			(xy 434.236368 -208.571338) (xy 434.235898 -208.581497) (xy 434.228112 -208.600266) (xy 434.213739 -208.61463)
			(xy 434.194966 -208.622404) (xy 434.184806 -208.6229) (xy 432.785266 -208.6229) (xy 432.775111 -208.622395)
			(xy 432.756348 -208.614617) (xy 432.741985 -208.600255) (xy 432.734205 -208.581493) (xy 432.733704 -208.571338)
			(xy 426.692568 -208.571338) (xy 426.692098 -208.581497) (xy 426.684312 -208.600266) (xy 426.669939 -208.61463)
			(xy 426.651166 -208.622404) (xy 426.641006 -208.6229) (xy 425.241466 -208.6229) (xy 425.231311 -208.622395)
			(xy 425.212548 -208.614617) (xy 425.198185 -208.600255) (xy 425.190405 -208.581493) (xy 425.189904 -208.571338)
			(xy 419.148768 -208.571338) (xy 419.148298 -208.581497) (xy 419.140512 -208.600266) (xy 419.126139 -208.61463)
			(xy 419.107366 -208.622404) (xy 419.097206 -208.6229) (xy 417.697666 -208.6229) (xy 417.687511 -208.622395)
			(xy 417.668748 -208.614617) (xy 417.654385 -208.600255) (xy 417.646605 -208.581493) (xy 417.646104 -208.571338)
			(xy 411.604968 -208.571338) (xy 411.604498 -208.581497) (xy 411.596712 -208.600266) (xy 411.582339 -208.61463)
			(xy 411.563566 -208.622404) (xy 411.553406 -208.6229) (xy 410.153866 -208.6229) (xy 410.143711 -208.622395)
			(xy 410.124948 -208.614617) (xy 410.110585 -208.600255) (xy 410.102805 -208.581493) (xy 410.102304 -208.571338)
			(xy 313.738768 -208.571338) (xy 313.738298 -208.581497) (xy 313.730512 -208.600266) (xy 313.716139 -208.61463)
			(xy 313.697366 -208.622404) (xy 313.687206 -208.6229) (xy 312.287666 -208.6229) (xy 312.277511 -208.622395)
			(xy 312.258748 -208.614617) (xy 312.244385 -208.600255) (xy 312.236605 -208.581493) (xy 312.236104 -208.571338)
			(xy 306.194968 -208.571338) (xy 306.194498 -208.581497) (xy 306.186712 -208.600266) (xy 306.172339 -208.61463)
			(xy 306.153566 -208.622404) (xy 306.143406 -208.6229) (xy 304.743866 -208.6229) (xy 304.733711 -208.622395)
			(xy 304.714948 -208.614617) (xy 304.700585 -208.600255) (xy 304.692805 -208.581493) (xy 304.692304 -208.571338)
			(xy 298.651168 -208.571338) (xy 298.650698 -208.581497) (xy 298.642912 -208.600266) (xy 298.628539 -208.61463)
			(xy 298.609766 -208.622404) (xy 298.599606 -208.6229) (xy 297.200066 -208.6229) (xy 297.189911 -208.622395)
			(xy 297.171148 -208.614617) (xy 297.156785 -208.600255) (xy 297.149005 -208.581493) (xy 297.148504 -208.571338)
			(xy 291.107368 -208.571338) (xy 291.106898 -208.581497) (xy 291.099112 -208.600266) (xy 291.084739 -208.61463)
			(xy 291.065966 -208.622404) (xy 291.055806 -208.6229) (xy 289.656266 -208.6229) (xy 289.646111 -208.622395)
			(xy 289.627348 -208.614617) (xy 289.612985 -208.600255) (xy 289.605205 -208.581493) (xy 289.604704 -208.571338)
			(xy 283.563568 -208.571338) (xy 283.563098 -208.581497) (xy 283.555312 -208.600266) (xy 283.540939 -208.61463)
			(xy 283.522166 -208.622404) (xy 283.512006 -208.6229) (xy 282.112466 -208.6229) (xy 282.102311 -208.622395)
			(xy 282.083548 -208.614617) (xy 282.069185 -208.600255) (xy 282.061405 -208.581493) (xy 282.060904 -208.571338)
			(xy 276.019768 -208.571338) (xy 276.019298 -208.581497) (xy 276.011512 -208.600266) (xy 275.997139 -208.61463)
			(xy 275.978366 -208.622404) (xy 275.968206 -208.6229) (xy 274.568666 -208.6229) (xy 274.558511 -208.622395)
			(xy 274.539748 -208.614617) (xy 274.525385 -208.600255) (xy 274.517605 -208.581493) (xy 274.517104 -208.571338)
			(xy 268.475968 -208.571338) (xy 268.475498 -208.581497) (xy 268.467712 -208.600266) (xy 268.453339 -208.61463)
			(xy 268.434566 -208.622404) (xy 268.424406 -208.6229) (xy 267.024866 -208.6229) (xy 267.014711 -208.622395)
			(xy 266.995948 -208.614617) (xy 266.981585 -208.600255) (xy 266.973805 -208.581493) (xy 266.973304 -208.571338)
			(xy 260.932168 -208.571338) (xy 260.931698 -208.581497) (xy 260.923912 -208.600266) (xy 260.909539 -208.61463)
			(xy 260.890766 -208.622404) (xy 260.880606 -208.6229) (xy 259.481066 -208.6229) (xy 259.470911 -208.622395)
			(xy 259.452148 -208.614617) (xy 259.437785 -208.600255) (xy 259.430005 -208.581493) (xy 259.429504 -208.571338)
			(xy 216.4715 -208.571338) (xy 216.470999 -208.581494) (xy 216.463219 -208.600256) (xy 216.448856 -208.614619)
			(xy 216.430094 -208.622399) (xy 216.419938 -208.6229) (xy 215.020398 -208.6229) (xy 215.010245 -208.622369)
			(xy 214.991483 -208.614601) (xy 214.977119 -208.600247) (xy 214.969338 -208.581491) (xy 214.968836 -208.571338)
			(xy 208.9277 -208.571338) (xy 208.927199 -208.581494) (xy 208.919419 -208.600256) (xy 208.905056 -208.614619)
			(xy 208.886294 -208.622399) (xy 208.876138 -208.6229) (xy 207.476598 -208.6229) (xy 207.466445 -208.622369)
			(xy 207.447683 -208.614601) (xy 207.433319 -208.600247) (xy 207.425538 -208.581491) (xy 207.425036 -208.571338)
			(xy 201.3839 -208.571338) (xy 201.383399 -208.581494) (xy 201.375619 -208.600256) (xy 201.361256 -208.614619)
			(xy 201.342494 -208.622399) (xy 201.332338 -208.6229) (xy 199.932798 -208.6229) (xy 199.922645 -208.622369)
			(xy 199.903883 -208.614601) (xy 199.889519 -208.600247) (xy 199.881738 -208.581491) (xy 199.881236 -208.571338)
			(xy 193.8401 -208.571338) (xy 193.839599 -208.581494) (xy 193.831819 -208.600256) (xy 193.817456 -208.614619)
			(xy 193.798694 -208.622399) (xy 193.788538 -208.6229) (xy 192.388998 -208.6229) (xy 192.378845 -208.622369)
			(xy 192.360083 -208.614601) (xy 192.345719 -208.600247) (xy 192.337938 -208.581491) (xy 192.337436 -208.571338)
			(xy 186.2963 -208.571338) (xy 186.295799 -208.581494) (xy 186.288019 -208.600256) (xy 186.273656 -208.614619)
			(xy 186.254894 -208.622399) (xy 186.244738 -208.6229) (xy 184.845198 -208.6229) (xy 184.835045 -208.622369)
			(xy 184.816283 -208.614601) (xy 184.801919 -208.600247) (xy 184.794138 -208.581491) (xy 184.793636 -208.571338)
			(xy 178.7525 -208.571338) (xy 178.751999 -208.581494) (xy 178.744219 -208.600256) (xy 178.729856 -208.614619)
			(xy 178.711094 -208.622399) (xy 178.700938 -208.6229) (xy 177.301398 -208.6229) (xy 177.291245 -208.622369)
			(xy 177.272483 -208.614601) (xy 177.258119 -208.600247) (xy 177.250338 -208.581491) (xy 177.249836 -208.571338)
			(xy 171.2087 -208.571338) (xy 171.208199 -208.581494) (xy 171.200419 -208.600256) (xy 171.186056 -208.614619)
			(xy 171.167294 -208.622399) (xy 171.157138 -208.6229) (xy 169.757598 -208.6229) (xy 169.747445 -208.622369)
			(xy 169.728683 -208.614601) (xy 169.714319 -208.600247) (xy 169.706538 -208.581491) (xy 169.706036 -208.571338)
			(xy 163.6649 -208.571338) (xy 163.664399 -208.581494) (xy 163.656619 -208.600256) (xy 163.642256 -208.614619)
			(xy 163.623494 -208.622399) (xy 163.613338 -208.6229) (xy 162.213798 -208.6229) (xy 162.203645 -208.622369)
			(xy 162.184883 -208.614601) (xy 162.170519 -208.600247) (xy 162.162738 -208.581491) (xy 162.162236 -208.571338)
			(xy 65.7987 -208.571338) (xy 65.798199 -208.581494) (xy 65.790419 -208.600256) (xy 65.776056 -208.614619)
			(xy 65.757294 -208.622399) (xy 65.747138 -208.6229) (xy 64.347598 -208.6229) (xy 64.337445 -208.622369)
			(xy 64.318683 -208.614601) (xy 64.304319 -208.600247) (xy 64.296538 -208.581491) (xy 64.296036 -208.571338)
			(xy 58.2549 -208.571338) (xy 58.254399 -208.581494) (xy 58.246619 -208.600256) (xy 58.232256 -208.614619)
			(xy 58.213494 -208.622399) (xy 58.203338 -208.6229) (xy 56.803798 -208.6229) (xy 56.793645 -208.622369)
			(xy 56.774883 -208.614601) (xy 56.760519 -208.600247) (xy 56.752738 -208.581491) (xy 56.752236 -208.571338)
			(xy 50.7111 -208.571338) (xy 50.710599 -208.581494) (xy 50.702819 -208.600256) (xy 50.688456 -208.614619)
			(xy 50.669694 -208.622399) (xy 50.659538 -208.6229) (xy 49.259998 -208.6229) (xy 49.249845 -208.622369)
			(xy 49.231083 -208.614601) (xy 49.216719 -208.600247) (xy 49.208938 -208.581491) (xy 49.208436 -208.571338)
			(xy 43.1673 -208.571338) (xy 43.166799 -208.581494) (xy 43.159019 -208.600256) (xy 43.144656 -208.614619)
			(xy 43.125894 -208.622399) (xy 43.115738 -208.6229) (xy 41.716198 -208.6229) (xy 41.706045 -208.622369)
			(xy 41.687283 -208.614601) (xy 41.672919 -208.600247) (xy 41.665138 -208.581491) (xy 41.664636 -208.571338)
			(xy 35.6235 -208.571338) (xy 35.622999 -208.581494) (xy 35.615219 -208.600256) (xy 35.600856 -208.614619)
			(xy 35.582094 -208.622399) (xy 35.571938 -208.6229) (xy 34.172398 -208.6229) (xy 34.162245 -208.622369)
			(xy 34.143483 -208.614601) (xy 34.129119 -208.600247) (xy 34.121338 -208.581491) (xy 34.120836 -208.571338)
			(xy 28.0797 -208.571338) (xy 28.079199 -208.581494) (xy 28.071419 -208.600256) (xy 28.057056 -208.614619)
			(xy 28.038294 -208.622399) (xy 28.028138 -208.6229) (xy 26.628598 -208.6229) (xy 26.618445 -208.622369)
			(xy 26.599683 -208.614601) (xy 26.585319 -208.600247) (xy 26.577538 -208.581491) (xy 26.577036 -208.571338)
			(xy 20.5359 -208.571338) (xy 20.535399 -208.581494) (xy 20.527619 -208.600256) (xy 20.513256 -208.614619)
			(xy 20.494494 -208.622399) (xy 20.484338 -208.6229) (xy 19.084798 -208.6229) (xy 19.074645 -208.622369)
			(xy 19.055883 -208.614601) (xy 19.041519 -208.600247) (xy 19.033738 -208.581491) (xy 19.033236 -208.571338)
			(xy 12.9921 -208.571338) (xy 12.991599 -208.581494) (xy 12.983819 -208.600256) (xy 12.969456 -208.614619)
			(xy 12.950694 -208.622399) (xy 12.940538 -208.6229) (xy 11.540998 -208.6229) (xy 11.530845 -208.622369)
			(xy 11.512083 -208.614601) (xy 11.497719 -208.600247) (xy 11.489938 -208.581491) (xy 11.489436 -208.571338)
			(xy 2.509012 -208.571338) (xy 2.509012 -209.421476) (xy 7.389368 -209.421476) (xy 7.389368 -209.012536)
			(xy 7.389851 -209.002388) (xy 7.397628 -208.983643) (xy 7.412006 -208.969319) (xy 7.430781 -208.961613)
			(xy 7.44093 -208.961228) (xy 8.84047 -208.961228) (xy 8.850593 -208.961751) (xy 8.869312 -208.969466)
			(xy 8.883669 -208.983742) (xy 8.891491 -209.002416) (xy 8.892032 -209.012536) (xy 8.892032 -209.421476)
			(xy 11.489436 -209.421476) (xy 11.489436 -209.012536) (xy 11.489852 -209.00238) (xy 11.497642 -208.983621)
			(xy 11.512042 -208.969295) (xy 11.53084 -208.961601) (xy 11.540998 -208.961228) (xy 12.940538 -208.961228)
			(xy 12.950666 -208.961695) (xy 12.969385 -208.969433) (xy 12.98374 -208.983725) (xy 12.99156 -209.002411)
			(xy 12.9921 -209.012536) (xy 12.9921 -209.421476) (xy 14.933168 -209.421476) (xy 14.933168 -209.012536)
			(xy 14.933651 -209.002388) (xy 14.941428 -208.983643) (xy 14.955806 -208.969319) (xy 14.974581 -208.961613)
			(xy 14.98473 -208.961228) (xy 16.38427 -208.961228) (xy 16.394393 -208.961751) (xy 16.413112 -208.969466)
			(xy 16.427469 -208.983742) (xy 16.435291 -209.002416) (xy 16.435832 -209.012536) (xy 16.435832 -209.421476)
			(xy 19.033236 -209.421476) (xy 19.033236 -209.012536) (xy 19.033652 -209.00238) (xy 19.041442 -208.983621)
			(xy 19.055842 -208.969295) (xy 19.07464 -208.961601) (xy 19.084798 -208.961228) (xy 20.484338 -208.961228)
			(xy 20.494466 -208.961695) (xy 20.513185 -208.969433) (xy 20.52754 -208.983725) (xy 20.53536 -209.002411)
			(xy 20.5359 -209.012536) (xy 20.5359 -209.421476) (xy 22.476968 -209.421476) (xy 22.476968 -209.012536)
			(xy 22.477451 -209.002388) (xy 22.485228 -208.983643) (xy 22.499606 -208.969319) (xy 22.518381 -208.961613)
			(xy 22.52853 -208.961228) (xy 23.92807 -208.961228) (xy 23.938193 -208.961751) (xy 23.956912 -208.969466)
			(xy 23.971269 -208.983742) (xy 23.979091 -209.002416) (xy 23.979632 -209.012536) (xy 23.979632 -209.421476)
			(xy 26.577036 -209.421476) (xy 26.577036 -209.012536) (xy 26.577452 -209.00238) (xy 26.585242 -208.983621)
			(xy 26.599642 -208.969295) (xy 26.61844 -208.961601) (xy 26.628598 -208.961228) (xy 28.028138 -208.961228)
			(xy 28.038266 -208.961695) (xy 28.056985 -208.969433) (xy 28.07134 -208.983725) (xy 28.07916 -209.002411)
			(xy 28.0797 -209.012536) (xy 28.0797 -209.421476) (xy 30.020768 -209.421476) (xy 30.020768 -209.012536)
			(xy 30.021251 -209.002388) (xy 30.029028 -208.983643) (xy 30.043406 -208.969319) (xy 30.062181 -208.961613)
			(xy 30.07233 -208.961228) (xy 31.47187 -208.961228) (xy 31.481993 -208.961751) (xy 31.500712 -208.969466)
			(xy 31.515069 -208.983742) (xy 31.522891 -209.002416) (xy 31.523432 -209.012536) (xy 31.523432 -209.421476)
			(xy 34.120836 -209.421476) (xy 34.120836 -209.012536) (xy 34.121252 -209.00238) (xy 34.129042 -208.983621)
			(xy 34.143442 -208.969295) (xy 34.16224 -208.961601) (xy 34.172398 -208.961228) (xy 35.571938 -208.961228)
			(xy 35.582066 -208.961695) (xy 35.600785 -208.969433) (xy 35.61514 -208.983725) (xy 35.62296 -209.002411)
			(xy 35.6235 -209.012536) (xy 35.6235 -209.421476) (xy 37.564568 -209.421476) (xy 37.564568 -209.012536)
			(xy 37.565051 -209.002388) (xy 37.572828 -208.983643) (xy 37.587206 -208.969319) (xy 37.605981 -208.961613)
			(xy 37.61613 -208.961228) (xy 39.01567 -208.961228) (xy 39.025793 -208.961751) (xy 39.044512 -208.969466)
			(xy 39.058869 -208.983742) (xy 39.066691 -209.002416) (xy 39.067232 -209.012536) (xy 39.067232 -209.421476)
			(xy 41.664636 -209.421476) (xy 41.664636 -209.012536) (xy 41.665052 -209.00238) (xy 41.672842 -208.983621)
			(xy 41.687242 -208.969295) (xy 41.70604 -208.961601) (xy 41.716198 -208.961228) (xy 43.115738 -208.961228)
			(xy 43.125866 -208.961695) (xy 43.144585 -208.969433) (xy 43.15894 -208.983725) (xy 43.16676 -209.002411)
			(xy 43.1673 -209.012536) (xy 43.1673 -209.421476) (xy 45.108368 -209.421476) (xy 45.108368 -209.012536)
			(xy 45.108851 -209.002388) (xy 45.116628 -208.983643) (xy 45.131006 -208.969319) (xy 45.149781 -208.961613)
			(xy 45.15993 -208.961228) (xy 46.55947 -208.961228) (xy 46.569593 -208.961751) (xy 46.588312 -208.969466)
			(xy 46.602669 -208.983742) (xy 46.610491 -209.002416) (xy 46.611032 -209.012536) (xy 46.611032 -209.421476)
			(xy 49.208436 -209.421476) (xy 49.208436 -209.012536) (xy 49.208852 -209.00238) (xy 49.216642 -208.983621)
			(xy 49.231042 -208.969295) (xy 49.24984 -208.961601) (xy 49.259998 -208.961228) (xy 50.659538 -208.961228)
			(xy 50.669666 -208.961695) (xy 50.688385 -208.969433) (xy 50.70274 -208.983725) (xy 50.71056 -209.002411)
			(xy 50.7111 -209.012536) (xy 50.7111 -209.421476) (xy 52.652168 -209.421476) (xy 52.652168 -209.012536)
			(xy 52.652651 -209.002388) (xy 52.660428 -208.983643) (xy 52.674806 -208.969319) (xy 52.693581 -208.961613)
			(xy 52.70373 -208.961228) (xy 54.10327 -208.961228) (xy 54.113393 -208.961751) (xy 54.132112 -208.969466)
			(xy 54.146469 -208.983742) (xy 54.154291 -209.002416) (xy 54.154832 -209.012536) (xy 54.154832 -209.421476)
			(xy 56.752236 -209.421476) (xy 56.752236 -209.012536) (xy 56.752652 -209.00238) (xy 56.760442 -208.983621)
			(xy 56.774842 -208.969295) (xy 56.79364 -208.961601) (xy 56.803798 -208.961228) (xy 58.203338 -208.961228)
			(xy 58.213466 -208.961695) (xy 58.232185 -208.969433) (xy 58.24654 -208.983725) (xy 58.25436 -209.002411)
			(xy 58.2549 -209.012536) (xy 58.2549 -209.421476) (xy 60.195968 -209.421476) (xy 60.195968 -209.012536)
			(xy 60.196451 -209.002388) (xy 60.204228 -208.983643) (xy 60.218606 -208.969319) (xy 60.237381 -208.961613)
			(xy 60.24753 -208.961228) (xy 61.64707 -208.961228) (xy 61.657193 -208.961751) (xy 61.675912 -208.969466)
			(xy 61.690269 -208.983742) (xy 61.698091 -209.002416) (xy 61.698632 -209.012536) (xy 61.698632 -209.421476)
			(xy 64.296036 -209.421476) (xy 64.296036 -209.012536) (xy 64.296452 -209.00238) (xy 64.304242 -208.983621)
			(xy 64.318642 -208.969295) (xy 64.33744 -208.961601) (xy 64.347598 -208.961228) (xy 65.747138 -208.961228)
			(xy 65.757266 -208.961695) (xy 65.775985 -208.969433) (xy 65.79034 -208.983725) (xy 65.79816 -209.002411)
			(xy 65.7987 -209.012536) (xy 65.7987 -209.421476) (xy 158.062168 -209.421476) (xy 158.062168 -209.012536)
			(xy 158.062651 -209.002388) (xy 158.070428 -208.983643) (xy 158.084806 -208.969319) (xy 158.103581 -208.961613)
			(xy 158.11373 -208.961228) (xy 159.51327 -208.961228) (xy 159.523393 -208.961751) (xy 159.542112 -208.969466)
			(xy 159.556469 -208.983742) (xy 159.564291 -209.002416) (xy 159.564832 -209.012536) (xy 159.564832 -209.421476)
			(xy 162.162236 -209.421476) (xy 162.162236 -209.012536) (xy 162.162652 -209.00238) (xy 162.170442 -208.983621)
			(xy 162.184842 -208.969295) (xy 162.20364 -208.961601) (xy 162.213798 -208.961228) (xy 163.613338 -208.961228)
			(xy 163.623466 -208.961695) (xy 163.642185 -208.969433) (xy 163.65654 -208.983725) (xy 163.66436 -209.002411)
			(xy 163.6649 -209.012536) (xy 163.6649 -209.421476) (xy 165.605968 -209.421476) (xy 165.605968 -209.012536)
			(xy 165.606451 -209.002388) (xy 165.614228 -208.983643) (xy 165.628606 -208.969319) (xy 165.647381 -208.961613)
			(xy 165.65753 -208.961228) (xy 167.05707 -208.961228) (xy 167.067193 -208.961751) (xy 167.085912 -208.969466)
			(xy 167.100269 -208.983742) (xy 167.108091 -209.002416) (xy 167.108632 -209.012536) (xy 167.108632 -209.421476)
			(xy 169.706036 -209.421476) (xy 169.706036 -209.012536) (xy 169.706452 -209.00238) (xy 169.714242 -208.983621)
			(xy 169.728642 -208.969295) (xy 169.74744 -208.961601) (xy 169.757598 -208.961228) (xy 171.157138 -208.961228)
			(xy 171.167266 -208.961695) (xy 171.185985 -208.969433) (xy 171.20034 -208.983725) (xy 171.20816 -209.002411)
			(xy 171.2087 -209.012536) (xy 171.2087 -209.421476) (xy 173.149768 -209.421476) (xy 173.149768 -209.012536)
			(xy 173.150251 -209.002388) (xy 173.158028 -208.983643) (xy 173.172406 -208.969319) (xy 173.191181 -208.961613)
			(xy 173.20133 -208.961228) (xy 174.60087 -208.961228) (xy 174.610993 -208.961751) (xy 174.629712 -208.969466)
			(xy 174.644069 -208.983742) (xy 174.651891 -209.002416) (xy 174.652432 -209.012536) (xy 174.652432 -209.421476)
			(xy 177.249836 -209.421476) (xy 177.249836 -209.012536) (xy 177.250252 -209.00238) (xy 177.258042 -208.983621)
			(xy 177.272442 -208.969295) (xy 177.29124 -208.961601) (xy 177.301398 -208.961228) (xy 178.700938 -208.961228)
			(xy 178.711066 -208.961695) (xy 178.729785 -208.969433) (xy 178.74414 -208.983725) (xy 178.75196 -209.002411)
			(xy 178.7525 -209.012536) (xy 178.7525 -209.421476) (xy 180.693568 -209.421476) (xy 180.693568 -209.012536)
			(xy 180.694051 -209.002388) (xy 180.701828 -208.983643) (xy 180.716206 -208.969319) (xy 180.734981 -208.961613)
			(xy 180.74513 -208.961228) (xy 182.14467 -208.961228) (xy 182.154793 -208.961751) (xy 182.173512 -208.969466)
			(xy 182.187869 -208.983742) (xy 182.195691 -209.002416) (xy 182.196232 -209.012536) (xy 182.196232 -209.421476)
			(xy 184.793636 -209.421476) (xy 184.793636 -209.012536) (xy 184.794052 -209.00238) (xy 184.801842 -208.983621)
			(xy 184.816242 -208.969295) (xy 184.83504 -208.961601) (xy 184.845198 -208.961228) (xy 186.244738 -208.961228)
			(xy 186.254866 -208.961695) (xy 186.273585 -208.969433) (xy 186.28794 -208.983725) (xy 186.29576 -209.002411)
			(xy 186.2963 -209.012536) (xy 186.2963 -209.421476) (xy 188.237368 -209.421476) (xy 188.237368 -209.012536)
			(xy 188.237851 -209.002388) (xy 188.245628 -208.983643) (xy 188.260006 -208.969319) (xy 188.278781 -208.961613)
			(xy 188.28893 -208.961228) (xy 189.68847 -208.961228) (xy 189.698593 -208.961751) (xy 189.717312 -208.969466)
			(xy 189.731669 -208.983742) (xy 189.739491 -209.002416) (xy 189.740032 -209.012536) (xy 189.740032 -209.421476)
			(xy 192.337436 -209.421476) (xy 192.337436 -209.012536) (xy 192.337852 -209.00238) (xy 192.345642 -208.983621)
			(xy 192.360042 -208.969295) (xy 192.37884 -208.961601) (xy 192.388998 -208.961228) (xy 193.788538 -208.961228)
			(xy 193.798666 -208.961695) (xy 193.817385 -208.969433) (xy 193.83174 -208.983725) (xy 193.83956 -209.002411)
			(xy 193.8401 -209.012536) (xy 193.8401 -209.421476) (xy 195.781168 -209.421476) (xy 195.781168 -209.012536)
			(xy 195.781651 -209.002388) (xy 195.789428 -208.983643) (xy 195.803806 -208.969319) (xy 195.822581 -208.961613)
			(xy 195.83273 -208.961228) (xy 197.23227 -208.961228) (xy 197.242393 -208.961751) (xy 197.261112 -208.969466)
			(xy 197.275469 -208.983742) (xy 197.283291 -209.002416) (xy 197.283832 -209.012536) (xy 197.283832 -209.421476)
			(xy 199.881236 -209.421476) (xy 199.881236 -209.012536) (xy 199.881652 -209.00238) (xy 199.889442 -208.983621)
			(xy 199.903842 -208.969295) (xy 199.92264 -208.961601) (xy 199.932798 -208.961228) (xy 201.332338 -208.961228)
			(xy 201.342466 -208.961695) (xy 201.361185 -208.969433) (xy 201.37554 -208.983725) (xy 201.38336 -209.002411)
			(xy 201.3839 -209.012536) (xy 201.3839 -209.421476) (xy 203.324968 -209.421476) (xy 203.324968 -209.012536)
			(xy 203.325451 -209.002388) (xy 203.333228 -208.983643) (xy 203.347606 -208.969319) (xy 203.366381 -208.961613)
			(xy 203.37653 -208.961228) (xy 204.77607 -208.961228) (xy 204.786193 -208.961751) (xy 204.804912 -208.969466)
			(xy 204.819269 -208.983742) (xy 204.827091 -209.002416) (xy 204.827632 -209.012536) (xy 204.827632 -209.421476)
			(xy 207.425036 -209.421476) (xy 207.425036 -209.012536) (xy 207.425452 -209.00238) (xy 207.433242 -208.983621)
			(xy 207.447642 -208.969295) (xy 207.46644 -208.961601) (xy 207.476598 -208.961228) (xy 208.876138 -208.961228)
			(xy 208.886266 -208.961695) (xy 208.904985 -208.969433) (xy 208.91934 -208.983725) (xy 208.92716 -209.002411)
			(xy 208.9277 -209.012536) (xy 208.9277 -209.421476) (xy 210.868768 -209.421476) (xy 210.868768 -209.012536)
			(xy 210.869251 -209.002388) (xy 210.877028 -208.983643) (xy 210.891406 -208.969319) (xy 210.910181 -208.961613)
			(xy 210.92033 -208.961228) (xy 212.31987 -208.961228) (xy 212.329993 -208.961751) (xy 212.348712 -208.969466)
			(xy 212.363069 -208.983742) (xy 212.370891 -209.002416) (xy 212.371432 -209.012536) (xy 212.371432 -209.421476)
			(xy 214.968836 -209.421476) (xy 214.968836 -209.012536) (xy 214.969252 -209.00238) (xy 214.977042 -208.983621)
			(xy 214.991442 -208.969295) (xy 215.01024 -208.961601) (xy 215.020398 -208.961228) (xy 216.419938 -208.961228)
			(xy 216.430066 -208.961695) (xy 216.448785 -208.969433) (xy 216.46314 -208.983725) (xy 216.47096 -209.002411)
			(xy 216.4715 -209.012536) (xy 216.4715 -209.421476) (xy 255.329436 -209.421476) (xy 255.329436 -209.012536)
			(xy 255.329852 -209.00238) (xy 255.337642 -208.983621) (xy 255.352042 -208.969295) (xy 255.37084 -208.961601)
			(xy 255.380998 -208.961228) (xy 256.780538 -208.961228) (xy 256.790666 -208.961695) (xy 256.809385 -208.969433)
			(xy 256.82374 -208.983725) (xy 256.83156 -209.002411) (xy 256.8321 -209.012536) (xy 256.8321 -209.421476)
			(xy 259.429504 -209.421476) (xy 259.429504 -209.012536) (xy 259.429951 -209.002384) (xy 259.437736 -208.983631)
			(xy 259.452125 -208.969307) (xy 259.470912 -208.961606) (xy 259.481066 -208.961228) (xy 260.880606 -208.961228)
			(xy 260.890732 -208.961721) (xy 260.909451 -208.969449) (xy 260.923806 -208.983733) (xy 260.931627 -209.002413)
			(xy 260.932168 -209.012536) (xy 260.932168 -209.421476) (xy 262.873236 -209.421476) (xy 262.873236 -209.012536)
			(xy 262.873652 -209.00238) (xy 262.881442 -208.983621) (xy 262.895842 -208.969295) (xy 262.91464 -208.961601)
			(xy 262.924798 -208.961228) (xy 264.324338 -208.961228) (xy 264.334466 -208.961695) (xy 264.353185 -208.969433)
			(xy 264.36754 -208.983725) (xy 264.37536 -209.002411) (xy 264.3759 -209.012536) (xy 264.3759 -209.421476)
			(xy 266.973304 -209.421476) (xy 266.973304 -209.012536) (xy 266.973751 -209.002384) (xy 266.981536 -208.983631)
			(xy 266.995925 -208.969307) (xy 267.014712 -208.961606) (xy 267.024866 -208.961228) (xy 268.424406 -208.961228)
			(xy 268.434532 -208.961721) (xy 268.453251 -208.969449) (xy 268.467606 -208.983733) (xy 268.475427 -209.002413)
			(xy 268.475968 -209.012536) (xy 268.475968 -209.421476) (xy 270.417036 -209.421476) (xy 270.417036 -209.012536)
			(xy 270.417452 -209.00238) (xy 270.425242 -208.983621) (xy 270.439642 -208.969295) (xy 270.45844 -208.961601)
			(xy 270.468598 -208.961228) (xy 271.868138 -208.961228) (xy 271.878266 -208.961695) (xy 271.896985 -208.969433)
			(xy 271.91134 -208.983725) (xy 271.91916 -209.002411) (xy 271.9197 -209.012536) (xy 271.9197 -209.421476)
			(xy 274.517104 -209.421476) (xy 274.517104 -209.012536) (xy 274.517551 -209.002384) (xy 274.525336 -208.983631)
			(xy 274.539725 -208.969307) (xy 274.558512 -208.961606) (xy 274.568666 -208.961228) (xy 275.968206 -208.961228)
			(xy 275.978332 -208.961721) (xy 275.997051 -208.969449) (xy 276.011406 -208.983733) (xy 276.019227 -209.002413)
			(xy 276.019768 -209.012536) (xy 276.019768 -209.421476) (xy 277.960836 -209.421476) (xy 277.960836 -209.012536)
			(xy 277.961252 -209.00238) (xy 277.969042 -208.983621) (xy 277.983442 -208.969295) (xy 278.00224 -208.961601)
			(xy 278.012398 -208.961228) (xy 279.411938 -208.961228) (xy 279.422066 -208.961695) (xy 279.440785 -208.969433)
			(xy 279.45514 -208.983725) (xy 279.46296 -209.002411) (xy 279.4635 -209.012536) (xy 279.4635 -209.421476)
			(xy 282.060904 -209.421476) (xy 282.060904 -209.012536) (xy 282.061351 -209.002384) (xy 282.069136 -208.983631)
			(xy 282.083525 -208.969307) (xy 282.102312 -208.961606) (xy 282.112466 -208.961228) (xy 283.512006 -208.961228)
			(xy 283.522132 -208.961721) (xy 283.540851 -208.969449) (xy 283.555206 -208.983733) (xy 283.563027 -209.002413)
			(xy 283.563568 -209.012536) (xy 283.563568 -209.421476) (xy 285.504636 -209.421476) (xy 285.504636 -209.012536)
			(xy 285.505052 -209.00238) (xy 285.512842 -208.983621) (xy 285.527242 -208.969295) (xy 285.54604 -208.961601)
			(xy 285.556198 -208.961228) (xy 286.955738 -208.961228) (xy 286.965866 -208.961695) (xy 286.984585 -208.969433)
			(xy 286.99894 -208.983725) (xy 287.00676 -209.002411) (xy 287.0073 -209.012536) (xy 287.0073 -209.421476)
			(xy 289.604704 -209.421476) (xy 289.604704 -209.012536) (xy 289.605151 -209.002384) (xy 289.612936 -208.983631)
			(xy 289.627325 -208.969307) (xy 289.646112 -208.961606) (xy 289.656266 -208.961228) (xy 291.055806 -208.961228)
			(xy 291.065932 -208.961721) (xy 291.084651 -208.969449) (xy 291.099006 -208.983733) (xy 291.106827 -209.002413)
			(xy 291.107368 -209.012536) (xy 291.107368 -209.421476) (xy 293.048436 -209.421476) (xy 293.048436 -209.012536)
			(xy 293.048852 -209.00238) (xy 293.056642 -208.983621) (xy 293.071042 -208.969295) (xy 293.08984 -208.961601)
			(xy 293.099998 -208.961228) (xy 294.499538 -208.961228) (xy 294.509666 -208.961695) (xy 294.528385 -208.969433)
			(xy 294.54274 -208.983725) (xy 294.55056 -209.002411) (xy 294.5511 -209.012536) (xy 294.5511 -209.421476)
			(xy 297.148504 -209.421476) (xy 297.148504 -209.012536) (xy 297.148951 -209.002384) (xy 297.156736 -208.983631)
			(xy 297.171125 -208.969307) (xy 297.189912 -208.961606) (xy 297.200066 -208.961228) (xy 298.599606 -208.961228)
			(xy 298.609732 -208.961721) (xy 298.628451 -208.969449) (xy 298.642806 -208.983733) (xy 298.650627 -209.002413)
			(xy 298.651168 -209.012536) (xy 298.651168 -209.421476) (xy 300.592236 -209.421476) (xy 300.592236 -209.012536)
			(xy 300.592652 -209.00238) (xy 300.600442 -208.983621) (xy 300.614842 -208.969295) (xy 300.63364 -208.961601)
			(xy 300.643798 -208.961228) (xy 302.043338 -208.961228) (xy 302.053466 -208.961695) (xy 302.072185 -208.969433)
			(xy 302.08654 -208.983725) (xy 302.09436 -209.002411) (xy 302.0949 -209.012536) (xy 302.0949 -209.421476)
			(xy 304.692304 -209.421476) (xy 304.692304 -209.012536) (xy 304.692751 -209.002384) (xy 304.700536 -208.983631)
			(xy 304.714925 -208.969307) (xy 304.733712 -208.961606) (xy 304.743866 -208.961228) (xy 306.143406 -208.961228)
			(xy 306.153532 -208.961721) (xy 306.172251 -208.969449) (xy 306.186606 -208.983733) (xy 306.194427 -209.002413)
			(xy 306.194968 -209.012536) (xy 306.194968 -209.421476) (xy 308.136036 -209.421476) (xy 308.136036 -209.012536)
			(xy 308.136452 -209.00238) (xy 308.144242 -208.983621) (xy 308.158642 -208.969295) (xy 308.17744 -208.961601)
			(xy 308.187598 -208.961228) (xy 309.587138 -208.961228) (xy 309.597266 -208.961695) (xy 309.615985 -208.969433)
			(xy 309.63034 -208.983725) (xy 309.63816 -209.002411) (xy 309.6387 -209.012536) (xy 309.6387 -209.421476)
			(xy 312.236104 -209.421476) (xy 312.236104 -209.012536) (xy 312.236551 -209.002384) (xy 312.244336 -208.983631)
			(xy 312.258725 -208.969307) (xy 312.277512 -208.961606) (xy 312.287666 -208.961228) (xy 313.687206 -208.961228)
			(xy 313.697332 -208.961721) (xy 313.716051 -208.969449) (xy 313.730406 -208.983733) (xy 313.738227 -209.002413)
			(xy 313.738768 -209.012536) (xy 313.738768 -209.421476) (xy 406.002236 -209.421476) (xy 406.002236 -209.012536)
			(xy 406.002652 -209.00238) (xy 406.010442 -208.983621) (xy 406.024842 -208.969295) (xy 406.04364 -208.961601)
			(xy 406.053798 -208.961228) (xy 407.453338 -208.961228) (xy 407.463466 -208.961695) (xy 407.482185 -208.969433)
			(xy 407.49654 -208.983725) (xy 407.50436 -209.002411) (xy 407.5049 -209.012536) (xy 407.5049 -209.421476)
			(xy 410.102304 -209.421476) (xy 410.102304 -209.012536) (xy 410.102751 -209.002384) (xy 410.110536 -208.983631)
			(xy 410.124925 -208.969307) (xy 410.143712 -208.961606) (xy 410.153866 -208.961228) (xy 411.553406 -208.961228)
			(xy 411.563532 -208.961721) (xy 411.582251 -208.969449) (xy 411.596606 -208.983733) (xy 411.604427 -209.002413)
			(xy 411.604968 -209.012536) (xy 411.604968 -209.421476) (xy 413.546036 -209.421476) (xy 413.546036 -209.012536)
			(xy 413.546452 -209.00238) (xy 413.554242 -208.983621) (xy 413.568642 -208.969295) (xy 413.58744 -208.961601)
			(xy 413.597598 -208.961228) (xy 414.997138 -208.961228) (xy 415.007266 -208.961695) (xy 415.025985 -208.969433)
			(xy 415.04034 -208.983725) (xy 415.04816 -209.002411) (xy 415.0487 -209.012536) (xy 415.0487 -209.421476)
			(xy 417.646104 -209.421476) (xy 417.646104 -209.012536) (xy 417.646551 -209.002384) (xy 417.654336 -208.983631)
			(xy 417.668725 -208.969307) (xy 417.687512 -208.961606) (xy 417.697666 -208.961228) (xy 419.097206 -208.961228)
			(xy 419.107332 -208.961721) (xy 419.126051 -208.969449) (xy 419.140406 -208.983733) (xy 419.148227 -209.002413)
			(xy 419.148768 -209.012536) (xy 419.148768 -209.421476) (xy 421.089836 -209.421476) (xy 421.089836 -209.012536)
			(xy 421.090252 -209.00238) (xy 421.098042 -208.983621) (xy 421.112442 -208.969295) (xy 421.13124 -208.961601)
			(xy 421.141398 -208.961228) (xy 422.540938 -208.961228) (xy 422.551066 -208.961695) (xy 422.569785 -208.969433)
			(xy 422.58414 -208.983725) (xy 422.59196 -209.002411) (xy 422.5925 -209.012536) (xy 422.5925 -209.421476)
			(xy 425.189904 -209.421476) (xy 425.189904 -209.012536) (xy 425.190351 -209.002384) (xy 425.198136 -208.983631)
			(xy 425.212525 -208.969307) (xy 425.231312 -208.961606) (xy 425.241466 -208.961228) (xy 426.641006 -208.961228)
			(xy 426.651132 -208.961721) (xy 426.669851 -208.969449) (xy 426.684206 -208.983733) (xy 426.692027 -209.002413)
			(xy 426.692568 -209.012536) (xy 426.692568 -209.421476) (xy 428.633636 -209.421476) (xy 428.633636 -209.012536)
			(xy 428.634052 -209.00238) (xy 428.641842 -208.983621) (xy 428.656242 -208.969295) (xy 428.67504 -208.961601)
			(xy 428.685198 -208.961228) (xy 430.084738 -208.961228) (xy 430.094866 -208.961695) (xy 430.113585 -208.969433)
			(xy 430.12794 -208.983725) (xy 430.13576 -209.002411) (xy 430.1363 -209.012536) (xy 430.1363 -209.421476)
			(xy 432.733704 -209.421476) (xy 432.733704 -209.012536) (xy 432.734151 -209.002384) (xy 432.741936 -208.983631)
			(xy 432.756325 -208.969307) (xy 432.775112 -208.961606) (xy 432.785266 -208.961228) (xy 434.184806 -208.961228)
			(xy 434.194932 -208.961721) (xy 434.213651 -208.969449) (xy 434.228006 -208.983733) (xy 434.235827 -209.002413)
			(xy 434.236368 -209.012536) (xy 434.236368 -209.421476) (xy 436.177436 -209.421476) (xy 436.177436 -209.012536)
			(xy 436.177852 -209.00238) (xy 436.185642 -208.983621) (xy 436.200042 -208.969295) (xy 436.21884 -208.961601)
			(xy 436.228998 -208.961228) (xy 437.628538 -208.961228) (xy 437.638666 -208.961695) (xy 437.657385 -208.969433)
			(xy 437.67174 -208.983725) (xy 437.67956 -209.002411) (xy 437.6801 -209.012536) (xy 437.6801 -209.421476)
			(xy 440.277504 -209.421476) (xy 440.277504 -209.012536) (xy 440.277951 -209.002384) (xy 440.285736 -208.983631)
			(xy 440.300125 -208.969307) (xy 440.318912 -208.961606) (xy 440.329066 -208.961228) (xy 441.728606 -208.961228)
			(xy 441.738732 -208.961721) (xy 441.757451 -208.969449) (xy 441.771806 -208.983733) (xy 441.779627 -209.002413)
			(xy 441.780168 -209.012536) (xy 441.780168 -209.421476) (xy 443.721236 -209.421476) (xy 443.721236 -209.012536)
			(xy 443.721652 -209.00238) (xy 443.729442 -208.983621) (xy 443.743842 -208.969295) (xy 443.76264 -208.961601)
			(xy 443.772798 -208.961228) (xy 445.172338 -208.961228) (xy 445.182466 -208.961695) (xy 445.201185 -208.969433)
			(xy 445.21554 -208.983725) (xy 445.22336 -209.002411) (xy 445.2239 -209.012536) (xy 445.2239 -209.421476)
			(xy 447.821304 -209.421476) (xy 447.821304 -209.012536) (xy 447.821751 -209.002384) (xy 447.829536 -208.983631)
			(xy 447.843925 -208.969307) (xy 447.862712 -208.961606) (xy 447.872866 -208.961228) (xy 449.272406 -208.961228)
			(xy 449.282532 -208.961721) (xy 449.301251 -208.969449) (xy 449.315606 -208.983733) (xy 449.323427 -209.002413)
			(xy 449.323968 -209.012536) (xy 449.323968 -209.421476) (xy 451.265036 -209.421476) (xy 451.265036 -209.012536)
			(xy 451.265452 -209.00238) (xy 451.273242 -208.983621) (xy 451.287642 -208.969295) (xy 451.30644 -208.961601)
			(xy 451.316598 -208.961228) (xy 452.716138 -208.961228) (xy 452.726266 -208.961695) (xy 452.744985 -208.969433)
			(xy 452.75934 -208.983725) (xy 452.76716 -209.002411) (xy 452.7677 -209.012536) (xy 452.7677 -209.421476)
			(xy 455.365104 -209.421476) (xy 455.365104 -209.012536) (xy 455.365551 -209.002384) (xy 455.373336 -208.983631)
			(xy 455.387725 -208.969307) (xy 455.406512 -208.961606) (xy 455.416666 -208.961228) (xy 456.816206 -208.961228)
			(xy 456.826332 -208.961721) (xy 456.845051 -208.969449) (xy 456.859406 -208.983733) (xy 456.867227 -209.002413)
			(xy 456.867768 -209.012536) (xy 456.867768 -209.421476) (xy 458.808836 -209.421476) (xy 458.808836 -209.012536)
			(xy 458.809252 -209.00238) (xy 458.817042 -208.983621) (xy 458.831442 -208.969295) (xy 458.85024 -208.961601)
			(xy 458.860398 -208.961228) (xy 460.259938 -208.961228) (xy 460.270066 -208.961695) (xy 460.288785 -208.969433)
			(xy 460.30314 -208.983725) (xy 460.31096 -209.002411) (xy 460.3115 -209.012536) (xy 460.3115 -209.421476)
			(xy 462.908904 -209.421476) (xy 462.908904 -209.012536) (xy 462.909351 -209.002384) (xy 462.917136 -208.983631)
			(xy 462.931525 -208.969307) (xy 462.950312 -208.961606) (xy 462.960466 -208.961228) (xy 464.360006 -208.961228)
			(xy 464.370132 -208.961721) (xy 464.388851 -208.969449) (xy 464.403206 -208.983733) (xy 464.411027 -209.002413)
			(xy 464.411568 -209.012536) (xy 464.411568 -209.421476) (xy 464.411158 -209.431633) (xy 464.403365 -209.450391)
			(xy 464.388964 -209.464716) (xy 464.370165 -209.472411) (xy 464.360006 -209.472784) (xy 462.960466 -209.472784)
			(xy 462.95034 -209.472302) (xy 462.931623 -209.464568) (xy 462.917268 -209.45028) (xy 462.909446 -209.4316)
			(xy 462.908904 -209.421476) (xy 460.3115 -209.421476) (xy 460.311059 -209.431629) (xy 460.303271 -209.450381)
			(xy 460.28888 -209.464705) (xy 460.270092 -209.472405) (xy 460.259938 -209.472784) (xy 458.860398 -209.472784)
			(xy 458.850274 -209.472276) (xy 458.831558 -209.464552) (xy 458.817202 -209.450272) (xy 458.809379 -209.431597)
			(xy 458.808836 -209.421476) (xy 456.867768 -209.421476) (xy 456.867358 -209.431633) (xy 456.859565 -209.450391)
			(xy 456.845164 -209.464716) (xy 456.826365 -209.472411) (xy 456.816206 -209.472784) (xy 455.416666 -209.472784)
			(xy 455.40654 -209.472302) (xy 455.387823 -209.464568) (xy 455.373468 -209.45028) (xy 455.365646 -209.4316)
			(xy 455.365104 -209.421476) (xy 452.7677 -209.421476) (xy 452.767259 -209.431629) (xy 452.759471 -209.450381)
			(xy 452.74508 -209.464705) (xy 452.726292 -209.472405) (xy 452.716138 -209.472784) (xy 451.316598 -209.472784)
			(xy 451.306474 -209.472276) (xy 451.287758 -209.464552) (xy 451.273402 -209.450272) (xy 451.265579 -209.431597)
			(xy 451.265036 -209.421476) (xy 449.323968 -209.421476) (xy 449.323558 -209.431633) (xy 449.315765 -209.450391)
			(xy 449.301364 -209.464716) (xy 449.282565 -209.472411) (xy 449.272406 -209.472784) (xy 447.872866 -209.472784)
			(xy 447.86274 -209.472302) (xy 447.844023 -209.464568) (xy 447.829668 -209.45028) (xy 447.821846 -209.4316)
			(xy 447.821304 -209.421476) (xy 445.2239 -209.421476) (xy 445.223459 -209.431629) (xy 445.215671 -209.450381)
			(xy 445.20128 -209.464705) (xy 445.182492 -209.472405) (xy 445.172338 -209.472784) (xy 443.772798 -209.472784)
			(xy 443.762674 -209.472276) (xy 443.743958 -209.464552) (xy 443.729602 -209.450272) (xy 443.721779 -209.431597)
			(xy 443.721236 -209.421476) (xy 441.780168 -209.421476) (xy 441.779758 -209.431633) (xy 441.771965 -209.450391)
			(xy 441.757564 -209.464716) (xy 441.738765 -209.472411) (xy 441.728606 -209.472784) (xy 440.329066 -209.472784)
			(xy 440.31894 -209.472302) (xy 440.300223 -209.464568) (xy 440.285868 -209.45028) (xy 440.278046 -209.4316)
			(xy 440.277504 -209.421476) (xy 437.6801 -209.421476) (xy 437.679659 -209.431629) (xy 437.671871 -209.450381)
			(xy 437.65748 -209.464705) (xy 437.638692 -209.472405) (xy 437.628538 -209.472784) (xy 436.228998 -209.472784)
			(xy 436.218874 -209.472276) (xy 436.200158 -209.464552) (xy 436.185802 -209.450272) (xy 436.177979 -209.431597)
			(xy 436.177436 -209.421476) (xy 434.236368 -209.421476) (xy 434.235958 -209.431633) (xy 434.228165 -209.450391)
			(xy 434.213764 -209.464716) (xy 434.194965 -209.472411) (xy 434.184806 -209.472784) (xy 432.785266 -209.472784)
			(xy 432.77514 -209.472302) (xy 432.756423 -209.464568) (xy 432.742068 -209.45028) (xy 432.734246 -209.4316)
			(xy 432.733704 -209.421476) (xy 430.1363 -209.421476) (xy 430.135859 -209.431629) (xy 430.128071 -209.450381)
			(xy 430.11368 -209.464705) (xy 430.094892 -209.472405) (xy 430.084738 -209.472784) (xy 428.685198 -209.472784)
			(xy 428.675074 -209.472276) (xy 428.656358 -209.464552) (xy 428.642002 -209.450272) (xy 428.634179 -209.431597)
			(xy 428.633636 -209.421476) (xy 426.692568 -209.421476) (xy 426.692158 -209.431633) (xy 426.684365 -209.450391)
			(xy 426.669964 -209.464716) (xy 426.651165 -209.472411) (xy 426.641006 -209.472784) (xy 425.241466 -209.472784)
			(xy 425.23134 -209.472302) (xy 425.212623 -209.464568) (xy 425.198268 -209.45028) (xy 425.190446 -209.4316)
			(xy 425.189904 -209.421476) (xy 422.5925 -209.421476) (xy 422.592059 -209.431629) (xy 422.584271 -209.450381)
			(xy 422.56988 -209.464705) (xy 422.551092 -209.472405) (xy 422.540938 -209.472784) (xy 421.141398 -209.472784)
			(xy 421.131274 -209.472276) (xy 421.112558 -209.464552) (xy 421.098202 -209.450272) (xy 421.090379 -209.431597)
			(xy 421.089836 -209.421476) (xy 419.148768 -209.421476) (xy 419.148358 -209.431633) (xy 419.140565 -209.450391)
			(xy 419.126164 -209.464716) (xy 419.107365 -209.472411) (xy 419.097206 -209.472784) (xy 417.697666 -209.472784)
			(xy 417.68754 -209.472302) (xy 417.668823 -209.464568) (xy 417.654468 -209.45028) (xy 417.646646 -209.4316)
			(xy 417.646104 -209.421476) (xy 415.0487 -209.421476) (xy 415.048259 -209.431629) (xy 415.040471 -209.450381)
			(xy 415.02608 -209.464705) (xy 415.007292 -209.472405) (xy 414.997138 -209.472784) (xy 413.597598 -209.472784)
			(xy 413.587474 -209.472276) (xy 413.568758 -209.464552) (xy 413.554402 -209.450272) (xy 413.546579 -209.431597)
			(xy 413.546036 -209.421476) (xy 411.604968 -209.421476) (xy 411.604558 -209.431633) (xy 411.596765 -209.450391)
			(xy 411.582364 -209.464716) (xy 411.563565 -209.472411) (xy 411.553406 -209.472784) (xy 410.153866 -209.472784)
			(xy 410.14374 -209.472302) (xy 410.125023 -209.464568) (xy 410.110668 -209.45028) (xy 410.102846 -209.4316)
			(xy 410.102304 -209.421476) (xy 407.5049 -209.421476) (xy 407.504459 -209.431629) (xy 407.496671 -209.450381)
			(xy 407.48228 -209.464705) (xy 407.463492 -209.472405) (xy 407.453338 -209.472784) (xy 406.053798 -209.472784)
			(xy 406.043674 -209.472276) (xy 406.024958 -209.464552) (xy 406.010602 -209.450272) (xy 406.002779 -209.431597)
			(xy 406.002236 -209.421476) (xy 313.738768 -209.421476) (xy 313.738358 -209.431633) (xy 313.730565 -209.450391)
			(xy 313.716164 -209.464716) (xy 313.697365 -209.472411) (xy 313.687206 -209.472784) (xy 312.287666 -209.472784)
			(xy 312.27754 -209.472302) (xy 312.258823 -209.464568) (xy 312.244468 -209.45028) (xy 312.236646 -209.4316)
			(xy 312.236104 -209.421476) (xy 309.6387 -209.421476) (xy 309.638259 -209.431629) (xy 309.630471 -209.450381)
			(xy 309.61608 -209.464705) (xy 309.597292 -209.472405) (xy 309.587138 -209.472784) (xy 308.187598 -209.472784)
			(xy 308.177474 -209.472276) (xy 308.158758 -209.464552) (xy 308.144402 -209.450272) (xy 308.136579 -209.431597)
			(xy 308.136036 -209.421476) (xy 306.194968 -209.421476) (xy 306.194558 -209.431633) (xy 306.186765 -209.450391)
			(xy 306.172364 -209.464716) (xy 306.153565 -209.472411) (xy 306.143406 -209.472784) (xy 304.743866 -209.472784)
			(xy 304.73374 -209.472302) (xy 304.715023 -209.464568) (xy 304.700668 -209.45028) (xy 304.692846 -209.4316)
			(xy 304.692304 -209.421476) (xy 302.0949 -209.421476) (xy 302.094459 -209.431629) (xy 302.086671 -209.450381)
			(xy 302.07228 -209.464705) (xy 302.053492 -209.472405) (xy 302.043338 -209.472784) (xy 300.643798 -209.472784)
			(xy 300.633674 -209.472276) (xy 300.614958 -209.464552) (xy 300.600602 -209.450272) (xy 300.592779 -209.431597)
			(xy 300.592236 -209.421476) (xy 298.651168 -209.421476) (xy 298.650758 -209.431633) (xy 298.642965 -209.450391)
			(xy 298.628564 -209.464716) (xy 298.609765 -209.472411) (xy 298.599606 -209.472784) (xy 297.200066 -209.472784)
			(xy 297.18994 -209.472302) (xy 297.171223 -209.464568) (xy 297.156868 -209.45028) (xy 297.149046 -209.4316)
			(xy 297.148504 -209.421476) (xy 294.5511 -209.421476) (xy 294.550659 -209.431629) (xy 294.542871 -209.450381)
			(xy 294.52848 -209.464705) (xy 294.509692 -209.472405) (xy 294.499538 -209.472784) (xy 293.099998 -209.472784)
			(xy 293.089874 -209.472276) (xy 293.071158 -209.464552) (xy 293.056802 -209.450272) (xy 293.048979 -209.431597)
			(xy 293.048436 -209.421476) (xy 291.107368 -209.421476) (xy 291.106958 -209.431633) (xy 291.099165 -209.450391)
			(xy 291.084764 -209.464716) (xy 291.065965 -209.472411) (xy 291.055806 -209.472784) (xy 289.656266 -209.472784)
			(xy 289.64614 -209.472302) (xy 289.627423 -209.464568) (xy 289.613068 -209.45028) (xy 289.605246 -209.4316)
			(xy 289.604704 -209.421476) (xy 287.0073 -209.421476) (xy 287.006859 -209.431629) (xy 286.999071 -209.450381)
			(xy 286.98468 -209.464705) (xy 286.965892 -209.472405) (xy 286.955738 -209.472784) (xy 285.556198 -209.472784)
			(xy 285.546074 -209.472276) (xy 285.527358 -209.464552) (xy 285.513002 -209.450272) (xy 285.505179 -209.431597)
			(xy 285.504636 -209.421476) (xy 283.563568 -209.421476) (xy 283.563158 -209.431633) (xy 283.555365 -209.450391)
			(xy 283.540964 -209.464716) (xy 283.522165 -209.472411) (xy 283.512006 -209.472784) (xy 282.112466 -209.472784)
			(xy 282.10234 -209.472302) (xy 282.083623 -209.464568) (xy 282.069268 -209.45028) (xy 282.061446 -209.4316)
			(xy 282.060904 -209.421476) (xy 279.4635 -209.421476) (xy 279.463059 -209.431629) (xy 279.455271 -209.450381)
			(xy 279.44088 -209.464705) (xy 279.422092 -209.472405) (xy 279.411938 -209.472784) (xy 278.012398 -209.472784)
			(xy 278.002274 -209.472276) (xy 277.983558 -209.464552) (xy 277.969202 -209.450272) (xy 277.961379 -209.431597)
			(xy 277.960836 -209.421476) (xy 276.019768 -209.421476) (xy 276.019358 -209.431633) (xy 276.011565 -209.450391)
			(xy 275.997164 -209.464716) (xy 275.978365 -209.472411) (xy 275.968206 -209.472784) (xy 274.568666 -209.472784)
			(xy 274.55854 -209.472302) (xy 274.539823 -209.464568) (xy 274.525468 -209.45028) (xy 274.517646 -209.4316)
			(xy 274.517104 -209.421476) (xy 271.9197 -209.421476) (xy 271.919259 -209.431629) (xy 271.911471 -209.450381)
			(xy 271.89708 -209.464705) (xy 271.878292 -209.472405) (xy 271.868138 -209.472784) (xy 270.468598 -209.472784)
			(xy 270.458474 -209.472276) (xy 270.439758 -209.464552) (xy 270.425402 -209.450272) (xy 270.417579 -209.431597)
			(xy 270.417036 -209.421476) (xy 268.475968 -209.421476) (xy 268.475558 -209.431633) (xy 268.467765 -209.450391)
			(xy 268.453364 -209.464716) (xy 268.434565 -209.472411) (xy 268.424406 -209.472784) (xy 267.024866 -209.472784)
			(xy 267.01474 -209.472302) (xy 266.996023 -209.464568) (xy 266.981668 -209.45028) (xy 266.973846 -209.4316)
			(xy 266.973304 -209.421476) (xy 264.3759 -209.421476) (xy 264.375459 -209.431629) (xy 264.367671 -209.450381)
			(xy 264.35328 -209.464705) (xy 264.334492 -209.472405) (xy 264.324338 -209.472784) (xy 262.924798 -209.472784)
			(xy 262.914674 -209.472276) (xy 262.895958 -209.464552) (xy 262.881602 -209.450272) (xy 262.873779 -209.431597)
			(xy 262.873236 -209.421476) (xy 260.932168 -209.421476) (xy 260.931758 -209.431633) (xy 260.923965 -209.450391)
			(xy 260.909564 -209.464716) (xy 260.890765 -209.472411) (xy 260.880606 -209.472784) (xy 259.481066 -209.472784)
			(xy 259.47094 -209.472302) (xy 259.452223 -209.464568) (xy 259.437868 -209.45028) (xy 259.430046 -209.4316)
			(xy 259.429504 -209.421476) (xy 256.8321 -209.421476) (xy 256.831659 -209.431629) (xy 256.823871 -209.450381)
			(xy 256.80948 -209.464705) (xy 256.790692 -209.472405) (xy 256.780538 -209.472784) (xy 255.380998 -209.472784)
			(xy 255.370874 -209.472276) (xy 255.352158 -209.464552) (xy 255.337802 -209.450272) (xy 255.329979 -209.431597)
			(xy 255.329436 -209.421476) (xy 216.4715 -209.421476) (xy 216.471059 -209.431629) (xy 216.463271 -209.450381)
			(xy 216.44888 -209.464705) (xy 216.430092 -209.472405) (xy 216.419938 -209.472784) (xy 215.020398 -209.472784)
			(xy 215.010274 -209.472276) (xy 214.991558 -209.464552) (xy 214.977202 -209.450272) (xy 214.969379 -209.431597)
			(xy 214.968836 -209.421476) (xy 212.371432 -209.421476) (xy 212.37096 -209.431625) (xy 212.363178 -209.45037)
			(xy 212.348797 -209.464694) (xy 212.33002 -209.4724) (xy 212.31987 -209.472784) (xy 210.92033 -209.472784)
			(xy 210.910208 -209.47225) (xy 210.891492 -209.464536) (xy 210.877136 -209.450265) (xy 210.869311 -209.431595)
			(xy 210.868768 -209.421476) (xy 208.9277 -209.421476) (xy 208.927259 -209.431629) (xy 208.919471 -209.450381)
			(xy 208.90508 -209.464705) (xy 208.886292 -209.472405) (xy 208.876138 -209.472784) (xy 207.476598 -209.472784)
			(xy 207.466474 -209.472276) (xy 207.447758 -209.464552) (xy 207.433402 -209.450272) (xy 207.425579 -209.431597)
			(xy 207.425036 -209.421476) (xy 204.827632 -209.421476) (xy 204.82716 -209.431625) (xy 204.819378 -209.45037)
			(xy 204.804997 -209.464694) (xy 204.78622 -209.4724) (xy 204.77607 -209.472784) (xy 203.37653 -209.472784)
			(xy 203.366408 -209.47225) (xy 203.347692 -209.464536) (xy 203.333336 -209.450265) (xy 203.325511 -209.431595)
			(xy 203.324968 -209.421476) (xy 201.3839 -209.421476) (xy 201.383459 -209.431629) (xy 201.375671 -209.450381)
			(xy 201.36128 -209.464705) (xy 201.342492 -209.472405) (xy 201.332338 -209.472784) (xy 199.932798 -209.472784)
			(xy 199.922674 -209.472276) (xy 199.903958 -209.464552) (xy 199.889602 -209.450272) (xy 199.881779 -209.431597)
			(xy 199.881236 -209.421476) (xy 197.283832 -209.421476) (xy 197.28336 -209.431625) (xy 197.275578 -209.45037)
			(xy 197.261197 -209.464694) (xy 197.24242 -209.4724) (xy 197.23227 -209.472784) (xy 195.83273 -209.472784)
			(xy 195.822608 -209.47225) (xy 195.803892 -209.464536) (xy 195.789536 -209.450265) (xy 195.781711 -209.431595)
			(xy 195.781168 -209.421476) (xy 193.8401 -209.421476) (xy 193.839659 -209.431629) (xy 193.831871 -209.450381)
			(xy 193.81748 -209.464705) (xy 193.798692 -209.472405) (xy 193.788538 -209.472784) (xy 192.388998 -209.472784)
			(xy 192.378874 -209.472276) (xy 192.360158 -209.464552) (xy 192.345802 -209.450272) (xy 192.337979 -209.431597)
			(xy 192.337436 -209.421476) (xy 189.740032 -209.421476) (xy 189.73956 -209.431625) (xy 189.731778 -209.45037)
			(xy 189.717397 -209.464694) (xy 189.69862 -209.4724) (xy 189.68847 -209.472784) (xy 188.28893 -209.472784)
			(xy 188.278808 -209.47225) (xy 188.260092 -209.464536) (xy 188.245736 -209.450265) (xy 188.237911 -209.431595)
			(xy 188.237368 -209.421476) (xy 186.2963 -209.421476) (xy 186.295859 -209.431629) (xy 186.288071 -209.450381)
			(xy 186.27368 -209.464705) (xy 186.254892 -209.472405) (xy 186.244738 -209.472784) (xy 184.845198 -209.472784)
			(xy 184.835074 -209.472276) (xy 184.816358 -209.464552) (xy 184.802002 -209.450272) (xy 184.794179 -209.431597)
			(xy 184.793636 -209.421476) (xy 182.196232 -209.421476) (xy 182.19576 -209.431625) (xy 182.187978 -209.45037)
			(xy 182.173597 -209.464694) (xy 182.15482 -209.4724) (xy 182.14467 -209.472784) (xy 180.74513 -209.472784)
			(xy 180.735008 -209.47225) (xy 180.716292 -209.464536) (xy 180.701936 -209.450265) (xy 180.694111 -209.431595)
			(xy 180.693568 -209.421476) (xy 178.7525 -209.421476) (xy 178.752059 -209.431629) (xy 178.744271 -209.450381)
			(xy 178.72988 -209.464705) (xy 178.711092 -209.472405) (xy 178.700938 -209.472784) (xy 177.301398 -209.472784)
			(xy 177.291274 -209.472276) (xy 177.272558 -209.464552) (xy 177.258202 -209.450272) (xy 177.250379 -209.431597)
			(xy 177.249836 -209.421476) (xy 174.652432 -209.421476) (xy 174.65196 -209.431625) (xy 174.644178 -209.45037)
			(xy 174.629797 -209.464694) (xy 174.61102 -209.4724) (xy 174.60087 -209.472784) (xy 173.20133 -209.472784)
			(xy 173.191208 -209.47225) (xy 173.172492 -209.464536) (xy 173.158136 -209.450265) (xy 173.150311 -209.431595)
			(xy 173.149768 -209.421476) (xy 171.2087 -209.421476) (xy 171.208259 -209.431629) (xy 171.200471 -209.450381)
			(xy 171.18608 -209.464705) (xy 171.167292 -209.472405) (xy 171.157138 -209.472784) (xy 169.757598 -209.472784)
			(xy 169.747474 -209.472276) (xy 169.728758 -209.464552) (xy 169.714402 -209.450272) (xy 169.706579 -209.431597)
			(xy 169.706036 -209.421476) (xy 167.108632 -209.421476) (xy 167.10816 -209.431625) (xy 167.100378 -209.45037)
			(xy 167.085997 -209.464694) (xy 167.06722 -209.4724) (xy 167.05707 -209.472784) (xy 165.65753 -209.472784)
			(xy 165.647408 -209.47225) (xy 165.628692 -209.464536) (xy 165.614336 -209.450265) (xy 165.606511 -209.431595)
			(xy 165.605968 -209.421476) (xy 163.6649 -209.421476) (xy 163.664459 -209.431629) (xy 163.656671 -209.450381)
			(xy 163.64228 -209.464705) (xy 163.623492 -209.472405) (xy 163.613338 -209.472784) (xy 162.213798 -209.472784)
			(xy 162.203674 -209.472276) (xy 162.184958 -209.464552) (xy 162.170602 -209.450272) (xy 162.162779 -209.431597)
			(xy 162.162236 -209.421476) (xy 159.564832 -209.421476) (xy 159.56436 -209.431625) (xy 159.556578 -209.45037)
			(xy 159.542197 -209.464694) (xy 159.52342 -209.4724) (xy 159.51327 -209.472784) (xy 158.11373 -209.472784)
			(xy 158.103608 -209.47225) (xy 158.084892 -209.464536) (xy 158.070536 -209.450265) (xy 158.062711 -209.431595)
			(xy 158.062168 -209.421476) (xy 65.7987 -209.421476) (xy 65.798259 -209.431629) (xy 65.790471 -209.450381)
			(xy 65.77608 -209.464705) (xy 65.757292 -209.472405) (xy 65.747138 -209.472784) (xy 64.347598 -209.472784)
			(xy 64.337474 -209.472276) (xy 64.318758 -209.464552) (xy 64.304402 -209.450272) (xy 64.296579 -209.431597)
			(xy 64.296036 -209.421476) (xy 61.698632 -209.421476) (xy 61.69816 -209.431625) (xy 61.690378 -209.45037)
			(xy 61.675997 -209.464694) (xy 61.65722 -209.4724) (xy 61.64707 -209.472784) (xy 60.24753 -209.472784)
			(xy 60.237408 -209.47225) (xy 60.218692 -209.464536) (xy 60.204336 -209.450265) (xy 60.196511 -209.431595)
			(xy 60.195968 -209.421476) (xy 58.2549 -209.421476) (xy 58.254459 -209.431629) (xy 58.246671 -209.450381)
			(xy 58.23228 -209.464705) (xy 58.213492 -209.472405) (xy 58.203338 -209.472784) (xy 56.803798 -209.472784)
			(xy 56.793674 -209.472276) (xy 56.774958 -209.464552) (xy 56.760602 -209.450272) (xy 56.752779 -209.431597)
			(xy 56.752236 -209.421476) (xy 54.154832 -209.421476) (xy 54.15436 -209.431625) (xy 54.146578 -209.45037)
			(xy 54.132197 -209.464694) (xy 54.11342 -209.4724) (xy 54.10327 -209.472784) (xy 52.70373 -209.472784)
			(xy 52.693608 -209.47225) (xy 52.674892 -209.464536) (xy 52.660536 -209.450265) (xy 52.652711 -209.431595)
			(xy 52.652168 -209.421476) (xy 50.7111 -209.421476) (xy 50.710659 -209.431629) (xy 50.702871 -209.450381)
			(xy 50.68848 -209.464705) (xy 50.669692 -209.472405) (xy 50.659538 -209.472784) (xy 49.259998 -209.472784)
			(xy 49.249874 -209.472276) (xy 49.231158 -209.464552) (xy 49.216802 -209.450272) (xy 49.208979 -209.431597)
			(xy 49.208436 -209.421476) (xy 46.611032 -209.421476) (xy 46.61056 -209.431625) (xy 46.602778 -209.45037)
			(xy 46.588397 -209.464694) (xy 46.56962 -209.4724) (xy 46.55947 -209.472784) (xy 45.15993 -209.472784)
			(xy 45.149808 -209.47225) (xy 45.131092 -209.464536) (xy 45.116736 -209.450265) (xy 45.108911 -209.431595)
			(xy 45.108368 -209.421476) (xy 43.1673 -209.421476) (xy 43.166859 -209.431629) (xy 43.159071 -209.450381)
			(xy 43.14468 -209.464705) (xy 43.125892 -209.472405) (xy 43.115738 -209.472784) (xy 41.716198 -209.472784)
			(xy 41.706074 -209.472276) (xy 41.687358 -209.464552) (xy 41.673002 -209.450272) (xy 41.665179 -209.431597)
			(xy 41.664636 -209.421476) (xy 39.067232 -209.421476) (xy 39.06676 -209.431625) (xy 39.058978 -209.45037)
			(xy 39.044597 -209.464694) (xy 39.02582 -209.4724) (xy 39.01567 -209.472784) (xy 37.61613 -209.472784)
			(xy 37.606008 -209.47225) (xy 37.587292 -209.464536) (xy 37.572936 -209.450265) (xy 37.565111 -209.431595)
			(xy 37.564568 -209.421476) (xy 35.6235 -209.421476) (xy 35.623059 -209.431629) (xy 35.615271 -209.450381)
			(xy 35.60088 -209.464705) (xy 35.582092 -209.472405) (xy 35.571938 -209.472784) (xy 34.172398 -209.472784)
			(xy 34.162274 -209.472276) (xy 34.143558 -209.464552) (xy 34.129202 -209.450272) (xy 34.121379 -209.431597)
			(xy 34.120836 -209.421476) (xy 31.523432 -209.421476) (xy 31.52296 -209.431625) (xy 31.515178 -209.45037)
			(xy 31.500797 -209.464694) (xy 31.48202 -209.4724) (xy 31.47187 -209.472784) (xy 30.07233 -209.472784)
			(xy 30.062208 -209.47225) (xy 30.043492 -209.464536) (xy 30.029136 -209.450265) (xy 30.021311 -209.431595)
			(xy 30.020768 -209.421476) (xy 28.0797 -209.421476) (xy 28.079259 -209.431629) (xy 28.071471 -209.450381)
			(xy 28.05708 -209.464705) (xy 28.038292 -209.472405) (xy 28.028138 -209.472784) (xy 26.628598 -209.472784)
			(xy 26.618474 -209.472276) (xy 26.599758 -209.464552) (xy 26.585402 -209.450272) (xy 26.577579 -209.431597)
			(xy 26.577036 -209.421476) (xy 23.979632 -209.421476) (xy 23.97916 -209.431625) (xy 23.971378 -209.45037)
			(xy 23.956997 -209.464694) (xy 23.93822 -209.4724) (xy 23.92807 -209.472784) (xy 22.52853 -209.472784)
			(xy 22.518408 -209.47225) (xy 22.499692 -209.464536) (xy 22.485336 -209.450265) (xy 22.477511 -209.431595)
			(xy 22.476968 -209.421476) (xy 20.5359 -209.421476) (xy 20.535459 -209.431629) (xy 20.527671 -209.450381)
			(xy 20.51328 -209.464705) (xy 20.494492 -209.472405) (xy 20.484338 -209.472784) (xy 19.084798 -209.472784)
			(xy 19.074674 -209.472276) (xy 19.055958 -209.464552) (xy 19.041602 -209.450272) (xy 19.033779 -209.431597)
			(xy 19.033236 -209.421476) (xy 16.435832 -209.421476) (xy 16.43536 -209.431625) (xy 16.427578 -209.45037)
			(xy 16.413197 -209.464694) (xy 16.39442 -209.4724) (xy 16.38427 -209.472784) (xy 14.98473 -209.472784)
			(xy 14.974608 -209.47225) (xy 14.955892 -209.464536) (xy 14.941536 -209.450265) (xy 14.933711 -209.431595)
			(xy 14.933168 -209.421476) (xy 12.9921 -209.421476) (xy 12.991659 -209.431629) (xy 12.983871 -209.450381)
			(xy 12.96948 -209.464705) (xy 12.950692 -209.472405) (xy 12.940538 -209.472784) (xy 11.540998 -209.472784)
			(xy 11.530874 -209.472276) (xy 11.512158 -209.464552) (xy 11.497802 -209.450272) (xy 11.489979 -209.431597)
			(xy 11.489436 -209.421476) (xy 8.892032 -209.421476) (xy 8.89156 -209.431625) (xy 8.883778 -209.45037)
			(xy 8.869397 -209.464694) (xy 8.85062 -209.4724) (xy 8.84047 -209.472784) (xy 7.44093 -209.472784)
			(xy 7.430808 -209.47225) (xy 7.412092 -209.464536) (xy 7.397736 -209.450265) (xy 7.389911 -209.431595)
			(xy 7.389368 -209.421476) (xy 2.509012 -209.421476) (xy 2.509012 -210.27136) (xy 7.389368 -210.27136)
			(xy 7.389368 -209.86242) (xy 7.389837 -209.852271) (xy 7.39762 -209.833525) (xy 7.412002 -209.819202)
			(xy 7.43078 -209.811496) (xy 7.44093 -209.811112) (xy 8.84047 -209.811112) (xy 8.850591 -209.81165)
			(xy 8.869307 -209.819363) (xy 8.883663 -209.833633) (xy 8.891488 -209.852302) (xy 8.892032 -209.86242)
			(xy 8.892032 -210.27136) (xy 14.933168 -210.27136) (xy 14.933168 -209.86242) (xy 14.933637 -209.852271)
			(xy 14.94142 -209.833525) (xy 14.955802 -209.819202) (xy 14.97458 -209.811496) (xy 14.98473 -209.811112)
			(xy 16.38427 -209.811112) (xy 16.394391 -209.81165) (xy 16.413107 -209.819363) (xy 16.427463 -209.833633)
			(xy 16.435288 -209.852302) (xy 16.435832 -209.86242) (xy 16.435832 -210.27136) (xy 22.476968 -210.27136)
			(xy 22.476968 -209.86242) (xy 22.477437 -209.852271) (xy 22.48522 -209.833525) (xy 22.499602 -209.819202)
			(xy 22.51838 -209.811496) (xy 22.52853 -209.811112) (xy 23.92807 -209.811112) (xy 23.938191 -209.81165)
			(xy 23.956907 -209.819363) (xy 23.971263 -209.833633) (xy 23.979088 -209.852302) (xy 23.979632 -209.86242)
			(xy 23.979632 -210.27136) (xy 30.020768 -210.27136) (xy 30.020768 -209.86242) (xy 30.021237 -209.852271)
			(xy 30.02902 -209.833525) (xy 30.043402 -209.819202) (xy 30.06218 -209.811496) (xy 30.07233 -209.811112)
			(xy 31.47187 -209.811112) (xy 31.481991 -209.81165) (xy 31.500707 -209.819363) (xy 31.515063 -209.833633)
			(xy 31.522888 -209.852302) (xy 31.523432 -209.86242) (xy 31.523432 -210.27136) (xy 37.564568 -210.27136)
			(xy 37.564568 -209.86242) (xy 37.565037 -209.852271) (xy 37.57282 -209.833525) (xy 37.587202 -209.819202)
			(xy 37.60598 -209.811496) (xy 37.61613 -209.811112) (xy 39.01567 -209.811112) (xy 39.025791 -209.81165)
			(xy 39.044507 -209.819363) (xy 39.058863 -209.833633) (xy 39.066688 -209.852302) (xy 39.067232 -209.86242)
			(xy 39.067232 -210.27136) (xy 45.108368 -210.27136) (xy 45.108368 -209.86242) (xy 45.108837 -209.852271)
			(xy 45.11662 -209.833525) (xy 45.131002 -209.819202) (xy 45.14978 -209.811496) (xy 45.15993 -209.811112)
			(xy 46.55947 -209.811112) (xy 46.569591 -209.81165) (xy 46.588307 -209.819363) (xy 46.602663 -209.833633)
			(xy 46.610488 -209.852302) (xy 46.611032 -209.86242) (xy 46.611032 -210.27136) (xy 52.652168 -210.27136)
			(xy 52.652168 -209.86242) (xy 52.652637 -209.852271) (xy 52.66042 -209.833525) (xy 52.674802 -209.819202)
			(xy 52.69358 -209.811496) (xy 52.70373 -209.811112) (xy 54.10327 -209.811112) (xy 54.113391 -209.81165)
			(xy 54.132107 -209.819363) (xy 54.146463 -209.833633) (xy 54.154288 -209.852302) (xy 54.154832 -209.86242)
			(xy 54.154832 -210.27136) (xy 60.195968 -210.27136) (xy 60.195968 -209.86242) (xy 60.196437 -209.852271)
			(xy 60.20422 -209.833525) (xy 60.218602 -209.819202) (xy 60.23738 -209.811496) (xy 60.24753 -209.811112)
			(xy 61.64707 -209.811112) (xy 61.657191 -209.81165) (xy 61.675907 -209.819363) (xy 61.690263 -209.833633)
			(xy 61.698088 -209.852302) (xy 61.698632 -209.86242) (xy 61.698632 -210.27136) (xy 158.062168 -210.27136)
			(xy 158.062168 -209.86242) (xy 158.062637 -209.852271) (xy 158.07042 -209.833525) (xy 158.084802 -209.819202)
			(xy 158.10358 -209.811496) (xy 158.11373 -209.811112) (xy 159.51327 -209.811112) (xy 159.523391 -209.81165)
			(xy 159.542107 -209.819363) (xy 159.556463 -209.833633) (xy 159.564288 -209.852302) (xy 159.564832 -209.86242)
			(xy 159.564832 -210.27136) (xy 165.605968 -210.27136) (xy 165.605968 -209.86242) (xy 165.606437 -209.852271)
			(xy 165.61422 -209.833525) (xy 165.628602 -209.819202) (xy 165.64738 -209.811496) (xy 165.65753 -209.811112)
			(xy 167.05707 -209.811112) (xy 167.067191 -209.81165) (xy 167.085907 -209.819363) (xy 167.100263 -209.833633)
			(xy 167.108088 -209.852302) (xy 167.108632 -209.86242) (xy 167.108632 -210.27136) (xy 173.149768 -210.27136)
			(xy 173.149768 -209.86242) (xy 173.150237 -209.852271) (xy 173.15802 -209.833525) (xy 173.172402 -209.819202)
			(xy 173.19118 -209.811496) (xy 173.20133 -209.811112) (xy 174.60087 -209.811112) (xy 174.610991 -209.81165)
			(xy 174.629707 -209.819363) (xy 174.644063 -209.833633) (xy 174.651888 -209.852302) (xy 174.652432 -209.86242)
			(xy 174.652432 -210.27136) (xy 180.693568 -210.27136) (xy 180.693568 -209.86242) (xy 180.694037 -209.852271)
			(xy 180.70182 -209.833525) (xy 180.716202 -209.819202) (xy 180.73498 -209.811496) (xy 180.74513 -209.811112)
			(xy 182.14467 -209.811112) (xy 182.154791 -209.81165) (xy 182.173507 -209.819363) (xy 182.187863 -209.833633)
			(xy 182.195688 -209.852302) (xy 182.196232 -209.86242) (xy 182.196232 -210.27136) (xy 188.237368 -210.27136)
			(xy 188.237368 -209.86242) (xy 188.237837 -209.852271) (xy 188.24562 -209.833525) (xy 188.260002 -209.819202)
			(xy 188.27878 -209.811496) (xy 188.28893 -209.811112) (xy 189.68847 -209.811112) (xy 189.698591 -209.81165)
			(xy 189.717307 -209.819363) (xy 189.731663 -209.833633) (xy 189.739488 -209.852302) (xy 189.740032 -209.86242)
			(xy 189.740032 -210.27136) (xy 195.781168 -210.27136) (xy 195.781168 -209.86242) (xy 195.781637 -209.852271)
			(xy 195.78942 -209.833525) (xy 195.803802 -209.819202) (xy 195.82258 -209.811496) (xy 195.83273 -209.811112)
			(xy 197.23227 -209.811112) (xy 197.242391 -209.81165) (xy 197.261107 -209.819363) (xy 197.275463 -209.833633)
			(xy 197.283288 -209.852302) (xy 197.283832 -209.86242) (xy 197.283832 -210.27136) (xy 203.324968 -210.27136)
			(xy 203.324968 -209.86242) (xy 203.325437 -209.852271) (xy 203.33322 -209.833525) (xy 203.347602 -209.819202)
			(xy 203.36638 -209.811496) (xy 203.37653 -209.811112) (xy 204.77607 -209.811112) (xy 204.786191 -209.81165)
			(xy 204.804907 -209.819363) (xy 204.819263 -209.833633) (xy 204.827088 -209.852302) (xy 204.827632 -209.86242)
			(xy 204.827632 -210.27136) (xy 210.868768 -210.27136) (xy 210.868768 -209.86242) (xy 210.869237 -209.852271)
			(xy 210.87702 -209.833525) (xy 210.891402 -209.819202) (xy 210.91018 -209.811496) (xy 210.92033 -209.811112)
			(xy 212.31987 -209.811112) (xy 212.329991 -209.81165) (xy 212.348707 -209.819363) (xy 212.363063 -209.833633)
			(xy 212.370888 -209.852302) (xy 212.371432 -209.86242) (xy 212.371432 -210.27136) (xy 255.329436 -210.27136)
			(xy 255.329436 -209.86242) (xy 255.329839 -209.852263) (xy 255.337634 -209.833504) (xy 255.352038 -209.819178)
			(xy 255.370838 -209.811484) (xy 255.380998 -209.811112) (xy 256.780538 -209.811112) (xy 256.790664 -209.811595)
			(xy 256.80938 -209.81933) (xy 256.823734 -209.833616) (xy 256.831557 -209.852297) (xy 256.8321 -209.86242)
			(xy 256.8321 -210.27136) (xy 262.873236 -210.27136) (xy 262.873236 -209.86242) (xy 262.873639 -209.852263)
			(xy 262.881434 -209.833504) (xy 262.895838 -209.819178) (xy 262.914638 -209.811484) (xy 262.924798 -209.811112)
			(xy 264.324338 -209.811112) (xy 264.334464 -209.811595) (xy 264.35318 -209.81933) (xy 264.367534 -209.833616)
			(xy 264.375357 -209.852297) (xy 264.3759 -209.86242) (xy 264.3759 -210.27136) (xy 270.417036 -210.27136)
			(xy 270.417036 -209.86242) (xy 270.417439 -209.852263) (xy 270.425234 -209.833504) (xy 270.439638 -209.819178)
			(xy 270.458438 -209.811484) (xy 270.468598 -209.811112) (xy 271.868138 -209.811112) (xy 271.878264 -209.811595)
			(xy 271.89698 -209.81933) (xy 271.911334 -209.833616) (xy 271.919157 -209.852297) (xy 271.9197 -209.86242)
			(xy 271.9197 -210.27136) (xy 277.960836 -210.27136) (xy 277.960836 -209.86242) (xy 277.961239 -209.852263)
			(xy 277.969034 -209.833504) (xy 277.983438 -209.819178) (xy 278.002238 -209.811484) (xy 278.012398 -209.811112)
			(xy 279.411938 -209.811112) (xy 279.422064 -209.811595) (xy 279.44078 -209.81933) (xy 279.455134 -209.833616)
			(xy 279.462957 -209.852297) (xy 279.4635 -209.86242) (xy 279.4635 -210.27136) (xy 285.504636 -210.27136)
			(xy 285.504636 -209.86242) (xy 285.505039 -209.852263) (xy 285.512834 -209.833504) (xy 285.527238 -209.819178)
			(xy 285.546038 -209.811484) (xy 285.556198 -209.811112) (xy 286.955738 -209.811112) (xy 286.965864 -209.811595)
			(xy 286.98458 -209.81933) (xy 286.998934 -209.833616) (xy 287.006757 -209.852297) (xy 287.0073 -209.86242)
			(xy 287.0073 -210.27136) (xy 293.048436 -210.27136) (xy 293.048436 -209.86242) (xy 293.048839 -209.852263)
			(xy 293.056634 -209.833504) (xy 293.071038 -209.819178) (xy 293.089838 -209.811484) (xy 293.099998 -209.811112)
			(xy 294.499538 -209.811112) (xy 294.509664 -209.811595) (xy 294.52838 -209.81933) (xy 294.542734 -209.833616)
			(xy 294.550557 -209.852297) (xy 294.5511 -209.86242) (xy 294.5511 -210.27136) (xy 300.592236 -210.27136)
			(xy 300.592236 -209.86242) (xy 300.592639 -209.852263) (xy 300.600434 -209.833504) (xy 300.614838 -209.819178)
			(xy 300.633638 -209.811484) (xy 300.643798 -209.811112) (xy 302.043338 -209.811112) (xy 302.053464 -209.811595)
			(xy 302.07218 -209.81933) (xy 302.086534 -209.833616) (xy 302.094357 -209.852297) (xy 302.0949 -209.86242)
			(xy 302.0949 -210.27136) (xy 308.136036 -210.27136) (xy 308.136036 -209.86242) (xy 308.136439 -209.852263)
			(xy 308.144234 -209.833504) (xy 308.158638 -209.819178) (xy 308.177438 -209.811484) (xy 308.187598 -209.811112)
			(xy 309.587138 -209.811112) (xy 309.597264 -209.811595) (xy 309.61598 -209.81933) (xy 309.630334 -209.833616)
			(xy 309.638157 -209.852297) (xy 309.6387 -209.86242) (xy 309.6387 -210.27136) (xy 406.002236 -210.27136)
			(xy 406.002236 -209.86242) (xy 406.002639 -209.852263) (xy 406.010434 -209.833504) (xy 406.024838 -209.819178)
			(xy 406.043638 -209.811484) (xy 406.053798 -209.811112) (xy 407.453338 -209.811112) (xy 407.463464 -209.811595)
			(xy 407.48218 -209.81933) (xy 407.496534 -209.833616) (xy 407.504357 -209.852297) (xy 407.5049 -209.86242)
			(xy 407.5049 -210.27136) (xy 413.546036 -210.27136) (xy 413.546036 -209.86242) (xy 413.546439 -209.852263)
			(xy 413.554234 -209.833504) (xy 413.568638 -209.819178) (xy 413.587438 -209.811484) (xy 413.597598 -209.811112)
			(xy 414.997138 -209.811112) (xy 415.007264 -209.811595) (xy 415.02598 -209.81933) (xy 415.040334 -209.833616)
			(xy 415.048157 -209.852297) (xy 415.0487 -209.86242) (xy 415.0487 -210.27136) (xy 421.089836 -210.27136)
			(xy 421.089836 -209.86242) (xy 421.090239 -209.852263) (xy 421.098034 -209.833504) (xy 421.112438 -209.819178)
			(xy 421.131238 -209.811484) (xy 421.141398 -209.811112) (xy 422.540938 -209.811112) (xy 422.551064 -209.811595)
			(xy 422.56978 -209.81933) (xy 422.584134 -209.833616) (xy 422.591957 -209.852297) (xy 422.5925 -209.86242)
			(xy 422.5925 -210.27136) (xy 428.633636 -210.27136) (xy 428.633636 -209.86242) (xy 428.634039 -209.852263)
			(xy 428.641834 -209.833504) (xy 428.656238 -209.819178) (xy 428.675038 -209.811484) (xy 428.685198 -209.811112)
			(xy 430.084738 -209.811112) (xy 430.094864 -209.811595) (xy 430.11358 -209.81933) (xy 430.127934 -209.833616)
			(xy 430.135757 -209.852297) (xy 430.1363 -209.86242) (xy 430.1363 -210.27136) (xy 436.177436 -210.27136)
			(xy 436.177436 -209.86242) (xy 436.177839 -209.852263) (xy 436.185634 -209.833504) (xy 436.200038 -209.819178)
			(xy 436.218838 -209.811484) (xy 436.228998 -209.811112) (xy 437.628538 -209.811112) (xy 437.638664 -209.811595)
			(xy 437.65738 -209.81933) (xy 437.671734 -209.833616) (xy 437.679557 -209.852297) (xy 437.6801 -209.86242)
			(xy 437.6801 -210.27136) (xy 443.721236 -210.27136) (xy 443.721236 -209.86242) (xy 443.721639 -209.852263)
			(xy 443.729434 -209.833504) (xy 443.743838 -209.819178) (xy 443.762638 -209.811484) (xy 443.772798 -209.811112)
			(xy 445.172338 -209.811112) (xy 445.182464 -209.811595) (xy 445.20118 -209.81933) (xy 445.215534 -209.833616)
			(xy 445.223357 -209.852297) (xy 445.2239 -209.86242) (xy 445.2239 -210.27136) (xy 451.265036 -210.27136)
			(xy 451.265036 -209.86242) (xy 451.265439 -209.852263) (xy 451.273234 -209.833504) (xy 451.287638 -209.819178)
			(xy 451.306438 -209.811484) (xy 451.316598 -209.811112) (xy 452.716138 -209.811112) (xy 452.726264 -209.811595)
			(xy 452.74498 -209.81933) (xy 452.759334 -209.833616) (xy 452.767157 -209.852297) (xy 452.7677 -209.86242)
			(xy 452.7677 -210.27136) (xy 458.808836 -210.27136) (xy 458.808836 -209.86242) (xy 458.809239 -209.852263)
			(xy 458.817034 -209.833504) (xy 458.831438 -209.819178) (xy 458.850238 -209.811484) (xy 458.860398 -209.811112)
			(xy 460.259938 -209.811112) (xy 460.270064 -209.811595) (xy 460.28878 -209.81933) (xy 460.303134 -209.833616)
			(xy 460.310957 -209.852297) (xy 460.3115 -209.86242) (xy 460.3115 -210.27136) (xy 460.311045 -210.281512)
			(xy 460.303263 -210.300263) (xy 460.288876 -210.314588) (xy 460.270091 -210.322289) (xy 460.259938 -210.322668)
			(xy 458.860398 -210.322668) (xy 458.850272 -210.322175) (xy 458.831553 -210.314448) (xy 458.817197 -210.300164)
			(xy 458.809376 -210.281483) (xy 458.808836 -210.27136) (xy 452.7677 -210.27136) (xy 452.767245 -210.281512)
			(xy 452.759463 -210.300263) (xy 452.745076 -210.314588) (xy 452.726291 -210.322289) (xy 452.716138 -210.322668)
			(xy 451.316598 -210.322668) (xy 451.306472 -210.322175) (xy 451.287753 -210.314448) (xy 451.273397 -210.300164)
			(xy 451.265576 -210.281483) (xy 451.265036 -210.27136) (xy 445.2239 -210.27136) (xy 445.223445 -210.281512)
			(xy 445.215663 -210.300263) (xy 445.201276 -210.314588) (xy 445.182491 -210.322289) (xy 445.172338 -210.322668)
			(xy 443.772798 -210.322668) (xy 443.762672 -210.322175) (xy 443.743953 -210.314448) (xy 443.729597 -210.300164)
			(xy 443.721776 -210.281483) (xy 443.721236 -210.27136) (xy 437.6801 -210.27136) (xy 437.679645 -210.281512)
			(xy 437.671863 -210.300263) (xy 437.657476 -210.314588) (xy 437.638691 -210.322289) (xy 437.628538 -210.322668)
			(xy 436.228998 -210.322668) (xy 436.218872 -210.322175) (xy 436.200153 -210.314448) (xy 436.185797 -210.300164)
			(xy 436.177976 -210.281483) (xy 436.177436 -210.27136) (xy 430.1363 -210.27136) (xy 430.135845 -210.281512)
			(xy 430.128063 -210.300263) (xy 430.113676 -210.314588) (xy 430.094891 -210.322289) (xy 430.084738 -210.322668)
			(xy 428.685198 -210.322668) (xy 428.675072 -210.322175) (xy 428.656353 -210.314448) (xy 428.641997 -210.300164)
			(xy 428.634176 -210.281483) (xy 428.633636 -210.27136) (xy 422.5925 -210.27136) (xy 422.592045 -210.281512)
			(xy 422.584263 -210.300263) (xy 422.569876 -210.314588) (xy 422.551091 -210.322289) (xy 422.540938 -210.322668)
			(xy 421.141398 -210.322668) (xy 421.131272 -210.322175) (xy 421.112553 -210.314448) (xy 421.098197 -210.300164)
			(xy 421.090376 -210.281483) (xy 421.089836 -210.27136) (xy 415.0487 -210.27136) (xy 415.048245 -210.281512)
			(xy 415.040463 -210.300263) (xy 415.026076 -210.314588) (xy 415.007291 -210.322289) (xy 414.997138 -210.322668)
			(xy 413.597598 -210.322668) (xy 413.587472 -210.322175) (xy 413.568753 -210.314448) (xy 413.554397 -210.300164)
			(xy 413.546576 -210.281483) (xy 413.546036 -210.27136) (xy 407.5049 -210.27136) (xy 407.504445 -210.281512)
			(xy 407.496663 -210.300263) (xy 407.482276 -210.314588) (xy 407.463491 -210.322289) (xy 407.453338 -210.322668)
			(xy 406.053798 -210.322668) (xy 406.043672 -210.322175) (xy 406.024953 -210.314448) (xy 406.010597 -210.300164)
			(xy 406.002776 -210.281483) (xy 406.002236 -210.27136) (xy 309.6387 -210.27136) (xy 309.638245 -210.281512)
			(xy 309.630463 -210.300263) (xy 309.616076 -210.314588) (xy 309.597291 -210.322289) (xy 309.587138 -210.322668)
			(xy 308.187598 -210.322668) (xy 308.177472 -210.322175) (xy 308.158753 -210.314448) (xy 308.144397 -210.300164)
			(xy 308.136576 -210.281483) (xy 308.136036 -210.27136) (xy 302.0949 -210.27136) (xy 302.094445 -210.281512)
			(xy 302.086663 -210.300263) (xy 302.072276 -210.314588) (xy 302.053491 -210.322289) (xy 302.043338 -210.322668)
			(xy 300.643798 -210.322668) (xy 300.633672 -210.322175) (xy 300.614953 -210.314448) (xy 300.600597 -210.300164)
			(xy 300.592776 -210.281483) (xy 300.592236 -210.27136) (xy 294.5511 -210.27136) (xy 294.550645 -210.281512)
			(xy 294.542863 -210.300263) (xy 294.528476 -210.314588) (xy 294.509691 -210.322289) (xy 294.499538 -210.322668)
			(xy 293.099998 -210.322668) (xy 293.089872 -210.322175) (xy 293.071153 -210.314448) (xy 293.056797 -210.300164)
			(xy 293.048976 -210.281483) (xy 293.048436 -210.27136) (xy 287.0073 -210.27136) (xy 287.006845 -210.281512)
			(xy 286.999063 -210.300263) (xy 286.984676 -210.314588) (xy 286.965891 -210.322289) (xy 286.955738 -210.322668)
			(xy 285.556198 -210.322668) (xy 285.546072 -210.322175) (xy 285.527353 -210.314448) (xy 285.512997 -210.300164)
			(xy 285.505176 -210.281483) (xy 285.504636 -210.27136) (xy 279.4635 -210.27136) (xy 279.463045 -210.281512)
			(xy 279.455263 -210.300263) (xy 279.440876 -210.314588) (xy 279.422091 -210.322289) (xy 279.411938 -210.322668)
			(xy 278.012398 -210.322668) (xy 278.002272 -210.322175) (xy 277.983553 -210.314448) (xy 277.969197 -210.300164)
			(xy 277.961376 -210.281483) (xy 277.960836 -210.27136) (xy 271.9197 -210.27136) (xy 271.919245 -210.281512)
			(xy 271.911463 -210.300263) (xy 271.897076 -210.314588) (xy 271.878291 -210.322289) (xy 271.868138 -210.322668)
			(xy 270.468598 -210.322668) (xy 270.458472 -210.322175) (xy 270.439753 -210.314448) (xy 270.425397 -210.300164)
			(xy 270.417576 -210.281483) (xy 270.417036 -210.27136) (xy 264.3759 -210.27136) (xy 264.375445 -210.281512)
			(xy 264.367663 -210.300263) (xy 264.353276 -210.314588) (xy 264.334491 -210.322289) (xy 264.324338 -210.322668)
			(xy 262.924798 -210.322668) (xy 262.914672 -210.322175) (xy 262.895953 -210.314448) (xy 262.881597 -210.300164)
			(xy 262.873776 -210.281483) (xy 262.873236 -210.27136) (xy 256.8321 -210.27136) (xy 256.831645 -210.281512)
			(xy 256.823863 -210.300263) (xy 256.809476 -210.314588) (xy 256.790691 -210.322289) (xy 256.780538 -210.322668)
			(xy 255.380998 -210.322668) (xy 255.370872 -210.322175) (xy 255.352153 -210.314448) (xy 255.337797 -210.300164)
			(xy 255.329976 -210.281483) (xy 255.329436 -210.27136) (xy 212.371432 -210.27136) (xy 212.370946 -210.281508)
			(xy 212.36317 -210.300253) (xy 212.348793 -210.314576) (xy 212.330019 -210.322283) (xy 212.31987 -210.322668)
			(xy 210.92033 -210.322668) (xy 210.910206 -210.322149) (xy 210.891487 -210.314433) (xy 210.87713 -210.300156)
			(xy 210.869308 -210.281481) (xy 210.868768 -210.27136) (xy 204.827632 -210.27136) (xy 204.827146 -210.281508)
			(xy 204.81937 -210.300253) (xy 204.804993 -210.314576) (xy 204.786219 -210.322283) (xy 204.77607 -210.322668)
			(xy 203.37653 -210.322668) (xy 203.366406 -210.322149) (xy 203.347687 -210.314433) (xy 203.33333 -210.300156)
			(xy 203.325508 -210.281481) (xy 203.324968 -210.27136) (xy 197.283832 -210.27136) (xy 197.283346 -210.281508)
			(xy 197.27557 -210.300253) (xy 197.261193 -210.314576) (xy 197.242419 -210.322283) (xy 197.23227 -210.322668)
			(xy 195.83273 -210.322668) (xy 195.822606 -210.322149) (xy 195.803887 -210.314433) (xy 195.78953 -210.300156)
			(xy 195.781708 -210.281481) (xy 195.781168 -210.27136) (xy 189.740032 -210.27136) (xy 189.739546 -210.281508)
			(xy 189.73177 -210.300253) (xy 189.717393 -210.314576) (xy 189.698619 -210.322283) (xy 189.68847 -210.322668)
			(xy 188.28893 -210.322668) (xy 188.278806 -210.322149) (xy 188.260087 -210.314433) (xy 188.24573 -210.300156)
			(xy 188.237908 -210.281481) (xy 188.237368 -210.27136) (xy 182.196232 -210.27136) (xy 182.195746 -210.281508)
			(xy 182.18797 -210.300253) (xy 182.173593 -210.314576) (xy 182.154819 -210.322283) (xy 182.14467 -210.322668)
			(xy 180.74513 -210.322668) (xy 180.735006 -210.322149) (xy 180.716287 -210.314433) (xy 180.70193 -210.300156)
			(xy 180.694108 -210.281481) (xy 180.693568 -210.27136) (xy 174.652432 -210.27136) (xy 174.651946 -210.281508)
			(xy 174.64417 -210.300253) (xy 174.629793 -210.314576) (xy 174.611019 -210.322283) (xy 174.60087 -210.322668)
			(xy 173.20133 -210.322668) (xy 173.191206 -210.322149) (xy 173.172487 -210.314433) (xy 173.15813 -210.300156)
			(xy 173.150308 -210.281481) (xy 173.149768 -210.27136) (xy 167.108632 -210.27136) (xy 167.108146 -210.281508)
			(xy 167.10037 -210.300253) (xy 167.085993 -210.314576) (xy 167.067219 -210.322283) (xy 167.05707 -210.322668)
			(xy 165.65753 -210.322668) (xy 165.647406 -210.322149) (xy 165.628687 -210.314433) (xy 165.61433 -210.300156)
			(xy 165.606508 -210.281481) (xy 165.605968 -210.27136) (xy 159.564832 -210.27136) (xy 159.564346 -210.281508)
			(xy 159.55657 -210.300253) (xy 159.542193 -210.314576) (xy 159.523419 -210.322283) (xy 159.51327 -210.322668)
			(xy 158.11373 -210.322668) (xy 158.103606 -210.322149) (xy 158.084887 -210.314433) (xy 158.07053 -210.300156)
			(xy 158.062708 -210.281481) (xy 158.062168 -210.27136) (xy 61.698632 -210.27136) (xy 61.698146 -210.281508)
			(xy 61.69037 -210.300253) (xy 61.675993 -210.314576) (xy 61.657219 -210.322283) (xy 61.64707 -210.322668)
			(xy 60.24753 -210.322668) (xy 60.237406 -210.322149) (xy 60.218687 -210.314433) (xy 60.20433 -210.300156)
			(xy 60.196508 -210.281481) (xy 60.195968 -210.27136) (xy 54.154832 -210.27136) (xy 54.154346 -210.281508)
			(xy 54.14657 -210.300253) (xy 54.132193 -210.314576) (xy 54.113419 -210.322283) (xy 54.10327 -210.322668)
			(xy 52.70373 -210.322668) (xy 52.693606 -210.322149) (xy 52.674887 -210.314433) (xy 52.66053 -210.300156)
			(xy 52.652708 -210.281481) (xy 52.652168 -210.27136) (xy 46.611032 -210.27136) (xy 46.610546 -210.281508)
			(xy 46.60277 -210.300253) (xy 46.588393 -210.314576) (xy 46.569619 -210.322283) (xy 46.55947 -210.322668)
			(xy 45.15993 -210.322668) (xy 45.149806 -210.322149) (xy 45.131087 -210.314433) (xy 45.11673 -210.300156)
			(xy 45.108908 -210.281481) (xy 45.108368 -210.27136) (xy 39.067232 -210.27136) (xy 39.066746 -210.281508)
			(xy 39.05897 -210.300253) (xy 39.044593 -210.314576) (xy 39.025819 -210.322283) (xy 39.01567 -210.322668)
			(xy 37.61613 -210.322668) (xy 37.606006 -210.322149) (xy 37.587287 -210.314433) (xy 37.57293 -210.300156)
			(xy 37.565108 -210.281481) (xy 37.564568 -210.27136) (xy 31.523432 -210.27136) (xy 31.522946 -210.281508)
			(xy 31.51517 -210.300253) (xy 31.500793 -210.314576) (xy 31.482019 -210.322283) (xy 31.47187 -210.322668)
			(xy 30.07233 -210.322668) (xy 30.062206 -210.322149) (xy 30.043487 -210.314433) (xy 30.02913 -210.300156)
			(xy 30.021308 -210.281481) (xy 30.020768 -210.27136) (xy 23.979632 -210.27136) (xy 23.979146 -210.281508)
			(xy 23.97137 -210.300253) (xy 23.956993 -210.314576) (xy 23.938219 -210.322283) (xy 23.92807 -210.322668)
			(xy 22.52853 -210.322668) (xy 22.518406 -210.322149) (xy 22.499687 -210.314433) (xy 22.48533 -210.300156)
			(xy 22.477508 -210.281481) (xy 22.476968 -210.27136) (xy 16.435832 -210.27136) (xy 16.435346 -210.281508)
			(xy 16.42757 -210.300253) (xy 16.413193 -210.314576) (xy 16.394419 -210.322283) (xy 16.38427 -210.322668)
			(xy 14.98473 -210.322668) (xy 14.974606 -210.322149) (xy 14.955887 -210.314433) (xy 14.94153 -210.300156)
			(xy 14.933708 -210.281481) (xy 14.933168 -210.27136) (xy 8.892032 -210.27136) (xy 8.891546 -210.281508)
			(xy 8.88377 -210.300253) (xy 8.869393 -210.314576) (xy 8.850619 -210.322283) (xy 8.84047 -210.322668)
			(xy 7.44093 -210.322668) (xy 7.430806 -210.322149) (xy 7.412087 -210.314433) (xy 7.39773 -210.300156)
			(xy 7.389908 -210.281481) (xy 7.389368 -210.27136) (xy 2.509012 -210.27136) (xy 2.509012 -211.121498)
			(xy 11.489436 -211.121498) (xy 11.489436 -210.712558) (xy 11.489899 -210.702398) (xy 11.497687 -210.683628)
			(xy 11.512062 -210.669264) (xy 11.530837 -210.661491) (xy 11.540998 -210.660996) (xy 12.940538 -210.660996)
			(xy 12.950693 -210.661501) (xy 12.969455 -210.66928) (xy 12.983817 -210.683642) (xy 12.991598 -210.702403)
			(xy 12.9921 -210.712558) (xy 12.9921 -211.121498) (xy 19.033236 -211.121498) (xy 19.033236 -210.712558)
			(xy 19.033699 -210.702398) (xy 19.041487 -210.683628) (xy 19.055862 -210.669264) (xy 19.074637 -210.661491)
			(xy 19.084798 -210.660996) (xy 20.484338 -210.660996) (xy 20.494493 -210.661501) (xy 20.513255 -210.66928)
			(xy 20.527617 -210.683642) (xy 20.535398 -210.702403) (xy 20.5359 -210.712558) (xy 20.5359 -211.121498)
			(xy 26.577036 -211.121498) (xy 26.577036 -210.712558) (xy 26.577499 -210.702398) (xy 26.585287 -210.683628)
			(xy 26.599662 -210.669264) (xy 26.618437 -210.661491) (xy 26.628598 -210.660996) (xy 28.028138 -210.660996)
			(xy 28.038293 -210.661501) (xy 28.057055 -210.66928) (xy 28.071417 -210.683642) (xy 28.079198 -210.702403)
			(xy 28.0797 -210.712558) (xy 28.0797 -211.121498) (xy 34.120836 -211.121498) (xy 34.120836 -210.712558)
			(xy 34.121299 -210.702398) (xy 34.129087 -210.683628) (xy 34.143462 -210.669264) (xy 34.162237 -210.661491)
			(xy 34.172398 -210.660996) (xy 35.571938 -210.660996) (xy 35.582093 -210.661501) (xy 35.600855 -210.66928)
			(xy 35.615217 -210.683642) (xy 35.622998 -210.702403) (xy 35.6235 -210.712558) (xy 35.6235 -211.121498)
			(xy 41.664636 -211.121498) (xy 41.664636 -210.712558) (xy 41.665099 -210.702398) (xy 41.672887 -210.683628)
			(xy 41.687262 -210.669264) (xy 41.706037 -210.661491) (xy 41.716198 -210.660996) (xy 43.115738 -210.660996)
			(xy 43.125893 -210.661501) (xy 43.144655 -210.66928) (xy 43.159017 -210.683642) (xy 43.166798 -210.702403)
			(xy 43.1673 -210.712558) (xy 43.1673 -211.121498) (xy 49.208436 -211.121498) (xy 49.208436 -210.712558)
			(xy 49.208899 -210.702398) (xy 49.216687 -210.683628) (xy 49.231062 -210.669264) (xy 49.249837 -210.661491)
			(xy 49.259998 -210.660996) (xy 50.659538 -210.660996) (xy 50.669693 -210.661501) (xy 50.688455 -210.66928)
			(xy 50.702817 -210.683642) (xy 50.710598 -210.702403) (xy 50.7111 -210.712558) (xy 50.7111 -211.121498)
			(xy 56.752236 -211.121498) (xy 56.752236 -210.712558) (xy 56.752699 -210.702398) (xy 56.760487 -210.683628)
			(xy 56.774862 -210.669264) (xy 56.793637 -210.661491) (xy 56.803798 -210.660996) (xy 58.203338 -210.660996)
			(xy 58.213493 -210.661501) (xy 58.232255 -210.66928) (xy 58.246617 -210.683642) (xy 58.254398 -210.702403)
			(xy 58.2549 -210.712558) (xy 58.2549 -211.121498) (xy 64.296036 -211.121498) (xy 64.296036 -210.712558)
			(xy 64.296499 -210.702398) (xy 64.304287 -210.683628) (xy 64.318662 -210.669264) (xy 64.337437 -210.661491)
			(xy 64.347598 -210.660996) (xy 65.747138 -210.660996) (xy 65.757293 -210.661501) (xy 65.776055 -210.66928)
			(xy 65.790417 -210.683642) (xy 65.798198 -210.702403) (xy 65.7987 -210.712558) (xy 65.7987 -211.121498)
			(xy 162.162236 -211.121498) (xy 162.162236 -210.712558) (xy 162.162699 -210.702398) (xy 162.170487 -210.683628)
			(xy 162.184862 -210.669264) (xy 162.203637 -210.661491) (xy 162.213798 -210.660996) (xy 163.613338 -210.660996)
			(xy 163.623493 -210.661501) (xy 163.642255 -210.66928) (xy 163.656617 -210.683642) (xy 163.664398 -210.702403)
			(xy 163.6649 -210.712558) (xy 163.6649 -211.121498) (xy 169.706036 -211.121498) (xy 169.706036 -210.712558)
			(xy 169.706499 -210.702398) (xy 169.714287 -210.683628) (xy 169.728662 -210.669264) (xy 169.747437 -210.661491)
			(xy 169.757598 -210.660996) (xy 171.157138 -210.660996) (xy 171.167293 -210.661501) (xy 171.186055 -210.66928)
			(xy 171.200417 -210.683642) (xy 171.208198 -210.702403) (xy 171.2087 -210.712558) (xy 171.2087 -211.121498)
			(xy 177.249836 -211.121498) (xy 177.249836 -210.712558) (xy 177.250299 -210.702398) (xy 177.258087 -210.683628)
			(xy 177.272462 -210.669264) (xy 177.291237 -210.661491) (xy 177.301398 -210.660996) (xy 178.700938 -210.660996)
			(xy 178.711093 -210.661501) (xy 178.729855 -210.66928) (xy 178.744217 -210.683642) (xy 178.751998 -210.702403)
			(xy 178.7525 -210.712558) (xy 178.7525 -211.121498) (xy 184.793636 -211.121498) (xy 184.793636 -210.712558)
			(xy 184.794099 -210.702398) (xy 184.801887 -210.683628) (xy 184.816262 -210.669264) (xy 184.835037 -210.661491)
			(xy 184.845198 -210.660996) (xy 186.244738 -210.660996) (xy 186.254893 -210.661501) (xy 186.273655 -210.66928)
			(xy 186.288017 -210.683642) (xy 186.295798 -210.702403) (xy 186.2963 -210.712558) (xy 186.2963 -211.121498)
			(xy 192.337436 -211.121498) (xy 192.337436 -210.712558) (xy 192.337899 -210.702398) (xy 192.345687 -210.683628)
			(xy 192.360062 -210.669264) (xy 192.378837 -210.661491) (xy 192.388998 -210.660996) (xy 193.788538 -210.660996)
			(xy 193.798693 -210.661501) (xy 193.817455 -210.66928) (xy 193.831817 -210.683642) (xy 193.839598 -210.702403)
			(xy 193.8401 -210.712558) (xy 193.8401 -211.121498) (xy 199.881236 -211.121498) (xy 199.881236 -210.712558)
			(xy 199.881699 -210.702398) (xy 199.889487 -210.683628) (xy 199.903862 -210.669264) (xy 199.922637 -210.661491)
			(xy 199.932798 -210.660996) (xy 201.332338 -210.660996) (xy 201.342493 -210.661501) (xy 201.361255 -210.66928)
			(xy 201.375617 -210.683642) (xy 201.383398 -210.702403) (xy 201.3839 -210.712558) (xy 201.3839 -211.121498)
			(xy 207.425036 -211.121498) (xy 207.425036 -210.712558) (xy 207.425499 -210.702398) (xy 207.433287 -210.683628)
			(xy 207.447662 -210.669264) (xy 207.466437 -210.661491) (xy 207.476598 -210.660996) (xy 208.876138 -210.660996)
			(xy 208.886293 -210.661501) (xy 208.905055 -210.66928) (xy 208.919417 -210.683642) (xy 208.927198 -210.702403)
			(xy 208.9277 -210.712558) (xy 208.9277 -211.121498) (xy 214.968836 -211.121498) (xy 214.968836 -210.712558)
			(xy 214.969299 -210.702398) (xy 214.977087 -210.683628) (xy 214.991462 -210.669264) (xy 215.010237 -210.661491)
			(xy 215.020398 -210.660996) (xy 216.419938 -210.660996) (xy 216.430093 -210.661501) (xy 216.448855 -210.66928)
			(xy 216.463217 -210.683642) (xy 216.470998 -210.702403) (xy 216.4715 -210.712558) (xy 216.4715 -211.121498)
			(xy 259.429504 -211.121498) (xy 259.429504 -210.712558) (xy 259.429998 -210.702402) (xy 259.43778 -210.683638)
			(xy 259.452145 -210.669276) (xy 259.47091 -210.661497) (xy 259.481066 -210.660996) (xy 260.880606 -210.660996)
			(xy 260.890759 -210.661528) (xy 260.90952 -210.669296) (xy 260.923884 -210.68365) (xy 260.931665 -210.702405)
			(xy 260.932168 -210.712558) (xy 260.932168 -211.121498) (xy 266.973304 -211.121498) (xy 266.973304 -210.712558)
			(xy 266.973798 -210.702402) (xy 266.98158 -210.683638) (xy 266.995945 -210.669276) (xy 267.01471 -210.661497)
			(xy 267.024866 -210.660996) (xy 268.424406 -210.660996) (xy 268.434559 -210.661528) (xy 268.45332 -210.669296)
			(xy 268.467684 -210.68365) (xy 268.475465 -210.702405) (xy 268.475968 -210.712558) (xy 268.475968 -211.121498)
			(xy 274.517104 -211.121498) (xy 274.517104 -210.712558) (xy 274.517598 -210.702402) (xy 274.52538 -210.683638)
			(xy 274.539745 -210.669276) (xy 274.55851 -210.661497) (xy 274.568666 -210.660996) (xy 275.968206 -210.660996)
			(xy 275.978359 -210.661528) (xy 275.99712 -210.669296) (xy 276.011484 -210.68365) (xy 276.019265 -210.702405)
			(xy 276.019768 -210.712558) (xy 276.019768 -211.121498) (xy 282.060904 -211.121498) (xy 282.060904 -210.712558)
			(xy 282.061398 -210.702402) (xy 282.06918 -210.683638) (xy 282.083545 -210.669276) (xy 282.10231 -210.661497)
			(xy 282.112466 -210.660996) (xy 283.512006 -210.660996) (xy 283.522159 -210.661528) (xy 283.54092 -210.669296)
			(xy 283.555284 -210.68365) (xy 283.563065 -210.702405) (xy 283.563568 -210.712558) (xy 283.563568 -211.121498)
			(xy 289.604704 -211.121498) (xy 289.604704 -210.712558) (xy 289.605198 -210.702402) (xy 289.61298 -210.683638)
			(xy 289.627345 -210.669276) (xy 289.64611 -210.661497) (xy 289.656266 -210.660996) (xy 291.055806 -210.660996)
			(xy 291.065959 -210.661528) (xy 291.08472 -210.669296) (xy 291.099084 -210.68365) (xy 291.106865 -210.702405)
			(xy 291.107368 -210.712558) (xy 291.107368 -211.121498) (xy 297.148504 -211.121498) (xy 297.148504 -210.712558)
			(xy 297.148998 -210.702402) (xy 297.15678 -210.683638) (xy 297.171145 -210.669276) (xy 297.18991 -210.661497)
			(xy 297.200066 -210.660996) (xy 298.599606 -210.660996) (xy 298.609759 -210.661528) (xy 298.62852 -210.669296)
			(xy 298.642884 -210.68365) (xy 298.650665 -210.702405) (xy 298.651168 -210.712558) (xy 298.651168 -211.121498)
			(xy 304.692304 -211.121498) (xy 304.692304 -210.712558) (xy 304.692798 -210.702402) (xy 304.70058 -210.683638)
			(xy 304.714945 -210.669276) (xy 304.73371 -210.661497) (xy 304.743866 -210.660996) (xy 306.143406 -210.660996)
			(xy 306.153559 -210.661528) (xy 306.17232 -210.669296) (xy 306.186684 -210.68365) (xy 306.194465 -210.702405)
			(xy 306.194968 -210.712558) (xy 306.194968 -211.121498) (xy 312.236104 -211.121498) (xy 312.236104 -210.712558)
			(xy 312.236598 -210.702402) (xy 312.24438 -210.683638) (xy 312.258745 -210.669276) (xy 312.27751 -210.661497)
			(xy 312.287666 -210.660996) (xy 313.687206 -210.660996) (xy 313.697359 -210.661528) (xy 313.71612 -210.669296)
			(xy 313.730484 -210.68365) (xy 313.738265 -210.702405) (xy 313.738768 -210.712558) (xy 313.738768 -211.121498)
			(xy 410.102304 -211.121498) (xy 410.102304 -210.712558) (xy 410.102798 -210.702402) (xy 410.11058 -210.683638)
			(xy 410.124945 -210.669276) (xy 410.14371 -210.661497) (xy 410.153866 -210.660996) (xy 411.553406 -210.660996)
			(xy 411.563559 -210.661528) (xy 411.58232 -210.669296) (xy 411.596684 -210.68365) (xy 411.604465 -210.702405)
			(xy 411.604968 -210.712558) (xy 411.604968 -211.121498) (xy 417.646104 -211.121498) (xy 417.646104 -210.712558)
			(xy 417.646598 -210.702402) (xy 417.65438 -210.683638) (xy 417.668745 -210.669276) (xy 417.68751 -210.661497)
			(xy 417.697666 -210.660996) (xy 419.097206 -210.660996) (xy 419.107359 -210.661528) (xy 419.12612 -210.669296)
			(xy 419.140484 -210.68365) (xy 419.148265 -210.702405) (xy 419.148768 -210.712558) (xy 419.148768 -211.121498)
			(xy 425.189904 -211.121498) (xy 425.189904 -210.712558) (xy 425.190398 -210.702402) (xy 425.19818 -210.683638)
			(xy 425.212545 -210.669276) (xy 425.23131 -210.661497) (xy 425.241466 -210.660996) (xy 426.641006 -210.660996)
			(xy 426.651159 -210.661528) (xy 426.66992 -210.669296) (xy 426.684284 -210.68365) (xy 426.692065 -210.702405)
			(xy 426.692568 -210.712558) (xy 426.692568 -211.121498) (xy 432.733704 -211.121498) (xy 432.733704 -210.712558)
			(xy 432.734198 -210.702402) (xy 432.74198 -210.683638) (xy 432.756345 -210.669276) (xy 432.77511 -210.661497)
			(xy 432.785266 -210.660996) (xy 434.184806 -210.660996) (xy 434.194959 -210.661528) (xy 434.21372 -210.669296)
			(xy 434.228084 -210.68365) (xy 434.235865 -210.702405) (xy 434.236368 -210.712558) (xy 434.236368 -211.121498)
			(xy 440.277504 -211.121498) (xy 440.277504 -210.712558) (xy 440.277998 -210.702402) (xy 440.28578 -210.683638)
			(xy 440.300145 -210.669276) (xy 440.31891 -210.661497) (xy 440.329066 -210.660996) (xy 441.728606 -210.660996)
			(xy 441.738759 -210.661528) (xy 441.75752 -210.669296) (xy 441.771884 -210.68365) (xy 441.779665 -210.702405)
			(xy 441.780168 -210.712558) (xy 441.780168 -211.121498) (xy 447.821304 -211.121498) (xy 447.821304 -210.712558)
			(xy 447.821798 -210.702402) (xy 447.82958 -210.683638) (xy 447.843945 -210.669276) (xy 447.86271 -210.661497)
			(xy 447.872866 -210.660996) (xy 449.272406 -210.660996) (xy 449.282559 -210.661528) (xy 449.30132 -210.669296)
			(xy 449.315684 -210.68365) (xy 449.323465 -210.702405) (xy 449.323968 -210.712558) (xy 449.323968 -211.121498)
			(xy 455.365104 -211.121498) (xy 455.365104 -210.712558) (xy 455.365598 -210.702402) (xy 455.37338 -210.683638)
			(xy 455.387745 -210.669276) (xy 455.40651 -210.661497) (xy 455.416666 -210.660996) (xy 456.816206 -210.660996)
			(xy 456.826359 -210.661528) (xy 456.84512 -210.669296) (xy 456.859484 -210.68365) (xy 456.867265 -210.702405)
			(xy 456.867768 -210.712558) (xy 456.867768 -211.121498) (xy 462.908904 -211.121498) (xy 462.908904 -210.712558)
			(xy 462.909398 -210.702402) (xy 462.91718 -210.683638) (xy 462.931545 -210.669276) (xy 462.95031 -210.661497)
			(xy 462.960466 -210.660996) (xy 464.360006 -210.660996) (xy 464.370159 -210.661528) (xy 464.38892 -210.669296)
			(xy 464.403284 -210.68365) (xy 464.411065 -210.702405) (xy 464.411568 -210.712558) (xy 464.411568 -211.121498)
			(xy 464.411065 -211.131655) (xy 464.403292 -211.150423) (xy 464.38893 -211.164788) (xy 464.370163 -211.172564)
			(xy 464.360006 -211.17306) (xy 462.960466 -211.17306) (xy 462.950306 -211.172594) (xy 462.931535 -211.164808)
			(xy 462.917171 -211.150434) (xy 462.909398 -211.131659) (xy 462.908904 -211.121498) (xy 456.867768 -211.121498)
			(xy 456.867265 -211.131655) (xy 456.859492 -211.150423) (xy 456.84513 -211.164788) (xy 456.826363 -211.172564)
			(xy 456.816206 -211.17306) (xy 455.416666 -211.17306) (xy 455.406506 -211.172594) (xy 455.387735 -211.164808)
			(xy 455.373371 -211.150434) (xy 455.365598 -211.131659) (xy 455.365104 -211.121498) (xy 449.323968 -211.121498)
			(xy 449.323465 -211.131655) (xy 449.315692 -211.150423) (xy 449.30133 -211.164788) (xy 449.282563 -211.172564)
			(xy 449.272406 -211.17306) (xy 447.872866 -211.17306) (xy 447.862706 -211.172594) (xy 447.843935 -211.164808)
			(xy 447.829571 -211.150434) (xy 447.821798 -211.131659) (xy 447.821304 -211.121498) (xy 441.780168 -211.121498)
			(xy 441.779665 -211.131655) (xy 441.771892 -211.150423) (xy 441.75753 -211.164788) (xy 441.738763 -211.172564)
			(xy 441.728606 -211.17306) (xy 440.329066 -211.17306) (xy 440.318906 -211.172594) (xy 440.300135 -211.164808)
			(xy 440.285771 -211.150434) (xy 440.277998 -211.131659) (xy 440.277504 -211.121498) (xy 434.236368 -211.121498)
			(xy 434.235865 -211.131655) (xy 434.228092 -211.150423) (xy 434.21373 -211.164788) (xy 434.194963 -211.172564)
			(xy 434.184806 -211.17306) (xy 432.785266 -211.17306) (xy 432.775106 -211.172594) (xy 432.756335 -211.164808)
			(xy 432.741971 -211.150434) (xy 432.734198 -211.131659) (xy 432.733704 -211.121498) (xy 426.692568 -211.121498)
			(xy 426.692065 -211.131655) (xy 426.684292 -211.150423) (xy 426.66993 -211.164788) (xy 426.651163 -211.172564)
			(xy 426.641006 -211.17306) (xy 425.241466 -211.17306) (xy 425.231306 -211.172594) (xy 425.212535 -211.164808)
			(xy 425.198171 -211.150434) (xy 425.190398 -211.131659) (xy 425.189904 -211.121498) (xy 419.148768 -211.121498)
			(xy 419.148265 -211.131655) (xy 419.140492 -211.150423) (xy 419.12613 -211.164788) (xy 419.107363 -211.172564)
			(xy 419.097206 -211.17306) (xy 417.697666 -211.17306) (xy 417.687506 -211.172594) (xy 417.668735 -211.164808)
			(xy 417.654371 -211.150434) (xy 417.646598 -211.131659) (xy 417.646104 -211.121498) (xy 411.604968 -211.121498)
			(xy 411.604465 -211.131655) (xy 411.596692 -211.150423) (xy 411.58233 -211.164788) (xy 411.563563 -211.172564)
			(xy 411.553406 -211.17306) (xy 410.153866 -211.17306) (xy 410.143706 -211.172594) (xy 410.124935 -211.164808)
			(xy 410.110571 -211.150434) (xy 410.102798 -211.131659) (xy 410.102304 -211.121498) (xy 313.738768 -211.121498)
			(xy 313.738265 -211.131655) (xy 313.730492 -211.150423) (xy 313.71613 -211.164788) (xy 313.697363 -211.172564)
			(xy 313.687206 -211.17306) (xy 312.287666 -211.17306) (xy 312.277506 -211.172594) (xy 312.258735 -211.164808)
			(xy 312.244371 -211.150434) (xy 312.236598 -211.131659) (xy 312.236104 -211.121498) (xy 306.194968 -211.121498)
			(xy 306.194465 -211.131655) (xy 306.186692 -211.150423) (xy 306.17233 -211.164788) (xy 306.153563 -211.172564)
			(xy 306.143406 -211.17306) (xy 304.743866 -211.17306) (xy 304.733706 -211.172594) (xy 304.714935 -211.164808)
			(xy 304.700571 -211.150434) (xy 304.692798 -211.131659) (xy 304.692304 -211.121498) (xy 298.651168 -211.121498)
			(xy 298.650665 -211.131655) (xy 298.642892 -211.150423) (xy 298.62853 -211.164788) (xy 298.609763 -211.172564)
			(xy 298.599606 -211.17306) (xy 297.200066 -211.17306) (xy 297.189906 -211.172594) (xy 297.171135 -211.164808)
			(xy 297.156771 -211.150434) (xy 297.148998 -211.131659) (xy 297.148504 -211.121498) (xy 291.107368 -211.121498)
			(xy 291.106865 -211.131655) (xy 291.099092 -211.150423) (xy 291.08473 -211.164788) (xy 291.065963 -211.172564)
			(xy 291.055806 -211.17306) (xy 289.656266 -211.17306) (xy 289.646106 -211.172594) (xy 289.627335 -211.164808)
			(xy 289.612971 -211.150434) (xy 289.605198 -211.131659) (xy 289.604704 -211.121498) (xy 283.563568 -211.121498)
			(xy 283.563065 -211.131655) (xy 283.555292 -211.150423) (xy 283.54093 -211.164788) (xy 283.522163 -211.172564)
			(xy 283.512006 -211.17306) (xy 282.112466 -211.17306) (xy 282.102306 -211.172594) (xy 282.083535 -211.164808)
			(xy 282.069171 -211.150434) (xy 282.061398 -211.131659) (xy 282.060904 -211.121498) (xy 276.019768 -211.121498)
			(xy 276.019265 -211.131655) (xy 276.011492 -211.150423) (xy 275.99713 -211.164788) (xy 275.978363 -211.172564)
			(xy 275.968206 -211.17306) (xy 274.568666 -211.17306) (xy 274.558506 -211.172594) (xy 274.539735 -211.164808)
			(xy 274.525371 -211.150434) (xy 274.517598 -211.131659) (xy 274.517104 -211.121498) (xy 268.475968 -211.121498)
			(xy 268.475465 -211.131655) (xy 268.467692 -211.150423) (xy 268.45333 -211.164788) (xy 268.434563 -211.172564)
			(xy 268.424406 -211.17306) (xy 267.024866 -211.17306) (xy 267.014706 -211.172594) (xy 266.995935 -211.164808)
			(xy 266.981571 -211.150434) (xy 266.973798 -211.131659) (xy 266.973304 -211.121498) (xy 260.932168 -211.121498)
			(xy 260.931665 -211.131655) (xy 260.923892 -211.150423) (xy 260.90953 -211.164788) (xy 260.890763 -211.172564)
			(xy 260.880606 -211.17306) (xy 259.481066 -211.17306) (xy 259.470906 -211.172594) (xy 259.452135 -211.164808)
			(xy 259.437771 -211.150434) (xy 259.429998 -211.131659) (xy 259.429504 -211.121498) (xy 216.4715 -211.121498)
			(xy 216.470966 -211.131651) (xy 216.463199 -211.150413) (xy 216.448846 -211.164777) (xy 216.430091 -211.172558)
			(xy 216.419938 -211.17306) (xy 215.020398 -211.17306) (xy 215.01024 -211.172568) (xy 214.99147 -211.164793)
			(xy 214.977105 -211.150426) (xy 214.969331 -211.131656) (xy 214.968836 -211.121498) (xy 208.9277 -211.121498)
			(xy 208.927166 -211.131651) (xy 208.919399 -211.150413) (xy 208.905046 -211.164777) (xy 208.886291 -211.172558)
			(xy 208.876138 -211.17306) (xy 207.476598 -211.17306) (xy 207.46644 -211.172568) (xy 207.44767 -211.164793)
			(xy 207.433305 -211.150426) (xy 207.425531 -211.131656) (xy 207.425036 -211.121498) (xy 201.3839 -211.121498)
			(xy 201.383366 -211.131651) (xy 201.375599 -211.150413) (xy 201.361246 -211.164777) (xy 201.342491 -211.172558)
			(xy 201.332338 -211.17306) (xy 199.932798 -211.17306) (xy 199.92264 -211.172568) (xy 199.90387 -211.164793)
			(xy 199.889505 -211.150426) (xy 199.881731 -211.131656) (xy 199.881236 -211.121498) (xy 193.8401 -211.121498)
			(xy 193.839566 -211.131651) (xy 193.831799 -211.150413) (xy 193.817446 -211.164777) (xy 193.798691 -211.172558)
			(xy 193.788538 -211.17306) (xy 192.388998 -211.17306) (xy 192.37884 -211.172568) (xy 192.36007 -211.164793)
			(xy 192.345705 -211.150426) (xy 192.337931 -211.131656) (xy 192.337436 -211.121498) (xy 186.2963 -211.121498)
			(xy 186.295766 -211.131651) (xy 186.287999 -211.150413) (xy 186.273646 -211.164777) (xy 186.254891 -211.172558)
			(xy 186.244738 -211.17306) (xy 184.845198 -211.17306) (xy 184.83504 -211.172568) (xy 184.81627 -211.164793)
			(xy 184.801905 -211.150426) (xy 184.794131 -211.131656) (xy 184.793636 -211.121498) (xy 178.7525 -211.121498)
			(xy 178.751966 -211.131651) (xy 178.744199 -211.150413) (xy 178.729846 -211.164777) (xy 178.711091 -211.172558)
			(xy 178.700938 -211.17306) (xy 177.301398 -211.17306) (xy 177.29124 -211.172568) (xy 177.27247 -211.164793)
			(xy 177.258105 -211.150426) (xy 177.250331 -211.131656) (xy 177.249836 -211.121498) (xy 171.2087 -211.121498)
			(xy 171.208166 -211.131651) (xy 171.200399 -211.150413) (xy 171.186046 -211.164777) (xy 171.167291 -211.172558)
			(xy 171.157138 -211.17306) (xy 169.757598 -211.17306) (xy 169.74744 -211.172568) (xy 169.72867 -211.164793)
			(xy 169.714305 -211.150426) (xy 169.706531 -211.131656) (xy 169.706036 -211.121498) (xy 163.6649 -211.121498)
			(xy 163.664366 -211.131651) (xy 163.656599 -211.150413) (xy 163.642246 -211.164777) (xy 163.623491 -211.172558)
			(xy 163.613338 -211.17306) (xy 162.213798 -211.17306) (xy 162.20364 -211.172568) (xy 162.18487 -211.164793)
			(xy 162.170505 -211.150426) (xy 162.162731 -211.131656) (xy 162.162236 -211.121498) (xy 65.7987 -211.121498)
			(xy 65.798166 -211.131651) (xy 65.790399 -211.150413) (xy 65.776046 -211.164777) (xy 65.757291 -211.172558)
			(xy 65.747138 -211.17306) (xy 64.347598 -211.17306) (xy 64.33744 -211.172568) (xy 64.31867 -211.164793)
			(xy 64.304305 -211.150426) (xy 64.296531 -211.131656) (xy 64.296036 -211.121498) (xy 58.2549 -211.121498)
			(xy 58.254366 -211.131651) (xy 58.246599 -211.150413) (xy 58.232246 -211.164777) (xy 58.213491 -211.172558)
			(xy 58.203338 -211.17306) (xy 56.803798 -211.17306) (xy 56.79364 -211.172568) (xy 56.77487 -211.164793)
			(xy 56.760505 -211.150426) (xy 56.752731 -211.131656) (xy 56.752236 -211.121498) (xy 50.7111 -211.121498)
			(xy 50.710566 -211.131651) (xy 50.702799 -211.150413) (xy 50.688446 -211.164777) (xy 50.669691 -211.172558)
			(xy 50.659538 -211.17306) (xy 49.259998 -211.17306) (xy 49.24984 -211.172568) (xy 49.23107 -211.164793)
			(xy 49.216705 -211.150426) (xy 49.208931 -211.131656) (xy 49.208436 -211.121498) (xy 43.1673 -211.121498)
			(xy 43.166766 -211.131651) (xy 43.158999 -211.150413) (xy 43.144646 -211.164777) (xy 43.125891 -211.172558)
			(xy 43.115738 -211.17306) (xy 41.716198 -211.17306) (xy 41.70604 -211.172568) (xy 41.68727 -211.164793)
			(xy 41.672905 -211.150426) (xy 41.665131 -211.131656) (xy 41.664636 -211.121498) (xy 35.6235 -211.121498)
			(xy 35.622966 -211.131651) (xy 35.615199 -211.150413) (xy 35.600846 -211.164777) (xy 35.582091 -211.172558)
			(xy 35.571938 -211.17306) (xy 34.172398 -211.17306) (xy 34.16224 -211.172568) (xy 34.14347 -211.164793)
			(xy 34.129105 -211.150426) (xy 34.121331 -211.131656) (xy 34.120836 -211.121498) (xy 28.0797 -211.121498)
			(xy 28.079166 -211.131651) (xy 28.071399 -211.150413) (xy 28.057046 -211.164777) (xy 28.038291 -211.172558)
			(xy 28.028138 -211.17306) (xy 26.628598 -211.17306) (xy 26.61844 -211.172568) (xy 26.59967 -211.164793)
			(xy 26.585305 -211.150426) (xy 26.577531 -211.131656) (xy 26.577036 -211.121498) (xy 20.5359 -211.121498)
			(xy 20.535366 -211.131651) (xy 20.527599 -211.150413) (xy 20.513246 -211.164777) (xy 20.494491 -211.172558)
			(xy 20.484338 -211.17306) (xy 19.084798 -211.17306) (xy 19.07464 -211.172568) (xy 19.05587 -211.164793)
			(xy 19.041505 -211.150426) (xy 19.033731 -211.131656) (xy 19.033236 -211.121498) (xy 12.9921 -211.121498)
			(xy 12.991566 -211.131651) (xy 12.983799 -211.150413) (xy 12.969446 -211.164777) (xy 12.950691 -211.172558)
			(xy 12.940538 -211.17306) (xy 11.540998 -211.17306) (xy 11.53084 -211.172568) (xy 11.51207 -211.164793)
			(xy 11.497705 -211.150426) (xy 11.489931 -211.131656) (xy 11.489436 -211.121498) (xy 2.509012 -211.121498)
			(xy 2.509012 -211.971382) (xy 7.389368 -211.971382) (xy 7.389368 -211.562442) (xy 7.389799 -211.552269)
			(xy 7.397576 -211.53347) (xy 7.41196 -211.519082) (xy 7.430757 -211.511301) (xy 7.44093 -211.51088)
			(xy 8.84047 -211.51088) (xy 8.850645 -211.51129) (xy 8.869447 -211.519072) (xy 8.883834 -211.533463)
			(xy 8.891613 -211.552267) (xy 8.892032 -211.562442) (xy 8.892032 -211.971382) (xy 14.933168 -211.971382)
			(xy 14.933168 -211.562442) (xy 14.933599 -211.552269) (xy 14.941376 -211.53347) (xy 14.95576 -211.519082)
			(xy 14.974557 -211.511301) (xy 14.98473 -211.51088) (xy 16.38427 -211.51088) (xy 16.394445 -211.51129)
			(xy 16.413247 -211.519072) (xy 16.427634 -211.533463) (xy 16.435413 -211.552267) (xy 16.435832 -211.562442)
			(xy 16.435832 -211.971382) (xy 22.476968 -211.971382) (xy 22.476968 -211.562442) (xy 22.477399 -211.552269)
			(xy 22.485176 -211.53347) (xy 22.49956 -211.519082) (xy 22.518357 -211.511301) (xy 22.52853 -211.51088)
			(xy 23.92807 -211.51088) (xy 23.938245 -211.51129) (xy 23.957047 -211.519072) (xy 23.971434 -211.533463)
			(xy 23.979213 -211.552267) (xy 23.979632 -211.562442) (xy 23.979632 -211.971382) (xy 30.020768 -211.971382)
			(xy 30.020768 -211.562442) (xy 30.021199 -211.552269) (xy 30.028976 -211.53347) (xy 30.04336 -211.519082)
			(xy 30.062157 -211.511301) (xy 30.07233 -211.51088) (xy 31.47187 -211.51088) (xy 31.482045 -211.51129)
			(xy 31.500847 -211.519072) (xy 31.515234 -211.533463) (xy 31.523013 -211.552267) (xy 31.523432 -211.562442)
			(xy 31.523432 -211.971382) (xy 37.564568 -211.971382) (xy 37.564568 -211.562442) (xy 37.564999 -211.552269)
			(xy 37.572776 -211.53347) (xy 37.58716 -211.519082) (xy 37.605957 -211.511301) (xy 37.61613 -211.51088)
			(xy 39.01567 -211.51088) (xy 39.025845 -211.51129) (xy 39.044647 -211.519072) (xy 39.059034 -211.533463)
			(xy 39.066813 -211.552267) (xy 39.067232 -211.562442) (xy 39.067232 -211.971382) (xy 45.108368 -211.971382)
			(xy 45.108368 -211.562442) (xy 45.108799 -211.552269) (xy 45.116576 -211.53347) (xy 45.13096 -211.519082)
			(xy 45.149757 -211.511301) (xy 45.15993 -211.51088) (xy 46.55947 -211.51088) (xy 46.569645 -211.51129)
			(xy 46.588447 -211.519072) (xy 46.602834 -211.533463) (xy 46.610613 -211.552267) (xy 46.611032 -211.562442)
			(xy 46.611032 -211.971382) (xy 52.652168 -211.971382) (xy 52.652168 -211.562442) (xy 52.652599 -211.552269)
			(xy 52.660376 -211.53347) (xy 52.67476 -211.519082) (xy 52.693557 -211.511301) (xy 52.70373 -211.51088)
			(xy 54.10327 -211.51088) (xy 54.113445 -211.51129) (xy 54.132247 -211.519072) (xy 54.146634 -211.533463)
			(xy 54.154413 -211.552267) (xy 54.154832 -211.562442) (xy 54.154832 -211.971382) (xy 60.195968 -211.971382)
			(xy 60.195968 -211.562442) (xy 60.196399 -211.552269) (xy 60.204176 -211.53347) (xy 60.21856 -211.519082)
			(xy 60.237357 -211.511301) (xy 60.24753 -211.51088) (xy 61.64707 -211.51088) (xy 61.657245 -211.51129)
			(xy 61.676047 -211.519072) (xy 61.690434 -211.533463) (xy 61.698213 -211.552267) (xy 61.698632 -211.562442)
			(xy 61.698632 -211.971382) (xy 158.062168 -211.971382) (xy 158.062168 -211.562442) (xy 158.062599 -211.552269)
			(xy 158.070376 -211.53347) (xy 158.08476 -211.519082) (xy 158.103557 -211.511301) (xy 158.11373 -211.51088)
			(xy 159.51327 -211.51088) (xy 159.523445 -211.51129) (xy 159.542247 -211.519072) (xy 159.556634 -211.533463)
			(xy 159.564413 -211.552267) (xy 159.564832 -211.562442) (xy 159.564832 -211.971382) (xy 165.605968 -211.971382)
			(xy 165.605968 -211.562442) (xy 165.606399 -211.552269) (xy 165.614176 -211.53347) (xy 165.62856 -211.519082)
			(xy 165.647357 -211.511301) (xy 165.65753 -211.51088) (xy 167.05707 -211.51088) (xy 167.067245 -211.51129)
			(xy 167.086047 -211.519072) (xy 167.100434 -211.533463) (xy 167.108213 -211.552267) (xy 167.108632 -211.562442)
			(xy 167.108632 -211.971382) (xy 173.149768 -211.971382) (xy 173.149768 -211.562442) (xy 173.150199 -211.552269)
			(xy 173.157976 -211.53347) (xy 173.17236 -211.519082) (xy 173.191157 -211.511301) (xy 173.20133 -211.51088)
			(xy 174.60087 -211.51088) (xy 174.611045 -211.51129) (xy 174.629847 -211.519072) (xy 174.644234 -211.533463)
			(xy 174.652013 -211.552267) (xy 174.652432 -211.562442) (xy 174.652432 -211.971382) (xy 180.693568 -211.971382)
			(xy 180.693568 -211.562442) (xy 180.693999 -211.552269) (xy 180.701776 -211.53347) (xy 180.71616 -211.519082)
			(xy 180.734957 -211.511301) (xy 180.74513 -211.51088) (xy 182.14467 -211.51088) (xy 182.154845 -211.51129)
			(xy 182.173647 -211.519072) (xy 182.188034 -211.533463) (xy 182.195813 -211.552267) (xy 182.196232 -211.562442)
			(xy 182.196232 -211.971382) (xy 188.237368 -211.971382) (xy 188.237368 -211.562442) (xy 188.237799 -211.552269)
			(xy 188.245576 -211.53347) (xy 188.25996 -211.519082) (xy 188.278757 -211.511301) (xy 188.28893 -211.51088)
			(xy 189.68847 -211.51088) (xy 189.698645 -211.51129) (xy 189.717447 -211.519072) (xy 189.731834 -211.533463)
			(xy 189.739613 -211.552267) (xy 189.740032 -211.562442) (xy 189.740032 -211.971382) (xy 195.781168 -211.971382)
			(xy 195.781168 -211.562442) (xy 195.781599 -211.552269) (xy 195.789376 -211.53347) (xy 195.80376 -211.519082)
			(xy 195.822557 -211.511301) (xy 195.83273 -211.51088) (xy 197.23227 -211.51088) (xy 197.242445 -211.51129)
			(xy 197.261247 -211.519072) (xy 197.275634 -211.533463) (xy 197.283413 -211.552267) (xy 197.283832 -211.562442)
			(xy 197.283832 -211.971382) (xy 203.324968 -211.971382) (xy 203.324968 -211.562442) (xy 203.325399 -211.552269)
			(xy 203.333176 -211.53347) (xy 203.34756 -211.519082) (xy 203.366357 -211.511301) (xy 203.37653 -211.51088)
			(xy 204.77607 -211.51088) (xy 204.786245 -211.51129) (xy 204.805047 -211.519072) (xy 204.819434 -211.533463)
			(xy 204.827213 -211.552267) (xy 204.827632 -211.562442) (xy 204.827632 -211.971382) (xy 210.868768 -211.971382)
			(xy 210.868768 -211.562442) (xy 210.869199 -211.552269) (xy 210.876976 -211.53347) (xy 210.89136 -211.519082)
			(xy 210.910157 -211.511301) (xy 210.92033 -211.51088) (xy 212.31987 -211.51088) (xy 212.330045 -211.51129)
			(xy 212.348847 -211.519072) (xy 212.363234 -211.533463) (xy 212.371013 -211.552267) (xy 212.371432 -211.562442)
			(xy 212.371432 -211.971382) (xy 255.329436 -211.971382) (xy 255.329436 -211.562442) (xy 255.329898 -211.552273)
			(xy 255.337669 -211.53348) (xy 255.352043 -211.519094) (xy 255.37083 -211.511307) (xy 255.380998 -211.51088)
			(xy 256.780538 -211.51088) (xy 256.790717 -211.511234) (xy 256.809521 -211.519039) (xy 256.823906 -211.533446)
			(xy 256.831682 -211.552262) (xy 256.8321 -211.562442) (xy 256.8321 -211.971382) (xy 262.873236 -211.971382)
			(xy 262.873236 -211.562442) (xy 262.873698 -211.552273) (xy 262.881469 -211.53348) (xy 262.895843 -211.519094)
			(xy 262.91463 -211.511307) (xy 262.924798 -211.51088) (xy 264.324338 -211.51088) (xy 264.334517 -211.511234)
			(xy 264.353321 -211.519039) (xy 264.367706 -211.533446) (xy 264.375482 -211.552262) (xy 264.3759 -211.562442)
			(xy 264.3759 -211.971382) (xy 270.417036 -211.971382) (xy 270.417036 -211.562442) (xy 270.417498 -211.552273)
			(xy 270.425269 -211.53348) (xy 270.439643 -211.519094) (xy 270.45843 -211.511307) (xy 270.468598 -211.51088)
			(xy 271.868138 -211.51088) (xy 271.878317 -211.511234) (xy 271.897121 -211.519039) (xy 271.911506 -211.533446)
			(xy 271.919282 -211.552262) (xy 271.9197 -211.562442) (xy 271.9197 -211.971382) (xy 277.960836 -211.971382)
			(xy 277.960836 -211.562442) (xy 277.961298 -211.552273) (xy 277.969069 -211.53348) (xy 277.983443 -211.519094)
			(xy 278.00223 -211.511307) (xy 278.012398 -211.51088) (xy 279.411938 -211.51088) (xy 279.422117 -211.511234)
			(xy 279.440921 -211.519039) (xy 279.455306 -211.533446) (xy 279.463082 -211.552262) (xy 279.4635 -211.562442)
			(xy 279.4635 -211.971382) (xy 285.504636 -211.971382) (xy 285.504636 -211.562442) (xy 285.505098 -211.552273)
			(xy 285.512869 -211.53348) (xy 285.527243 -211.519094) (xy 285.54603 -211.511307) (xy 285.556198 -211.51088)
			(xy 286.955738 -211.51088) (xy 286.965917 -211.511234) (xy 286.984721 -211.519039) (xy 286.999106 -211.533446)
			(xy 287.006882 -211.552262) (xy 287.0073 -211.562442) (xy 287.0073 -211.971382) (xy 293.048436 -211.971382)
			(xy 293.048436 -211.562442) (xy 293.048898 -211.552273) (xy 293.056669 -211.53348) (xy 293.071043 -211.519094)
			(xy 293.08983 -211.511307) (xy 293.099998 -211.51088) (xy 294.499538 -211.51088) (xy 294.509717 -211.511234)
			(xy 294.528521 -211.519039) (xy 294.542906 -211.533446) (xy 294.550682 -211.552262) (xy 294.5511 -211.562442)
			(xy 294.5511 -211.971382) (xy 300.592236 -211.971382) (xy 300.592236 -211.562442) (xy 300.592698 -211.552273)
			(xy 300.600469 -211.53348) (xy 300.614843 -211.519094) (xy 300.63363 -211.511307) (xy 300.643798 -211.51088)
			(xy 302.043338 -211.51088) (xy 302.053517 -211.511234) (xy 302.072321 -211.519039) (xy 302.086706 -211.533446)
			(xy 302.094482 -211.552262) (xy 302.0949 -211.562442) (xy 302.0949 -211.971382) (xy 308.136036 -211.971382)
			(xy 308.136036 -211.562442) (xy 308.136498 -211.552273) (xy 308.144269 -211.53348) (xy 308.158643 -211.519094)
			(xy 308.17743 -211.511307) (xy 308.187598 -211.51088) (xy 309.587138 -211.51088) (xy 309.597317 -211.511234)
			(xy 309.616121 -211.519039) (xy 309.630506 -211.533446) (xy 309.638282 -211.552262) (xy 309.6387 -211.562442)
			(xy 309.6387 -211.971382) (xy 406.002236 -211.971382) (xy 406.002236 -211.562442) (xy 406.002698 -211.552273)
			(xy 406.010469 -211.53348) (xy 406.024843 -211.519094) (xy 406.04363 -211.511307) (xy 406.053798 -211.51088)
			(xy 407.453338 -211.51088) (xy 407.463517 -211.511234) (xy 407.482321 -211.519039) (xy 407.496706 -211.533446)
			(xy 407.504482 -211.552262) (xy 407.5049 -211.562442) (xy 407.5049 -211.971382) (xy 413.546036 -211.971382)
			(xy 413.546036 -211.562442) (xy 413.546498 -211.552273) (xy 413.554269 -211.53348) (xy 413.568643 -211.519094)
			(xy 413.58743 -211.511307) (xy 413.597598 -211.51088) (xy 414.997138 -211.51088) (xy 415.007317 -211.511234)
			(xy 415.026121 -211.519039) (xy 415.040506 -211.533446) (xy 415.048282 -211.552262) (xy 415.0487 -211.562442)
			(xy 415.0487 -211.971382) (xy 421.089836 -211.971382) (xy 421.089836 -211.562442) (xy 421.090298 -211.552273)
			(xy 421.098069 -211.53348) (xy 421.112443 -211.519094) (xy 421.13123 -211.511307) (xy 421.141398 -211.51088)
			(xy 422.540938 -211.51088) (xy 422.551117 -211.511234) (xy 422.569921 -211.519039) (xy 422.584306 -211.533446)
			(xy 422.592082 -211.552262) (xy 422.5925 -211.562442) (xy 422.5925 -211.971382) (xy 428.633636 -211.971382)
			(xy 428.633636 -211.562442) (xy 428.634098 -211.552273) (xy 428.641869 -211.53348) (xy 428.656243 -211.519094)
			(xy 428.67503 -211.511307) (xy 428.685198 -211.51088) (xy 430.084738 -211.51088) (xy 430.094917 -211.511234)
			(xy 430.113721 -211.519039) (xy 430.128106 -211.533446) (xy 430.135882 -211.552262) (xy 430.1363 -211.562442)
			(xy 430.1363 -211.971382) (xy 436.177436 -211.971382) (xy 436.177436 -211.562442) (xy 436.177898 -211.552273)
			(xy 436.185669 -211.53348) (xy 436.200043 -211.519094) (xy 436.21883 -211.511307) (xy 436.228998 -211.51088)
			(xy 437.628538 -211.51088) (xy 437.638717 -211.511234) (xy 437.657521 -211.519039) (xy 437.671906 -211.533446)
			(xy 437.679682 -211.552262) (xy 437.6801 -211.562442) (xy 437.6801 -211.971382) (xy 443.721236 -211.971382)
			(xy 443.721236 -211.562442) (xy 443.721698 -211.552273) (xy 443.729469 -211.53348) (xy 443.743843 -211.519094)
			(xy 443.76263 -211.511307) (xy 443.772798 -211.51088) (xy 445.172338 -211.51088) (xy 445.182517 -211.511234)
			(xy 445.201321 -211.519039) (xy 445.215706 -211.533446) (xy 445.223482 -211.552262) (xy 445.2239 -211.562442)
			(xy 445.2239 -211.971382) (xy 451.265036 -211.971382) (xy 451.265036 -211.562442) (xy 451.265498 -211.552273)
			(xy 451.273269 -211.53348) (xy 451.287643 -211.519094) (xy 451.30643 -211.511307) (xy 451.316598 -211.51088)
			(xy 452.716138 -211.51088) (xy 452.726317 -211.511234) (xy 452.745121 -211.519039) (xy 452.759506 -211.533446)
			(xy 452.767282 -211.552262) (xy 452.7677 -211.562442) (xy 452.7677 -211.971382) (xy 458.808836 -211.971382)
			(xy 458.808836 -211.562442) (xy 458.809298 -211.552273) (xy 458.817069 -211.53348) (xy 458.831443 -211.519094)
			(xy 458.85023 -211.511307) (xy 458.860398 -211.51088) (xy 460.259938 -211.51088) (xy 460.270117 -211.511234)
			(xy 460.288921 -211.519039) (xy 460.303306 -211.533446) (xy 460.311082 -211.552262) (xy 460.3115 -211.562442)
			(xy 460.3115 -211.971382) (xy 460.310953 -211.981534) (xy 460.303191 -212.000295) (xy 460.288842 -212.01466)
			(xy 460.270089 -212.022442) (xy 460.259938 -212.022944) (xy 458.860398 -212.022944) (xy 458.850224 -212.022537)
			(xy 458.831426 -212.014748) (xy 458.81704 -212.000357) (xy 458.809259 -211.981556) (xy 458.808836 -211.971382)
			(xy 452.7677 -211.971382) (xy 452.767153 -211.981534) (xy 452.759391 -212.000295) (xy 452.745042 -212.01466)
			(xy 452.726289 -212.022442) (xy 452.716138 -212.022944) (xy 451.316598 -212.022944) (xy 451.306424 -212.022537)
			(xy 451.287626 -212.014748) (xy 451.27324 -212.000357) (xy 451.265459 -211.981556) (xy 451.265036 -211.971382)
			(xy 445.2239 -211.971382) (xy 445.223353 -211.981534) (xy 445.215591 -212.000295) (xy 445.201242 -212.01466)
			(xy 445.182489 -212.022442) (xy 445.172338 -212.022944) (xy 443.772798 -212.022944) (xy 443.762624 -212.022537)
			(xy 443.743826 -212.014748) (xy 443.72944 -212.000357) (xy 443.721659 -211.981556) (xy 443.721236 -211.971382)
			(xy 437.6801 -211.971382) (xy 437.679553 -211.981534) (xy 437.671791 -212.000295) (xy 437.657442 -212.01466)
			(xy 437.638689 -212.022442) (xy 437.628538 -212.022944) (xy 436.228998 -212.022944) (xy 436.218824 -212.022537)
			(xy 436.200026 -212.014748) (xy 436.18564 -212.000357) (xy 436.177859 -211.981556) (xy 436.177436 -211.971382)
			(xy 430.1363 -211.971382) (xy 430.135753 -211.981534) (xy 430.127991 -212.000295) (xy 430.113642 -212.01466)
			(xy 430.094889 -212.022442) (xy 430.084738 -212.022944) (xy 428.685198 -212.022944) (xy 428.675024 -212.022537)
			(xy 428.656226 -212.014748) (xy 428.64184 -212.000357) (xy 428.634059 -211.981556) (xy 428.633636 -211.971382)
			(xy 422.5925 -211.971382) (xy 422.591953 -211.981534) (xy 422.584191 -212.000295) (xy 422.569842 -212.01466)
			(xy 422.551089 -212.022442) (xy 422.540938 -212.022944) (xy 421.141398 -212.022944) (xy 421.131224 -212.022537)
			(xy 421.112426 -212.014748) (xy 421.09804 -212.000357) (xy 421.090259 -211.981556) (xy 421.089836 -211.971382)
			(xy 415.0487 -211.971382) (xy 415.048153 -211.981534) (xy 415.040391 -212.000295) (xy 415.026042 -212.01466)
			(xy 415.007289 -212.022442) (xy 414.997138 -212.022944) (xy 413.597598 -212.022944) (xy 413.587424 -212.022537)
			(xy 413.568626 -212.014748) (xy 413.55424 -212.000357) (xy 413.546459 -211.981556) (xy 413.546036 -211.971382)
			(xy 407.5049 -211.971382) (xy 407.504353 -211.981534) (xy 407.496591 -212.000295) (xy 407.482242 -212.01466)
			(xy 407.463489 -212.022442) (xy 407.453338 -212.022944) (xy 406.053798 -212.022944) (xy 406.043624 -212.022537)
			(xy 406.024826 -212.014748) (xy 406.01044 -212.000357) (xy 406.002659 -211.981556) (xy 406.002236 -211.971382)
			(xy 309.6387 -211.971382) (xy 309.638153 -211.981534) (xy 309.630391 -212.000295) (xy 309.616042 -212.01466)
			(xy 309.597289 -212.022442) (xy 309.587138 -212.022944) (xy 308.187598 -212.022944) (xy 308.177424 -212.022537)
			(xy 308.158626 -212.014748) (xy 308.14424 -212.000357) (xy 308.136459 -211.981556) (xy 308.136036 -211.971382)
			(xy 302.0949 -211.971382) (xy 302.094353 -211.981534) (xy 302.086591 -212.000295) (xy 302.072242 -212.01466)
			(xy 302.053489 -212.022442) (xy 302.043338 -212.022944) (xy 300.643798 -212.022944) (xy 300.633624 -212.022537)
			(xy 300.614826 -212.014748) (xy 300.60044 -212.000357) (xy 300.592659 -211.981556) (xy 300.592236 -211.971382)
			(xy 294.5511 -211.971382) (xy 294.550553 -211.981534) (xy 294.542791 -212.000295) (xy 294.528442 -212.01466)
			(xy 294.509689 -212.022442) (xy 294.499538 -212.022944) (xy 293.099998 -212.022944) (xy 293.089824 -212.022537)
			(xy 293.071026 -212.014748) (xy 293.05664 -212.000357) (xy 293.048859 -211.981556) (xy 293.048436 -211.971382)
			(xy 287.0073 -211.971382) (xy 287.006753 -211.981534) (xy 286.998991 -212.000295) (xy 286.984642 -212.01466)
			(xy 286.965889 -212.022442) (xy 286.955738 -212.022944) (xy 285.556198 -212.022944) (xy 285.546024 -212.022537)
			(xy 285.527226 -212.014748) (xy 285.51284 -212.000357) (xy 285.505059 -211.981556) (xy 285.504636 -211.971382)
			(xy 279.4635 -211.971382) (xy 279.462953 -211.981534) (xy 279.455191 -212.000295) (xy 279.440842 -212.01466)
			(xy 279.422089 -212.022442) (xy 279.411938 -212.022944) (xy 278.012398 -212.022944) (xy 278.002224 -212.022537)
			(xy 277.983426 -212.014748) (xy 277.96904 -212.000357) (xy 277.961259 -211.981556) (xy 277.960836 -211.971382)
			(xy 271.9197 -211.971382) (xy 271.919153 -211.981534) (xy 271.911391 -212.000295) (xy 271.897042 -212.01466)
			(xy 271.878289 -212.022442) (xy 271.868138 -212.022944) (xy 270.468598 -212.022944) (xy 270.458424 -212.022537)
			(xy 270.439626 -212.014748) (xy 270.42524 -212.000357) (xy 270.417459 -211.981556) (xy 270.417036 -211.971382)
			(xy 264.3759 -211.971382) (xy 264.375353 -211.981534) (xy 264.367591 -212.000295) (xy 264.353242 -212.01466)
			(xy 264.334489 -212.022442) (xy 264.324338 -212.022944) (xy 262.924798 -212.022944) (xy 262.914624 -212.022537)
			(xy 262.895826 -212.014748) (xy 262.88144 -212.000357) (xy 262.873659 -211.981556) (xy 262.873236 -211.971382)
			(xy 256.8321 -211.971382) (xy 256.831553 -211.981534) (xy 256.823791 -212.000295) (xy 256.809442 -212.01466)
			(xy 256.790689 -212.022442) (xy 256.780538 -212.022944) (xy 255.380998 -212.022944) (xy 255.370824 -212.022537)
			(xy 255.352026 -212.014748) (xy 255.33764 -212.000357) (xy 255.329859 -211.981556) (xy 255.329436 -211.971382)
			(xy 212.371432 -211.971382) (xy 212.371021 -211.981556) (xy 212.363236 -212.000356) (xy 212.348846 -212.014743)
			(xy 212.330044 -212.022523) (xy 212.31987 -212.022944) (xy 210.92033 -212.022944) (xy 210.910158 -212.022511)
			(xy 210.891361 -212.014733) (xy 210.876974 -212.000349) (xy 210.869191 -211.981554) (xy 210.868768 -211.971382)
			(xy 204.827632 -211.971382) (xy 204.827221 -211.981556) (xy 204.819436 -212.000356) (xy 204.805046 -212.014743)
			(xy 204.786244 -212.022523) (xy 204.77607 -212.022944) (xy 203.37653 -212.022944) (xy 203.366358 -212.022511)
			(xy 203.347561 -212.014733) (xy 203.333174 -212.000349) (xy 203.325391 -211.981554) (xy 203.324968 -211.971382)
			(xy 197.283832 -211.971382) (xy 197.283421 -211.981556) (xy 197.275636 -212.000356) (xy 197.261246 -212.014743)
			(xy 197.242444 -212.022523) (xy 197.23227 -212.022944) (xy 195.83273 -212.022944) (xy 195.822558 -212.022511)
			(xy 195.803761 -212.014733) (xy 195.789374 -212.000349) (xy 195.781591 -211.981554) (xy 195.781168 -211.971382)
			(xy 189.740032 -211.971382) (xy 189.739621 -211.981556) (xy 189.731836 -212.000356) (xy 189.717446 -212.014743)
			(xy 189.698644 -212.022523) (xy 189.68847 -212.022944) (xy 188.28893 -212.022944) (xy 188.278758 -212.022511)
			(xy 188.259961 -212.014733) (xy 188.245574 -212.000349) (xy 188.237791 -211.981554) (xy 188.237368 -211.971382)
			(xy 182.196232 -211.971382) (xy 182.195821 -211.981556) (xy 182.188036 -212.000356) (xy 182.173646 -212.014743)
			(xy 182.154844 -212.022523) (xy 182.14467 -212.022944) (xy 180.74513 -212.022944) (xy 180.734958 -212.022511)
			(xy 180.716161 -212.014733) (xy 180.701774 -212.000349) (xy 180.693991 -211.981554) (xy 180.693568 -211.971382)
			(xy 174.652432 -211.971382) (xy 174.652021 -211.981556) (xy 174.644236 -212.000356) (xy 174.629846 -212.014743)
			(xy 174.611044 -212.022523) (xy 174.60087 -212.022944) (xy 173.20133 -212.022944) (xy 173.191158 -212.022511)
			(xy 173.172361 -212.014733) (xy 173.157974 -212.000349) (xy 173.150191 -211.981554) (xy 173.149768 -211.971382)
			(xy 167.108632 -211.971382) (xy 167.108221 -211.981556) (xy 167.100436 -212.000356) (xy 167.086046 -212.014743)
			(xy 167.067244 -212.022523) (xy 167.05707 -212.022944) (xy 165.65753 -212.022944) (xy 165.647358 -212.022511)
			(xy 165.628561 -212.014733) (xy 165.614174 -212.000349) (xy 165.606391 -211.981554) (xy 165.605968 -211.971382)
			(xy 159.564832 -211.971382) (xy 159.564421 -211.981556) (xy 159.556636 -212.000356) (xy 159.542246 -212.014743)
			(xy 159.523444 -212.022523) (xy 159.51327 -212.022944) (xy 158.11373 -212.022944) (xy 158.103558 -212.022511)
			(xy 158.084761 -212.014733) (xy 158.070374 -212.000349) (xy 158.062591 -211.981554) (xy 158.062168 -211.971382)
			(xy 61.698632 -211.971382) (xy 61.698221 -211.981556) (xy 61.690436 -212.000356) (xy 61.676046 -212.014743)
			(xy 61.657244 -212.022523) (xy 61.64707 -212.022944) (xy 60.24753 -212.022944) (xy 60.237358 -212.022511)
			(xy 60.218561 -212.014733) (xy 60.204174 -212.000349) (xy 60.196391 -211.981554) (xy 60.195968 -211.971382)
			(xy 54.154832 -211.971382) (xy 54.154421 -211.981556) (xy 54.146636 -212.000356) (xy 54.132246 -212.014743)
			(xy 54.113444 -212.022523) (xy 54.10327 -212.022944) (xy 52.70373 -212.022944) (xy 52.693558 -212.022511)
			(xy 52.674761 -212.014733) (xy 52.660374 -212.000349) (xy 52.652591 -211.981554) (xy 52.652168 -211.971382)
			(xy 46.611032 -211.971382) (xy 46.610621 -211.981556) (xy 46.602836 -212.000356) (xy 46.588446 -212.014743)
			(xy 46.569644 -212.022523) (xy 46.55947 -212.022944) (xy 45.15993 -212.022944) (xy 45.149758 -212.022511)
			(xy 45.130961 -212.014733) (xy 45.116574 -212.000349) (xy 45.108791 -211.981554) (xy 45.108368 -211.971382)
			(xy 39.067232 -211.971382) (xy 39.066821 -211.981556) (xy 39.059036 -212.000356) (xy 39.044646 -212.014743)
			(xy 39.025844 -212.022523) (xy 39.01567 -212.022944) (xy 37.61613 -212.022944) (xy 37.605958 -212.022511)
			(xy 37.587161 -212.014733) (xy 37.572774 -212.000349) (xy 37.564991 -211.981554) (xy 37.564568 -211.971382)
			(xy 31.523432 -211.971382) (xy 31.523021 -211.981556) (xy 31.515236 -212.000356) (xy 31.500846 -212.014743)
			(xy 31.482044 -212.022523) (xy 31.47187 -212.022944) (xy 30.07233 -212.022944) (xy 30.062158 -212.022511)
			(xy 30.043361 -212.014733) (xy 30.028974 -212.000349) (xy 30.021191 -211.981554) (xy 30.020768 -211.971382)
			(xy 23.979632 -211.971382) (xy 23.979221 -211.981556) (xy 23.971436 -212.000356) (xy 23.957046 -212.014743)
			(xy 23.938244 -212.022523) (xy 23.92807 -212.022944) (xy 22.52853 -212.022944) (xy 22.518358 -212.022511)
			(xy 22.499561 -212.014733) (xy 22.485174 -212.000349) (xy 22.477391 -211.981554) (xy 22.476968 -211.971382)
			(xy 16.435832 -211.971382) (xy 16.435421 -211.981556) (xy 16.427636 -212.000356) (xy 16.413246 -212.014743)
			(xy 16.394444 -212.022523) (xy 16.38427 -212.022944) (xy 14.98473 -212.022944) (xy 14.974558 -212.022511)
			(xy 14.955761 -212.014733) (xy 14.941374 -212.000349) (xy 14.933591 -211.981554) (xy 14.933168 -211.971382)
			(xy 8.892032 -211.971382) (xy 8.891621 -211.981556) (xy 8.883836 -212.000356) (xy 8.869446 -212.014743)
			(xy 8.850644 -212.022523) (xy 8.84047 -212.022944) (xy 7.44093 -212.022944) (xy 7.430758 -212.022511)
			(xy 7.411961 -212.014733) (xy 7.397574 -212.000349) (xy 7.389791 -211.981554) (xy 7.389368 -211.971382)
			(xy 2.509012 -211.971382) (xy 2.509012 -212.82152) (xy 11.489436 -212.82152) (xy 11.489436 -212.41258)
			(xy 11.489806 -212.40242) (xy 11.497615 -212.38366) (xy 11.512028 -212.369336) (xy 11.530836 -212.361644)
			(xy 11.540998 -212.361272) (xy 12.940538 -212.361272) (xy 12.950671 -212.361696) (xy 12.969399 -212.369443)
			(xy 12.983755 -212.383748) (xy 12.991567 -212.402449) (xy 12.9921 -212.41258) (xy 12.9921 -212.82152)
			(xy 19.033236 -212.82152) (xy 19.033236 -212.41258) (xy 19.033606 -212.40242) (xy 19.041415 -212.38366)
			(xy 19.055828 -212.369336) (xy 19.074636 -212.361644) (xy 19.084798 -212.361272) (xy 20.484338 -212.361272)
			(xy 20.494471 -212.361696) (xy 20.513199 -212.369443) (xy 20.527555 -212.383748) (xy 20.535367 -212.402449)
			(xy 20.5359 -212.41258) (xy 20.5359 -212.82152) (xy 26.577036 -212.82152) (xy 26.577036 -212.41258)
			(xy 26.577406 -212.40242) (xy 26.585215 -212.38366) (xy 26.599628 -212.369336) (xy 26.618436 -212.361644)
			(xy 26.628598 -212.361272) (xy 28.028138 -212.361272) (xy 28.038271 -212.361696) (xy 28.056999 -212.369443)
			(xy 28.071355 -212.383748) (xy 28.079167 -212.402449) (xy 28.0797 -212.41258) (xy 28.0797 -212.82152)
			(xy 34.120836 -212.82152) (xy 34.120836 -212.41258) (xy 34.121206 -212.40242) (xy 34.129015 -212.38366)
			(xy 34.143428 -212.369336) (xy 34.162236 -212.361644) (xy 34.172398 -212.361272) (xy 35.571938 -212.361272)
			(xy 35.582071 -212.361696) (xy 35.600799 -212.369443) (xy 35.615155 -212.383748) (xy 35.622967 -212.402449)
			(xy 35.6235 -212.41258) (xy 35.6235 -212.82152) (xy 41.664636 -212.82152) (xy 41.664636 -212.41258)
			(xy 41.665006 -212.40242) (xy 41.672815 -212.38366) (xy 41.687228 -212.369336) (xy 41.706036 -212.361644)
			(xy 41.716198 -212.361272) (xy 43.115738 -212.361272) (xy 43.125871 -212.361696) (xy 43.144599 -212.369443)
			(xy 43.158955 -212.383748) (xy 43.166767 -212.402449) (xy 43.1673 -212.41258) (xy 43.1673 -212.82152)
			(xy 49.208436 -212.82152) (xy 49.208436 -212.41258) (xy 49.208806 -212.40242) (xy 49.216615 -212.38366)
			(xy 49.231028 -212.369336) (xy 49.249836 -212.361644) (xy 49.259998 -212.361272) (xy 50.659538 -212.361272)
			(xy 50.669671 -212.361696) (xy 50.688399 -212.369443) (xy 50.702755 -212.383748) (xy 50.710567 -212.402449)
			(xy 50.7111 -212.41258) (xy 50.7111 -212.82152) (xy 56.752236 -212.82152) (xy 56.752236 -212.41258)
			(xy 56.752606 -212.40242) (xy 56.760415 -212.38366) (xy 56.774828 -212.369336) (xy 56.793636 -212.361644)
			(xy 56.803798 -212.361272) (xy 58.203338 -212.361272) (xy 58.213471 -212.361696) (xy 58.232199 -212.369443)
			(xy 58.246555 -212.383748) (xy 58.254367 -212.402449) (xy 58.2549 -212.41258) (xy 58.2549 -212.82152)
			(xy 64.296036 -212.82152) (xy 64.296036 -212.41258) (xy 64.296406 -212.40242) (xy 64.304215 -212.38366)
			(xy 64.318628 -212.369336) (xy 64.337436 -212.361644) (xy 64.347598 -212.361272) (xy 65.747138 -212.361272)
			(xy 65.757271 -212.361696) (xy 65.775999 -212.369443) (xy 65.790355 -212.383748) (xy 65.798167 -212.402449)
			(xy 65.7987 -212.41258) (xy 65.7987 -212.82152) (xy 162.162236 -212.82152) (xy 162.162236 -212.41258)
			(xy 162.162606 -212.40242) (xy 162.170415 -212.38366) (xy 162.184828 -212.369336) (xy 162.203636 -212.361644)
			(xy 162.213798 -212.361272) (xy 163.613338 -212.361272) (xy 163.623471 -212.361696) (xy 163.642199 -212.369443)
			(xy 163.656555 -212.383748) (xy 163.664367 -212.402449) (xy 163.6649 -212.41258) (xy 163.6649 -212.82152)
			(xy 169.706036 -212.82152) (xy 169.706036 -212.41258) (xy 169.706406 -212.40242) (xy 169.714215 -212.38366)
			(xy 169.728628 -212.369336) (xy 169.747436 -212.361644) (xy 169.757598 -212.361272) (xy 171.157138 -212.361272)
			(xy 171.167271 -212.361696) (xy 171.185999 -212.369443) (xy 171.200355 -212.383748) (xy 171.208167 -212.402449)
			(xy 171.2087 -212.41258) (xy 171.2087 -212.82152) (xy 177.249836 -212.82152) (xy 177.249836 -212.41258)
			(xy 177.250206 -212.40242) (xy 177.258015 -212.38366) (xy 177.272428 -212.369336) (xy 177.291236 -212.361644)
			(xy 177.301398 -212.361272) (xy 178.700938 -212.361272) (xy 178.711071 -212.361696) (xy 178.729799 -212.369443)
			(xy 178.744155 -212.383748) (xy 178.751967 -212.402449) (xy 178.7525 -212.41258) (xy 178.7525 -212.82152)
			(xy 184.793636 -212.82152) (xy 184.793636 -212.41258) (xy 184.794006 -212.40242) (xy 184.801815 -212.38366)
			(xy 184.816228 -212.369336) (xy 184.835036 -212.361644) (xy 184.845198 -212.361272) (xy 186.244738 -212.361272)
			(xy 186.254871 -212.361696) (xy 186.273599 -212.369443) (xy 186.287955 -212.383748) (xy 186.295767 -212.402449)
			(xy 186.2963 -212.41258) (xy 186.2963 -212.82152) (xy 192.337436 -212.82152) (xy 192.337436 -212.41258)
			(xy 192.337806 -212.40242) (xy 192.345615 -212.38366) (xy 192.360028 -212.369336) (xy 192.378836 -212.361644)
			(xy 192.388998 -212.361272) (xy 193.788538 -212.361272) (xy 193.798671 -212.361696) (xy 193.817399 -212.369443)
			(xy 193.831755 -212.383748) (xy 193.839567 -212.402449) (xy 193.8401 -212.41258) (xy 193.8401 -212.82152)
			(xy 199.881236 -212.82152) (xy 199.881236 -212.41258) (xy 199.881606 -212.40242) (xy 199.889415 -212.38366)
			(xy 199.903828 -212.369336) (xy 199.922636 -212.361644) (xy 199.932798 -212.361272) (xy 201.332338 -212.361272)
			(xy 201.342471 -212.361696) (xy 201.361199 -212.369443) (xy 201.375555 -212.383748) (xy 201.383367 -212.402449)
			(xy 201.3839 -212.41258) (xy 201.3839 -212.82152) (xy 207.425036 -212.82152) (xy 207.425036 -212.41258)
			(xy 207.425406 -212.40242) (xy 207.433215 -212.38366) (xy 207.447628 -212.369336) (xy 207.466436 -212.361644)
			(xy 207.476598 -212.361272) (xy 208.876138 -212.361272) (xy 208.886271 -212.361696) (xy 208.904999 -212.369443)
			(xy 208.919355 -212.383748) (xy 208.927167 -212.402449) (xy 208.9277 -212.41258) (xy 208.9277 -212.82152)
			(xy 214.968836 -212.82152) (xy 214.968836 -212.41258) (xy 214.969206 -212.40242) (xy 214.977015 -212.38366)
			(xy 214.991428 -212.369336) (xy 215.010236 -212.361644) (xy 215.020398 -212.361272) (xy 216.419938 -212.361272)
			(xy 216.430071 -212.361696) (xy 216.448799 -212.369443) (xy 216.463155 -212.383748) (xy 216.470967 -212.402449)
			(xy 216.4715 -212.41258) (xy 216.4715 -212.82152) (xy 259.429504 -212.82152) (xy 259.429504 -212.41258)
			(xy 259.429905 -212.402424) (xy 259.437708 -212.38367) (xy 259.452111 -212.369348) (xy 259.470908 -212.361649)
			(xy 259.481066 -212.361272) (xy 260.880606 -212.361272) (xy 260.890737 -212.361723) (xy 260.909464 -212.369458)
			(xy 260.923821 -212.383756) (xy 260.931635 -212.402451) (xy 260.932168 -212.41258) (xy 260.932168 -212.82152)
			(xy 266.973304 -212.82152) (xy 266.973304 -212.41258) (xy 266.973705 -212.402424) (xy 266.981508 -212.38367)
			(xy 266.995911 -212.369348) (xy 267.014708 -212.361649) (xy 267.024866 -212.361272) (xy 268.424406 -212.361272)
			(xy 268.434537 -212.361723) (xy 268.453264 -212.369458) (xy 268.467621 -212.383756) (xy 268.475435 -212.402451)
			(xy 268.475968 -212.41258) (xy 268.475968 -212.82152) (xy 274.517104 -212.82152) (xy 274.517104 -212.41258)
			(xy 274.517505 -212.402424) (xy 274.525308 -212.38367) (xy 274.539711 -212.369348) (xy 274.558508 -212.361649)
			(xy 274.568666 -212.361272) (xy 275.968206 -212.361272) (xy 275.978337 -212.361723) (xy 275.997064 -212.369458)
			(xy 276.011421 -212.383756) (xy 276.019235 -212.402451) (xy 276.019768 -212.41258) (xy 276.019768 -212.82152)
			(xy 282.060904 -212.82152) (xy 282.060904 -212.41258) (xy 282.061305 -212.402424) (xy 282.069108 -212.38367)
			(xy 282.083511 -212.369348) (xy 282.102308 -212.361649) (xy 282.112466 -212.361272) (xy 283.512006 -212.361272)
			(xy 283.522137 -212.361723) (xy 283.540864 -212.369458) (xy 283.555221 -212.383756) (xy 283.563035 -212.402451)
			(xy 283.563568 -212.41258) (xy 283.563568 -212.82152) (xy 289.604704 -212.82152) (xy 289.604704 -212.41258)
			(xy 289.605105 -212.402424) (xy 289.612908 -212.38367) (xy 289.627311 -212.369348) (xy 289.646108 -212.361649)
			(xy 289.656266 -212.361272) (xy 291.055806 -212.361272) (xy 291.065937 -212.361723) (xy 291.084664 -212.369458)
			(xy 291.099021 -212.383756) (xy 291.106835 -212.402451) (xy 291.107368 -212.41258) (xy 291.107368 -212.82152)
			(xy 297.148504 -212.82152) (xy 297.148504 -212.41258) (xy 297.148905 -212.402424) (xy 297.156708 -212.38367)
			(xy 297.171111 -212.369348) (xy 297.189908 -212.361649) (xy 297.200066 -212.361272) (xy 298.599606 -212.361272)
			(xy 298.609737 -212.361723) (xy 298.628464 -212.369458) (xy 298.642821 -212.383756) (xy 298.650635 -212.402451)
			(xy 298.651168 -212.41258) (xy 298.651168 -212.82152) (xy 304.692304 -212.82152) (xy 304.692304 -212.41258)
			(xy 304.692705 -212.402424) (xy 304.700508 -212.38367) (xy 304.714911 -212.369348) (xy 304.733708 -212.361649)
			(xy 304.743866 -212.361272) (xy 306.143406 -212.361272) (xy 306.153537 -212.361723) (xy 306.172264 -212.369458)
			(xy 306.186621 -212.383756) (xy 306.194435 -212.402451) (xy 306.194968 -212.41258) (xy 306.194968 -212.82152)
			(xy 312.236104 -212.82152) (xy 312.236104 -212.41258) (xy 312.236505 -212.402424) (xy 312.244308 -212.38367)
			(xy 312.258711 -212.369348) (xy 312.277508 -212.361649) (xy 312.287666 -212.361272) (xy 313.687206 -212.361272)
			(xy 313.697337 -212.361723) (xy 313.716064 -212.369458) (xy 313.730421 -212.383756) (xy 313.738235 -212.402451)
			(xy 313.738768 -212.41258) (xy 313.738768 -212.82152) (xy 410.102304 -212.82152) (xy 410.102304 -212.41258)
			(xy 410.102705 -212.402424) (xy 410.110508 -212.38367) (xy 410.124911 -212.369348) (xy 410.143708 -212.361649)
			(xy 410.153866 -212.361272) (xy 411.553406 -212.361272) (xy 411.563537 -212.361723) (xy 411.582264 -212.369458)
			(xy 411.596621 -212.383756) (xy 411.604435 -212.402451) (xy 411.604968 -212.41258) (xy 411.604968 -212.82152)
			(xy 417.646104 -212.82152) (xy 417.646104 -212.41258) (xy 417.646505 -212.402424) (xy 417.654308 -212.38367)
			(xy 417.668711 -212.369348) (xy 417.687508 -212.361649) (xy 417.697666 -212.361272) (xy 419.097206 -212.361272)
			(xy 419.107337 -212.361723) (xy 419.126064 -212.369458) (xy 419.140421 -212.383756) (xy 419.148235 -212.402451)
			(xy 419.148768 -212.41258) (xy 419.148768 -212.82152) (xy 425.189904 -212.82152) (xy 425.189904 -212.41258)
			(xy 425.190305 -212.402424) (xy 425.198108 -212.38367) (xy 425.212511 -212.369348) (xy 425.231308 -212.361649)
			(xy 425.241466 -212.361272) (xy 426.641006 -212.361272) (xy 426.651137 -212.361723) (xy 426.669864 -212.369458)
			(xy 426.684221 -212.383756) (xy 426.692035 -212.402451) (xy 426.692568 -212.41258) (xy 426.692568 -212.82152)
			(xy 432.733704 -212.82152) (xy 432.733704 -212.41258) (xy 432.734105 -212.402424) (xy 432.741908 -212.38367)
			(xy 432.756311 -212.369348) (xy 432.775108 -212.361649) (xy 432.785266 -212.361272) (xy 434.184806 -212.361272)
			(xy 434.194937 -212.361723) (xy 434.213664 -212.369458) (xy 434.228021 -212.383756) (xy 434.235835 -212.402451)
			(xy 434.236368 -212.41258) (xy 434.236368 -212.82152) (xy 440.277504 -212.82152) (xy 440.277504 -212.41258)
			(xy 440.277905 -212.402424) (xy 440.285708 -212.38367) (xy 440.300111 -212.369348) (xy 440.318908 -212.361649)
			(xy 440.329066 -212.361272) (xy 441.728606 -212.361272) (xy 441.738737 -212.361723) (xy 441.757464 -212.369458)
			(xy 441.771821 -212.383756) (xy 441.779635 -212.402451) (xy 441.780168 -212.41258) (xy 441.780168 -212.82152)
			(xy 447.821304 -212.82152) (xy 447.821304 -212.41258) (xy 447.821705 -212.402424) (xy 447.829508 -212.38367)
			(xy 447.843911 -212.369348) (xy 447.862708 -212.361649) (xy 447.872866 -212.361272) (xy 449.272406 -212.361272)
			(xy 449.282537 -212.361723) (xy 449.301264 -212.369458) (xy 449.315621 -212.383756) (xy 449.323435 -212.402451)
			(xy 449.323968 -212.41258) (xy 449.323968 -212.82152) (xy 455.365104 -212.82152) (xy 455.365104 -212.41258)
			(xy 455.365505 -212.402424) (xy 455.373308 -212.38367) (xy 455.387711 -212.369348) (xy 455.406508 -212.361649)
			(xy 455.416666 -212.361272) (xy 456.816206 -212.361272) (xy 456.826337 -212.361723) (xy 456.845064 -212.369458)
			(xy 456.859421 -212.383756) (xy 456.867235 -212.402451) (xy 456.867768 -212.41258) (xy 456.867768 -212.82152)
			(xy 462.908904 -212.82152) (xy 462.908904 -212.41258) (xy 462.909305 -212.402424) (xy 462.917108 -212.38367)
			(xy 462.931511 -212.369348) (xy 462.950308 -212.361649) (xy 462.960466 -212.361272) (xy 464.360006 -212.361272)
			(xy 464.370137 -212.361723) (xy 464.388864 -212.369458) (xy 464.403221 -212.383756) (xy 464.411035 -212.402451)
			(xy 464.411568 -212.41258) (xy 464.411568 -212.82152) (xy 464.411194 -212.831679) (xy 464.403386 -212.850439)
			(xy 464.388974 -212.864762) (xy 464.370168 -212.872456) (xy 464.360006 -212.872828) (xy 462.960466 -212.872828)
			(xy 462.950333 -212.8724) (xy 462.931605 -212.864656) (xy 462.917249 -212.850351) (xy 462.909437 -212.831651)
			(xy 462.908904 -212.82152) (xy 456.867768 -212.82152) (xy 456.867394 -212.831679) (xy 456.859586 -212.850439)
			(xy 456.845174 -212.864762) (xy 456.826368 -212.872456) (xy 456.816206 -212.872828) (xy 455.416666 -212.872828)
			(xy 455.406533 -212.8724) (xy 455.387805 -212.864656) (xy 455.373449 -212.850351) (xy 455.365637 -212.831651)
			(xy 455.365104 -212.82152) (xy 449.323968 -212.82152) (xy 449.323594 -212.831679) (xy 449.315786 -212.850439)
			(xy 449.301374 -212.864762) (xy 449.282568 -212.872456) (xy 449.272406 -212.872828) (xy 447.872866 -212.872828)
			(xy 447.862733 -212.8724) (xy 447.844005 -212.864656) (xy 447.829649 -212.850351) (xy 447.821837 -212.831651)
			(xy 447.821304 -212.82152) (xy 441.780168 -212.82152) (xy 441.779794 -212.831679) (xy 441.771986 -212.850439)
			(xy 441.757574 -212.864762) (xy 441.738768 -212.872456) (xy 441.728606 -212.872828) (xy 440.329066 -212.872828)
			(xy 440.318933 -212.8724) (xy 440.300205 -212.864656) (xy 440.285849 -212.850351) (xy 440.278037 -212.831651)
			(xy 440.277504 -212.82152) (xy 434.236368 -212.82152) (xy 434.235994 -212.831679) (xy 434.228186 -212.850439)
			(xy 434.213774 -212.864762) (xy 434.194968 -212.872456) (xy 434.184806 -212.872828) (xy 432.785266 -212.872828)
			(xy 432.775133 -212.8724) (xy 432.756405 -212.864656) (xy 432.742049 -212.850351) (xy 432.734237 -212.831651)
			(xy 432.733704 -212.82152) (xy 426.692568 -212.82152) (xy 426.692194 -212.831679) (xy 426.684386 -212.850439)
			(xy 426.669974 -212.864762) (xy 426.651168 -212.872456) (xy 426.641006 -212.872828) (xy 425.241466 -212.872828)
			(xy 425.231333 -212.8724) (xy 425.212605 -212.864656) (xy 425.198249 -212.850351) (xy 425.190437 -212.831651)
			(xy 425.189904 -212.82152) (xy 419.148768 -212.82152) (xy 419.148394 -212.831679) (xy 419.140586 -212.850439)
			(xy 419.126174 -212.864762) (xy 419.107368 -212.872456) (xy 419.097206 -212.872828) (xy 417.697666 -212.872828)
			(xy 417.687533 -212.8724) (xy 417.668805 -212.864656) (xy 417.654449 -212.850351) (xy 417.646637 -212.831651)
			(xy 417.646104 -212.82152) (xy 411.604968 -212.82152) (xy 411.604594 -212.831679) (xy 411.596786 -212.850439)
			(xy 411.582374 -212.864762) (xy 411.563568 -212.872456) (xy 411.553406 -212.872828) (xy 410.153866 -212.872828)
			(xy 410.143733 -212.8724) (xy 410.125005 -212.864656) (xy 410.110649 -212.850351) (xy 410.102837 -212.831651)
			(xy 410.102304 -212.82152) (xy 313.738768 -212.82152) (xy 313.738394 -212.831679) (xy 313.730586 -212.850439)
			(xy 313.716174 -212.864762) (xy 313.697368 -212.872456) (xy 313.687206 -212.872828) (xy 312.287666 -212.872828)
			(xy 312.277533 -212.8724) (xy 312.258805 -212.864656) (xy 312.244449 -212.850351) (xy 312.236637 -212.831651)
			(xy 312.236104 -212.82152) (xy 306.194968 -212.82152) (xy 306.194594 -212.831679) (xy 306.186786 -212.850439)
			(xy 306.172374 -212.864762) (xy 306.153568 -212.872456) (xy 306.143406 -212.872828) (xy 304.743866 -212.872828)
			(xy 304.733733 -212.8724) (xy 304.715005 -212.864656) (xy 304.700649 -212.850351) (xy 304.692837 -212.831651)
			(xy 304.692304 -212.82152) (xy 298.651168 -212.82152) (xy 298.650794 -212.831679) (xy 298.642986 -212.850439)
			(xy 298.628574 -212.864762) (xy 298.609768 -212.872456) (xy 298.599606 -212.872828) (xy 297.200066 -212.872828)
			(xy 297.189933 -212.8724) (xy 297.171205 -212.864656) (xy 297.156849 -212.850351) (xy 297.149037 -212.831651)
			(xy 297.148504 -212.82152) (xy 291.107368 -212.82152) (xy 291.106994 -212.831679) (xy 291.099186 -212.850439)
			(xy 291.084774 -212.864762) (xy 291.065968 -212.872456) (xy 291.055806 -212.872828) (xy 289.656266 -212.872828)
			(xy 289.646133 -212.8724) (xy 289.627405 -212.864656) (xy 289.613049 -212.850351) (xy 289.605237 -212.831651)
			(xy 289.604704 -212.82152) (xy 283.563568 -212.82152) (xy 283.563194 -212.831679) (xy 283.555386 -212.850439)
			(xy 283.540974 -212.864762) (xy 283.522168 -212.872456) (xy 283.512006 -212.872828) (xy 282.112466 -212.872828)
			(xy 282.102333 -212.8724) (xy 282.083605 -212.864656) (xy 282.069249 -212.850351) (xy 282.061437 -212.831651)
			(xy 282.060904 -212.82152) (xy 276.019768 -212.82152) (xy 276.019394 -212.831679) (xy 276.011586 -212.850439)
			(xy 275.997174 -212.864762) (xy 275.978368 -212.872456) (xy 275.968206 -212.872828) (xy 274.568666 -212.872828)
			(xy 274.558533 -212.8724) (xy 274.539805 -212.864656) (xy 274.525449 -212.850351) (xy 274.517637 -212.831651)
			(xy 274.517104 -212.82152) (xy 268.475968 -212.82152) (xy 268.475594 -212.831679) (xy 268.467786 -212.850439)
			(xy 268.453374 -212.864762) (xy 268.434568 -212.872456) (xy 268.424406 -212.872828) (xy 267.024866 -212.872828)
			(xy 267.014733 -212.8724) (xy 266.996005 -212.864656) (xy 266.981649 -212.850351) (xy 266.973837 -212.831651)
			(xy 266.973304 -212.82152) (xy 260.932168 -212.82152) (xy 260.931794 -212.831679) (xy 260.923986 -212.850439)
			(xy 260.909574 -212.864762) (xy 260.890768 -212.872456) (xy 260.880606 -212.872828) (xy 259.481066 -212.872828)
			(xy 259.470933 -212.8724) (xy 259.452205 -212.864656) (xy 259.437849 -212.850351) (xy 259.430037 -212.831651)
			(xy 259.429504 -212.82152) (xy 216.4715 -212.82152) (xy 216.471095 -212.831675) (xy 216.463293 -212.850428)
			(xy 216.448891 -212.864751) (xy 216.430096 -212.87245) (xy 216.419938 -212.872828) (xy 215.020398 -212.872828)
			(xy 215.010267 -212.872374) (xy 214.99154 -212.86464) (xy 214.977183 -212.850343) (xy 214.969369 -212.831649)
			(xy 214.968836 -212.82152) (xy 208.9277 -212.82152) (xy 208.927295 -212.831675) (xy 208.919493 -212.850428)
			(xy 208.905091 -212.864751) (xy 208.886296 -212.87245) (xy 208.876138 -212.872828) (xy 207.476598 -212.872828)
			(xy 207.466467 -212.872374) (xy 207.44774 -212.86464) (xy 207.433383 -212.850343) (xy 207.425569 -212.831649)
			(xy 207.425036 -212.82152) (xy 201.3839 -212.82152) (xy 201.383495 -212.831675) (xy 201.375693 -212.850428)
			(xy 201.361291 -212.864751) (xy 201.342496 -212.87245) (xy 201.332338 -212.872828) (xy 199.932798 -212.872828)
			(xy 199.922667 -212.872374) (xy 199.90394 -212.86464) (xy 199.889583 -212.850343) (xy 199.881769 -212.831649)
			(xy 199.881236 -212.82152) (xy 193.8401 -212.82152) (xy 193.839695 -212.831675) (xy 193.831893 -212.850428)
			(xy 193.817491 -212.864751) (xy 193.798696 -212.87245) (xy 193.788538 -212.872828) (xy 192.388998 -212.872828)
			(xy 192.378867 -212.872374) (xy 192.36014 -212.86464) (xy 192.345783 -212.850343) (xy 192.337969 -212.831649)
			(xy 192.337436 -212.82152) (xy 186.2963 -212.82152) (xy 186.295895 -212.831675) (xy 186.288093 -212.850428)
			(xy 186.273691 -212.864751) (xy 186.254896 -212.87245) (xy 186.244738 -212.872828) (xy 184.845198 -212.872828)
			(xy 184.835067 -212.872374) (xy 184.81634 -212.86464) (xy 184.801983 -212.850343) (xy 184.794169 -212.831649)
			(xy 184.793636 -212.82152) (xy 178.7525 -212.82152) (xy 178.752095 -212.831675) (xy 178.744293 -212.850428)
			(xy 178.729891 -212.864751) (xy 178.711096 -212.87245) (xy 178.700938 -212.872828) (xy 177.301398 -212.872828)
			(xy 177.291267 -212.872374) (xy 177.27254 -212.86464) (xy 177.258183 -212.850343) (xy 177.250369 -212.831649)
			(xy 177.249836 -212.82152) (xy 171.2087 -212.82152) (xy 171.208295 -212.831675) (xy 171.200493 -212.850428)
			(xy 171.186091 -212.864751) (xy 171.167296 -212.87245) (xy 171.157138 -212.872828) (xy 169.757598 -212.872828)
			(xy 169.747467 -212.872374) (xy 169.72874 -212.86464) (xy 169.714383 -212.850343) (xy 169.706569 -212.831649)
			(xy 169.706036 -212.82152) (xy 163.6649 -212.82152) (xy 163.664495 -212.831675) (xy 163.656693 -212.850428)
			(xy 163.642291 -212.864751) (xy 163.623496 -212.87245) (xy 163.613338 -212.872828) (xy 162.213798 -212.872828)
			(xy 162.203667 -212.872374) (xy 162.18494 -212.86464) (xy 162.170583 -212.850343) (xy 162.162769 -212.831649)
			(xy 162.162236 -212.82152) (xy 65.7987 -212.82152) (xy 65.798295 -212.831675) (xy 65.790493 -212.850428)
			(xy 65.776091 -212.864751) (xy 65.757296 -212.87245) (xy 65.747138 -212.872828) (xy 64.347598 -212.872828)
			(xy 64.337467 -212.872374) (xy 64.31874 -212.86464) (xy 64.304383 -212.850343) (xy 64.296569 -212.831649)
			(xy 64.296036 -212.82152) (xy 58.2549 -212.82152) (xy 58.254495 -212.831675) (xy 58.246693 -212.850428)
			(xy 58.232291 -212.864751) (xy 58.213496 -212.87245) (xy 58.203338 -212.872828) (xy 56.803798 -212.872828)
			(xy 56.793667 -212.872374) (xy 56.77494 -212.86464) (xy 56.760583 -212.850343) (xy 56.752769 -212.831649)
			(xy 56.752236 -212.82152) (xy 50.7111 -212.82152) (xy 50.710695 -212.831675) (xy 50.702893 -212.850428)
			(xy 50.688491 -212.864751) (xy 50.669696 -212.87245) (xy 50.659538 -212.872828) (xy 49.259998 -212.872828)
			(xy 49.249867 -212.872374) (xy 49.23114 -212.86464) (xy 49.216783 -212.850343) (xy 49.208969 -212.831649)
			(xy 49.208436 -212.82152) (xy 43.1673 -212.82152) (xy 43.166895 -212.831675) (xy 43.159093 -212.850428)
			(xy 43.144691 -212.864751) (xy 43.125896 -212.87245) (xy 43.115738 -212.872828) (xy 41.716198 -212.872828)
			(xy 41.706067 -212.872374) (xy 41.68734 -212.86464) (xy 41.672983 -212.850343) (xy 41.665169 -212.831649)
			(xy 41.664636 -212.82152) (xy 35.6235 -212.82152) (xy 35.623095 -212.831675) (xy 35.615293 -212.850428)
			(xy 35.600891 -212.864751) (xy 35.582096 -212.87245) (xy 35.571938 -212.872828) (xy 34.172398 -212.872828)
			(xy 34.162267 -212.872374) (xy 34.14354 -212.86464) (xy 34.129183 -212.850343) (xy 34.121369 -212.831649)
			(xy 34.120836 -212.82152) (xy 28.0797 -212.82152) (xy 28.079295 -212.831675) (xy 28.071493 -212.850428)
			(xy 28.057091 -212.864751) (xy 28.038296 -212.87245) (xy 28.028138 -212.872828) (xy 26.628598 -212.872828)
			(xy 26.618467 -212.872374) (xy 26.59974 -212.86464) (xy 26.585383 -212.850343) (xy 26.577569 -212.831649)
			(xy 26.577036 -212.82152) (xy 20.5359 -212.82152) (xy 20.535495 -212.831675) (xy 20.527693 -212.850428)
			(xy 20.513291 -212.864751) (xy 20.494496 -212.87245) (xy 20.484338 -212.872828) (xy 19.084798 -212.872828)
			(xy 19.074667 -212.872374) (xy 19.05594 -212.86464) (xy 19.041583 -212.850343) (xy 19.033769 -212.831649)
			(xy 19.033236 -212.82152) (xy 12.9921 -212.82152) (xy 12.991695 -212.831675) (xy 12.983893 -212.850428)
			(xy 12.969491 -212.864751) (xy 12.950696 -212.87245) (xy 12.940538 -212.872828) (xy 11.540998 -212.872828)
			(xy 11.530867 -212.872374) (xy 11.51214 -212.86464) (xy 11.497783 -212.850343) (xy 11.489969 -212.831649)
			(xy 11.489436 -212.82152) (xy 2.509012 -212.82152) (xy 2.509012 -213.671404) (xy 7.389368 -213.671404)
			(xy 7.389368 -213.262464) (xy 7.389791 -213.252312) (xy 7.397593 -213.233565) (xy 7.411988 -213.219244)
			(xy 7.430775 -213.211539) (xy 7.44093 -213.211156) (xy 8.84047 -213.211156) (xy 8.850597 -213.211651)
			(xy 8.86932 -213.219372) (xy 8.883678 -213.233656) (xy 8.891496 -213.25234) (xy 8.892032 -213.262464)
			(xy 8.892032 -213.671404) (xy 14.933168 -213.671404) (xy 14.933168 -213.262464) (xy 14.933591 -213.252312)
			(xy 14.941393 -213.233565) (xy 14.955788 -213.219244) (xy 14.974575 -213.211539) (xy 14.98473 -213.211156)
			(xy 16.38427 -213.211156) (xy 16.394397 -213.211651) (xy 16.41312 -213.219372) (xy 16.427478 -213.233656)
			(xy 16.435296 -213.25234) (xy 16.435832 -213.262464) (xy 16.435832 -213.671404) (xy 22.476968 -213.671404)
			(xy 22.476968 -213.262464) (xy 22.477391 -213.252312) (xy 22.485193 -213.233565) (xy 22.499588 -213.219244)
			(xy 22.518375 -213.211539) (xy 22.52853 -213.211156) (xy 23.92807 -213.211156) (xy 23.938197 -213.211651)
			(xy 23.95692 -213.219372) (xy 23.971278 -213.233656) (xy 23.979096 -213.25234) (xy 23.979632 -213.262464)
			(xy 23.979632 -213.671404) (xy 30.020768 -213.671404) (xy 30.020768 -213.262464) (xy 30.021191 -213.252312)
			(xy 30.028993 -213.233565) (xy 30.043388 -213.219244) (xy 30.062175 -213.211539) (xy 30.07233 -213.211156)
			(xy 31.47187 -213.211156) (xy 31.481997 -213.211651) (xy 31.50072 -213.219372) (xy 31.515078 -213.233656)
			(xy 31.522896 -213.25234) (xy 31.523432 -213.262464) (xy 31.523432 -213.671404) (xy 37.564568 -213.671404)
			(xy 37.564568 -213.262464) (xy 37.564991 -213.252312) (xy 37.572793 -213.233565) (xy 37.587188 -213.219244)
			(xy 37.605975 -213.211539) (xy 37.61613 -213.211156) (xy 39.01567 -213.211156) (xy 39.025797 -213.211651)
			(xy 39.04452 -213.219372) (xy 39.058878 -213.233656) (xy 39.066696 -213.25234) (xy 39.067232 -213.262464)
			(xy 39.067232 -213.671404) (xy 45.108368 -213.671404) (xy 45.108368 -213.262464) (xy 45.108791 -213.252312)
			(xy 45.116593 -213.233565) (xy 45.130988 -213.219244) (xy 45.149775 -213.211539) (xy 45.15993 -213.211156)
			(xy 46.55947 -213.211156) (xy 46.569597 -213.211651) (xy 46.58832 -213.219372) (xy 46.602678 -213.233656)
			(xy 46.610496 -213.25234) (xy 46.611032 -213.262464) (xy 46.611032 -213.671404) (xy 52.652168 -213.671404)
			(xy 52.652168 -213.262464) (xy 52.652591 -213.252312) (xy 52.660393 -213.233565) (xy 52.674788 -213.219244)
			(xy 52.693575 -213.211539) (xy 52.70373 -213.211156) (xy 54.10327 -213.211156) (xy 54.113397 -213.211651)
			(xy 54.13212 -213.219372) (xy 54.146478 -213.233656) (xy 54.154296 -213.25234) (xy 54.154832 -213.262464)
			(xy 54.154832 -213.671404) (xy 60.195968 -213.671404) (xy 60.195968 -213.262464) (xy 60.196391 -213.252312)
			(xy 60.204193 -213.233565) (xy 60.218588 -213.219244) (xy 60.237375 -213.211539) (xy 60.24753 -213.211156)
			(xy 61.64707 -213.211156) (xy 61.657197 -213.211651) (xy 61.67592 -213.219372) (xy 61.690278 -213.233656)
			(xy 61.698096 -213.25234) (xy 61.698632 -213.262464) (xy 61.698632 -213.671404) (xy 61.698182 -213.681554)
			(xy 61.690391 -213.700301) (xy 61.676004 -213.714623) (xy 61.657222 -213.722328) (xy 61.64707 -213.722712)
			(xy 60.24753 -213.722712) (xy 60.237412 -213.722151) (xy 60.218701 -213.714442) (xy 60.204345 -213.700179)
			(xy 60.196516 -213.681519) (xy 60.195968 -213.671404) (xy 54.154832 -213.671404) (xy 54.154382 -213.681554)
			(xy 54.146591 -213.700301) (xy 54.132204 -213.714623) (xy 54.113422 -213.722328) (xy 54.10327 -213.722712)
			(xy 52.70373 -213.722712) (xy 52.693612 -213.722151) (xy 52.674901 -213.714442) (xy 52.660545 -213.700179)
			(xy 52.652716 -213.681519) (xy 52.652168 -213.671404) (xy 46.611032 -213.671404) (xy 46.610582 -213.681554)
			(xy 46.602791 -213.700301) (xy 46.588404 -213.714623) (xy 46.569622 -213.722328) (xy 46.55947 -213.722712)
			(xy 45.15993 -213.722712) (xy 45.149812 -213.722151) (xy 45.131101 -213.714442) (xy 45.116745 -213.700179)
			(xy 45.108916 -213.681519) (xy 45.108368 -213.671404) (xy 39.067232 -213.671404) (xy 39.066782 -213.681554)
			(xy 39.058991 -213.700301) (xy 39.044604 -213.714623) (xy 39.025822 -213.722328) (xy 39.01567 -213.722712)
			(xy 37.61613 -213.722712) (xy 37.606012 -213.722151) (xy 37.587301 -213.714442) (xy 37.572945 -213.700179)
			(xy 37.565116 -213.681519) (xy 37.564568 -213.671404) (xy 31.523432 -213.671404) (xy 31.522982 -213.681554)
			(xy 31.515191 -213.700301) (xy 31.500804 -213.714623) (xy 31.482022 -213.722328) (xy 31.47187 -213.722712)
			(xy 30.07233 -213.722712) (xy 30.062212 -213.722151) (xy 30.043501 -213.714442) (xy 30.029145 -213.700179)
			(xy 30.021316 -213.681519) (xy 30.020768 -213.671404) (xy 23.979632 -213.671404) (xy 23.979182 -213.681554)
			(xy 23.971391 -213.700301) (xy 23.957004 -213.714623) (xy 23.938222 -213.722328) (xy 23.92807 -213.722712)
			(xy 22.52853 -213.722712) (xy 22.518412 -213.722151) (xy 22.499701 -213.714442) (xy 22.485345 -213.700179)
			(xy 22.477516 -213.681519) (xy 22.476968 -213.671404) (xy 16.435832 -213.671404) (xy 16.435382 -213.681554)
			(xy 16.427591 -213.700301) (xy 16.413204 -213.714623) (xy 16.394422 -213.722328) (xy 16.38427 -213.722712)
			(xy 14.98473 -213.722712) (xy 14.974612 -213.722151) (xy 14.955901 -213.714442) (xy 14.941545 -213.700179)
			(xy 14.933716 -213.681519) (xy 14.933168 -213.671404) (xy 8.892032 -213.671404) (xy 8.891582 -213.681554)
			(xy 8.883791 -213.700301) (xy 8.869404 -213.714623) (xy 8.850622 -213.722328) (xy 8.84047 -213.722712)
			(xy 7.44093 -213.722712) (xy 7.430812 -213.722151) (xy 7.412101 -213.714442) (xy 7.397745 -213.700179)
			(xy 7.389916 -213.681519) (xy 7.389368 -213.671404) (xy 2.509012 -213.671404) (xy 2.509012 -213.732618)
			(xy 90.165428 -213.732618) (xy 90.165936 -213.706731) (xy 90.174035 -213.655593) (xy 90.190034 -213.606353)
			(xy 90.21354 -213.560221) (xy 90.243972 -213.518334) (xy 90.280582 -213.481724) (xy 90.322469 -213.451292)
			(xy 90.368601 -213.427786) (xy 90.417841 -213.411787) (xy 90.468979 -213.403688) (xy 90.520753 -213.403688)
			(xy 90.571891 -213.411787) (xy 90.621131 -213.427786) (xy 90.667263 -213.451292) (xy 90.70915 -213.481724)
			(xy 90.74576 -213.518334) (xy 90.776192 -213.560221) (xy 90.799698 -213.606353) (xy 90.815697 -213.655593)
			(xy 90.823796 -213.706731) (xy 90.824304 -213.732618) (xy 92.045028 -213.732618) (xy 92.045536 -213.706731)
			(xy 92.053635 -213.655593) (xy 92.069634 -213.606353) (xy 92.09314 -213.560221) (xy 92.123572 -213.518334)
			(xy 92.160182 -213.481724) (xy 92.202069 -213.451292) (xy 92.248201 -213.427786) (xy 92.297441 -213.411787)
			(xy 92.348579 -213.403688) (xy 92.400353 -213.403688) (xy 92.451491 -213.411787) (xy 92.500731 -213.427786)
			(xy 92.546863 -213.451292) (xy 92.58875 -213.481724) (xy 92.62536 -213.518334) (xy 92.655792 -213.560221)
			(xy 92.679298 -213.606353) (xy 92.695297 -213.655593) (xy 92.703396 -213.706731) (xy 92.703904 -213.732618)
			(xy 93.924628 -213.732618) (xy 93.925136 -213.706731) (xy 93.933235 -213.655593) (xy 93.949234 -213.606353)
			(xy 93.97274 -213.560221) (xy 94.003172 -213.518334) (xy 94.039782 -213.481724) (xy 94.081669 -213.451292)
			(xy 94.127801 -213.427786) (xy 94.177041 -213.411787) (xy 94.228179 -213.403688) (xy 94.279953 -213.403688)
			(xy 94.331091 -213.411787) (xy 94.380331 -213.427786) (xy 94.426463 -213.451292) (xy 94.46835 -213.481724)
			(xy 94.50496 -213.518334) (xy 94.535392 -213.560221) (xy 94.558898 -213.606353) (xy 94.574897 -213.655593)
			(xy 94.582996 -213.706731) (xy 94.583504 -213.732618) (xy 95.804228 -213.732618) (xy 95.804736 -213.706731)
			(xy 95.812835 -213.655593) (xy 95.828834 -213.606353) (xy 95.85234 -213.560221) (xy 95.882772 -213.518334)
			(xy 95.919382 -213.481724) (xy 95.961269 -213.451292) (xy 96.007401 -213.427786) (xy 96.056641 -213.411787)
			(xy 96.107779 -213.403688) (xy 96.159553 -213.403688) (xy 96.210691 -213.411787) (xy 96.259931 -213.427786)
			(xy 96.306063 -213.451292) (xy 96.34795 -213.481724) (xy 96.38456 -213.518334) (xy 96.414992 -213.560221)
			(xy 96.438498 -213.606353) (xy 96.454497 -213.655593) (xy 96.462596 -213.706731) (xy 96.463104 -213.732618)
			(xy 97.683828 -213.732618) (xy 97.684336 -213.706731) (xy 97.692435 -213.655593) (xy 97.708434 -213.606353)
			(xy 97.73194 -213.560221) (xy 97.762372 -213.518334) (xy 97.798982 -213.481724) (xy 97.840869 -213.451292)
			(xy 97.887001 -213.427786) (xy 97.936241 -213.411787) (xy 97.987379 -213.403688) (xy 98.039153 -213.403688)
			(xy 98.090291 -213.411787) (xy 98.139531 -213.427786) (xy 98.185663 -213.451292) (xy 98.22755 -213.481724)
			(xy 98.26416 -213.518334) (xy 98.294592 -213.560221) (xy 98.318098 -213.606353) (xy 98.334097 -213.655593)
			(xy 98.342196 -213.706731) (xy 98.342704 -213.732618) (xy 99.563428 -213.732618) (xy 99.563936 -213.706731)
			(xy 99.572035 -213.655593) (xy 99.588034 -213.606353) (xy 99.61154 -213.560221) (xy 99.641972 -213.518334)
			(xy 99.678582 -213.481724) (xy 99.720469 -213.451292) (xy 99.766601 -213.427786) (xy 99.815841 -213.411787)
			(xy 99.866979 -213.403688) (xy 99.918753 -213.403688) (xy 99.969891 -213.411787) (xy 100.019131 -213.427786)
			(xy 100.065263 -213.451292) (xy 100.10715 -213.481724) (xy 100.14376 -213.518334) (xy 100.174192 -213.560221)
			(xy 100.197698 -213.606353) (xy 100.213697 -213.655593) (xy 100.221796 -213.706731) (xy 100.222304 -213.732618)
			(xy 101.443028 -213.732618) (xy 101.443536 -213.706731) (xy 101.451635 -213.655593) (xy 101.467634 -213.606353)
			(xy 101.49114 -213.560221) (xy 101.521572 -213.518334) (xy 101.558182 -213.481724) (xy 101.600069 -213.451292)
			(xy 101.646201 -213.427786) (xy 101.695441 -213.411787) (xy 101.746579 -213.403688) (xy 101.798353 -213.403688)
			(xy 101.849491 -213.411787) (xy 101.898731 -213.427786) (xy 101.944863 -213.451292) (xy 101.98675 -213.481724)
			(xy 102.02336 -213.518334) (xy 102.053792 -213.560221) (xy 102.077298 -213.606353) (xy 102.093297 -213.655593)
			(xy 102.101396 -213.706731) (xy 102.101904 -213.732618) (xy 103.322628 -213.732618) (xy 103.323136 -213.706731)
			(xy 103.331235 -213.655593) (xy 103.347234 -213.606353) (xy 103.37074 -213.560221) (xy 103.401172 -213.518334)
			(xy 103.437782 -213.481724) (xy 103.479669 -213.451292) (xy 103.525801 -213.427786) (xy 103.575041 -213.411787)
			(xy 103.626179 -213.403688) (xy 103.677953 -213.403688) (xy 103.729091 -213.411787) (xy 103.778331 -213.427786)
			(xy 103.824463 -213.451292) (xy 103.86635 -213.481724) (xy 103.90296 -213.518334) (xy 103.933392 -213.560221)
			(xy 103.956898 -213.606353) (xy 103.972897 -213.655593) (xy 103.980996 -213.706731) (xy 103.981504 -213.732618)
			(xy 105.202228 -213.732618) (xy 105.202736 -213.706731) (xy 105.210835 -213.655593) (xy 105.226834 -213.606353)
			(xy 105.25034 -213.560221) (xy 105.280772 -213.518334) (xy 105.317382 -213.481724) (xy 105.359269 -213.451292)
			(xy 105.405401 -213.427786) (xy 105.454641 -213.411787) (xy 105.505779 -213.403688) (xy 105.557553 -213.403688)
			(xy 105.608691 -213.411787) (xy 105.657931 -213.427786) (xy 105.704063 -213.451292) (xy 105.74595 -213.481724)
			(xy 105.78256 -213.518334) (xy 105.812992 -213.560221) (xy 105.836498 -213.606353) (xy 105.852497 -213.655593)
			(xy 105.860596 -213.706731) (xy 105.861104 -213.732618) (xy 107.081828 -213.732618) (xy 107.082336 -213.706731)
			(xy 107.090435 -213.655593) (xy 107.106434 -213.606353) (xy 107.12994 -213.560221) (xy 107.160372 -213.518334)
			(xy 107.196982 -213.481724) (xy 107.238869 -213.451292) (xy 107.285001 -213.427786) (xy 107.334241 -213.411787)
			(xy 107.385379 -213.403688) (xy 107.437153 -213.403688) (xy 107.488291 -213.411787) (xy 107.537531 -213.427786)
			(xy 107.583663 -213.451292) (xy 107.62555 -213.481724) (xy 107.66216 -213.518334) (xy 107.692592 -213.560221)
			(xy 107.716098 -213.606353) (xy 107.732097 -213.655593) (xy 107.740196 -213.706731) (xy 107.740704 -213.732618)
			(xy 114.600228 -213.732618) (xy 114.600736 -213.706731) (xy 114.608835 -213.655593) (xy 114.624834 -213.606353)
			(xy 114.64834 -213.560221) (xy 114.678772 -213.518334) (xy 114.715382 -213.481724) (xy 114.757269 -213.451292)
			(xy 114.803401 -213.427786) (xy 114.852641 -213.411787) (xy 114.903779 -213.403688) (xy 114.955553 -213.403688)
			(xy 115.006691 -213.411787) (xy 115.055931 -213.427786) (xy 115.102063 -213.451292) (xy 115.14395 -213.481724)
			(xy 115.18056 -213.518334) (xy 115.210992 -213.560221) (xy 115.234498 -213.606353) (xy 115.250497 -213.655593)
			(xy 115.258596 -213.706731) (xy 115.259104 -213.732618) (xy 116.479828 -213.732618) (xy 116.480336 -213.706731)
			(xy 116.488435 -213.655593) (xy 116.504434 -213.606353) (xy 116.52794 -213.560221) (xy 116.558372 -213.518334)
			(xy 116.594982 -213.481724) (xy 116.636869 -213.451292) (xy 116.683001 -213.427786) (xy 116.732241 -213.411787)
			(xy 116.783379 -213.403688) (xy 116.835153 -213.403688) (xy 116.886291 -213.411787) (xy 116.935531 -213.427786)
			(xy 116.981663 -213.451292) (xy 117.02355 -213.481724) (xy 117.06016 -213.518334) (xy 117.090592 -213.560221)
			(xy 117.114098 -213.606353) (xy 117.130097 -213.655593) (xy 117.138196 -213.706731) (xy 117.138704 -213.732618)
			(xy 118.359428 -213.732618) (xy 118.359936 -213.706731) (xy 118.368035 -213.655593) (xy 118.384034 -213.606353)
			(xy 118.40754 -213.560221) (xy 118.437972 -213.518334) (xy 118.474582 -213.481724) (xy 118.516469 -213.451292)
			(xy 118.562601 -213.427786) (xy 118.611841 -213.411787) (xy 118.662979 -213.403688) (xy 118.714753 -213.403688)
			(xy 118.765891 -213.411787) (xy 118.815131 -213.427786) (xy 118.861263 -213.451292) (xy 118.90315 -213.481724)
			(xy 118.93976 -213.518334) (xy 118.970192 -213.560221) (xy 118.993698 -213.606353) (xy 119.009697 -213.655593)
			(xy 119.017796 -213.706731) (xy 119.018304 -213.732618) (xy 120.239028 -213.732618) (xy 120.239536 -213.706731)
			(xy 120.247635 -213.655593) (xy 120.263634 -213.606353) (xy 120.28714 -213.560221) (xy 120.317572 -213.518334)
			(xy 120.354182 -213.481724) (xy 120.396069 -213.451292) (xy 120.442201 -213.427786) (xy 120.491441 -213.411787)
			(xy 120.542579 -213.403688) (xy 120.594353 -213.403688) (xy 120.645491 -213.411787) (xy 120.694731 -213.427786)
			(xy 120.740863 -213.451292) (xy 120.78275 -213.481724) (xy 120.81936 -213.518334) (xy 120.849792 -213.560221)
			(xy 120.873298 -213.606353) (xy 120.889297 -213.655593) (xy 120.897396 -213.706731) (xy 120.897904 -213.732618)
			(xy 122.118628 -213.732618) (xy 122.119136 -213.706731) (xy 122.127235 -213.655593) (xy 122.143234 -213.606353)
			(xy 122.16674 -213.560221) (xy 122.197172 -213.518334) (xy 122.233782 -213.481724) (xy 122.275669 -213.451292)
			(xy 122.321801 -213.427786) (xy 122.371041 -213.411787) (xy 122.422179 -213.403688) (xy 122.473953 -213.403688)
			(xy 122.525091 -213.411787) (xy 122.574331 -213.427786) (xy 122.620463 -213.451292) (xy 122.66235 -213.481724)
			(xy 122.69896 -213.518334) (xy 122.729392 -213.560221) (xy 122.752898 -213.606353) (xy 122.768897 -213.655593)
			(xy 122.776996 -213.706731) (xy 122.777504 -213.732618) (xy 123.99772 -213.732618) (xy 123.998228 -213.706711)
			(xy 124.006334 -213.655534) (xy 124.022346 -213.606255) (xy 124.045869 -213.560088) (xy 124.076325 -213.518169)
			(xy 124.112963 -213.481531) (xy 124.154882 -213.451075) (xy 124.201049 -213.427552) (xy 124.250328 -213.41154)
			(xy 124.301505 -213.403434) (xy 124.353319 -213.403434) (xy 124.404496 -213.41154) (xy 124.453775 -213.427552)
			(xy 124.499942 -213.451075) (xy 124.541861 -213.481531) (xy 124.578499 -213.518169) (xy 124.608955 -213.560088)
			(xy 124.632478 -213.606255) (xy 124.64849 -213.655534) (xy 124.656596 -213.706711) (xy 124.657104 -213.732618)
			(xy 125.87732 -213.732618) (xy 125.877828 -213.706711) (xy 125.885934 -213.655534) (xy 125.901946 -213.606255)
			(xy 125.925469 -213.560088) (xy 125.955925 -213.518169) (xy 125.992563 -213.481531) (xy 126.034482 -213.451075)
			(xy 126.080649 -213.427552) (xy 126.129928 -213.41154) (xy 126.181105 -213.403434) (xy 126.232919 -213.403434)
			(xy 126.284096 -213.41154) (xy 126.333375 -213.427552) (xy 126.379542 -213.451075) (xy 126.421461 -213.481531)
			(xy 126.458099 -213.518169) (xy 126.488555 -213.560088) (xy 126.512078 -213.606255) (xy 126.52809 -213.655534)
			(xy 126.536196 -213.706711) (xy 126.536704 -213.732618) (xy 127.757428 -213.732618) (xy 127.757936 -213.706731)
			(xy 127.766035 -213.655593) (xy 127.782034 -213.606353) (xy 127.80554 -213.560221) (xy 127.835972 -213.518334)
			(xy 127.872582 -213.481724) (xy 127.914469 -213.451292) (xy 127.960601 -213.427786) (xy 128.009841 -213.411787)
			(xy 128.060979 -213.403688) (xy 128.112753 -213.403688) (xy 128.163891 -213.411787) (xy 128.213131 -213.427786)
			(xy 128.259263 -213.451292) (xy 128.30115 -213.481724) (xy 128.33776 -213.518334) (xy 128.368192 -213.560221)
			(xy 128.391698 -213.606353) (xy 128.407697 -213.655593) (xy 128.415796 -213.706731) (xy 128.416304 -213.732618)
			(xy 129.637028 -213.732618) (xy 129.637536 -213.706731) (xy 129.645635 -213.655593) (xy 129.661634 -213.606353)
			(xy 129.68514 -213.560221) (xy 129.715572 -213.518334) (xy 129.752182 -213.481724) (xy 129.794069 -213.451292)
			(xy 129.840201 -213.427786) (xy 129.889441 -213.411787) (xy 129.940579 -213.403688) (xy 129.992353 -213.403688)
			(xy 130.043491 -213.411787) (xy 130.092731 -213.427786) (xy 130.138863 -213.451292) (xy 130.18075 -213.481724)
			(xy 130.21736 -213.518334) (xy 130.247792 -213.560221) (xy 130.271298 -213.606353) (xy 130.287297 -213.655593)
			(xy 130.295396 -213.706731) (xy 130.295904 -213.732618) (xy 131.516628 -213.732618) (xy 131.517136 -213.706731)
			(xy 131.525235 -213.655593) (xy 131.541234 -213.606353) (xy 131.56474 -213.560221) (xy 131.595172 -213.518334)
			(xy 131.631782 -213.481724) (xy 131.673669 -213.451292) (xy 131.719801 -213.427786) (xy 131.769041 -213.411787)
			(xy 131.820179 -213.403688) (xy 131.871953 -213.403688) (xy 131.923091 -213.411787) (xy 131.972331 -213.427786)
			(xy 132.018463 -213.451292) (xy 132.06035 -213.481724) (xy 132.09696 -213.518334) (xy 132.127392 -213.560221)
			(xy 132.150898 -213.606353) (xy 132.166897 -213.655593) (xy 132.169401 -213.671404) (xy 158.062168 -213.671404)
			(xy 158.062168 -213.262464) (xy 158.062591 -213.252312) (xy 158.070393 -213.233565) (xy 158.084788 -213.219244)
			(xy 158.103575 -213.211539) (xy 158.11373 -213.211156) (xy 159.51327 -213.211156) (xy 159.523397 -213.211651)
			(xy 159.54212 -213.219372) (xy 159.556478 -213.233656) (xy 159.564296 -213.25234) (xy 159.564832 -213.262464)
			(xy 159.564832 -213.671404) (xy 165.605968 -213.671404) (xy 165.605968 -213.262464) (xy 165.606391 -213.252312)
			(xy 165.614193 -213.233565) (xy 165.628588 -213.219244) (xy 165.647375 -213.211539) (xy 165.65753 -213.211156)
			(xy 167.05707 -213.211156) (xy 167.067197 -213.211651) (xy 167.08592 -213.219372) (xy 167.100278 -213.233656)
			(xy 167.108096 -213.25234) (xy 167.108632 -213.262464) (xy 167.108632 -213.671404) (xy 173.149768 -213.671404)
			(xy 173.149768 -213.262464) (xy 173.150191 -213.252312) (xy 173.157993 -213.233565) (xy 173.172388 -213.219244)
			(xy 173.191175 -213.211539) (xy 173.20133 -213.211156) (xy 174.60087 -213.211156) (xy 174.610997 -213.211651)
			(xy 174.62972 -213.219372) (xy 174.644078 -213.233656) (xy 174.651896 -213.25234) (xy 174.652432 -213.262464)
			(xy 174.652432 -213.671404) (xy 180.693568 -213.671404) (xy 180.693568 -213.262464) (xy 180.693991 -213.252312)
			(xy 180.701793 -213.233565) (xy 180.716188 -213.219244) (xy 180.734975 -213.211539) (xy 180.74513 -213.211156)
			(xy 182.14467 -213.211156) (xy 182.154797 -213.211651) (xy 182.17352 -213.219372) (xy 182.187878 -213.233656)
			(xy 182.195696 -213.25234) (xy 182.196232 -213.262464) (xy 182.196232 -213.671404) (xy 188.237368 -213.671404)
			(xy 188.237368 -213.262464) (xy 188.237791 -213.252312) (xy 188.245593 -213.233565) (xy 188.259988 -213.219244)
			(xy 188.278775 -213.211539) (xy 188.28893 -213.211156) (xy 189.68847 -213.211156) (xy 189.698597 -213.211651)
			(xy 189.71732 -213.219372) (xy 189.731678 -213.233656) (xy 189.739496 -213.25234) (xy 189.740032 -213.262464)
			(xy 189.740032 -213.671404) (xy 195.781168 -213.671404) (xy 195.781168 -213.262464) (xy 195.781591 -213.252312)
			(xy 195.789393 -213.233565) (xy 195.803788 -213.219244) (xy 195.822575 -213.211539) (xy 195.83273 -213.211156)
			(xy 197.23227 -213.211156) (xy 197.242397 -213.211651) (xy 197.26112 -213.219372) (xy 197.275478 -213.233656)
			(xy 197.283296 -213.25234) (xy 197.283832 -213.262464) (xy 197.283832 -213.671404) (xy 203.324968 -213.671404)
			(xy 203.324968 -213.262464) (xy 203.325391 -213.252312) (xy 203.333193 -213.233565) (xy 203.347588 -213.219244)
			(xy 203.366375 -213.211539) (xy 203.37653 -213.211156) (xy 204.77607 -213.211156) (xy 204.786197 -213.211651)
			(xy 204.80492 -213.219372) (xy 204.819278 -213.233656) (xy 204.827096 -213.25234) (xy 204.827632 -213.262464)
			(xy 204.827632 -213.671404) (xy 210.868768 -213.671404) (xy 210.868768 -213.262464) (xy 210.869191 -213.252312)
			(xy 210.876993 -213.233565) (xy 210.891388 -213.219244) (xy 210.910175 -213.211539) (xy 210.92033 -213.211156)
			(xy 212.31987 -213.211156) (xy 212.329997 -213.211651) (xy 212.34872 -213.219372) (xy 212.363078 -213.233656)
			(xy 212.370896 -213.25234) (xy 212.371432 -213.262464) (xy 212.371432 -213.671404) (xy 255.329436 -213.671404)
			(xy 255.329436 -213.262464) (xy 255.329793 -213.252303) (xy 255.337607 -213.233543) (xy 255.352024 -213.21922)
			(xy 255.370834 -213.211528) (xy 255.380998 -213.211156) (xy 256.780538 -213.211156) (xy 256.790669 -213.211596)
			(xy 256.809394 -213.219339) (xy 256.82375 -213.23364) (xy 256.831565 -213.252335) (xy 256.8321 -213.262464)
			(xy 256.8321 -213.671404) (xy 262.873236 -213.671404) (xy 262.873236 -213.262464) (xy 262.873593 -213.252303)
			(xy 262.881407 -213.233543) (xy 262.895824 -213.21922) (xy 262.914634 -213.211528) (xy 262.924798 -213.211156)
			(xy 264.324338 -213.211156) (xy 264.334469 -213.211596) (xy 264.353194 -213.219339) (xy 264.36755 -213.23364)
			(xy 264.375365 -213.252335) (xy 264.3759 -213.262464) (xy 264.3759 -213.671404) (xy 270.417036 -213.671404)
			(xy 270.417036 -213.262464) (xy 270.417393 -213.252303) (xy 270.425207 -213.233543) (xy 270.439624 -213.21922)
			(xy 270.458434 -213.211528) (xy 270.468598 -213.211156) (xy 271.868138 -213.211156) (xy 271.878269 -213.211596)
			(xy 271.896994 -213.219339) (xy 271.91135 -213.23364) (xy 271.919165 -213.252335) (xy 271.9197 -213.262464)
			(xy 271.9197 -213.671404) (xy 277.960836 -213.671404) (xy 277.960836 -213.262464) (xy 277.961193 -213.252303)
			(xy 277.969007 -213.233543) (xy 277.983424 -213.21922) (xy 278.002234 -213.211528) (xy 278.012398 -213.211156)
			(xy 279.411938 -213.211156) (xy 279.422069 -213.211596) (xy 279.440794 -213.219339) (xy 279.45515 -213.23364)
			(xy 279.462965 -213.252335) (xy 279.4635 -213.262464) (xy 279.4635 -213.671404) (xy 285.504636 -213.671404)
			(xy 285.504636 -213.262464) (xy 285.504993 -213.252303) (xy 285.512807 -213.233543) (xy 285.527224 -213.21922)
			(xy 285.546034 -213.211528) (xy 285.556198 -213.211156) (xy 286.955738 -213.211156) (xy 286.965869 -213.211596)
			(xy 286.984594 -213.219339) (xy 286.99895 -213.23364) (xy 287.006765 -213.252335) (xy 287.0073 -213.262464)
			(xy 287.0073 -213.671404) (xy 293.048436 -213.671404) (xy 293.048436 -213.262464) (xy 293.048793 -213.252303)
			(xy 293.056607 -213.233543) (xy 293.071024 -213.21922) (xy 293.089834 -213.211528) (xy 293.099998 -213.211156)
			(xy 294.499538 -213.211156) (xy 294.509669 -213.211596) (xy 294.528394 -213.219339) (xy 294.54275 -213.23364)
			(xy 294.550565 -213.252335) (xy 294.5511 -213.262464) (xy 294.5511 -213.671404) (xy 300.592236 -213.671404)
			(xy 300.592236 -213.262464) (xy 300.592593 -213.252303) (xy 300.600407 -213.233543) (xy 300.614824 -213.21922)
			(xy 300.633634 -213.211528) (xy 300.643798 -213.211156) (xy 302.043338 -213.211156) (xy 302.053469 -213.211596)
			(xy 302.072194 -213.219339) (xy 302.08655 -213.23364) (xy 302.094365 -213.252335) (xy 302.0949 -213.262464)
			(xy 302.0949 -213.671404) (xy 308.136036 -213.671404) (xy 308.136036 -213.262464) (xy 308.136393 -213.252303)
			(xy 308.144207 -213.233543) (xy 308.158624 -213.21922) (xy 308.177434 -213.211528) (xy 308.187598 -213.211156)
			(xy 309.587138 -213.211156) (xy 309.597269 -213.211596) (xy 309.615994 -213.219339) (xy 309.63035 -213.23364)
			(xy 309.638165 -213.252335) (xy 309.6387 -213.262464) (xy 309.6387 -213.671404) (xy 309.638282 -213.681558)
			(xy 309.630485 -213.700311) (xy 309.616087 -213.714634) (xy 309.597294 -213.722334) (xy 309.587138 -213.722712)
			(xy 308.187598 -213.722712) (xy 308.177478 -213.722177) (xy 308.158766 -213.714458) (xy 308.144412 -213.700187)
			(xy 308.136584 -213.681521) (xy 308.136036 -213.671404) (xy 302.0949 -213.671404) (xy 302.094482 -213.681558)
			(xy 302.086685 -213.700311) (xy 302.072287 -213.714634) (xy 302.053494 -213.722334) (xy 302.043338 -213.722712)
			(xy 300.643798 -213.722712) (xy 300.633678 -213.722177) (xy 300.614966 -213.714458) (xy 300.600612 -213.700187)
			(xy 300.592784 -213.681521) (xy 300.592236 -213.671404) (xy 294.5511 -213.671404) (xy 294.550682 -213.681558)
			(xy 294.542885 -213.700311) (xy 294.528487 -213.714634) (xy 294.509694 -213.722334) (xy 294.499538 -213.722712)
			(xy 293.099998 -213.722712) (xy 293.089878 -213.722177) (xy 293.071166 -213.714458) (xy 293.056812 -213.700187)
			(xy 293.048984 -213.681521) (xy 293.048436 -213.671404) (xy 287.0073 -213.671404) (xy 287.006882 -213.681558)
			(xy 286.999085 -213.700311) (xy 286.984687 -213.714634) (xy 286.965894 -213.722334) (xy 286.955738 -213.722712)
			(xy 285.556198 -213.722712) (xy 285.546078 -213.722177) (xy 285.527366 -213.714458) (xy 285.513012 -213.700187)
			(xy 285.505184 -213.681521) (xy 285.504636 -213.671404) (xy 279.4635 -213.671404) (xy 279.463082 -213.681558)
			(xy 279.455285 -213.700311) (xy 279.440887 -213.714634) (xy 279.422094 -213.722334) (xy 279.411938 -213.722712)
			(xy 278.012398 -213.722712) (xy 278.002278 -213.722177) (xy 277.983566 -213.714458) (xy 277.969212 -213.700187)
			(xy 277.961384 -213.681521) (xy 277.960836 -213.671404) (xy 271.9197 -213.671404) (xy 271.919282 -213.681558)
			(xy 271.911485 -213.700311) (xy 271.897087 -213.714634) (xy 271.878294 -213.722334) (xy 271.868138 -213.722712)
			(xy 270.468598 -213.722712) (xy 270.458478 -213.722177) (xy 270.439766 -213.714458) (xy 270.425412 -213.700187)
			(xy 270.417584 -213.681521) (xy 270.417036 -213.671404) (xy 264.3759 -213.671404) (xy 264.375482 -213.681558)
			(xy 264.367685 -213.700311) (xy 264.353287 -213.714634) (xy 264.334494 -213.722334) (xy 264.324338 -213.722712)
			(xy 262.924798 -213.722712) (xy 262.914678 -213.722177) (xy 262.895966 -213.714458) (xy 262.881612 -213.700187)
			(xy 262.873784 -213.681521) (xy 262.873236 -213.671404) (xy 256.8321 -213.671404) (xy 256.831682 -213.681558)
			(xy 256.823885 -213.700311) (xy 256.809487 -213.714634) (xy 256.790694 -213.722334) (xy 256.780538 -213.722712)
			(xy 255.380998 -213.722712) (xy 255.370878 -213.722177) (xy 255.352166 -213.714458) (xy 255.337812 -213.700187)
			(xy 255.329984 -213.681521) (xy 255.329436 -213.671404) (xy 212.371432 -213.671404) (xy 212.370982 -213.681554)
			(xy 212.363191 -213.700301) (xy 212.348804 -213.714623) (xy 212.330022 -213.722328) (xy 212.31987 -213.722712)
			(xy 210.92033 -213.722712) (xy 210.910212 -213.722151) (xy 210.891501 -213.714442) (xy 210.877145 -213.700179)
			(xy 210.869316 -213.681519) (xy 210.868768 -213.671404) (xy 204.827632 -213.671404) (xy 204.827182 -213.681554)
			(xy 204.819391 -213.700301) (xy 204.805004 -213.714623) (xy 204.786222 -213.722328) (xy 204.77607 -213.722712)
			(xy 203.37653 -213.722712) (xy 203.366412 -213.722151) (xy 203.347701 -213.714442) (xy 203.333345 -213.700179)
			(xy 203.325516 -213.681519) (xy 203.324968 -213.671404) (xy 197.283832 -213.671404) (xy 197.283382 -213.681554)
			(xy 197.275591 -213.700301) (xy 197.261204 -213.714623) (xy 197.242422 -213.722328) (xy 197.23227 -213.722712)
			(xy 195.83273 -213.722712) (xy 195.822612 -213.722151) (xy 195.803901 -213.714442) (xy 195.789545 -213.700179)
			(xy 195.781716 -213.681519) (xy 195.781168 -213.671404) (xy 189.740032 -213.671404) (xy 189.739582 -213.681554)
			(xy 189.731791 -213.700301) (xy 189.717404 -213.714623) (xy 189.698622 -213.722328) (xy 189.68847 -213.722712)
			(xy 188.28893 -213.722712) (xy 188.278812 -213.722151) (xy 188.260101 -213.714442) (xy 188.245745 -213.700179)
			(xy 188.237916 -213.681519) (xy 188.237368 -213.671404) (xy 182.196232 -213.671404) (xy 182.195782 -213.681554)
			(xy 182.187991 -213.700301) (xy 182.173604 -213.714623) (xy 182.154822 -213.722328) (xy 182.14467 -213.722712)
			(xy 180.74513 -213.722712) (xy 180.735012 -213.722151) (xy 180.716301 -213.714442) (xy 180.701945 -213.700179)
			(xy 180.694116 -213.681519) (xy 180.693568 -213.671404) (xy 174.652432 -213.671404) (xy 174.651982 -213.681554)
			(xy 174.644191 -213.700301) (xy 174.629804 -213.714623) (xy 174.611022 -213.722328) (xy 174.60087 -213.722712)
			(xy 173.20133 -213.722712) (xy 173.191212 -213.722151) (xy 173.172501 -213.714442) (xy 173.158145 -213.700179)
			(xy 173.150316 -213.681519) (xy 173.149768 -213.671404) (xy 167.108632 -213.671404) (xy 167.108182 -213.681554)
			(xy 167.100391 -213.700301) (xy 167.086004 -213.714623) (xy 167.067222 -213.722328) (xy 167.05707 -213.722712)
			(xy 165.65753 -213.722712) (xy 165.647412 -213.722151) (xy 165.628701 -213.714442) (xy 165.614345 -213.700179)
			(xy 165.606516 -213.681519) (xy 165.605968 -213.671404) (xy 159.564832 -213.671404) (xy 159.564382 -213.681554)
			(xy 159.556591 -213.700301) (xy 159.542204 -213.714623) (xy 159.523422 -213.722328) (xy 159.51327 -213.722712)
			(xy 158.11373 -213.722712) (xy 158.103612 -213.722151) (xy 158.084901 -213.714442) (xy 158.070545 -213.700179)
			(xy 158.062716 -213.681519) (xy 158.062168 -213.671404) (xy 132.169401 -213.671404) (xy 132.174996 -213.706731)
			(xy 132.175504 -213.732618) (xy 338.105496 -213.732618) (xy 338.106004 -213.706731) (xy 338.114103 -213.655593)
			(xy 338.130102 -213.606353) (xy 338.153608 -213.560221) (xy 338.18404 -213.518334) (xy 338.22065 -213.481724)
			(xy 338.262537 -213.451292) (xy 338.308669 -213.427786) (xy 338.357909 -213.411787) (xy 338.409047 -213.403688)
			(xy 338.460821 -213.403688) (xy 338.511959 -213.411787) (xy 338.561199 -213.427786) (xy 338.607331 -213.451292)
			(xy 338.649218 -213.481724) (xy 338.685828 -213.518334) (xy 338.71626 -213.560221) (xy 338.739766 -213.606353)
			(xy 338.755765 -213.655593) (xy 338.763864 -213.706731) (xy 338.764372 -213.732618) (xy 339.985096 -213.732618)
			(xy 339.985604 -213.706731) (xy 339.993703 -213.655593) (xy 340.009702 -213.606353) (xy 340.033208 -213.560221)
			(xy 340.06364 -213.518334) (xy 340.10025 -213.481724) (xy 340.142137 -213.451292) (xy 340.188269 -213.427786)
			(xy 340.237509 -213.411787) (xy 340.288647 -213.403688) (xy 340.340421 -213.403688) (xy 340.391559 -213.411787)
			(xy 340.440799 -213.427786) (xy 340.486931 -213.451292) (xy 340.528818 -213.481724) (xy 340.565428 -213.518334)
			(xy 340.59586 -213.560221) (xy 340.619366 -213.606353) (xy 340.635365 -213.655593) (xy 340.643464 -213.706731)
			(xy 340.643972 -213.732618) (xy 341.864696 -213.732618) (xy 341.865204 -213.706731) (xy 341.873303 -213.655593)
			(xy 341.889302 -213.606353) (xy 341.912808 -213.560221) (xy 341.94324 -213.518334) (xy 341.97985 -213.481724)
			(xy 342.021737 -213.451292) (xy 342.067869 -213.427786) (xy 342.117109 -213.411787) (xy 342.168247 -213.403688)
			(xy 342.220021 -213.403688) (xy 342.271159 -213.411787) (xy 342.320399 -213.427786) (xy 342.366531 -213.451292)
			(xy 342.408418 -213.481724) (xy 342.445028 -213.518334) (xy 342.47546 -213.560221) (xy 342.498966 -213.606353)
			(xy 342.514965 -213.655593) (xy 342.523064 -213.706731) (xy 342.523572 -213.732618) (xy 343.744296 -213.732618)
			(xy 343.744804 -213.706731) (xy 343.752903 -213.655593) (xy 343.768902 -213.606353) (xy 343.792408 -213.560221)
			(xy 343.82284 -213.518334) (xy 343.85945 -213.481724) (xy 343.901337 -213.451292) (xy 343.947469 -213.427786)
			(xy 343.996709 -213.411787) (xy 344.047847 -213.403688) (xy 344.099621 -213.403688) (xy 344.150759 -213.411787)
			(xy 344.199999 -213.427786) (xy 344.246131 -213.451292) (xy 344.288018 -213.481724) (xy 344.324628 -213.518334)
			(xy 344.35506 -213.560221) (xy 344.378566 -213.606353) (xy 344.394565 -213.655593) (xy 344.402664 -213.706731)
			(xy 344.403172 -213.732618) (xy 345.623896 -213.732618) (xy 345.624404 -213.706731) (xy 345.632503 -213.655593)
			(xy 345.648502 -213.606353) (xy 345.672008 -213.560221) (xy 345.70244 -213.518334) (xy 345.73905 -213.481724)
			(xy 345.780937 -213.451292) (xy 345.827069 -213.427786) (xy 345.876309 -213.411787) (xy 345.927447 -213.403688)
			(xy 345.979221 -213.403688) (xy 346.030359 -213.411787) (xy 346.079599 -213.427786) (xy 346.125731 -213.451292)
			(xy 346.167618 -213.481724) (xy 346.204228 -213.518334) (xy 346.23466 -213.560221) (xy 346.258166 -213.606353)
			(xy 346.274165 -213.655593) (xy 346.282264 -213.706731) (xy 346.282772 -213.732618) (xy 347.503496 -213.732618)
			(xy 347.504004 -213.706731) (xy 347.512103 -213.655593) (xy 347.528102 -213.606353) (xy 347.551608 -213.560221)
			(xy 347.58204 -213.518334) (xy 347.61865 -213.481724) (xy 347.660537 -213.451292) (xy 347.706669 -213.427786)
			(xy 347.755909 -213.411787) (xy 347.807047 -213.403688) (xy 347.858821 -213.403688) (xy 347.909959 -213.411787)
			(xy 347.959199 -213.427786) (xy 348.005331 -213.451292) (xy 348.047218 -213.481724) (xy 348.083828 -213.518334)
			(xy 348.11426 -213.560221) (xy 348.137766 -213.606353) (xy 348.153765 -213.655593) (xy 348.161864 -213.706731)
			(xy 348.162372 -213.732618) (xy 349.383096 -213.732618) (xy 349.383604 -213.706731) (xy 349.391703 -213.655593)
			(xy 349.407702 -213.606353) (xy 349.431208 -213.560221) (xy 349.46164 -213.518334) (xy 349.49825 -213.481724)
			(xy 349.540137 -213.451292) (xy 349.586269 -213.427786) (xy 349.635509 -213.411787) (xy 349.686647 -213.403688)
			(xy 349.738421 -213.403688) (xy 349.789559 -213.411787) (xy 349.838799 -213.427786) (xy 349.884931 -213.451292)
			(xy 349.926818 -213.481724) (xy 349.963428 -213.518334) (xy 349.99386 -213.560221) (xy 350.017366 -213.606353)
			(xy 350.033365 -213.655593) (xy 350.041464 -213.706731) (xy 350.041972 -213.732618) (xy 351.262696 -213.732618)
			(xy 351.263204 -213.706731) (xy 351.271303 -213.655593) (xy 351.287302 -213.606353) (xy 351.310808 -213.560221)
			(xy 351.34124 -213.518334) (xy 351.37785 -213.481724) (xy 351.419737 -213.451292) (xy 351.465869 -213.427786)
			(xy 351.515109 -213.411787) (xy 351.566247 -213.403688) (xy 351.618021 -213.403688) (xy 351.669159 -213.411787)
			(xy 351.718399 -213.427786) (xy 351.764531 -213.451292) (xy 351.806418 -213.481724) (xy 351.843028 -213.518334)
			(xy 351.87346 -213.560221) (xy 351.896966 -213.606353) (xy 351.912965 -213.655593) (xy 351.921064 -213.706731)
			(xy 351.921572 -213.732618) (xy 353.142296 -213.732618) (xy 353.142804 -213.706731) (xy 353.150903 -213.655593)
			(xy 353.166902 -213.606353) (xy 353.190408 -213.560221) (xy 353.22084 -213.518334) (xy 353.25745 -213.481724)
			(xy 353.299337 -213.451292) (xy 353.345469 -213.427786) (xy 353.394709 -213.411787) (xy 353.445847 -213.403688)
			(xy 353.497621 -213.403688) (xy 353.548759 -213.411787) (xy 353.597999 -213.427786) (xy 353.644131 -213.451292)
			(xy 353.686018 -213.481724) (xy 353.722628 -213.518334) (xy 353.75306 -213.560221) (xy 353.776566 -213.606353)
			(xy 353.792565 -213.655593) (xy 353.800664 -213.706731) (xy 353.801172 -213.732618) (xy 355.021896 -213.732618)
			(xy 355.022404 -213.706731) (xy 355.030503 -213.655593) (xy 355.046502 -213.606353) (xy 355.070008 -213.560221)
			(xy 355.10044 -213.518334) (xy 355.13705 -213.481724) (xy 355.178937 -213.451292) (xy 355.225069 -213.427786)
			(xy 355.274309 -213.411787) (xy 355.325447 -213.403688) (xy 355.377221 -213.403688) (xy 355.428359 -213.411787)
			(xy 355.477599 -213.427786) (xy 355.523731 -213.451292) (xy 355.565618 -213.481724) (xy 355.602228 -213.518334)
			(xy 355.63266 -213.560221) (xy 355.656166 -213.606353) (xy 355.672165 -213.655593) (xy 355.674669 -213.671404)
			(xy 406.002236 -213.671404) (xy 406.002236 -213.262464) (xy 406.002593 -213.252303) (xy 406.010407 -213.233543)
			(xy 406.024824 -213.21922) (xy 406.043634 -213.211528) (xy 406.053798 -213.211156) (xy 407.453338 -213.211156)
			(xy 407.463469 -213.211596) (xy 407.482194 -213.219339) (xy 407.49655 -213.23364) (xy 407.504365 -213.252335)
			(xy 407.5049 -213.262464) (xy 407.5049 -213.671404) (xy 413.546036 -213.671404) (xy 413.546036 -213.262464)
			(xy 413.546393 -213.252303) (xy 413.554207 -213.233543) (xy 413.568624 -213.21922) (xy 413.587434 -213.211528)
			(xy 413.597598 -213.211156) (xy 414.997138 -213.211156) (xy 415.007269 -213.211596) (xy 415.025994 -213.219339)
			(xy 415.04035 -213.23364) (xy 415.048165 -213.252335) (xy 415.0487 -213.262464) (xy 415.0487 -213.671404)
			(xy 421.089836 -213.671404) (xy 421.089836 -213.262464) (xy 421.090193 -213.252303) (xy 421.098007 -213.233543)
			(xy 421.112424 -213.21922) (xy 421.131234 -213.211528) (xy 421.141398 -213.211156) (xy 422.540938 -213.211156)
			(xy 422.551069 -213.211596) (xy 422.569794 -213.219339) (xy 422.58415 -213.23364) (xy 422.591965 -213.252335)
			(xy 422.5925 -213.262464) (xy 422.5925 -213.671404) (xy 428.633636 -213.671404) (xy 428.633636 -213.262464)
			(xy 428.633993 -213.252303) (xy 428.641807 -213.233543) (xy 428.656224 -213.21922) (xy 428.675034 -213.211528)
			(xy 428.685198 -213.211156) (xy 430.084738 -213.211156) (xy 430.094869 -213.211596) (xy 430.113594 -213.219339)
			(xy 430.12795 -213.23364) (xy 430.135765 -213.252335) (xy 430.1363 -213.262464) (xy 430.1363 -213.671404)
			(xy 436.177436 -213.671404) (xy 436.177436 -213.262464) (xy 436.177793 -213.252303) (xy 436.185607 -213.233543)
			(xy 436.200024 -213.21922) (xy 436.218834 -213.211528) (xy 436.228998 -213.211156) (xy 437.628538 -213.211156)
			(xy 437.638669 -213.211596) (xy 437.657394 -213.219339) (xy 437.67175 -213.23364) (xy 437.679565 -213.252335)
			(xy 437.6801 -213.262464) (xy 437.6801 -213.671404) (xy 443.721236 -213.671404) (xy 443.721236 -213.262464)
			(xy 443.721593 -213.252303) (xy 443.729407 -213.233543) (xy 443.743824 -213.21922) (xy 443.762634 -213.211528)
			(xy 443.772798 -213.211156) (xy 445.172338 -213.211156) (xy 445.182469 -213.211596) (xy 445.201194 -213.219339)
			(xy 445.21555 -213.23364) (xy 445.223365 -213.252335) (xy 445.2239 -213.262464) (xy 445.2239 -213.671404)
			(xy 451.265036 -213.671404) (xy 451.265036 -213.262464) (xy 451.265393 -213.252303) (xy 451.273207 -213.233543)
			(xy 451.287624 -213.21922) (xy 451.306434 -213.211528) (xy 451.316598 -213.211156) (xy 452.716138 -213.211156)
			(xy 452.726269 -213.211596) (xy 452.744994 -213.219339) (xy 452.75935 -213.23364) (xy 452.767165 -213.252335)
			(xy 452.7677 -213.262464) (xy 452.7677 -213.671404) (xy 458.808836 -213.671404) (xy 458.808836 -213.262464)
			(xy 458.809193 -213.252303) (xy 458.817007 -213.233543) (xy 458.831424 -213.21922) (xy 458.850234 -213.211528)
			(xy 458.860398 -213.211156) (xy 460.259938 -213.211156) (xy 460.270069 -213.211596) (xy 460.288794 -213.219339)
			(xy 460.30315 -213.23364) (xy 460.310965 -213.252335) (xy 460.3115 -213.262464) (xy 460.3115 -213.671404)
			(xy 460.311082 -213.681558) (xy 460.303285 -213.700311) (xy 460.288887 -213.714634) (xy 460.270094 -213.722334)
			(xy 460.259938 -213.722712) (xy 458.860398 -213.722712) (xy 458.850278 -213.722177) (xy 458.831566 -213.714458)
			(xy 458.817212 -213.700187) (xy 458.809384 -213.681521) (xy 458.808836 -213.671404) (xy 452.7677 -213.671404)
			(xy 452.767282 -213.681558) (xy 452.759485 -213.700311) (xy 452.745087 -213.714634) (xy 452.726294 -213.722334)
			(xy 452.716138 -213.722712) (xy 451.316598 -213.722712) (xy 451.306478 -213.722177) (xy 451.287766 -213.714458)
			(xy 451.273412 -213.700187) (xy 451.265584 -213.681521) (xy 451.265036 -213.671404) (xy 445.2239 -213.671404)
			(xy 445.223482 -213.681558) (xy 445.215685 -213.700311) (xy 445.201287 -213.714634) (xy 445.182494 -213.722334)
			(xy 445.172338 -213.722712) (xy 443.772798 -213.722712) (xy 443.762678 -213.722177) (xy 443.743966 -213.714458)
			(xy 443.729612 -213.700187) (xy 443.721784 -213.681521) (xy 443.721236 -213.671404) (xy 437.6801 -213.671404)
			(xy 437.679682 -213.681558) (xy 437.671885 -213.700311) (xy 437.657487 -213.714634) (xy 437.638694 -213.722334)
			(xy 437.628538 -213.722712) (xy 436.228998 -213.722712) (xy 436.218878 -213.722177) (xy 436.200166 -213.714458)
			(xy 436.185812 -213.700187) (xy 436.177984 -213.681521) (xy 436.177436 -213.671404) (xy 430.1363 -213.671404)
			(xy 430.135882 -213.681558) (xy 430.128085 -213.700311) (xy 430.113687 -213.714634) (xy 430.094894 -213.722334)
			(xy 430.084738 -213.722712) (xy 428.685198 -213.722712) (xy 428.675078 -213.722177) (xy 428.656366 -213.714458)
			(xy 428.642012 -213.700187) (xy 428.634184 -213.681521) (xy 428.633636 -213.671404) (xy 422.5925 -213.671404)
			(xy 422.592082 -213.681558) (xy 422.584285 -213.700311) (xy 422.569887 -213.714634) (xy 422.551094 -213.722334)
			(xy 422.540938 -213.722712) (xy 421.141398 -213.722712) (xy 421.131278 -213.722177) (xy 421.112566 -213.714458)
			(xy 421.098212 -213.700187) (xy 421.090384 -213.681521) (xy 421.089836 -213.671404) (xy 415.0487 -213.671404)
			(xy 415.048282 -213.681558) (xy 415.040485 -213.700311) (xy 415.026087 -213.714634) (xy 415.007294 -213.722334)
			(xy 414.997138 -213.722712) (xy 413.597598 -213.722712) (xy 413.587478 -213.722177) (xy 413.568766 -213.714458)
			(xy 413.554412 -213.700187) (xy 413.546584 -213.681521) (xy 413.546036 -213.671404) (xy 407.5049 -213.671404)
			(xy 407.504482 -213.681558) (xy 407.496685 -213.700311) (xy 407.482287 -213.714634) (xy 407.463494 -213.722334)
			(xy 407.453338 -213.722712) (xy 406.053798 -213.722712) (xy 406.043678 -213.722177) (xy 406.024966 -213.714458)
			(xy 406.010612 -213.700187) (xy 406.002784 -213.681521) (xy 406.002236 -213.671404) (xy 355.674669 -213.671404)
			(xy 355.680264 -213.706731) (xy 355.680772 -213.732618) (xy 355.680423 -213.755595) (xy 355.674102 -213.801111)
			(xy 355.661516 -213.845306) (xy 355.652578 -213.866476) (xy 355.642672 -213.888828) (xy 355.856286 -214.293958)
			(xy 355.880416 -214.29853) (xy 355.90533 -214.303664) (xy 355.95334 -214.320459) (xy 355.998199 -214.344434)
			(xy 356.038841 -214.375017) (xy 356.074299 -214.411484) (xy 356.103732 -214.452967) (xy 356.12644 -214.49848)
			(xy 356.141883 -214.546942) (xy 356.149695 -214.597202) (xy 356.150164 -214.622634) (xy 356.149656 -214.648521)
			(xy 356.141557 -214.699659) (xy 356.125558 -214.748899) (xy 356.102052 -214.795031) (xy 356.07162 -214.836918)
			(xy 356.03501 -214.873528) (xy 355.993123 -214.90396) (xy 355.946991 -214.927466) (xy 355.897751 -214.943465)
			(xy 355.846613 -214.951564) (xy 355.794839 -214.951564) (xy 355.743701 -214.943465) (xy 355.694461 -214.927466)
			(xy 355.648329 -214.90396) (xy 355.606442 -214.873528) (xy 355.569832 -214.836918) (xy 355.5394 -214.795031)
			(xy 355.515894 -214.748899) (xy 355.499895 -214.699659) (xy 355.491796 -214.648521) (xy 355.491288 -214.622634)
			(xy 355.491658 -214.599658) (xy 355.49797 -214.554143) (xy 355.510548 -214.509947) (xy 355.519482 -214.488776)
			(xy 355.529388 -214.466424) (xy 355.315774 -214.061294) (xy 355.291644 -214.056722) (xy 355.266713 -214.051663)
			(xy 355.218699 -214.034858) (xy 355.173839 -214.010874) (xy 355.133197 -213.980281) (xy 355.097739 -213.943805)
			(xy 355.068309 -213.902313) (xy 355.045605 -213.856791) (xy 355.030167 -213.80832) (xy 355.022362 -213.758053)
			(xy 355.021896 -213.732618) (xy 353.801172 -213.732618) (xy 353.800823 -213.755595) (xy 353.794502 -213.801111)
			(xy 353.781916 -213.845306) (xy 353.772978 -213.866476) (xy 353.763072 -213.888828) (xy 353.976686 -214.293958)
			(xy 354.000816 -214.29853) (xy 354.02573 -214.303664) (xy 354.07374 -214.320459) (xy 354.118599 -214.344434)
			(xy 354.159241 -214.375017) (xy 354.194699 -214.411484) (xy 354.224132 -214.452967) (xy 354.24684 -214.49848)
			(xy 354.262283 -214.546942) (xy 354.270095 -214.597202) (xy 354.270564 -214.622634) (xy 354.270056 -214.648521)
			(xy 354.261957 -214.699659) (xy 354.245958 -214.748899) (xy 354.222452 -214.795031) (xy 354.19202 -214.836918)
			(xy 354.15541 -214.873528) (xy 354.113523 -214.90396) (xy 354.067391 -214.927466) (xy 354.018151 -214.943465)
			(xy 353.967013 -214.951564) (xy 353.915239 -214.951564) (xy 353.864101 -214.943465) (xy 353.814861 -214.927466)
			(xy 353.768729 -214.90396) (xy 353.726842 -214.873528) (xy 353.690232 -214.836918) (xy 353.6598 -214.795031)
			(xy 353.636294 -214.748899) (xy 353.620295 -214.699659) (xy 353.612196 -214.648521) (xy 353.611688 -214.622634)
			(xy 353.612058 -214.599658) (xy 353.61837 -214.554143) (xy 353.630948 -214.509947) (xy 353.639882 -214.488776)
			(xy 353.649788 -214.466424) (xy 353.436174 -214.061294) (xy 353.412044 -214.056722) (xy 353.387113 -214.051663)
			(xy 353.339099 -214.034858) (xy 353.294239 -214.010874) (xy 353.253597 -213.980281) (xy 353.218139 -213.943805)
			(xy 353.188709 -213.902313) (xy 353.166005 -213.856791) (xy 353.150567 -213.80832) (xy 353.142762 -213.758053)
			(xy 353.142296 -213.732618) (xy 351.921572 -213.732618) (xy 351.921223 -213.755595) (xy 351.914902 -213.801111)
			(xy 351.902316 -213.845306) (xy 351.893378 -213.866476) (xy 351.883472 -213.888828) (xy 352.097086 -214.293958)
			(xy 352.121216 -214.29853) (xy 352.14613 -214.303664) (xy 352.19414 -214.320459) (xy 352.238999 -214.344434)
			(xy 352.279641 -214.375017) (xy 352.315099 -214.411484) (xy 352.344532 -214.452967) (xy 352.36724 -214.49848)
			(xy 352.382683 -214.546942) (xy 352.390495 -214.597202) (xy 352.390964 -214.622634) (xy 352.390456 -214.648521)
			(xy 352.382357 -214.699659) (xy 352.366358 -214.748899) (xy 352.342852 -214.795031) (xy 352.31242 -214.836918)
			(xy 352.27581 -214.873528) (xy 352.233923 -214.90396) (xy 352.187791 -214.927466) (xy 352.138551 -214.943465)
			(xy 352.087413 -214.951564) (xy 352.035639 -214.951564) (xy 351.984501 -214.943465) (xy 351.935261 -214.927466)
			(xy 351.889129 -214.90396) (xy 351.847242 -214.873528) (xy 351.810632 -214.836918) (xy 351.7802 -214.795031)
			(xy 351.756694 -214.748899) (xy 351.740695 -214.699659) (xy 351.732596 -214.648521) (xy 351.732088 -214.622634)
			(xy 351.732458 -214.599658) (xy 351.73877 -214.554143) (xy 351.751348 -214.509947) (xy 351.760282 -214.488776)
			(xy 351.770188 -214.466424) (xy 351.556574 -214.061294) (xy 351.532444 -214.056722) (xy 351.507513 -214.051663)
			(xy 351.459499 -214.034858) (xy 351.414639 -214.010874) (xy 351.373997 -213.980281) (xy 351.338539 -213.943805)
			(xy 351.309109 -213.902313) (xy 351.286405 -213.856791) (xy 351.270967 -213.80832) (xy 351.263162 -213.758053)
			(xy 351.262696 -213.732618) (xy 350.041972 -213.732618) (xy 350.041623 -213.755595) (xy 350.035302 -213.801111)
			(xy 350.022716 -213.845306) (xy 350.013778 -213.866476) (xy 350.003872 -213.888828) (xy 350.217486 -214.293958)
			(xy 350.241616 -214.29853) (xy 350.26653 -214.303664) (xy 350.31454 -214.320459) (xy 350.359399 -214.344434)
			(xy 350.400041 -214.375017) (xy 350.435499 -214.411484) (xy 350.464932 -214.452967) (xy 350.48764 -214.49848)
			(xy 350.503083 -214.546942) (xy 350.510895 -214.597202) (xy 350.511364 -214.622634) (xy 350.510856 -214.648521)
			(xy 350.502757 -214.699659) (xy 350.486758 -214.748899) (xy 350.463252 -214.795031) (xy 350.43282 -214.836918)
			(xy 350.39621 -214.873528) (xy 350.354323 -214.90396) (xy 350.308191 -214.927466) (xy 350.258951 -214.943465)
			(xy 350.207813 -214.951564) (xy 350.156039 -214.951564) (xy 350.104901 -214.943465) (xy 350.055661 -214.927466)
			(xy 350.009529 -214.90396) (xy 349.967642 -214.873528) (xy 349.931032 -214.836918) (xy 349.9006 -214.795031)
			(xy 349.877094 -214.748899) (xy 349.861095 -214.699659) (xy 349.852996 -214.648521) (xy 349.852488 -214.622634)
			(xy 349.852858 -214.599658) (xy 349.85917 -214.554143) (xy 349.871748 -214.509947) (xy 349.880682 -214.488776)
			(xy 349.890588 -214.466424) (xy 349.676974 -214.061294) (xy 349.652844 -214.056722) (xy 349.627913 -214.051663)
			(xy 349.579899 -214.034858) (xy 349.535039 -214.010874) (xy 349.494397 -213.980281) (xy 349.458939 -213.943805)
			(xy 349.429509 -213.902313) (xy 349.406805 -213.856791) (xy 349.391367 -213.80832) (xy 349.383562 -213.758053)
			(xy 349.383096 -213.732618) (xy 348.162372 -213.732618) (xy 348.162023 -213.755595) (xy 348.155702 -213.801111)
			(xy 348.143116 -213.845306) (xy 348.134178 -213.866476) (xy 348.124272 -213.888828) (xy 348.337886 -214.293958)
			(xy 348.362016 -214.29853) (xy 348.38693 -214.303664) (xy 348.43494 -214.320459) (xy 348.479799 -214.344434)
			(xy 348.520441 -214.375017) (xy 348.555899 -214.411484) (xy 348.585332 -214.452967) (xy 348.60804 -214.49848)
			(xy 348.623483 -214.546942) (xy 348.631295 -214.597202) (xy 348.631764 -214.622634) (xy 348.631256 -214.648521)
			(xy 348.623157 -214.699659) (xy 348.607158 -214.748899) (xy 348.583652 -214.795031) (xy 348.55322 -214.836918)
			(xy 348.51661 -214.873528) (xy 348.474723 -214.90396) (xy 348.428591 -214.927466) (xy 348.379351 -214.943465)
			(xy 348.328213 -214.951564) (xy 348.276439 -214.951564) (xy 348.225301 -214.943465) (xy 348.176061 -214.927466)
			(xy 348.129929 -214.90396) (xy 348.088042 -214.873528) (xy 348.051432 -214.836918) (xy 348.021 -214.795031)
			(xy 347.997494 -214.748899) (xy 347.981495 -214.699659) (xy 347.973396 -214.648521) (xy 347.972888 -214.622634)
			(xy 347.973258 -214.599658) (xy 347.97957 -214.554143) (xy 347.992148 -214.509947) (xy 348.001082 -214.488776)
			(xy 348.010988 -214.466424) (xy 347.797374 -214.061294) (xy 347.773244 -214.056722) (xy 347.748313 -214.051663)
			(xy 347.700299 -214.034858) (xy 347.655439 -214.010874) (xy 347.614797 -213.980281) (xy 347.579339 -213.943805)
			(xy 347.549909 -213.902313) (xy 347.527205 -213.856791) (xy 347.511767 -213.80832) (xy 347.503962 -213.758053)
			(xy 347.503496 -213.732618) (xy 346.282772 -213.732618) (xy 346.282423 -213.755595) (xy 346.276102 -213.801111)
			(xy 346.263516 -213.845306) (xy 346.254578 -213.866476) (xy 346.244672 -213.888828) (xy 346.458286 -214.293958)
			(xy 346.482416 -214.29853) (xy 346.50733 -214.303664) (xy 346.55534 -214.320459) (xy 346.600199 -214.344434)
			(xy 346.640841 -214.375017) (xy 346.676299 -214.411484) (xy 346.705732 -214.452967) (xy 346.72844 -214.49848)
			(xy 346.743883 -214.546942) (xy 346.751695 -214.597202) (xy 346.752164 -214.622634) (xy 346.751656 -214.648521)
			(xy 346.743557 -214.699659) (xy 346.727558 -214.748899) (xy 346.704052 -214.795031) (xy 346.67362 -214.836918)
			(xy 346.63701 -214.873528) (xy 346.595123 -214.90396) (xy 346.548991 -214.927466) (xy 346.499751 -214.943465)
			(xy 346.448613 -214.951564) (xy 346.396839 -214.951564) (xy 346.345701 -214.943465) (xy 346.296461 -214.927466)
			(xy 346.250329 -214.90396) (xy 346.208442 -214.873528) (xy 346.171832 -214.836918) (xy 346.1414 -214.795031)
			(xy 346.117894 -214.748899) (xy 346.101895 -214.699659) (xy 346.093796 -214.648521) (xy 346.093288 -214.622634)
			(xy 346.093658 -214.599658) (xy 346.09997 -214.554143) (xy 346.112548 -214.509947) (xy 346.121482 -214.488776)
			(xy 346.131388 -214.466424) (xy 345.917774 -214.061294) (xy 345.893644 -214.056722) (xy 345.868713 -214.051663)
			(xy 345.820699 -214.034858) (xy 345.775839 -214.010874) (xy 345.735197 -213.980281) (xy 345.699739 -213.943805)
			(xy 345.670309 -213.902313) (xy 345.647605 -213.856791) (xy 345.632167 -213.80832) (xy 345.624362 -213.758053)
			(xy 345.623896 -213.732618) (xy 344.403172 -213.732618) (xy 344.402823 -213.755595) (xy 344.396502 -213.801111)
			(xy 344.383916 -213.845306) (xy 344.374978 -213.866476) (xy 344.365072 -213.888828) (xy 344.578686 -214.293958)
			(xy 344.602816 -214.29853) (xy 344.62773 -214.303664) (xy 344.67574 -214.320459) (xy 344.720599 -214.344434)
			(xy 344.761241 -214.375017) (xy 344.796699 -214.411484) (xy 344.826132 -214.452967) (xy 344.84884 -214.49848)
			(xy 344.864283 -214.546942) (xy 344.872095 -214.597202) (xy 344.872564 -214.622634) (xy 344.872056 -214.648521)
			(xy 344.863957 -214.699659) (xy 344.847958 -214.748899) (xy 344.824452 -214.795031) (xy 344.79402 -214.836918)
			(xy 344.75741 -214.873528) (xy 344.715523 -214.90396) (xy 344.669391 -214.927466) (xy 344.620151 -214.943465)
			(xy 344.569013 -214.951564) (xy 344.517239 -214.951564) (xy 344.466101 -214.943465) (xy 344.416861 -214.927466)
			(xy 344.370729 -214.90396) (xy 344.328842 -214.873528) (xy 344.292232 -214.836918) (xy 344.2618 -214.795031)
			(xy 344.238294 -214.748899) (xy 344.222295 -214.699659) (xy 344.214196 -214.648521) (xy 344.213688 -214.622634)
			(xy 344.214058 -214.599658) (xy 344.22037 -214.554143) (xy 344.232948 -214.509947) (xy 344.241882 -214.488776)
			(xy 344.251788 -214.466424) (xy 344.038174 -214.061294) (xy 344.014044 -214.056722) (xy 343.989113 -214.051663)
			(xy 343.941099 -214.034858) (xy 343.896239 -214.010874) (xy 343.855597 -213.980281) (xy 343.820139 -213.943805)
			(xy 343.790709 -213.902313) (xy 343.768005 -213.856791) (xy 343.752567 -213.80832) (xy 343.744762 -213.758053)
			(xy 343.744296 -213.732618) (xy 342.523572 -213.732618) (xy 342.523223 -213.755595) (xy 342.516902 -213.801111)
			(xy 342.504316 -213.845306) (xy 342.495378 -213.866476) (xy 342.485472 -213.888828) (xy 342.699086 -214.293958)
			(xy 342.723216 -214.29853) (xy 342.74813 -214.303664) (xy 342.79614 -214.320459) (xy 342.840999 -214.344434)
			(xy 342.881641 -214.375017) (xy 342.917099 -214.411484) (xy 342.946532 -214.452967) (xy 342.96924 -214.49848)
			(xy 342.984683 -214.546942) (xy 342.992495 -214.597202) (xy 342.992964 -214.622634) (xy 342.992456 -214.648521)
			(xy 342.984357 -214.699659) (xy 342.968358 -214.748899) (xy 342.944852 -214.795031) (xy 342.91442 -214.836918)
			(xy 342.87781 -214.873528) (xy 342.835923 -214.90396) (xy 342.789791 -214.927466) (xy 342.740551 -214.943465)
			(xy 342.689413 -214.951564) (xy 342.637639 -214.951564) (xy 342.586501 -214.943465) (xy 342.537261 -214.927466)
			(xy 342.491129 -214.90396) (xy 342.449242 -214.873528) (xy 342.412632 -214.836918) (xy 342.3822 -214.795031)
			(xy 342.358694 -214.748899) (xy 342.342695 -214.699659) (xy 342.334596 -214.648521) (xy 342.334088 -214.622634)
			(xy 342.334458 -214.599658) (xy 342.34077 -214.554143) (xy 342.353348 -214.509947) (xy 342.362282 -214.488776)
			(xy 342.372188 -214.466424) (xy 342.158574 -214.061294) (xy 342.134444 -214.056722) (xy 342.109513 -214.051663)
			(xy 342.061499 -214.034858) (xy 342.016639 -214.010874) (xy 341.975997 -213.980281) (xy 341.940539 -213.943805)
			(xy 341.911109 -213.902313) (xy 341.888405 -213.856791) (xy 341.872967 -213.80832) (xy 341.865162 -213.758053)
			(xy 341.864696 -213.732618) (xy 340.643972 -213.732618) (xy 340.643623 -213.755595) (xy 340.637302 -213.801111)
			(xy 340.624716 -213.845306) (xy 340.615778 -213.866476) (xy 340.605872 -213.888828) (xy 340.819486 -214.293958)
			(xy 340.843616 -214.29853) (xy 340.86853 -214.303664) (xy 340.91654 -214.320459) (xy 340.961399 -214.344434)
			(xy 341.002041 -214.375017) (xy 341.037499 -214.411484) (xy 341.066932 -214.452967) (xy 341.08964 -214.49848)
			(xy 341.105083 -214.546942) (xy 341.112895 -214.597202) (xy 341.113364 -214.622634) (xy 341.112856 -214.648521)
			(xy 341.104757 -214.699659) (xy 341.088758 -214.748899) (xy 341.065252 -214.795031) (xy 341.03482 -214.836918)
			(xy 340.99821 -214.873528) (xy 340.956323 -214.90396) (xy 340.910191 -214.927466) (xy 340.860951 -214.943465)
			(xy 340.809813 -214.951564) (xy 340.758039 -214.951564) (xy 340.706901 -214.943465) (xy 340.657661 -214.927466)
			(xy 340.611529 -214.90396) (xy 340.569642 -214.873528) (xy 340.533032 -214.836918) (xy 340.5026 -214.795031)
			(xy 340.479094 -214.748899) (xy 340.463095 -214.699659) (xy 340.454996 -214.648521) (xy 340.454488 -214.622634)
			(xy 340.454858 -214.599658) (xy 340.46117 -214.554143) (xy 340.473748 -214.509947) (xy 340.482682 -214.488776)
			(xy 340.492588 -214.466424) (xy 340.278974 -214.061294) (xy 340.254844 -214.056722) (xy 340.229913 -214.051663)
			(xy 340.181899 -214.034858) (xy 340.137039 -214.010874) (xy 340.096397 -213.980281) (xy 340.060939 -213.943805)
			(xy 340.031509 -213.902313) (xy 340.008805 -213.856791) (xy 339.993367 -213.80832) (xy 339.985562 -213.758053)
			(xy 339.985096 -213.732618) (xy 338.764372 -213.732618) (xy 338.764023 -213.755595) (xy 338.757702 -213.801111)
			(xy 338.745116 -213.845306) (xy 338.736178 -213.866476) (xy 338.726272 -213.888828) (xy 338.939886 -214.293958)
			(xy 338.964016 -214.29853) (xy 338.98893 -214.303664) (xy 339.03694 -214.320459) (xy 339.081799 -214.344434)
			(xy 339.122441 -214.375017) (xy 339.157899 -214.411484) (xy 339.187332 -214.452967) (xy 339.21004 -214.49848)
			(xy 339.225483 -214.546942) (xy 339.233295 -214.597202) (xy 339.233764 -214.622634) (xy 339.233256 -214.648521)
			(xy 339.225157 -214.699659) (xy 339.209158 -214.748899) (xy 339.185652 -214.795031) (xy 339.15522 -214.836918)
			(xy 339.11861 -214.873528) (xy 339.076723 -214.90396) (xy 339.030591 -214.927466) (xy 338.981351 -214.943465)
			(xy 338.930213 -214.951564) (xy 338.878439 -214.951564) (xy 338.827301 -214.943465) (xy 338.778061 -214.927466)
			(xy 338.731929 -214.90396) (xy 338.690042 -214.873528) (xy 338.653432 -214.836918) (xy 338.623 -214.795031)
			(xy 338.599494 -214.748899) (xy 338.583495 -214.699659) (xy 338.575396 -214.648521) (xy 338.574888 -214.622634)
			(xy 338.575258 -214.599658) (xy 338.58157 -214.554143) (xy 338.594148 -214.509947) (xy 338.603082 -214.488776)
			(xy 338.612988 -214.466424) (xy 338.399374 -214.061294) (xy 338.375244 -214.056722) (xy 338.350313 -214.051663)
			(xy 338.302299 -214.034858) (xy 338.257439 -214.010874) (xy 338.216797 -213.980281) (xy 338.181339 -213.943805)
			(xy 338.151909 -213.902313) (xy 338.129205 -213.856791) (xy 338.113767 -213.80832) (xy 338.105962 -213.758053)
			(xy 338.105496 -213.732618) (xy 132.175504 -213.732618) (xy 132.175153 -213.755595) (xy 132.168832 -213.80111)
			(xy 132.156248 -213.845306) (xy 132.14731 -213.866476) (xy 132.137404 -213.888828) (xy 132.351018 -214.293958)
			(xy 132.375148 -214.29853) (xy 132.400067 -214.303641) (xy 132.448077 -214.320441) (xy 132.492936 -214.344419)
			(xy 132.533576 -214.375006) (xy 132.569034 -214.411476) (xy 132.598466 -214.452961) (xy 132.621173 -214.498476)
			(xy 132.636615 -214.54694) (xy 132.644427 -214.597201) (xy 132.644896 -214.622634) (xy 132.644388 -214.648521)
			(xy 132.636289 -214.699659) (xy 132.62029 -214.748899) (xy 132.596784 -214.795031) (xy 132.566352 -214.836918)
			(xy 132.529742 -214.873528) (xy 132.487855 -214.90396) (xy 132.441723 -214.927466) (xy 132.392483 -214.943465)
			(xy 132.341345 -214.951564) (xy 132.289571 -214.951564) (xy 132.238433 -214.943465) (xy 132.189193 -214.927466)
			(xy 132.143061 -214.90396) (xy 132.101174 -214.873528) (xy 132.064564 -214.836918) (xy 132.034132 -214.795031)
			(xy 132.010626 -214.748899) (xy 131.994627 -214.699659) (xy 131.986528 -214.648521) (xy 131.98602 -214.622634)
			(xy 131.986387 -214.599658) (xy 131.9927 -214.554143) (xy 132.005279 -214.509947) (xy 132.014214 -214.488776)
			(xy 132.02412 -214.466424) (xy 131.810506 -214.061294) (xy 131.786376 -214.056722) (xy 131.76145 -214.051639)
			(xy 131.713436 -214.034839) (xy 131.668575 -214.010859) (xy 131.627932 -213.980269) (xy 131.592474 -213.943796)
			(xy 131.563043 -213.902307) (xy 131.540338 -213.856787) (xy 131.5249 -213.808318) (xy 131.517094 -213.758052)
			(xy 131.516628 -213.732618) (xy 130.295904 -213.732618) (xy 130.295553 -213.755595) (xy 130.289232 -213.80111)
			(xy 130.276648 -213.845306) (xy 130.26771 -213.866476) (xy 130.257804 -213.888828) (xy 130.471418 -214.293958)
			(xy 130.495548 -214.29853) (xy 130.520467 -214.303641) (xy 130.568477 -214.320441) (xy 130.613336 -214.344419)
			(xy 130.653976 -214.375006) (xy 130.689434 -214.411476) (xy 130.718866 -214.452961) (xy 130.741573 -214.498476)
			(xy 130.757015 -214.54694) (xy 130.764827 -214.597201) (xy 130.765296 -214.622634) (xy 130.764788 -214.648521)
			(xy 130.756689 -214.699659) (xy 130.74069 -214.748899) (xy 130.717184 -214.795031) (xy 130.686752 -214.836918)
			(xy 130.650142 -214.873528) (xy 130.608255 -214.90396) (xy 130.562123 -214.927466) (xy 130.512883 -214.943465)
			(xy 130.461745 -214.951564) (xy 130.409971 -214.951564) (xy 130.358833 -214.943465) (xy 130.309593 -214.927466)
			(xy 130.263461 -214.90396) (xy 130.221574 -214.873528) (xy 130.184964 -214.836918) (xy 130.154532 -214.795031)
			(xy 130.131026 -214.748899) (xy 130.115027 -214.699659) (xy 130.106928 -214.648521) (xy 130.10642 -214.622634)
			(xy 130.106787 -214.599658) (xy 130.1131 -214.554143) (xy 130.125679 -214.509947) (xy 130.134614 -214.488776)
			(xy 130.14452 -214.466424) (xy 129.930906 -214.061294) (xy 129.906776 -214.056722) (xy 129.88185 -214.051639)
			(xy 129.833836 -214.034839) (xy 129.788975 -214.010859) (xy 129.748332 -213.980269) (xy 129.712874 -213.943796)
			(xy 129.683443 -213.902307) (xy 129.660738 -213.856787) (xy 129.6453 -213.808318) (xy 129.637494 -213.758052)
			(xy 129.637028 -213.732618) (xy 128.416304 -213.732618) (xy 128.415953 -213.755595) (xy 128.409632 -213.80111)
			(xy 128.397048 -213.845306) (xy 128.38811 -213.866476) (xy 128.378204 -213.888828) (xy 128.591818 -214.293958)
			(xy 128.615948 -214.29853) (xy 128.640867 -214.303641) (xy 128.688877 -214.320441) (xy 128.733736 -214.344419)
			(xy 128.774376 -214.375006) (xy 128.809834 -214.411476) (xy 128.839266 -214.452961) (xy 128.861973 -214.498476)
			(xy 128.877415 -214.54694) (xy 128.885227 -214.597201) (xy 128.885696 -214.622634) (xy 128.885188 -214.648521)
			(xy 128.877089 -214.699659) (xy 128.86109 -214.748899) (xy 128.837584 -214.795031) (xy 128.807152 -214.836918)
			(xy 128.770542 -214.873528) (xy 128.728655 -214.90396) (xy 128.682523 -214.927466) (xy 128.633283 -214.943465)
			(xy 128.582145 -214.951564) (xy 128.530371 -214.951564) (xy 128.479233 -214.943465) (xy 128.429993 -214.927466)
			(xy 128.383861 -214.90396) (xy 128.341974 -214.873528) (xy 128.305364 -214.836918) (xy 128.274932 -214.795031)
			(xy 128.251426 -214.748899) (xy 128.235427 -214.699659) (xy 128.227328 -214.648521) (xy 128.22682 -214.622634)
			(xy 128.227187 -214.599658) (xy 128.2335 -214.554143) (xy 128.246079 -214.509947) (xy 128.255014 -214.488776)
			(xy 128.26492 -214.466424) (xy 128.051306 -214.061294) (xy 128.027176 -214.056722) (xy 128.00225 -214.051639)
			(xy 127.954236 -214.034839) (xy 127.909375 -214.010859) (xy 127.868732 -213.980269) (xy 127.833274 -213.943796)
			(xy 127.803843 -213.902307) (xy 127.781138 -213.856787) (xy 127.7657 -213.808318) (xy 127.757894 -213.758052)
			(xy 127.757428 -213.732618) (xy 126.536704 -213.732618) (xy 126.536283 -213.755559) (xy 126.529855 -213.80099)
			(xy 126.517209 -213.845096) (xy 126.508256 -213.866222) (xy 126.49835 -213.888574) (xy 126.712218 -214.293958)
			(xy 126.736348 -214.29853) (xy 126.761267 -214.303641) (xy 126.809277 -214.320441) (xy 126.854136 -214.344419)
			(xy 126.894776 -214.375006) (xy 126.930234 -214.411476) (xy 126.959666 -214.452961) (xy 126.982373 -214.498476)
			(xy 126.997815 -214.54694) (xy 127.005627 -214.597201) (xy 127.006096 -214.622634) (xy 127.005588 -214.648521)
			(xy 126.997489 -214.699659) (xy 126.98149 -214.748899) (xy 126.957984 -214.795031) (xy 126.927552 -214.836918)
			(xy 126.890942 -214.873528) (xy 126.849055 -214.90396) (xy 126.802923 -214.927466) (xy 126.753683 -214.943465)
			(xy 126.702545 -214.951564) (xy 126.650771 -214.951564) (xy 126.599633 -214.943465) (xy 126.550393 -214.927466)
			(xy 126.504261 -214.90396) (xy 126.462374 -214.873528) (xy 126.425764 -214.836918) (xy 126.395332 -214.795031)
			(xy 126.371826 -214.748899) (xy 126.355827 -214.699659) (xy 126.347728 -214.648521) (xy 126.34722 -214.622634)
			(xy 126.347587 -214.599658) (xy 126.3539 -214.554143) (xy 126.366479 -214.509947) (xy 126.375414 -214.488776)
			(xy 126.38532 -214.466424) (xy 126.171706 -214.061294) (xy 126.147576 -214.056722) (xy 126.12262 -214.051672)
			(xy 126.074538 -214.034924) (xy 126.029605 -214.010979) (xy 125.98889 -213.980407) (xy 125.953363 -213.943936)
			(xy 125.92387 -213.902434) (xy 125.901111 -213.856888) (xy 125.88563 -213.808384) (xy 125.877795 -213.758075)
			(xy 125.87732 -213.732618) (xy 124.657104 -213.732618) (xy 124.656681 -213.756953) (xy 124.649527 -213.805095)
			(xy 124.635379 -213.851663) (xy 124.625354 -213.873842) (xy 124.614432 -213.896448) (xy 124.820172 -214.292942)
			(xy 124.845826 -214.296752) (xy 124.87151 -214.301109) (xy 124.921167 -214.316849) (xy 124.967731 -214.340204)
			(xy 125.010041 -214.370592) (xy 125.047044 -214.407258) (xy 125.077819 -214.449288) (xy 125.101599 -214.495635)
			(xy 125.117793 -214.545146) (xy 125.125998 -214.596588) (xy 125.126496 -214.622634) (xy 125.125988 -214.648521)
			(xy 125.117889 -214.699659) (xy 125.10189 -214.748899) (xy 125.078384 -214.795031) (xy 125.047952 -214.836918)
			(xy 125.011342 -214.873528) (xy 124.969455 -214.90396) (xy 124.923323 -214.927466) (xy 124.874083 -214.943465)
			(xy 124.822945 -214.951564) (xy 124.771171 -214.951564) (xy 124.720033 -214.943465) (xy 124.670793 -214.927466)
			(xy 124.624661 -214.90396) (xy 124.582774 -214.873528) (xy 124.546164 -214.836918) (xy 124.515732 -214.795031)
			(xy 124.492226 -214.748899) (xy 124.476227 -214.699659) (xy 124.468128 -214.648521) (xy 124.46762 -214.622634)
			(xy 124.468099 -214.597068) (xy 124.476002 -214.546552) (xy 124.491623 -214.497866) (xy 124.502672 -214.474806)
			(xy 124.514102 -214.451438) (xy 124.31268 -214.062818) (xy 124.28601 -214.059516) (xy 124.259814 -214.055663)
			(xy 124.20902 -214.04073) (xy 124.161267 -214.017866) (xy 124.117785 -213.987661) (xy 124.079693 -213.950891)
			(xy 124.047971 -213.908503) (xy 124.023436 -213.861587) (xy 124.006718 -213.811352) (xy 123.998249 -213.75909)
			(xy 123.99772 -213.732618) (xy 122.777504 -213.732618) (xy 122.777153 -213.755595) (xy 122.770832 -213.80111)
			(xy 122.758248 -213.845306) (xy 122.74931 -213.866476) (xy 122.739404 -213.888828) (xy 122.953018 -214.293958)
			(xy 122.977148 -214.29853) (xy 123.002067 -214.303641) (xy 123.050077 -214.320441) (xy 123.094936 -214.344419)
			(xy 123.135576 -214.375006) (xy 123.171034 -214.411476) (xy 123.200466 -214.452961) (xy 123.223173 -214.498476)
			(xy 123.238615 -214.54694) (xy 123.246427 -214.597201) (xy 123.246896 -214.622634) (xy 123.246388 -214.648521)
			(xy 123.238289 -214.699659) (xy 123.22229 -214.748899) (xy 123.198784 -214.795031) (xy 123.168352 -214.836918)
			(xy 123.131742 -214.873528) (xy 123.089855 -214.90396) (xy 123.043723 -214.927466) (xy 122.994483 -214.943465)
			(xy 122.943345 -214.951564) (xy 122.891571 -214.951564) (xy 122.840433 -214.943465) (xy 122.791193 -214.927466)
			(xy 122.745061 -214.90396) (xy 122.703174 -214.873528) (xy 122.666564 -214.836918) (xy 122.636132 -214.795031)
			(xy 122.612626 -214.748899) (xy 122.596627 -214.699659) (xy 122.588528 -214.648521) (xy 122.58802 -214.622634)
			(xy 122.588387 -214.599658) (xy 122.5947 -214.554143) (xy 122.607279 -214.509947) (xy 122.616214 -214.488776)
			(xy 122.62612 -214.466424) (xy 122.412506 -214.061294) (xy 122.388376 -214.056722) (xy 122.36345 -214.051639)
			(xy 122.315436 -214.034839) (xy 122.270575 -214.010859) (xy 122.229932 -213.980269) (xy 122.194474 -213.943796)
			(xy 122.165043 -213.902307) (xy 122.142338 -213.856787) (xy 122.1269 -213.808318) (xy 122.119094 -213.758052)
			(xy 122.118628 -213.732618) (xy 120.897904 -213.732618) (xy 120.897553 -213.755595) (xy 120.891232 -213.80111)
			(xy 120.878648 -213.845306) (xy 120.86971 -213.866476) (xy 120.859804 -213.888828) (xy 121.073418 -214.293958)
			(xy 121.097548 -214.29853) (xy 121.122467 -214.303641) (xy 121.170477 -214.320441) (xy 121.215336 -214.344419)
			(xy 121.255976 -214.375006) (xy 121.291434 -214.411476) (xy 121.320866 -214.452961) (xy 121.343573 -214.498476)
			(xy 121.359015 -214.54694) (xy 121.366827 -214.597201) (xy 121.367296 -214.622634) (xy 121.366788 -214.648521)
			(xy 121.358689 -214.699659) (xy 121.34269 -214.748899) (xy 121.319184 -214.795031) (xy 121.288752 -214.836918)
			(xy 121.252142 -214.873528) (xy 121.210255 -214.90396) (xy 121.164123 -214.927466) (xy 121.114883 -214.943465)
			(xy 121.063745 -214.951564) (xy 121.011971 -214.951564) (xy 120.960833 -214.943465) (xy 120.911593 -214.927466)
			(xy 120.865461 -214.90396) (xy 120.823574 -214.873528) (xy 120.786964 -214.836918) (xy 120.756532 -214.795031)
			(xy 120.733026 -214.748899) (xy 120.717027 -214.699659) (xy 120.708928 -214.648521) (xy 120.70842 -214.622634)
			(xy 120.708787 -214.599658) (xy 120.7151 -214.554143) (xy 120.727679 -214.509947) (xy 120.736614 -214.488776)
			(xy 120.74652 -214.466424) (xy 120.532906 -214.061294) (xy 120.508776 -214.056722) (xy 120.48385 -214.051639)
			(xy 120.435836 -214.034839) (xy 120.390975 -214.010859) (xy 120.350332 -213.980269) (xy 120.314874 -213.943796)
			(xy 120.285443 -213.902307) (xy 120.262738 -213.856787) (xy 120.2473 -213.808318) (xy 120.239494 -213.758052)
			(xy 120.239028 -213.732618) (xy 119.018304 -213.732618) (xy 119.017953 -213.755595) (xy 119.011632 -213.80111)
			(xy 118.999048 -213.845306) (xy 118.99011 -213.866476) (xy 118.980204 -213.888828) (xy 119.193818 -214.293958)
			(xy 119.217948 -214.29853) (xy 119.242867 -214.303641) (xy 119.290877 -214.320441) (xy 119.335736 -214.344419)
			(xy 119.376376 -214.375006) (xy 119.411834 -214.411476) (xy 119.441266 -214.452961) (xy 119.463973 -214.498476)
			(xy 119.479415 -214.54694) (xy 119.487227 -214.597201) (xy 119.487696 -214.622634) (xy 119.487188 -214.648521)
			(xy 119.479089 -214.699659) (xy 119.46309 -214.748899) (xy 119.439584 -214.795031) (xy 119.409152 -214.836918)
			(xy 119.372542 -214.873528) (xy 119.330655 -214.90396) (xy 119.284523 -214.927466) (xy 119.235283 -214.943465)
			(xy 119.184145 -214.951564) (xy 119.132371 -214.951564) (xy 119.081233 -214.943465) (xy 119.031993 -214.927466)
			(xy 118.985861 -214.90396) (xy 118.943974 -214.873528) (xy 118.907364 -214.836918) (xy 118.876932 -214.795031)
			(xy 118.853426 -214.748899) (xy 118.837427 -214.699659) (xy 118.829328 -214.648521) (xy 118.82882 -214.622634)
			(xy 118.829187 -214.599658) (xy 118.8355 -214.554143) (xy 118.848079 -214.509947) (xy 118.857014 -214.488776)
			(xy 118.86692 -214.466424) (xy 118.653306 -214.061294) (xy 118.629176 -214.056722) (xy 118.60425 -214.051639)
			(xy 118.556236 -214.034839) (xy 118.511375 -214.010859) (xy 118.470732 -213.980269) (xy 118.435274 -213.943796)
			(xy 118.405843 -213.902307) (xy 118.383138 -213.856787) (xy 118.3677 -213.808318) (xy 118.359894 -213.758052)
			(xy 118.359428 -213.732618) (xy 117.138704 -213.732618) (xy 117.138353 -213.755595) (xy 117.132032 -213.80111)
			(xy 117.119448 -213.845306) (xy 117.11051 -213.866476) (xy 117.100604 -213.888828) (xy 117.314218 -214.293958)
			(xy 117.338348 -214.29853) (xy 117.363267 -214.303641) (xy 117.411277 -214.320441) (xy 117.456136 -214.344419)
			(xy 117.496776 -214.375006) (xy 117.532234 -214.411476) (xy 117.561666 -214.452961) (xy 117.584373 -214.498476)
			(xy 117.599815 -214.54694) (xy 117.607627 -214.597201) (xy 117.608096 -214.622634) (xy 117.607588 -214.648521)
			(xy 117.599489 -214.699659) (xy 117.58349 -214.748899) (xy 117.559984 -214.795031) (xy 117.529552 -214.836918)
			(xy 117.492942 -214.873528) (xy 117.451055 -214.90396) (xy 117.404923 -214.927466) (xy 117.355683 -214.943465)
			(xy 117.304545 -214.951564) (xy 117.252771 -214.951564) (xy 117.201633 -214.943465) (xy 117.152393 -214.927466)
			(xy 117.106261 -214.90396) (xy 117.064374 -214.873528) (xy 117.027764 -214.836918) (xy 116.997332 -214.795031)
			(xy 116.973826 -214.748899) (xy 116.957827 -214.699659) (xy 116.949728 -214.648521) (xy 116.94922 -214.622634)
			(xy 116.949587 -214.599658) (xy 116.9559 -214.554143) (xy 116.968479 -214.509947) (xy 116.977414 -214.488776)
			(xy 116.98732 -214.466424) (xy 116.773706 -214.061294) (xy 116.749576 -214.056722) (xy 116.72465 -214.051639)
			(xy 116.676636 -214.034839) (xy 116.631775 -214.010859) (xy 116.591132 -213.980269) (xy 116.555674 -213.943796)
			(xy 116.526243 -213.902307) (xy 116.503538 -213.856787) (xy 116.4881 -213.808318) (xy 116.480294 -213.758052)
			(xy 116.479828 -213.732618) (xy 115.259104 -213.732618) (xy 115.258753 -213.755595) (xy 115.252432 -213.80111)
			(xy 115.239848 -213.845306) (xy 115.23091 -213.866476) (xy 115.221004 -213.888828) (xy 115.434618 -214.293958)
			(xy 115.458748 -214.29853) (xy 115.483667 -214.303641) (xy 115.531677 -214.320441) (xy 115.576536 -214.344419)
			(xy 115.617176 -214.375006) (xy 115.652634 -214.411476) (xy 115.682066 -214.452961) (xy 115.704773 -214.498476)
			(xy 115.720215 -214.54694) (xy 115.728027 -214.597201) (xy 115.728496 -214.622634) (xy 115.727988 -214.648521)
			(xy 115.719889 -214.699659) (xy 115.70389 -214.748899) (xy 115.680384 -214.795031) (xy 115.649952 -214.836918)
			(xy 115.613342 -214.873528) (xy 115.571455 -214.90396) (xy 115.525323 -214.927466) (xy 115.476083 -214.943465)
			(xy 115.424945 -214.951564) (xy 115.373171 -214.951564) (xy 115.322033 -214.943465) (xy 115.272793 -214.927466)
			(xy 115.226661 -214.90396) (xy 115.184774 -214.873528) (xy 115.148164 -214.836918) (xy 115.117732 -214.795031)
			(xy 115.094226 -214.748899) (xy 115.078227 -214.699659) (xy 115.070128 -214.648521) (xy 115.06962 -214.622634)
			(xy 115.069987 -214.599658) (xy 115.0763 -214.554143) (xy 115.088879 -214.509947) (xy 115.097814 -214.488776)
			(xy 115.10772 -214.466424) (xy 114.894106 -214.061294) (xy 114.869976 -214.056722) (xy 114.84505 -214.051639)
			(xy 114.797036 -214.034839) (xy 114.752175 -214.010859) (xy 114.711532 -213.980269) (xy 114.676074 -213.943796)
			(xy 114.646643 -213.902307) (xy 114.623938 -213.856787) (xy 114.6085 -213.808318) (xy 114.600694 -213.758052)
			(xy 114.600228 -213.732618) (xy 107.740704 -213.732618) (xy 107.740353 -213.755595) (xy 107.734032 -213.80111)
			(xy 107.721448 -213.845306) (xy 107.71251 -213.866476) (xy 107.702604 -213.888828) (xy 107.916218 -214.293958)
			(xy 107.940348 -214.29853) (xy 107.965267 -214.303641) (xy 108.013277 -214.320441) (xy 108.058136 -214.344419)
			(xy 108.098776 -214.375006) (xy 108.134234 -214.411476) (xy 108.163666 -214.452961) (xy 108.186373 -214.498476)
			(xy 108.201815 -214.54694) (xy 108.209627 -214.597201) (xy 108.210096 -214.622634) (xy 108.209588 -214.648521)
			(xy 108.201489 -214.699659) (xy 108.18549 -214.748899) (xy 108.161984 -214.795031) (xy 108.131552 -214.836918)
			(xy 108.094942 -214.873528) (xy 108.053055 -214.90396) (xy 108.006923 -214.927466) (xy 107.957683 -214.943465)
			(xy 107.906545 -214.951564) (xy 107.854771 -214.951564) (xy 107.803633 -214.943465) (xy 107.754393 -214.927466)
			(xy 107.708261 -214.90396) (xy 107.666374 -214.873528) (xy 107.629764 -214.836918) (xy 107.599332 -214.795031)
			(xy 107.575826 -214.748899) (xy 107.559827 -214.699659) (xy 107.551728 -214.648521) (xy 107.55122 -214.622634)
			(xy 107.551587 -214.599658) (xy 107.5579 -214.554143) (xy 107.570479 -214.509947) (xy 107.579414 -214.488776)
			(xy 107.58932 -214.466424) (xy 107.375706 -214.061294) (xy 107.351576 -214.056722) (xy 107.32665 -214.051639)
			(xy 107.278636 -214.034839) (xy 107.233775 -214.010859) (xy 107.193132 -213.980269) (xy 107.157674 -213.943796)
			(xy 107.128243 -213.902307) (xy 107.105538 -213.856787) (xy 107.0901 -213.808318) (xy 107.082294 -213.758052)
			(xy 107.081828 -213.732618) (xy 105.861104 -213.732618) (xy 105.860753 -213.755595) (xy 105.854432 -213.80111)
			(xy 105.841848 -213.845306) (xy 105.83291 -213.866476) (xy 105.823004 -213.888828) (xy 106.036618 -214.293958)
			(xy 106.060748 -214.29853) (xy 106.085667 -214.303641) (xy 106.133677 -214.320441) (xy 106.178536 -214.344419)
			(xy 106.219176 -214.375006) (xy 106.254634 -214.411476) (xy 106.284066 -214.452961) (xy 106.306773 -214.498476)
			(xy 106.322215 -214.54694) (xy 106.330027 -214.597201) (xy 106.330496 -214.622634) (xy 106.329988 -214.648521)
			(xy 106.321889 -214.699659) (xy 106.30589 -214.748899) (xy 106.282384 -214.795031) (xy 106.251952 -214.836918)
			(xy 106.215342 -214.873528) (xy 106.173455 -214.90396) (xy 106.127323 -214.927466) (xy 106.078083 -214.943465)
			(xy 106.026945 -214.951564) (xy 105.975171 -214.951564) (xy 105.924033 -214.943465) (xy 105.874793 -214.927466)
			(xy 105.828661 -214.90396) (xy 105.786774 -214.873528) (xy 105.750164 -214.836918) (xy 105.719732 -214.795031)
			(xy 105.696226 -214.748899) (xy 105.680227 -214.699659) (xy 105.672128 -214.648521) (xy 105.67162 -214.622634)
			(xy 105.671987 -214.599658) (xy 105.6783 -214.554143) (xy 105.690879 -214.509947) (xy 105.699814 -214.488776)
			(xy 105.70972 -214.466424) (xy 105.496106 -214.061294) (xy 105.471976 -214.056722) (xy 105.44705 -214.051639)
			(xy 105.399036 -214.034839) (xy 105.354175 -214.010859) (xy 105.313532 -213.980269) (xy 105.278074 -213.943796)
			(xy 105.248643 -213.902307) (xy 105.225938 -213.856787) (xy 105.2105 -213.808318) (xy 105.202694 -213.758052)
			(xy 105.202228 -213.732618) (xy 103.981504 -213.732618) (xy 103.981153 -213.755595) (xy 103.974832 -213.80111)
			(xy 103.962248 -213.845306) (xy 103.95331 -213.866476) (xy 103.943404 -213.888828) (xy 104.157018 -214.293958)
			(xy 104.181148 -214.29853) (xy 104.206067 -214.303641) (xy 104.254077 -214.320441) (xy 104.298936 -214.344419)
			(xy 104.339576 -214.375006) (xy 104.375034 -214.411476) (xy 104.404466 -214.452961) (xy 104.427173 -214.498476)
			(xy 104.442615 -214.54694) (xy 104.450427 -214.597201) (xy 104.450896 -214.622634) (xy 104.450388 -214.648521)
			(xy 104.442289 -214.699659) (xy 104.42629 -214.748899) (xy 104.402784 -214.795031) (xy 104.372352 -214.836918)
			(xy 104.335742 -214.873528) (xy 104.293855 -214.90396) (xy 104.247723 -214.927466) (xy 104.198483 -214.943465)
			(xy 104.147345 -214.951564) (xy 104.095571 -214.951564) (xy 104.044433 -214.943465) (xy 103.995193 -214.927466)
			(xy 103.949061 -214.90396) (xy 103.907174 -214.873528) (xy 103.870564 -214.836918) (xy 103.840132 -214.795031)
			(xy 103.816626 -214.748899) (xy 103.800627 -214.699659) (xy 103.792528 -214.648521) (xy 103.79202 -214.622634)
			(xy 103.792387 -214.599658) (xy 103.7987 -214.554143) (xy 103.811279 -214.509947) (xy 103.820214 -214.488776)
			(xy 103.83012 -214.466424) (xy 103.616506 -214.061294) (xy 103.592376 -214.056722) (xy 103.56745 -214.051639)
			(xy 103.519436 -214.034839) (xy 103.474575 -214.010859) (xy 103.433932 -213.980269) (xy 103.398474 -213.943796)
			(xy 103.369043 -213.902307) (xy 103.346338 -213.856787) (xy 103.3309 -213.808318) (xy 103.323094 -213.758052)
			(xy 103.322628 -213.732618) (xy 102.101904 -213.732618) (xy 102.101553 -213.755595) (xy 102.095232 -213.80111)
			(xy 102.082648 -213.845306) (xy 102.07371 -213.866476) (xy 102.063804 -213.888828) (xy 102.277418 -214.293958)
			(xy 102.301548 -214.29853) (xy 102.326467 -214.303641) (xy 102.374477 -214.320441) (xy 102.419336 -214.344419)
			(xy 102.459976 -214.375006) (xy 102.495434 -214.411476) (xy 102.524866 -214.452961) (xy 102.547573 -214.498476)
			(xy 102.563015 -214.54694) (xy 102.570827 -214.597201) (xy 102.571296 -214.622634) (xy 102.570788 -214.648521)
			(xy 102.562689 -214.699659) (xy 102.54669 -214.748899) (xy 102.523184 -214.795031) (xy 102.492752 -214.836918)
			(xy 102.456142 -214.873528) (xy 102.414255 -214.90396) (xy 102.368123 -214.927466) (xy 102.318883 -214.943465)
			(xy 102.267745 -214.951564) (xy 102.215971 -214.951564) (xy 102.164833 -214.943465) (xy 102.115593 -214.927466)
			(xy 102.069461 -214.90396) (xy 102.027574 -214.873528) (xy 101.990964 -214.836918) (xy 101.960532 -214.795031)
			(xy 101.937026 -214.748899) (xy 101.921027 -214.699659) (xy 101.912928 -214.648521) (xy 101.91242 -214.622634)
			(xy 101.912787 -214.599658) (xy 101.9191 -214.554143) (xy 101.931679 -214.509947) (xy 101.940614 -214.488776)
			(xy 101.95052 -214.466424) (xy 101.736906 -214.061294) (xy 101.712776 -214.056722) (xy 101.68785 -214.051639)
			(xy 101.639836 -214.034839) (xy 101.594975 -214.010859) (xy 101.554332 -213.980269) (xy 101.518874 -213.943796)
			(xy 101.489443 -213.902307) (xy 101.466738 -213.856787) (xy 101.4513 -213.808318) (xy 101.443494 -213.758052)
			(xy 101.443028 -213.732618) (xy 100.222304 -213.732618) (xy 100.221953 -213.755595) (xy 100.215632 -213.80111)
			(xy 100.203048 -213.845306) (xy 100.19411 -213.866476) (xy 100.184204 -213.888828) (xy 100.397818 -214.293958)
			(xy 100.421948 -214.29853) (xy 100.446867 -214.303641) (xy 100.494877 -214.320441) (xy 100.539736 -214.344419)
			(xy 100.580376 -214.375006) (xy 100.615834 -214.411476) (xy 100.645266 -214.452961) (xy 100.667973 -214.498476)
			(xy 100.683415 -214.54694) (xy 100.691227 -214.597201) (xy 100.691696 -214.622634) (xy 100.691188 -214.648521)
			(xy 100.683089 -214.699659) (xy 100.66709 -214.748899) (xy 100.643584 -214.795031) (xy 100.613152 -214.836918)
			(xy 100.576542 -214.873528) (xy 100.534655 -214.90396) (xy 100.488523 -214.927466) (xy 100.439283 -214.943465)
			(xy 100.388145 -214.951564) (xy 100.336371 -214.951564) (xy 100.285233 -214.943465) (xy 100.235993 -214.927466)
			(xy 100.189861 -214.90396) (xy 100.147974 -214.873528) (xy 100.111364 -214.836918) (xy 100.080932 -214.795031)
			(xy 100.057426 -214.748899) (xy 100.041427 -214.699659) (xy 100.033328 -214.648521) (xy 100.03282 -214.622634)
			(xy 100.033187 -214.599658) (xy 100.0395 -214.554143) (xy 100.052079 -214.509947) (xy 100.061014 -214.488776)
			(xy 100.07092 -214.466424) (xy 99.857306 -214.061294) (xy 99.833176 -214.056722) (xy 99.80825 -214.051639)
			(xy 99.760236 -214.034839) (xy 99.715375 -214.010859) (xy 99.674732 -213.980269) (xy 99.639274 -213.943796)
			(xy 99.609843 -213.902307) (xy 99.587138 -213.856787) (xy 99.5717 -213.808318) (xy 99.563894 -213.758052)
			(xy 99.563428 -213.732618) (xy 98.342704 -213.732618) (xy 98.342353 -213.755595) (xy 98.336032 -213.80111)
			(xy 98.323448 -213.845306) (xy 98.31451 -213.866476) (xy 98.304604 -213.888828) (xy 98.518218 -214.293958)
			(xy 98.542348 -214.29853) (xy 98.567267 -214.303641) (xy 98.615277 -214.320441) (xy 98.660136 -214.344419)
			(xy 98.700776 -214.375006) (xy 98.736234 -214.411476) (xy 98.765666 -214.452961) (xy 98.788373 -214.498476)
			(xy 98.803815 -214.54694) (xy 98.811627 -214.597201) (xy 98.812096 -214.622634) (xy 98.811588 -214.648521)
			(xy 98.803489 -214.699659) (xy 98.78749 -214.748899) (xy 98.763984 -214.795031) (xy 98.733552 -214.836918)
			(xy 98.696942 -214.873528) (xy 98.655055 -214.90396) (xy 98.608923 -214.927466) (xy 98.559683 -214.943465)
			(xy 98.508545 -214.951564) (xy 98.456771 -214.951564) (xy 98.405633 -214.943465) (xy 98.356393 -214.927466)
			(xy 98.310261 -214.90396) (xy 98.268374 -214.873528) (xy 98.231764 -214.836918) (xy 98.201332 -214.795031)
			(xy 98.177826 -214.748899) (xy 98.161827 -214.699659) (xy 98.153728 -214.648521) (xy 98.15322 -214.622634)
			(xy 98.153587 -214.599658) (xy 98.1599 -214.554143) (xy 98.172479 -214.509947) (xy 98.181414 -214.488776)
			(xy 98.19132 -214.466424) (xy 97.977706 -214.061294) (xy 97.953576 -214.056722) (xy 97.92865 -214.051639)
			(xy 97.880636 -214.034839) (xy 97.835775 -214.010859) (xy 97.795132 -213.980269) (xy 97.759674 -213.943796)
			(xy 97.730243 -213.902307) (xy 97.707538 -213.856787) (xy 97.6921 -213.808318) (xy 97.684294 -213.758052)
			(xy 97.683828 -213.732618) (xy 96.463104 -213.732618) (xy 96.462753 -213.755595) (xy 96.456432 -213.80111)
			(xy 96.443848 -213.845306) (xy 96.43491 -213.866476) (xy 96.425004 -213.888828) (xy 96.638618 -214.293958)
			(xy 96.662748 -214.29853) (xy 96.687667 -214.303641) (xy 96.735677 -214.320441) (xy 96.780536 -214.344419)
			(xy 96.821176 -214.375006) (xy 96.856634 -214.411476) (xy 96.886066 -214.452961) (xy 96.908773 -214.498476)
			(xy 96.924215 -214.54694) (xy 96.932027 -214.597201) (xy 96.932496 -214.622634) (xy 96.931988 -214.648521)
			(xy 96.923889 -214.699659) (xy 96.90789 -214.748899) (xy 96.884384 -214.795031) (xy 96.853952 -214.836918)
			(xy 96.817342 -214.873528) (xy 96.775455 -214.90396) (xy 96.729323 -214.927466) (xy 96.680083 -214.943465)
			(xy 96.628945 -214.951564) (xy 96.577171 -214.951564) (xy 96.526033 -214.943465) (xy 96.476793 -214.927466)
			(xy 96.430661 -214.90396) (xy 96.388774 -214.873528) (xy 96.352164 -214.836918) (xy 96.321732 -214.795031)
			(xy 96.298226 -214.748899) (xy 96.282227 -214.699659) (xy 96.274128 -214.648521) (xy 96.27362 -214.622634)
			(xy 96.273987 -214.599658) (xy 96.2803 -214.554143) (xy 96.292879 -214.509947) (xy 96.301814 -214.488776)
			(xy 96.31172 -214.466424) (xy 96.098106 -214.061294) (xy 96.073976 -214.056722) (xy 96.04905 -214.051639)
			(xy 96.001036 -214.034839) (xy 95.956175 -214.010859) (xy 95.915532 -213.980269) (xy 95.880074 -213.943796)
			(xy 95.850643 -213.902307) (xy 95.827938 -213.856787) (xy 95.8125 -213.808318) (xy 95.804694 -213.758052)
			(xy 95.804228 -213.732618) (xy 94.583504 -213.732618) (xy 94.583153 -213.755595) (xy 94.576832 -213.80111)
			(xy 94.564248 -213.845306) (xy 94.55531 -213.866476) (xy 94.545404 -213.888828) (xy 94.759018 -214.293958)
			(xy 94.783148 -214.29853) (xy 94.808067 -214.303641) (xy 94.856077 -214.320441) (xy 94.900936 -214.344419)
			(xy 94.941576 -214.375006) (xy 94.977034 -214.411476) (xy 95.006466 -214.452961) (xy 95.029173 -214.498476)
			(xy 95.044615 -214.54694) (xy 95.052427 -214.597201) (xy 95.052896 -214.622634) (xy 95.052388 -214.648521)
			(xy 95.044289 -214.699659) (xy 95.02829 -214.748899) (xy 95.004784 -214.795031) (xy 94.974352 -214.836918)
			(xy 94.937742 -214.873528) (xy 94.895855 -214.90396) (xy 94.849723 -214.927466) (xy 94.800483 -214.943465)
			(xy 94.749345 -214.951564) (xy 94.697571 -214.951564) (xy 94.646433 -214.943465) (xy 94.597193 -214.927466)
			(xy 94.551061 -214.90396) (xy 94.509174 -214.873528) (xy 94.472564 -214.836918) (xy 94.442132 -214.795031)
			(xy 94.418626 -214.748899) (xy 94.402627 -214.699659) (xy 94.394528 -214.648521) (xy 94.39402 -214.622634)
			(xy 94.394387 -214.599658) (xy 94.4007 -214.554143) (xy 94.413279 -214.509947) (xy 94.422214 -214.488776)
			(xy 94.43212 -214.466424) (xy 94.218506 -214.061294) (xy 94.194376 -214.056722) (xy 94.16945 -214.051639)
			(xy 94.121436 -214.034839) (xy 94.076575 -214.010859) (xy 94.035932 -213.980269) (xy 94.000474 -213.943796)
			(xy 93.971043 -213.902307) (xy 93.948338 -213.856787) (xy 93.9329 -213.808318) (xy 93.925094 -213.758052)
			(xy 93.924628 -213.732618) (xy 92.703904 -213.732618) (xy 92.703553 -213.755595) (xy 92.697232 -213.80111)
			(xy 92.684648 -213.845306) (xy 92.67571 -213.866476) (xy 92.665804 -213.888828) (xy 92.879418 -214.293958)
			(xy 92.903548 -214.29853) (xy 92.928467 -214.303641) (xy 92.976477 -214.320441) (xy 93.021336 -214.344419)
			(xy 93.061976 -214.375006) (xy 93.097434 -214.411476) (xy 93.126866 -214.452961) (xy 93.149573 -214.498476)
			(xy 93.165015 -214.54694) (xy 93.172827 -214.597201) (xy 93.173296 -214.622634) (xy 93.172788 -214.648521)
			(xy 93.164689 -214.699659) (xy 93.14869 -214.748899) (xy 93.125184 -214.795031) (xy 93.094752 -214.836918)
			(xy 93.058142 -214.873528) (xy 93.016255 -214.90396) (xy 92.970123 -214.927466) (xy 92.920883 -214.943465)
			(xy 92.869745 -214.951564) (xy 92.817971 -214.951564) (xy 92.766833 -214.943465) (xy 92.717593 -214.927466)
			(xy 92.671461 -214.90396) (xy 92.629574 -214.873528) (xy 92.592964 -214.836918) (xy 92.562532 -214.795031)
			(xy 92.539026 -214.748899) (xy 92.523027 -214.699659) (xy 92.514928 -214.648521) (xy 92.51442 -214.622634)
			(xy 92.514787 -214.599658) (xy 92.5211 -214.554143) (xy 92.533679 -214.509947) (xy 92.542614 -214.488776)
			(xy 92.55252 -214.466424) (xy 92.338906 -214.061294) (xy 92.314776 -214.056722) (xy 92.28985 -214.051639)
			(xy 92.241836 -214.034839) (xy 92.196975 -214.010859) (xy 92.156332 -213.980269) (xy 92.120874 -213.943796)
			(xy 92.091443 -213.902307) (xy 92.068738 -213.856787) (xy 92.0533 -213.808318) (xy 92.045494 -213.758052)
			(xy 92.045028 -213.732618) (xy 90.824304 -213.732618) (xy 90.823953 -213.755595) (xy 90.817632 -213.80111)
			(xy 90.805048 -213.845306) (xy 90.79611 -213.866476) (xy 90.786204 -213.888828) (xy 90.999818 -214.293958)
			(xy 91.023948 -214.29853) (xy 91.048867 -214.303641) (xy 91.096877 -214.320441) (xy 91.141736 -214.344419)
			(xy 91.182376 -214.375006) (xy 91.217834 -214.411476) (xy 91.247266 -214.452961) (xy 91.269973 -214.498476)
			(xy 91.285415 -214.54694) (xy 91.293227 -214.597201) (xy 91.293696 -214.622634) (xy 91.293188 -214.648521)
			(xy 91.285089 -214.699659) (xy 91.26909 -214.748899) (xy 91.245584 -214.795031) (xy 91.215152 -214.836918)
			(xy 91.178542 -214.873528) (xy 91.136655 -214.90396) (xy 91.090523 -214.927466) (xy 91.041283 -214.943465)
			(xy 90.990145 -214.951564) (xy 90.938371 -214.951564) (xy 90.887233 -214.943465) (xy 90.837993 -214.927466)
			(xy 90.791861 -214.90396) (xy 90.749974 -214.873528) (xy 90.713364 -214.836918) (xy 90.682932 -214.795031)
			(xy 90.659426 -214.748899) (xy 90.643427 -214.699659) (xy 90.635328 -214.648521) (xy 90.63482 -214.622634)
			(xy 90.635187 -214.599658) (xy 90.6415 -214.554143) (xy 90.654079 -214.509947) (xy 90.663014 -214.488776)
			(xy 90.67292 -214.466424) (xy 90.459306 -214.061294) (xy 90.435176 -214.056722) (xy 90.41025 -214.051639)
			(xy 90.362236 -214.034839) (xy 90.317375 -214.010859) (xy 90.276732 -213.980269) (xy 90.241274 -213.943796)
			(xy 90.211843 -213.902307) (xy 90.189138 -213.856787) (xy 90.1737 -213.808318) (xy 90.165894 -213.758052)
			(xy 90.165428 -213.732618) (xy 2.509012 -213.732618) (xy 2.509012 -214.521542) (xy 11.489436 -214.521542)
			(xy 11.489436 -214.112602) (xy 11.489935 -214.102445) (xy 11.497708 -214.083676) (xy 11.512073 -214.069311)
			(xy 11.530841 -214.061536) (xy 11.540998 -214.06104) (xy 12.940538 -214.06104) (xy 12.950698 -214.061502)
			(xy 12.969469 -214.06929) (xy 12.983833 -214.083665) (xy 12.991606 -214.102441) (xy 12.9921 -214.112602)
			(xy 12.9921 -214.521542) (xy 19.033236 -214.521542) (xy 19.033236 -214.112602) (xy 19.033735 -214.102445)
			(xy 19.041508 -214.083676) (xy 19.055873 -214.069311) (xy 19.074641 -214.061536) (xy 19.084798 -214.06104)
			(xy 20.484338 -214.06104) (xy 20.494498 -214.061502) (xy 20.513269 -214.06929) (xy 20.527633 -214.083665)
			(xy 20.535406 -214.102441) (xy 20.5359 -214.112602) (xy 20.5359 -214.521542) (xy 26.577036 -214.521542)
			(xy 26.577036 -214.112602) (xy 26.577535 -214.102445) (xy 26.585308 -214.083676) (xy 26.599673 -214.069311)
			(xy 26.618441 -214.061536) (xy 26.628598 -214.06104) (xy 28.028138 -214.06104) (xy 28.038298 -214.061502)
			(xy 28.057069 -214.06929) (xy 28.071433 -214.083665) (xy 28.079206 -214.102441) (xy 28.0797 -214.112602)
			(xy 28.0797 -214.521542) (xy 34.120836 -214.521542) (xy 34.120836 -214.112602) (xy 34.121335 -214.102445)
			(xy 34.129108 -214.083676) (xy 34.143473 -214.069311) (xy 34.162241 -214.061536) (xy 34.172398 -214.06104)
			(xy 35.571938 -214.06104) (xy 35.582098 -214.061502) (xy 35.600869 -214.06929) (xy 35.615233 -214.083665)
			(xy 35.623006 -214.102441) (xy 35.6235 -214.112602) (xy 35.6235 -214.521542) (xy 41.664636 -214.521542)
			(xy 41.664636 -214.112602) (xy 41.665135 -214.102445) (xy 41.672908 -214.083676) (xy 41.687273 -214.069311)
			(xy 41.706041 -214.061536) (xy 41.716198 -214.06104) (xy 43.115738 -214.06104) (xy 43.125898 -214.061502)
			(xy 43.144669 -214.06929) (xy 43.159033 -214.083665) (xy 43.166806 -214.102441) (xy 43.1673 -214.112602)
			(xy 43.1673 -214.521542) (xy 49.208436 -214.521542) (xy 49.208436 -214.112602) (xy 49.208935 -214.102445)
			(xy 49.216708 -214.083676) (xy 49.231073 -214.069311) (xy 49.249841 -214.061536) (xy 49.259998 -214.06104)
			(xy 50.659538 -214.06104) (xy 50.669698 -214.061502) (xy 50.688469 -214.06929) (xy 50.702833 -214.083665)
			(xy 50.710606 -214.102441) (xy 50.7111 -214.112602) (xy 50.7111 -214.521542) (xy 56.752236 -214.521542)
			(xy 56.752236 -214.112602) (xy 56.752735 -214.102445) (xy 56.760508 -214.083676) (xy 56.774873 -214.069311)
			(xy 56.793641 -214.061536) (xy 56.803798 -214.06104) (xy 58.203338 -214.06104) (xy 58.213498 -214.061502)
			(xy 58.232269 -214.06929) (xy 58.246633 -214.083665) (xy 58.254406 -214.102441) (xy 58.2549 -214.112602)
			(xy 58.2549 -214.521542) (xy 64.296036 -214.521542) (xy 64.296036 -214.112602) (xy 64.296535 -214.102445)
			(xy 64.304308 -214.083676) (xy 64.318673 -214.069311) (xy 64.337441 -214.061536) (xy 64.347598 -214.06104)
			(xy 65.747138 -214.06104) (xy 65.757298 -214.061502) (xy 65.776069 -214.06929) (xy 65.790433 -214.083665)
			(xy 65.798206 -214.102441) (xy 65.7987 -214.112602) (xy 65.7987 -214.521542) (xy 65.798202 -214.531698)
			(xy 65.790421 -214.550461) (xy 65.776057 -214.564823) (xy 65.757294 -214.572603) (xy 65.747138 -214.573104)
			(xy 64.347598 -214.573104) (xy 64.337445 -214.572569) (xy 64.318684 -214.564802) (xy 64.304321 -214.550449)
			(xy 64.296539 -214.531694) (xy 64.296036 -214.521542) (xy 58.2549 -214.521542) (xy 58.254402 -214.531698)
			(xy 58.246621 -214.550461) (xy 58.232257 -214.564823) (xy 58.213494 -214.572603) (xy 58.203338 -214.573104)
			(xy 56.803798 -214.573104) (xy 56.793645 -214.572569) (xy 56.774884 -214.564802) (xy 56.760521 -214.550449)
			(xy 56.752739 -214.531694) (xy 56.752236 -214.521542) (xy 50.7111 -214.521542) (xy 50.710602 -214.531698)
			(xy 50.702821 -214.550461) (xy 50.688457 -214.564823) (xy 50.669694 -214.572603) (xy 50.659538 -214.573104)
			(xy 49.259998 -214.573104) (xy 49.249845 -214.572569) (xy 49.231084 -214.564802) (xy 49.216721 -214.550449)
			(xy 49.208939 -214.531694) (xy 49.208436 -214.521542) (xy 43.1673 -214.521542) (xy 43.166802 -214.531698)
			(xy 43.159021 -214.550461) (xy 43.144657 -214.564823) (xy 43.125894 -214.572603) (xy 43.115738 -214.573104)
			(xy 41.716198 -214.573104) (xy 41.706045 -214.572569) (xy 41.687284 -214.564802) (xy 41.672921 -214.550449)
			(xy 41.665139 -214.531694) (xy 41.664636 -214.521542) (xy 35.6235 -214.521542) (xy 35.623002 -214.531698)
			(xy 35.615221 -214.550461) (xy 35.600857 -214.564823) (xy 35.582094 -214.572603) (xy 35.571938 -214.573104)
			(xy 34.172398 -214.573104) (xy 34.162245 -214.572569) (xy 34.143484 -214.564802) (xy 34.129121 -214.550449)
			(xy 34.121339 -214.531694) (xy 34.120836 -214.521542) (xy 28.0797 -214.521542) (xy 28.079202 -214.531698)
			(xy 28.071421 -214.550461) (xy 28.057057 -214.564823) (xy 28.038294 -214.572603) (xy 28.028138 -214.573104)
			(xy 26.628598 -214.573104) (xy 26.618445 -214.572569) (xy 26.599684 -214.564802) (xy 26.585321 -214.550449)
			(xy 26.577539 -214.531694) (xy 26.577036 -214.521542) (xy 20.5359 -214.521542) (xy 20.535402 -214.531698)
			(xy 20.527621 -214.550461) (xy 20.513257 -214.564823) (xy 20.494494 -214.572603) (xy 20.484338 -214.573104)
			(xy 19.084798 -214.573104) (xy 19.074645 -214.572569) (xy 19.055884 -214.564802) (xy 19.041521 -214.550449)
			(xy 19.033739 -214.531694) (xy 19.033236 -214.521542) (xy 12.9921 -214.521542) (xy 12.991602 -214.531698)
			(xy 12.983821 -214.550461) (xy 12.969457 -214.564823) (xy 12.950694 -214.572603) (xy 12.940538 -214.573104)
			(xy 11.540998 -214.573104) (xy 11.530845 -214.572569) (xy 11.512084 -214.564802) (xy 11.497721 -214.550449)
			(xy 11.489939 -214.531694) (xy 11.489436 -214.521542) (xy 2.509012 -214.521542) (xy 2.509012 -215.371426)
			(xy 7.389368 -215.371426) (xy 7.389368 -214.962486) (xy 7.389753 -214.95231) (xy 7.397548 -214.933509)
			(xy 7.411946 -214.919124) (xy 7.430753 -214.911345) (xy 7.44093 -214.910924) (xy 8.84047 -214.910924)
			(xy 8.850638 -214.911388) (xy 8.869429 -214.919161) (xy 8.883815 -214.933534) (xy 8.891603 -214.952318)
			(xy 8.892032 -214.962486) (xy 8.892032 -215.371426) (xy 14.933168 -215.371426) (xy 14.933168 -214.962486)
			(xy 14.933553 -214.95231) (xy 14.941348 -214.933509) (xy 14.955746 -214.919124) (xy 14.974553 -214.911345)
			(xy 14.98473 -214.910924) (xy 16.38427 -214.910924) (xy 16.394438 -214.911388) (xy 16.413229 -214.919161)
			(xy 16.427615 -214.933534) (xy 16.435403 -214.952318) (xy 16.435832 -214.962486) (xy 16.435832 -215.371426)
			(xy 22.476968 -215.371426) (xy 22.476968 -214.962486) (xy 22.477353 -214.95231) (xy 22.485148 -214.933509)
			(xy 22.499546 -214.919124) (xy 22.518353 -214.911345) (xy 22.52853 -214.910924) (xy 23.92807 -214.910924)
			(xy 23.938238 -214.911388) (xy 23.957029 -214.919161) (xy 23.971415 -214.933534) (xy 23.979203 -214.952318)
			(xy 23.979632 -214.962486) (xy 23.979632 -215.371426) (xy 30.020768 -215.371426) (xy 30.020768 -214.962486)
			(xy 30.021153 -214.95231) (xy 30.028948 -214.933509) (xy 30.043346 -214.919124) (xy 30.062153 -214.911345)
			(xy 30.07233 -214.910924) (xy 31.47187 -214.910924) (xy 31.482038 -214.911388) (xy 31.500829 -214.919161)
			(xy 31.515215 -214.933534) (xy 31.523003 -214.952318) (xy 31.523432 -214.962486) (xy 31.523432 -215.371426)
			(xy 37.564568 -215.371426) (xy 37.564568 -214.962486) (xy 37.564953 -214.95231) (xy 37.572748 -214.933509)
			(xy 37.587146 -214.919124) (xy 37.605953 -214.911345) (xy 37.61613 -214.910924) (xy 39.01567 -214.910924)
			(xy 39.025838 -214.911388) (xy 39.044629 -214.919161) (xy 39.059015 -214.933534) (xy 39.066803 -214.952318)
			(xy 39.067232 -214.962486) (xy 39.067232 -215.371426) (xy 45.108368 -215.371426) (xy 45.108368 -214.962486)
			(xy 45.108753 -214.95231) (xy 45.116548 -214.933509) (xy 45.130946 -214.919124) (xy 45.149753 -214.911345)
			(xy 45.15993 -214.910924) (xy 46.55947 -214.910924) (xy 46.569638 -214.911388) (xy 46.588429 -214.919161)
			(xy 46.602815 -214.933534) (xy 46.610603 -214.952318) (xy 46.611032 -214.962486) (xy 46.611032 -215.371426)
			(xy 52.652168 -215.371426) (xy 52.652168 -214.962486) (xy 52.652553 -214.95231) (xy 52.660348 -214.933509)
			(xy 52.674746 -214.919124) (xy 52.693553 -214.911345) (xy 52.70373 -214.910924) (xy 54.10327 -214.910924)
			(xy 54.113438 -214.911388) (xy 54.132229 -214.919161) (xy 54.146615 -214.933534) (xy 54.154403 -214.952318)
			(xy 54.154832 -214.962486) (xy 54.154832 -215.371426) (xy 60.195968 -215.371426) (xy 60.195968 -214.962486)
			(xy 60.196353 -214.95231) (xy 60.204148 -214.933509) (xy 60.218546 -214.919124) (xy 60.237353 -214.911345)
			(xy 60.24753 -214.910924) (xy 61.64707 -214.910924) (xy 61.657238 -214.911388) (xy 61.676029 -214.919161)
			(xy 61.690415 -214.933534) (xy 61.698203 -214.952318) (xy 61.698632 -214.962486) (xy 61.698632 -215.371426)
			(xy 61.698257 -215.381603) (xy 61.690458 -215.400404) (xy 61.676057 -215.414789) (xy 61.657248 -215.422568)
			(xy 61.64707 -215.422988) (xy 60.24753 -215.422988) (xy 60.237364 -215.422512) (xy 60.218575 -215.414742)
			(xy 60.20419 -215.400372) (xy 60.196399 -215.381592) (xy 60.195968 -215.371426) (xy 54.154832 -215.371426)
			(xy 54.154457 -215.381603) (xy 54.146658 -215.400404) (xy 54.132257 -215.414789) (xy 54.113448 -215.422568)
			(xy 54.10327 -215.422988) (xy 52.70373 -215.422988) (xy 52.693564 -215.422512) (xy 52.674775 -215.414742)
			(xy 52.66039 -215.400372) (xy 52.652599 -215.381592) (xy 52.652168 -215.371426) (xy 46.611032 -215.371426)
			(xy 46.610657 -215.381603) (xy 46.602858 -215.400404) (xy 46.588457 -215.414789) (xy 46.569648 -215.422568)
			(xy 46.55947 -215.422988) (xy 45.15993 -215.422988) (xy 45.149764 -215.422512) (xy 45.130975 -215.414742)
			(xy 45.11659 -215.400372) (xy 45.108799 -215.381592) (xy 45.108368 -215.371426) (xy 39.067232 -215.371426)
			(xy 39.066857 -215.381603) (xy 39.059058 -215.400404) (xy 39.044657 -215.414789) (xy 39.025848 -215.422568)
			(xy 39.01567 -215.422988) (xy 37.61613 -215.422988) (xy 37.605964 -215.422512) (xy 37.587175 -215.414742)
			(xy 37.57279 -215.400372) (xy 37.564999 -215.381592) (xy 37.564568 -215.371426) (xy 31.523432 -215.371426)
			(xy 31.523057 -215.381603) (xy 31.515258 -215.400404) (xy 31.500857 -215.414789) (xy 31.482048 -215.422568)
			(xy 31.47187 -215.422988) (xy 30.07233 -215.422988) (xy 30.062164 -215.422512) (xy 30.043375 -215.414742)
			(xy 30.02899 -215.400372) (xy 30.021199 -215.381592) (xy 30.020768 -215.371426) (xy 23.979632 -215.371426)
			(xy 23.979257 -215.381603) (xy 23.971458 -215.400404) (xy 23.957057 -215.414789) (xy 23.938248 -215.422568)
			(xy 23.92807 -215.422988) (xy 22.52853 -215.422988) (xy 22.518364 -215.422512) (xy 22.499575 -215.414742)
			(xy 22.48519 -215.400372) (xy 22.477399 -215.381592) (xy 22.476968 -215.371426) (xy 16.435832 -215.371426)
			(xy 16.435457 -215.381603) (xy 16.427658 -215.400404) (xy 16.413257 -215.414789) (xy 16.394448 -215.422568)
			(xy 16.38427 -215.422988) (xy 14.98473 -215.422988) (xy 14.974564 -215.422512) (xy 14.955775 -215.414742)
			(xy 14.94139 -215.400372) (xy 14.933599 -215.381592) (xy 14.933168 -215.371426) (xy 8.892032 -215.371426)
			(xy 8.891657 -215.381603) (xy 8.883858 -215.400404) (xy 8.869457 -215.414789) (xy 8.850648 -215.422568)
			(xy 8.84047 -215.422988) (xy 7.44093 -215.422988) (xy 7.430764 -215.422512) (xy 7.411975 -215.414742)
			(xy 7.39759 -215.400372) (xy 7.389799 -215.381592) (xy 7.389368 -215.371426) (xy 2.509012 -215.371426)
			(xy 2.509012 -215.436704) (xy 88.28532 -215.436704) (xy 88.285828 -215.410797) (xy 88.293934 -215.35962)
			(xy 88.309946 -215.310341) (xy 88.333469 -215.264174) (xy 88.363925 -215.222255) (xy 88.400563 -215.185617)
			(xy 88.442482 -215.155161) (xy 88.488649 -215.131638) (xy 88.537928 -215.115626) (xy 88.589105 -215.10752)
			(xy 88.640919 -215.10752) (xy 88.692096 -215.115626) (xy 88.741375 -215.131638) (xy 88.787542 -215.155161)
			(xy 88.829461 -215.185617) (xy 88.866099 -215.222255) (xy 88.896555 -215.264174) (xy 88.920078 -215.310341)
			(xy 88.93609 -215.35962) (xy 88.944196 -215.410797) (xy 88.944704 -215.436704) (xy 89.22512 -215.436704)
			(xy 89.225629 -215.41136) (xy 89.2334 -215.36127) (xy 89.248746 -215.31296) (xy 89.271303 -215.267567)
			(xy 89.300542 -215.226161) (xy 89.335773 -215.189717) (xy 89.376165 -215.159094) (xy 89.420769 -215.135013)
			(xy 89.468532 -215.118041) (xy 89.493344 -215.112854) (xy 89.516204 -215.108536) (xy 89.721182 -214.753444)
			(xy 89.713308 -214.7316) (xy 89.704729 -214.705181) (xy 89.695532 -214.650406) (xy 89.69502 -214.622634)
			(xy 89.695528 -214.596747) (xy 89.703627 -214.545609) (xy 89.719626 -214.496369) (xy 89.743132 -214.450237)
			(xy 89.773564 -214.40835) (xy 89.810174 -214.37174) (xy 89.852061 -214.341308) (xy 89.898193 -214.317802)
			(xy 89.947433 -214.301803) (xy 89.998571 -214.293704) (xy 90.050345 -214.293704) (xy 90.101483 -214.301803)
			(xy 90.150723 -214.317802) (xy 90.196855 -214.341308) (xy 90.238742 -214.37174) (xy 90.275352 -214.40835)
			(xy 90.305784 -214.450237) (xy 90.32929 -214.496369) (xy 90.345289 -214.545609) (xy 90.353388 -214.596747)
			(xy 90.353896 -214.622634) (xy 90.353447 -214.64797) (xy 90.34569 -214.698044) (xy 90.330363 -214.746341)
			(xy 90.307827 -214.791726) (xy 90.278612 -214.833128) (xy 90.243408 -214.869572) (xy 90.203042 -214.900202)
			(xy 90.158465 -214.924296) (xy 90.110727 -214.941286) (xy 90.085926 -214.946484) (xy 90.063066 -214.950802)
			(xy 89.858088 -215.305894) (xy 89.865962 -215.327738) (xy 89.87461 -215.354146) (xy 89.883929 -215.408922)
			(xy 89.884504 -215.436704) (xy 91.10472 -215.436704) (xy 91.105229 -215.41136) (xy 91.113 -215.36127)
			(xy 91.128346 -215.31296) (xy 91.150903 -215.267567) (xy 91.180142 -215.226161) (xy 91.215373 -215.189717)
			(xy 91.255765 -215.159094) (xy 91.300369 -215.135013) (xy 91.348132 -215.118041) (xy 91.372944 -215.112854)
			(xy 91.395804 -215.108536) (xy 91.600782 -214.753444) (xy 91.592908 -214.7316) (xy 91.584329 -214.705181)
			(xy 91.575132 -214.650406) (xy 91.57462 -214.622634) (xy 91.575128 -214.596747) (xy 91.583227 -214.545609)
			(xy 91.599226 -214.496369) (xy 91.622732 -214.450237) (xy 91.653164 -214.40835) (xy 91.689774 -214.37174)
			(xy 91.731661 -214.341308) (xy 91.777793 -214.317802) (xy 91.827033 -214.301803) (xy 91.878171 -214.293704)
			(xy 91.929945 -214.293704) (xy 91.981083 -214.301803) (xy 92.030323 -214.317802) (xy 92.076455 -214.341308)
			(xy 92.118342 -214.37174) (xy 92.154952 -214.40835) (xy 92.185384 -214.450237) (xy 92.20889 -214.496369)
			(xy 92.224889 -214.545609) (xy 92.232988 -214.596747) (xy 92.233496 -214.622634) (xy 92.233047 -214.64797)
			(xy 92.22529 -214.698044) (xy 92.209963 -214.746341) (xy 92.187427 -214.791726) (xy 92.158212 -214.833128)
			(xy 92.123008 -214.869572) (xy 92.082642 -214.900202) (xy 92.038065 -214.924296) (xy 91.990327 -214.941286)
			(xy 91.965526 -214.946484) (xy 91.942666 -214.950802) (xy 91.737688 -215.305894) (xy 91.745562 -215.327738)
			(xy 91.75421 -215.354146) (xy 91.763529 -215.408922) (xy 91.764104 -215.436704) (xy 92.98432 -215.436704)
			(xy 92.984829 -215.41136) (xy 92.9926 -215.36127) (xy 93.007946 -215.31296) (xy 93.030503 -215.267567)
			(xy 93.059742 -215.226161) (xy 93.094973 -215.189717) (xy 93.135365 -215.159094) (xy 93.179969 -215.135013)
			(xy 93.227732 -215.118041) (xy 93.252544 -215.112854) (xy 93.275404 -215.108536) (xy 93.480382 -214.753444)
			(xy 93.472508 -214.7316) (xy 93.463929 -214.705181) (xy 93.454732 -214.650406) (xy 93.45422 -214.622634)
			(xy 93.454728 -214.596747) (xy 93.462827 -214.545609) (xy 93.478826 -214.496369) (xy 93.502332 -214.450237)
			(xy 93.532764 -214.40835) (xy 93.569374 -214.37174) (xy 93.611261 -214.341308) (xy 93.657393 -214.317802)
			(xy 93.706633 -214.301803) (xy 93.757771 -214.293704) (xy 93.809545 -214.293704) (xy 93.860683 -214.301803)
			(xy 93.909923 -214.317802) (xy 93.956055 -214.341308) (xy 93.997942 -214.37174) (xy 94.034552 -214.40835)
			(xy 94.064984 -214.450237) (xy 94.08849 -214.496369) (xy 94.104489 -214.545609) (xy 94.112588 -214.596747)
			(xy 94.113096 -214.622634) (xy 94.112647 -214.64797) (xy 94.10489 -214.698044) (xy 94.089563 -214.746341)
			(xy 94.067027 -214.791726) (xy 94.037812 -214.833128) (xy 94.002608 -214.869572) (xy 93.962242 -214.900202)
			(xy 93.917665 -214.924296) (xy 93.869927 -214.941286) (xy 93.845126 -214.946484) (xy 93.822266 -214.950802)
			(xy 93.617288 -215.305894) (xy 93.625162 -215.327738) (xy 93.63381 -215.354146) (xy 93.643129 -215.408922)
			(xy 93.643704 -215.436704) (xy 94.86392 -215.436704) (xy 94.864429 -215.41136) (xy 94.8722 -215.36127)
			(xy 94.887546 -215.31296) (xy 94.910103 -215.267567) (xy 94.939342 -215.226161) (xy 94.974573 -215.189717)
			(xy 95.014965 -215.159094) (xy 95.059569 -215.135013) (xy 95.107332 -215.118041) (xy 95.132144 -215.112854)
			(xy 95.155004 -215.108536) (xy 95.359982 -214.753444) (xy 95.352108 -214.7316) (xy 95.343529 -214.705181)
			(xy 95.334332 -214.650406) (xy 95.33382 -214.622634) (xy 95.334328 -214.596747) (xy 95.342427 -214.545609)
			(xy 95.358426 -214.496369) (xy 95.381932 -214.450237) (xy 95.412364 -214.40835) (xy 95.448974 -214.37174)
			(xy 95.490861 -214.341308) (xy 95.536993 -214.317802) (xy 95.586233 -214.301803) (xy 95.637371 -214.293704)
			(xy 95.689145 -214.293704) (xy 95.740283 -214.301803) (xy 95.789523 -214.317802) (xy 95.835655 -214.341308)
			(xy 95.877542 -214.37174) (xy 95.914152 -214.40835) (xy 95.944584 -214.450237) (xy 95.96809 -214.496369)
			(xy 95.984089 -214.545609) (xy 95.992188 -214.596747) (xy 95.992696 -214.622634) (xy 95.992247 -214.64797)
			(xy 95.98449 -214.698044) (xy 95.969163 -214.746341) (xy 95.946627 -214.791726) (xy 95.917412 -214.833128)
			(xy 95.882208 -214.869572) (xy 95.841842 -214.900202) (xy 95.797265 -214.924296) (xy 95.749527 -214.941286)
			(xy 95.724726 -214.946484) (xy 95.701866 -214.950802) (xy 95.496888 -215.305894) (xy 95.504762 -215.327738)
			(xy 95.51341 -215.354146) (xy 95.522729 -215.408922) (xy 95.523304 -215.436704) (xy 96.74352 -215.436704)
			(xy 96.744029 -215.41136) (xy 96.7518 -215.36127) (xy 96.767146 -215.31296) (xy 96.789703 -215.267567)
			(xy 96.818942 -215.226161) (xy 96.854173 -215.189717) (xy 96.894565 -215.159094) (xy 96.939169 -215.135013)
			(xy 96.986932 -215.118041) (xy 97.011744 -215.112854) (xy 97.034604 -215.108536) (xy 97.239582 -214.753444)
			(xy 97.231708 -214.7316) (xy 97.223129 -214.705181) (xy 97.213932 -214.650406) (xy 97.21342 -214.622634)
			(xy 97.213928 -214.596747) (xy 97.222027 -214.545609) (xy 97.238026 -214.496369) (xy 97.261532 -214.450237)
			(xy 97.291964 -214.40835) (xy 97.328574 -214.37174) (xy 97.370461 -214.341308) (xy 97.416593 -214.317802)
			(xy 97.465833 -214.301803) (xy 97.516971 -214.293704) (xy 97.568745 -214.293704) (xy 97.619883 -214.301803)
			(xy 97.669123 -214.317802) (xy 97.715255 -214.341308) (xy 97.757142 -214.37174) (xy 97.793752 -214.40835)
			(xy 97.824184 -214.450237) (xy 97.84769 -214.496369) (xy 97.863689 -214.545609) (xy 97.871788 -214.596747)
			(xy 97.872296 -214.622634) (xy 97.871847 -214.64797) (xy 97.86409 -214.698044) (xy 97.848763 -214.746341)
			(xy 97.826227 -214.791726) (xy 97.797012 -214.833128) (xy 97.761808 -214.869572) (xy 97.721442 -214.900202)
			(xy 97.676865 -214.924296) (xy 97.629127 -214.941286) (xy 97.604326 -214.946484) (xy 97.581466 -214.950802)
			(xy 97.376488 -215.305894) (xy 97.384362 -215.327738) (xy 97.39301 -215.354146) (xy 97.402329 -215.408922)
			(xy 97.402904 -215.436704) (xy 98.62312 -215.436704) (xy 98.623629 -215.41136) (xy 98.6314 -215.36127)
			(xy 98.646746 -215.31296) (xy 98.669303 -215.267567) (xy 98.698542 -215.226161) (xy 98.733773 -215.189717)
			(xy 98.774165 -215.159094) (xy 98.818769 -215.135013) (xy 98.866532 -215.118041) (xy 98.891344 -215.112854)
			(xy 98.914204 -215.108536) (xy 99.119182 -214.753444) (xy 99.111308 -214.7316) (xy 99.102729 -214.705181)
			(xy 99.093532 -214.650406) (xy 99.09302 -214.622634) (xy 99.093528 -214.596747) (xy 99.101627 -214.545609)
			(xy 99.117626 -214.496369) (xy 99.141132 -214.450237) (xy 99.171564 -214.40835) (xy 99.208174 -214.37174)
			(xy 99.250061 -214.341308) (xy 99.296193 -214.317802) (xy 99.345433 -214.301803) (xy 99.396571 -214.293704)
			(xy 99.448345 -214.293704) (xy 99.499483 -214.301803) (xy 99.548723 -214.317802) (xy 99.594855 -214.341308)
			(xy 99.636742 -214.37174) (xy 99.673352 -214.40835) (xy 99.703784 -214.450237) (xy 99.72729 -214.496369)
			(xy 99.743289 -214.545609) (xy 99.751388 -214.596747) (xy 99.751896 -214.622634) (xy 99.751447 -214.64797)
			(xy 99.74369 -214.698044) (xy 99.728363 -214.746341) (xy 99.705827 -214.791726) (xy 99.676612 -214.833128)
			(xy 99.641408 -214.869572) (xy 99.601042 -214.900202) (xy 99.556465 -214.924296) (xy 99.508727 -214.941286)
			(xy 99.483926 -214.946484) (xy 99.461066 -214.950802) (xy 99.256088 -215.305894) (xy 99.263962 -215.327738)
			(xy 99.27261 -215.354146) (xy 99.281929 -215.408922) (xy 99.282504 -215.436704) (xy 100.50272 -215.436704)
			(xy 100.503229 -215.41136) (xy 100.511 -215.36127) (xy 100.526346 -215.31296) (xy 100.548903 -215.267567)
			(xy 100.578142 -215.226161) (xy 100.613373 -215.189717) (xy 100.653765 -215.159094) (xy 100.698369 -215.135013)
			(xy 100.746132 -215.118041) (xy 100.770944 -215.112854) (xy 100.793804 -215.108536) (xy 100.998782 -214.753444)
			(xy 100.990908 -214.7316) (xy 100.982329 -214.705181) (xy 100.973132 -214.650406) (xy 100.97262 -214.622634)
			(xy 100.973128 -214.596747) (xy 100.981227 -214.545609) (xy 100.997226 -214.496369) (xy 101.020732 -214.450237)
			(xy 101.051164 -214.40835) (xy 101.087774 -214.37174) (xy 101.129661 -214.341308) (xy 101.175793 -214.317802)
			(xy 101.225033 -214.301803) (xy 101.276171 -214.293704) (xy 101.327945 -214.293704) (xy 101.379083 -214.301803)
			(xy 101.428323 -214.317802) (xy 101.474455 -214.341308) (xy 101.516342 -214.37174) (xy 101.552952 -214.40835)
			(xy 101.583384 -214.450237) (xy 101.60689 -214.496369) (xy 101.622889 -214.545609) (xy 101.630988 -214.596747)
			(xy 101.631496 -214.622634) (xy 101.631047 -214.64797) (xy 101.62329 -214.698044) (xy 101.607963 -214.746341)
			(xy 101.585427 -214.791726) (xy 101.556212 -214.833128) (xy 101.521008 -214.869572) (xy 101.480642 -214.900202)
			(xy 101.436065 -214.924296) (xy 101.388327 -214.941286) (xy 101.363526 -214.946484) (xy 101.340666 -214.950802)
			(xy 101.135688 -215.305894) (xy 101.143562 -215.327738) (xy 101.15221 -215.354146) (xy 101.161529 -215.408922)
			(xy 101.162104 -215.436704) (xy 102.38232 -215.436704) (xy 102.382829 -215.41136) (xy 102.3906 -215.36127)
			(xy 102.405946 -215.31296) (xy 102.428503 -215.267567) (xy 102.457742 -215.226161) (xy 102.492973 -215.189717)
			(xy 102.533365 -215.159094) (xy 102.577969 -215.135013) (xy 102.625732 -215.118041) (xy 102.650544 -215.112854)
			(xy 102.673404 -215.108536) (xy 102.878382 -214.753444) (xy 102.870508 -214.7316) (xy 102.861929 -214.705181)
			(xy 102.852732 -214.650406) (xy 102.85222 -214.622634) (xy 102.852728 -214.596747) (xy 102.860827 -214.545609)
			(xy 102.876826 -214.496369) (xy 102.900332 -214.450237) (xy 102.930764 -214.40835) (xy 102.967374 -214.37174)
			(xy 103.009261 -214.341308) (xy 103.055393 -214.317802) (xy 103.104633 -214.301803) (xy 103.155771 -214.293704)
			(xy 103.207545 -214.293704) (xy 103.258683 -214.301803) (xy 103.307923 -214.317802) (xy 103.354055 -214.341308)
			(xy 103.395942 -214.37174) (xy 103.432552 -214.40835) (xy 103.462984 -214.450237) (xy 103.48649 -214.496369)
			(xy 103.502489 -214.545609) (xy 103.510588 -214.596747) (xy 103.511096 -214.622634) (xy 103.510647 -214.64797)
			(xy 103.50289 -214.698044) (xy 103.487563 -214.746341) (xy 103.465027 -214.791726) (xy 103.435812 -214.833128)
			(xy 103.400608 -214.869572) (xy 103.360242 -214.900202) (xy 103.315665 -214.924296) (xy 103.267927 -214.941286)
			(xy 103.243126 -214.946484) (xy 103.220266 -214.950802) (xy 103.015288 -215.305894) (xy 103.023162 -215.327738)
			(xy 103.03181 -215.354146) (xy 103.041129 -215.408922) (xy 103.041704 -215.436704) (xy 104.26192 -215.436704)
			(xy 104.262429 -215.41136) (xy 104.2702 -215.36127) (xy 104.285546 -215.31296) (xy 104.308103 -215.267567)
			(xy 104.337342 -215.226161) (xy 104.372573 -215.189717) (xy 104.412965 -215.159094) (xy 104.457569 -215.135013)
			(xy 104.505332 -215.118041) (xy 104.530144 -215.112854) (xy 104.553004 -215.108536) (xy 104.757982 -214.753444)
			(xy 104.750108 -214.7316) (xy 104.741529 -214.705181) (xy 104.732332 -214.650406) (xy 104.73182 -214.622634)
			(xy 104.732328 -214.596747) (xy 104.740427 -214.545609) (xy 104.756426 -214.496369) (xy 104.779932 -214.450237)
			(xy 104.810364 -214.40835) (xy 104.846974 -214.37174) (xy 104.888861 -214.341308) (xy 104.934993 -214.317802)
			(xy 104.984233 -214.301803) (xy 105.035371 -214.293704) (xy 105.087145 -214.293704) (xy 105.138283 -214.301803)
			(xy 105.187523 -214.317802) (xy 105.233655 -214.341308) (xy 105.275542 -214.37174) (xy 105.312152 -214.40835)
			(xy 105.342584 -214.450237) (xy 105.36609 -214.496369) (xy 105.382089 -214.545609) (xy 105.390188 -214.596747)
			(xy 105.390696 -214.622634) (xy 105.390247 -214.64797) (xy 105.38249 -214.698044) (xy 105.367163 -214.746341)
			(xy 105.344627 -214.791726) (xy 105.315412 -214.833128) (xy 105.280208 -214.869572) (xy 105.239842 -214.900202)
			(xy 105.195265 -214.924296) (xy 105.147527 -214.941286) (xy 105.122726 -214.946484) (xy 105.099866 -214.950802)
			(xy 104.894888 -215.305894) (xy 104.902762 -215.327738) (xy 104.91141 -215.354146) (xy 104.920729 -215.408922)
			(xy 104.921304 -215.436704) (xy 106.14152 -215.436704) (xy 106.142029 -215.41136) (xy 106.1498 -215.36127)
			(xy 106.165146 -215.31296) (xy 106.187703 -215.267567) (xy 106.216942 -215.226161) (xy 106.252173 -215.189717)
			(xy 106.292565 -215.159094) (xy 106.337169 -215.135013) (xy 106.384932 -215.118041) (xy 106.409744 -215.112854)
			(xy 106.432604 -215.108536) (xy 106.637582 -214.753444) (xy 106.629708 -214.7316) (xy 106.621129 -214.705181)
			(xy 106.611932 -214.650406) (xy 106.61142 -214.622634) (xy 106.611928 -214.596747) (xy 106.620027 -214.545609)
			(xy 106.636026 -214.496369) (xy 106.659532 -214.450237) (xy 106.689964 -214.40835) (xy 106.726574 -214.37174)
			(xy 106.768461 -214.341308) (xy 106.814593 -214.317802) (xy 106.863833 -214.301803) (xy 106.914971 -214.293704)
			(xy 106.966745 -214.293704) (xy 107.017883 -214.301803) (xy 107.067123 -214.317802) (xy 107.113255 -214.341308)
			(xy 107.155142 -214.37174) (xy 107.191752 -214.40835) (xy 107.222184 -214.450237) (xy 107.24569 -214.496369)
			(xy 107.261689 -214.545609) (xy 107.269788 -214.596747) (xy 107.270296 -214.622634) (xy 107.269847 -214.64797)
			(xy 107.26209 -214.698044) (xy 107.246763 -214.746341) (xy 107.224227 -214.791726) (xy 107.195012 -214.833128)
			(xy 107.159808 -214.869572) (xy 107.119442 -214.900202) (xy 107.074865 -214.924296) (xy 107.027127 -214.941286)
			(xy 107.002326 -214.946484) (xy 106.979466 -214.950802) (xy 106.774488 -215.305894) (xy 106.782362 -215.327738)
			(xy 106.79101 -215.354146) (xy 106.800329 -215.408922) (xy 106.800904 -215.436704) (xy 108.02112 -215.436704)
			(xy 108.021629 -215.41136) (xy 108.0294 -215.36127) (xy 108.044746 -215.31296) (xy 108.067303 -215.267567)
			(xy 108.096542 -215.226161) (xy 108.131773 -215.189717) (xy 108.172165 -215.159094) (xy 108.216769 -215.135013)
			(xy 108.264532 -215.118041) (xy 108.289344 -215.112854) (xy 108.312204 -215.108536) (xy 108.517182 -214.753444)
			(xy 108.509308 -214.7316) (xy 108.500729 -214.705181) (xy 108.491532 -214.650406) (xy 108.49102 -214.622634)
			(xy 108.491528 -214.596747) (xy 108.499627 -214.545609) (xy 108.515626 -214.496369) (xy 108.539132 -214.450237)
			(xy 108.569564 -214.40835) (xy 108.606174 -214.37174) (xy 108.648061 -214.341308) (xy 108.694193 -214.317802)
			(xy 108.743433 -214.301803) (xy 108.794571 -214.293704) (xy 108.846345 -214.293704) (xy 108.897483 -214.301803)
			(xy 108.946723 -214.317802) (xy 108.992855 -214.341308) (xy 109.034742 -214.37174) (xy 109.071352 -214.40835)
			(xy 109.101784 -214.450237) (xy 109.12529 -214.496369) (xy 109.141289 -214.545609) (xy 109.14142 -214.546434)
			(xy 110.371128 -214.546434) (xy 110.371636 -214.520547) (xy 110.379735 -214.469409) (xy 110.395734 -214.420169)
			(xy 110.41924 -214.374037) (xy 110.449672 -214.33215) (xy 110.486282 -214.29554) (xy 110.528169 -214.265108)
			(xy 110.574301 -214.241602) (xy 110.623541 -214.225603) (xy 110.674679 -214.217504) (xy 110.726453 -214.217504)
			(xy 110.777591 -214.225603) (xy 110.826831 -214.241602) (xy 110.872963 -214.265108) (xy 110.91485 -214.29554)
			(xy 110.95146 -214.33215) (xy 110.981892 -214.374037) (xy 111.005398 -214.420169) (xy 111.021397 -214.469409)
			(xy 111.029496 -214.520547) (xy 111.030004 -214.546434) (xy 111.030004 -214.546942) (xy 111.029596 -214.56979)
			(xy 111.029246 -214.572283) (xy 112.250803 -214.572283) (xy 112.250803 -214.520517) (xy 112.258901 -214.469389)
			(xy 112.274896 -214.420157) (xy 112.298395 -214.374033) (xy 112.32882 -214.332153) (xy 112.365421 -214.295547)
			(xy 112.407297 -214.265117) (xy 112.453418 -214.241612) (xy 112.502648 -214.22561) (xy 112.553775 -214.217507)
			(xy 112.579658 -214.216996) (xy 112.605169 -214.217509) (xy 112.655581 -214.225363) (xy 112.704182 -214.24089)
			(xy 112.749811 -214.263719) (xy 112.791377 -214.293306) (xy 112.827889 -214.328944) (xy 112.843564 -214.349076)
			(xy 113.255552 -214.349076) (xy 113.271247 -214.328958) (xy 113.307753 -214.293314) (xy 113.349314 -214.263719)
			(xy 113.394938 -214.24088) (xy 113.443536 -214.225342) (xy 113.493947 -214.217476) (xy 113.519458 -214.216996)
			(xy 113.545352 -214.217406) (xy 113.596504 -214.225502) (xy 113.645759 -214.2415) (xy 113.691905 -214.265008)
			(xy 113.733805 -214.295445) (xy 113.770428 -214.332063) (xy 113.80087 -214.373959) (xy 113.824384 -214.420102)
			(xy 113.840388 -214.469355) (xy 113.848491 -214.520506) (xy 113.848491 -214.572294) (xy 113.840388 -214.623445)
			(xy 113.824384 -214.672698) (xy 113.80087 -214.718841) (xy 113.770428 -214.760737) (xy 113.733805 -214.797355)
			(xy 113.691905 -214.827792) (xy 113.645759 -214.8513) (xy 113.596504 -214.867298) (xy 113.545352 -214.875394)
			(xy 113.519458 -214.875872) (xy 113.493944 -214.875433) (xy 113.443527 -214.867566) (xy 113.394925 -214.852025)
			(xy 113.349296 -214.829181) (xy 113.307732 -214.799581) (xy 113.271224 -214.763931) (xy 113.255552 -214.743792)
			(xy 112.843564 -214.743792) (xy 112.827909 -214.763943) (xy 112.791396 -214.799586) (xy 112.749827 -214.829178)
			(xy 112.704195 -214.852012) (xy 112.655589 -214.867542) (xy 112.605171 -214.875398) (xy 112.579658 -214.875872)
			(xy 112.553775 -214.875293) (xy 112.502648 -214.86719) (xy 112.453418 -214.851188) (xy 112.407297 -214.827683)
			(xy 112.365421 -214.797253) (xy 112.32882 -214.760647) (xy 112.298395 -214.718767) (xy 112.274896 -214.672643)
			(xy 112.258901 -214.623411) (xy 112.250803 -214.572283) (xy 111.029246 -214.572283) (xy 111.023246 -214.615045)
			(xy 111.010702 -214.658987) (xy 111.00181 -214.680038) (xy 110.991904 -214.702644) (xy 111.205772 -215.108028)
			(xy 111.229902 -215.1126) (xy 111.254835 -215.117694) (xy 111.302873 -215.134477) (xy 111.347761 -215.158443)
			(xy 111.388433 -215.189024) (xy 111.423922 -215.225492) (xy 111.453384 -215.266981) (xy 111.47612 -215.312505)
			(xy 111.491589 -215.360982) (xy 111.499424 -215.411261) (xy 111.499904 -215.436704) (xy 113.65992 -215.436704)
			(xy 113.660429 -215.41136) (xy 113.6682 -215.36127) (xy 113.683546 -215.31296) (xy 113.706103 -215.267567)
			(xy 113.735342 -215.226161) (xy 113.770573 -215.189717) (xy 113.810965 -215.159094) (xy 113.855569 -215.135013)
			(xy 113.903332 -215.118041) (xy 113.928144 -215.112854) (xy 113.951004 -215.108536) (xy 114.156236 -214.753444)
			(xy 114.148362 -214.731346) (xy 114.139733 -214.704999) (xy 114.130411 -214.650352) (xy 114.12982 -214.622634)
			(xy 114.130328 -214.596727) (xy 114.138434 -214.54555) (xy 114.154446 -214.496271) (xy 114.177969 -214.450104)
			(xy 114.208425 -214.408185) (xy 114.245063 -214.371547) (xy 114.286982 -214.341091) (xy 114.333149 -214.317568)
			(xy 114.382428 -214.301556) (xy 114.433605 -214.29345) (xy 114.485419 -214.29345) (xy 114.536596 -214.301556)
			(xy 114.585875 -214.317568) (xy 114.632042 -214.341091) (xy 114.673961 -214.371547) (xy 114.710599 -214.408185)
			(xy 114.741055 -214.450104) (xy 114.764578 -214.496271) (xy 114.78059 -214.54555) (xy 114.788696 -214.596727)
			(xy 114.789204 -214.622634) (xy 114.78871 -214.647978) (xy 114.780934 -214.698068) (xy 114.765584 -214.746377)
			(xy 114.743024 -214.791769) (xy 114.713783 -214.833174) (xy 114.678552 -214.869617) (xy 114.638158 -214.90024)
			(xy 114.593555 -214.924322) (xy 114.545792 -214.941296) (xy 114.52098 -214.946484) (xy 114.49812 -214.950802)
			(xy 114.292888 -215.305894) (xy 114.300762 -215.327992) (xy 114.309397 -215.354337) (xy 114.318716 -215.408986)
			(xy 114.319304 -215.436704) (xy 115.53952 -215.436704) (xy 115.540029 -215.41136) (xy 115.5478 -215.36127)
			(xy 115.563146 -215.31296) (xy 115.585703 -215.267567) (xy 115.614942 -215.226161) (xy 115.650173 -215.189717)
			(xy 115.690565 -215.159094) (xy 115.735169 -215.135013) (xy 115.782932 -215.118041) (xy 115.807744 -215.112854)
			(xy 115.830604 -215.108536) (xy 116.035582 -214.753444) (xy 116.027708 -214.7316) (xy 116.019129 -214.705181)
			(xy 116.009932 -214.650406) (xy 116.00942 -214.622634) (xy 116.009928 -214.596747) (xy 116.018027 -214.545609)
			(xy 116.034026 -214.496369) (xy 116.057532 -214.450237) (xy 116.087964 -214.40835) (xy 116.124574 -214.37174)
			(xy 116.166461 -214.341308) (xy 116.212593 -214.317802) (xy 116.261833 -214.301803) (xy 116.312971 -214.293704)
			(xy 116.364745 -214.293704) (xy 116.415883 -214.301803) (xy 116.465123 -214.317802) (xy 116.511255 -214.341308)
			(xy 116.553142 -214.37174) (xy 116.589752 -214.40835) (xy 116.620184 -214.450237) (xy 116.64369 -214.496369)
			(xy 116.659689 -214.545609) (xy 116.667788 -214.596747) (xy 116.668296 -214.622634) (xy 116.667847 -214.64797)
			(xy 116.66009 -214.698044) (xy 116.644763 -214.746341) (xy 116.622227 -214.791726) (xy 116.593012 -214.833128)
			(xy 116.557808 -214.869572) (xy 116.517442 -214.900202) (xy 116.472865 -214.924296) (xy 116.425127 -214.941286)
			(xy 116.400326 -214.946484) (xy 116.377466 -214.950802) (xy 116.172488 -215.305894) (xy 116.180362 -215.327738)
			(xy 116.18901 -215.354146) (xy 116.198329 -215.408922) (xy 116.198904 -215.436704) (xy 117.41912 -215.436704)
			(xy 117.419629 -215.41136) (xy 117.4274 -215.36127) (xy 117.442746 -215.31296) (xy 117.465303 -215.267567)
			(xy 117.494542 -215.226161) (xy 117.529773 -215.189717) (xy 117.570165 -215.159094) (xy 117.614769 -215.135013)
			(xy 117.662532 -215.118041) (xy 117.687344 -215.112854) (xy 117.710204 -215.108536) (xy 117.915182 -214.753444)
			(xy 117.907308 -214.7316) (xy 117.898729 -214.705181) (xy 117.889532 -214.650406) (xy 117.88902 -214.622634)
			(xy 117.889528 -214.596747) (xy 117.897627 -214.545609) (xy 117.913626 -214.496369) (xy 117.937132 -214.450237)
			(xy 117.967564 -214.40835) (xy 118.004174 -214.37174) (xy 118.046061 -214.341308) (xy 118.092193 -214.317802)
			(xy 118.141433 -214.301803) (xy 118.192571 -214.293704) (xy 118.244345 -214.293704) (xy 118.295483 -214.301803)
			(xy 118.344723 -214.317802) (xy 118.390855 -214.341308) (xy 118.432742 -214.37174) (xy 118.469352 -214.40835)
			(xy 118.499784 -214.450237) (xy 118.52329 -214.496369) (xy 118.539289 -214.545609) (xy 118.547388 -214.596747)
			(xy 118.547896 -214.622634) (xy 118.547447 -214.64797) (xy 118.53969 -214.698044) (xy 118.524363 -214.746341)
			(xy 118.501827 -214.791726) (xy 118.472612 -214.833128) (xy 118.437408 -214.869572) (xy 118.397042 -214.900202)
			(xy 118.352465 -214.924296) (xy 118.304727 -214.941286) (xy 118.279926 -214.946484) (xy 118.257066 -214.950802)
			(xy 118.052088 -215.305894) (xy 118.059962 -215.327738) (xy 118.06861 -215.354146) (xy 118.077929 -215.408922)
			(xy 118.078504 -215.436704) (xy 119.29872 -215.436704) (xy 119.299229 -215.41136) (xy 119.307 -215.36127)
			(xy 119.322346 -215.31296) (xy 119.344903 -215.267567) (xy 119.374142 -215.226161) (xy 119.409373 -215.189717)
			(xy 119.449765 -215.159094) (xy 119.494369 -215.135013) (xy 119.542132 -215.118041) (xy 119.566944 -215.112854)
			(xy 119.589804 -215.108536) (xy 119.794782 -214.753444) (xy 119.786908 -214.7316) (xy 119.778329 -214.705181)
			(xy 119.769132 -214.650406) (xy 119.76862 -214.622634) (xy 119.769128 -214.596747) (xy 119.777227 -214.545609)
			(xy 119.793226 -214.496369) (xy 119.816732 -214.450237) (xy 119.847164 -214.40835) (xy 119.883774 -214.37174)
			(xy 119.925661 -214.341308) (xy 119.971793 -214.317802) (xy 120.021033 -214.301803) (xy 120.072171 -214.293704)
			(xy 120.123945 -214.293704) (xy 120.175083 -214.301803) (xy 120.224323 -214.317802) (xy 120.270455 -214.341308)
			(xy 120.312342 -214.37174) (xy 120.348952 -214.40835) (xy 120.379384 -214.450237) (xy 120.40289 -214.496369)
			(xy 120.418889 -214.545609) (xy 120.426988 -214.596747) (xy 120.427496 -214.622634) (xy 120.427047 -214.64797)
			(xy 120.41929 -214.698044) (xy 120.403963 -214.746341) (xy 120.381427 -214.791726) (xy 120.352212 -214.833128)
			(xy 120.317008 -214.869572) (xy 120.276642 -214.900202) (xy 120.232065 -214.924296) (xy 120.184327 -214.941286)
			(xy 120.159526 -214.946484) (xy 120.136666 -214.950802) (xy 119.931688 -215.305894) (xy 119.939562 -215.327738)
			(xy 119.94821 -215.354146) (xy 119.957529 -215.408922) (xy 119.958104 -215.436704) (xy 121.17832 -215.436704)
			(xy 121.178829 -215.41136) (xy 121.1866 -215.36127) (xy 121.201946 -215.31296) (xy 121.224503 -215.267567)
			(xy 121.253742 -215.226161) (xy 121.288973 -215.189717) (xy 121.329365 -215.159094) (xy 121.373969 -215.135013)
			(xy 121.421732 -215.118041) (xy 121.446544 -215.112854) (xy 121.469404 -215.108536) (xy 121.674382 -214.753444)
			(xy 121.666508 -214.7316) (xy 121.657929 -214.705181) (xy 121.648732 -214.650406) (xy 121.64822 -214.622634)
			(xy 121.648728 -214.596747) (xy 121.656827 -214.545609) (xy 121.672826 -214.496369) (xy 121.696332 -214.450237)
			(xy 121.726764 -214.40835) (xy 121.763374 -214.37174) (xy 121.805261 -214.341308) (xy 121.851393 -214.317802)
			(xy 121.900633 -214.301803) (xy 121.951771 -214.293704) (xy 122.003545 -214.293704) (xy 122.054683 -214.301803)
			(xy 122.103923 -214.317802) (xy 122.150055 -214.341308) (xy 122.191942 -214.37174) (xy 122.228552 -214.40835)
			(xy 122.258984 -214.450237) (xy 122.28249 -214.496369) (xy 122.298489 -214.545609) (xy 122.306588 -214.596747)
			(xy 122.307096 -214.622634) (xy 122.306647 -214.64797) (xy 122.29889 -214.698044) (xy 122.283563 -214.746341)
			(xy 122.261027 -214.791726) (xy 122.231812 -214.833128) (xy 122.196608 -214.869572) (xy 122.156242 -214.900202)
			(xy 122.111665 -214.924296) (xy 122.063927 -214.941286) (xy 122.039126 -214.946484) (xy 122.016266 -214.950802)
			(xy 121.811288 -215.305894) (xy 121.819162 -215.327738) (xy 121.82781 -215.354146) (xy 121.837129 -215.408922)
			(xy 121.837704 -215.436704) (xy 123.05792 -215.436704) (xy 123.058429 -215.41136) (xy 123.0662 -215.36127)
			(xy 123.081546 -215.31296) (xy 123.104103 -215.267567) (xy 123.133342 -215.226161) (xy 123.168573 -215.189717)
			(xy 123.208965 -215.159094) (xy 123.253569 -215.135013) (xy 123.301332 -215.118041) (xy 123.326144 -215.112854)
			(xy 123.349004 -215.108536) (xy 123.553982 -214.753444) (xy 123.546108 -214.7316) (xy 123.537529 -214.705181)
			(xy 123.528332 -214.650406) (xy 123.52782 -214.622634) (xy 123.528328 -214.596747) (xy 123.536427 -214.545609)
			(xy 123.552426 -214.496369) (xy 123.575932 -214.450237) (xy 123.606364 -214.40835) (xy 123.642974 -214.37174)
			(xy 123.684861 -214.341308) (xy 123.730993 -214.317802) (xy 123.780233 -214.301803) (xy 123.831371 -214.293704)
			(xy 123.883145 -214.293704) (xy 123.934283 -214.301803) (xy 123.983523 -214.317802) (xy 124.029655 -214.341308)
			(xy 124.071542 -214.37174) (xy 124.108152 -214.40835) (xy 124.138584 -214.450237) (xy 124.16209 -214.496369)
			(xy 124.178089 -214.545609) (xy 124.186188 -214.596747) (xy 124.186696 -214.622634) (xy 124.186247 -214.64797)
			(xy 124.17849 -214.698044) (xy 124.163163 -214.746341) (xy 124.140627 -214.791726) (xy 124.111412 -214.833128)
			(xy 124.076208 -214.869572) (xy 124.035842 -214.900202) (xy 123.991265 -214.924296) (xy 123.943527 -214.941286)
			(xy 123.918726 -214.946484) (xy 123.895866 -214.950802) (xy 123.690888 -215.305894) (xy 123.698762 -215.327738)
			(xy 123.70741 -215.354146) (xy 123.716729 -215.408922) (xy 123.717304 -215.436704) (xy 124.93752 -215.436704)
			(xy 124.938029 -215.41136) (xy 124.9458 -215.36127) (xy 124.961146 -215.31296) (xy 124.983703 -215.267567)
			(xy 125.012942 -215.226161) (xy 125.048173 -215.189717) (xy 125.088565 -215.159094) (xy 125.133169 -215.135013)
			(xy 125.180932 -215.118041) (xy 125.205744 -215.112854) (xy 125.228604 -215.108536) (xy 125.433582 -214.753444)
			(xy 125.425708 -214.7316) (xy 125.417129 -214.705181) (xy 125.407932 -214.650406) (xy 125.40742 -214.622634)
			(xy 125.407928 -214.596747) (xy 125.416027 -214.545609) (xy 125.432026 -214.496369) (xy 125.455532 -214.450237)
			(xy 125.485964 -214.40835) (xy 125.522574 -214.37174) (xy 125.564461 -214.341308) (xy 125.610593 -214.317802)
			(xy 125.659833 -214.301803) (xy 125.710971 -214.293704) (xy 125.762745 -214.293704) (xy 125.813883 -214.301803)
			(xy 125.863123 -214.317802) (xy 125.909255 -214.341308) (xy 125.951142 -214.37174) (xy 125.987752 -214.40835)
			(xy 126.018184 -214.450237) (xy 126.04169 -214.496369) (xy 126.057689 -214.545609) (xy 126.065788 -214.596747)
			(xy 126.066296 -214.622634) (xy 126.065847 -214.64797) (xy 126.05809 -214.698044) (xy 126.042763 -214.746341)
			(xy 126.020227 -214.791726) (xy 125.991012 -214.833128) (xy 125.955808 -214.869572) (xy 125.915442 -214.900202)
			(xy 125.870865 -214.924296) (xy 125.823127 -214.941286) (xy 125.798326 -214.946484) (xy 125.775466 -214.950802)
			(xy 125.570488 -215.305894) (xy 125.578362 -215.327738) (xy 125.58701 -215.354146) (xy 125.596329 -215.408922)
			(xy 125.596904 -215.436704) (xy 126.81712 -215.436704) (xy 126.817629 -215.41136) (xy 126.8254 -215.36127)
			(xy 126.840746 -215.31296) (xy 126.863303 -215.267567) (xy 126.892542 -215.226161) (xy 126.927773 -215.189717)
			(xy 126.968165 -215.159094) (xy 127.012769 -215.135013) (xy 127.060532 -215.118041) (xy 127.085344 -215.112854)
			(xy 127.108204 -215.108536) (xy 127.313182 -214.753444) (xy 127.305308 -214.7316) (xy 127.296729 -214.705181)
			(xy 127.287532 -214.650406) (xy 127.28702 -214.622634) (xy 127.287528 -214.596747) (xy 127.295627 -214.545609)
			(xy 127.311626 -214.496369) (xy 127.335132 -214.450237) (xy 127.365564 -214.40835) (xy 127.402174 -214.37174)
			(xy 127.444061 -214.341308) (xy 127.490193 -214.317802) (xy 127.539433 -214.301803) (xy 127.590571 -214.293704)
			(xy 127.642345 -214.293704) (xy 127.693483 -214.301803) (xy 127.742723 -214.317802) (xy 127.788855 -214.341308)
			(xy 127.830742 -214.37174) (xy 127.867352 -214.40835) (xy 127.897784 -214.450237) (xy 127.92129 -214.496369)
			(xy 127.937289 -214.545609) (xy 127.945388 -214.596747) (xy 127.945896 -214.622634) (xy 127.945447 -214.64797)
			(xy 127.93769 -214.698044) (xy 127.922363 -214.746341) (xy 127.899827 -214.791726) (xy 127.870612 -214.833128)
			(xy 127.835408 -214.869572) (xy 127.795042 -214.900202) (xy 127.750465 -214.924296) (xy 127.702727 -214.941286)
			(xy 127.677926 -214.946484) (xy 127.655066 -214.950802) (xy 127.450088 -215.305894) (xy 127.457962 -215.327738)
			(xy 127.46661 -215.354146) (xy 127.475929 -215.408922) (xy 127.476504 -215.436704) (xy 128.69672 -215.436704)
			(xy 128.697229 -215.41136) (xy 128.705 -215.36127) (xy 128.720346 -215.31296) (xy 128.742903 -215.267567)
			(xy 128.772142 -215.226161) (xy 128.807373 -215.189717) (xy 128.847765 -215.159094) (xy 128.892369 -215.135013)
			(xy 128.940132 -215.118041) (xy 128.964944 -215.112854) (xy 128.987804 -215.108536) (xy 129.192782 -214.753444)
			(xy 129.184908 -214.7316) (xy 129.176329 -214.705181) (xy 129.167132 -214.650406) (xy 129.16662 -214.622634)
			(xy 129.167128 -214.596747) (xy 129.175227 -214.545609) (xy 129.191226 -214.496369) (xy 129.214732 -214.450237)
			(xy 129.245164 -214.40835) (xy 129.281774 -214.37174) (xy 129.323661 -214.341308) (xy 129.369793 -214.317802)
			(xy 129.419033 -214.301803) (xy 129.470171 -214.293704) (xy 129.521945 -214.293704) (xy 129.573083 -214.301803)
			(xy 129.622323 -214.317802) (xy 129.668455 -214.341308) (xy 129.710342 -214.37174) (xy 129.746952 -214.40835)
			(xy 129.777384 -214.450237) (xy 129.80089 -214.496369) (xy 129.816889 -214.545609) (xy 129.824988 -214.596747)
			(xy 129.825496 -214.622634) (xy 129.825047 -214.64797) (xy 129.81729 -214.698044) (xy 129.801963 -214.746341)
			(xy 129.779427 -214.791726) (xy 129.750212 -214.833128) (xy 129.715008 -214.869572) (xy 129.674642 -214.900202)
			(xy 129.630065 -214.924296) (xy 129.582327 -214.941286) (xy 129.557526 -214.946484) (xy 129.534666 -214.950802)
			(xy 129.329688 -215.305894) (xy 129.337562 -215.327738) (xy 129.34621 -215.354146) (xy 129.355529 -215.408922)
			(xy 129.356104 -215.436704) (xy 130.57632 -215.436704) (xy 130.576829 -215.41136) (xy 130.5846 -215.36127)
			(xy 130.599946 -215.31296) (xy 130.622503 -215.267567) (xy 130.651742 -215.226161) (xy 130.686973 -215.189717)
			(xy 130.727365 -215.159094) (xy 130.771969 -215.135013) (xy 130.819732 -215.118041) (xy 130.844544 -215.112854)
			(xy 130.867404 -215.108536) (xy 131.072382 -214.753444) (xy 131.064508 -214.7316) (xy 131.055929 -214.705181)
			(xy 131.046732 -214.650406) (xy 131.04622 -214.622634) (xy 131.046728 -214.596747) (xy 131.054827 -214.545609)
			(xy 131.070826 -214.496369) (xy 131.094332 -214.450237) (xy 131.124764 -214.40835) (xy 131.161374 -214.37174)
			(xy 131.203261 -214.341308) (xy 131.249393 -214.317802) (xy 131.298633 -214.301803) (xy 131.349771 -214.293704)
			(xy 131.401545 -214.293704) (xy 131.452683 -214.301803) (xy 131.501923 -214.317802) (xy 131.548055 -214.341308)
			(xy 131.589942 -214.37174) (xy 131.626552 -214.40835) (xy 131.656984 -214.450237) (xy 131.68049 -214.496369)
			(xy 131.696489 -214.545609) (xy 131.704588 -214.596747) (xy 131.705096 -214.622634) (xy 131.704647 -214.64797)
			(xy 131.69689 -214.698044) (xy 131.681563 -214.746341) (xy 131.659027 -214.791726) (xy 131.629812 -214.833128)
			(xy 131.594608 -214.869572) (xy 131.554242 -214.900202) (xy 131.509665 -214.924296) (xy 131.461927 -214.941286)
			(xy 131.437126 -214.946484) (xy 131.414266 -214.950802) (xy 131.209288 -215.305894) (xy 131.217162 -215.327738)
			(xy 131.22581 -215.354146) (xy 131.235129 -215.408922) (xy 131.235704 -215.436704) (xy 132.45592 -215.436704)
			(xy 132.456429 -215.41136) (xy 132.4642 -215.36127) (xy 132.479546 -215.31296) (xy 132.502103 -215.267567)
			(xy 132.531342 -215.226161) (xy 132.566573 -215.189717) (xy 132.606965 -215.159094) (xy 132.651569 -215.135013)
			(xy 132.699332 -215.118041) (xy 132.724144 -215.112854) (xy 132.747004 -215.108536) (xy 132.951982 -214.753444)
			(xy 132.944108 -214.7316) (xy 132.935529 -214.705181) (xy 132.926332 -214.650406) (xy 132.92582 -214.622634)
			(xy 132.926328 -214.596747) (xy 132.934427 -214.545609) (xy 132.950426 -214.496369) (xy 132.973932 -214.450237)
			(xy 133.004364 -214.40835) (xy 133.040974 -214.37174) (xy 133.082861 -214.341308) (xy 133.128993 -214.317802)
			(xy 133.178233 -214.301803) (xy 133.229371 -214.293704) (xy 133.281145 -214.293704) (xy 133.332283 -214.301803)
			(xy 133.381523 -214.317802) (xy 133.427655 -214.341308) (xy 133.469542 -214.37174) (xy 133.506152 -214.40835)
			(xy 133.536584 -214.450237) (xy 133.56009 -214.496369) (xy 133.576089 -214.545609) (xy 133.57622 -214.546434)
			(xy 134.80542 -214.546434) (xy 134.805928 -214.520527) (xy 134.814034 -214.46935) (xy 134.830046 -214.420071)
			(xy 134.853569 -214.373904) (xy 134.884025 -214.331985) (xy 134.920663 -214.295347) (xy 134.962582 -214.264891)
			(xy 135.008749 -214.241368) (xy 135.058028 -214.225356) (xy 135.109205 -214.21725) (xy 135.161019 -214.21725)
			(xy 135.212196 -214.225356) (xy 135.261475 -214.241368) (xy 135.307642 -214.264891) (xy 135.349561 -214.295347)
			(xy 135.386199 -214.331985) (xy 135.416655 -214.373904) (xy 135.440178 -214.420071) (xy 135.45619 -214.46935)
			(xy 135.464296 -214.520527) (xy 135.464316 -214.521542) (xy 162.162236 -214.521542) (xy 162.162236 -214.112602)
			(xy 162.162735 -214.102445) (xy 162.170508 -214.083676) (xy 162.184873 -214.069311) (xy 162.203641 -214.061536)
			(xy 162.213798 -214.06104) (xy 163.613338 -214.06104) (xy 163.623498 -214.061502) (xy 163.642269 -214.06929)
			(xy 163.656633 -214.083665) (xy 163.664406 -214.102441) (xy 163.6649 -214.112602) (xy 163.6649 -214.521542)
			(xy 169.706036 -214.521542) (xy 169.706036 -214.112602) (xy 169.706535 -214.102445) (xy 169.714308 -214.083676)
			(xy 169.728673 -214.069311) (xy 169.747441 -214.061536) (xy 169.757598 -214.06104) (xy 171.157138 -214.06104)
			(xy 171.167298 -214.061502) (xy 171.186069 -214.06929) (xy 171.200433 -214.083665) (xy 171.208206 -214.102441)
			(xy 171.2087 -214.112602) (xy 171.2087 -214.521542) (xy 177.249836 -214.521542) (xy 177.249836 -214.112602)
			(xy 177.250335 -214.102445) (xy 177.258108 -214.083676) (xy 177.272473 -214.069311) (xy 177.291241 -214.061536)
			(xy 177.301398 -214.06104) (xy 178.700938 -214.06104) (xy 178.711098 -214.061502) (xy 178.729869 -214.06929)
			(xy 178.744233 -214.083665) (xy 178.752006 -214.102441) (xy 178.7525 -214.112602) (xy 178.7525 -214.521542)
			(xy 184.793636 -214.521542) (xy 184.793636 -214.112602) (xy 184.794135 -214.102445) (xy 184.801908 -214.083676)
			(xy 184.816273 -214.069311) (xy 184.835041 -214.061536) (xy 184.845198 -214.06104) (xy 186.244738 -214.06104)
			(xy 186.254898 -214.061502) (xy 186.273669 -214.06929) (xy 186.288033 -214.083665) (xy 186.295806 -214.102441)
			(xy 186.2963 -214.112602) (xy 186.2963 -214.521542) (xy 192.337436 -214.521542) (xy 192.337436 -214.112602)
			(xy 192.337935 -214.102445) (xy 192.345708 -214.083676) (xy 192.360073 -214.069311) (xy 192.378841 -214.061536)
			(xy 192.388998 -214.06104) (xy 193.788538 -214.06104) (xy 193.798698 -214.061502) (xy 193.817469 -214.06929)
			(xy 193.831833 -214.083665) (xy 193.839606 -214.102441) (xy 193.8401 -214.112602) (xy 193.8401 -214.521542)
			(xy 199.881236 -214.521542) (xy 199.881236 -214.112602) (xy 199.881735 -214.102445) (xy 199.889508 -214.083676)
			(xy 199.903873 -214.069311) (xy 199.922641 -214.061536) (xy 199.932798 -214.06104) (xy 201.332338 -214.06104)
			(xy 201.342498 -214.061502) (xy 201.361269 -214.06929) (xy 201.375633 -214.083665) (xy 201.383406 -214.102441)
			(xy 201.3839 -214.112602) (xy 201.3839 -214.521542) (xy 207.425036 -214.521542) (xy 207.425036 -214.112602)
			(xy 207.425535 -214.102445) (xy 207.433308 -214.083676) (xy 207.447673 -214.069311) (xy 207.466441 -214.061536)
			(xy 207.476598 -214.06104) (xy 208.876138 -214.06104) (xy 208.886298 -214.061502) (xy 208.905069 -214.06929)
			(xy 208.919433 -214.083665) (xy 208.927206 -214.102441) (xy 208.9277 -214.112602) (xy 208.9277 -214.521542)
			(xy 214.968836 -214.521542) (xy 214.968836 -214.112602) (xy 214.969335 -214.102445) (xy 214.977108 -214.083676)
			(xy 214.991473 -214.069311) (xy 215.010241 -214.061536) (xy 215.020398 -214.06104) (xy 216.419938 -214.06104)
			(xy 216.430098 -214.061502) (xy 216.448869 -214.06929) (xy 216.463233 -214.083665) (xy 216.471006 -214.102441)
			(xy 216.4715 -214.112602) (xy 216.4715 -214.521542) (xy 259.429504 -214.521542) (xy 259.429504 -214.112602)
			(xy 259.430034 -214.102449) (xy 259.437802 -214.083686) (xy 259.452156 -214.069322) (xy 259.470913 -214.061541)
			(xy 259.481066 -214.06104) (xy 260.880606 -214.06104) (xy 260.890764 -214.061529) (xy 260.909534 -214.069305)
			(xy 260.923899 -214.083673) (xy 260.931673 -214.102444) (xy 260.932168 -214.112602) (xy 260.932168 -214.521542)
			(xy 266.973304 -214.521542) (xy 266.973304 -214.112602) (xy 266.973834 -214.102449) (xy 266.981602 -214.083686)
			(xy 266.995956 -214.069322) (xy 267.014713 -214.061541) (xy 267.024866 -214.06104) (xy 268.424406 -214.06104)
			(xy 268.434564 -214.061529) (xy 268.453334 -214.069305) (xy 268.467699 -214.083673) (xy 268.475473 -214.102444)
			(xy 268.475968 -214.112602) (xy 268.475968 -214.521542) (xy 274.517104 -214.521542) (xy 274.517104 -214.112602)
			(xy 274.517634 -214.102449) (xy 274.525402 -214.083686) (xy 274.539756 -214.069322) (xy 274.558513 -214.061541)
			(xy 274.568666 -214.06104) (xy 275.968206 -214.06104) (xy 275.978364 -214.061529) (xy 275.997134 -214.069305)
			(xy 276.011499 -214.083673) (xy 276.019273 -214.102444) (xy 276.019768 -214.112602) (xy 276.019768 -214.521542)
			(xy 282.060904 -214.521542) (xy 282.060904 -214.112602) (xy 282.061434 -214.102449) (xy 282.069202 -214.083686)
			(xy 282.083556 -214.069322) (xy 282.102313 -214.061541) (xy 282.112466 -214.06104) (xy 283.512006 -214.06104)
			(xy 283.522164 -214.061529) (xy 283.540934 -214.069305) (xy 283.555299 -214.083673) (xy 283.563073 -214.102444)
			(xy 283.563568 -214.112602) (xy 283.563568 -214.521542) (xy 289.604704 -214.521542) (xy 289.604704 -214.112602)
			(xy 289.605234 -214.102449) (xy 289.613002 -214.083686) (xy 289.627356 -214.069322) (xy 289.646113 -214.061541)
			(xy 289.656266 -214.06104) (xy 291.055806 -214.06104) (xy 291.065964 -214.061529) (xy 291.084734 -214.069305)
			(xy 291.099099 -214.083673) (xy 291.106873 -214.102444) (xy 291.107368 -214.112602) (xy 291.107368 -214.521542)
			(xy 297.148504 -214.521542) (xy 297.148504 -214.112602) (xy 297.149034 -214.102449) (xy 297.156802 -214.083686)
			(xy 297.171156 -214.069322) (xy 297.189913 -214.061541) (xy 297.200066 -214.06104) (xy 298.599606 -214.06104)
			(xy 298.609764 -214.061529) (xy 298.628534 -214.069305) (xy 298.642899 -214.083673) (xy 298.650673 -214.102444)
			(xy 298.651168 -214.112602) (xy 298.651168 -214.521542) (xy 304.692304 -214.521542) (xy 304.692304 -214.112602)
			(xy 304.692834 -214.102449) (xy 304.700602 -214.083686) (xy 304.714956 -214.069322) (xy 304.733713 -214.061541)
			(xy 304.743866 -214.06104) (xy 306.143406 -214.06104) (xy 306.153564 -214.061529) (xy 306.172334 -214.069305)
			(xy 306.186699 -214.083673) (xy 306.194473 -214.102444) (xy 306.194968 -214.112602) (xy 306.194968 -214.521542)
			(xy 312.236104 -214.521542) (xy 312.236104 -214.112602) (xy 312.236634 -214.102449) (xy 312.244402 -214.083686)
			(xy 312.258756 -214.069322) (xy 312.277513 -214.061541) (xy 312.287666 -214.06104) (xy 313.687206 -214.06104)
			(xy 313.697364 -214.061529) (xy 313.716134 -214.069305) (xy 313.730499 -214.083673) (xy 313.738273 -214.102444)
			(xy 313.738768 -214.112602) (xy 313.738768 -214.521542) (xy 313.738301 -214.531702) (xy 313.730514 -214.550471)
			(xy 313.71614 -214.564834) (xy 313.697366 -214.572608) (xy 313.687206 -214.573104) (xy 312.287666 -214.573104)
			(xy 312.277511 -214.572596) (xy 312.258749 -214.564818) (xy 312.244387 -214.550457) (xy 312.236606 -214.531697)
			(xy 312.236104 -214.521542) (xy 306.194968 -214.521542) (xy 306.194501 -214.531702) (xy 306.186714 -214.550471)
			(xy 306.17234 -214.564834) (xy 306.153566 -214.572608) (xy 306.143406 -214.573104) (xy 304.743866 -214.573104)
			(xy 304.733711 -214.572596) (xy 304.714949 -214.564818) (xy 304.700587 -214.550457) (xy 304.692806 -214.531697)
			(xy 304.692304 -214.521542) (xy 298.651168 -214.521542) (xy 298.650701 -214.531702) (xy 298.642914 -214.550471)
			(xy 298.62854 -214.564834) (xy 298.609766 -214.572608) (xy 298.599606 -214.573104) (xy 297.200066 -214.573104)
			(xy 297.189911 -214.572596) (xy 297.171149 -214.564818) (xy 297.156787 -214.550457) (xy 297.149006 -214.531697)
			(xy 297.148504 -214.521542) (xy 291.107368 -214.521542) (xy 291.106901 -214.531702) (xy 291.099114 -214.550471)
			(xy 291.08474 -214.564834) (xy 291.065966 -214.572608) (xy 291.055806 -214.573104) (xy 289.656266 -214.573104)
			(xy 289.646111 -214.572596) (xy 289.627349 -214.564818) (xy 289.612987 -214.550457) (xy 289.605206 -214.531697)
			(xy 289.604704 -214.521542) (xy 283.563568 -214.521542) (xy 283.563101 -214.531702) (xy 283.555314 -214.550471)
			(xy 283.54094 -214.564834) (xy 283.522166 -214.572608) (xy 283.512006 -214.573104) (xy 282.112466 -214.573104)
			(xy 282.102311 -214.572596) (xy 282.083549 -214.564818) (xy 282.069187 -214.550457) (xy 282.061406 -214.531697)
			(xy 282.060904 -214.521542) (xy 276.019768 -214.521542) (xy 276.019301 -214.531702) (xy 276.011514 -214.550471)
			(xy 275.99714 -214.564834) (xy 275.978366 -214.572608) (xy 275.968206 -214.573104) (xy 274.568666 -214.573104)
			(xy 274.558511 -214.572596) (xy 274.539749 -214.564818) (xy 274.525387 -214.550457) (xy 274.517606 -214.531697)
			(xy 274.517104 -214.521542) (xy 268.475968 -214.521542) (xy 268.475501 -214.531702) (xy 268.467714 -214.550471)
			(xy 268.45334 -214.564834) (xy 268.434566 -214.572608) (xy 268.424406 -214.573104) (xy 267.024866 -214.573104)
			(xy 267.014711 -214.572596) (xy 266.995949 -214.564818) (xy 266.981587 -214.550457) (xy 266.973806 -214.531697)
			(xy 266.973304 -214.521542) (xy 260.932168 -214.521542) (xy 260.931701 -214.531702) (xy 260.923914 -214.550471)
			(xy 260.90954 -214.564834) (xy 260.890766 -214.572608) (xy 260.880606 -214.573104) (xy 259.481066 -214.573104)
			(xy 259.470911 -214.572596) (xy 259.452149 -214.564818) (xy 259.437787 -214.550457) (xy 259.430006 -214.531697)
			(xy 259.429504 -214.521542) (xy 216.4715 -214.521542) (xy 216.471002 -214.531698) (xy 216.463221 -214.550461)
			(xy 216.448857 -214.564823) (xy 216.430094 -214.572603) (xy 216.419938 -214.573104) (xy 215.020398 -214.573104)
			(xy 215.010245 -214.572569) (xy 214.991484 -214.564802) (xy 214.977121 -214.550449) (xy 214.969339 -214.531694)
			(xy 214.968836 -214.521542) (xy 208.9277 -214.521542) (xy 208.927202 -214.531698) (xy 208.919421 -214.550461)
			(xy 208.905057 -214.564823) (xy 208.886294 -214.572603) (xy 208.876138 -214.573104) (xy 207.476598 -214.573104)
			(xy 207.466445 -214.572569) (xy 207.447684 -214.564802) (xy 207.433321 -214.550449) (xy 207.425539 -214.531694)
			(xy 207.425036 -214.521542) (xy 201.3839 -214.521542) (xy 201.383402 -214.531698) (xy 201.375621 -214.550461)
			(xy 201.361257 -214.564823) (xy 201.342494 -214.572603) (xy 201.332338 -214.573104) (xy 199.932798 -214.573104)
			(xy 199.922645 -214.572569) (xy 199.903884 -214.564802) (xy 199.889521 -214.550449) (xy 199.881739 -214.531694)
			(xy 199.881236 -214.521542) (xy 193.8401 -214.521542) (xy 193.839602 -214.531698) (xy 193.831821 -214.550461)
			(xy 193.817457 -214.564823) (xy 193.798694 -214.572603) (xy 193.788538 -214.573104) (xy 192.388998 -214.573104)
			(xy 192.378845 -214.572569) (xy 192.360084 -214.564802) (xy 192.345721 -214.550449) (xy 192.337939 -214.531694)
			(xy 192.337436 -214.521542) (xy 186.2963 -214.521542) (xy 186.295802 -214.531698) (xy 186.288021 -214.550461)
			(xy 186.273657 -214.564823) (xy 186.254894 -214.572603) (xy 186.244738 -214.573104) (xy 184.845198 -214.573104)
			(xy 184.835045 -214.572569) (xy 184.816284 -214.564802) (xy 184.801921 -214.550449) (xy 184.794139 -214.531694)
			(xy 184.793636 -214.521542) (xy 178.7525 -214.521542) (xy 178.752002 -214.531698) (xy 178.744221 -214.550461)
			(xy 178.729857 -214.564823) (xy 178.711094 -214.572603) (xy 178.700938 -214.573104) (xy 177.301398 -214.573104)
			(xy 177.291245 -214.572569) (xy 177.272484 -214.564802) (xy 177.258121 -214.550449) (xy 177.250339 -214.531694)
			(xy 177.249836 -214.521542) (xy 171.2087 -214.521542) (xy 171.208202 -214.531698) (xy 171.200421 -214.550461)
			(xy 171.186057 -214.564823) (xy 171.167294 -214.572603) (xy 171.157138 -214.573104) (xy 169.757598 -214.573104)
			(xy 169.747445 -214.572569) (xy 169.728684 -214.564802) (xy 169.714321 -214.550449) (xy 169.706539 -214.531694)
			(xy 169.706036 -214.521542) (xy 163.6649 -214.521542) (xy 163.664402 -214.531698) (xy 163.656621 -214.550461)
			(xy 163.642257 -214.564823) (xy 163.623494 -214.572603) (xy 163.613338 -214.573104) (xy 162.213798 -214.573104)
			(xy 162.203645 -214.572569) (xy 162.184884 -214.564802) (xy 162.170521 -214.550449) (xy 162.162739 -214.531694)
			(xy 162.162236 -214.521542) (xy 135.464316 -214.521542) (xy 135.464804 -214.546434) (xy 135.464102 -214.577275)
			(xy 135.452589 -214.637875) (xy 135.441944 -214.66683) (xy 135.433308 -214.688674) (xy 135.656066 -215.110314)
			(xy 135.678672 -215.115394) (xy 135.702597 -215.121362) (xy 135.748484 -215.139404) (xy 135.791171 -215.164081)
			(xy 135.829706 -215.194841) (xy 135.863229 -215.230999) (xy 135.890992 -215.271747) (xy 135.912374 -215.316176)
			(xy 135.9269 -215.363294) (xy 135.928125 -215.371426) (xy 158.062168 -215.371426) (xy 158.062168 -214.962486)
			(xy 158.062553 -214.95231) (xy 158.070348 -214.933509) (xy 158.084746 -214.919124) (xy 158.103553 -214.911345)
			(xy 158.11373 -214.910924) (xy 159.51327 -214.910924) (xy 159.523438 -214.911388) (xy 159.542229 -214.919161)
			(xy 159.556615 -214.933534) (xy 159.564403 -214.952318) (xy 159.564832 -214.962486) (xy 159.564832 -215.371426)
			(xy 165.605968 -215.371426) (xy 165.605968 -214.962486) (xy 165.606353 -214.95231) (xy 165.614148 -214.933509)
			(xy 165.628546 -214.919124) (xy 165.647353 -214.911345) (xy 165.65753 -214.910924) (xy 167.05707 -214.910924)
			(xy 167.067238 -214.911388) (xy 167.086029 -214.919161) (xy 167.100415 -214.933534) (xy 167.108203 -214.952318)
			(xy 167.108632 -214.962486) (xy 167.108632 -215.371426) (xy 173.149768 -215.371426) (xy 173.149768 -214.962486)
			(xy 173.150153 -214.95231) (xy 173.157948 -214.933509) (xy 173.172346 -214.919124) (xy 173.191153 -214.911345)
			(xy 173.20133 -214.910924) (xy 174.60087 -214.910924) (xy 174.611038 -214.911388) (xy 174.629829 -214.919161)
			(xy 174.644215 -214.933534) (xy 174.652003 -214.952318) (xy 174.652432 -214.962486) (xy 174.652432 -215.371426)
			(xy 180.693568 -215.371426) (xy 180.693568 -214.962486) (xy 180.693953 -214.95231) (xy 180.701748 -214.933509)
			(xy 180.716146 -214.919124) (xy 180.734953 -214.911345) (xy 180.74513 -214.910924) (xy 182.14467 -214.910924)
			(xy 182.154838 -214.911388) (xy 182.173629 -214.919161) (xy 182.188015 -214.933534) (xy 182.195803 -214.952318)
			(xy 182.196232 -214.962486) (xy 182.196232 -215.371426) (xy 188.237368 -215.371426) (xy 188.237368 -214.962486)
			(xy 188.237753 -214.95231) (xy 188.245548 -214.933509) (xy 188.259946 -214.919124) (xy 188.278753 -214.911345)
			(xy 188.28893 -214.910924) (xy 189.68847 -214.910924) (xy 189.698638 -214.911388) (xy 189.717429 -214.919161)
			(xy 189.731815 -214.933534) (xy 189.739603 -214.952318) (xy 189.740032 -214.962486) (xy 189.740032 -215.371426)
			(xy 195.781168 -215.371426) (xy 195.781168 -214.962486) (xy 195.781553 -214.95231) (xy 195.789348 -214.933509)
			(xy 195.803746 -214.919124) (xy 195.822553 -214.911345) (xy 195.83273 -214.910924) (xy 197.23227 -214.910924)
			(xy 197.242438 -214.911388) (xy 197.261229 -214.919161) (xy 197.275615 -214.933534) (xy 197.283403 -214.952318)
			(xy 197.283832 -214.962486) (xy 197.283832 -215.371426) (xy 203.324968 -215.371426) (xy 203.324968 -214.962486)
			(xy 203.325353 -214.95231) (xy 203.333148 -214.933509) (xy 203.347546 -214.919124) (xy 203.366353 -214.911345)
			(xy 203.37653 -214.910924) (xy 204.77607 -214.910924) (xy 204.786238 -214.911388) (xy 204.805029 -214.919161)
			(xy 204.819415 -214.933534) (xy 204.827203 -214.952318) (xy 204.827632 -214.962486) (xy 204.827632 -215.371426)
			(xy 210.868768 -215.371426) (xy 210.868768 -214.962486) (xy 210.869153 -214.95231) (xy 210.876948 -214.933509)
			(xy 210.891346 -214.919124) (xy 210.910153 -214.911345) (xy 210.92033 -214.910924) (xy 212.31987 -214.910924)
			(xy 212.330038 -214.911388) (xy 212.348829 -214.919161) (xy 212.363215 -214.933534) (xy 212.371003 -214.952318)
			(xy 212.371432 -214.962486) (xy 212.371432 -215.371426) (xy 255.329436 -215.371426) (xy 255.329436 -214.962486)
			(xy 255.329922 -214.952328) (xy 255.337701 -214.933559) (xy 255.352069 -214.919194) (xy 255.37084 -214.91142)
			(xy 255.380998 -214.910924) (xy 256.780538 -214.910924) (xy 256.790696 -214.911402) (xy 256.809464 -214.919186)
			(xy 256.823827 -214.933556) (xy 256.831603 -214.952327) (xy 256.8321 -214.962486) (xy 256.8321 -215.371426)
			(xy 262.873236 -215.371426) (xy 262.873236 -214.962486) (xy 262.873722 -214.952328) (xy 262.881501 -214.933559)
			(xy 262.895869 -214.919194) (xy 262.91464 -214.91142) (xy 262.924798 -214.910924) (xy 264.324338 -214.910924)
			(xy 264.334496 -214.911402) (xy 264.353264 -214.919186) (xy 264.367627 -214.933556) (xy 264.375403 -214.952327)
			(xy 264.3759 -214.962486) (xy 264.3759 -215.371426) (xy 270.417036 -215.371426) (xy 270.417036 -214.962486)
			(xy 270.417522 -214.952328) (xy 270.425301 -214.933559) (xy 270.439669 -214.919194) (xy 270.45844 -214.91142)
			(xy 270.468598 -214.910924) (xy 271.868138 -214.910924) (xy 271.878296 -214.911402) (xy 271.897064 -214.919186)
			(xy 271.911427 -214.933556) (xy 271.919203 -214.952327) (xy 271.9197 -214.962486) (xy 271.9197 -215.371426)
			(xy 277.960836 -215.371426) (xy 277.960836 -214.962486) (xy 277.961322 -214.952328) (xy 277.969101 -214.933559)
			(xy 277.983469 -214.919194) (xy 278.00224 -214.91142) (xy 278.012398 -214.910924) (xy 279.411938 -214.910924)
			(xy 279.422096 -214.911402) (xy 279.440864 -214.919186) (xy 279.455227 -214.933556) (xy 279.463003 -214.952327)
			(xy 279.4635 -214.962486) (xy 279.4635 -215.371426) (xy 285.504636 -215.371426) (xy 285.504636 -214.962486)
			(xy 285.505122 -214.952328) (xy 285.512901 -214.933559) (xy 285.527269 -214.919194) (xy 285.54604 -214.91142)
			(xy 285.556198 -214.910924) (xy 286.955738 -214.910924) (xy 286.965896 -214.911402) (xy 286.984664 -214.919186)
			(xy 286.999027 -214.933556) (xy 287.006803 -214.952327) (xy 287.0073 -214.962486) (xy 287.0073 -215.371426)
			(xy 293.048436 -215.371426) (xy 293.048436 -214.962486) (xy 293.048922 -214.952328) (xy 293.056701 -214.933559)
			(xy 293.071069 -214.919194) (xy 293.08984 -214.91142) (xy 293.099998 -214.910924) (xy 294.499538 -214.910924)
			(xy 294.509696 -214.911402) (xy 294.528464 -214.919186) (xy 294.542827 -214.933556) (xy 294.550603 -214.952327)
			(xy 294.5511 -214.962486) (xy 294.5511 -215.371426) (xy 300.592236 -215.371426) (xy 300.592236 -214.962486)
			(xy 300.592722 -214.952328) (xy 300.600501 -214.933559) (xy 300.614869 -214.919194) (xy 300.63364 -214.91142)
			(xy 300.643798 -214.910924) (xy 302.043338 -214.910924) (xy 302.053496 -214.911402) (xy 302.072264 -214.919186)
			(xy 302.086627 -214.933556) (xy 302.094403 -214.952327) (xy 302.0949 -214.962486) (xy 302.0949 -215.371426)
			(xy 308.136036 -215.371426) (xy 308.136036 -214.962486) (xy 308.136522 -214.952328) (xy 308.144301 -214.933559)
			(xy 308.158669 -214.919194) (xy 308.17744 -214.91142) (xy 308.187598 -214.910924) (xy 309.587138 -214.910924)
			(xy 309.597296 -214.911402) (xy 309.616064 -214.919186) (xy 309.630427 -214.933556) (xy 309.638203 -214.952327)
			(xy 309.6387 -214.962486) (xy 309.6387 -215.371426) (xy 309.638189 -215.381581) (xy 309.630413 -215.400343)
			(xy 309.616053 -215.414706) (xy 309.597293 -215.422487) (xy 309.587138 -215.422988) (xy 308.187598 -215.422988)
			(xy 308.177443 -215.422469) (xy 308.158679 -215.414699) (xy 308.144315 -215.400341) (xy 308.136536 -215.38158)
			(xy 308.136036 -215.371426) (xy 302.0949 -215.371426) (xy 302.094389 -215.381581) (xy 302.086613 -215.400343)
			(xy 302.072253 -215.414706) (xy 302.053493 -215.422487) (xy 302.043338 -215.422988) (xy 300.643798 -215.422988)
			(xy 300.633643 -215.422469) (xy 300.614879 -215.414699) (xy 300.600515 -215.400341) (xy 300.592736 -215.38158)
			(xy 300.592236 -215.371426) (xy 294.5511 -215.371426) (xy 294.550589 -215.381581) (xy 294.542813 -215.400343)
			(xy 294.528453 -215.414706) (xy 294.509693 -215.422487) (xy 294.499538 -215.422988) (xy 293.099998 -215.422988)
			(xy 293.089843 -215.422469) (xy 293.071079 -215.414699) (xy 293.056715 -215.400341) (xy 293.048936 -215.38158)
			(xy 293.048436 -215.371426) (xy 287.0073 -215.371426) (xy 287.006789 -215.381581) (xy 286.999013 -215.400343)
			(xy 286.984653 -215.414706) (xy 286.965893 -215.422487) (xy 286.955738 -215.422988) (xy 285.556198 -215.422988)
			(xy 285.546043 -215.422469) (xy 285.527279 -215.414699) (xy 285.512915 -215.400341) (xy 285.505136 -215.38158)
			(xy 285.504636 -215.371426) (xy 279.4635 -215.371426) (xy 279.462989 -215.381581) (xy 279.455213 -215.400343)
			(xy 279.440853 -215.414706) (xy 279.422093 -215.422487) (xy 279.411938 -215.422988) (xy 278.012398 -215.422988)
			(xy 278.002243 -215.422469) (xy 277.983479 -215.414699) (xy 277.969115 -215.400341) (xy 277.961336 -215.38158)
			(xy 277.960836 -215.371426) (xy 271.9197 -215.371426) (xy 271.919189 -215.381581) (xy 271.911413 -215.400343)
			(xy 271.897053 -215.414706) (xy 271.878293 -215.422487) (xy 271.868138 -215.422988) (xy 270.468598 -215.422988)
			(xy 270.458443 -215.422469) (xy 270.439679 -215.414699) (xy 270.425315 -215.400341) (xy 270.417536 -215.38158)
			(xy 270.417036 -215.371426) (xy 264.3759 -215.371426) (xy 264.375389 -215.381581) (xy 264.367613 -215.400343)
			(xy 264.353253 -215.414706) (xy 264.334493 -215.422487) (xy 264.324338 -215.422988) (xy 262.924798 -215.422988)
			(xy 262.914643 -215.422469) (xy 262.895879 -215.414699) (xy 262.881515 -215.400341) (xy 262.873736 -215.38158)
			(xy 262.873236 -215.371426) (xy 256.8321 -215.371426) (xy 256.831589 -215.381581) (xy 256.823813 -215.400343)
			(xy 256.809453 -215.414706) (xy 256.790693 -215.422487) (xy 256.780538 -215.422988) (xy 255.380998 -215.422988)
			(xy 255.370843 -215.422469) (xy 255.352079 -215.414699) (xy 255.337715 -215.400341) (xy 255.329936 -215.38158)
			(xy 255.329436 -215.371426) (xy 212.371432 -215.371426) (xy 212.371057 -215.381603) (xy 212.363258 -215.400404)
			(xy 212.348857 -215.414789) (xy 212.330048 -215.422568) (xy 212.31987 -215.422988) (xy 210.92033 -215.422988)
			(xy 210.910164 -215.422512) (xy 210.891375 -215.414742) (xy 210.87699 -215.400372) (xy 210.869199 -215.381592)
			(xy 210.868768 -215.371426) (xy 204.827632 -215.371426) (xy 204.827257 -215.381603) (xy 204.819458 -215.400404)
			(xy 204.805057 -215.414789) (xy 204.786248 -215.422568) (xy 204.77607 -215.422988) (xy 203.37653 -215.422988)
			(xy 203.366364 -215.422512) (xy 203.347575 -215.414742) (xy 203.33319 -215.400372) (xy 203.325399 -215.381592)
			(xy 203.324968 -215.371426) (xy 197.283832 -215.371426) (xy 197.283457 -215.381603) (xy 197.275658 -215.400404)
			(xy 197.261257 -215.414789) (xy 197.242448 -215.422568) (xy 197.23227 -215.422988) (xy 195.83273 -215.422988)
			(xy 195.822564 -215.422512) (xy 195.803775 -215.414742) (xy 195.78939 -215.400372) (xy 195.781599 -215.381592)
			(xy 195.781168 -215.371426) (xy 189.740032 -215.371426) (xy 189.739657 -215.381603) (xy 189.731858 -215.400404)
			(xy 189.717457 -215.414789) (xy 189.698648 -215.422568) (xy 189.68847 -215.422988) (xy 188.28893 -215.422988)
			(xy 188.278764 -215.422512) (xy 188.259975 -215.414742) (xy 188.24559 -215.400372) (xy 188.237799 -215.381592)
			(xy 188.237368 -215.371426) (xy 182.196232 -215.371426) (xy 182.195857 -215.381603) (xy 182.188058 -215.400404)
			(xy 182.173657 -215.414789) (xy 182.154848 -215.422568) (xy 182.14467 -215.422988) (xy 180.74513 -215.422988)
			(xy 180.734964 -215.422512) (xy 180.716175 -215.414742) (xy 180.70179 -215.400372) (xy 180.693999 -215.381592)
			(xy 180.693568 -215.371426) (xy 174.652432 -215.371426) (xy 174.652057 -215.381603) (xy 174.644258 -215.400404)
			(xy 174.629857 -215.414789) (xy 174.611048 -215.422568) (xy 174.60087 -215.422988) (xy 173.20133 -215.422988)
			(xy 173.191164 -215.422512) (xy 173.172375 -215.414742) (xy 173.15799 -215.400372) (xy 173.150199 -215.381592)
			(xy 173.149768 -215.371426) (xy 167.108632 -215.371426) (xy 167.108257 -215.381603) (xy 167.100458 -215.400404)
			(xy 167.086057 -215.414789) (xy 167.067248 -215.422568) (xy 167.05707 -215.422988) (xy 165.65753 -215.422988)
			(xy 165.647364 -215.422512) (xy 165.628575 -215.414742) (xy 165.61419 -215.400372) (xy 165.606399 -215.381592)
			(xy 165.605968 -215.371426) (xy 159.564832 -215.371426) (xy 159.564457 -215.381603) (xy 159.556658 -215.400404)
			(xy 159.542257 -215.414789) (xy 159.523448 -215.422568) (xy 159.51327 -215.422988) (xy 158.11373 -215.422988)
			(xy 158.103564 -215.422512) (xy 158.084775 -215.414742) (xy 158.07039 -215.400372) (xy 158.062599 -215.381592)
			(xy 158.062168 -215.371426) (xy 135.928125 -215.371426) (xy 135.934244 -215.412051) (xy 135.934704 -215.436704)
			(xy 336.225388 -215.436704) (xy 336.225896 -215.410797) (xy 336.234002 -215.35962) (xy 336.250014 -215.310341)
			(xy 336.273537 -215.264174) (xy 336.303993 -215.222255) (xy 336.340631 -215.185617) (xy 336.38255 -215.155161)
			(xy 336.428717 -215.131638) (xy 336.477996 -215.115626) (xy 336.529173 -215.10752) (xy 336.580987 -215.10752)
			(xy 336.632164 -215.115626) (xy 336.681443 -215.131638) (xy 336.72761 -215.155161) (xy 336.769529 -215.185617)
			(xy 336.806167 -215.222255) (xy 336.836623 -215.264174) (xy 336.860146 -215.310341) (xy 336.876158 -215.35962)
			(xy 336.884264 -215.410797) (xy 336.884772 -215.436704) (xy 337.165188 -215.436704) (xy 337.165723 -215.411361)
			(xy 337.173493 -215.361274) (xy 337.188837 -215.312966) (xy 337.211392 -215.267575) (xy 337.240627 -215.226169)
			(xy 337.275854 -215.189725) (xy 337.316243 -215.159101) (xy 337.360842 -215.135018) (xy 337.408601 -215.118043)
			(xy 337.433412 -215.112854) (xy 337.456272 -215.108536) (xy 337.66125 -214.753444) (xy 337.653376 -214.7316)
			(xy 337.644799 -214.705181) (xy 337.6356 -214.650406) (xy 337.635088 -214.622634) (xy 337.635596 -214.596747)
			(xy 337.643695 -214.545609) (xy 337.659694 -214.496369) (xy 337.6832 -214.450237) (xy 337.713632 -214.40835)
			(xy 337.750242 -214.37174) (xy 337.792129 -214.341308) (xy 337.838261 -214.317802) (xy 337.887501 -214.301803)
			(xy 337.938639 -214.293704) (xy 337.990413 -214.293704) (xy 338.041551 -214.301803) (xy 338.090791 -214.317802)
			(xy 338.136923 -214.341308) (xy 338.17881 -214.37174) (xy 338.21542 -214.40835) (xy 338.245852 -214.450237)
			(xy 338.269358 -214.496369) (xy 338.285357 -214.545609) (xy 338.293456 -214.596747) (xy 338.293964 -214.622634)
			(xy 338.293541 -214.647971) (xy 338.285783 -214.698047) (xy 338.270454 -214.746347) (xy 338.247915 -214.791733)
			(xy 338.218698 -214.833136) (xy 338.18349 -214.869581) (xy 338.14312 -214.90021) (xy 338.098539 -214.924301)
			(xy 338.050797 -214.941288) (xy 338.025994 -214.946484) (xy 338.003134 -214.950802) (xy 337.798156 -215.305894)
			(xy 337.80603 -215.327738) (xy 337.814677 -215.354146) (xy 337.823997 -215.408922) (xy 337.824572 -215.436704)
			(xy 339.044788 -215.436704) (xy 339.045323 -215.411361) (xy 339.053093 -215.361274) (xy 339.068437 -215.312966)
			(xy 339.090992 -215.267575) (xy 339.120227 -215.226169) (xy 339.155454 -215.189725) (xy 339.195843 -215.159101)
			(xy 339.240442 -215.135018) (xy 339.288201 -215.118043) (xy 339.313012 -215.112854) (xy 339.335872 -215.108536)
			(xy 339.54085 -214.753444) (xy 339.532976 -214.7316) (xy 339.524399 -214.705181) (xy 339.5152 -214.650406)
			(xy 339.514688 -214.622634) (xy 339.515196 -214.596747) (xy 339.523295 -214.545609) (xy 339.539294 -214.496369)
			(xy 339.5628 -214.450237) (xy 339.593232 -214.40835) (xy 339.629842 -214.37174) (xy 339.671729 -214.341308)
			(xy 339.717861 -214.317802) (xy 339.767101 -214.301803) (xy 339.818239 -214.293704) (xy 339.870013 -214.293704)
			(xy 339.921151 -214.301803) (xy 339.970391 -214.317802) (xy 340.016523 -214.341308) (xy 340.05841 -214.37174)
			(xy 340.09502 -214.40835) (xy 340.125452 -214.450237) (xy 340.148958 -214.496369) (xy 340.164957 -214.545609)
			(xy 340.173056 -214.596747) (xy 340.173564 -214.622634) (xy 340.173141 -214.647971) (xy 340.165383 -214.698047)
			(xy 340.150054 -214.746347) (xy 340.127515 -214.791733) (xy 340.098298 -214.833136) (xy 340.06309 -214.869581)
			(xy 340.02272 -214.90021) (xy 339.978139 -214.924301) (xy 339.930397 -214.941288) (xy 339.905594 -214.946484)
			(xy 339.882734 -214.950802) (xy 339.677756 -215.305894) (xy 339.68563 -215.327738) (xy 339.694277 -215.354146)
			(xy 339.703597 -215.408922) (xy 339.704172 -215.436704) (xy 340.924388 -215.436704) (xy 340.924923 -215.411361)
			(xy 340.932693 -215.361274) (xy 340.948037 -215.312966) (xy 340.970592 -215.267575) (xy 340.999827 -215.226169)
			(xy 341.035054 -215.189725) (xy 341.075443 -215.159101) (xy 341.120042 -215.135018) (xy 341.167801 -215.118043)
			(xy 341.192612 -215.112854) (xy 341.215472 -215.108536) (xy 341.42045 -214.753444) (xy 341.412576 -214.7316)
			(xy 341.403999 -214.705181) (xy 341.3948 -214.650406) (xy 341.394288 -214.622634) (xy 341.394796 -214.596747)
			(xy 341.402895 -214.545609) (xy 341.418894 -214.496369) (xy 341.4424 -214.450237) (xy 341.472832 -214.40835)
			(xy 341.509442 -214.37174) (xy 341.551329 -214.341308) (xy 341.597461 -214.317802) (xy 341.646701 -214.301803)
			(xy 341.697839 -214.293704) (xy 341.749613 -214.293704) (xy 341.800751 -214.301803) (xy 341.849991 -214.317802)
			(xy 341.896123 -214.341308) (xy 341.93801 -214.37174) (xy 341.97462 -214.40835) (xy 342.005052 -214.450237)
			(xy 342.028558 -214.496369) (xy 342.044557 -214.545609) (xy 342.052656 -214.596747) (xy 342.053164 -214.622634)
			(xy 342.052741 -214.647971) (xy 342.044983 -214.698047) (xy 342.029654 -214.746347) (xy 342.007115 -214.791733)
			(xy 341.977898 -214.833136) (xy 341.94269 -214.869581) (xy 341.90232 -214.90021) (xy 341.857739 -214.924301)
			(xy 341.809997 -214.941288) (xy 341.785194 -214.946484) (xy 341.762334 -214.950802) (xy 341.557356 -215.305894)
			(xy 341.56523 -215.327738) (xy 341.573877 -215.354146) (xy 341.583197 -215.408922) (xy 341.583772 -215.436704)
			(xy 342.803988 -215.436704) (xy 342.804523 -215.411361) (xy 342.812293 -215.361274) (xy 342.827637 -215.312966)
			(xy 342.850192 -215.267575) (xy 342.879427 -215.226169) (xy 342.914654 -215.189725) (xy 342.955043 -215.159101)
			(xy 342.999642 -215.135018) (xy 343.047401 -215.118043) (xy 343.072212 -215.112854) (xy 343.095072 -215.108536)
			(xy 343.30005 -214.753444) (xy 343.292176 -214.7316) (xy 343.283599 -214.705181) (xy 343.2744 -214.650406)
			(xy 343.273888 -214.622634) (xy 343.274396 -214.596747) (xy 343.282495 -214.545609) (xy 343.298494 -214.496369)
			(xy 343.322 -214.450237) (xy 343.352432 -214.40835) (xy 343.389042 -214.37174) (xy 343.430929 -214.341308)
			(xy 343.477061 -214.317802) (xy 343.526301 -214.301803) (xy 343.577439 -214.293704) (xy 343.629213 -214.293704)
			(xy 343.680351 -214.301803) (xy 343.729591 -214.317802) (xy 343.775723 -214.341308) (xy 343.81761 -214.37174)
			(xy 343.85422 -214.40835) (xy 343.884652 -214.450237) (xy 343.908158 -214.496369) (xy 343.924157 -214.545609)
			(xy 343.932256 -214.596747) (xy 343.932764 -214.622634) (xy 343.932341 -214.647971) (xy 343.924583 -214.698047)
			(xy 343.909254 -214.746347) (xy 343.886715 -214.791733) (xy 343.857498 -214.833136) (xy 343.82229 -214.869581)
			(xy 343.78192 -214.90021) (xy 343.737339 -214.924301) (xy 343.689597 -214.941288) (xy 343.664794 -214.946484)
			(xy 343.641934 -214.950802) (xy 343.436956 -215.305894) (xy 343.44483 -215.327738) (xy 343.453477 -215.354146)
			(xy 343.462797 -215.408922) (xy 343.463372 -215.436704) (xy 344.683588 -215.436704) (xy 344.684123 -215.411361)
			(xy 344.691893 -215.361274) (xy 344.707237 -215.312966) (xy 344.729792 -215.267575) (xy 344.759027 -215.226169)
			(xy 344.794254 -215.189725) (xy 344.834643 -215.159101) (xy 344.879242 -215.135018) (xy 344.927001 -215.118043)
			(xy 344.951812 -215.112854) (xy 344.974672 -215.108536) (xy 345.17965 -214.753444) (xy 345.171776 -214.7316)
			(xy 345.163199 -214.705181) (xy 345.154 -214.650406) (xy 345.153488 -214.622634) (xy 345.153996 -214.596747)
			(xy 345.162095 -214.545609) (xy 345.178094 -214.496369) (xy 345.2016 -214.450237) (xy 345.232032 -214.40835)
			(xy 345.268642 -214.37174) (xy 345.310529 -214.341308) (xy 345.356661 -214.317802) (xy 345.405901 -214.301803)
			(xy 345.457039 -214.293704) (xy 345.508813 -214.293704) (xy 345.559951 -214.301803) (xy 345.609191 -214.317802)
			(xy 345.655323 -214.341308) (xy 345.69721 -214.37174) (xy 345.73382 -214.40835) (xy 345.764252 -214.450237)
			(xy 345.787758 -214.496369) (xy 345.803757 -214.545609) (xy 345.811856 -214.596747) (xy 345.812364 -214.622634)
			(xy 345.811941 -214.647971) (xy 345.804183 -214.698047) (xy 345.788854 -214.746347) (xy 345.766315 -214.791733)
			(xy 345.737098 -214.833136) (xy 345.70189 -214.869581) (xy 345.66152 -214.90021) (xy 345.616939 -214.924301)
			(xy 345.569197 -214.941288) (xy 345.544394 -214.946484) (xy 345.521534 -214.950802) (xy 345.316556 -215.305894)
			(xy 345.32443 -215.327738) (xy 345.333077 -215.354146) (xy 345.342397 -215.408922) (xy 345.342972 -215.436704)
			(xy 346.563188 -215.436704) (xy 346.563723 -215.411361) (xy 346.571493 -215.361274) (xy 346.586837 -215.312966)
			(xy 346.609392 -215.267575) (xy 346.638627 -215.226169) (xy 346.673854 -215.189725) (xy 346.714243 -215.159101)
			(xy 346.758842 -215.135018) (xy 346.806601 -215.118043) (xy 346.831412 -215.112854) (xy 346.854272 -215.108536)
			(xy 347.05925 -214.753444) (xy 347.051376 -214.7316) (xy 347.042799 -214.705181) (xy 347.0336 -214.650406)
			(xy 347.033088 -214.622634) (xy 347.033596 -214.596747) (xy 347.041695 -214.545609) (xy 347.057694 -214.496369)
			(xy 347.0812 -214.450237) (xy 347.111632 -214.40835) (xy 347.148242 -214.37174) (xy 347.190129 -214.341308)
			(xy 347.236261 -214.317802) (xy 347.285501 -214.301803) (xy 347.336639 -214.293704) (xy 347.388413 -214.293704)
			(xy 347.439551 -214.301803) (xy 347.488791 -214.317802) (xy 347.534923 -214.341308) (xy 347.57681 -214.37174)
			(xy 347.61342 -214.40835) (xy 347.643852 -214.450237) (xy 347.667358 -214.496369) (xy 347.683357 -214.545609)
			(xy 347.691456 -214.596747) (xy 347.691964 -214.622634) (xy 347.691541 -214.647971) (xy 347.683783 -214.698047)
			(xy 347.668454 -214.746347) (xy 347.645915 -214.791733) (xy 347.616698 -214.833136) (xy 347.58149 -214.869581)
			(xy 347.54112 -214.90021) (xy 347.496539 -214.924301) (xy 347.448797 -214.941288) (xy 347.423994 -214.946484)
			(xy 347.401134 -214.950802) (xy 347.196156 -215.305894) (xy 347.20403 -215.327738) (xy 347.212677 -215.354146)
			(xy 347.221997 -215.408922) (xy 347.222572 -215.436704) (xy 348.442788 -215.436704) (xy 348.443323 -215.411361)
			(xy 348.451093 -215.361274) (xy 348.466437 -215.312966) (xy 348.488992 -215.267575) (xy 348.518227 -215.226169)
			(xy 348.553454 -215.189725) (xy 348.593843 -215.159101) (xy 348.638442 -215.135018) (xy 348.686201 -215.118043)
			(xy 348.711012 -215.112854) (xy 348.733872 -215.108536) (xy 348.93885 -214.753444) (xy 348.930976 -214.7316)
			(xy 348.922399 -214.705181) (xy 348.9132 -214.650406) (xy 348.912688 -214.622634) (xy 348.913196 -214.596747)
			(xy 348.921295 -214.545609) (xy 348.937294 -214.496369) (xy 348.9608 -214.450237) (xy 348.991232 -214.40835)
			(xy 349.027842 -214.37174) (xy 349.069729 -214.341308) (xy 349.115861 -214.317802) (xy 349.165101 -214.301803)
			(xy 349.216239 -214.293704) (xy 349.268013 -214.293704) (xy 349.319151 -214.301803) (xy 349.368391 -214.317802)
			(xy 349.414523 -214.341308) (xy 349.45641 -214.37174) (xy 349.49302 -214.40835) (xy 349.523452 -214.450237)
			(xy 349.546958 -214.496369) (xy 349.562957 -214.545609) (xy 349.571056 -214.596747) (xy 349.571564 -214.622634)
			(xy 349.571141 -214.647971) (xy 349.563383 -214.698047) (xy 349.548054 -214.746347) (xy 349.525515 -214.791733)
			(xy 349.496298 -214.833136) (xy 349.46109 -214.869581) (xy 349.42072 -214.90021) (xy 349.376139 -214.924301)
			(xy 349.328397 -214.941288) (xy 349.303594 -214.946484) (xy 349.280734 -214.950802) (xy 349.075756 -215.305894)
			(xy 349.08363 -215.327738) (xy 349.092277 -215.354146) (xy 349.101597 -215.408922) (xy 349.102172 -215.436704)
			(xy 350.322388 -215.436704) (xy 350.322923 -215.411361) (xy 350.330693 -215.361274) (xy 350.346037 -215.312966)
			(xy 350.368592 -215.267575) (xy 350.397827 -215.226169) (xy 350.433054 -215.189725) (xy 350.473443 -215.159101)
			(xy 350.518042 -215.135018) (xy 350.565801 -215.118043) (xy 350.590612 -215.112854) (xy 350.613472 -215.108536)
			(xy 350.81845 -214.753444) (xy 350.810576 -214.7316) (xy 350.801999 -214.705181) (xy 350.7928 -214.650406)
			(xy 350.792288 -214.622634) (xy 350.792796 -214.596747) (xy 350.800895 -214.545609) (xy 350.816894 -214.496369)
			(xy 350.8404 -214.450237) (xy 350.870832 -214.40835) (xy 350.907442 -214.37174) (xy 350.949329 -214.341308)
			(xy 350.995461 -214.317802) (xy 351.044701 -214.301803) (xy 351.095839 -214.293704) (xy 351.147613 -214.293704)
			(xy 351.198751 -214.301803) (xy 351.247991 -214.317802) (xy 351.294123 -214.341308) (xy 351.33601 -214.37174)
			(xy 351.37262 -214.40835) (xy 351.403052 -214.450237) (xy 351.426558 -214.496369) (xy 351.442557 -214.545609)
			(xy 351.450656 -214.596747) (xy 351.451164 -214.622634) (xy 351.450741 -214.647971) (xy 351.442983 -214.698047)
			(xy 351.427654 -214.746347) (xy 351.405115 -214.791733) (xy 351.375898 -214.833136) (xy 351.34069 -214.869581)
			(xy 351.30032 -214.90021) (xy 351.255739 -214.924301) (xy 351.207997 -214.941288) (xy 351.183194 -214.946484)
			(xy 351.160334 -214.950802) (xy 350.955356 -215.305894) (xy 350.96323 -215.327738) (xy 350.971877 -215.354146)
			(xy 350.981197 -215.408922) (xy 350.981772 -215.436704) (xy 352.201988 -215.436704) (xy 352.202523 -215.411361)
			(xy 352.210293 -215.361274) (xy 352.225637 -215.312966) (xy 352.248192 -215.267575) (xy 352.277427 -215.226169)
			(xy 352.312654 -215.189725) (xy 352.353043 -215.159101) (xy 352.397642 -215.135018) (xy 352.445401 -215.118043)
			(xy 352.470212 -215.112854) (xy 352.493072 -215.108536) (xy 352.69805 -214.753444) (xy 352.690176 -214.7316)
			(xy 352.681599 -214.705181) (xy 352.6724 -214.650406) (xy 352.671888 -214.622634) (xy 352.672396 -214.596747)
			(xy 352.680495 -214.545609) (xy 352.696494 -214.496369) (xy 352.72 -214.450237) (xy 352.750432 -214.40835)
			(xy 352.787042 -214.37174) (xy 352.828929 -214.341308) (xy 352.875061 -214.317802) (xy 352.924301 -214.301803)
			(xy 352.975439 -214.293704) (xy 353.027213 -214.293704) (xy 353.078351 -214.301803) (xy 353.127591 -214.317802)
			(xy 353.173723 -214.341308) (xy 353.21561 -214.37174) (xy 353.25222 -214.40835) (xy 353.282652 -214.450237)
			(xy 353.306158 -214.496369) (xy 353.322157 -214.545609) (xy 353.330256 -214.596747) (xy 353.330764 -214.622634)
			(xy 353.330341 -214.647971) (xy 353.322583 -214.698047) (xy 353.307254 -214.746347) (xy 353.284715 -214.791733)
			(xy 353.255498 -214.833136) (xy 353.22029 -214.869581) (xy 353.17992 -214.90021) (xy 353.135339 -214.924301)
			(xy 353.087597 -214.941288) (xy 353.062794 -214.946484) (xy 353.039934 -214.950802) (xy 352.834956 -215.305894)
			(xy 352.84283 -215.327738) (xy 352.851477 -215.354146) (xy 352.860797 -215.408922) (xy 352.861372 -215.436704)
			(xy 354.081588 -215.436704) (xy 354.082123 -215.411361) (xy 354.089893 -215.361274) (xy 354.105237 -215.312966)
			(xy 354.127792 -215.267575) (xy 354.157027 -215.226169) (xy 354.192254 -215.189725) (xy 354.232643 -215.159101)
			(xy 354.277242 -215.135018) (xy 354.325001 -215.118043) (xy 354.349812 -215.112854) (xy 354.372672 -215.108536)
			(xy 354.57765 -214.753444) (xy 354.569776 -214.7316) (xy 354.561199 -214.705181) (xy 354.552 -214.650406)
			(xy 354.551488 -214.622634) (xy 354.551996 -214.596747) (xy 354.560095 -214.545609) (xy 354.576094 -214.496369)
			(xy 354.5996 -214.450237) (xy 354.630032 -214.40835) (xy 354.666642 -214.37174) (xy 354.708529 -214.341308)
			(xy 354.754661 -214.317802) (xy 354.803901 -214.301803) (xy 354.855039 -214.293704) (xy 354.906813 -214.293704)
			(xy 354.957951 -214.301803) (xy 355.007191 -214.317802) (xy 355.053323 -214.341308) (xy 355.09521 -214.37174)
			(xy 355.13182 -214.40835) (xy 355.162252 -214.450237) (xy 355.185758 -214.496369) (xy 355.201757 -214.545609)
			(xy 355.209856 -214.596747) (xy 355.210364 -214.622634) (xy 355.209941 -214.647971) (xy 355.202183 -214.698047)
			(xy 355.186854 -214.746347) (xy 355.164315 -214.791733) (xy 355.135098 -214.833136) (xy 355.09989 -214.869581)
			(xy 355.05952 -214.90021) (xy 355.014939 -214.924301) (xy 354.967197 -214.941288) (xy 354.942394 -214.946484)
			(xy 354.919534 -214.950802) (xy 354.714556 -215.305894) (xy 354.72243 -215.327738) (xy 354.731077 -215.354146)
			(xy 354.740397 -215.408922) (xy 354.740972 -215.436704) (xy 355.961188 -215.436704) (xy 355.961723 -215.411361)
			(xy 355.969493 -215.361274) (xy 355.984837 -215.312966) (xy 356.007392 -215.267575) (xy 356.036627 -215.226169)
			(xy 356.071854 -215.189725) (xy 356.112243 -215.159101) (xy 356.156842 -215.135018) (xy 356.204601 -215.118043)
			(xy 356.229412 -215.112854) (xy 356.252272 -215.108536) (xy 356.45725 -214.753444) (xy 356.449376 -214.7316)
			(xy 356.440799 -214.705181) (xy 356.4316 -214.650406) (xy 356.431088 -214.622634) (xy 356.431596 -214.596747)
			(xy 356.439695 -214.545609) (xy 356.455694 -214.496369) (xy 356.4792 -214.450237) (xy 356.509632 -214.40835)
			(xy 356.546242 -214.37174) (xy 356.588129 -214.341308) (xy 356.634261 -214.317802) (xy 356.683501 -214.301803)
			(xy 356.734639 -214.293704) (xy 356.786413 -214.293704) (xy 356.837551 -214.301803) (xy 356.886791 -214.317802)
			(xy 356.932923 -214.341308) (xy 356.97481 -214.37174) (xy 357.01142 -214.40835) (xy 357.041852 -214.450237)
			(xy 357.065358 -214.496369) (xy 357.081357 -214.545609) (xy 357.089456 -214.596747) (xy 357.089964 -214.622634)
			(xy 358.310688 -214.622634) (xy 358.311196 -214.596747) (xy 358.319295 -214.545609) (xy 358.335294 -214.496369)
			(xy 358.3588 -214.450237) (xy 358.389232 -214.40835) (xy 358.425842 -214.37174) (xy 358.467729 -214.341308)
			(xy 358.513861 -214.317802) (xy 358.563101 -214.301803) (xy 358.614239 -214.293704) (xy 358.666013 -214.293704)
			(xy 358.717151 -214.301803) (xy 358.766391 -214.317802) (xy 358.812523 -214.341308) (xy 358.85441 -214.37174)
			(xy 358.89102 -214.40835) (xy 358.921452 -214.450237) (xy 358.944958 -214.496369) (xy 358.953137 -214.521542)
			(xy 410.102304 -214.521542) (xy 410.102304 -214.112602) (xy 410.102834 -214.102449) (xy 410.110602 -214.083686)
			(xy 410.124956 -214.069322) (xy 410.143713 -214.061541) (xy 410.153866 -214.06104) (xy 411.553406 -214.06104)
			(xy 411.563564 -214.061529) (xy 411.582334 -214.069305) (xy 411.596699 -214.083673) (xy 411.604473 -214.102444)
			(xy 411.604968 -214.112602) (xy 411.604968 -214.521542) (xy 417.646104 -214.521542) (xy 417.646104 -214.112602)
			(xy 417.646634 -214.102449) (xy 417.654402 -214.083686) (xy 417.668756 -214.069322) (xy 417.687513 -214.061541)
			(xy 417.697666 -214.06104) (xy 419.097206 -214.06104) (xy 419.107364 -214.061529) (xy 419.126134 -214.069305)
			(xy 419.140499 -214.083673) (xy 419.148273 -214.102444) (xy 419.148768 -214.112602) (xy 419.148768 -214.521542)
			(xy 425.189904 -214.521542) (xy 425.189904 -214.112602) (xy 425.190434 -214.102449) (xy 425.198202 -214.083686)
			(xy 425.212556 -214.069322) (xy 425.231313 -214.061541) (xy 425.241466 -214.06104) (xy 426.641006 -214.06104)
			(xy 426.651164 -214.061529) (xy 426.669934 -214.069305) (xy 426.684299 -214.083673) (xy 426.692073 -214.102444)
			(xy 426.692568 -214.112602) (xy 426.692568 -214.521542) (xy 432.733704 -214.521542) (xy 432.733704 -214.112602)
			(xy 432.734234 -214.102449) (xy 432.742002 -214.083686) (xy 432.756356 -214.069322) (xy 432.775113 -214.061541)
			(xy 432.785266 -214.06104) (xy 434.184806 -214.06104) (xy 434.194964 -214.061529) (xy 434.213734 -214.069305)
			(xy 434.228099 -214.083673) (xy 434.235873 -214.102444) (xy 434.236368 -214.112602) (xy 434.236368 -214.521542)
			(xy 440.277504 -214.521542) (xy 440.277504 -214.112602) (xy 440.278034 -214.102449) (xy 440.285802 -214.083686)
			(xy 440.300156 -214.069322) (xy 440.318913 -214.061541) (xy 440.329066 -214.06104) (xy 441.728606 -214.06104)
			(xy 441.738764 -214.061529) (xy 441.757534 -214.069305) (xy 441.771899 -214.083673) (xy 441.779673 -214.102444)
			(xy 441.780168 -214.112602) (xy 441.780168 -214.521542) (xy 447.821304 -214.521542) (xy 447.821304 -214.112602)
			(xy 447.821834 -214.102449) (xy 447.829602 -214.083686) (xy 447.843956 -214.069322) (xy 447.862713 -214.061541)
			(xy 447.872866 -214.06104) (xy 449.272406 -214.06104) (xy 449.282564 -214.061529) (xy 449.301334 -214.069305)
			(xy 449.315699 -214.083673) (xy 449.323473 -214.102444) (xy 449.323968 -214.112602) (xy 449.323968 -214.521542)
			(xy 455.365104 -214.521542) (xy 455.365104 -214.112602) (xy 455.365634 -214.102449) (xy 455.373402 -214.083686)
			(xy 455.387756 -214.069322) (xy 455.406513 -214.061541) (xy 455.416666 -214.06104) (xy 456.816206 -214.06104)
			(xy 456.826364 -214.061529) (xy 456.845134 -214.069305) (xy 456.859499 -214.083673) (xy 456.867273 -214.102444)
			(xy 456.867768 -214.112602) (xy 456.867768 -214.521542) (xy 462.908904 -214.521542) (xy 462.908904 -214.112602)
			(xy 462.909434 -214.102449) (xy 462.917202 -214.083686) (xy 462.931556 -214.069322) (xy 462.950313 -214.061541)
			(xy 462.960466 -214.06104) (xy 464.360006 -214.06104) (xy 464.370164 -214.061529) (xy 464.388934 -214.069305)
			(xy 464.403299 -214.083673) (xy 464.411073 -214.102444) (xy 464.411568 -214.112602) (xy 464.411568 -214.521542)
			(xy 464.411101 -214.531702) (xy 464.403314 -214.550471) (xy 464.38894 -214.564834) (xy 464.370166 -214.572608)
			(xy 464.360006 -214.573104) (xy 462.960466 -214.573104) (xy 462.950311 -214.572596) (xy 462.931549 -214.564818)
			(xy 462.917187 -214.550457) (xy 462.909406 -214.531697) (xy 462.908904 -214.521542) (xy 456.867768 -214.521542)
			(xy 456.867301 -214.531702) (xy 456.859514 -214.550471) (xy 456.84514 -214.564834) (xy 456.826366 -214.572608)
			(xy 456.816206 -214.573104) (xy 455.416666 -214.573104) (xy 455.406511 -214.572596) (xy 455.387749 -214.564818)
			(xy 455.373387 -214.550457) (xy 455.365606 -214.531697) (xy 455.365104 -214.521542) (xy 449.323968 -214.521542)
			(xy 449.323501 -214.531702) (xy 449.315714 -214.550471) (xy 449.30134 -214.564834) (xy 449.282566 -214.572608)
			(xy 449.272406 -214.573104) (xy 447.872866 -214.573104) (xy 447.862711 -214.572596) (xy 447.843949 -214.564818)
			(xy 447.829587 -214.550457) (xy 447.821806 -214.531697) (xy 447.821304 -214.521542) (xy 441.780168 -214.521542)
			(xy 441.779701 -214.531702) (xy 441.771914 -214.550471) (xy 441.75754 -214.564834) (xy 441.738766 -214.572608)
			(xy 441.728606 -214.573104) (xy 440.329066 -214.573104) (xy 440.318911 -214.572596) (xy 440.300149 -214.564818)
			(xy 440.285787 -214.550457) (xy 440.278006 -214.531697) (xy 440.277504 -214.521542) (xy 434.236368 -214.521542)
			(xy 434.235901 -214.531702) (xy 434.228114 -214.550471) (xy 434.21374 -214.564834) (xy 434.194966 -214.572608)
			(xy 434.184806 -214.573104) (xy 432.785266 -214.573104) (xy 432.775111 -214.572596) (xy 432.756349 -214.564818)
			(xy 432.741987 -214.550457) (xy 432.734206 -214.531697) (xy 432.733704 -214.521542) (xy 426.692568 -214.521542)
			(xy 426.692101 -214.531702) (xy 426.684314 -214.550471) (xy 426.66994 -214.564834) (xy 426.651166 -214.572608)
			(xy 426.641006 -214.573104) (xy 425.241466 -214.573104) (xy 425.231311 -214.572596) (xy 425.212549 -214.564818)
			(xy 425.198187 -214.550457) (xy 425.190406 -214.531697) (xy 425.189904 -214.521542) (xy 419.148768 -214.521542)
			(xy 419.148301 -214.531702) (xy 419.140514 -214.550471) (xy 419.12614 -214.564834) (xy 419.107366 -214.572608)
			(xy 419.097206 -214.573104) (xy 417.697666 -214.573104) (xy 417.687511 -214.572596) (xy 417.668749 -214.564818)
			(xy 417.654387 -214.550457) (xy 417.646606 -214.531697) (xy 417.646104 -214.521542) (xy 411.604968 -214.521542)
			(xy 411.604501 -214.531702) (xy 411.596714 -214.550471) (xy 411.58234 -214.564834) (xy 411.563566 -214.572608)
			(xy 411.553406 -214.573104) (xy 410.153866 -214.573104) (xy 410.143711 -214.572596) (xy 410.124949 -214.564818)
			(xy 410.110587 -214.550457) (xy 410.102806 -214.531697) (xy 410.102304 -214.521542) (xy 358.953137 -214.521542)
			(xy 358.960957 -214.545609) (xy 358.969056 -214.596747) (xy 358.969564 -214.622634) (xy 358.969564 -214.623142)
			(xy 358.968984 -214.650659) (xy 358.959791 -214.70492) (xy 358.951276 -214.731092) (xy 358.943656 -214.75319)
			(xy 359.148888 -215.108536) (xy 359.171748 -215.112854) (xy 359.196559 -215.118062) (xy 359.244336 -215.135013)
			(xy 359.288953 -215.15908) (xy 359.329358 -215.189696) (xy 359.364599 -215.226137) (xy 359.393844 -215.267545)
			(xy 359.416403 -215.312943) (xy 359.431745 -215.36126) (xy 359.43332 -215.371426) (xy 406.002236 -215.371426)
			(xy 406.002236 -214.962486) (xy 406.002722 -214.952328) (xy 406.010501 -214.933559) (xy 406.024869 -214.919194)
			(xy 406.04364 -214.91142) (xy 406.053798 -214.910924) (xy 407.453338 -214.910924) (xy 407.463496 -214.911402)
			(xy 407.482264 -214.919186) (xy 407.496627 -214.933556) (xy 407.504403 -214.952327) (xy 407.5049 -214.962486)
			(xy 407.5049 -215.371426) (xy 413.546036 -215.371426) (xy 413.546036 -214.962486) (xy 413.546522 -214.952328)
			(xy 413.554301 -214.933559) (xy 413.568669 -214.919194) (xy 413.58744 -214.91142) (xy 413.597598 -214.910924)
			(xy 414.997138 -214.910924) (xy 415.007296 -214.911402) (xy 415.026064 -214.919186) (xy 415.040427 -214.933556)
			(xy 415.048203 -214.952327) (xy 415.0487 -214.962486) (xy 415.0487 -215.371426) (xy 421.089836 -215.371426)
			(xy 421.089836 -214.962486) (xy 421.090322 -214.952328) (xy 421.098101 -214.933559) (xy 421.112469 -214.919194)
			(xy 421.13124 -214.91142) (xy 421.141398 -214.910924) (xy 422.540938 -214.910924) (xy 422.551096 -214.911402)
			(xy 422.569864 -214.919186) (xy 422.584227 -214.933556) (xy 422.592003 -214.952327) (xy 422.5925 -214.962486)
			(xy 422.5925 -215.371426) (xy 428.633636 -215.371426) (xy 428.633636 -214.962486) (xy 428.634122 -214.952328)
			(xy 428.641901 -214.933559) (xy 428.656269 -214.919194) (xy 428.67504 -214.91142) (xy 428.685198 -214.910924)
			(xy 430.084738 -214.910924) (xy 430.094896 -214.911402) (xy 430.113664 -214.919186) (xy 430.128027 -214.933556)
			(xy 430.135803 -214.952327) (xy 430.1363 -214.962486) (xy 430.1363 -215.371426) (xy 436.177436 -215.371426)
			(xy 436.177436 -214.962486) (xy 436.177922 -214.952328) (xy 436.185701 -214.933559) (xy 436.200069 -214.919194)
			(xy 436.21884 -214.91142) (xy 436.228998 -214.910924) (xy 437.628538 -214.910924) (xy 437.638696 -214.911402)
			(xy 437.657464 -214.919186) (xy 437.671827 -214.933556) (xy 437.679603 -214.952327) (xy 437.6801 -214.962486)
			(xy 437.6801 -215.371426) (xy 443.721236 -215.371426) (xy 443.721236 -214.962486) (xy 443.721722 -214.952328)
			(xy 443.729501 -214.933559) (xy 443.743869 -214.919194) (xy 443.76264 -214.91142) (xy 443.772798 -214.910924)
			(xy 445.172338 -214.910924) (xy 445.182496 -214.911402) (xy 445.201264 -214.919186) (xy 445.215627 -214.933556)
			(xy 445.223403 -214.952327) (xy 445.2239 -214.962486) (xy 445.2239 -215.371426) (xy 451.265036 -215.371426)
			(xy 451.265036 -214.962486) (xy 451.265522 -214.952328) (xy 451.273301 -214.933559) (xy 451.287669 -214.919194)
			(xy 451.30644 -214.91142) (xy 451.316598 -214.910924) (xy 452.716138 -214.910924) (xy 452.726296 -214.911402)
			(xy 452.745064 -214.919186) (xy 452.759427 -214.933556) (xy 452.767203 -214.952327) (xy 452.7677 -214.962486)
			(xy 452.7677 -215.371426) (xy 458.808836 -215.371426) (xy 458.808836 -214.962486) (xy 458.809322 -214.952328)
			(xy 458.817101 -214.933559) (xy 458.831469 -214.919194) (xy 458.85024 -214.91142) (xy 458.860398 -214.910924)
			(xy 460.259938 -214.910924) (xy 460.270096 -214.911402) (xy 460.288864 -214.919186) (xy 460.303227 -214.933556)
			(xy 460.311003 -214.952327) (xy 460.3115 -214.962486) (xy 460.3115 -215.371426) (xy 460.310989 -215.381581)
			(xy 460.303213 -215.400343) (xy 460.288853 -215.414706) (xy 460.270093 -215.422487) (xy 460.259938 -215.422988)
			(xy 458.860398 -215.422988) (xy 458.850243 -215.422469) (xy 458.831479 -215.414699) (xy 458.817115 -215.400341)
			(xy 458.809336 -215.38158) (xy 458.808836 -215.371426) (xy 452.7677 -215.371426) (xy 452.767189 -215.381581)
			(xy 452.759413 -215.400343) (xy 452.745053 -215.414706) (xy 452.726293 -215.422487) (xy 452.716138 -215.422988)
			(xy 451.316598 -215.422988) (xy 451.306443 -215.422469) (xy 451.287679 -215.414699) (xy 451.273315 -215.400341)
			(xy 451.265536 -215.38158) (xy 451.265036 -215.371426) (xy 445.2239 -215.371426) (xy 445.223389 -215.381581)
			(xy 445.215613 -215.400343) (xy 445.201253 -215.414706) (xy 445.182493 -215.422487) (xy 445.172338 -215.422988)
			(xy 443.772798 -215.422988) (xy 443.762643 -215.422469) (xy 443.743879 -215.414699) (xy 443.729515 -215.400341)
			(xy 443.721736 -215.38158) (xy 443.721236 -215.371426) (xy 437.6801 -215.371426) (xy 437.679589 -215.381581)
			(xy 437.671813 -215.400343) (xy 437.657453 -215.414706) (xy 437.638693 -215.422487) (xy 437.628538 -215.422988)
			(xy 436.228998 -215.422988) (xy 436.218843 -215.422469) (xy 436.200079 -215.414699) (xy 436.185715 -215.400341)
			(xy 436.177936 -215.38158) (xy 436.177436 -215.371426) (xy 430.1363 -215.371426) (xy 430.135789 -215.381581)
			(xy 430.128013 -215.400343) (xy 430.113653 -215.414706) (xy 430.094893 -215.422487) (xy 430.084738 -215.422988)
			(xy 428.685198 -215.422988) (xy 428.675043 -215.422469) (xy 428.656279 -215.414699) (xy 428.641915 -215.400341)
			(xy 428.634136 -215.38158) (xy 428.633636 -215.371426) (xy 422.5925 -215.371426) (xy 422.591989 -215.381581)
			(xy 422.584213 -215.400343) (xy 422.569853 -215.414706) (xy 422.551093 -215.422487) (xy 422.540938 -215.422988)
			(xy 421.141398 -215.422988) (xy 421.131243 -215.422469) (xy 421.112479 -215.414699) (xy 421.098115 -215.400341)
			(xy 421.090336 -215.38158) (xy 421.089836 -215.371426) (xy 415.0487 -215.371426) (xy 415.048189 -215.381581)
			(xy 415.040413 -215.400343) (xy 415.026053 -215.414706) (xy 415.007293 -215.422487) (xy 414.997138 -215.422988)
			(xy 413.597598 -215.422988) (xy 413.587443 -215.422469) (xy 413.568679 -215.414699) (xy 413.554315 -215.400341)
			(xy 413.546536 -215.38158) (xy 413.546036 -215.371426) (xy 407.5049 -215.371426) (xy 407.504389 -215.381581)
			(xy 407.496613 -215.400343) (xy 407.482253 -215.414706) (xy 407.463493 -215.422487) (xy 407.453338 -215.422988)
			(xy 406.053798 -215.422988) (xy 406.043643 -215.422469) (xy 406.024879 -215.414699) (xy 406.010515 -215.400341)
			(xy 406.002736 -215.38158) (xy 406.002236 -215.371426) (xy 359.43332 -215.371426) (xy 359.439507 -215.411357)
			(xy 359.439972 -215.436704) (xy 359.439464 -215.462611) (xy 359.431358 -215.513788) (xy 359.415346 -215.563067)
			(xy 359.391823 -215.609234) (xy 359.361367 -215.651153) (xy 359.324729 -215.687791) (xy 359.28281 -215.718247)
			(xy 359.236643 -215.74177) (xy 359.187364 -215.757782) (xy 359.136187 -215.765888) (xy 359.084373 -215.765888)
			(xy 359.033196 -215.757782) (xy 358.983917 -215.74177) (xy 358.93775 -215.718247) (xy 358.895831 -215.687791)
			(xy 358.859193 -215.651153) (xy 358.828737 -215.609234) (xy 358.805214 -215.563067) (xy 358.789202 -215.513788)
			(xy 358.781096 -215.462611) (xy 358.780588 -215.436704) (xy 358.781184 -215.408987) (xy 358.790506 -215.35434)
			(xy 358.79913 -215.327992) (xy 358.80675 -215.306148) (xy 358.601772 -214.950802) (xy 358.578912 -214.946484)
			(xy 358.554096 -214.941291) (xy 358.506315 -214.924344) (xy 358.461694 -214.900279) (xy 358.421285 -214.869663)
			(xy 358.386043 -214.833219) (xy 358.356798 -214.791807) (xy 358.33424 -214.746405) (xy 358.318903 -214.698083)
			(xy 358.311148 -214.647983) (xy 358.310688 -214.622634) (xy 357.089964 -214.622634) (xy 357.089541 -214.647971)
			(xy 357.081783 -214.698047) (xy 357.066454 -214.746347) (xy 357.043915 -214.791733) (xy 357.014698 -214.833136)
			(xy 356.97949 -214.869581) (xy 356.93912 -214.90021) (xy 356.894539 -214.924301) (xy 356.846797 -214.941288)
			(xy 356.821994 -214.946484) (xy 356.799134 -214.950802) (xy 356.594156 -215.305894) (xy 356.60203 -215.327738)
			(xy 356.610677 -215.354146) (xy 356.619997 -215.408922) (xy 356.620572 -215.436704) (xy 356.620064 -215.462606)
			(xy 356.90152 -215.462606) (xy 356.90152 -215.410794) (xy 356.909625 -215.35962) (xy 356.925635 -215.310344)
			(xy 356.949157 -215.264178) (xy 356.97961 -215.222261) (xy 357.016246 -215.185623) (xy 357.058161 -215.155167)
			(xy 357.104325 -215.131643) (xy 357.1536 -215.11563) (xy 357.204774 -215.107522) (xy 357.23068 -215.107012)
			(xy 357.256191 -215.107502) (xy 357.306606 -215.11536) (xy 357.355207 -215.130891) (xy 357.400836 -215.153725)
			(xy 357.442402 -215.183316) (xy 357.478912 -215.218958) (xy 357.494586 -215.239092) (xy 357.906574 -215.239092)
			(xy 357.92226 -215.218967) (xy 357.958768 -215.183323) (xy 358.000331 -215.153729) (xy 358.045956 -215.130891)
			(xy 358.094556 -215.115355) (xy 358.144969 -215.107491) (xy 358.17048 -215.107012) (xy 358.196391 -215.107484)
			(xy 358.247575 -215.115588) (xy 358.296861 -215.131599) (xy 358.343035 -215.155124) (xy 358.38496 -215.185582)
			(xy 358.421605 -215.222224) (xy 358.452066 -215.264148) (xy 358.475593 -215.310321) (xy 358.491607 -215.359606)
			(xy 358.499714 -215.410789) (xy 358.499714 -215.462611) (xy 358.491607 -215.513794) (xy 358.475593 -215.563079)
			(xy 358.452066 -215.609252) (xy 358.421605 -215.651176) (xy 358.38496 -215.687818) (xy 358.343035 -215.718276)
			(xy 358.296861 -215.741801) (xy 358.247575 -215.757812) (xy 358.196391 -215.765916) (xy 358.17048 -215.766396)
			(xy 358.144968 -215.765932) (xy 358.094552 -215.758068) (xy 358.04595 -215.742532) (xy 358.000322 -215.719693)
			(xy 357.958757 -215.690098) (xy 357.922247 -215.654452) (xy 357.906574 -215.634316) (xy 357.494586 -215.634316)
			(xy 357.478925 -215.654461) (xy 357.442412 -215.690104) (xy 357.400844 -215.719696) (xy 357.355213 -215.74253)
			(xy 357.306609 -215.758062) (xy 357.256193 -215.76592) (xy 357.23068 -215.766396) (xy 357.204774 -215.765878)
			(xy 357.1536 -215.75777) (xy 357.104325 -215.741757) (xy 357.058161 -215.718233) (xy 357.016246 -215.687777)
			(xy 356.97961 -215.651139) (xy 356.949157 -215.609222) (xy 356.925635 -215.563056) (xy 356.909625 -215.51378)
			(xy 356.90152 -215.462606) (xy 356.620064 -215.462606) (xy 356.620064 -215.462611) (xy 356.611958 -215.513788)
			(xy 356.595946 -215.563067) (xy 356.572423 -215.609234) (xy 356.541967 -215.651153) (xy 356.505329 -215.687791)
			(xy 356.46341 -215.718247) (xy 356.417243 -215.74177) (xy 356.367964 -215.757782) (xy 356.316787 -215.765888)
			(xy 356.264973 -215.765888) (xy 356.213796 -215.757782) (xy 356.164517 -215.74177) (xy 356.11835 -215.718247)
			(xy 356.076431 -215.687791) (xy 356.039793 -215.651153) (xy 356.009337 -215.609234) (xy 355.985814 -215.563067)
			(xy 355.969802 -215.513788) (xy 355.961696 -215.462611) (xy 355.961188 -215.436704) (xy 354.740972 -215.436704)
			(xy 354.740464 -215.462611) (xy 354.732358 -215.513788) (xy 354.716346 -215.563067) (xy 354.692823 -215.609234)
			(xy 354.662367 -215.651153) (xy 354.625729 -215.687791) (xy 354.58381 -215.718247) (xy 354.537643 -215.74177)
			(xy 354.488364 -215.757782) (xy 354.437187 -215.765888) (xy 354.385373 -215.765888) (xy 354.334196 -215.757782)
			(xy 354.284917 -215.74177) (xy 354.23875 -215.718247) (xy 354.196831 -215.687791) (xy 354.160193 -215.651153)
			(xy 354.129737 -215.609234) (xy 354.106214 -215.563067) (xy 354.090202 -215.513788) (xy 354.082096 -215.462611)
			(xy 354.081588 -215.436704) (xy 352.861372 -215.436704) (xy 352.860864 -215.462611) (xy 352.852758 -215.513788)
			(xy 352.836746 -215.563067) (xy 352.813223 -215.609234) (xy 352.782767 -215.651153) (xy 352.746129 -215.687791)
			(xy 352.70421 -215.718247) (xy 352.658043 -215.74177) (xy 352.608764 -215.757782) (xy 352.557587 -215.765888)
			(xy 352.505773 -215.765888) (xy 352.454596 -215.757782) (xy 352.405317 -215.74177) (xy 352.35915 -215.718247)
			(xy 352.317231 -215.687791) (xy 352.280593 -215.651153) (xy 352.250137 -215.609234) (xy 352.226614 -215.563067)
			(xy 352.210602 -215.513788) (xy 352.202496 -215.462611) (xy 352.201988 -215.436704) (xy 350.981772 -215.436704)
			(xy 350.981264 -215.462611) (xy 350.973158 -215.513788) (xy 350.957146 -215.563067) (xy 350.933623 -215.609234)
			(xy 350.903167 -215.651153) (xy 350.866529 -215.687791) (xy 350.82461 -215.718247) (xy 350.778443 -215.74177)
			(xy 350.729164 -215.757782) (xy 350.677987 -215.765888) (xy 350.626173 -215.765888) (xy 350.574996 -215.757782)
			(xy 350.525717 -215.74177) (xy 350.47955 -215.718247) (xy 350.437631 -215.687791) (xy 350.400993 -215.651153)
			(xy 350.370537 -215.609234) (xy 350.347014 -215.563067) (xy 350.331002 -215.513788) (xy 350.322896 -215.462611)
			(xy 350.322388 -215.436704) (xy 349.102172 -215.436704) (xy 349.101664 -215.462611) (xy 349.093558 -215.513788)
			(xy 349.077546 -215.563067) (xy 349.054023 -215.609234) (xy 349.023567 -215.651153) (xy 348.986929 -215.687791)
			(xy 348.94501 -215.718247) (xy 348.898843 -215.74177) (xy 348.849564 -215.757782) (xy 348.798387 -215.765888)
			(xy 348.746573 -215.765888) (xy 348.695396 -215.757782) (xy 348.646117 -215.74177) (xy 348.59995 -215.718247)
			(xy 348.558031 -215.687791) (xy 348.521393 -215.651153) (xy 348.490937 -215.609234) (xy 348.467414 -215.563067)
			(xy 348.451402 -215.513788) (xy 348.443296 -215.462611) (xy 348.442788 -215.436704) (xy 347.222572 -215.436704)
			(xy 347.222064 -215.462611) (xy 347.213958 -215.513788) (xy 347.197946 -215.563067) (xy 347.174423 -215.609234)
			(xy 347.143967 -215.651153) (xy 347.107329 -215.687791) (xy 347.06541 -215.718247) (xy 347.019243 -215.74177)
			(xy 346.969964 -215.757782) (xy 346.918787 -215.765888) (xy 346.866973 -215.765888) (xy 346.815796 -215.757782)
			(xy 346.766517 -215.74177) (xy 346.72035 -215.718247) (xy 346.678431 -215.687791) (xy 346.641793 -215.651153)
			(xy 346.611337 -215.609234) (xy 346.587814 -215.563067) (xy 346.571802 -215.513788) (xy 346.563696 -215.462611)
			(xy 346.563188 -215.436704) (xy 345.342972 -215.436704) (xy 345.342464 -215.462611) (xy 345.334358 -215.513788)
			(xy 345.318346 -215.563067) (xy 345.294823 -215.609234) (xy 345.264367 -215.651153) (xy 345.227729 -215.687791)
			(xy 345.18581 -215.718247) (xy 345.139643 -215.74177) (xy 345.090364 -215.757782) (xy 345.039187 -215.765888)
			(xy 344.987373 -215.765888) (xy 344.936196 -215.757782) (xy 344.886917 -215.74177) (xy 344.84075 -215.718247)
			(xy 344.798831 -215.687791) (xy 344.762193 -215.651153) (xy 344.731737 -215.609234) (xy 344.708214 -215.563067)
			(xy 344.692202 -215.513788) (xy 344.684096 -215.462611) (xy 344.683588 -215.436704) (xy 343.463372 -215.436704)
			(xy 343.462864 -215.462611) (xy 343.454758 -215.513788) (xy 343.438746 -215.563067) (xy 343.415223 -215.609234)
			(xy 343.384767 -215.651153) (xy 343.348129 -215.687791) (xy 343.30621 -215.718247) (xy 343.260043 -215.74177)
			(xy 343.210764 -215.757782) (xy 343.159587 -215.765888) (xy 343.107773 -215.765888) (xy 343.056596 -215.757782)
			(xy 343.007317 -215.74177) (xy 342.96115 -215.718247) (xy 342.919231 -215.687791) (xy 342.882593 -215.651153)
			(xy 342.852137 -215.609234) (xy 342.828614 -215.563067) (xy 342.812602 -215.513788) (xy 342.804496 -215.462611)
			(xy 342.803988 -215.436704) (xy 341.583772 -215.436704) (xy 341.583264 -215.462611) (xy 341.575158 -215.513788)
			(xy 341.559146 -215.563067) (xy 341.535623 -215.609234) (xy 341.505167 -215.651153) (xy 341.468529 -215.687791)
			(xy 341.42661 -215.718247) (xy 341.380443 -215.74177) (xy 341.331164 -215.757782) (xy 341.279987 -215.765888)
			(xy 341.228173 -215.765888) (xy 341.176996 -215.757782) (xy 341.127717 -215.74177) (xy 341.08155 -215.718247)
			(xy 341.039631 -215.687791) (xy 341.002993 -215.651153) (xy 340.972537 -215.609234) (xy 340.949014 -215.563067)
			(xy 340.933002 -215.513788) (xy 340.924896 -215.462611) (xy 340.924388 -215.436704) (xy 339.704172 -215.436704)
			(xy 339.703664 -215.462611) (xy 339.695558 -215.513788) (xy 339.679546 -215.563067) (xy 339.656023 -215.609234)
			(xy 339.625567 -215.651153) (xy 339.588929 -215.687791) (xy 339.54701 -215.718247) (xy 339.500843 -215.74177)
			(xy 339.451564 -215.757782) (xy 339.400387 -215.765888) (xy 339.348573 -215.765888) (xy 339.297396 -215.757782)
			(xy 339.248117 -215.74177) (xy 339.20195 -215.718247) (xy 339.160031 -215.687791) (xy 339.123393 -215.651153)
			(xy 339.092937 -215.609234) (xy 339.069414 -215.563067) (xy 339.053402 -215.513788) (xy 339.045296 -215.462611)
			(xy 339.044788 -215.436704) (xy 337.824572 -215.436704) (xy 337.824064 -215.462611) (xy 337.815958 -215.513788)
			(xy 337.799946 -215.563067) (xy 337.776423 -215.609234) (xy 337.745967 -215.651153) (xy 337.709329 -215.687791)
			(xy 337.66741 -215.718247) (xy 337.621243 -215.74177) (xy 337.571964 -215.757782) (xy 337.520787 -215.765888)
			(xy 337.468973 -215.765888) (xy 337.417796 -215.757782) (xy 337.368517 -215.74177) (xy 337.32235 -215.718247)
			(xy 337.280431 -215.687791) (xy 337.243793 -215.651153) (xy 337.213337 -215.609234) (xy 337.189814 -215.563067)
			(xy 337.173802 -215.513788) (xy 337.165696 -215.462611) (xy 337.165188 -215.436704) (xy 336.884772 -215.436704)
			(xy 336.884181 -215.464421) (xy 336.874856 -215.519068) (xy 336.86623 -215.545416) (xy 336.858356 -215.567514)
			(xy 337.063334 -215.922352) (xy 337.086194 -215.92667) (xy 337.110997 -215.931858) (xy 337.158737 -215.948846)
			(xy 337.203315 -215.972939) (xy 337.243681 -216.00357) (xy 337.278884 -216.040017) (xy 337.308096 -216.081421)
			(xy 337.330629 -216.126808) (xy 337.345951 -216.175108) (xy 337.353102 -216.22131) (xy 410.102304 -216.22131)
			(xy 410.102304 -215.81237) (xy 410.102808 -215.802214) (xy 410.110586 -215.783451) (xy 410.124948 -215.769088)
			(xy 410.143711 -215.761309) (xy 410.153866 -215.760808) (xy 411.553406 -215.760808) (xy 411.56356 -215.761328)
			(xy 411.582324 -215.769099) (xy 411.596688 -215.783456) (xy 411.604467 -215.802216) (xy 411.604968 -215.81237)
			(xy 411.604968 -216.22131) (xy 417.646104 -216.22131) (xy 417.646104 -215.81237) (xy 417.646608 -215.802214)
			(xy 417.654386 -215.783451) (xy 417.668748 -215.769088) (xy 417.687511 -215.761309) (xy 417.697666 -215.760808)
			(xy 419.097206 -215.760808) (xy 419.10736 -215.761328) (xy 419.126124 -215.769099) (xy 419.140488 -215.783456)
			(xy 419.148267 -215.802216) (xy 419.148768 -215.81237) (xy 419.148768 -216.22131) (xy 425.189904 -216.22131)
			(xy 425.189904 -215.81237) (xy 425.190408 -215.802214) (xy 425.198186 -215.783451) (xy 425.212548 -215.769088)
			(xy 425.231311 -215.761309) (xy 425.241466 -215.760808) (xy 426.641006 -215.760808) (xy 426.65116 -215.761328)
			(xy 426.669924 -215.769099) (xy 426.684288 -215.783456) (xy 426.692067 -215.802216) (xy 426.692568 -215.81237)
			(xy 426.692568 -216.22131) (xy 432.733704 -216.22131) (xy 432.733704 -215.81237) (xy 432.734208 -215.802214)
			(xy 432.741986 -215.783451) (xy 432.756348 -215.769088) (xy 432.775111 -215.761309) (xy 432.785266 -215.760808)
			(xy 434.184806 -215.760808) (xy 434.19496 -215.761328) (xy 434.213724 -215.769099) (xy 434.228088 -215.783456)
			(xy 434.235867 -215.802216) (xy 434.236368 -215.81237) (xy 434.236368 -216.22131) (xy 440.277504 -216.22131)
			(xy 440.277504 -215.81237) (xy 440.278008 -215.802214) (xy 440.285786 -215.783451) (xy 440.300148 -215.769088)
			(xy 440.318911 -215.761309) (xy 440.329066 -215.760808) (xy 441.728606 -215.760808) (xy 441.73876 -215.761328)
			(xy 441.757524 -215.769099) (xy 441.771888 -215.783456) (xy 441.779667 -215.802216) (xy 441.780168 -215.81237)
			(xy 441.780168 -216.22131) (xy 447.821304 -216.22131) (xy 447.821304 -215.81237) (xy 447.821808 -215.802214)
			(xy 447.829586 -215.783451) (xy 447.843948 -215.769088) (xy 447.862711 -215.761309) (xy 447.872866 -215.760808)
			(xy 449.272406 -215.760808) (xy 449.28256 -215.761328) (xy 449.301324 -215.769099) (xy 449.315688 -215.783456)
			(xy 449.323467 -215.802216) (xy 449.323968 -215.81237) (xy 449.323968 -216.22131) (xy 455.365104 -216.22131)
			(xy 455.365104 -215.81237) (xy 455.365608 -215.802214) (xy 455.373386 -215.783451) (xy 455.387748 -215.769088)
			(xy 455.406511 -215.761309) (xy 455.416666 -215.760808) (xy 456.816206 -215.760808) (xy 456.82636 -215.761328)
			(xy 456.845124 -215.769099) (xy 456.859488 -215.783456) (xy 456.867267 -215.802216) (xy 456.867768 -215.81237)
			(xy 456.867768 -216.22131) (xy 462.908904 -216.22131) (xy 462.908904 -215.81237) (xy 462.909408 -215.802214)
			(xy 462.917186 -215.783451) (xy 462.931548 -215.769088) (xy 462.950311 -215.761309) (xy 462.960466 -215.760808)
			(xy 464.360006 -215.760808) (xy 464.37016 -215.761328) (xy 464.388924 -215.769099) (xy 464.403288 -215.783456)
			(xy 464.411067 -215.802216) (xy 464.411568 -215.81237) (xy 464.411568 -216.22131) (xy 464.411075 -216.231468)
			(xy 464.403298 -216.250236) (xy 464.388932 -216.2646) (xy 464.370164 -216.272376) (xy 464.360006 -216.272872)
			(xy 462.960466 -216.272872) (xy 462.950307 -216.272395) (xy 462.931539 -216.264611) (xy 462.917176 -216.250241)
			(xy 462.909401 -216.231469) (xy 462.908904 -216.22131) (xy 456.867768 -216.22131) (xy 456.867275 -216.231468)
			(xy 456.859498 -216.250236) (xy 456.845132 -216.2646) (xy 456.826364 -216.272376) (xy 456.816206 -216.272872)
			(xy 455.416666 -216.272872) (xy 455.406507 -216.272395) (xy 455.387739 -216.264611) (xy 455.373376 -216.250241)
			(xy 455.365601 -216.231469) (xy 455.365104 -216.22131) (xy 449.323968 -216.22131) (xy 449.323475 -216.231468)
			(xy 449.315698 -216.250236) (xy 449.301332 -216.2646) (xy 449.282564 -216.272376) (xy 449.272406 -216.272872)
			(xy 447.872866 -216.272872) (xy 447.862707 -216.272395) (xy 447.843939 -216.264611) (xy 447.829576 -216.250241)
			(xy 447.821801 -216.231469) (xy 447.821304 -216.22131) (xy 441.780168 -216.22131) (xy 441.779675 -216.231468)
			(xy 441.771898 -216.250236) (xy 441.757532 -216.2646) (xy 441.738764 -216.272376) (xy 441.728606 -216.272872)
			(xy 440.329066 -216.272872) (xy 440.318907 -216.272395) (xy 440.300139 -216.264611) (xy 440.285776 -216.250241)
			(xy 440.278001 -216.231469) (xy 440.277504 -216.22131) (xy 434.236368 -216.22131) (xy 434.235875 -216.231468)
			(xy 434.228098 -216.250236) (xy 434.213732 -216.2646) (xy 434.194964 -216.272376) (xy 434.184806 -216.272872)
			(xy 432.785266 -216.272872) (xy 432.775107 -216.272395) (xy 432.756339 -216.264611) (xy 432.741976 -216.250241)
			(xy 432.734201 -216.231469) (xy 432.733704 -216.22131) (xy 426.692568 -216.22131) (xy 426.692075 -216.231468)
			(xy 426.684298 -216.250236) (xy 426.669932 -216.2646) (xy 426.651164 -216.272376) (xy 426.641006 -216.272872)
			(xy 425.241466 -216.272872) (xy 425.231307 -216.272395) (xy 425.212539 -216.264611) (xy 425.198176 -216.250241)
			(xy 425.190401 -216.231469) (xy 425.189904 -216.22131) (xy 419.148768 -216.22131) (xy 419.148275 -216.231468)
			(xy 419.140498 -216.250236) (xy 419.126132 -216.2646) (xy 419.107364 -216.272376) (xy 419.097206 -216.272872)
			(xy 417.697666 -216.272872) (xy 417.687507 -216.272395) (xy 417.668739 -216.264611) (xy 417.654376 -216.250241)
			(xy 417.646601 -216.231469) (xy 417.646104 -216.22131) (xy 411.604968 -216.22131) (xy 411.604475 -216.231468)
			(xy 411.596698 -216.250236) (xy 411.582332 -216.2646) (xy 411.563564 -216.272376) (xy 411.553406 -216.272872)
			(xy 410.153866 -216.272872) (xy 410.143707 -216.272395) (xy 410.124939 -216.264611) (xy 410.110576 -216.250241)
			(xy 410.102801 -216.231469) (xy 410.102304 -216.22131) (xy 337.353102 -216.22131) (xy 337.353702 -216.225184)
			(xy 337.354164 -216.25052) (xy 337.353656 -216.276407) (xy 337.345557 -216.327545) (xy 337.329558 -216.376785)
			(xy 337.306052 -216.422917) (xy 337.27562 -216.464804) (xy 337.23901 -216.501414) (xy 337.197123 -216.531846)
			(xy 337.150991 -216.555352) (xy 337.101751 -216.571351) (xy 337.050613 -216.57945) (xy 336.998839 -216.57945)
			(xy 336.947701 -216.571351) (xy 336.898461 -216.555352) (xy 336.852329 -216.531846) (xy 336.810442 -216.501414)
			(xy 336.773832 -216.464804) (xy 336.7434 -216.422917) (xy 336.719894 -216.376785) (xy 336.703895 -216.327545)
			(xy 336.695796 -216.276407) (xy 336.695288 -216.25052) (xy 336.695823 -216.222812) (xy 336.705015 -216.168165)
			(xy 336.713576 -216.141808) (xy 336.72145 -216.11971) (xy 336.516472 -215.764872) (xy 336.493612 -215.760554)
			(xy 336.46879 -215.755389) (xy 336.421007 -215.73844) (xy 336.376384 -215.714372) (xy 336.335974 -215.683753)
			(xy 336.300731 -215.647305) (xy 336.271487 -215.60589) (xy 336.248932 -215.560483) (xy 336.233597 -215.512158)
			(xy 336.225846 -215.462054) (xy 336.225388 -215.436704) (xy 135.934704 -215.436704) (xy 135.934196 -215.462611)
			(xy 135.92609 -215.513788) (xy 135.910078 -215.563067) (xy 135.886555 -215.609234) (xy 135.856099 -215.651153)
			(xy 135.819461 -215.687791) (xy 135.777542 -215.718247) (xy 135.731375 -215.74177) (xy 135.682096 -215.757782)
			(xy 135.630919 -215.765888) (xy 135.579105 -215.765888) (xy 135.527928 -215.757782) (xy 135.478649 -215.74177)
			(xy 135.432482 -215.718247) (xy 135.390563 -215.687791) (xy 135.353925 -215.651153) (xy 135.323469 -215.609234)
			(xy 135.299946 -215.563067) (xy 135.283934 -215.513788) (xy 135.275828 -215.462611) (xy 135.27532 -215.436704)
			(xy 135.27603 -215.405863) (xy 135.287538 -215.345263) (xy 135.29818 -215.316308) (xy 135.306816 -215.294464)
			(xy 135.084058 -214.872824) (xy 135.061452 -214.867744) (xy 135.037516 -214.861817) (xy 134.991624 -214.843773)
			(xy 134.948934 -214.819093) (xy 134.910397 -214.788329) (xy 134.876873 -214.752166) (xy 134.849112 -214.711412)
			(xy 134.827733 -214.666976) (xy 134.813212 -214.619852) (xy 134.805875 -214.57109) (xy 134.80542 -214.546434)
			(xy 133.57622 -214.546434) (xy 133.584188 -214.596747) (xy 133.584696 -214.622634) (xy 133.584247 -214.64797)
			(xy 133.57649 -214.698044) (xy 133.561163 -214.746341) (xy 133.538627 -214.791726) (xy 133.509412 -214.833128)
			(xy 133.474208 -214.869572) (xy 133.433842 -214.900202) (xy 133.389265 -214.924296) (xy 133.341527 -214.941286)
			(xy 133.316726 -214.946484) (xy 133.293866 -214.950802) (xy 133.088888 -215.305894) (xy 133.096762 -215.327738)
			(xy 133.10541 -215.354146) (xy 133.114729 -215.408922) (xy 133.115304 -215.436704) (xy 133.114796 -215.46261)
			(xy 133.396194 -215.46261) (xy 133.396194 -215.41079) (xy 133.4043 -215.359609) (xy 133.420313 -215.310326)
			(xy 133.44384 -215.264155) (xy 133.474299 -215.222232) (xy 133.510941 -215.185591) (xy 133.552865 -215.155133)
			(xy 133.599037 -215.131609) (xy 133.648321 -215.115597) (xy 133.699502 -215.107493) (xy 133.725412 -215.107012)
			(xy 133.750924 -215.107479) (xy 133.80134 -215.115342) (xy 133.849942 -215.130878) (xy 133.89557 -215.153716)
			(xy 133.937135 -215.183311) (xy 133.973645 -215.218956) (xy 133.989318 -215.239092) (xy 134.401306 -215.239092)
			(xy 134.416974 -215.218952) (xy 134.453485 -215.183309) (xy 134.495052 -215.153716) (xy 134.540681 -215.130881)
			(xy 134.589284 -215.115348) (xy 134.6397 -215.107489) (xy 134.665212 -215.107012) (xy 134.691119 -215.107513)
			(xy 134.742295 -215.11562) (xy 134.791573 -215.131633) (xy 134.837739 -215.155158) (xy 134.879656 -215.185614)
			(xy 134.916294 -215.222253) (xy 134.946749 -215.264172) (xy 134.970271 -215.310339) (xy 134.986282 -215.359617)
			(xy 134.994388 -215.410793) (xy 134.994388 -215.462607) (xy 134.986282 -215.513783) (xy 134.970271 -215.563061)
			(xy 134.946749 -215.609228) (xy 134.916294 -215.651147) (xy 134.879656 -215.687786) (xy 134.837739 -215.718242)
			(xy 134.791573 -215.741767) (xy 134.742295 -215.75778) (xy 134.691119 -215.765887) (xy 134.665212 -215.766396)
			(xy 134.6397 -215.765908) (xy 134.589286 -215.758049) (xy 134.540685 -215.742517) (xy 134.495056 -215.719683)
			(xy 134.453491 -215.690092) (xy 134.41698 -215.65445) (xy 134.401306 -215.634316) (xy 133.989318 -215.634316)
			(xy 133.973638 -215.654446) (xy 133.937129 -215.69009) (xy 133.895565 -215.719683) (xy 133.849938 -215.74252)
			(xy 133.801337 -215.758055) (xy 133.750924 -215.765918) (xy 133.725412 -215.766396) (xy 133.699502 -215.765907)
			(xy 133.648321 -215.757803) (xy 133.599037 -215.741791) (xy 133.552865 -215.718267) (xy 133.510941 -215.687809)
			(xy 133.474299 -215.651168) (xy 133.44384 -215.609245) (xy 133.420313 -215.563074) (xy 133.4043 -215.513791)
			(xy 133.396194 -215.46261) (xy 133.114796 -215.46261) (xy 133.114796 -215.462611) (xy 133.10669 -215.513788)
			(xy 133.090678 -215.563067) (xy 133.067155 -215.609234) (xy 133.036699 -215.651153) (xy 133.000061 -215.687791)
			(xy 132.958142 -215.718247) (xy 132.911975 -215.74177) (xy 132.862696 -215.757782) (xy 132.811519 -215.765888)
			(xy 132.759705 -215.765888) (xy 132.708528 -215.757782) (xy 132.659249 -215.74177) (xy 132.613082 -215.718247)
			(xy 132.571163 -215.687791) (xy 132.534525 -215.651153) (xy 132.504069 -215.609234) (xy 132.480546 -215.563067)
			(xy 132.464534 -215.513788) (xy 132.456428 -215.462611) (xy 132.45592 -215.436704) (xy 131.235704 -215.436704)
			(xy 131.235196 -215.462611) (xy 131.22709 -215.513788) (xy 131.211078 -215.563067) (xy 131.187555 -215.609234)
			(xy 131.157099 -215.651153) (xy 131.120461 -215.687791) (xy 131.078542 -215.718247) (xy 131.032375 -215.74177)
			(xy 130.983096 -215.757782) (xy 130.931919 -215.765888) (xy 130.880105 -215.765888) (xy 130.828928 -215.757782)
			(xy 130.779649 -215.74177) (xy 130.733482 -215.718247) (xy 130.691563 -215.687791) (xy 130.654925 -215.651153)
			(xy 130.624469 -215.609234) (xy 130.600946 -215.563067) (xy 130.584934 -215.513788) (xy 130.576828 -215.462611)
			(xy 130.57632 -215.436704) (xy 129.356104 -215.436704) (xy 129.355596 -215.462611) (xy 129.34749 -215.513788)
			(xy 129.331478 -215.563067) (xy 129.307955 -215.609234) (xy 129.277499 -215.651153) (xy 129.240861 -215.687791)
			(xy 129.198942 -215.718247) (xy 129.152775 -215.74177) (xy 129.103496 -215.757782) (xy 129.052319 -215.765888)
			(xy 129.000505 -215.765888) (xy 128.949328 -215.757782) (xy 128.900049 -215.74177) (xy 128.853882 -215.718247)
			(xy 128.811963 -215.687791) (xy 128.775325 -215.651153) (xy 128.744869 -215.609234) (xy 128.721346 -215.563067)
			(xy 128.705334 -215.513788) (xy 128.697228 -215.462611) (xy 128.69672 -215.436704) (xy 127.476504 -215.436704)
			(xy 127.475996 -215.462611) (xy 127.46789 -215.513788) (xy 127.451878 -215.563067) (xy 127.428355 -215.609234)
			(xy 127.397899 -215.651153) (xy 127.361261 -215.687791) (xy 127.319342 -215.718247) (xy 127.273175 -215.74177)
			(xy 127.223896 -215.757782) (xy 127.172719 -215.765888) (xy 127.120905 -215.765888) (xy 127.069728 -215.757782)
			(xy 127.020449 -215.74177) (xy 126.974282 -215.718247) (xy 126.932363 -215.687791) (xy 126.895725 -215.651153)
			(xy 126.865269 -215.609234) (xy 126.841746 -215.563067) (xy 126.825734 -215.513788) (xy 126.817628 -215.462611)
			(xy 126.81712 -215.436704) (xy 125.596904 -215.436704) (xy 125.596396 -215.462611) (xy 125.58829 -215.513788)
			(xy 125.572278 -215.563067) (xy 125.548755 -215.609234) (xy 125.518299 -215.651153) (xy 125.481661 -215.687791)
			(xy 125.439742 -215.718247) (xy 125.393575 -215.74177) (xy 125.344296 -215.757782) (xy 125.293119 -215.765888)
			(xy 125.241305 -215.765888) (xy 125.190128 -215.757782) (xy 125.140849 -215.74177) (xy 125.094682 -215.718247)
			(xy 125.052763 -215.687791) (xy 125.016125 -215.651153) (xy 124.985669 -215.609234) (xy 124.962146 -215.563067)
			(xy 124.946134 -215.513788) (xy 124.938028 -215.462611) (xy 124.93752 -215.436704) (xy 123.717304 -215.436704)
			(xy 123.716796 -215.462611) (xy 123.70869 -215.513788) (xy 123.692678 -215.563067) (xy 123.669155 -215.609234)
			(xy 123.638699 -215.651153) (xy 123.602061 -215.687791) (xy 123.560142 -215.718247) (xy 123.513975 -215.74177)
			(xy 123.464696 -215.757782) (xy 123.413519 -215.765888) (xy 123.361705 -215.765888) (xy 123.310528 -215.757782)
			(xy 123.261249 -215.74177) (xy 123.215082 -215.718247) (xy 123.173163 -215.687791) (xy 123.136525 -215.651153)
			(xy 123.106069 -215.609234) (xy 123.082546 -215.563067) (xy 123.066534 -215.513788) (xy 123.058428 -215.462611)
			(xy 123.05792 -215.436704) (xy 121.837704 -215.436704) (xy 121.837196 -215.462611) (xy 121.82909 -215.513788)
			(xy 121.813078 -215.563067) (xy 121.789555 -215.609234) (xy 121.759099 -215.651153) (xy 121.722461 -215.687791)
			(xy 121.680542 -215.718247) (xy 121.634375 -215.74177) (xy 121.585096 -215.757782) (xy 121.533919 -215.765888)
			(xy 121.482105 -215.765888) (xy 121.430928 -215.757782) (xy 121.381649 -215.74177) (xy 121.335482 -215.718247)
			(xy 121.293563 -215.687791) (xy 121.256925 -215.651153) (xy 121.226469 -215.609234) (xy 121.202946 -215.563067)
			(xy 121.186934 -215.513788) (xy 121.178828 -215.462611) (xy 121.17832 -215.436704) (xy 119.958104 -215.436704)
			(xy 119.957596 -215.462611) (xy 119.94949 -215.513788) (xy 119.933478 -215.563067) (xy 119.909955 -215.609234)
			(xy 119.879499 -215.651153) (xy 119.842861 -215.687791) (xy 119.800942 -215.718247) (xy 119.754775 -215.74177)
			(xy 119.705496 -215.757782) (xy 119.654319 -215.765888) (xy 119.602505 -215.765888) (xy 119.551328 -215.757782)
			(xy 119.502049 -215.74177) (xy 119.455882 -215.718247) (xy 119.413963 -215.687791) (xy 119.377325 -215.651153)
			(xy 119.346869 -215.609234) (xy 119.323346 -215.563067) (xy 119.307334 -215.513788) (xy 119.299228 -215.462611)
			(xy 119.29872 -215.436704) (xy 118.078504 -215.436704) (xy 118.077996 -215.462611) (xy 118.06989 -215.513788)
			(xy 118.053878 -215.563067) (xy 118.030355 -215.609234) (xy 117.999899 -215.651153) (xy 117.963261 -215.687791)
			(xy 117.921342 -215.718247) (xy 117.875175 -215.74177) (xy 117.825896 -215.757782) (xy 117.774719 -215.765888)
			(xy 117.722905 -215.765888) (xy 117.671728 -215.757782) (xy 117.622449 -215.74177) (xy 117.576282 -215.718247)
			(xy 117.534363 -215.687791) (xy 117.497725 -215.651153) (xy 117.467269 -215.609234) (xy 117.443746 -215.563067)
			(xy 117.427734 -215.513788) (xy 117.419628 -215.462611) (xy 117.41912 -215.436704) (xy 116.198904 -215.436704)
			(xy 116.198396 -215.462611) (xy 116.19029 -215.513788) (xy 116.174278 -215.563067) (xy 116.150755 -215.609234)
			(xy 116.120299 -215.651153) (xy 116.083661 -215.687791) (xy 116.041742 -215.718247) (xy 115.995575 -215.74177)
			(xy 115.946296 -215.757782) (xy 115.895119 -215.765888) (xy 115.843305 -215.765888) (xy 115.792128 -215.757782)
			(xy 115.742849 -215.74177) (xy 115.696682 -215.718247) (xy 115.654763 -215.687791) (xy 115.618125 -215.651153)
			(xy 115.587669 -215.609234) (xy 115.564146 -215.563067) (xy 115.548134 -215.513788) (xy 115.540028 -215.462611)
			(xy 115.53952 -215.436704) (xy 114.319304 -215.436704) (xy 114.318796 -215.462611) (xy 114.31069 -215.513788)
			(xy 114.294678 -215.563067) (xy 114.271155 -215.609234) (xy 114.240699 -215.651153) (xy 114.204061 -215.687791)
			(xy 114.162142 -215.718247) (xy 114.115975 -215.74177) (xy 114.066696 -215.757782) (xy 114.015519 -215.765888)
			(xy 113.963705 -215.765888) (xy 113.912528 -215.757782) (xy 113.863249 -215.74177) (xy 113.817082 -215.718247)
			(xy 113.775163 -215.687791) (xy 113.738525 -215.651153) (xy 113.708069 -215.609234) (xy 113.684546 -215.563067)
			(xy 113.668534 -215.513788) (xy 113.660428 -215.462611) (xy 113.65992 -215.436704) (xy 111.499904 -215.436704)
			(xy 111.499396 -215.462611) (xy 111.49129 -215.513788) (xy 111.475278 -215.563067) (xy 111.451755 -215.609234)
			(xy 111.421299 -215.651153) (xy 111.384661 -215.687791) (xy 111.342742 -215.718247) (xy 111.296575 -215.74177)
			(xy 111.247296 -215.757782) (xy 111.196119 -215.765888) (xy 111.144305 -215.765888) (xy 111.093128 -215.757782)
			(xy 111.043849 -215.74177) (xy 110.997682 -215.718247) (xy 110.955763 -215.687791) (xy 110.919125 -215.651153)
			(xy 110.888669 -215.609234) (xy 110.865146 -215.563067) (xy 110.849134 -215.513788) (xy 110.841028 -215.462611)
			(xy 110.84052 -215.436704) (xy 110.840955 -215.413764) (xy 110.847378 -215.368334) (xy 110.860018 -215.324227)
			(xy 110.868968 -215.3031) (xy 110.878874 -215.280494) (xy 110.665006 -214.87511) (xy 110.640876 -214.870538)
			(xy 110.615954 -214.86544) (xy 110.567941 -214.848641) (xy 110.523081 -214.824663) (xy 110.482438 -214.794075)
			(xy 110.44698 -214.757604) (xy 110.417549 -214.716116) (xy 110.394843 -214.670598) (xy 110.379403 -214.622131)
			(xy 110.371595 -214.571867) (xy 110.371128 -214.546434) (xy 109.14142 -214.546434) (xy 109.149388 -214.596747)
			(xy 109.149896 -214.622634) (xy 109.149447 -214.64797) (xy 109.14169 -214.698044) (xy 109.126363 -214.746341)
			(xy 109.103827 -214.791726) (xy 109.074612 -214.833128) (xy 109.039408 -214.869572) (xy 108.999042 -214.900202)
			(xy 108.954465 -214.924296) (xy 108.906727 -214.941286) (xy 108.881926 -214.946484) (xy 108.859066 -214.950802)
			(xy 108.654088 -215.305894) (xy 108.661962 -215.327738) (xy 108.67061 -215.354146) (xy 108.679929 -215.408922)
			(xy 108.680504 -215.436704) (xy 108.679996 -215.46261) (xy 108.961394 -215.46261) (xy 108.961394 -215.41079)
			(xy 108.9695 -215.359609) (xy 108.985513 -215.310326) (xy 109.00904 -215.264155) (xy 109.039499 -215.222232)
			(xy 109.076141 -215.185591) (xy 109.118065 -215.155133) (xy 109.164237 -215.131609) (xy 109.213521 -215.115597)
			(xy 109.264702 -215.107493) (xy 109.290612 -215.107012) (xy 109.316124 -215.107479) (xy 109.36654 -215.115342)
			(xy 109.415142 -215.130878) (xy 109.46077 -215.153716) (xy 109.502335 -215.183311) (xy 109.538845 -215.218956)
			(xy 109.554518 -215.239092) (xy 109.966506 -215.239092) (xy 109.982174 -215.218952) (xy 110.018685 -215.183309)
			(xy 110.060252 -215.153716) (xy 110.105881 -215.130881) (xy 110.154484 -215.115348) (xy 110.2049 -215.107489)
			(xy 110.230412 -215.107012) (xy 110.256319 -215.107513) (xy 110.307495 -215.11562) (xy 110.356773 -215.131633)
			(xy 110.402939 -215.155158) (xy 110.444856 -215.185614) (xy 110.481494 -215.222253) (xy 110.511949 -215.264172)
			(xy 110.535471 -215.310339) (xy 110.551482 -215.359617) (xy 110.559588 -215.410793) (xy 110.559588 -215.462607)
			(xy 110.551482 -215.513783) (xy 110.535471 -215.563061) (xy 110.511949 -215.609228) (xy 110.481494 -215.651147)
			(xy 110.444856 -215.687786) (xy 110.402939 -215.718242) (xy 110.356773 -215.741767) (xy 110.307495 -215.75778)
			(xy 110.256319 -215.765887) (xy 110.230412 -215.766396) (xy 110.2049 -215.765908) (xy 110.154486 -215.758049)
			(xy 110.105885 -215.742517) (xy 110.060256 -215.719683) (xy 110.018691 -215.690092) (xy 109.98218 -215.65445)
			(xy 109.966506 -215.634316) (xy 109.554518 -215.634316) (xy 109.538838 -215.654446) (xy 109.502329 -215.69009)
			(xy 109.460765 -215.719683) (xy 109.415138 -215.74252) (xy 109.366537 -215.758055) (xy 109.316124 -215.765918)
			(xy 109.290612 -215.766396) (xy 109.264702 -215.765907) (xy 109.213521 -215.757803) (xy 109.164237 -215.741791)
			(xy 109.118065 -215.718267) (xy 109.076141 -215.687809) (xy 109.039499 -215.651168) (xy 109.00904 -215.609245)
			(xy 108.985513 -215.563074) (xy 108.9695 -215.513791) (xy 108.961394 -215.46261) (xy 108.679996 -215.46261)
			(xy 108.679996 -215.462611) (xy 108.67189 -215.513788) (xy 108.655878 -215.563067) (xy 108.632355 -215.609234)
			(xy 108.601899 -215.651153) (xy 108.565261 -215.687791) (xy 108.523342 -215.718247) (xy 108.477175 -215.74177)
			(xy 108.427896 -215.757782) (xy 108.376719 -215.765888) (xy 108.324905 -215.765888) (xy 108.273728 -215.757782)
			(xy 108.224449 -215.74177) (xy 108.178282 -215.718247) (xy 108.136363 -215.687791) (xy 108.099725 -215.651153)
			(xy 108.069269 -215.609234) (xy 108.045746 -215.563067) (xy 108.029734 -215.513788) (xy 108.021628 -215.462611)
			(xy 108.02112 -215.436704) (xy 106.800904 -215.436704) (xy 106.800396 -215.462611) (xy 106.79229 -215.513788)
			(xy 106.776278 -215.563067) (xy 106.752755 -215.609234) (xy 106.722299 -215.651153) (xy 106.685661 -215.687791)
			(xy 106.643742 -215.718247) (xy 106.597575 -215.74177) (xy 106.548296 -215.757782) (xy 106.497119 -215.765888)
			(xy 106.445305 -215.765888) (xy 106.394128 -215.757782) (xy 106.344849 -215.74177) (xy 106.298682 -215.718247)
			(xy 106.256763 -215.687791) (xy 106.220125 -215.651153) (xy 106.189669 -215.609234) (xy 106.166146 -215.563067)
			(xy 106.150134 -215.513788) (xy 106.142028 -215.462611) (xy 106.14152 -215.436704) (xy 104.921304 -215.436704)
			(xy 104.920796 -215.462611) (xy 104.91269 -215.513788) (xy 104.896678 -215.563067) (xy 104.873155 -215.609234)
			(xy 104.842699 -215.651153) (xy 104.806061 -215.687791) (xy 104.764142 -215.718247) (xy 104.717975 -215.74177)
			(xy 104.668696 -215.757782) (xy 104.617519 -215.765888) (xy 104.565705 -215.765888) (xy 104.514528 -215.757782)
			(xy 104.465249 -215.74177) (xy 104.419082 -215.718247) (xy 104.377163 -215.687791) (xy 104.340525 -215.651153)
			(xy 104.310069 -215.609234) (xy 104.286546 -215.563067) (xy 104.270534 -215.513788) (xy 104.262428 -215.462611)
			(xy 104.26192 -215.436704) (xy 103.041704 -215.436704) (xy 103.041196 -215.462611) (xy 103.03309 -215.513788)
			(xy 103.017078 -215.563067) (xy 102.993555 -215.609234) (xy 102.963099 -215.651153) (xy 102.926461 -215.687791)
			(xy 102.884542 -215.718247) (xy 102.838375 -215.74177) (xy 102.789096 -215.757782) (xy 102.737919 -215.765888)
			(xy 102.686105 -215.765888) (xy 102.634928 -215.757782) (xy 102.585649 -215.74177) (xy 102.539482 -215.718247)
			(xy 102.497563 -215.687791) (xy 102.460925 -215.651153) (xy 102.430469 -215.609234) (xy 102.406946 -215.563067)
			(xy 102.390934 -215.513788) (xy 102.382828 -215.462611) (xy 102.38232 -215.436704) (xy 101.162104 -215.436704)
			(xy 101.161596 -215.462611) (xy 101.15349 -215.513788) (xy 101.137478 -215.563067) (xy 101.113955 -215.609234)
			(xy 101.083499 -215.651153) (xy 101.046861 -215.687791) (xy 101.004942 -215.718247) (xy 100.958775 -215.74177)
			(xy 100.909496 -215.757782) (xy 100.858319 -215.765888) (xy 100.806505 -215.765888) (xy 100.755328 -215.757782)
			(xy 100.706049 -215.74177) (xy 100.659882 -215.718247) (xy 100.617963 -215.687791) (xy 100.581325 -215.651153)
			(xy 100.550869 -215.609234) (xy 100.527346 -215.563067) (xy 100.511334 -215.513788) (xy 100.503228 -215.462611)
			(xy 100.50272 -215.436704) (xy 99.282504 -215.436704) (xy 99.281996 -215.462611) (xy 99.27389 -215.513788)
			(xy 99.257878 -215.563067) (xy 99.234355 -215.609234) (xy 99.203899 -215.651153) (xy 99.167261 -215.687791)
			(xy 99.125342 -215.718247) (xy 99.079175 -215.74177) (xy 99.029896 -215.757782) (xy 98.978719 -215.765888)
			(xy 98.926905 -215.765888) (xy 98.875728 -215.757782) (xy 98.826449 -215.74177) (xy 98.780282 -215.718247)
			(xy 98.738363 -215.687791) (xy 98.701725 -215.651153) (xy 98.671269 -215.609234) (xy 98.647746 -215.563067)
			(xy 98.631734 -215.513788) (xy 98.623628 -215.462611) (xy 98.62312 -215.436704) (xy 97.402904 -215.436704)
			(xy 97.402396 -215.462611) (xy 97.39429 -215.513788) (xy 97.378278 -215.563067) (xy 97.354755 -215.609234)
			(xy 97.324299 -215.651153) (xy 97.287661 -215.687791) (xy 97.245742 -215.718247) (xy 97.199575 -215.74177)
			(xy 97.150296 -215.757782) (xy 97.099119 -215.765888) (xy 97.047305 -215.765888) (xy 96.996128 -215.757782)
			(xy 96.946849 -215.74177) (xy 96.900682 -215.718247) (xy 96.858763 -215.687791) (xy 96.822125 -215.651153)
			(xy 96.791669 -215.609234) (xy 96.768146 -215.563067) (xy 96.752134 -215.513788) (xy 96.744028 -215.462611)
			(xy 96.74352 -215.436704) (xy 95.523304 -215.436704) (xy 95.522796 -215.462611) (xy 95.51469 -215.513788)
			(xy 95.498678 -215.563067) (xy 95.475155 -215.609234) (xy 95.444699 -215.651153) (xy 95.408061 -215.687791)
			(xy 95.366142 -215.718247) (xy 95.319975 -215.74177) (xy 95.270696 -215.757782) (xy 95.219519 -215.765888)
			(xy 95.167705 -215.765888) (xy 95.116528 -215.757782) (xy 95.067249 -215.74177) (xy 95.021082 -215.718247)
			(xy 94.979163 -215.687791) (xy 94.942525 -215.651153) (xy 94.912069 -215.609234) (xy 94.888546 -215.563067)
			(xy 94.872534 -215.513788) (xy 94.864428 -215.462611) (xy 94.86392 -215.436704) (xy 93.643704 -215.436704)
			(xy 93.643196 -215.462611) (xy 93.63509 -215.513788) (xy 93.619078 -215.563067) (xy 93.595555 -215.609234)
			(xy 93.565099 -215.651153) (xy 93.528461 -215.687791) (xy 93.486542 -215.718247) (xy 93.440375 -215.74177)
			(xy 93.391096 -215.757782) (xy 93.339919 -215.765888) (xy 93.288105 -215.765888) (xy 93.236928 -215.757782)
			(xy 93.187649 -215.74177) (xy 93.141482 -215.718247) (xy 93.099563 -215.687791) (xy 93.062925 -215.651153)
			(xy 93.032469 -215.609234) (xy 93.008946 -215.563067) (xy 92.992934 -215.513788) (xy 92.984828 -215.462611)
			(xy 92.98432 -215.436704) (xy 91.764104 -215.436704) (xy 91.763596 -215.462611) (xy 91.75549 -215.513788)
			(xy 91.739478 -215.563067) (xy 91.715955 -215.609234) (xy 91.685499 -215.651153) (xy 91.648861 -215.687791)
			(xy 91.606942 -215.718247) (xy 91.560775 -215.74177) (xy 91.511496 -215.757782) (xy 91.460319 -215.765888)
			(xy 91.408505 -215.765888) (xy 91.357328 -215.757782) (xy 91.308049 -215.74177) (xy 91.261882 -215.718247)
			(xy 91.219963 -215.687791) (xy 91.183325 -215.651153) (xy 91.152869 -215.609234) (xy 91.129346 -215.563067)
			(xy 91.113334 -215.513788) (xy 91.105228 -215.462611) (xy 91.10472 -215.436704) (xy 89.884504 -215.436704)
			(xy 89.883996 -215.462611) (xy 89.87589 -215.513788) (xy 89.859878 -215.563067) (xy 89.836355 -215.609234)
			(xy 89.805899 -215.651153) (xy 89.769261 -215.687791) (xy 89.727342 -215.718247) (xy 89.681175 -215.74177)
			(xy 89.631896 -215.757782) (xy 89.580719 -215.765888) (xy 89.528905 -215.765888) (xy 89.477728 -215.757782)
			(xy 89.428449 -215.74177) (xy 89.382282 -215.718247) (xy 89.340363 -215.687791) (xy 89.303725 -215.651153)
			(xy 89.273269 -215.609234) (xy 89.249746 -215.563067) (xy 89.233734 -215.513788) (xy 89.225628 -215.462611)
			(xy 89.22512 -215.436704) (xy 88.944704 -215.436704) (xy 88.944111 -215.464421) (xy 88.934787 -215.519068)
			(xy 88.926162 -215.545416) (xy 88.918288 -215.567514) (xy 89.123266 -215.922352) (xy 89.146126 -215.92667)
			(xy 89.170934 -215.931835) (xy 89.218674 -215.948828) (xy 89.263251 -215.972925) (xy 89.303616 -216.003559)
			(xy 89.338819 -216.040009) (xy 89.36803 -216.081415) (xy 89.390562 -216.126804) (xy 89.405883 -216.175106)
			(xy 89.413035 -216.22131) (xy 162.162236 -216.22131) (xy 162.162236 -215.81237) (xy 162.162709 -215.802211)
			(xy 162.170493 -215.783441) (xy 162.184865 -215.769077) (xy 162.203638 -215.761303) (xy 162.213798 -215.760808)
			(xy 163.613338 -215.760808) (xy 163.623495 -215.761302) (xy 163.642259 -215.769083) (xy 163.656622 -215.783448)
			(xy 163.6644 -215.802213) (xy 163.6649 -215.81237) (xy 163.6649 -216.22131) (xy 169.706036 -216.22131)
			(xy 169.706036 -215.81237) (xy 169.706509 -215.802211) (xy 169.714293 -215.783441) (xy 169.728665 -215.769077)
			(xy 169.747438 -215.761303) (xy 169.757598 -215.760808) (xy 171.157138 -215.760808) (xy 171.167295 -215.761302)
			(xy 171.186059 -215.769083) (xy 171.200422 -215.783448) (xy 171.2082 -215.802213) (xy 171.2087 -215.81237)
			(xy 171.2087 -216.22131) (xy 177.249836 -216.22131) (xy 177.249836 -215.81237) (xy 177.250309 -215.802211)
			(xy 177.258093 -215.783441) (xy 177.272465 -215.769077) (xy 177.291238 -215.761303) (xy 177.301398 -215.760808)
			(xy 178.700938 -215.760808) (xy 178.711095 -215.761302) (xy 178.729859 -215.769083) (xy 178.744222 -215.783448)
			(xy 178.752 -215.802213) (xy 178.7525 -215.81237) (xy 178.7525 -216.22131) (xy 184.793636 -216.22131)
			(xy 184.793636 -215.81237) (xy 184.794109 -215.802211) (xy 184.801893 -215.783441) (xy 184.816265 -215.769077)
			(xy 184.835038 -215.761303) (xy 184.845198 -215.760808) (xy 186.244738 -215.760808) (xy 186.254895 -215.761302)
			(xy 186.273659 -215.769083) (xy 186.288022 -215.783448) (xy 186.2958 -215.802213) (xy 186.2963 -215.81237)
			(xy 186.2963 -216.22131) (xy 192.337436 -216.22131) (xy 192.337436 -215.81237) (xy 192.337909 -215.802211)
			(xy 192.345693 -215.783441) (xy 192.360065 -215.769077) (xy 192.378838 -215.761303) (xy 192.388998 -215.760808)
			(xy 193.788538 -215.760808) (xy 193.798695 -215.761302) (xy 193.817459 -215.769083) (xy 193.831822 -215.783448)
			(xy 193.8396 -215.802213) (xy 193.8401 -215.81237) (xy 193.8401 -216.22131) (xy 199.881236 -216.22131)
			(xy 199.881236 -215.81237) (xy 199.881709 -215.802211) (xy 199.889493 -215.783441) (xy 199.903865 -215.769077)
			(xy 199.922638 -215.761303) (xy 199.932798 -215.760808) (xy 201.332338 -215.760808) (xy 201.342495 -215.761302)
			(xy 201.361259 -215.769083) (xy 201.375622 -215.783448) (xy 201.3834 -215.802213) (xy 201.3839 -215.81237)
			(xy 201.3839 -216.22131) (xy 207.425036 -216.22131) (xy 207.425036 -215.81237) (xy 207.425509 -215.802211)
			(xy 207.433293 -215.783441) (xy 207.447665 -215.769077) (xy 207.466438 -215.761303) (xy 207.476598 -215.760808)
			(xy 208.876138 -215.760808) (xy 208.886295 -215.761302) (xy 208.905059 -215.769083) (xy 208.919422 -215.783448)
			(xy 208.9272 -215.802213) (xy 208.9277 -215.81237) (xy 208.9277 -216.22131) (xy 214.968836 -216.22131)
			(xy 214.968836 -215.81237) (xy 214.969309 -215.802211) (xy 214.977093 -215.783441) (xy 214.991465 -215.769077)
			(xy 215.010238 -215.761303) (xy 215.020398 -215.760808) (xy 216.419938 -215.760808) (xy 216.430095 -215.761302)
			(xy 216.448859 -215.769083) (xy 216.463222 -215.783448) (xy 216.471 -215.802213) (xy 216.4715 -215.81237)
			(xy 216.4715 -216.22131) (xy 259.429504 -216.22131) (xy 259.429504 -215.81237) (xy 259.430008 -215.802214)
			(xy 259.437786 -215.783451) (xy 259.452148 -215.769088) (xy 259.470911 -215.761309) (xy 259.481066 -215.760808)
			(xy 260.880606 -215.760808) (xy 260.89076 -215.761328) (xy 260.909524 -215.769099) (xy 260.923888 -215.783456)
			(xy 260.931667 -215.802216) (xy 260.932168 -215.81237) (xy 260.932168 -216.22131) (xy 266.973304 -216.22131)
			(xy 266.973304 -215.81237) (xy 266.973808 -215.802214) (xy 266.981586 -215.783451) (xy 266.995948 -215.769088)
			(xy 267.014711 -215.761309) (xy 267.024866 -215.760808) (xy 268.424406 -215.760808) (xy 268.43456 -215.761328)
			(xy 268.453324 -215.769099) (xy 268.467688 -215.783456) (xy 268.475467 -215.802216) (xy 268.475968 -215.81237)
			(xy 268.475968 -216.22131) (xy 274.517104 -216.22131) (xy 274.517104 -215.81237) (xy 274.517608 -215.802214)
			(xy 274.525386 -215.783451) (xy 274.539748 -215.769088) (xy 274.558511 -215.761309) (xy 274.568666 -215.760808)
			(xy 275.968206 -215.760808) (xy 275.97836 -215.761328) (xy 275.997124 -215.769099) (xy 276.011488 -215.783456)
			(xy 276.019267 -215.802216) (xy 276.019768 -215.81237) (xy 276.019768 -216.22131) (xy 282.060904 -216.22131)
			(xy 282.060904 -215.81237) (xy 282.061408 -215.802214) (xy 282.069186 -215.783451) (xy 282.083548 -215.769088)
			(xy 282.102311 -215.761309) (xy 282.112466 -215.760808) (xy 283.512006 -215.760808) (xy 283.52216 -215.761328)
			(xy 283.540924 -215.769099) (xy 283.555288 -215.783456) (xy 283.563067 -215.802216) (xy 283.563568 -215.81237)
			(xy 283.563568 -216.22131) (xy 289.604704 -216.22131) (xy 289.604704 -215.81237) (xy 289.605208 -215.802214)
			(xy 289.612986 -215.783451) (xy 289.627348 -215.769088) (xy 289.646111 -215.761309) (xy 289.656266 -215.760808)
			(xy 291.055806 -215.760808) (xy 291.06596 -215.761328) (xy 291.084724 -215.769099) (xy 291.099088 -215.783456)
			(xy 291.106867 -215.802216) (xy 291.107368 -215.81237) (xy 291.107368 -216.22131) (xy 297.148504 -216.22131)
			(xy 297.148504 -215.81237) (xy 297.149008 -215.802214) (xy 297.156786 -215.783451) (xy 297.171148 -215.769088)
			(xy 297.189911 -215.761309) (xy 297.200066 -215.760808) (xy 298.599606 -215.760808) (xy 298.60976 -215.761328)
			(xy 298.628524 -215.769099) (xy 298.642888 -215.783456) (xy 298.650667 -215.802216) (xy 298.651168 -215.81237)
			(xy 298.651168 -216.22131) (xy 304.692304 -216.22131) (xy 304.692304 -215.81237) (xy 304.692808 -215.802214)
			(xy 304.700586 -215.783451) (xy 304.714948 -215.769088) (xy 304.733711 -215.761309) (xy 304.743866 -215.760808)
			(xy 306.143406 -215.760808) (xy 306.15356 -215.761328) (xy 306.172324 -215.769099) (xy 306.186688 -215.783456)
			(xy 306.194467 -215.802216) (xy 306.194968 -215.81237) (xy 306.194968 -216.22131) (xy 312.236104 -216.22131)
			(xy 312.236104 -215.81237) (xy 312.236608 -215.802214) (xy 312.244386 -215.783451) (xy 312.258748 -215.769088)
			(xy 312.277511 -215.761309) (xy 312.287666 -215.760808) (xy 313.687206 -215.760808) (xy 313.69736 -215.761328)
			(xy 313.716124 -215.769099) (xy 313.730488 -215.783456) (xy 313.738267 -215.802216) (xy 313.738768 -215.81237)
			(xy 313.738768 -216.22131) (xy 313.738275 -216.231468) (xy 313.730498 -216.250236) (xy 313.716132 -216.2646)
			(xy 313.697364 -216.272376) (xy 313.687206 -216.272872) (xy 312.287666 -216.272872) (xy 312.277507 -216.272395)
			(xy 312.258739 -216.264611) (xy 312.244376 -216.250241) (xy 312.236601 -216.231469) (xy 312.236104 -216.22131)
			(xy 306.194968 -216.22131) (xy 306.194475 -216.231468) (xy 306.186698 -216.250236) (xy 306.172332 -216.2646)
			(xy 306.153564 -216.272376) (xy 306.143406 -216.272872) (xy 304.743866 -216.272872) (xy 304.733707 -216.272395)
			(xy 304.714939 -216.264611) (xy 304.700576 -216.250241) (xy 304.692801 -216.231469) (xy 304.692304 -216.22131)
			(xy 298.651168 -216.22131) (xy 298.650675 -216.231468) (xy 298.642898 -216.250236) (xy 298.628532 -216.2646)
			(xy 298.609764 -216.272376) (xy 298.599606 -216.272872) (xy 297.200066 -216.272872) (xy 297.189907 -216.272395)
			(xy 297.171139 -216.264611) (xy 297.156776 -216.250241) (xy 297.149001 -216.231469) (xy 297.148504 -216.22131)
			(xy 291.107368 -216.22131) (xy 291.106875 -216.231468) (xy 291.099098 -216.250236) (xy 291.084732 -216.2646)
			(xy 291.065964 -216.272376) (xy 291.055806 -216.272872) (xy 289.656266 -216.272872) (xy 289.646107 -216.272395)
			(xy 289.627339 -216.264611) (xy 289.612976 -216.250241) (xy 289.605201 -216.231469) (xy 289.604704 -216.22131)
			(xy 283.563568 -216.22131) (xy 283.563075 -216.231468) (xy 283.555298 -216.250236) (xy 283.540932 -216.2646)
			(xy 283.522164 -216.272376) (xy 283.512006 -216.272872) (xy 282.112466 -216.272872) (xy 282.102307 -216.272395)
			(xy 282.083539 -216.264611) (xy 282.069176 -216.250241) (xy 282.061401 -216.231469) (xy 282.060904 -216.22131)
			(xy 276.019768 -216.22131) (xy 276.019275 -216.231468) (xy 276.011498 -216.250236) (xy 275.997132 -216.2646)
			(xy 275.978364 -216.272376) (xy 275.968206 -216.272872) (xy 274.568666 -216.272872) (xy 274.558507 -216.272395)
			(xy 274.539739 -216.264611) (xy 274.525376 -216.250241) (xy 274.517601 -216.231469) (xy 274.517104 -216.22131)
			(xy 268.475968 -216.22131) (xy 268.475475 -216.231468) (xy 268.467698 -216.250236) (xy 268.453332 -216.2646)
			(xy 268.434564 -216.272376) (xy 268.424406 -216.272872) (xy 267.024866 -216.272872) (xy 267.014707 -216.272395)
			(xy 266.995939 -216.264611) (xy 266.981576 -216.250241) (xy 266.973801 -216.231469) (xy 266.973304 -216.22131)
			(xy 260.932168 -216.22131) (xy 260.931675 -216.231468) (xy 260.923898 -216.250236) (xy 260.909532 -216.2646)
			(xy 260.890764 -216.272376) (xy 260.880606 -216.272872) (xy 259.481066 -216.272872) (xy 259.470907 -216.272395)
			(xy 259.452139 -216.264611) (xy 259.437776 -216.250241) (xy 259.430001 -216.231469) (xy 259.429504 -216.22131)
			(xy 216.4715 -216.22131) (xy 216.470976 -216.231464) (xy 216.463205 -216.250226) (xy 216.448849 -216.264589)
			(xy 216.430091 -216.27237) (xy 216.419938 -216.272872) (xy 215.020398 -216.272872) (xy 215.010241 -216.272368)
			(xy 214.991474 -216.264595) (xy 214.977109 -216.250233) (xy 214.969333 -216.231467) (xy 214.968836 -216.22131)
			(xy 208.9277 -216.22131) (xy 208.927176 -216.231464) (xy 208.919405 -216.250226) (xy 208.905049 -216.264589)
			(xy 208.886291 -216.27237) (xy 208.876138 -216.272872) (xy 207.476598 -216.272872) (xy 207.466441 -216.272368)
			(xy 207.447674 -216.264595) (xy 207.433309 -216.250233) (xy 207.425533 -216.231467) (xy 207.425036 -216.22131)
			(xy 201.3839 -216.22131) (xy 201.383376 -216.231464) (xy 201.375605 -216.250226) (xy 201.361249 -216.264589)
			(xy 201.342491 -216.27237) (xy 201.332338 -216.272872) (xy 199.932798 -216.272872) (xy 199.922641 -216.272368)
			(xy 199.903874 -216.264595) (xy 199.889509 -216.250233) (xy 199.881733 -216.231467) (xy 199.881236 -216.22131)
			(xy 193.8401 -216.22131) (xy 193.839576 -216.231464) (xy 193.831805 -216.250226) (xy 193.817449 -216.264589)
			(xy 193.798691 -216.27237) (xy 193.788538 -216.272872) (xy 192.388998 -216.272872) (xy 192.378841 -216.272368)
			(xy 192.360074 -216.264595) (xy 192.345709 -216.250233) (xy 192.337933 -216.231467) (xy 192.337436 -216.22131)
			(xy 186.2963 -216.22131) (xy 186.295776 -216.231464) (xy 186.288005 -216.250226) (xy 186.273649 -216.264589)
			(xy 186.254891 -216.27237) (xy 186.244738 -216.272872) (xy 184.845198 -216.272872) (xy 184.835041 -216.272368)
			(xy 184.816274 -216.264595) (xy 184.801909 -216.250233) (xy 184.794133 -216.231467) (xy 184.793636 -216.22131)
			(xy 178.7525 -216.22131) (xy 178.751976 -216.231464) (xy 178.744205 -216.250226) (xy 178.729849 -216.264589)
			(xy 178.711091 -216.27237) (xy 178.700938 -216.272872) (xy 177.301398 -216.272872) (xy 177.291241 -216.272368)
			(xy 177.272474 -216.264595) (xy 177.258109 -216.250233) (xy 177.250333 -216.231467) (xy 177.249836 -216.22131)
			(xy 171.2087 -216.22131) (xy 171.208176 -216.231464) (xy 171.200405 -216.250226) (xy 171.186049 -216.264589)
			(xy 171.167291 -216.27237) (xy 171.157138 -216.272872) (xy 169.757598 -216.272872) (xy 169.747441 -216.272368)
			(xy 169.728674 -216.264595) (xy 169.714309 -216.250233) (xy 169.706533 -216.231467) (xy 169.706036 -216.22131)
			(xy 163.6649 -216.22131) (xy 163.664376 -216.231464) (xy 163.656605 -216.250226) (xy 163.642249 -216.264589)
			(xy 163.623491 -216.27237) (xy 163.613338 -216.272872) (xy 162.213798 -216.272872) (xy 162.203641 -216.272368)
			(xy 162.184874 -216.264595) (xy 162.170509 -216.250233) (xy 162.162733 -216.231467) (xy 162.162236 -216.22131)
			(xy 89.413035 -216.22131) (xy 89.413634 -216.225183) (xy 89.414096 -216.25052) (xy 89.413588 -216.276407)
			(xy 89.405489 -216.327545) (xy 89.38949 -216.376785) (xy 89.365984 -216.422917) (xy 89.335552 -216.464804)
			(xy 89.298942 -216.501414) (xy 89.257055 -216.531846) (xy 89.210923 -216.555352) (xy 89.161683 -216.571351)
			(xy 89.110545 -216.57945) (xy 89.058771 -216.57945) (xy 89.007633 -216.571351) (xy 88.958393 -216.555352)
			(xy 88.912261 -216.531846) (xy 88.870374 -216.501414) (xy 88.833764 -216.464804) (xy 88.803332 -216.422917)
			(xy 88.779826 -216.376785) (xy 88.763827 -216.327545) (xy 88.755728 -216.276407) (xy 88.75522 -216.25052)
			(xy 88.755754 -216.222812) (xy 88.764946 -216.168165) (xy 88.773508 -216.141808) (xy 88.781382 -216.11971)
			(xy 88.576404 -215.764872) (xy 88.553544 -215.760554) (xy 88.528711 -215.755439) (xy 88.480928 -215.73848)
			(xy 88.436306 -215.714403) (xy 88.395898 -215.683776) (xy 88.360658 -215.647323) (xy 88.331415 -215.605902)
			(xy 88.308862 -215.560492) (xy 88.293529 -215.512163) (xy 88.285778 -215.462056) (xy 88.28532 -215.436704)
			(xy 2.509012 -215.436704) (xy 2.509012 -216.22131) (xy 11.489436 -216.22131) (xy 11.489436 -215.81237)
			(xy 11.489909 -215.802211) (xy 11.497693 -215.783441) (xy 11.512065 -215.769077) (xy 11.530838 -215.761303)
			(xy 11.540998 -215.760808) (xy 12.940538 -215.760808) (xy 12.950695 -215.761302) (xy 12.969459 -215.769083)
			(xy 12.983822 -215.783448) (xy 12.9916 -215.802213) (xy 12.9921 -215.81237) (xy 12.9921 -216.22131)
			(xy 19.033236 -216.22131) (xy 19.033236 -215.81237) (xy 19.033709 -215.802211) (xy 19.041493 -215.783441)
			(xy 19.055865 -215.769077) (xy 19.074638 -215.761303) (xy 19.084798 -215.760808) (xy 20.484338 -215.760808)
			(xy 20.494495 -215.761302) (xy 20.513259 -215.769083) (xy 20.527622 -215.783448) (xy 20.5354 -215.802213)
			(xy 20.5359 -215.81237) (xy 20.5359 -216.22131) (xy 26.577036 -216.22131) (xy 26.577036 -215.81237)
			(xy 26.577509 -215.802211) (xy 26.585293 -215.783441) (xy 26.599665 -215.769077) (xy 26.618438 -215.761303)
			(xy 26.628598 -215.760808) (xy 28.028138 -215.760808) (xy 28.038295 -215.761302) (xy 28.057059 -215.769083)
			(xy 28.071422 -215.783448) (xy 28.0792 -215.802213) (xy 28.0797 -215.81237) (xy 28.0797 -216.22131)
			(xy 34.120836 -216.22131) (xy 34.120836 -215.81237) (xy 34.121309 -215.802211) (xy 34.129093 -215.783441)
			(xy 34.143465 -215.769077) (xy 34.162238 -215.761303) (xy 34.172398 -215.760808) (xy 35.571938 -215.760808)
			(xy 35.582095 -215.761302) (xy 35.600859 -215.769083) (xy 35.615222 -215.783448) (xy 35.623 -215.802213)
			(xy 35.6235 -215.81237) (xy 35.6235 -216.22131) (xy 41.664636 -216.22131) (xy 41.664636 -215.81237)
			(xy 41.665109 -215.802211) (xy 41.672893 -215.783441) (xy 41.687265 -215.769077) (xy 41.706038 -215.761303)
			(xy 41.716198 -215.760808) (xy 43.115738 -215.760808) (xy 43.125895 -215.761302) (xy 43.144659 -215.769083)
			(xy 43.159022 -215.783448) (xy 43.1668 -215.802213) (xy 43.1673 -215.81237) (xy 43.1673 -216.22131)
			(xy 49.208436 -216.22131) (xy 49.208436 -215.81237) (xy 49.208909 -215.802211) (xy 49.216693 -215.783441)
			(xy 49.231065 -215.769077) (xy 49.249838 -215.761303) (xy 49.259998 -215.760808) (xy 50.659538 -215.760808)
			(xy 50.669695 -215.761302) (xy 50.688459 -215.769083) (xy 50.702822 -215.783448) (xy 50.7106 -215.802213)
			(xy 50.7111 -215.81237) (xy 50.7111 -216.22131) (xy 56.752236 -216.22131) (xy 56.752236 -215.81237)
			(xy 56.752709 -215.802211) (xy 56.760493 -215.783441) (xy 56.774865 -215.769077) (xy 56.793638 -215.761303)
			(xy 56.803798 -215.760808) (xy 58.203338 -215.760808) (xy 58.213495 -215.761302) (xy 58.232259 -215.769083)
			(xy 58.246622 -215.783448) (xy 58.2544 -215.802213) (xy 58.2549 -215.81237) (xy 58.2549 -216.22131)
			(xy 64.296036 -216.22131) (xy 64.296036 -215.81237) (xy 64.296509 -215.802211) (xy 64.304293 -215.783441)
			(xy 64.318665 -215.769077) (xy 64.337438 -215.761303) (xy 64.347598 -215.760808) (xy 65.747138 -215.760808)
			(xy 65.757295 -215.761302) (xy 65.776059 -215.769083) (xy 65.790422 -215.783448) (xy 65.7982 -215.802213)
			(xy 65.7987 -215.81237) (xy 65.7987 -216.22131) (xy 65.798176 -216.231464) (xy 65.790405 -216.250226)
			(xy 65.776049 -216.264589) (xy 65.757291 -216.27237) (xy 65.747138 -216.272872) (xy 64.347598 -216.272872)
			(xy 64.337441 -216.272368) (xy 64.318674 -216.264595) (xy 64.304309 -216.250233) (xy 64.296533 -216.231467)
			(xy 64.296036 -216.22131) (xy 58.2549 -216.22131) (xy 58.254376 -216.231464) (xy 58.246605 -216.250226)
			(xy 58.232249 -216.264589) (xy 58.213491 -216.27237) (xy 58.203338 -216.272872) (xy 56.803798 -216.272872)
			(xy 56.793641 -216.272368) (xy 56.774874 -216.264595) (xy 56.760509 -216.250233) (xy 56.752733 -216.231467)
			(xy 56.752236 -216.22131) (xy 50.7111 -216.22131) (xy 50.710576 -216.231464) (xy 50.702805 -216.250226)
			(xy 50.688449 -216.264589) (xy 50.669691 -216.27237) (xy 50.659538 -216.272872) (xy 49.259998 -216.272872)
			(xy 49.249841 -216.272368) (xy 49.231074 -216.264595) (xy 49.216709 -216.250233) (xy 49.208933 -216.231467)
			(xy 49.208436 -216.22131) (xy 43.1673 -216.22131) (xy 43.166776 -216.231464) (xy 43.159005 -216.250226)
			(xy 43.144649 -216.264589) (xy 43.125891 -216.27237) (xy 43.115738 -216.272872) (xy 41.716198 -216.272872)
			(xy 41.706041 -216.272368) (xy 41.687274 -216.264595) (xy 41.672909 -216.250233) (xy 41.665133 -216.231467)
			(xy 41.664636 -216.22131) (xy 35.6235 -216.22131) (xy 35.622976 -216.231464) (xy 35.615205 -216.250226)
			(xy 35.600849 -216.264589) (xy 35.582091 -216.27237) (xy 35.571938 -216.272872) (xy 34.172398 -216.272872)
			(xy 34.162241 -216.272368) (xy 34.143474 -216.264595) (xy 34.129109 -216.250233) (xy 34.121333 -216.231467)
			(xy 34.120836 -216.22131) (xy 28.0797 -216.22131) (xy 28.079176 -216.231464) (xy 28.071405 -216.250226)
			(xy 28.057049 -216.264589) (xy 28.038291 -216.27237) (xy 28.028138 -216.272872) (xy 26.628598 -216.272872)
			(xy 26.618441 -216.272368) (xy 26.599674 -216.264595) (xy 26.585309 -216.250233) (xy 26.577533 -216.231467)
			(xy 26.577036 -216.22131) (xy 20.5359 -216.22131) (xy 20.535376 -216.231464) (xy 20.527605 -216.250226)
			(xy 20.513249 -216.264589) (xy 20.494491 -216.27237) (xy 20.484338 -216.272872) (xy 19.084798 -216.272872)
			(xy 19.074641 -216.272368) (xy 19.055874 -216.264595) (xy 19.041509 -216.250233) (xy 19.033733 -216.231467)
			(xy 19.033236 -216.22131) (xy 12.9921 -216.22131) (xy 12.991576 -216.231464) (xy 12.983805 -216.250226)
			(xy 12.969449 -216.264589) (xy 12.950691 -216.27237) (xy 12.940538 -216.272872) (xy 11.540998 -216.272872)
			(xy 11.530841 -216.272368) (xy 11.512074 -216.264595) (xy 11.497709 -216.250233) (xy 11.489933 -216.231467)
			(xy 11.489436 -216.22131) (xy 2.509012 -216.22131) (xy 2.509012 -217.071448) (xy 7.389368 -217.071448)
			(xy 7.389368 -216.662508) (xy 7.389828 -216.652358) (xy 7.397614 -216.633612) (xy 7.411999 -216.61929)
			(xy 7.430779 -216.611584) (xy 7.44093 -216.6112) (xy 8.84047 -216.6112) (xy 8.85059 -216.61175) (xy 8.869303 -216.61946)
			(xy 8.883659 -216.633727) (xy 8.891486 -216.652391) (xy 8.892032 -216.662508) (xy 8.892032 -217.071448)
			(xy 14.933168 -217.071448) (xy 14.933168 -216.662508) (xy 14.933628 -216.652358) (xy 14.941414 -216.633612)
			(xy 14.955799 -216.61929) (xy 14.974579 -216.611584) (xy 14.98473 -216.6112) (xy 16.38427 -216.6112)
			(xy 16.39439 -216.61175) (xy 16.413103 -216.61946) (xy 16.427459 -216.633727) (xy 16.435286 -216.652391)
			(xy 16.435832 -216.662508) (xy 16.435832 -217.071448) (xy 22.476968 -217.071448) (xy 22.476968 -216.662508)
			(xy 22.477428 -216.652358) (xy 22.485214 -216.633612) (xy 22.499599 -216.61929) (xy 22.518379 -216.611584)
			(xy 22.52853 -216.6112) (xy 23.92807 -216.6112) (xy 23.93819 -216.61175) (xy 23.956903 -216.61946)
			(xy 23.971259 -216.633727) (xy 23.979086 -216.652391) (xy 23.979632 -216.662508) (xy 23.979632 -217.071448)
			(xy 30.020768 -217.071448) (xy 30.020768 -216.662508) (xy 30.021228 -216.652358) (xy 30.029014 -216.633612)
			(xy 30.043399 -216.61929) (xy 30.062179 -216.611584) (xy 30.07233 -216.6112) (xy 31.47187 -216.6112)
			(xy 31.48199 -216.61175) (xy 31.500703 -216.61946) (xy 31.515059 -216.633727) (xy 31.522886 -216.652391)
			(xy 31.523432 -216.662508) (xy 31.523432 -217.071448) (xy 37.564568 -217.071448) (xy 37.564568 -216.662508)
			(xy 37.565028 -216.652358) (xy 37.572814 -216.633612) (xy 37.587199 -216.61929) (xy 37.605979 -216.611584)
			(xy 37.61613 -216.6112) (xy 39.01567 -216.6112) (xy 39.02579 -216.61175) (xy 39.044503 -216.61946)
			(xy 39.058859 -216.633727) (xy 39.066686 -216.652391) (xy 39.067232 -216.662508) (xy 39.067232 -217.071448)
			(xy 45.108368 -217.071448) (xy 45.108368 -216.662508) (xy 45.108828 -216.652358) (xy 45.116614 -216.633612)
			(xy 45.130999 -216.61929) (xy 45.149779 -216.611584) (xy 45.15993 -216.6112) (xy 46.55947 -216.6112)
			(xy 46.56959 -216.61175) (xy 46.588303 -216.61946) (xy 46.602659 -216.633727) (xy 46.610486 -216.652391)
			(xy 46.611032 -216.662508) (xy 46.611032 -217.071448) (xy 52.652168 -217.071448) (xy 52.652168 -216.662508)
			(xy 52.652628 -216.652358) (xy 52.660414 -216.633612) (xy 52.674799 -216.61929) (xy 52.693579 -216.611584)
			(xy 52.70373 -216.6112) (xy 54.10327 -216.6112) (xy 54.11339 -216.61175) (xy 54.132103 -216.61946)
			(xy 54.146459 -216.633727) (xy 54.154286 -216.652391) (xy 54.154832 -216.662508) (xy 54.154832 -217.071448)
			(xy 60.195968 -217.071448) (xy 60.195968 -216.662508) (xy 60.196428 -216.652358) (xy 60.204214 -216.633612)
			(xy 60.218599 -216.61929) (xy 60.237379 -216.611584) (xy 60.24753 -216.6112) (xy 61.64707 -216.6112)
			(xy 61.65719 -216.61175) (xy 61.675903 -216.61946) (xy 61.690259 -216.633727) (xy 61.698086 -216.652391)
			(xy 61.698632 -216.662508) (xy 61.698632 -217.071448) (xy 61.698218 -217.081601) (xy 61.690413 -217.100348)
			(xy 61.676015 -217.114669) (xy 61.657225 -217.122373) (xy 61.64707 -217.122756) (xy 60.24753 -217.122756)
			(xy 60.237405 -217.122249) (xy 60.218683 -217.11453) (xy 60.204326 -217.10025) (xy 60.196506 -217.081571)
			(xy 60.195968 -217.071448) (xy 54.154832 -217.071448) (xy 54.154418 -217.081601) (xy 54.146613 -217.100348)
			(xy 54.132215 -217.114669) (xy 54.113425 -217.122373) (xy 54.10327 -217.122756) (xy 52.70373 -217.122756)
			(xy 52.693605 -217.122249) (xy 52.674883 -217.11453) (xy 52.660526 -217.10025) (xy 52.652706 -217.081571)
			(xy 52.652168 -217.071448) (xy 46.611032 -217.071448) (xy 46.610618 -217.081601) (xy 46.602813 -217.100348)
			(xy 46.588415 -217.114669) (xy 46.569625 -217.122373) (xy 46.55947 -217.122756) (xy 45.15993 -217.122756)
			(xy 45.149805 -217.122249) (xy 45.131083 -217.11453) (xy 45.116726 -217.10025) (xy 45.108906 -217.081571)
			(xy 45.108368 -217.071448) (xy 39.067232 -217.071448) (xy 39.066818 -217.081601) (xy 39.059013 -217.100348)
			(xy 39.044615 -217.114669) (xy 39.025825 -217.122373) (xy 39.01567 -217.122756) (xy 37.61613 -217.122756)
			(xy 37.606005 -217.122249) (xy 37.587283 -217.11453) (xy 37.572926 -217.10025) (xy 37.565106 -217.081571)
			(xy 37.564568 -217.071448) (xy 31.523432 -217.071448) (xy 31.523018 -217.081601) (xy 31.515213 -217.100348)
			(xy 31.500815 -217.114669) (xy 31.482025 -217.122373) (xy 31.47187 -217.122756) (xy 30.07233 -217.122756)
			(xy 30.062205 -217.122249) (xy 30.043483 -217.11453) (xy 30.029126 -217.10025) (xy 30.021306 -217.081571)
			(xy 30.020768 -217.071448) (xy 23.979632 -217.071448) (xy 23.979218 -217.081601) (xy 23.971413 -217.100348)
			(xy 23.957015 -217.114669) (xy 23.938225 -217.122373) (xy 23.92807 -217.122756) (xy 22.52853 -217.122756)
			(xy 22.518405 -217.122249) (xy 22.499683 -217.11453) (xy 22.485326 -217.10025) (xy 22.477506 -217.081571)
			(xy 22.476968 -217.071448) (xy 16.435832 -217.071448) (xy 16.435418 -217.081601) (xy 16.427613 -217.100348)
			(xy 16.413215 -217.114669) (xy 16.394425 -217.122373) (xy 16.38427 -217.122756) (xy 14.98473 -217.122756)
			(xy 14.974605 -217.122249) (xy 14.955883 -217.11453) (xy 14.941526 -217.10025) (xy 14.933706 -217.081571)
			(xy 14.933168 -217.071448) (xy 8.892032 -217.071448) (xy 8.891618 -217.081601) (xy 8.883813 -217.100348)
			(xy 8.869415 -217.114669) (xy 8.850625 -217.122373) (xy 8.84047 -217.122756) (xy 7.44093 -217.122756)
			(xy 7.430805 -217.122249) (xy 7.412083 -217.11453) (xy 7.397726 -217.10025) (xy 7.389906 -217.081571)
			(xy 7.389368 -217.071448) (xy 2.509012 -217.071448) (xy 2.509012 -217.921332) (xy 11.489436 -217.921332)
			(xy 11.489436 -217.512392) (xy 11.489816 -217.502233) (xy 11.497621 -217.483473) (xy 11.512031 -217.469149)
			(xy 11.530837 -217.461456) (xy 11.540998 -217.461084) (xy 12.940538 -217.461084) (xy 12.950673 -217.461497)
			(xy 12.969403 -217.469245) (xy 12.983759 -217.483554) (xy 12.99157 -217.502259) (xy 12.9921 -217.512392)
			(xy 12.9921 -217.921332) (xy 19.033236 -217.921332) (xy 19.033236 -217.512392) (xy 19.033616 -217.502233)
			(xy 19.041421 -217.483473) (xy 19.055831 -217.469149) (xy 19.074637 -217.461456) (xy 19.084798 -217.461084)
			(xy 20.484338 -217.461084) (xy 20.494473 -217.461497) (xy 20.513203 -217.469245) (xy 20.527559 -217.483554)
			(xy 20.53537 -217.502259) (xy 20.5359 -217.512392) (xy 20.5359 -217.921332) (xy 26.577036 -217.921332)
			(xy 26.577036 -217.512392) (xy 26.577416 -217.502233) (xy 26.585221 -217.483473) (xy 26.599631 -217.469149)
			(xy 26.618437 -217.461456) (xy 26.628598 -217.461084) (xy 28.028138 -217.461084) (xy 28.038273 -217.461497)
			(xy 28.057003 -217.469245) (xy 28.071359 -217.483554) (xy 28.07917 -217.502259) (xy 28.0797 -217.512392)
			(xy 28.0797 -217.921332) (xy 34.120836 -217.921332) (xy 34.120836 -217.512392) (xy 34.121216 -217.502233)
			(xy 34.129021 -217.483473) (xy 34.143431 -217.469149) (xy 34.162237 -217.461456) (xy 34.172398 -217.461084)
			(xy 35.571938 -217.461084) (xy 35.582073 -217.461497) (xy 35.600803 -217.469245) (xy 35.615159 -217.483554)
			(xy 35.62297 -217.502259) (xy 35.6235 -217.512392) (xy 35.6235 -217.921332) (xy 41.664636 -217.921332)
			(xy 41.664636 -217.512392) (xy 41.665016 -217.502233) (xy 41.672821 -217.483473) (xy 41.687231 -217.469149)
			(xy 41.706037 -217.461456) (xy 41.716198 -217.461084) (xy 43.115738 -217.461084) (xy 43.125873 -217.461497)
			(xy 43.144603 -217.469245) (xy 43.158959 -217.483554) (xy 43.16677 -217.502259) (xy 43.1673 -217.512392)
			(xy 43.1673 -217.921332) (xy 49.208436 -217.921332) (xy 49.208436 -217.512392) (xy 49.208816 -217.502233)
			(xy 49.216621 -217.483473) (xy 49.231031 -217.469149) (xy 49.249837 -217.461456) (xy 49.259998 -217.461084)
			(xy 50.659538 -217.461084) (xy 50.669673 -217.461497) (xy 50.688403 -217.469245) (xy 50.702759 -217.483554)
			(xy 50.71057 -217.502259) (xy 50.7111 -217.512392) (xy 50.7111 -217.921332) (xy 56.752236 -217.921332)
			(xy 56.752236 -217.512392) (xy 56.752616 -217.502233) (xy 56.760421 -217.483473) (xy 56.774831 -217.469149)
			(xy 56.793637 -217.461456) (xy 56.803798 -217.461084) (xy 58.203338 -217.461084) (xy 58.213473 -217.461497)
			(xy 58.232203 -217.469245) (xy 58.246559 -217.483554) (xy 58.25437 -217.502259) (xy 58.2549 -217.512392)
			(xy 58.2549 -217.921332) (xy 64.296036 -217.921332) (xy 64.296036 -217.512392) (xy 64.296416 -217.502233)
			(xy 64.304221 -217.483473) (xy 64.318631 -217.469149) (xy 64.337437 -217.461456) (xy 64.347598 -217.461084)
			(xy 65.747138 -217.461084) (xy 65.757273 -217.461497) (xy 65.776003 -217.469245) (xy 65.790359 -217.483554)
			(xy 65.79817 -217.502259) (xy 65.7987 -217.512392) (xy 65.7987 -217.878406) (xy 88.755728 -217.878406)
			(xy 88.756236 -217.852519) (xy 88.764335 -217.801381) (xy 88.780334 -217.752141) (xy 88.80384 -217.706009)
			(xy 88.834272 -217.664122) (xy 88.870882 -217.627512) (xy 88.912769 -217.59708) (xy 88.958901 -217.573574)
			(xy 89.008141 -217.557575) (xy 89.059279 -217.549476) (xy 89.111053 -217.549476) (xy 89.162191 -217.557575)
			(xy 89.211431 -217.573574) (xy 89.257563 -217.59708) (xy 89.29945 -217.627512) (xy 89.33606 -217.664122)
			(xy 89.366492 -217.706009) (xy 89.389998 -217.752141) (xy 89.405997 -217.801381) (xy 89.414096 -217.852519)
			(xy 89.414604 -217.878406) (xy 89.695528 -217.878406) (xy 89.695994 -217.853071) (xy 89.703746 -217.802996)
			(xy 89.719069 -217.754698) (xy 89.741602 -217.709313) (xy 89.770814 -217.66791) (xy 89.806017 -217.631464)
			(xy 89.846382 -217.600835) (xy 89.890959 -217.576742) (xy 89.938697 -217.559754) (xy 89.963498 -217.554556)
			(xy 89.986358 -217.550238) (xy 90.191336 -217.195146) (xy 90.183462 -217.173302) (xy 90.174824 -217.146891)
			(xy 90.165499 -217.092117) (xy 90.16492 -217.064336) (xy 90.165428 -217.038429) (xy 90.173534 -216.987252)
			(xy 90.189546 -216.937973) (xy 90.213069 -216.891806) (xy 90.243525 -216.849887) (xy 90.280163 -216.813249)
			(xy 90.322082 -216.782793) (xy 90.368249 -216.75927) (xy 90.417528 -216.743258) (xy 90.468705 -216.735152)
			(xy 90.520519 -216.735152) (xy 90.571696 -216.743258) (xy 90.620975 -216.75927) (xy 90.667142 -216.782793)
			(xy 90.709061 -216.813249) (xy 90.745699 -216.849887) (xy 90.776155 -216.891806) (xy 90.799678 -216.937973)
			(xy 90.81569 -216.987252) (xy 90.823796 -217.038429) (xy 90.824304 -217.064336) (xy 90.823812 -217.08968)
			(xy 90.816035 -217.13977) (xy 90.800686 -217.188079) (xy 90.778125 -217.233471) (xy 90.748884 -217.274876)
			(xy 90.713652 -217.311319) (xy 90.673259 -217.341943) (xy 90.628655 -217.366024) (xy 90.580892 -217.382998)
			(xy 90.55608 -217.388186) (xy 90.53322 -217.392504) (xy 90.328242 -217.747596) (xy 90.336116 -217.76944)
			(xy 90.344706 -217.795856) (xy 90.353895 -217.850633) (xy 90.354404 -217.878406) (xy 90.635328 -217.878406)
			(xy 90.635836 -217.852519) (xy 90.643935 -217.801381) (xy 90.659934 -217.752141) (xy 90.68344 -217.706009)
			(xy 90.713872 -217.664122) (xy 90.750482 -217.627512) (xy 90.792369 -217.59708) (xy 90.838501 -217.573574)
			(xy 90.887741 -217.557575) (xy 90.938879 -217.549476) (xy 90.990653 -217.549476) (xy 91.041791 -217.557575)
			(xy 91.091031 -217.573574) (xy 91.137163 -217.59708) (xy 91.17905 -217.627512) (xy 91.21566 -217.664122)
			(xy 91.246092 -217.706009) (xy 91.269598 -217.752141) (xy 91.285597 -217.801381) (xy 91.293696 -217.852519)
			(xy 91.294204 -217.878406) (xy 91.575128 -217.878406) (xy 91.575594 -217.853071) (xy 91.583346 -217.802996)
			(xy 91.598669 -217.754698) (xy 91.621202 -217.709313) (xy 91.650414 -217.66791) (xy 91.685617 -217.631464)
			(xy 91.725982 -217.600835) (xy 91.770559 -217.576742) (xy 91.818297 -217.559754) (xy 91.843098 -217.554556)
			(xy 91.865958 -217.550238) (xy 92.070936 -217.195146) (xy 92.063062 -217.173302) (xy 92.054424 -217.146891)
			(xy 92.045099 -217.092117) (xy 92.04452 -217.064336) (xy 92.045028 -217.038429) (xy 92.053134 -216.987252)
			(xy 92.069146 -216.937973) (xy 92.092669 -216.891806) (xy 92.123125 -216.849887) (xy 92.159763 -216.813249)
			(xy 92.201682 -216.782793) (xy 92.247849 -216.75927) (xy 92.297128 -216.743258) (xy 92.348305 -216.735152)
			(xy 92.400119 -216.735152) (xy 92.451296 -216.743258) (xy 92.500575 -216.75927) (xy 92.546742 -216.782793)
			(xy 92.588661 -216.813249) (xy 92.625299 -216.849887) (xy 92.655755 -216.891806) (xy 92.679278 -216.937973)
			(xy 92.69529 -216.987252) (xy 92.703396 -217.038429) (xy 92.703904 -217.064336) (xy 92.703412 -217.08968)
			(xy 92.695635 -217.13977) (xy 92.680286 -217.188079) (xy 92.657725 -217.233471) (xy 92.628484 -217.274876)
			(xy 92.593252 -217.311319) (xy 92.552859 -217.341943) (xy 92.508255 -217.366024) (xy 92.460492 -217.382998)
			(xy 92.43568 -217.388186) (xy 92.41282 -217.392504) (xy 92.207842 -217.747596) (xy 92.215716 -217.76944)
			(xy 92.224306 -217.795856) (xy 92.233495 -217.850633) (xy 92.234004 -217.878406) (xy 92.514928 -217.878406)
			(xy 92.515436 -217.852519) (xy 92.523535 -217.801381) (xy 92.539534 -217.752141) (xy 92.56304 -217.706009)
			(xy 92.593472 -217.664122) (xy 92.630082 -217.627512) (xy 92.671969 -217.59708) (xy 92.718101 -217.573574)
			(xy 92.767341 -217.557575) (xy 92.818479 -217.549476) (xy 92.870253 -217.549476) (xy 92.921391 -217.557575)
			(xy 92.970631 -217.573574) (xy 93.016763 -217.59708) (xy 93.05865 -217.627512) (xy 93.09526 -217.664122)
			(xy 93.125692 -217.706009) (xy 93.149198 -217.752141) (xy 93.165197 -217.801381) (xy 93.173296 -217.852519)
			(xy 93.173804 -217.878406) (xy 93.454728 -217.878406) (xy 93.455194 -217.853071) (xy 93.462946 -217.802996)
			(xy 93.478269 -217.754698) (xy 93.500802 -217.709313) (xy 93.530014 -217.66791) (xy 93.565217 -217.631464)
			(xy 93.605582 -217.600835) (xy 93.650159 -217.576742) (xy 93.697897 -217.559754) (xy 93.722698 -217.554556)
			(xy 93.745558 -217.550238) (xy 93.950536 -217.195146) (xy 93.942662 -217.173302) (xy 93.934024 -217.146891)
			(xy 93.924699 -217.092117) (xy 93.92412 -217.064336) (xy 93.924628 -217.038429) (xy 93.932734 -216.987252)
			(xy 93.948746 -216.937973) (xy 93.972269 -216.891806) (xy 94.002725 -216.849887) (xy 94.039363 -216.813249)
			(xy 94.081282 -216.782793) (xy 94.127449 -216.75927) (xy 94.176728 -216.743258) (xy 94.227905 -216.735152)
			(xy 94.279719 -216.735152) (xy 94.330896 -216.743258) (xy 94.380175 -216.75927) (xy 94.426342 -216.782793)
			(xy 94.468261 -216.813249) (xy 94.504899 -216.849887) (xy 94.535355 -216.891806) (xy 94.558878 -216.937973)
			(xy 94.57489 -216.987252) (xy 94.582996 -217.038429) (xy 94.583504 -217.064336) (xy 94.583012 -217.08968)
			(xy 94.575235 -217.13977) (xy 94.559886 -217.188079) (xy 94.537325 -217.233471) (xy 94.508084 -217.274876)
			(xy 94.472852 -217.311319) (xy 94.432459 -217.341943) (xy 94.387855 -217.366024) (xy 94.340092 -217.382998)
			(xy 94.31528 -217.388186) (xy 94.29242 -217.392504) (xy 94.087442 -217.747596) (xy 94.095316 -217.76944)
			(xy 94.103906 -217.795856) (xy 94.113095 -217.850633) (xy 94.113604 -217.878406) (xy 94.394528 -217.878406)
			(xy 94.395036 -217.852519) (xy 94.403135 -217.801381) (xy 94.419134 -217.752141) (xy 94.44264 -217.706009)
			(xy 94.473072 -217.664122) (xy 94.509682 -217.627512) (xy 94.551569 -217.59708) (xy 94.597701 -217.573574)
			(xy 94.646941 -217.557575) (xy 94.698079 -217.549476) (xy 94.749853 -217.549476) (xy 94.800991 -217.557575)
			(xy 94.850231 -217.573574) (xy 94.896363 -217.59708) (xy 94.93825 -217.627512) (xy 94.97486 -217.664122)
			(xy 95.005292 -217.706009) (xy 95.028798 -217.752141) (xy 95.044797 -217.801381) (xy 95.052896 -217.852519)
			(xy 95.053404 -217.878406) (xy 95.334328 -217.878406) (xy 95.334794 -217.853071) (xy 95.342546 -217.802996)
			(xy 95.357869 -217.754698) (xy 95.380402 -217.709313) (xy 95.409614 -217.66791) (xy 95.444817 -217.631464)
			(xy 95.485182 -217.600835) (xy 95.529759 -217.576742) (xy 95.577497 -217.559754) (xy 95.602298 -217.554556)
			(xy 95.625158 -217.550238) (xy 95.830136 -217.195146) (xy 95.822262 -217.173302) (xy 95.813624 -217.146891)
			(xy 95.804299 -217.092117) (xy 95.80372 -217.064336) (xy 95.804228 -217.038429) (xy 95.812334 -216.987252)
			(xy 95.828346 -216.937973) (xy 95.851869 -216.891806) (xy 95.882325 -216.849887) (xy 95.918963 -216.813249)
			(xy 95.960882 -216.782793) (xy 96.007049 -216.75927) (xy 96.056328 -216.743258) (xy 96.107505 -216.735152)
			(xy 96.159319 -216.735152) (xy 96.210496 -216.743258) (xy 96.259775 -216.75927) (xy 96.305942 -216.782793)
			(xy 96.347861 -216.813249) (xy 96.384499 -216.849887) (xy 96.414955 -216.891806) (xy 96.438478 -216.937973)
			(xy 96.45449 -216.987252) (xy 96.462596 -217.038429) (xy 96.463104 -217.064336) (xy 96.462612 -217.08968)
			(xy 96.454835 -217.13977) (xy 96.439486 -217.188079) (xy 96.416925 -217.233471) (xy 96.387684 -217.274876)
			(xy 96.352452 -217.311319) (xy 96.312059 -217.341943) (xy 96.267455 -217.366024) (xy 96.219692 -217.382998)
			(xy 96.19488 -217.388186) (xy 96.17202 -217.392504) (xy 95.967042 -217.747596) (xy 95.974916 -217.76944)
			(xy 95.983506 -217.795856) (xy 95.992695 -217.850633) (xy 95.993204 -217.878406) (xy 96.274128 -217.878406)
			(xy 96.274636 -217.852519) (xy 96.282735 -217.801381) (xy 96.298734 -217.752141) (xy 96.32224 -217.706009)
			(xy 96.352672 -217.664122) (xy 96.389282 -217.627512) (xy 96.431169 -217.59708) (xy 96.477301 -217.573574)
			(xy 96.526541 -217.557575) (xy 96.577679 -217.549476) (xy 96.629453 -217.549476) (xy 96.680591 -217.557575)
			(xy 96.729831 -217.573574) (xy 96.775963 -217.59708) (xy 96.81785 -217.627512) (xy 96.85446 -217.664122)
			(xy 96.884892 -217.706009) (xy 96.908398 -217.752141) (xy 96.924397 -217.801381) (xy 96.932496 -217.852519)
			(xy 96.933004 -217.878406) (xy 97.213928 -217.878406) (xy 97.214394 -217.853071) (xy 97.222146 -217.802996)
			(xy 97.237469 -217.754698) (xy 97.260002 -217.709313) (xy 97.289214 -217.66791) (xy 97.324417 -217.631464)
			(xy 97.364782 -217.600835) (xy 97.409359 -217.576742) (xy 97.457097 -217.559754) (xy 97.481898 -217.554556)
			(xy 97.504758 -217.550238) (xy 97.709736 -217.195146) (xy 97.701862 -217.173302) (xy 97.693224 -217.146891)
			(xy 97.683899 -217.092117) (xy 97.68332 -217.064336) (xy 97.683828 -217.038429) (xy 97.691934 -216.987252)
			(xy 97.707946 -216.937973) (xy 97.731469 -216.891806) (xy 97.761925 -216.849887) (xy 97.798563 -216.813249)
			(xy 97.840482 -216.782793) (xy 97.886649 -216.75927) (xy 97.935928 -216.743258) (xy 97.987105 -216.735152)
			(xy 98.038919 -216.735152) (xy 98.090096 -216.743258) (xy 98.139375 -216.75927) (xy 98.185542 -216.782793)
			(xy 98.227461 -216.813249) (xy 98.264099 -216.849887) (xy 98.294555 -216.891806) (xy 98.318078 -216.937973)
			(xy 98.33409 -216.987252) (xy 98.342196 -217.038429) (xy 98.342704 -217.064336) (xy 98.342212 -217.08968)
			(xy 98.334435 -217.13977) (xy 98.319086 -217.188079) (xy 98.296525 -217.233471) (xy 98.267284 -217.274876)
			(xy 98.232052 -217.311319) (xy 98.191659 -217.341943) (xy 98.147055 -217.366024) (xy 98.099292 -217.382998)
			(xy 98.07448 -217.388186) (xy 98.05162 -217.392504) (xy 97.846642 -217.747596) (xy 97.854516 -217.76944)
			(xy 97.863106 -217.795856) (xy 97.872295 -217.850633) (xy 97.872804 -217.878406) (xy 98.153728 -217.878406)
			(xy 98.154236 -217.852519) (xy 98.162335 -217.801381) (xy 98.178334 -217.752141) (xy 98.20184 -217.706009)
			(xy 98.232272 -217.664122) (xy 98.268882 -217.627512) (xy 98.310769 -217.59708) (xy 98.356901 -217.573574)
			(xy 98.406141 -217.557575) (xy 98.457279 -217.549476) (xy 98.509053 -217.549476) (xy 98.560191 -217.557575)
			(xy 98.609431 -217.573574) (xy 98.655563 -217.59708) (xy 98.69745 -217.627512) (xy 98.73406 -217.664122)
			(xy 98.764492 -217.706009) (xy 98.787998 -217.752141) (xy 98.803997 -217.801381) (xy 98.812096 -217.852519)
			(xy 98.812604 -217.878406) (xy 99.093528 -217.878406) (xy 99.093994 -217.853071) (xy 99.101746 -217.802996)
			(xy 99.117069 -217.754698) (xy 99.139602 -217.709313) (xy 99.168814 -217.66791) (xy 99.204017 -217.631464)
			(xy 99.244382 -217.600835) (xy 99.288959 -217.576742) (xy 99.336697 -217.559754) (xy 99.361498 -217.554556)
			(xy 99.384358 -217.550238) (xy 99.589336 -217.195146) (xy 99.581462 -217.173302) (xy 99.572824 -217.146891)
			(xy 99.563499 -217.092117) (xy 99.56292 -217.064336) (xy 99.563428 -217.038429) (xy 99.571534 -216.987252)
			(xy 99.587546 -216.937973) (xy 99.611069 -216.891806) (xy 99.641525 -216.849887) (xy 99.678163 -216.813249)
			(xy 99.720082 -216.782793) (xy 99.766249 -216.75927) (xy 99.815528 -216.743258) (xy 99.866705 -216.735152)
			(xy 99.918519 -216.735152) (xy 99.969696 -216.743258) (xy 100.018975 -216.75927) (xy 100.065142 -216.782793)
			(xy 100.107061 -216.813249) (xy 100.143699 -216.849887) (xy 100.174155 -216.891806) (xy 100.197678 -216.937973)
			(xy 100.21369 -216.987252) (xy 100.221796 -217.038429) (xy 100.222304 -217.064336) (xy 100.221812 -217.08968)
			(xy 100.214035 -217.13977) (xy 100.198686 -217.188079) (xy 100.176125 -217.233471) (xy 100.146884 -217.274876)
			(xy 100.111652 -217.311319) (xy 100.071259 -217.341943) (xy 100.026655 -217.366024) (xy 99.978892 -217.382998)
			(xy 99.95408 -217.388186) (xy 99.93122 -217.392504) (xy 99.726242 -217.747596) (xy 99.734116 -217.76944)
			(xy 99.742706 -217.795856) (xy 99.751895 -217.850633) (xy 99.752404 -217.878406) (xy 100.033328 -217.878406)
			(xy 100.033836 -217.852519) (xy 100.041935 -217.801381) (xy 100.057934 -217.752141) (xy 100.08144 -217.706009)
			(xy 100.111872 -217.664122) (xy 100.148482 -217.627512) (xy 100.190369 -217.59708) (xy 100.236501 -217.573574)
			(xy 100.285741 -217.557575) (xy 100.336879 -217.549476) (xy 100.388653 -217.549476) (xy 100.439791 -217.557575)
			(xy 100.489031 -217.573574) (xy 100.535163 -217.59708) (xy 100.57705 -217.627512) (xy 100.61366 -217.664122)
			(xy 100.644092 -217.706009) (xy 100.667598 -217.752141) (xy 100.683597 -217.801381) (xy 100.691696 -217.852519)
			(xy 100.692204 -217.878406) (xy 100.973128 -217.878406) (xy 100.973594 -217.853071) (xy 100.981346 -217.802996)
			(xy 100.996669 -217.754698) (xy 101.019202 -217.709313) (xy 101.048414 -217.66791) (xy 101.083617 -217.631464)
			(xy 101.123982 -217.600835) (xy 101.168559 -217.576742) (xy 101.216297 -217.559754) (xy 101.241098 -217.554556)
			(xy 101.263958 -217.550238) (xy 101.468936 -217.195146) (xy 101.461062 -217.173302) (xy 101.452424 -217.146891)
			(xy 101.443099 -217.092117) (xy 101.44252 -217.064336) (xy 101.443028 -217.038429) (xy 101.451134 -216.987252)
			(xy 101.467146 -216.937973) (xy 101.490669 -216.891806) (xy 101.521125 -216.849887) (xy 101.557763 -216.813249)
			(xy 101.599682 -216.782793) (xy 101.645849 -216.75927) (xy 101.695128 -216.743258) (xy 101.746305 -216.735152)
			(xy 101.798119 -216.735152) (xy 101.849296 -216.743258) (xy 101.898575 -216.75927) (xy 101.944742 -216.782793)
			(xy 101.986661 -216.813249) (xy 102.023299 -216.849887) (xy 102.053755 -216.891806) (xy 102.077278 -216.937973)
			(xy 102.09329 -216.987252) (xy 102.101396 -217.038429) (xy 102.101904 -217.064336) (xy 102.101412 -217.08968)
			(xy 102.093635 -217.13977) (xy 102.078286 -217.188079) (xy 102.055725 -217.233471) (xy 102.026484 -217.274876)
			(xy 101.991252 -217.311319) (xy 101.950859 -217.341943) (xy 101.906255 -217.366024) (xy 101.858492 -217.382998)
			(xy 101.83368 -217.388186) (xy 101.81082 -217.392504) (xy 101.605842 -217.747596) (xy 101.613716 -217.76944)
			(xy 101.622306 -217.795856) (xy 101.631495 -217.850633) (xy 101.632004 -217.878406) (xy 101.912928 -217.878406)
			(xy 101.913436 -217.852519) (xy 101.921535 -217.801381) (xy 101.937534 -217.752141) (xy 101.96104 -217.706009)
			(xy 101.991472 -217.664122) (xy 102.028082 -217.627512) (xy 102.069969 -217.59708) (xy 102.116101 -217.573574)
			(xy 102.165341 -217.557575) (xy 102.216479 -217.549476) (xy 102.268253 -217.549476) (xy 102.319391 -217.557575)
			(xy 102.368631 -217.573574) (xy 102.414763 -217.59708) (xy 102.45665 -217.627512) (xy 102.49326 -217.664122)
			(xy 102.523692 -217.706009) (xy 102.547198 -217.752141) (xy 102.563197 -217.801381) (xy 102.571296 -217.852519)
			(xy 102.571804 -217.878406) (xy 102.852728 -217.878406) (xy 102.853194 -217.853071) (xy 102.860946 -217.802996)
			(xy 102.876269 -217.754698) (xy 102.898802 -217.709313) (xy 102.928014 -217.66791) (xy 102.963217 -217.631464)
			(xy 103.003582 -217.600835) (xy 103.048159 -217.576742) (xy 103.095897 -217.559754) (xy 103.120698 -217.554556)
			(xy 103.143558 -217.550238) (xy 103.348536 -217.195146) (xy 103.340662 -217.173302) (xy 103.332024 -217.146891)
			(xy 103.322699 -217.092117) (xy 103.32212 -217.064336) (xy 103.322628 -217.038429) (xy 103.330734 -216.987252)
			(xy 103.346746 -216.937973) (xy 103.370269 -216.891806) (xy 103.400725 -216.849887) (xy 103.437363 -216.813249)
			(xy 103.479282 -216.782793) (xy 103.525449 -216.75927) (xy 103.574728 -216.743258) (xy 103.625905 -216.735152)
			(xy 103.677719 -216.735152) (xy 103.728896 -216.743258) (xy 103.778175 -216.75927) (xy 103.824342 -216.782793)
			(xy 103.866261 -216.813249) (xy 103.902899 -216.849887) (xy 103.933355 -216.891806) (xy 103.956878 -216.937973)
			(xy 103.97289 -216.987252) (xy 103.980996 -217.038429) (xy 103.981504 -217.064336) (xy 103.981012 -217.08968)
			(xy 103.973235 -217.13977) (xy 103.957886 -217.188079) (xy 103.935325 -217.233471) (xy 103.906084 -217.274876)
			(xy 103.870852 -217.311319) (xy 103.830459 -217.341943) (xy 103.785855 -217.366024) (xy 103.738092 -217.382998)
			(xy 103.71328 -217.388186) (xy 103.69042 -217.392504) (xy 103.485442 -217.747596) (xy 103.493316 -217.76944)
			(xy 103.501906 -217.795856) (xy 103.511095 -217.850633) (xy 103.511604 -217.878406) (xy 103.792528 -217.878406)
			(xy 103.793036 -217.852519) (xy 103.801135 -217.801381) (xy 103.817134 -217.752141) (xy 103.84064 -217.706009)
			(xy 103.871072 -217.664122) (xy 103.907682 -217.627512) (xy 103.949569 -217.59708) (xy 103.995701 -217.573574)
			(xy 104.044941 -217.557575) (xy 104.096079 -217.549476) (xy 104.147853 -217.549476) (xy 104.198991 -217.557575)
			(xy 104.248231 -217.573574) (xy 104.294363 -217.59708) (xy 104.33625 -217.627512) (xy 104.37286 -217.664122)
			(xy 104.403292 -217.706009) (xy 104.426798 -217.752141) (xy 104.442797 -217.801381) (xy 104.450896 -217.852519)
			(xy 104.451404 -217.878406) (xy 104.732328 -217.878406) (xy 104.732794 -217.853071) (xy 104.740546 -217.802996)
			(xy 104.755869 -217.754698) (xy 104.778402 -217.709313) (xy 104.807614 -217.66791) (xy 104.842817 -217.631464)
			(xy 104.883182 -217.600835) (xy 104.927759 -217.576742) (xy 104.975497 -217.559754) (xy 105.000298 -217.554556)
			(xy 105.023158 -217.550238) (xy 105.228136 -217.195146) (xy 105.220262 -217.173302) (xy 105.211624 -217.146891)
			(xy 105.202299 -217.092117) (xy 105.20172 -217.064336) (xy 105.202228 -217.038429) (xy 105.210334 -216.987252)
			(xy 105.226346 -216.937973) (xy 105.249869 -216.891806) (xy 105.280325 -216.849887) (xy 105.316963 -216.813249)
			(xy 105.358882 -216.782793) (xy 105.405049 -216.75927) (xy 105.454328 -216.743258) (xy 105.505505 -216.735152)
			(xy 105.557319 -216.735152) (xy 105.608496 -216.743258) (xy 105.657775 -216.75927) (xy 105.703942 -216.782793)
			(xy 105.745861 -216.813249) (xy 105.782499 -216.849887) (xy 105.812955 -216.891806) (xy 105.836478 -216.937973)
			(xy 105.85249 -216.987252) (xy 105.860596 -217.038429) (xy 105.861104 -217.064336) (xy 105.860612 -217.08968)
			(xy 105.852835 -217.13977) (xy 105.837486 -217.188079) (xy 105.814925 -217.233471) (xy 105.785684 -217.274876)
			(xy 105.750452 -217.311319) (xy 105.710059 -217.341943) (xy 105.665455 -217.366024) (xy 105.617692 -217.382998)
			(xy 105.59288 -217.388186) (xy 105.57002 -217.392504) (xy 105.365042 -217.747596) (xy 105.372916 -217.76944)
			(xy 105.381506 -217.795856) (xy 105.390695 -217.850633) (xy 105.391204 -217.878406) (xy 105.672128 -217.878406)
			(xy 105.672636 -217.852519) (xy 105.680735 -217.801381) (xy 105.696734 -217.752141) (xy 105.72024 -217.706009)
			(xy 105.750672 -217.664122) (xy 105.787282 -217.627512) (xy 105.829169 -217.59708) (xy 105.875301 -217.573574)
			(xy 105.924541 -217.557575) (xy 105.975679 -217.549476) (xy 106.027453 -217.549476) (xy 106.078591 -217.557575)
			(xy 106.127831 -217.573574) (xy 106.173963 -217.59708) (xy 106.21585 -217.627512) (xy 106.25246 -217.664122)
			(xy 106.282892 -217.706009) (xy 106.306398 -217.752141) (xy 106.322397 -217.801381) (xy 106.330496 -217.852519)
			(xy 106.331004 -217.878406) (xy 106.611928 -217.878406) (xy 106.612394 -217.853071) (xy 106.620146 -217.802996)
			(xy 106.635469 -217.754698) (xy 106.658002 -217.709313) (xy 106.687214 -217.66791) (xy 106.722417 -217.631464)
			(xy 106.762782 -217.600835) (xy 106.807359 -217.576742) (xy 106.855097 -217.559754) (xy 106.879898 -217.554556)
			(xy 106.902758 -217.550238) (xy 107.107736 -217.195146) (xy 107.099862 -217.173302) (xy 107.091224 -217.146891)
			(xy 107.081899 -217.092117) (xy 107.08132 -217.064336) (xy 107.081828 -217.038429) (xy 107.089934 -216.987252)
			(xy 107.105946 -216.937973) (xy 107.129469 -216.891806) (xy 107.159925 -216.849887) (xy 107.196563 -216.813249)
			(xy 107.238482 -216.782793) (xy 107.284649 -216.75927) (xy 107.333928 -216.743258) (xy 107.385105 -216.735152)
			(xy 107.436919 -216.735152) (xy 107.488096 -216.743258) (xy 107.537375 -216.75927) (xy 107.583542 -216.782793)
			(xy 107.625461 -216.813249) (xy 107.662099 -216.849887) (xy 107.692555 -216.891806) (xy 107.716078 -216.937973)
			(xy 107.73209 -216.987252) (xy 107.740196 -217.038429) (xy 107.740704 -217.064336) (xy 107.740212 -217.08968)
			(xy 107.732435 -217.13977) (xy 107.717086 -217.188079) (xy 107.694525 -217.233471) (xy 107.665284 -217.274876)
			(xy 107.630052 -217.311319) (xy 107.589659 -217.341943) (xy 107.545055 -217.366024) (xy 107.497292 -217.382998)
			(xy 107.47248 -217.388186) (xy 107.44962 -217.392504) (xy 107.244642 -217.747596) (xy 107.252516 -217.76944)
			(xy 107.261106 -217.795856) (xy 107.270295 -217.850633) (xy 107.270804 -217.878406) (xy 107.551728 -217.878406)
			(xy 107.552236 -217.852519) (xy 107.560335 -217.801381) (xy 107.576334 -217.752141) (xy 107.59984 -217.706009)
			(xy 107.630272 -217.664122) (xy 107.666882 -217.627512) (xy 107.708769 -217.59708) (xy 107.754901 -217.573574)
			(xy 107.804141 -217.557575) (xy 107.855279 -217.549476) (xy 107.907053 -217.549476) (xy 107.958191 -217.557575)
			(xy 108.007431 -217.573574) (xy 108.053563 -217.59708) (xy 108.09545 -217.627512) (xy 108.13206 -217.664122)
			(xy 108.162492 -217.706009) (xy 108.185998 -217.752141) (xy 108.201997 -217.801381) (xy 108.210096 -217.852519)
			(xy 108.210604 -217.878406) (xy 108.491528 -217.878406) (xy 108.491994 -217.853071) (xy 108.499746 -217.802996)
			(xy 108.515069 -217.754698) (xy 108.537602 -217.709313) (xy 108.566814 -217.66791) (xy 108.602017 -217.631464)
			(xy 108.642382 -217.600835) (xy 108.686959 -217.576742) (xy 108.734697 -217.559754) (xy 108.759498 -217.554556)
			(xy 108.782358 -217.550238) (xy 108.987336 -217.195146) (xy 108.979462 -217.173302) (xy 108.970824 -217.146891)
			(xy 108.961499 -217.092117) (xy 108.96092 -217.064336) (xy 108.961428 -217.038429) (xy 108.969534 -216.987252)
			(xy 108.985546 -216.937973) (xy 109.009069 -216.891806) (xy 109.039525 -216.849887) (xy 109.076163 -216.813249)
			(xy 109.118082 -216.782793) (xy 109.164249 -216.75927) (xy 109.213528 -216.743258) (xy 109.264705 -216.735152)
			(xy 109.316519 -216.735152) (xy 109.367696 -216.743258) (xy 109.416975 -216.75927) (xy 109.463142 -216.782793)
			(xy 109.505061 -216.813249) (xy 109.541699 -216.849887) (xy 109.572155 -216.891806) (xy 109.595678 -216.937973)
			(xy 109.61169 -216.987252) (xy 109.619796 -217.038429) (xy 109.620304 -217.064336) (xy 109.619812 -217.08968)
			(xy 109.612035 -217.13977) (xy 109.596686 -217.188079) (xy 109.574125 -217.233471) (xy 109.544884 -217.274876)
			(xy 109.509652 -217.311319) (xy 109.469259 -217.341943) (xy 109.424655 -217.366024) (xy 109.376892 -217.382998)
			(xy 109.35208 -217.388186) (xy 109.32922 -217.392504) (xy 109.124242 -217.747596) (xy 109.132116 -217.76944)
			(xy 109.140706 -217.795856) (xy 109.149895 -217.850633) (xy 109.150404 -217.878406) (xy 109.431328 -217.878406)
			(xy 109.431836 -217.852519) (xy 109.439935 -217.801381) (xy 109.455934 -217.752141) (xy 109.47944 -217.706009)
			(xy 109.509872 -217.664122) (xy 109.546482 -217.627512) (xy 109.588369 -217.59708) (xy 109.634501 -217.573574)
			(xy 109.683741 -217.557575) (xy 109.734879 -217.549476) (xy 109.786653 -217.549476) (xy 109.837791 -217.557575)
			(xy 109.887031 -217.573574) (xy 109.933163 -217.59708) (xy 109.97505 -217.627512) (xy 110.01166 -217.664122)
			(xy 110.042092 -217.706009) (xy 110.065598 -217.752141) (xy 110.081597 -217.801381) (xy 110.089696 -217.852519)
			(xy 110.090204 -217.878406) (xy 110.371128 -217.878406) (xy 110.371594 -217.853071) (xy 110.379346 -217.802996)
			(xy 110.394669 -217.754698) (xy 110.417202 -217.709313) (xy 110.446414 -217.66791) (xy 110.481617 -217.631464)
			(xy 110.521982 -217.600835) (xy 110.566559 -217.576742) (xy 110.614297 -217.559754) (xy 110.639098 -217.554556)
			(xy 110.661958 -217.550238) (xy 110.866936 -217.194892) (xy 110.859316 -217.173048) (xy 110.850741 -217.146694)
			(xy 110.841552 -217.092045) (xy 110.841028 -217.064336) (xy 110.841536 -217.038449) (xy 110.849635 -216.987311)
			(xy 110.865634 -216.938071) (xy 110.88914 -216.891939) (xy 110.919572 -216.850052) (xy 110.956182 -216.813442)
			(xy 110.998069 -216.78301) (xy 111.044201 -216.759504) (xy 111.093441 -216.743505) (xy 111.144579 -216.735406)
			(xy 111.196353 -216.735406) (xy 111.247491 -216.743505) (xy 111.296731 -216.759504) (xy 111.342863 -216.78301)
			(xy 111.38475 -216.813442) (xy 111.42136 -216.850052) (xy 111.451792 -216.891939) (xy 111.475298 -216.938071)
			(xy 111.491297 -216.987311) (xy 111.499396 -217.038449) (xy 111.499904 -217.064336) (xy 112.72012 -217.064336)
			(xy 112.720628 -217.038429) (xy 112.728734 -216.987252) (xy 112.744746 -216.937973) (xy 112.768269 -216.891806)
			(xy 112.798725 -216.849887) (xy 112.835363 -216.813249) (xy 112.877282 -216.782793) (xy 112.923449 -216.75927)
			(xy 112.972728 -216.743258) (xy 113.023905 -216.735152) (xy 113.075719 -216.735152) (xy 113.126896 -216.743258)
			(xy 113.176175 -216.75927) (xy 113.222342 -216.782793) (xy 113.264261 -216.813249) (xy 113.300899 -216.849887)
			(xy 113.331355 -216.891806) (xy 113.354878 -216.937973) (xy 113.37089 -216.987252) (xy 113.378996 -217.038429)
			(xy 113.379504 -217.064336) (xy 114.59972 -217.064336) (xy 114.600228 -217.038429) (xy 114.608334 -216.987252)
			(xy 114.624346 -216.937973) (xy 114.647869 -216.891806) (xy 114.678325 -216.849887) (xy 114.714963 -216.813249)
			(xy 114.756882 -216.782793) (xy 114.803049 -216.75927) (xy 114.852328 -216.743258) (xy 114.903505 -216.735152)
			(xy 114.955319 -216.735152) (xy 115.006496 -216.743258) (xy 115.055775 -216.75927) (xy 115.101942 -216.782793)
			(xy 115.143861 -216.813249) (xy 115.180499 -216.849887) (xy 115.210955 -216.891806) (xy 115.234478 -216.937973)
			(xy 115.25049 -216.987252) (xy 115.258596 -217.038429) (xy 115.259104 -217.064336) (xy 116.47932 -217.064336)
			(xy 116.479828 -217.038429) (xy 116.487934 -216.987252) (xy 116.503946 -216.937973) (xy 116.527469 -216.891806)
			(xy 116.557925 -216.849887) (xy 116.594563 -216.813249) (xy 116.636482 -216.782793) (xy 116.682649 -216.75927)
			(xy 116.731928 -216.743258) (xy 116.783105 -216.735152) (xy 116.834919 -216.735152) (xy 116.886096 -216.743258)
			(xy 116.935375 -216.75927) (xy 116.981542 -216.782793) (xy 117.023461 -216.813249) (xy 117.060099 -216.849887)
			(xy 117.090555 -216.891806) (xy 117.114078 -216.937973) (xy 117.13009 -216.987252) (xy 117.138196 -217.038429)
			(xy 117.138704 -217.064336) (xy 118.35892 -217.064336) (xy 118.359428 -217.038429) (xy 118.367534 -216.987252)
			(xy 118.383546 -216.937973) (xy 118.407069 -216.891806) (xy 118.437525 -216.849887) (xy 118.474163 -216.813249)
			(xy 118.516082 -216.782793) (xy 118.562249 -216.75927) (xy 118.611528 -216.743258) (xy 118.662705 -216.735152)
			(xy 118.714519 -216.735152) (xy 118.765696 -216.743258) (xy 118.814975 -216.75927) (xy 118.861142 -216.782793)
			(xy 118.903061 -216.813249) (xy 118.939699 -216.849887) (xy 118.970155 -216.891806) (xy 118.993678 -216.937973)
			(xy 119.00969 -216.987252) (xy 119.017796 -217.038429) (xy 119.018304 -217.064336) (xy 120.23852 -217.064336)
			(xy 120.239028 -217.038429) (xy 120.247134 -216.987252) (xy 120.263146 -216.937973) (xy 120.286669 -216.891806)
			(xy 120.317125 -216.849887) (xy 120.353763 -216.813249) (xy 120.395682 -216.782793) (xy 120.441849 -216.75927)
			(xy 120.491128 -216.743258) (xy 120.542305 -216.735152) (xy 120.594119 -216.735152) (xy 120.645296 -216.743258)
			(xy 120.694575 -216.75927) (xy 120.740742 -216.782793) (xy 120.782661 -216.813249) (xy 120.819299 -216.849887)
			(xy 120.849755 -216.891806) (xy 120.873278 -216.937973) (xy 120.88929 -216.987252) (xy 120.897396 -217.038429)
			(xy 120.897904 -217.064336) (xy 122.11812 -217.064336) (xy 122.118628 -217.038429) (xy 122.126734 -216.987252)
			(xy 122.142746 -216.937973) (xy 122.166269 -216.891806) (xy 122.196725 -216.849887) (xy 122.233363 -216.813249)
			(xy 122.275282 -216.782793) (xy 122.321449 -216.75927) (xy 122.370728 -216.743258) (xy 122.421905 -216.735152)
			(xy 122.473719 -216.735152) (xy 122.524896 -216.743258) (xy 122.574175 -216.75927) (xy 122.620342 -216.782793)
			(xy 122.662261 -216.813249) (xy 122.698899 -216.849887) (xy 122.729355 -216.891806) (xy 122.752878 -216.937973)
			(xy 122.76889 -216.987252) (xy 122.776996 -217.038429) (xy 122.777504 -217.064336) (xy 123.99772 -217.064336)
			(xy 123.998228 -217.038429) (xy 124.006334 -216.987252) (xy 124.022346 -216.937973) (xy 124.045869 -216.891806)
			(xy 124.076325 -216.849887) (xy 124.112963 -216.813249) (xy 124.154882 -216.782793) (xy 124.201049 -216.75927)
			(xy 124.250328 -216.743258) (xy 124.301505 -216.735152) (xy 124.353319 -216.735152) (xy 124.404496 -216.743258)
			(xy 124.453775 -216.75927) (xy 124.499942 -216.782793) (xy 124.541861 -216.813249) (xy 124.578499 -216.849887)
			(xy 124.608955 -216.891806) (xy 124.632478 -216.937973) (xy 124.64849 -216.987252) (xy 124.656596 -217.038429)
			(xy 124.657104 -217.064336) (xy 125.87732 -217.064336) (xy 125.877828 -217.038429) (xy 125.885934 -216.987252)
			(xy 125.901946 -216.937973) (xy 125.925469 -216.891806) (xy 125.955925 -216.849887) (xy 125.992563 -216.813249)
			(xy 126.034482 -216.782793) (xy 126.080649 -216.75927) (xy 126.129928 -216.743258) (xy 126.181105 -216.735152)
			(xy 126.232919 -216.735152) (xy 126.284096 -216.743258) (xy 126.333375 -216.75927) (xy 126.379542 -216.782793)
			(xy 126.421461 -216.813249) (xy 126.458099 -216.849887) (xy 126.488555 -216.891806) (xy 126.512078 -216.937973)
			(xy 126.52809 -216.987252) (xy 126.536196 -217.038429) (xy 126.536704 -217.064336) (xy 127.75692 -217.064336)
			(xy 127.757428 -217.038429) (xy 127.765534 -216.987252) (xy 127.781546 -216.937973) (xy 127.805069 -216.891806)
			(xy 127.835525 -216.849887) (xy 127.872163 -216.813249) (xy 127.914082 -216.782793) (xy 127.960249 -216.75927)
			(xy 128.009528 -216.743258) (xy 128.060705 -216.735152) (xy 128.112519 -216.735152) (xy 128.163696 -216.743258)
			(xy 128.212975 -216.75927) (xy 128.259142 -216.782793) (xy 128.301061 -216.813249) (xy 128.337699 -216.849887)
			(xy 128.368155 -216.891806) (xy 128.391678 -216.937973) (xy 128.40769 -216.987252) (xy 128.415796 -217.038429)
			(xy 128.416304 -217.064336) (xy 129.63652 -217.064336) (xy 129.637028 -217.038429) (xy 129.645134 -216.987252)
			(xy 129.661146 -216.937973) (xy 129.684669 -216.891806) (xy 129.715125 -216.849887) (xy 129.751763 -216.813249)
			(xy 129.793682 -216.782793) (xy 129.839849 -216.75927) (xy 129.889128 -216.743258) (xy 129.940305 -216.735152)
			(xy 129.992119 -216.735152) (xy 130.043296 -216.743258) (xy 130.092575 -216.75927) (xy 130.138742 -216.782793)
			(xy 130.180661 -216.813249) (xy 130.217299 -216.849887) (xy 130.247755 -216.891806) (xy 130.271278 -216.937973)
			(xy 130.28729 -216.987252) (xy 130.295396 -217.038429) (xy 130.295904 -217.064336) (xy 131.51612 -217.064336)
			(xy 131.516628 -217.038429) (xy 131.524734 -216.987252) (xy 131.540746 -216.937973) (xy 131.564269 -216.891806)
			(xy 131.594725 -216.849887) (xy 131.631363 -216.813249) (xy 131.673282 -216.782793) (xy 131.719449 -216.75927)
			(xy 131.768728 -216.743258) (xy 131.819905 -216.735152) (xy 131.871719 -216.735152) (xy 131.922896 -216.743258)
			(xy 131.972175 -216.75927) (xy 132.018342 -216.782793) (xy 132.060261 -216.813249) (xy 132.096899 -216.849887)
			(xy 132.127355 -216.891806) (xy 132.150878 -216.937973) (xy 132.16689 -216.987252) (xy 132.174996 -217.038429)
			(xy 132.175504 -217.064336) (xy 133.39572 -217.064336) (xy 133.396228 -217.038429) (xy 133.404334 -216.987252)
			(xy 133.420346 -216.937973) (xy 133.443869 -216.891806) (xy 133.474325 -216.849887) (xy 133.510963 -216.813249)
			(xy 133.552882 -216.782793) (xy 133.599049 -216.75927) (xy 133.648328 -216.743258) (xy 133.699505 -216.735152)
			(xy 133.751319 -216.735152) (xy 133.802496 -216.743258) (xy 133.851775 -216.75927) (xy 133.897942 -216.782793)
			(xy 133.939861 -216.813249) (xy 133.976499 -216.849887) (xy 134.006955 -216.891806) (xy 134.030478 -216.937973)
			(xy 134.04649 -216.987252) (xy 134.054596 -217.038429) (xy 134.055104 -217.064336) (xy 134.054946 -217.071448)
			(xy 158.062168 -217.071448) (xy 158.062168 -216.662508) (xy 158.062628 -216.652358) (xy 158.070414 -216.633612)
			(xy 158.084799 -216.61929) (xy 158.103579 -216.611584) (xy 158.11373 -216.6112) (xy 159.51327 -216.6112)
			(xy 159.52339 -216.61175) (xy 159.542103 -216.61946) (xy 159.556459 -216.633727) (xy 159.564286 -216.652391)
			(xy 159.564832 -216.662508) (xy 159.564832 -217.071448) (xy 165.605968 -217.071448) (xy 165.605968 -216.662508)
			(xy 165.606428 -216.652358) (xy 165.614214 -216.633612) (xy 165.628599 -216.61929) (xy 165.647379 -216.611584)
			(xy 165.65753 -216.6112) (xy 167.05707 -216.6112) (xy 167.06719 -216.61175) (xy 167.085903 -216.61946)
			(xy 167.100259 -216.633727) (xy 167.108086 -216.652391) (xy 167.108632 -216.662508) (xy 167.108632 -217.071448)
			(xy 173.149768 -217.071448) (xy 173.149768 -216.662508) (xy 173.150228 -216.652358) (xy 173.158014 -216.633612)
			(xy 173.172399 -216.61929) (xy 173.191179 -216.611584) (xy 173.20133 -216.6112) (xy 174.60087 -216.6112)
			(xy 174.61099 -216.61175) (xy 174.629703 -216.61946) (xy 174.644059 -216.633727) (xy 174.651886 -216.652391)
			(xy 174.652432 -216.662508) (xy 174.652432 -217.071448) (xy 180.693568 -217.071448) (xy 180.693568 -216.662508)
			(xy 180.694028 -216.652358) (xy 180.701814 -216.633612) (xy 180.716199 -216.61929) (xy 180.734979 -216.611584)
			(xy 180.74513 -216.6112) (xy 182.14467 -216.6112) (xy 182.15479 -216.61175) (xy 182.173503 -216.61946)
			(xy 182.187859 -216.633727) (xy 182.195686 -216.652391) (xy 182.196232 -216.662508) (xy 182.196232 -217.071448)
			(xy 188.237368 -217.071448) (xy 188.237368 -216.662508) (xy 188.237828 -216.652358) (xy 188.245614 -216.633612)
			(xy 188.259999 -216.61929) (xy 188.278779 -216.611584) (xy 188.28893 -216.6112) (xy 189.68847 -216.6112)
			(xy 189.69859 -216.61175) (xy 189.717303 -216.61946) (xy 189.731659 -216.633727) (xy 189.739486 -216.652391)
			(xy 189.740032 -216.662508) (xy 189.740032 -217.071448) (xy 195.781168 -217.071448) (xy 195.781168 -216.662508)
			(xy 195.781628 -216.652358) (xy 195.789414 -216.633612) (xy 195.803799 -216.61929) (xy 195.822579 -216.611584)
			(xy 195.83273 -216.6112) (xy 197.23227 -216.6112) (xy 197.24239 -216.61175) (xy 197.261103 -216.61946)
			(xy 197.275459 -216.633727) (xy 197.283286 -216.652391) (xy 197.283832 -216.662508) (xy 197.283832 -217.071448)
			(xy 203.324968 -217.071448) (xy 203.324968 -216.662508) (xy 203.325428 -216.652358) (xy 203.333214 -216.633612)
			(xy 203.347599 -216.61929) (xy 203.366379 -216.611584) (xy 203.37653 -216.6112) (xy 204.77607 -216.6112)
			(xy 204.78619 -216.61175) (xy 204.804903 -216.61946) (xy 204.819259 -216.633727) (xy 204.827086 -216.652391)
			(xy 204.827632 -216.662508) (xy 204.827632 -217.071448) (xy 210.868768 -217.071448) (xy 210.868768 -216.662508)
			(xy 210.869228 -216.652358) (xy 210.877014 -216.633612) (xy 210.891399 -216.61929) (xy 210.910179 -216.611584)
			(xy 210.92033 -216.6112) (xy 212.31987 -216.6112) (xy 212.32999 -216.61175) (xy 212.348703 -216.61946)
			(xy 212.363059 -216.633727) (xy 212.370886 -216.652391) (xy 212.371432 -216.662508) (xy 212.371432 -217.071448)
			(xy 255.329436 -217.071448) (xy 255.329436 -216.662508) (xy 255.329829 -216.65235) (xy 255.337629 -216.633591)
			(xy 255.352035 -216.619266) (xy 255.370838 -216.611572) (xy 255.380998 -216.6112) (xy 256.780538 -216.6112)
			(xy 256.790662 -216.611694) (xy 256.809377 -216.619427) (xy 256.82373 -216.63371) (xy 256.831555 -216.652386)
			(xy 256.8321 -216.662508) (xy 256.8321 -217.071448) (xy 262.873236 -217.071448) (xy 262.873236 -216.662508)
			(xy 262.873629 -216.65235) (xy 262.881429 -216.633591) (xy 262.895835 -216.619266) (xy 262.914638 -216.611572)
			(xy 262.924798 -216.6112) (xy 264.324338 -216.6112) (xy 264.334462 -216.611694) (xy 264.353177 -216.619427)
			(xy 264.36753 -216.63371) (xy 264.375355 -216.652386) (xy 264.3759 -216.662508) (xy 264.3759 -217.071448)
			(xy 270.417036 -217.071448) (xy 270.417036 -216.662508) (xy 270.417429 -216.65235) (xy 270.425229 -216.633591)
			(xy 270.439635 -216.619266) (xy 270.458438 -216.611572) (xy 270.468598 -216.6112) (xy 271.868138 -216.6112)
			(xy 271.878262 -216.611694) (xy 271.896977 -216.619427) (xy 271.91133 -216.63371) (xy 271.919155 -216.652386)
			(xy 271.9197 -216.662508) (xy 271.9197 -217.071448) (xy 277.960836 -217.071448) (xy 277.960836 -216.662508)
			(xy 277.961229 -216.65235) (xy 277.969029 -216.633591) (xy 277.983435 -216.619266) (xy 278.002238 -216.611572)
			(xy 278.012398 -216.6112) (xy 279.411938 -216.6112) (xy 279.422062 -216.611694) (xy 279.440777 -216.619427)
			(xy 279.45513 -216.63371) (xy 279.462955 -216.652386) (xy 279.4635 -216.662508) (xy 279.4635 -217.071448)
			(xy 285.504636 -217.071448) (xy 285.504636 -216.662508) (xy 285.505029 -216.65235) (xy 285.512829 -216.633591)
			(xy 285.527235 -216.619266) (xy 285.546038 -216.611572) (xy 285.556198 -216.6112) (xy 286.955738 -216.6112)
			(xy 286.965862 -216.611694) (xy 286.984577 -216.619427) (xy 286.99893 -216.63371) (xy 287.006755 -216.652386)
			(xy 287.0073 -216.662508) (xy 287.0073 -217.071448) (xy 293.048436 -217.071448) (xy 293.048436 -216.662508)
			(xy 293.048829 -216.65235) (xy 293.056629 -216.633591) (xy 293.071035 -216.619266) (xy 293.089838 -216.611572)
			(xy 293.099998 -216.6112) (xy 294.499538 -216.6112) (xy 294.509662 -216.611694) (xy 294.528377 -216.619427)
			(xy 294.54273 -216.63371) (xy 294.550555 -216.652386) (xy 294.5511 -216.662508) (xy 294.5511 -217.071448)
			(xy 300.592236 -217.071448) (xy 300.592236 -216.662508) (xy 300.592629 -216.65235) (xy 300.600429 -216.633591)
			(xy 300.614835 -216.619266) (xy 300.633638 -216.611572) (xy 300.643798 -216.6112) (xy 302.043338 -216.6112)
			(xy 302.053462 -216.611694) (xy 302.072177 -216.619427) (xy 302.08653 -216.63371) (xy 302.094355 -216.652386)
			(xy 302.0949 -216.662508) (xy 302.0949 -217.071448) (xy 308.136036 -217.071448) (xy 308.136036 -216.662508)
			(xy 308.136429 -216.65235) (xy 308.144229 -216.633591) (xy 308.158635 -216.619266) (xy 308.177438 -216.611572)
			(xy 308.187598 -216.6112) (xy 309.587138 -216.6112) (xy 309.597262 -216.611694) (xy 309.615977 -216.619427)
			(xy 309.63033 -216.63371) (xy 309.638155 -216.652386) (xy 309.6387 -216.662508) (xy 309.6387 -217.071448)
			(xy 309.638318 -217.081605) (xy 309.630506 -217.100359) (xy 309.616098 -217.11468) (xy 309.597298 -217.122378)
			(xy 309.587138 -217.122756) (xy 308.187598 -217.122756) (xy 308.177471 -217.122275) (xy 308.158749 -217.114546)
			(xy 308.144392 -217.100258) (xy 308.136574 -217.081573) (xy 308.136036 -217.071448) (xy 302.0949 -217.071448)
			(xy 302.094518 -217.081605) (xy 302.086706 -217.100359) (xy 302.072298 -217.11468) (xy 302.053498 -217.122378)
			(xy 302.043338 -217.122756) (xy 300.643798 -217.122756) (xy 300.633671 -217.122275) (xy 300.614949 -217.114546)
			(xy 300.600592 -217.100258) (xy 300.592774 -217.081573) (xy 300.592236 -217.071448) (xy 294.5511 -217.071448)
			(xy 294.550718 -217.081605) (xy 294.542906 -217.100359) (xy 294.528498 -217.11468) (xy 294.509698 -217.122378)
			(xy 294.499538 -217.122756) (xy 293.099998 -217.122756) (xy 293.089871 -217.122275) (xy 293.071149 -217.114546)
			(xy 293.056792 -217.100258) (xy 293.048974 -217.081573) (xy 293.048436 -217.071448) (xy 287.0073 -217.071448)
			(xy 287.006918 -217.081605) (xy 286.999106 -217.100359) (xy 286.984698 -217.11468) (xy 286.965898 -217.122378)
			(xy 286.955738 -217.122756) (xy 285.556198 -217.122756) (xy 285.546071 -217.122275) (xy 285.527349 -217.114546)
			(xy 285.512992 -217.100258) (xy 285.505174 -217.081573) (xy 285.504636 -217.071448) (xy 279.4635 -217.071448)
			(xy 279.463118 -217.081605) (xy 279.455306 -217.100359) (xy 279.440898 -217.11468) (xy 279.422098 -217.122378)
			(xy 279.411938 -217.122756) (xy 278.012398 -217.122756) (xy 278.002271 -217.122275) (xy 277.983549 -217.114546)
			(xy 277.969192 -217.100258) (xy 277.961374 -217.081573) (xy 277.960836 -217.071448) (xy 271.9197 -217.071448)
			(xy 271.919318 -217.081605) (xy 271.911506 -217.100359) (xy 271.897098 -217.11468) (xy 271.878298 -217.122378)
			(xy 271.868138 -217.122756) (xy 270.468598 -217.122756) (xy 270.458471 -217.122275) (xy 270.439749 -217.114546)
			(xy 270.425392 -217.100258) (xy 270.417574 -217.081573) (xy 270.417036 -217.071448) (xy 264.3759 -217.071448)
			(xy 264.375518 -217.081605) (xy 264.367706 -217.100359) (xy 264.353298 -217.11468) (xy 264.334498 -217.122378)
			(xy 264.324338 -217.122756) (xy 262.924798 -217.122756) (xy 262.914671 -217.122275) (xy 262.895949 -217.114546)
			(xy 262.881592 -217.100258) (xy 262.873774 -217.081573) (xy 262.873236 -217.071448) (xy 256.8321 -217.071448)
			(xy 256.831718 -217.081605) (xy 256.823906 -217.100359) (xy 256.809498 -217.11468) (xy 256.790698 -217.122378)
			(xy 256.780538 -217.122756) (xy 255.380998 -217.122756) (xy 255.370871 -217.122275) (xy 255.352149 -217.114546)
			(xy 255.337792 -217.100258) (xy 255.329974 -217.081573) (xy 255.329436 -217.071448) (xy 212.371432 -217.071448)
			(xy 212.371018 -217.081601) (xy 212.363213 -217.100348) (xy 212.348815 -217.114669) (xy 212.330025 -217.122373)
			(xy 212.31987 -217.122756) (xy 210.92033 -217.122756) (xy 210.910205 -217.122249) (xy 210.891483 -217.11453)
			(xy 210.877126 -217.10025) (xy 210.869306 -217.081571) (xy 210.868768 -217.071448) (xy 204.827632 -217.071448)
			(xy 204.827218 -217.081601) (xy 204.819413 -217.100348) (xy 204.805015 -217.114669) (xy 204.786225 -217.122373)
			(xy 204.77607 -217.122756) (xy 203.37653 -217.122756) (xy 203.366405 -217.122249) (xy 203.347683 -217.11453)
			(xy 203.333326 -217.10025) (xy 203.325506 -217.081571) (xy 203.324968 -217.071448) (xy 197.283832 -217.071448)
			(xy 197.283418 -217.081601) (xy 197.275613 -217.100348) (xy 197.261215 -217.114669) (xy 197.242425 -217.122373)
			(xy 197.23227 -217.122756) (xy 195.83273 -217.122756) (xy 195.822605 -217.122249) (xy 195.803883 -217.11453)
			(xy 195.789526 -217.10025) (xy 195.781706 -217.081571) (xy 195.781168 -217.071448) (xy 189.740032 -217.071448)
			(xy 189.739618 -217.081601) (xy 189.731813 -217.100348) (xy 189.717415 -217.114669) (xy 189.698625 -217.122373)
			(xy 189.68847 -217.122756) (xy 188.28893 -217.122756) (xy 188.278805 -217.122249) (xy 188.260083 -217.11453)
			(xy 188.245726 -217.10025) (xy 188.237906 -217.081571) (xy 188.237368 -217.071448) (xy 182.196232 -217.071448)
			(xy 182.195818 -217.081601) (xy 182.188013 -217.100348) (xy 182.173615 -217.114669) (xy 182.154825 -217.122373)
			(xy 182.14467 -217.122756) (xy 180.74513 -217.122756) (xy 180.735005 -217.122249) (xy 180.716283 -217.11453)
			(xy 180.701926 -217.10025) (xy 180.694106 -217.081571) (xy 180.693568 -217.071448) (xy 174.652432 -217.071448)
			(xy 174.652018 -217.081601) (xy 174.644213 -217.100348) (xy 174.629815 -217.114669) (xy 174.611025 -217.122373)
			(xy 174.60087 -217.122756) (xy 173.20133 -217.122756) (xy 173.191205 -217.122249) (xy 173.172483 -217.11453)
			(xy 173.158126 -217.10025) (xy 173.150306 -217.081571) (xy 173.149768 -217.071448) (xy 167.108632 -217.071448)
			(xy 167.108218 -217.081601) (xy 167.100413 -217.100348) (xy 167.086015 -217.114669) (xy 167.067225 -217.122373)
			(xy 167.05707 -217.122756) (xy 165.65753 -217.122756) (xy 165.647405 -217.122249) (xy 165.628683 -217.11453)
			(xy 165.614326 -217.10025) (xy 165.606506 -217.081571) (xy 165.605968 -217.071448) (xy 159.564832 -217.071448)
			(xy 159.564418 -217.081601) (xy 159.556613 -217.100348) (xy 159.542215 -217.114669) (xy 159.523425 -217.122373)
			(xy 159.51327 -217.122756) (xy 158.11373 -217.122756) (xy 158.103605 -217.122249) (xy 158.084883 -217.11453)
			(xy 158.070526 -217.10025) (xy 158.062706 -217.081571) (xy 158.062168 -217.071448) (xy 134.054946 -217.071448)
			(xy 134.054489 -217.091989) (xy 134.045169 -217.146507) (xy 134.036562 -217.172794) (xy 134.028942 -217.194892)
			(xy 134.234174 -217.550238) (xy 134.257034 -217.554556) (xy 134.281841 -217.559728) (xy 134.329579 -217.576721)
			(xy 134.374156 -217.600818) (xy 134.41452 -217.631451) (xy 134.449723 -217.6679) (xy 134.478934 -217.709305)
			(xy 134.501466 -217.754693) (xy 134.516789 -217.802993) (xy 134.524541 -217.85307) (xy 134.525004 -217.878406)
			(xy 134.524496 -217.904293) (xy 134.521797 -217.921332) (xy 162.162236 -217.921332) (xy 162.162236 -217.512392)
			(xy 162.162616 -217.502233) (xy 162.170421 -217.483473) (xy 162.184831 -217.469149) (xy 162.203637 -217.461456)
			(xy 162.213798 -217.461084) (xy 163.613338 -217.461084) (xy 163.623473 -217.461497) (xy 163.642203 -217.469245)
			(xy 163.656559 -217.483554) (xy 163.66437 -217.502259) (xy 163.6649 -217.512392) (xy 163.6649 -217.921332)
			(xy 169.706036 -217.921332) (xy 169.706036 -217.512392) (xy 169.706416 -217.502233) (xy 169.714221 -217.483473)
			(xy 169.728631 -217.469149) (xy 169.747437 -217.461456) (xy 169.757598 -217.461084) (xy 171.157138 -217.461084)
			(xy 171.167273 -217.461497) (xy 171.186003 -217.469245) (xy 171.200359 -217.483554) (xy 171.20817 -217.502259)
			(xy 171.2087 -217.512392) (xy 171.2087 -217.921332) (xy 177.249836 -217.921332) (xy 177.249836 -217.512392)
			(xy 177.250216 -217.502233) (xy 177.258021 -217.483473) (xy 177.272431 -217.469149) (xy 177.291237 -217.461456)
			(xy 177.301398 -217.461084) (xy 178.700938 -217.461084) (xy 178.711073 -217.461497) (xy 178.729803 -217.469245)
			(xy 178.744159 -217.483554) (xy 178.75197 -217.502259) (xy 178.7525 -217.512392) (xy 178.7525 -217.921332)
			(xy 184.793636 -217.921332) (xy 184.793636 -217.512392) (xy 184.794016 -217.502233) (xy 184.801821 -217.483473)
			(xy 184.816231 -217.469149) (xy 184.835037 -217.461456) (xy 184.845198 -217.461084) (xy 186.244738 -217.461084)
			(xy 186.254873 -217.461497) (xy 186.273603 -217.469245) (xy 186.287959 -217.483554) (xy 186.29577 -217.502259)
			(xy 186.2963 -217.512392) (xy 186.2963 -217.921332) (xy 192.337436 -217.921332) (xy 192.337436 -217.512392)
			(xy 192.337816 -217.502233) (xy 192.345621 -217.483473) (xy 192.360031 -217.469149) (xy 192.378837 -217.461456)
			(xy 192.388998 -217.461084) (xy 193.788538 -217.461084) (xy 193.798673 -217.461497) (xy 193.817403 -217.469245)
			(xy 193.831759 -217.483554) (xy 193.83957 -217.502259) (xy 193.8401 -217.512392) (xy 193.8401 -217.921332)
			(xy 199.881236 -217.921332) (xy 199.881236 -217.512392) (xy 199.881616 -217.502233) (xy 199.889421 -217.483473)
			(xy 199.903831 -217.469149) (xy 199.922637 -217.461456) (xy 199.932798 -217.461084) (xy 201.332338 -217.461084)
			(xy 201.342473 -217.461497) (xy 201.361203 -217.469245) (xy 201.375559 -217.483554) (xy 201.38337 -217.502259)
			(xy 201.3839 -217.512392) (xy 201.3839 -217.921332) (xy 207.425036 -217.921332) (xy 207.425036 -217.512392)
			(xy 207.425416 -217.502233) (xy 207.433221 -217.483473) (xy 207.447631 -217.469149) (xy 207.466437 -217.461456)
			(xy 207.476598 -217.461084) (xy 208.876138 -217.461084) (xy 208.886273 -217.461497) (xy 208.905003 -217.469245)
			(xy 208.919359 -217.483554) (xy 208.92717 -217.502259) (xy 208.9277 -217.512392) (xy 208.9277 -217.921332)
			(xy 214.968836 -217.921332) (xy 214.968836 -217.512392) (xy 214.969216 -217.502233) (xy 214.977021 -217.483473)
			(xy 214.991431 -217.469149) (xy 215.010237 -217.461456) (xy 215.020398 -217.461084) (xy 216.419938 -217.461084)
			(xy 216.430073 -217.461497) (xy 216.448803 -217.469245) (xy 216.463159 -217.483554) (xy 216.47097 -217.502259)
			(xy 216.4715 -217.512392) (xy 216.4715 -217.921332) (xy 259.429504 -217.921332) (xy 259.429504 -217.512392)
			(xy 259.429915 -217.502237) (xy 259.437714 -217.483484) (xy 259.452114 -217.46916) (xy 259.470909 -217.461462)
			(xy 259.481066 -217.461084) (xy 260.880606 -217.461084) (xy 260.890738 -217.461523) (xy 260.909468 -217.469261)
			(xy 260.923826 -217.483562) (xy 260.931637 -217.502262) (xy 260.932168 -217.512392) (xy 260.932168 -217.921332)
			(xy 266.973304 -217.921332) (xy 266.973304 -217.512392) (xy 266.973715 -217.502237) (xy 266.981514 -217.483484)
			(xy 266.995914 -217.46916) (xy 267.014709 -217.461462) (xy 267.024866 -217.461084) (xy 268.424406 -217.461084)
			(xy 268.434538 -217.461523) (xy 268.453268 -217.469261) (xy 268.467626 -217.483562) (xy 268.475437 -217.502262)
			(xy 268.475968 -217.512392) (xy 268.475968 -217.921332) (xy 274.517104 -217.921332) (xy 274.517104 -217.512392)
			(xy 274.517515 -217.502237) (xy 274.525314 -217.483484) (xy 274.539714 -217.46916) (xy 274.558509 -217.461462)
			(xy 274.568666 -217.461084) (xy 275.968206 -217.461084) (xy 275.978338 -217.461523) (xy 275.997068 -217.469261)
			(xy 276.011426 -217.483562) (xy 276.019237 -217.502262) (xy 276.019768 -217.512392) (xy 276.019768 -217.921332)
			(xy 282.060904 -217.921332) (xy 282.060904 -217.512392) (xy 282.061315 -217.502237) (xy 282.069114 -217.483484)
			(xy 282.083514 -217.46916) (xy 282.102309 -217.461462) (xy 282.112466 -217.461084) (xy 283.512006 -217.461084)
			(xy 283.522138 -217.461523) (xy 283.540868 -217.469261) (xy 283.555226 -217.483562) (xy 283.563037 -217.502262)
			(xy 283.563568 -217.512392) (xy 283.563568 -217.921332) (xy 289.604704 -217.921332) (xy 289.604704 -217.512392)
			(xy 289.605115 -217.502237) (xy 289.612914 -217.483484) (xy 289.627314 -217.46916) (xy 289.646109 -217.461462)
			(xy 289.656266 -217.461084) (xy 291.055806 -217.461084) (xy 291.065938 -217.461523) (xy 291.084668 -217.469261)
			(xy 291.099026 -217.483562) (xy 291.106837 -217.502262) (xy 291.107368 -217.512392) (xy 291.107368 -217.921332)
			(xy 297.148504 -217.921332) (xy 297.148504 -217.512392) (xy 297.148915 -217.502237) (xy 297.156714 -217.483484)
			(xy 297.171114 -217.46916) (xy 297.189909 -217.461462) (xy 297.200066 -217.461084) (xy 298.599606 -217.461084)
			(xy 298.609738 -217.461523) (xy 298.628468 -217.469261) (xy 298.642826 -217.483562) (xy 298.650637 -217.502262)
			(xy 298.651168 -217.512392) (xy 298.651168 -217.921332) (xy 304.692304 -217.921332) (xy 304.692304 -217.512392)
			(xy 304.692715 -217.502237) (xy 304.700514 -217.483484) (xy 304.714914 -217.46916) (xy 304.733709 -217.461462)
			(xy 304.743866 -217.461084) (xy 306.143406 -217.461084) (xy 306.153538 -217.461523) (xy 306.172268 -217.469261)
			(xy 306.186626 -217.483562) (xy 306.194437 -217.502262) (xy 306.194968 -217.512392) (xy 306.194968 -217.921332)
			(xy 312.236104 -217.921332) (xy 312.236104 -217.512392) (xy 312.236515 -217.502237) (xy 312.244314 -217.483484)
			(xy 312.258714 -217.46916) (xy 312.277509 -217.461462) (xy 312.287666 -217.461084) (xy 313.687206 -217.461084)
			(xy 313.697338 -217.461523) (xy 313.716068 -217.469261) (xy 313.730426 -217.483562) (xy 313.738237 -217.502262)
			(xy 313.738768 -217.512392) (xy 313.738768 -217.878406) (xy 336.695796 -217.878406) (xy 336.696304 -217.852519)
			(xy 336.704403 -217.801381) (xy 336.720402 -217.752141) (xy 336.743908 -217.706009) (xy 336.77434 -217.664122)
			(xy 336.81095 -217.627512) (xy 336.852837 -217.59708) (xy 336.898969 -217.573574) (xy 336.948209 -217.557575)
			(xy 336.999347 -217.549476) (xy 337.051121 -217.549476) (xy 337.102259 -217.557575) (xy 337.151499 -217.573574)
			(xy 337.197631 -217.59708) (xy 337.239518 -217.627512) (xy 337.276128 -217.664122) (xy 337.30656 -217.706009)
			(xy 337.330066 -217.752141) (xy 337.346065 -217.801381) (xy 337.354164 -217.852519) (xy 337.354672 -217.878406)
			(xy 337.635596 -217.878406) (xy 337.636088 -217.853072) (xy 337.643839 -217.803) (xy 337.65916 -217.754704)
			(xy 337.681691 -217.70932) (xy 337.710899 -217.667918) (xy 337.746099 -217.631473) (xy 337.78646 -217.600842)
			(xy 337.831033 -217.576747) (xy 337.878767 -217.559756) (xy 337.903566 -217.554556) (xy 337.926426 -217.550238)
			(xy 338.131404 -217.195146) (xy 338.12353 -217.173302) (xy 338.114891 -217.146892) (xy 338.105567 -217.092117)
			(xy 338.104988 -217.064336) (xy 338.105496 -217.038429) (xy 338.113602 -216.987252) (xy 338.129614 -216.937973)
			(xy 338.153137 -216.891806) (xy 338.183593 -216.849887) (xy 338.220231 -216.813249) (xy 338.26215 -216.782793)
			(xy 338.308317 -216.75927) (xy 338.357596 -216.743258) (xy 338.408773 -216.735152) (xy 338.460587 -216.735152)
			(xy 338.511764 -216.743258) (xy 338.561043 -216.75927) (xy 338.60721 -216.782793) (xy 338.649129 -216.813249)
			(xy 338.685767 -216.849887) (xy 338.716223 -216.891806) (xy 338.739746 -216.937973) (xy 338.755758 -216.987252)
			(xy 338.763864 -217.038429) (xy 338.764372 -217.064336) (xy 338.763906 -217.089682) (xy 338.756128 -217.139773)
			(xy 338.740777 -217.188085) (xy 338.718213 -217.233478) (xy 338.688969 -217.274884) (xy 338.653734 -217.311328)
			(xy 338.613336 -217.34195) (xy 338.568729 -217.36603) (xy 338.520962 -217.383) (xy 338.496148 -217.388186)
			(xy 338.473288 -217.392504) (xy 338.26831 -217.747596) (xy 338.276184 -217.76944) (xy 338.284773 -217.795856)
			(xy 338.293963 -217.850633) (xy 338.294472 -217.878406) (xy 338.575396 -217.878406) (xy 338.575904 -217.852519)
			(xy 338.584003 -217.801381) (xy 338.600002 -217.752141) (xy 338.623508 -217.706009) (xy 338.65394 -217.664122)
			(xy 338.69055 -217.627512) (xy 338.732437 -217.59708) (xy 338.778569 -217.573574) (xy 338.827809 -217.557575)
			(xy 338.878947 -217.549476) (xy 338.930721 -217.549476) (xy 338.981859 -217.557575) (xy 339.031099 -217.573574)
			(xy 339.077231 -217.59708) (xy 339.119118 -217.627512) (xy 339.155728 -217.664122) (xy 339.18616 -217.706009)
			(xy 339.209666 -217.752141) (xy 339.225665 -217.801381) (xy 339.233764 -217.852519) (xy 339.234272 -217.878406)
			(xy 339.515196 -217.878406) (xy 339.515688 -217.853072) (xy 339.523439 -217.803) (xy 339.53876 -217.754704)
			(xy 339.561291 -217.70932) (xy 339.590499 -217.667918) (xy 339.625699 -217.631473) (xy 339.66606 -217.600842)
			(xy 339.710633 -217.576747) (xy 339.758367 -217.559756) (xy 339.783166 -217.554556) (xy 339.806026 -217.550238)
			(xy 340.011004 -217.195146) (xy 340.00313 -217.173302) (xy 339.994491 -217.146892) (xy 339.985167 -217.092117)
			(xy 339.984588 -217.064336) (xy 339.985096 -217.038429) (xy 339.993202 -216.987252) (xy 340.009214 -216.937973)
			(xy 340.032737 -216.891806) (xy 340.063193 -216.849887) (xy 340.099831 -216.813249) (xy 340.14175 -216.782793)
			(xy 340.187917 -216.75927) (xy 340.237196 -216.743258) (xy 340.288373 -216.735152) (xy 340.340187 -216.735152)
			(xy 340.391364 -216.743258) (xy 340.440643 -216.75927) (xy 340.48681 -216.782793) (xy 340.528729 -216.813249)
			(xy 340.565367 -216.849887) (xy 340.595823 -216.891806) (xy 340.619346 -216.937973) (xy 340.635358 -216.987252)
			(xy 340.643464 -217.038429) (xy 340.643972 -217.064336) (xy 340.643506 -217.089682) (xy 340.635728 -217.139773)
			(xy 340.620377 -217.188085) (xy 340.597813 -217.233478) (xy 340.568569 -217.274884) (xy 340.533334 -217.311328)
			(xy 340.492936 -217.34195) (xy 340.448329 -217.36603) (xy 340.400562 -217.383) (xy 340.375748 -217.388186)
			(xy 340.352888 -217.392504) (xy 340.14791 -217.747596) (xy 340.155784 -217.76944) (xy 340.164373 -217.795856)
			(xy 340.173563 -217.850633) (xy 340.174072 -217.878406) (xy 340.454996 -217.878406) (xy 340.455504 -217.852519)
			(xy 340.463603 -217.801381) (xy 340.479602 -217.752141) (xy 340.503108 -217.706009) (xy 340.53354 -217.664122)
			(xy 340.57015 -217.627512) (xy 340.612037 -217.59708) (xy 340.658169 -217.573574) (xy 340.707409 -217.557575)
			(xy 340.758547 -217.549476) (xy 340.810321 -217.549476) (xy 340.861459 -217.557575) (xy 340.910699 -217.573574)
			(xy 340.956831 -217.59708) (xy 340.998718 -217.627512) (xy 341.035328 -217.664122) (xy 341.06576 -217.706009)
			(xy 341.089266 -217.752141) (xy 341.105265 -217.801381) (xy 341.113364 -217.852519) (xy 341.113872 -217.878406)
			(xy 341.394796 -217.878406) (xy 341.395288 -217.853072) (xy 341.403039 -217.803) (xy 341.41836 -217.754704)
			(xy 341.440891 -217.70932) (xy 341.470099 -217.667918) (xy 341.505299 -217.631473) (xy 341.54566 -217.600842)
			(xy 341.590233 -217.576747) (xy 341.637967 -217.559756) (xy 341.662766 -217.554556) (xy 341.685626 -217.550238)
			(xy 341.890604 -217.195146) (xy 341.88273 -217.173302) (xy 341.874091 -217.146892) (xy 341.864767 -217.092117)
			(xy 341.864188 -217.064336) (xy 341.864696 -217.038429) (xy 341.872802 -216.987252) (xy 341.888814 -216.937973)
			(xy 341.912337 -216.891806) (xy 341.942793 -216.849887) (xy 341.979431 -216.813249) (xy 342.02135 -216.782793)
			(xy 342.067517 -216.75927) (xy 342.116796 -216.743258) (xy 342.167973 -216.735152) (xy 342.219787 -216.735152)
			(xy 342.270964 -216.743258) (xy 342.320243 -216.75927) (xy 342.36641 -216.782793) (xy 342.408329 -216.813249)
			(xy 342.444967 -216.849887) (xy 342.475423 -216.891806) (xy 342.498946 -216.937973) (xy 342.514958 -216.987252)
			(xy 342.523064 -217.038429) (xy 342.523572 -217.064336) (xy 342.523106 -217.089682) (xy 342.515328 -217.139773)
			(xy 342.499977 -217.188085) (xy 342.477413 -217.233478) (xy 342.448169 -217.274884) (xy 342.412934 -217.311328)
			(xy 342.372536 -217.34195) (xy 342.327929 -217.36603) (xy 342.280162 -217.383) (xy 342.255348 -217.388186)
			(xy 342.232488 -217.392504) (xy 342.02751 -217.747596) (xy 342.035384 -217.76944) (xy 342.043973 -217.795856)
			(xy 342.053163 -217.850633) (xy 342.053672 -217.878406) (xy 342.334596 -217.878406) (xy 342.335104 -217.852519)
			(xy 342.343203 -217.801381) (xy 342.359202 -217.752141) (xy 342.382708 -217.706009) (xy 342.41314 -217.664122)
			(xy 342.44975 -217.627512) (xy 342.491637 -217.59708) (xy 342.537769 -217.573574) (xy 342.587009 -217.557575)
			(xy 342.638147 -217.549476) (xy 342.689921 -217.549476) (xy 342.741059 -217.557575) (xy 342.790299 -217.573574)
			(xy 342.836431 -217.59708) (xy 342.878318 -217.627512) (xy 342.914928 -217.664122) (xy 342.94536 -217.706009)
			(xy 342.968866 -217.752141) (xy 342.984865 -217.801381) (xy 342.992964 -217.852519) (xy 342.993472 -217.878406)
			(xy 343.274396 -217.878406) (xy 343.274888 -217.853072) (xy 343.282639 -217.803) (xy 343.29796 -217.754704)
			(xy 343.320491 -217.70932) (xy 343.349699 -217.667918) (xy 343.384899 -217.631473) (xy 343.42526 -217.600842)
			(xy 343.469833 -217.576747) (xy 343.517567 -217.559756) (xy 343.542366 -217.554556) (xy 343.565226 -217.550238)
			(xy 343.770204 -217.195146) (xy 343.76233 -217.173302) (xy 343.753691 -217.146892) (xy 343.744367 -217.092117)
			(xy 343.743788 -217.064336) (xy 343.744296 -217.038429) (xy 343.752402 -216.987252) (xy 343.768414 -216.937973)
			(xy 343.791937 -216.891806) (xy 343.822393 -216.849887) (xy 343.859031 -216.813249) (xy 343.90095 -216.782793)
			(xy 343.947117 -216.75927) (xy 343.996396 -216.743258) (xy 344.047573 -216.735152) (xy 344.099387 -216.735152)
			(xy 344.150564 -216.743258) (xy 344.199843 -216.75927) (xy 344.24601 -216.782793) (xy 344.287929 -216.813249)
			(xy 344.324567 -216.849887) (xy 344.355023 -216.891806) (xy 344.378546 -216.937973) (xy 344.394558 -216.987252)
			(xy 344.402664 -217.038429) (xy 344.403172 -217.064336) (xy 344.402706 -217.089682) (xy 344.394928 -217.139773)
			(xy 344.379577 -217.188085) (xy 344.357013 -217.233478) (xy 344.327769 -217.274884) (xy 344.292534 -217.311328)
			(xy 344.252136 -217.34195) (xy 344.207529 -217.36603) (xy 344.159762 -217.383) (xy 344.134948 -217.388186)
			(xy 344.112088 -217.392504) (xy 343.90711 -217.747596) (xy 343.914984 -217.76944) (xy 343.923573 -217.795856)
			(xy 343.932763 -217.850633) (xy 343.933272 -217.878406) (xy 344.214196 -217.878406) (xy 344.214704 -217.852519)
			(xy 344.222803 -217.801381) (xy 344.238802 -217.752141) (xy 344.262308 -217.706009) (xy 344.29274 -217.664122)
			(xy 344.32935 -217.627512) (xy 344.371237 -217.59708) (xy 344.417369 -217.573574) (xy 344.466609 -217.557575)
			(xy 344.517747 -217.549476) (xy 344.569521 -217.549476) (xy 344.620659 -217.557575) (xy 344.669899 -217.573574)
			(xy 344.716031 -217.59708) (xy 344.757918 -217.627512) (xy 344.794528 -217.664122) (xy 344.82496 -217.706009)
			(xy 344.848466 -217.752141) (xy 344.864465 -217.801381) (xy 344.872564 -217.852519) (xy 344.873072 -217.878406)
			(xy 345.153996 -217.878406) (xy 345.154488 -217.853072) (xy 345.162239 -217.803) (xy 345.17756 -217.754704)
			(xy 345.200091 -217.70932) (xy 345.229299 -217.667918) (xy 345.264499 -217.631473) (xy 345.30486 -217.600842)
			(xy 345.349433 -217.576747) (xy 345.397167 -217.559756) (xy 345.421966 -217.554556) (xy 345.444826 -217.550238)
			(xy 345.649804 -217.195146) (xy 345.64193 -217.173302) (xy 345.633291 -217.146892) (xy 345.623967 -217.092117)
			(xy 345.623388 -217.064336) (xy 345.623896 -217.038429) (xy 345.632002 -216.987252) (xy 345.648014 -216.937973)
			(xy 345.671537 -216.891806) (xy 345.701993 -216.849887) (xy 345.738631 -216.813249) (xy 345.78055 -216.782793)
			(xy 345.826717 -216.75927) (xy 345.875996 -216.743258) (xy 345.927173 -216.735152) (xy 345.978987 -216.735152)
			(xy 346.030164 -216.743258) (xy 346.079443 -216.75927) (xy 346.12561 -216.782793) (xy 346.167529 -216.813249)
			(xy 346.204167 -216.849887) (xy 346.234623 -216.891806) (xy 346.258146 -216.937973) (xy 346.274158 -216.987252)
			(xy 346.282264 -217.038429) (xy 346.282772 -217.064336) (xy 346.282306 -217.089682) (xy 346.274528 -217.139773)
			(xy 346.259177 -217.188085) (xy 346.236613 -217.233478) (xy 346.207369 -217.274884) (xy 346.172134 -217.311328)
			(xy 346.131736 -217.34195) (xy 346.087129 -217.36603) (xy 346.039362 -217.383) (xy 346.014548 -217.388186)
			(xy 345.991688 -217.392504) (xy 345.78671 -217.747596) (xy 345.794584 -217.76944) (xy 345.803173 -217.795856)
			(xy 345.812363 -217.850633) (xy 345.812872 -217.878406) (xy 346.093796 -217.878406) (xy 346.094304 -217.852519)
			(xy 346.102403 -217.801381) (xy 346.118402 -217.752141) (xy 346.141908 -217.706009) (xy 346.17234 -217.664122)
			(xy 346.20895 -217.627512) (xy 346.250837 -217.59708) (xy 346.296969 -217.573574) (xy 346.346209 -217.557575)
			(xy 346.397347 -217.549476) (xy 346.449121 -217.549476) (xy 346.500259 -217.557575) (xy 346.549499 -217.573574)
			(xy 346.595631 -217.59708) (xy 346.637518 -217.627512) (xy 346.674128 -217.664122) (xy 346.70456 -217.706009)
			(xy 346.728066 -217.752141) (xy 346.744065 -217.801381) (xy 346.752164 -217.852519) (xy 346.752672 -217.878406)
			(xy 347.033596 -217.878406) (xy 347.034088 -217.853072) (xy 347.041839 -217.803) (xy 347.05716 -217.754704)
			(xy 347.079691 -217.70932) (xy 347.108899 -217.667918) (xy 347.144099 -217.631473) (xy 347.18446 -217.600842)
			(xy 347.229033 -217.576747) (xy 347.276767 -217.559756) (xy 347.301566 -217.554556) (xy 347.324426 -217.550238)
			(xy 347.529404 -217.195146) (xy 347.52153 -217.173302) (xy 347.512891 -217.146892) (xy 347.503567 -217.092117)
			(xy 347.502988 -217.064336) (xy 347.503496 -217.038429) (xy 347.511602 -216.987252) (xy 347.527614 -216.937973)
			(xy 347.551137 -216.891806) (xy 347.581593 -216.849887) (xy 347.618231 -216.813249) (xy 347.66015 -216.782793)
			(xy 347.706317 -216.75927) (xy 347.755596 -216.743258) (xy 347.806773 -216.735152) (xy 347.858587 -216.735152)
			(xy 347.909764 -216.743258) (xy 347.959043 -216.75927) (xy 348.00521 -216.782793) (xy 348.047129 -216.813249)
			(xy 348.083767 -216.849887) (xy 348.114223 -216.891806) (xy 348.137746 -216.937973) (xy 348.153758 -216.987252)
			(xy 348.161864 -217.038429) (xy 348.162372 -217.064336) (xy 348.161906 -217.089682) (xy 348.154128 -217.139773)
			(xy 348.138777 -217.188085) (xy 348.116213 -217.233478) (xy 348.086969 -217.274884) (xy 348.051734 -217.311328)
			(xy 348.011336 -217.34195) (xy 347.966729 -217.36603) (xy 347.918962 -217.383) (xy 347.894148 -217.388186)
			(xy 347.871288 -217.392504) (xy 347.66631 -217.747596) (xy 347.674184 -217.76944) (xy 347.682773 -217.795856)
			(xy 347.691963 -217.850633) (xy 347.692472 -217.878406) (xy 347.973396 -217.878406) (xy 347.973904 -217.852519)
			(xy 347.982003 -217.801381) (xy 347.998002 -217.752141) (xy 348.021508 -217.706009) (xy 348.05194 -217.664122)
			(xy 348.08855 -217.627512) (xy 348.130437 -217.59708) (xy 348.176569 -217.573574) (xy 348.225809 -217.557575)
			(xy 348.276947 -217.549476) (xy 348.328721 -217.549476) (xy 348.379859 -217.557575) (xy 348.429099 -217.573574)
			(xy 348.475231 -217.59708) (xy 348.517118 -217.627512) (xy 348.553728 -217.664122) (xy 348.58416 -217.706009)
			(xy 348.607666 -217.752141) (xy 348.623665 -217.801381) (xy 348.631764 -217.852519) (xy 348.632272 -217.878406)
			(xy 348.913196 -217.878406) (xy 348.913688 -217.853072) (xy 348.921439 -217.803) (xy 348.93676 -217.754704)
			(xy 348.959291 -217.70932) (xy 348.988499 -217.667918) (xy 349.023699 -217.631473) (xy 349.06406 -217.600842)
			(xy 349.108633 -217.576747) (xy 349.156367 -217.559756) (xy 349.181166 -217.554556) (xy 349.204026 -217.550238)
			(xy 349.409004 -217.195146) (xy 349.40113 -217.173302) (xy 349.392491 -217.146892) (xy 349.383167 -217.092117)
			(xy 349.382588 -217.064336) (xy 349.383096 -217.038429) (xy 349.391202 -216.987252) (xy 349.407214 -216.937973)
			(xy 349.430737 -216.891806) (xy 349.461193 -216.849887) (xy 349.497831 -216.813249) (xy 349.53975 -216.782793)
			(xy 349.585917 -216.75927) (xy 349.635196 -216.743258) (xy 349.686373 -216.735152) (xy 349.738187 -216.735152)
			(xy 349.789364 -216.743258) (xy 349.838643 -216.75927) (xy 349.88481 -216.782793) (xy 349.926729 -216.813249)
			(xy 349.963367 -216.849887) (xy 349.993823 -216.891806) (xy 350.017346 -216.937973) (xy 350.033358 -216.987252)
			(xy 350.041464 -217.038429) (xy 350.041972 -217.064336) (xy 350.041506 -217.089682) (xy 350.033728 -217.139773)
			(xy 350.018377 -217.188085) (xy 349.995813 -217.233478) (xy 349.966569 -217.274884) (xy 349.931334 -217.311328)
			(xy 349.890936 -217.34195) (xy 349.846329 -217.36603) (xy 349.798562 -217.383) (xy 349.773748 -217.388186)
			(xy 349.750888 -217.392504) (xy 349.54591 -217.747596) (xy 349.553784 -217.76944) (xy 349.562373 -217.795856)
			(xy 349.571563 -217.850633) (xy 349.572072 -217.878406) (xy 349.852996 -217.878406) (xy 349.853504 -217.852519)
			(xy 349.861603 -217.801381) (xy 349.877602 -217.752141) (xy 349.901108 -217.706009) (xy 349.93154 -217.664122)
			(xy 349.96815 -217.627512) (xy 350.010037 -217.59708) (xy 350.056169 -217.573574) (xy 350.105409 -217.557575)
			(xy 350.156547 -217.549476) (xy 350.208321 -217.549476) (xy 350.259459 -217.557575) (xy 350.308699 -217.573574)
			(xy 350.354831 -217.59708) (xy 350.396718 -217.627512) (xy 350.433328 -217.664122) (xy 350.46376 -217.706009)
			(xy 350.487266 -217.752141) (xy 350.503265 -217.801381) (xy 350.511364 -217.852519) (xy 350.511872 -217.878406)
			(xy 350.792796 -217.878406) (xy 350.793288 -217.853072) (xy 350.801039 -217.803) (xy 350.81636 -217.754704)
			(xy 350.838891 -217.70932) (xy 350.868099 -217.667918) (xy 350.903299 -217.631473) (xy 350.94366 -217.600842)
			(xy 350.988233 -217.576747) (xy 351.035967 -217.559756) (xy 351.060766 -217.554556) (xy 351.083626 -217.550238)
			(xy 351.288604 -217.195146) (xy 351.28073 -217.173302) (xy 351.272091 -217.146892) (xy 351.262767 -217.092117)
			(xy 351.262188 -217.064336) (xy 351.262696 -217.038429) (xy 351.270802 -216.987252) (xy 351.286814 -216.937973)
			(xy 351.310337 -216.891806) (xy 351.340793 -216.849887) (xy 351.377431 -216.813249) (xy 351.41935 -216.782793)
			(xy 351.465517 -216.75927) (xy 351.514796 -216.743258) (xy 351.565973 -216.735152) (xy 351.617787 -216.735152)
			(xy 351.668964 -216.743258) (xy 351.718243 -216.75927) (xy 351.76441 -216.782793) (xy 351.806329 -216.813249)
			(xy 351.842967 -216.849887) (xy 351.873423 -216.891806) (xy 351.896946 -216.937973) (xy 351.912958 -216.987252)
			(xy 351.921064 -217.038429) (xy 351.921572 -217.064336) (xy 351.921106 -217.089682) (xy 351.913328 -217.139773)
			(xy 351.897977 -217.188085) (xy 351.875413 -217.233478) (xy 351.846169 -217.274884) (xy 351.810934 -217.311328)
			(xy 351.770536 -217.34195) (xy 351.725929 -217.36603) (xy 351.678162 -217.383) (xy 351.653348 -217.388186)
			(xy 351.630488 -217.392504) (xy 351.42551 -217.747596) (xy 351.433384 -217.76944) (xy 351.441973 -217.795856)
			(xy 351.451163 -217.850633) (xy 351.451672 -217.878406) (xy 351.732596 -217.878406) (xy 351.733104 -217.852519)
			(xy 351.741203 -217.801381) (xy 351.757202 -217.752141) (xy 351.780708 -217.706009) (xy 351.81114 -217.664122)
			(xy 351.84775 -217.627512) (xy 351.889637 -217.59708) (xy 351.935769 -217.573574) (xy 351.985009 -217.557575)
			(xy 352.036147 -217.549476) (xy 352.087921 -217.549476) (xy 352.139059 -217.557575) (xy 352.188299 -217.573574)
			(xy 352.234431 -217.59708) (xy 352.276318 -217.627512) (xy 352.312928 -217.664122) (xy 352.34336 -217.706009)
			(xy 352.366866 -217.752141) (xy 352.382865 -217.801381) (xy 352.390964 -217.852519) (xy 352.391472 -217.878406)
			(xy 352.672396 -217.878406) (xy 352.672888 -217.853072) (xy 352.680639 -217.803) (xy 352.69596 -217.754704)
			(xy 352.718491 -217.70932) (xy 352.747699 -217.667918) (xy 352.782899 -217.631473) (xy 352.82326 -217.600842)
			(xy 352.867833 -217.576747) (xy 352.915567 -217.559756) (xy 352.940366 -217.554556) (xy 352.963226 -217.550238)
			(xy 353.168204 -217.195146) (xy 353.16033 -217.173302) (xy 353.151691 -217.146892) (xy 353.142367 -217.092117)
			(xy 353.141788 -217.064336) (xy 353.142296 -217.038429) (xy 353.150402 -216.987252) (xy 353.166414 -216.937973)
			(xy 353.189937 -216.891806) (xy 353.220393 -216.849887) (xy 353.257031 -216.813249) (xy 353.29895 -216.782793)
			(xy 353.345117 -216.75927) (xy 353.394396 -216.743258) (xy 353.445573 -216.735152) (xy 353.497387 -216.735152)
			(xy 353.548564 -216.743258) (xy 353.597843 -216.75927) (xy 353.64401 -216.782793) (xy 353.685929 -216.813249)
			(xy 353.722567 -216.849887) (xy 353.753023 -216.891806) (xy 353.776546 -216.937973) (xy 353.792558 -216.987252)
			(xy 353.800664 -217.038429) (xy 353.801172 -217.064336) (xy 353.800706 -217.089682) (xy 353.792928 -217.139773)
			(xy 353.777577 -217.188085) (xy 353.755013 -217.233478) (xy 353.725769 -217.274884) (xy 353.690534 -217.311328)
			(xy 353.650136 -217.34195) (xy 353.605529 -217.36603) (xy 353.557762 -217.383) (xy 353.532948 -217.388186)
			(xy 353.510088 -217.392504) (xy 353.30511 -217.747596) (xy 353.312984 -217.76944) (xy 353.321573 -217.795856)
			(xy 353.330763 -217.850633) (xy 353.331272 -217.878406) (xy 353.612196 -217.878406) (xy 353.612704 -217.852519)
			(xy 353.620803 -217.801381) (xy 353.636802 -217.752141) (xy 353.660308 -217.706009) (xy 353.69074 -217.664122)
			(xy 353.72735 -217.627512) (xy 353.769237 -217.59708) (xy 353.815369 -217.573574) (xy 353.864609 -217.557575)
			(xy 353.915747 -217.549476) (xy 353.967521 -217.549476) (xy 354.018659 -217.557575) (xy 354.067899 -217.573574)
			(xy 354.114031 -217.59708) (xy 354.155918 -217.627512) (xy 354.192528 -217.664122) (xy 354.22296 -217.706009)
			(xy 354.246466 -217.752141) (xy 354.262465 -217.801381) (xy 354.270564 -217.852519) (xy 354.271072 -217.878406)
			(xy 354.551996 -217.878406) (xy 354.552488 -217.853072) (xy 354.560239 -217.803) (xy 354.57556 -217.754704)
			(xy 354.598091 -217.70932) (xy 354.627299 -217.667918) (xy 354.662499 -217.631473) (xy 354.70286 -217.600842)
			(xy 354.747433 -217.576747) (xy 354.795167 -217.559756) (xy 354.819966 -217.554556) (xy 354.842826 -217.550238)
			(xy 355.047804 -217.195146) (xy 355.03993 -217.173302) (xy 355.031291 -217.146892) (xy 355.021967 -217.092117)
			(xy 355.021388 -217.064336) (xy 355.021896 -217.038429) (xy 355.030002 -216.987252) (xy 355.046014 -216.937973)
			(xy 355.069537 -216.891806) (xy 355.099993 -216.849887) (xy 355.136631 -216.813249) (xy 355.17855 -216.782793)
			(xy 355.224717 -216.75927) (xy 355.273996 -216.743258) (xy 355.325173 -216.735152) (xy 355.376987 -216.735152)
			(xy 355.428164 -216.743258) (xy 355.477443 -216.75927) (xy 355.52361 -216.782793) (xy 355.565529 -216.813249)
			(xy 355.602167 -216.849887) (xy 355.632623 -216.891806) (xy 355.656146 -216.937973) (xy 355.672158 -216.987252)
			(xy 355.680264 -217.038429) (xy 355.680772 -217.064336) (xy 355.680306 -217.089682) (xy 355.672528 -217.139773)
			(xy 355.657177 -217.188085) (xy 355.634613 -217.233478) (xy 355.605369 -217.274884) (xy 355.570134 -217.311328)
			(xy 355.529736 -217.34195) (xy 355.485129 -217.36603) (xy 355.437362 -217.383) (xy 355.412548 -217.388186)
			(xy 355.389688 -217.392504) (xy 355.18471 -217.747596) (xy 355.192584 -217.76944) (xy 355.201173 -217.795856)
			(xy 355.210363 -217.850633) (xy 355.210872 -217.878406) (xy 355.491796 -217.878406) (xy 355.492304 -217.852519)
			(xy 355.500403 -217.801381) (xy 355.516402 -217.752141) (xy 355.539908 -217.706009) (xy 355.57034 -217.664122)
			(xy 355.60695 -217.627512) (xy 355.648837 -217.59708) (xy 355.694969 -217.573574) (xy 355.744209 -217.557575)
			(xy 355.795347 -217.549476) (xy 355.847121 -217.549476) (xy 355.898259 -217.557575) (xy 355.947499 -217.573574)
			(xy 355.993631 -217.59708) (xy 356.035518 -217.627512) (xy 356.072128 -217.664122) (xy 356.10256 -217.706009)
			(xy 356.126066 -217.752141) (xy 356.142065 -217.801381) (xy 356.150164 -217.852519) (xy 356.150672 -217.878406)
			(xy 356.431596 -217.878406) (xy 356.432088 -217.853072) (xy 356.439839 -217.803) (xy 356.45516 -217.754704)
			(xy 356.477691 -217.70932) (xy 356.506899 -217.667918) (xy 356.542099 -217.631473) (xy 356.58246 -217.600842)
			(xy 356.627033 -217.576747) (xy 356.674767 -217.559756) (xy 356.699566 -217.554556) (xy 356.722426 -217.550238)
			(xy 356.927404 -217.195146) (xy 356.91953 -217.173302) (xy 356.910891 -217.146892) (xy 356.901567 -217.092117)
			(xy 356.900988 -217.064336) (xy 356.901496 -217.038429) (xy 356.909602 -216.987252) (xy 356.925614 -216.937973)
			(xy 356.949137 -216.891806) (xy 356.979593 -216.849887) (xy 357.016231 -216.813249) (xy 357.05815 -216.782793)
			(xy 357.104317 -216.75927) (xy 357.153596 -216.743258) (xy 357.204773 -216.735152) (xy 357.256587 -216.735152)
			(xy 357.307764 -216.743258) (xy 357.357043 -216.75927) (xy 357.40321 -216.782793) (xy 357.445129 -216.813249)
			(xy 357.481767 -216.849887) (xy 357.512223 -216.891806) (xy 357.535746 -216.937973) (xy 357.551758 -216.987252)
			(xy 357.559864 -217.038429) (xy 357.560372 -217.064336) (xy 357.559906 -217.089682) (xy 357.552128 -217.139773)
			(xy 357.536777 -217.188085) (xy 357.514213 -217.233478) (xy 357.484969 -217.274884) (xy 357.449734 -217.311328)
			(xy 357.409336 -217.34195) (xy 357.364729 -217.36603) (xy 357.316962 -217.383) (xy 357.292148 -217.388186)
			(xy 357.269288 -217.392504) (xy 357.06431 -217.747596) (xy 357.072184 -217.76944) (xy 357.080773 -217.795856)
			(xy 357.089963 -217.850633) (xy 357.090472 -217.878406) (xy 357.371396 -217.878406) (xy 357.371904 -217.852519)
			(xy 357.380003 -217.801381) (xy 357.396002 -217.752141) (xy 357.419508 -217.706009) (xy 357.44994 -217.664122)
			(xy 357.48655 -217.627512) (xy 357.528437 -217.59708) (xy 357.574569 -217.573574) (xy 357.623809 -217.557575)
			(xy 357.674947 -217.549476) (xy 357.726721 -217.549476) (xy 357.777859 -217.557575) (xy 357.827099 -217.573574)
			(xy 357.873231 -217.59708) (xy 357.915118 -217.627512) (xy 357.951728 -217.664122) (xy 357.98216 -217.706009)
			(xy 358.005666 -217.752141) (xy 358.021665 -217.801381) (xy 358.029764 -217.852519) (xy 358.030272 -217.878406)
			(xy 358.311196 -217.878406) (xy 358.311688 -217.853072) (xy 358.319439 -217.803) (xy 358.33476 -217.754704)
			(xy 358.357291 -217.70932) (xy 358.386499 -217.667918) (xy 358.421699 -217.631473) (xy 358.46206 -217.600842)
			(xy 358.506633 -217.576747) (xy 358.554367 -217.559756) (xy 358.579166 -217.554556) (xy 358.602026 -217.550238)
			(xy 358.807004 -217.194892) (xy 358.799384 -217.173048) (xy 358.790811 -217.146694) (xy 358.78162 -217.092045)
			(xy 358.781096 -217.064336) (xy 358.781604 -217.038449) (xy 358.789703 -216.987311) (xy 358.805702 -216.938071)
			(xy 358.829208 -216.891939) (xy 358.85964 -216.850052) (xy 358.89625 -216.813442) (xy 358.938137 -216.78301)
			(xy 358.984269 -216.759504) (xy 359.033509 -216.743505) (xy 359.084647 -216.735406) (xy 359.136421 -216.735406)
			(xy 359.187559 -216.743505) (xy 359.236799 -216.759504) (xy 359.282931 -216.78301) (xy 359.324818 -216.813442)
			(xy 359.361428 -216.850052) (xy 359.39186 -216.891939) (xy 359.415366 -216.938071) (xy 359.431365 -216.987311)
			(xy 359.439464 -217.038449) (xy 359.439972 -217.064336) (xy 360.660188 -217.064336) (xy 360.660696 -217.038429)
			(xy 360.668802 -216.987252) (xy 360.684814 -216.937973) (xy 360.708337 -216.891806) (xy 360.738793 -216.849887)
			(xy 360.775431 -216.813249) (xy 360.81735 -216.782793) (xy 360.863517 -216.75927) (xy 360.912796 -216.743258)
			(xy 360.963973 -216.735152) (xy 361.015787 -216.735152) (xy 361.066964 -216.743258) (xy 361.116243 -216.75927)
			(xy 361.16241 -216.782793) (xy 361.204329 -216.813249) (xy 361.240967 -216.849887) (xy 361.271423 -216.891806)
			(xy 361.294946 -216.937973) (xy 361.310958 -216.987252) (xy 361.319064 -217.038429) (xy 361.319572 -217.064336)
			(xy 362.539788 -217.064336) (xy 362.540296 -217.038429) (xy 362.548402 -216.987252) (xy 362.564414 -216.937973)
			(xy 362.587937 -216.891806) (xy 362.618393 -216.849887) (xy 362.655031 -216.813249) (xy 362.69695 -216.782793)
			(xy 362.743117 -216.75927) (xy 362.792396 -216.743258) (xy 362.843573 -216.735152) (xy 362.895387 -216.735152)
			(xy 362.946564 -216.743258) (xy 362.995843 -216.75927) (xy 363.04201 -216.782793) (xy 363.083929 -216.813249)
			(xy 363.120567 -216.849887) (xy 363.151023 -216.891806) (xy 363.174546 -216.937973) (xy 363.190558 -216.987252)
			(xy 363.198664 -217.038429) (xy 363.199172 -217.064336) (xy 364.419388 -217.064336) (xy 364.419896 -217.038429)
			(xy 364.428002 -216.987252) (xy 364.444014 -216.937973) (xy 364.467537 -216.891806) (xy 364.497993 -216.849887)
			(xy 364.534631 -216.813249) (xy 364.57655 -216.782793) (xy 364.622717 -216.75927) (xy 364.671996 -216.743258)
			(xy 364.723173 -216.735152) (xy 364.774987 -216.735152) (xy 364.826164 -216.743258) (xy 364.875443 -216.75927)
			(xy 364.92161 -216.782793) (xy 364.963529 -216.813249) (xy 365.000167 -216.849887) (xy 365.030623 -216.891806)
			(xy 365.054146 -216.937973) (xy 365.070158 -216.987252) (xy 365.078264 -217.038429) (xy 365.078772 -217.064336)
			(xy 366.298988 -217.064336) (xy 366.299496 -217.038429) (xy 366.307602 -216.987252) (xy 366.323614 -216.937973)
			(xy 366.347137 -216.891806) (xy 366.377593 -216.849887) (xy 366.414231 -216.813249) (xy 366.45615 -216.782793)
			(xy 366.502317 -216.75927) (xy 366.551596 -216.743258) (xy 366.602773 -216.735152) (xy 366.654587 -216.735152)
			(xy 366.705764 -216.743258) (xy 366.755043 -216.75927) (xy 366.80121 -216.782793) (xy 366.843129 -216.813249)
			(xy 366.879767 -216.849887) (xy 366.910223 -216.891806) (xy 366.933746 -216.937973) (xy 366.949758 -216.987252)
			(xy 366.957864 -217.038429) (xy 366.958372 -217.064336) (xy 368.178588 -217.064336) (xy 368.179096 -217.038429)
			(xy 368.187202 -216.987252) (xy 368.203214 -216.937973) (xy 368.226737 -216.891806) (xy 368.257193 -216.849887)
			(xy 368.293831 -216.813249) (xy 368.33575 -216.782793) (xy 368.381917 -216.75927) (xy 368.431196 -216.743258)
			(xy 368.482373 -216.735152) (xy 368.534187 -216.735152) (xy 368.585364 -216.743258) (xy 368.634643 -216.75927)
			(xy 368.68081 -216.782793) (xy 368.722729 -216.813249) (xy 368.759367 -216.849887) (xy 368.789823 -216.891806)
			(xy 368.813346 -216.937973) (xy 368.829358 -216.987252) (xy 368.837464 -217.038429) (xy 368.837972 -217.064336)
			(xy 370.058188 -217.064336) (xy 370.058696 -217.038429) (xy 370.066802 -216.987252) (xy 370.082814 -216.937973)
			(xy 370.106337 -216.891806) (xy 370.136793 -216.849887) (xy 370.173431 -216.813249) (xy 370.21535 -216.782793)
			(xy 370.261517 -216.75927) (xy 370.310796 -216.743258) (xy 370.361973 -216.735152) (xy 370.413787 -216.735152)
			(xy 370.464964 -216.743258) (xy 370.514243 -216.75927) (xy 370.56041 -216.782793) (xy 370.602329 -216.813249)
			(xy 370.638967 -216.849887) (xy 370.669423 -216.891806) (xy 370.692946 -216.937973) (xy 370.708958 -216.987252)
			(xy 370.717064 -217.038429) (xy 370.717572 -217.064336) (xy 371.937788 -217.064336) (xy 371.938296 -217.038429)
			(xy 371.946402 -216.987252) (xy 371.962414 -216.937973) (xy 371.985937 -216.891806) (xy 372.016393 -216.849887)
			(xy 372.053031 -216.813249) (xy 372.09495 -216.782793) (xy 372.141117 -216.75927) (xy 372.190396 -216.743258)
			(xy 372.241573 -216.735152) (xy 372.293387 -216.735152) (xy 372.344564 -216.743258) (xy 372.393843 -216.75927)
			(xy 372.44001 -216.782793) (xy 372.481929 -216.813249) (xy 372.518567 -216.849887) (xy 372.549023 -216.891806)
			(xy 372.572546 -216.937973) (xy 372.588558 -216.987252) (xy 372.596664 -217.038429) (xy 372.597172 -217.064336)
			(xy 373.817388 -217.064336) (xy 373.817896 -217.038429) (xy 373.826002 -216.987252) (xy 373.842014 -216.937973)
			(xy 373.865537 -216.891806) (xy 373.895993 -216.849887) (xy 373.932631 -216.813249) (xy 373.97455 -216.782793)
			(xy 374.020717 -216.75927) (xy 374.069996 -216.743258) (xy 374.121173 -216.735152) (xy 374.172987 -216.735152)
			(xy 374.224164 -216.743258) (xy 374.273443 -216.75927) (xy 374.31961 -216.782793) (xy 374.361529 -216.813249)
			(xy 374.398167 -216.849887) (xy 374.428623 -216.891806) (xy 374.452146 -216.937973) (xy 374.468158 -216.987252)
			(xy 374.476264 -217.038429) (xy 374.476772 -217.064336) (xy 375.696988 -217.064336) (xy 375.697496 -217.038429)
			(xy 375.705602 -216.987252) (xy 375.721614 -216.937973) (xy 375.745137 -216.891806) (xy 375.775593 -216.849887)
			(xy 375.812231 -216.813249) (xy 375.85415 -216.782793) (xy 375.900317 -216.75927) (xy 375.949596 -216.743258)
			(xy 376.000773 -216.735152) (xy 376.052587 -216.735152) (xy 376.103764 -216.743258) (xy 376.153043 -216.75927)
			(xy 376.19921 -216.782793) (xy 376.241129 -216.813249) (xy 376.277767 -216.849887) (xy 376.308223 -216.891806)
			(xy 376.331746 -216.937973) (xy 376.347758 -216.987252) (xy 376.355864 -217.038429) (xy 376.356372 -217.064336)
			(xy 377.576588 -217.064336) (xy 377.577096 -217.038429) (xy 377.585202 -216.987252) (xy 377.601214 -216.937973)
			(xy 377.624737 -216.891806) (xy 377.655193 -216.849887) (xy 377.691831 -216.813249) (xy 377.73375 -216.782793)
			(xy 377.779917 -216.75927) (xy 377.829196 -216.743258) (xy 377.880373 -216.735152) (xy 377.932187 -216.735152)
			(xy 377.983364 -216.743258) (xy 378.032643 -216.75927) (xy 378.07881 -216.782793) (xy 378.120729 -216.813249)
			(xy 378.157367 -216.849887) (xy 378.187823 -216.891806) (xy 378.211346 -216.937973) (xy 378.227358 -216.987252)
			(xy 378.235464 -217.038429) (xy 378.235972 -217.064336) (xy 379.456188 -217.064336) (xy 379.456696 -217.038429)
			(xy 379.464802 -216.987252) (xy 379.480814 -216.937973) (xy 379.504337 -216.891806) (xy 379.534793 -216.849887)
			(xy 379.571431 -216.813249) (xy 379.61335 -216.782793) (xy 379.659517 -216.75927) (xy 379.708796 -216.743258)
			(xy 379.759973 -216.735152) (xy 379.811787 -216.735152) (xy 379.862964 -216.743258) (xy 379.912243 -216.75927)
			(xy 379.95841 -216.782793) (xy 380.000329 -216.813249) (xy 380.036967 -216.849887) (xy 380.067423 -216.891806)
			(xy 380.090946 -216.937973) (xy 380.106958 -216.987252) (xy 380.115064 -217.038429) (xy 380.115572 -217.064336)
			(xy 381.335788 -217.064336) (xy 381.336296 -217.038429) (xy 381.344402 -216.987252) (xy 381.360414 -216.937973)
			(xy 381.383937 -216.891806) (xy 381.414393 -216.849887) (xy 381.451031 -216.813249) (xy 381.49295 -216.782793)
			(xy 381.539117 -216.75927) (xy 381.588396 -216.743258) (xy 381.639573 -216.735152) (xy 381.691387 -216.735152)
			(xy 381.742564 -216.743258) (xy 381.791843 -216.75927) (xy 381.83801 -216.782793) (xy 381.879929 -216.813249)
			(xy 381.916567 -216.849887) (xy 381.947023 -216.891806) (xy 381.970546 -216.937973) (xy 381.986558 -216.987252)
			(xy 381.994664 -217.038429) (xy 381.995172 -217.064336) (xy 381.995014 -217.071448) (xy 406.002236 -217.071448)
			(xy 406.002236 -216.662508) (xy 406.002629 -216.65235) (xy 406.010429 -216.633591) (xy 406.024835 -216.619266)
			(xy 406.043638 -216.611572) (xy 406.053798 -216.6112) (xy 407.453338 -216.6112) (xy 407.463462 -216.611694)
			(xy 407.482177 -216.619427) (xy 407.49653 -216.63371) (xy 407.504355 -216.652386) (xy 407.5049 -216.662508)
			(xy 407.5049 -217.071448) (xy 413.546036 -217.071448) (xy 413.546036 -216.662508) (xy 413.546429 -216.65235)
			(xy 413.554229 -216.633591) (xy 413.568635 -216.619266) (xy 413.587438 -216.611572) (xy 413.597598 -216.6112)
			(xy 414.997138 -216.6112) (xy 415.007262 -216.611694) (xy 415.025977 -216.619427) (xy 415.04033 -216.63371)
			(xy 415.048155 -216.652386) (xy 415.0487 -216.662508) (xy 415.0487 -217.071448) (xy 421.089836 -217.071448)
			(xy 421.089836 -216.662508) (xy 421.090229 -216.65235) (xy 421.098029 -216.633591) (xy 421.112435 -216.619266)
			(xy 421.131238 -216.611572) (xy 421.141398 -216.6112) (xy 422.540938 -216.6112) (xy 422.551062 -216.611694)
			(xy 422.569777 -216.619427) (xy 422.58413 -216.63371) (xy 422.591955 -216.652386) (xy 422.5925 -216.662508)
			(xy 422.5925 -217.071448) (xy 428.633636 -217.071448) (xy 428.633636 -216.662508) (xy 428.634029 -216.65235)
			(xy 428.641829 -216.633591) (xy 428.656235 -216.619266) (xy 428.675038 -216.611572) (xy 428.685198 -216.6112)
			(xy 430.084738 -216.6112) (xy 430.094862 -216.611694) (xy 430.113577 -216.619427) (xy 430.12793 -216.63371)
			(xy 430.135755 -216.652386) (xy 430.1363 -216.662508) (xy 430.1363 -217.071448) (xy 436.177436 -217.071448)
			(xy 436.177436 -216.662508) (xy 436.177829 -216.65235) (xy 436.185629 -216.633591) (xy 436.200035 -216.619266)
			(xy 436.218838 -216.611572) (xy 436.228998 -216.6112) (xy 437.628538 -216.6112) (xy 437.638662 -216.611694)
			(xy 437.657377 -216.619427) (xy 437.67173 -216.63371) (xy 437.679555 -216.652386) (xy 437.6801 -216.662508)
			(xy 437.6801 -217.071448) (xy 443.721236 -217.071448) (xy 443.721236 -216.662508) (xy 443.721629 -216.65235)
			(xy 443.729429 -216.633591) (xy 443.743835 -216.619266) (xy 443.762638 -216.611572) (xy 443.772798 -216.6112)
			(xy 445.172338 -216.6112) (xy 445.182462 -216.611694) (xy 445.201177 -216.619427) (xy 445.21553 -216.63371)
			(xy 445.223355 -216.652386) (xy 445.2239 -216.662508) (xy 445.2239 -217.071448) (xy 451.265036 -217.071448)
			(xy 451.265036 -216.662508) (xy 451.265429 -216.65235) (xy 451.273229 -216.633591) (xy 451.287635 -216.619266)
			(xy 451.306438 -216.611572) (xy 451.316598 -216.6112) (xy 452.716138 -216.6112) (xy 452.726262 -216.611694)
			(xy 452.744977 -216.619427) (xy 452.75933 -216.63371) (xy 452.767155 -216.652386) (xy 452.7677 -216.662508)
			(xy 452.7677 -217.071448) (xy 458.808836 -217.071448) (xy 458.808836 -216.662508) (xy 458.809229 -216.65235)
			(xy 458.817029 -216.633591) (xy 458.831435 -216.619266) (xy 458.850238 -216.611572) (xy 458.860398 -216.6112)
			(xy 460.259938 -216.6112) (xy 460.270062 -216.611694) (xy 460.288777 -216.619427) (xy 460.30313 -216.63371)
			(xy 460.310955 -216.652386) (xy 460.3115 -216.662508) (xy 460.3115 -217.071448) (xy 460.311118 -217.081605)
			(xy 460.303306 -217.100359) (xy 460.288898 -217.11468) (xy 460.270098 -217.122378) (xy 460.259938 -217.122756)
			(xy 458.860398 -217.122756) (xy 458.850271 -217.122275) (xy 458.831549 -217.114546) (xy 458.817192 -217.100258)
			(xy 458.809374 -217.081573) (xy 458.808836 -217.071448) (xy 452.7677 -217.071448) (xy 452.767318 -217.081605)
			(xy 452.759506 -217.100359) (xy 452.745098 -217.11468) (xy 452.726298 -217.122378) (xy 452.716138 -217.122756)
			(xy 451.316598 -217.122756) (xy 451.306471 -217.122275) (xy 451.287749 -217.114546) (xy 451.273392 -217.100258)
			(xy 451.265574 -217.081573) (xy 451.265036 -217.071448) (xy 445.2239 -217.071448) (xy 445.223518 -217.081605)
			(xy 445.215706 -217.100359) (xy 445.201298 -217.11468) (xy 445.182498 -217.122378) (xy 445.172338 -217.122756)
			(xy 443.772798 -217.122756) (xy 443.762671 -217.122275) (xy 443.743949 -217.114546) (xy 443.729592 -217.100258)
			(xy 443.721774 -217.081573) (xy 443.721236 -217.071448) (xy 437.6801 -217.071448) (xy 437.679718 -217.081605)
			(xy 437.671906 -217.100359) (xy 437.657498 -217.11468) (xy 437.638698 -217.122378) (xy 437.628538 -217.122756)
			(xy 436.228998 -217.122756) (xy 436.218871 -217.122275) (xy 436.200149 -217.114546) (xy 436.185792 -217.100258)
			(xy 436.177974 -217.081573) (xy 436.177436 -217.071448) (xy 430.1363 -217.071448) (xy 430.135918 -217.081605)
			(xy 430.128106 -217.100359) (xy 430.113698 -217.11468) (xy 430.094898 -217.122378) (xy 430.084738 -217.122756)
			(xy 428.685198 -217.122756) (xy 428.675071 -217.122275) (xy 428.656349 -217.114546) (xy 428.641992 -217.100258)
			(xy 428.634174 -217.081573) (xy 428.633636 -217.071448) (xy 422.5925 -217.071448) (xy 422.592118 -217.081605)
			(xy 422.584306 -217.100359) (xy 422.569898 -217.11468) (xy 422.551098 -217.122378) (xy 422.540938 -217.122756)
			(xy 421.141398 -217.122756) (xy 421.131271 -217.122275) (xy 421.112549 -217.114546) (xy 421.098192 -217.100258)
			(xy 421.090374 -217.081573) (xy 421.089836 -217.071448) (xy 415.0487 -217.071448) (xy 415.048318 -217.081605)
			(xy 415.040506 -217.100359) (xy 415.026098 -217.11468) (xy 415.007298 -217.122378) (xy 414.997138 -217.122756)
			(xy 413.597598 -217.122756) (xy 413.587471 -217.122275) (xy 413.568749 -217.114546) (xy 413.554392 -217.100258)
			(xy 413.546574 -217.081573) (xy 413.546036 -217.071448) (xy 407.5049 -217.071448) (xy 407.504518 -217.081605)
			(xy 407.496706 -217.100359) (xy 407.482298 -217.11468) (xy 407.463498 -217.122378) (xy 407.453338 -217.122756)
			(xy 406.053798 -217.122756) (xy 406.043671 -217.122275) (xy 406.024949 -217.114546) (xy 406.010592 -217.100258)
			(xy 406.002774 -217.081573) (xy 406.002236 -217.071448) (xy 381.995014 -217.071448) (xy 381.994559 -217.091989)
			(xy 381.985238 -217.146507) (xy 381.97663 -217.172794) (xy 381.96901 -217.194892) (xy 382.174242 -217.550238)
			(xy 382.197102 -217.554556) (xy 382.221903 -217.559751) (xy 382.269642 -217.57674) (xy 382.314219 -217.600833)
			(xy 382.354584 -217.631463) (xy 382.389788 -217.667908) (xy 382.419 -217.709312) (xy 382.441533 -217.754697)
			(xy 382.456856 -217.802996) (xy 382.464608 -217.85307) (xy 382.465072 -217.878406) (xy 382.464564 -217.904293)
			(xy 382.461865 -217.921332) (xy 410.102304 -217.921332) (xy 410.102304 -217.512392) (xy 410.102715 -217.502237)
			(xy 410.110514 -217.483484) (xy 410.124914 -217.46916) (xy 410.143709 -217.461462) (xy 410.153866 -217.461084)
			(xy 411.553406 -217.461084) (xy 411.563538 -217.461523) (xy 411.582268 -217.469261) (xy 411.596626 -217.483562)
			(xy 411.604437 -217.502262) (xy 411.604968 -217.512392) (xy 411.604968 -217.921332) (xy 417.646104 -217.921332)
			(xy 417.646104 -217.512392) (xy 417.646515 -217.502237) (xy 417.654314 -217.483484) (xy 417.668714 -217.46916)
			(xy 417.687509 -217.461462) (xy 417.697666 -217.461084) (xy 419.097206 -217.461084) (xy 419.107338 -217.461523)
			(xy 419.126068 -217.469261) (xy 419.140426 -217.483562) (xy 419.148237 -217.502262) (xy 419.148768 -217.512392)
			(xy 419.148768 -217.921332) (xy 425.189904 -217.921332) (xy 425.189904 -217.512392) (xy 425.190315 -217.502237)
			(xy 425.198114 -217.483484) (xy 425.212514 -217.46916) (xy 425.231309 -217.461462) (xy 425.241466 -217.461084)
			(xy 426.641006 -217.461084) (xy 426.651138 -217.461523) (xy 426.669868 -217.469261) (xy 426.684226 -217.483562)
			(xy 426.692037 -217.502262) (xy 426.692568 -217.512392) (xy 426.692568 -217.921332) (xy 432.733704 -217.921332)
			(xy 432.733704 -217.512392) (xy 432.734115 -217.502237) (xy 432.741914 -217.483484) (xy 432.756314 -217.46916)
			(xy 432.775109 -217.461462) (xy 432.785266 -217.461084) (xy 434.184806 -217.461084) (xy 434.194938 -217.461523)
			(xy 434.213668 -217.469261) (xy 434.228026 -217.483562) (xy 434.235837 -217.502262) (xy 434.236368 -217.512392)
			(xy 434.236368 -217.921332) (xy 440.277504 -217.921332) (xy 440.277504 -217.512392) (xy 440.277915 -217.502237)
			(xy 440.285714 -217.483484) (xy 440.300114 -217.46916) (xy 440.318909 -217.461462) (xy 440.329066 -217.461084)
			(xy 441.728606 -217.461084) (xy 441.738738 -217.461523) (xy 441.757468 -217.469261) (xy 441.771826 -217.483562)
			(xy 441.779637 -217.502262) (xy 441.780168 -217.512392) (xy 441.780168 -217.921332) (xy 447.821304 -217.921332)
			(xy 447.821304 -217.512392) (xy 447.821715 -217.502237) (xy 447.829514 -217.483484) (xy 447.843914 -217.46916)
			(xy 447.862709 -217.461462) (xy 447.872866 -217.461084) (xy 449.272406 -217.461084) (xy 449.282538 -217.461523)
			(xy 449.301268 -217.469261) (xy 449.315626 -217.483562) (xy 449.323437 -217.502262) (xy 449.323968 -217.512392)
			(xy 449.323968 -217.921332) (xy 455.365104 -217.921332) (xy 455.365104 -217.512392) (xy 455.365515 -217.502237)
			(xy 455.373314 -217.483484) (xy 455.387714 -217.46916) (xy 455.406509 -217.461462) (xy 455.416666 -217.461084)
			(xy 456.816206 -217.461084) (xy 456.826338 -217.461523) (xy 456.845068 -217.469261) (xy 456.859426 -217.483562)
			(xy 456.867237 -217.502262) (xy 456.867768 -217.512392) (xy 456.867768 -217.921332) (xy 462.908904 -217.921332)
			(xy 462.908904 -217.512392) (xy 462.909315 -217.502237) (xy 462.917114 -217.483484) (xy 462.931514 -217.46916)
			(xy 462.950309 -217.461462) (xy 462.960466 -217.461084) (xy 464.360006 -217.461084) (xy 464.370138 -217.461523)
			(xy 464.388868 -217.469261) (xy 464.403226 -217.483562) (xy 464.411037 -217.502262) (xy 464.411568 -217.512392)
			(xy 464.411568 -217.921332) (xy 464.411204 -217.931492) (xy 464.403392 -217.950252) (xy 464.388977 -217.964575)
			(xy 464.370169 -217.972268) (xy 464.360006 -217.97264) (xy 462.960466 -217.97264) (xy 462.950335 -217.972201)
			(xy 462.931609 -217.964458) (xy 462.917253 -217.950157) (xy 462.909439 -217.931461) (xy 462.908904 -217.921332)
			(xy 456.867768 -217.921332) (xy 456.867404 -217.931492) (xy 456.859592 -217.950252) (xy 456.845177 -217.964575)
			(xy 456.826369 -217.972268) (xy 456.816206 -217.97264) (xy 455.416666 -217.97264) (xy 455.406535 -217.972201)
			(xy 455.387809 -217.964458) (xy 455.373453 -217.950157) (xy 455.365639 -217.931461) (xy 455.365104 -217.921332)
			(xy 449.323968 -217.921332) (xy 449.323604 -217.931492) (xy 449.315792 -217.950252) (xy 449.301377 -217.964575)
			(xy 449.282569 -217.972268) (xy 449.272406 -217.97264) (xy 447.872866 -217.97264) (xy 447.862735 -217.972201)
			(xy 447.844009 -217.964458) (xy 447.829653 -217.950157) (xy 447.821839 -217.931461) (xy 447.821304 -217.921332)
			(xy 441.780168 -217.921332) (xy 441.779804 -217.931492) (xy 441.771992 -217.950252) (xy 441.757577 -217.964575)
			(xy 441.738769 -217.972268) (xy 441.728606 -217.97264) (xy 440.329066 -217.97264) (xy 440.318935 -217.972201)
			(xy 440.300209 -217.964458) (xy 440.285853 -217.950157) (xy 440.278039 -217.931461) (xy 440.277504 -217.921332)
			(xy 434.236368 -217.921332) (xy 434.236004 -217.931492) (xy 434.228192 -217.950252) (xy 434.213777 -217.964575)
			(xy 434.194969 -217.972268) (xy 434.184806 -217.97264) (xy 432.785266 -217.97264) (xy 432.775135 -217.972201)
			(xy 432.756409 -217.964458) (xy 432.742053 -217.950157) (xy 432.734239 -217.931461) (xy 432.733704 -217.921332)
			(xy 426.692568 -217.921332) (xy 426.692204 -217.931492) (xy 426.684392 -217.950252) (xy 426.669977 -217.964575)
			(xy 426.651169 -217.972268) (xy 426.641006 -217.97264) (xy 425.241466 -217.97264) (xy 425.231335 -217.972201)
			(xy 425.212609 -217.964458) (xy 425.198253 -217.950157) (xy 425.190439 -217.931461) (xy 425.189904 -217.921332)
			(xy 419.148768 -217.921332) (xy 419.148404 -217.931492) (xy 419.140592 -217.950252) (xy 419.126177 -217.964575)
			(xy 419.107369 -217.972268) (xy 419.097206 -217.97264) (xy 417.697666 -217.97264) (xy 417.687535 -217.972201)
			(xy 417.668809 -217.964458) (xy 417.654453 -217.950157) (xy 417.646639 -217.931461) (xy 417.646104 -217.921332)
			(xy 411.604968 -217.921332) (xy 411.604604 -217.931492) (xy 411.596792 -217.950252) (xy 411.582377 -217.964575)
			(xy 411.563569 -217.972268) (xy 411.553406 -217.97264) (xy 410.153866 -217.97264) (xy 410.143735 -217.972201)
			(xy 410.125009 -217.964458) (xy 410.110653 -217.950157) (xy 410.102839 -217.931461) (xy 410.102304 -217.921332)
			(xy 382.461865 -217.921332) (xy 382.456465 -217.955431) (xy 382.440466 -218.004671) (xy 382.41696 -218.050803)
			(xy 382.386528 -218.09269) (xy 382.349918 -218.1293) (xy 382.308031 -218.159732) (xy 382.261899 -218.183238)
			(xy 382.212659 -218.199237) (xy 382.161521 -218.207336) (xy 382.109747 -218.207336) (xy 382.058609 -218.199237)
			(xy 382.009369 -218.183238) (xy 381.963237 -218.159732) (xy 381.92135 -218.1293) (xy 381.88474 -218.09269)
			(xy 381.854308 -218.050803) (xy 381.830802 -218.004671) (xy 381.814803 -217.955431) (xy 381.806704 -217.904293)
			(xy 381.806196 -217.878406) (xy 381.806727 -217.850698) (xy 381.815921 -217.796051) (xy 381.824484 -217.769694)
			(xy 381.832358 -217.747596) (xy 381.62738 -217.392504) (xy 381.60452 -217.388186) (xy 381.579675 -217.38302)
			(xy 381.531826 -217.366126) (xy 381.487133 -217.342096) (xy 381.446653 -217.311499) (xy 381.411341 -217.275058)
			(xy 381.382033 -217.233634) (xy 381.359422 -217.188207) (xy 381.344043 -217.13985) (xy 381.336258 -217.089708)
			(xy 381.335788 -217.064336) (xy 380.115572 -217.064336) (xy 380.114959 -217.091989) (xy 380.105638 -217.146507)
			(xy 380.09703 -217.172794) (xy 380.08941 -217.194892) (xy 380.294642 -217.550238) (xy 380.317502 -217.554556)
			(xy 380.342303 -217.559751) (xy 380.390042 -217.57674) (xy 380.434619 -217.600833) (xy 380.474984 -217.631463)
			(xy 380.510188 -217.667908) (xy 380.5394 -217.709312) (xy 380.561933 -217.754697) (xy 380.577256 -217.802996)
			(xy 380.585008 -217.85307) (xy 380.585472 -217.878406) (xy 380.584964 -217.904293) (xy 380.576865 -217.955431)
			(xy 380.560866 -218.004671) (xy 380.53736 -218.050803) (xy 380.506928 -218.09269) (xy 380.470318 -218.1293)
			(xy 380.428431 -218.159732) (xy 380.382299 -218.183238) (xy 380.333059 -218.199237) (xy 380.281921 -218.207336)
			(xy 380.230147 -218.207336) (xy 380.179009 -218.199237) (xy 380.129769 -218.183238) (xy 380.083637 -218.159732)
			(xy 380.04175 -218.1293) (xy 380.00514 -218.09269) (xy 379.974708 -218.050803) (xy 379.951202 -218.004671)
			(xy 379.935203 -217.955431) (xy 379.927104 -217.904293) (xy 379.926596 -217.878406) (xy 379.927127 -217.850698)
			(xy 379.936321 -217.796051) (xy 379.944884 -217.769694) (xy 379.952758 -217.747596) (xy 379.74778 -217.392504)
			(xy 379.72492 -217.388186) (xy 379.700075 -217.38302) (xy 379.652226 -217.366126) (xy 379.607533 -217.342096)
			(xy 379.567053 -217.311499) (xy 379.531741 -217.275058) (xy 379.502433 -217.233634) (xy 379.479822 -217.188207)
			(xy 379.464443 -217.13985) (xy 379.456658 -217.089708) (xy 379.456188 -217.064336) (xy 378.235972 -217.064336)
			(xy 378.235359 -217.091989) (xy 378.226038 -217.146507) (xy 378.21743 -217.172794) (xy 378.20981 -217.194892)
			(xy 378.415042 -217.550238) (xy 378.437902 -217.554556) (xy 378.462703 -217.559751) (xy 378.510442 -217.57674)
			(xy 378.555019 -217.600833) (xy 378.595384 -217.631463) (xy 378.630588 -217.667908) (xy 378.6598 -217.709312)
			(xy 378.682333 -217.754697) (xy 378.697656 -217.802996) (xy 378.705408 -217.85307) (xy 378.705872 -217.878406)
			(xy 378.705364 -217.904293) (xy 378.697265 -217.955431) (xy 378.681266 -218.004671) (xy 378.65776 -218.050803)
			(xy 378.627328 -218.09269) (xy 378.590718 -218.1293) (xy 378.548831 -218.159732) (xy 378.502699 -218.183238)
			(xy 378.453459 -218.199237) (xy 378.402321 -218.207336) (xy 378.350547 -218.207336) (xy 378.299409 -218.199237)
			(xy 378.250169 -218.183238) (xy 378.204037 -218.159732) (xy 378.16215 -218.1293) (xy 378.12554 -218.09269)
			(xy 378.095108 -218.050803) (xy 378.071602 -218.004671) (xy 378.055603 -217.955431) (xy 378.047504 -217.904293)
			(xy 378.046996 -217.878406) (xy 378.047527 -217.850698) (xy 378.056721 -217.796051) (xy 378.065284 -217.769694)
			(xy 378.073158 -217.747596) (xy 377.86818 -217.392504) (xy 377.84532 -217.388186) (xy 377.820475 -217.38302)
			(xy 377.772626 -217.366126) (xy 377.727933 -217.342096) (xy 377.687453 -217.311499) (xy 377.652141 -217.275058)
			(xy 377.622833 -217.233634) (xy 377.600222 -217.188207) (xy 377.584843 -217.13985) (xy 377.577058 -217.089708)
			(xy 377.576588 -217.064336) (xy 376.356372 -217.064336) (xy 376.355759 -217.091989) (xy 376.346438 -217.146507)
			(xy 376.33783 -217.172794) (xy 376.33021 -217.194892) (xy 376.535442 -217.550238) (xy 376.558302 -217.554556)
			(xy 376.583103 -217.559751) (xy 376.630842 -217.57674) (xy 376.675419 -217.600833) (xy 376.715784 -217.631463)
			(xy 376.750988 -217.667908) (xy 376.7802 -217.709312) (xy 376.802733 -217.754697) (xy 376.818056 -217.802996)
			(xy 376.825808 -217.85307) (xy 376.826272 -217.878406) (xy 376.825764 -217.904293) (xy 376.817665 -217.955431)
			(xy 376.801666 -218.004671) (xy 376.77816 -218.050803) (xy 376.747728 -218.09269) (xy 376.711118 -218.1293)
			(xy 376.669231 -218.159732) (xy 376.623099 -218.183238) (xy 376.573859 -218.199237) (xy 376.522721 -218.207336)
			(xy 376.470947 -218.207336) (xy 376.419809 -218.199237) (xy 376.370569 -218.183238) (xy 376.324437 -218.159732)
			(xy 376.28255 -218.1293) (xy 376.24594 -218.09269) (xy 376.215508 -218.050803) (xy 376.192002 -218.004671)
			(xy 376.176003 -217.955431) (xy 376.167904 -217.904293) (xy 376.167396 -217.878406) (xy 376.167927 -217.850698)
			(xy 376.177121 -217.796051) (xy 376.185684 -217.769694) (xy 376.193558 -217.747596) (xy 375.98858 -217.392504)
			(xy 375.96572 -217.388186) (xy 375.940875 -217.38302) (xy 375.893026 -217.366126) (xy 375.848333 -217.342096)
			(xy 375.807853 -217.311499) (xy 375.772541 -217.275058) (xy 375.743233 -217.233634) (xy 375.720622 -217.188207)
			(xy 375.705243 -217.13985) (xy 375.697458 -217.089708) (xy 375.696988 -217.064336) (xy 374.476772 -217.064336)
			(xy 374.476159 -217.091989) (xy 374.466838 -217.146507) (xy 374.45823 -217.172794) (xy 374.45061 -217.194892)
			(xy 374.655842 -217.550238) (xy 374.678702 -217.554556) (xy 374.703503 -217.559751) (xy 374.751242 -217.57674)
			(xy 374.795819 -217.600833) (xy 374.836184 -217.631463) (xy 374.871388 -217.667908) (xy 374.9006 -217.709312)
			(xy 374.923133 -217.754697) (xy 374.938456 -217.802996) (xy 374.946208 -217.85307) (xy 374.946672 -217.878406)
			(xy 374.946164 -217.904293) (xy 374.938065 -217.955431) (xy 374.922066 -218.004671) (xy 374.89856 -218.050803)
			(xy 374.868128 -218.09269) (xy 374.831518 -218.1293) (xy 374.789631 -218.159732) (xy 374.743499 -218.183238)
			(xy 374.694259 -218.199237) (xy 374.643121 -218.207336) (xy 374.591347 -218.207336) (xy 374.540209 -218.199237)
			(xy 374.490969 -218.183238) (xy 374.444837 -218.159732) (xy 374.40295 -218.1293) (xy 374.36634 -218.09269)
			(xy 374.335908 -218.050803) (xy 374.312402 -218.004671) (xy 374.296403 -217.955431) (xy 374.288304 -217.904293)
			(xy 374.287796 -217.878406) (xy 374.288327 -217.850698) (xy 374.297521 -217.796051) (xy 374.306084 -217.769694)
			(xy 374.313958 -217.747596) (xy 374.10898 -217.392504) (xy 374.08612 -217.388186) (xy 374.061275 -217.38302)
			(xy 374.013426 -217.366126) (xy 373.968733 -217.342096) (xy 373.928253 -217.311499) (xy 373.892941 -217.275058)
			(xy 373.863633 -217.233634) (xy 373.841022 -217.188207) (xy 373.825643 -217.13985) (xy 373.817858 -217.089708)
			(xy 373.817388 -217.064336) (xy 372.597172 -217.064336) (xy 372.596559 -217.091989) (xy 372.587238 -217.146507)
			(xy 372.57863 -217.172794) (xy 372.57101 -217.194892) (xy 372.776242 -217.550238) (xy 372.799102 -217.554556)
			(xy 372.823903 -217.559751) (xy 372.871642 -217.57674) (xy 372.916219 -217.600833) (xy 372.956584 -217.631463)
			(xy 372.991788 -217.667908) (xy 373.021 -217.709312) (xy 373.043533 -217.754697) (xy 373.058856 -217.802996)
			(xy 373.066608 -217.85307) (xy 373.067072 -217.878406) (xy 373.066564 -217.904293) (xy 373.058465 -217.955431)
			(xy 373.042466 -218.004671) (xy 373.01896 -218.050803) (xy 372.988528 -218.09269) (xy 372.951918 -218.1293)
			(xy 372.910031 -218.159732) (xy 372.863899 -218.183238) (xy 372.814659 -218.199237) (xy 372.763521 -218.207336)
			(xy 372.711747 -218.207336) (xy 372.660609 -218.199237) (xy 372.611369 -218.183238) (xy 372.565237 -218.159732)
			(xy 372.52335 -218.1293) (xy 372.48674 -218.09269) (xy 372.456308 -218.050803) (xy 372.432802 -218.004671)
			(xy 372.416803 -217.955431) (xy 372.408704 -217.904293) (xy 372.408196 -217.878406) (xy 372.408727 -217.850698)
			(xy 372.417921 -217.796051) (xy 372.426484 -217.769694) (xy 372.434358 -217.747596) (xy 372.22938 -217.392504)
			(xy 372.20652 -217.388186) (xy 372.181675 -217.38302) (xy 372.133826 -217.366126) (xy 372.089133 -217.342096)
			(xy 372.048653 -217.311499) (xy 372.013341 -217.275058) (xy 371.984033 -217.233634) (xy 371.961422 -217.188207)
			(xy 371.946043 -217.13985) (xy 371.938258 -217.089708) (xy 371.937788 -217.064336) (xy 370.717572 -217.064336)
			(xy 370.716959 -217.091989) (xy 370.707638 -217.146507) (xy 370.69903 -217.172794) (xy 370.69141 -217.194892)
			(xy 370.896642 -217.550238) (xy 370.919502 -217.554556) (xy 370.944303 -217.559751) (xy 370.992042 -217.57674)
			(xy 371.036619 -217.600833) (xy 371.076984 -217.631463) (xy 371.112188 -217.667908) (xy 371.1414 -217.709312)
			(xy 371.163933 -217.754697) (xy 371.179256 -217.802996) (xy 371.187008 -217.85307) (xy 371.187472 -217.878406)
			(xy 371.186964 -217.904293) (xy 371.178865 -217.955431) (xy 371.162866 -218.004671) (xy 371.13936 -218.050803)
			(xy 371.108928 -218.09269) (xy 371.072318 -218.1293) (xy 371.030431 -218.159732) (xy 370.984299 -218.183238)
			(xy 370.935059 -218.199237) (xy 370.883921 -218.207336) (xy 370.832147 -218.207336) (xy 370.781009 -218.199237)
			(xy 370.731769 -218.183238) (xy 370.685637 -218.159732) (xy 370.64375 -218.1293) (xy 370.60714 -218.09269)
			(xy 370.576708 -218.050803) (xy 370.553202 -218.004671) (xy 370.537203 -217.955431) (xy 370.529104 -217.904293)
			(xy 370.528596 -217.878406) (xy 370.529127 -217.850698) (xy 370.538321 -217.796051) (xy 370.546884 -217.769694)
			(xy 370.554758 -217.747596) (xy 370.34978 -217.392504) (xy 370.32692 -217.388186) (xy 370.302075 -217.38302)
			(xy 370.254226 -217.366126) (xy 370.209533 -217.342096) (xy 370.169053 -217.311499) (xy 370.133741 -217.275058)
			(xy 370.104433 -217.233634) (xy 370.081822 -217.188207) (xy 370.066443 -217.13985) (xy 370.058658 -217.089708)
			(xy 370.058188 -217.064336) (xy 368.837972 -217.064336) (xy 368.837359 -217.091989) (xy 368.828038 -217.146507)
			(xy 368.81943 -217.172794) (xy 368.81181 -217.194892) (xy 369.017042 -217.550238) (xy 369.039902 -217.554556)
			(xy 369.064703 -217.559751) (xy 369.112442 -217.57674) (xy 369.157019 -217.600833) (xy 369.197384 -217.631463)
			(xy 369.232588 -217.667908) (xy 369.2618 -217.709312) (xy 369.284333 -217.754697) (xy 369.299656 -217.802996)
			(xy 369.307408 -217.85307) (xy 369.307872 -217.878406) (xy 369.307364 -217.904293) (xy 369.299265 -217.955431)
			(xy 369.283266 -218.004671) (xy 369.25976 -218.050803) (xy 369.229328 -218.09269) (xy 369.192718 -218.1293)
			(xy 369.150831 -218.159732) (xy 369.104699 -218.183238) (xy 369.055459 -218.199237) (xy 369.004321 -218.207336)
			(xy 368.952547 -218.207336) (xy 368.901409 -218.199237) (xy 368.852169 -218.183238) (xy 368.806037 -218.159732)
			(xy 368.76415 -218.1293) (xy 368.72754 -218.09269) (xy 368.697108 -218.050803) (xy 368.673602 -218.004671)
			(xy 368.657603 -217.955431) (xy 368.649504 -217.904293) (xy 368.648996 -217.878406) (xy 368.649527 -217.850698)
			(xy 368.658721 -217.796051) (xy 368.667284 -217.769694) (xy 368.675158 -217.747596) (xy 368.47018 -217.392504)
			(xy 368.44732 -217.388186) (xy 368.422475 -217.38302) (xy 368.374626 -217.366126) (xy 368.329933 -217.342096)
			(xy 368.289453 -217.311499) (xy 368.254141 -217.275058) (xy 368.224833 -217.233634) (xy 368.202222 -217.188207)
			(xy 368.186843 -217.13985) (xy 368.179058 -217.089708) (xy 368.178588 -217.064336) (xy 366.958372 -217.064336)
			(xy 366.957759 -217.091989) (xy 366.948438 -217.146507) (xy 366.93983 -217.172794) (xy 366.93221 -217.194892)
			(xy 367.137442 -217.550238) (xy 367.160302 -217.554556) (xy 367.185103 -217.559751) (xy 367.232842 -217.57674)
			(xy 367.277419 -217.600833) (xy 367.317784 -217.631463) (xy 367.352988 -217.667908) (xy 367.3822 -217.709312)
			(xy 367.404733 -217.754697) (xy 367.420056 -217.802996) (xy 367.427808 -217.85307) (xy 367.428272 -217.878406)
			(xy 367.427764 -217.904293) (xy 367.419665 -217.955431) (xy 367.403666 -218.004671) (xy 367.38016 -218.050803)
			(xy 367.349728 -218.09269) (xy 367.313118 -218.1293) (xy 367.271231 -218.159732) (xy 367.225099 -218.183238)
			(xy 367.175859 -218.199237) (xy 367.124721 -218.207336) (xy 367.072947 -218.207336) (xy 367.021809 -218.199237)
			(xy 366.972569 -218.183238) (xy 366.926437 -218.159732) (xy 366.88455 -218.1293) (xy 366.84794 -218.09269)
			(xy 366.817508 -218.050803) (xy 366.794002 -218.004671) (xy 366.778003 -217.955431) (xy 366.769904 -217.904293)
			(xy 366.769396 -217.878406) (xy 366.769927 -217.850698) (xy 366.779121 -217.796051) (xy 366.787684 -217.769694)
			(xy 366.795558 -217.747596) (xy 366.59058 -217.392504) (xy 366.56772 -217.388186) (xy 366.542875 -217.38302)
			(xy 366.495026 -217.366126) (xy 366.450333 -217.342096) (xy 366.409853 -217.311499) (xy 366.374541 -217.275058)
			(xy 366.345233 -217.233634) (xy 366.322622 -217.188207) (xy 366.307243 -217.13985) (xy 366.299458 -217.089708)
			(xy 366.298988 -217.064336) (xy 365.078772 -217.064336) (xy 365.078159 -217.091989) (xy 365.068838 -217.146507)
			(xy 365.06023 -217.172794) (xy 365.05261 -217.194892) (xy 365.257842 -217.550238) (xy 365.280702 -217.554556)
			(xy 365.305503 -217.559751) (xy 365.353242 -217.57674) (xy 365.397819 -217.600833) (xy 365.438184 -217.631463)
			(xy 365.473388 -217.667908) (xy 365.5026 -217.709312) (xy 365.525133 -217.754697) (xy 365.540456 -217.802996)
			(xy 365.548208 -217.85307) (xy 365.548672 -217.878406) (xy 365.548164 -217.904293) (xy 365.540065 -217.955431)
			(xy 365.524066 -218.004671) (xy 365.50056 -218.050803) (xy 365.470128 -218.09269) (xy 365.433518 -218.1293)
			(xy 365.391631 -218.159732) (xy 365.345499 -218.183238) (xy 365.296259 -218.199237) (xy 365.245121 -218.207336)
			(xy 365.193347 -218.207336) (xy 365.142209 -218.199237) (xy 365.092969 -218.183238) (xy 365.046837 -218.159732)
			(xy 365.00495 -218.1293) (xy 364.96834 -218.09269) (xy 364.937908 -218.050803) (xy 364.914402 -218.004671)
			(xy 364.898403 -217.955431) (xy 364.890304 -217.904293) (xy 364.889796 -217.878406) (xy 364.890327 -217.850698)
			(xy 364.899521 -217.796051) (xy 364.908084 -217.769694) (xy 364.915958 -217.747596) (xy 364.71098 -217.392504)
			(xy 364.68812 -217.388186) (xy 364.663275 -217.38302) (xy 364.615426 -217.366126) (xy 364.570733 -217.342096)
			(xy 364.530253 -217.311499) (xy 364.494941 -217.275058) (xy 364.465633 -217.233634) (xy 364.443022 -217.188207)
			(xy 364.427643 -217.13985) (xy 364.419858 -217.089708) (xy 364.419388 -217.064336) (xy 363.199172 -217.064336)
			(xy 363.198559 -217.091989) (xy 363.189238 -217.146507) (xy 363.18063 -217.172794) (xy 363.17301 -217.194892)
			(xy 363.378242 -217.550238) (xy 363.401102 -217.554556) (xy 363.425903 -217.559751) (xy 363.473642 -217.57674)
			(xy 363.518219 -217.600833) (xy 363.558584 -217.631463) (xy 363.593788 -217.667908) (xy 363.623 -217.709312)
			(xy 363.645533 -217.754697) (xy 363.660856 -217.802996) (xy 363.668608 -217.85307) (xy 363.669072 -217.878406)
			(xy 363.668564 -217.904293) (xy 363.660465 -217.955431) (xy 363.644466 -218.004671) (xy 363.62096 -218.050803)
			(xy 363.590528 -218.09269) (xy 363.553918 -218.1293) (xy 363.512031 -218.159732) (xy 363.465899 -218.183238)
			(xy 363.416659 -218.199237) (xy 363.365521 -218.207336) (xy 363.313747 -218.207336) (xy 363.262609 -218.199237)
			(xy 363.213369 -218.183238) (xy 363.167237 -218.159732) (xy 363.12535 -218.1293) (xy 363.08874 -218.09269)
			(xy 363.058308 -218.050803) (xy 363.034802 -218.004671) (xy 363.018803 -217.955431) (xy 363.010704 -217.904293)
			(xy 363.010196 -217.878406) (xy 363.010727 -217.850698) (xy 363.019921 -217.796051) (xy 363.028484 -217.769694)
			(xy 363.036358 -217.747596) (xy 362.83138 -217.392504) (xy 362.80852 -217.388186) (xy 362.783675 -217.38302)
			(xy 362.735826 -217.366126) (xy 362.691133 -217.342096) (xy 362.650653 -217.311499) (xy 362.615341 -217.275058)
			(xy 362.586033 -217.233634) (xy 362.563422 -217.188207) (xy 362.548043 -217.13985) (xy 362.540258 -217.089708)
			(xy 362.539788 -217.064336) (xy 361.319572 -217.064336) (xy 361.318959 -217.091989) (xy 361.309638 -217.146507)
			(xy 361.30103 -217.172794) (xy 361.29341 -217.194892) (xy 361.498642 -217.550238) (xy 361.521502 -217.554556)
			(xy 361.546303 -217.559751) (xy 361.594042 -217.57674) (xy 361.638619 -217.600833) (xy 361.678984 -217.631463)
			(xy 361.714188 -217.667908) (xy 361.7434 -217.709312) (xy 361.765933 -217.754697) (xy 361.781256 -217.802996)
			(xy 361.789008 -217.85307) (xy 361.789472 -217.878406) (xy 361.788964 -217.904293) (xy 361.780865 -217.955431)
			(xy 361.764866 -218.004671) (xy 361.74136 -218.050803) (xy 361.710928 -218.09269) (xy 361.674318 -218.1293)
			(xy 361.632431 -218.159732) (xy 361.586299 -218.183238) (xy 361.537059 -218.199237) (xy 361.485921 -218.207336)
			(xy 361.434147 -218.207336) (xy 361.383009 -218.199237) (xy 361.333769 -218.183238) (xy 361.287637 -218.159732)
			(xy 361.24575 -218.1293) (xy 361.20914 -218.09269) (xy 361.178708 -218.050803) (xy 361.155202 -218.004671)
			(xy 361.139203 -217.955431) (xy 361.131104 -217.904293) (xy 361.130596 -217.878406) (xy 361.131127 -217.850698)
			(xy 361.140321 -217.796051) (xy 361.148884 -217.769694) (xy 361.156758 -217.747596) (xy 360.95178 -217.392504)
			(xy 360.92892 -217.388186) (xy 360.904075 -217.38302) (xy 360.856226 -217.366126) (xy 360.811533 -217.342096)
			(xy 360.771053 -217.311499) (xy 360.735741 -217.275058) (xy 360.706433 -217.233634) (xy 360.683822 -217.188207)
			(xy 360.668443 -217.13985) (xy 360.660658 -217.089708) (xy 360.660188 -217.064336) (xy 359.439972 -217.064336)
			(xy 359.439506 -217.089682) (xy 359.431728 -217.139773) (xy 359.416377 -217.188085) (xy 359.393813 -217.233478)
			(xy 359.364569 -217.274884) (xy 359.329334 -217.311328) (xy 359.288936 -217.34195) (xy 359.244329 -217.36603)
			(xy 359.196562 -217.383) (xy 359.171748 -217.388186) (xy 359.148888 -217.392504) (xy 358.94391 -217.747596)
			(xy 358.951784 -217.76944) (xy 358.960373 -217.795856) (xy 358.969563 -217.850633) (xy 358.970072 -217.878406)
			(xy 358.969564 -217.904293) (xy 358.961465 -217.955431) (xy 358.945466 -218.004671) (xy 358.92196 -218.050803)
			(xy 358.891528 -218.09269) (xy 358.854918 -218.1293) (xy 358.813031 -218.159732) (xy 358.766899 -218.183238)
			(xy 358.717659 -218.199237) (xy 358.666521 -218.207336) (xy 358.614747 -218.207336) (xy 358.563609 -218.199237)
			(xy 358.514369 -218.183238) (xy 358.468237 -218.159732) (xy 358.42635 -218.1293) (xy 358.38974 -218.09269)
			(xy 358.359308 -218.050803) (xy 358.335802 -218.004671) (xy 358.319803 -217.955431) (xy 358.311704 -217.904293)
			(xy 358.311196 -217.878406) (xy 358.030272 -217.878406) (xy 358.029741 -217.906114) (xy 358.020546 -217.960761)
			(xy 358.011984 -217.987118) (xy 358.004364 -218.008962) (xy 358.209342 -218.364054) (xy 358.232202 -218.368372)
			(xy 358.257007 -218.373552) (xy 358.304747 -218.390542) (xy 358.349324 -218.414636) (xy 358.38969 -218.445268)
			(xy 358.424894 -218.481716) (xy 358.454106 -218.523121) (xy 358.476638 -218.568508) (xy 358.491959 -218.616809)
			(xy 358.49971 -218.666886) (xy 358.500172 -218.692222) (xy 359.720388 -218.692222) (xy 359.720939 -218.66688)
			(xy 359.728707 -218.616793) (xy 359.744048 -218.568485) (xy 359.766601 -218.523094) (xy 359.795834 -218.481689)
			(xy 359.831059 -218.445245) (xy 359.871446 -218.41462) (xy 359.916044 -218.390537) (xy 359.963802 -218.373561)
			(xy 359.988612 -218.368372) (xy 360.011472 -218.364054) (xy 360.216704 -218.008708) (xy 360.20883 -217.98661)
			(xy 360.200361 -217.960367) (xy 360.191292 -217.905977) (xy 360.190796 -217.878406) (xy 360.191304 -217.852519)
			(xy 360.199403 -217.801381) (xy 360.215402 -217.752141) (xy 360.238908 -217.706009) (xy 360.26934 -217.664122)
			(xy 360.30595 -217.627512) (xy 360.347837 -217.59708) (xy 360.393969 -217.573574) (xy 360.443209 -217.557575)
			(xy 360.494347 -217.549476) (xy 360.546121 -217.549476) (xy 360.597259 -217.557575) (xy 360.646499 -217.573574)
			(xy 360.692631 -217.59708) (xy 360.734518 -217.627512) (xy 360.771128 -217.664122) (xy 360.80156 -217.706009)
			(xy 360.825066 -217.752141) (xy 360.841065 -217.801381) (xy 360.849164 -217.852519) (xy 360.849672 -217.878406)
			(xy 360.849225 -217.903782) (xy 360.841455 -217.953934) (xy 360.826085 -218.002302) (xy 360.803477 -218.047739)
			(xy 360.774167 -218.089171) (xy 360.73885 -218.125617) (xy 360.69836 -218.156215) (xy 360.653656 -218.18024)
			(xy 360.605796 -218.197124) (xy 360.58094 -218.202256) (xy 360.55808 -218.206574) (xy 360.353356 -218.561412)
			(xy 360.36123 -218.583256) (xy 360.369881 -218.609663) (xy 360.379198 -218.66444) (xy 360.379772 -218.692222)
			(xy 361.600496 -218.692222) (xy 361.601002 -218.666888) (xy 361.608751 -218.616817) (xy 361.62407 -218.568521)
			(xy 361.646599 -218.523138) (xy 361.675805 -218.481736) (xy 361.711003 -218.44529) (xy 361.751363 -218.414659)
			(xy 361.795934 -218.390564) (xy 361.843667 -218.373572) (xy 361.868466 -218.368372) (xy 361.891326 -218.364054)
			(xy 362.096304 -218.008962) (xy 362.088684 -217.986864) (xy 362.080159 -217.960694) (xy 362.070969 -217.906431)
			(xy 362.070396 -217.878914) (xy 362.070396 -217.878406) (xy 362.070904 -217.852519) (xy 362.079003 -217.801381)
			(xy 362.095002 -217.752141) (xy 362.118508 -217.706009) (xy 362.14894 -217.664122) (xy 362.18555 -217.627512)
			(xy 362.227437 -217.59708) (xy 362.273569 -217.573574) (xy 362.322809 -217.557575) (xy 362.373947 -217.549476)
			(xy 362.425721 -217.549476) (xy 362.476859 -217.557575) (xy 362.526099 -217.573574) (xy 362.572231 -217.59708)
			(xy 362.614118 -217.627512) (xy 362.650728 -217.664122) (xy 362.68116 -217.706009) (xy 362.704666 -217.752141)
			(xy 362.720665 -217.801381) (xy 362.728764 -217.852519) (xy 362.729272 -217.878406) (xy 362.728863 -217.903772)
			(xy 362.721112 -217.953909) (xy 362.705764 -218.002264) (xy 362.683182 -218.047694) (xy 362.6539 -218.089122)
			(xy 362.61861 -218.12557) (xy 362.578149 -218.156175) (xy 362.533472 -218.180212) (xy 362.485638 -218.197113)
			(xy 362.460794 -218.202256) (xy 362.437934 -218.206574) (xy 362.23321 -218.561412) (xy 362.241084 -218.583256)
			(xy 362.249677 -218.609671) (xy 362.258865 -218.664449) (xy 362.259372 -218.692222) (xy 363.479588 -218.692222)
			(xy 363.480139 -218.66688) (xy 363.487907 -218.616793) (xy 363.503248 -218.568485) (xy 363.525801 -218.523094)
			(xy 363.555034 -218.481689) (xy 363.590259 -218.445245) (xy 363.630646 -218.41462) (xy 363.675244 -218.390537)
			(xy 363.723002 -218.373561) (xy 363.747812 -218.368372) (xy 363.770672 -218.364054) (xy 363.975904 -218.008708)
			(xy 363.96803 -217.98661) (xy 363.959561 -217.960367) (xy 363.950492 -217.905977) (xy 363.949996 -217.878406)
			(xy 363.950504 -217.852519) (xy 363.958603 -217.801381) (xy 363.974602 -217.752141) (xy 363.998108 -217.706009)
			(xy 364.02854 -217.664122) (xy 364.06515 -217.627512) (xy 364.107037 -217.59708) (xy 364.153169 -217.573574)
			(xy 364.202409 -217.557575) (xy 364.253547 -217.549476) (xy 364.305321 -217.549476) (xy 364.356459 -217.557575)
			(xy 364.405699 -217.573574) (xy 364.451831 -217.59708) (xy 364.493718 -217.627512) (xy 364.530328 -217.664122)
			(xy 364.56076 -217.706009) (xy 364.584266 -217.752141) (xy 364.600265 -217.801381) (xy 364.608364 -217.852519)
			(xy 364.608872 -217.878406) (xy 364.608425 -217.903782) (xy 364.600655 -217.953934) (xy 364.585285 -218.002302)
			(xy 364.562677 -218.047739) (xy 364.533367 -218.089171) (xy 364.49805 -218.125617) (xy 364.45756 -218.156215)
			(xy 364.412856 -218.18024) (xy 364.364996 -218.197124) (xy 364.34014 -218.202256) (xy 364.31728 -218.206574)
			(xy 364.112556 -218.561412) (xy 364.12043 -218.583256) (xy 364.129081 -218.609663) (xy 364.138398 -218.66444)
			(xy 364.138972 -218.692222) (xy 365.359188 -218.692222) (xy 365.359739 -218.66688) (xy 365.367507 -218.616793)
			(xy 365.382848 -218.568485) (xy 365.405401 -218.523094) (xy 365.434634 -218.481689) (xy 365.469859 -218.445245)
			(xy 365.510246 -218.41462) (xy 365.554844 -218.390537) (xy 365.602602 -218.373561) (xy 365.627412 -218.368372)
			(xy 365.650272 -218.364054) (xy 365.855504 -218.008708) (xy 365.84763 -217.98661) (xy 365.839161 -217.960367)
			(xy 365.830092 -217.905977) (xy 365.829596 -217.878406) (xy 365.830104 -217.852519) (xy 365.838203 -217.801381)
			(xy 365.854202 -217.752141) (xy 365.877708 -217.706009) (xy 365.90814 -217.664122) (xy 365.94475 -217.627512)
			(xy 365.986637 -217.59708) (xy 366.032769 -217.573574) (xy 366.082009 -217.557575) (xy 366.133147 -217.549476)
			(xy 366.184921 -217.549476) (xy 366.236059 -217.557575) (xy 366.285299 -217.573574) (xy 366.331431 -217.59708)
			(xy 366.373318 -217.627512) (xy 366.409928 -217.664122) (xy 366.44036 -217.706009) (xy 366.463866 -217.752141)
			(xy 366.479865 -217.801381) (xy 366.487964 -217.852519) (xy 366.488472 -217.878406) (xy 366.488025 -217.903782)
			(xy 366.480255 -217.953934) (xy 366.464885 -218.002302) (xy 366.442277 -218.047739) (xy 366.412967 -218.089171)
			(xy 366.37765 -218.125617) (xy 366.33716 -218.156215) (xy 366.292456 -218.18024) (xy 366.244596 -218.197124)
			(xy 366.21974 -218.202256) (xy 366.19688 -218.206574) (xy 365.992156 -218.561412) (xy 366.00003 -218.583256)
			(xy 366.008681 -218.609663) (xy 366.017998 -218.66444) (xy 366.018572 -218.692222) (xy 367.238788 -218.692222)
			(xy 367.239339 -218.66688) (xy 367.247107 -218.616793) (xy 367.262448 -218.568485) (xy 367.285001 -218.523094)
			(xy 367.314234 -218.481689) (xy 367.349459 -218.445245) (xy 367.389846 -218.41462) (xy 367.434444 -218.390537)
			(xy 367.482202 -218.373561) (xy 367.507012 -218.368372) (xy 367.529872 -218.364054) (xy 367.735104 -218.008708)
			(xy 367.72723 -217.98661) (xy 367.718761 -217.960367) (xy 367.709692 -217.905977) (xy 367.709196 -217.878406)
			(xy 367.709704 -217.852519) (xy 367.717803 -217.801381) (xy 367.733802 -217.752141) (xy 367.757308 -217.706009)
			(xy 367.78774 -217.664122) (xy 367.82435 -217.627512) (xy 367.866237 -217.59708) (xy 367.912369 -217.573574)
			(xy 367.961609 -217.557575) (xy 368.012747 -217.549476) (xy 368.064521 -217.549476) (xy 368.115659 -217.557575)
			(xy 368.164899 -217.573574) (xy 368.211031 -217.59708) (xy 368.252918 -217.627512) (xy 368.289528 -217.664122)
			(xy 368.31996 -217.706009) (xy 368.343466 -217.752141) (xy 368.359465 -217.801381) (xy 368.367564 -217.852519)
			(xy 368.368072 -217.878406) (xy 368.367625 -217.903782) (xy 368.359855 -217.953934) (xy 368.344485 -218.002302)
			(xy 368.321877 -218.047739) (xy 368.292567 -218.089171) (xy 368.25725 -218.125617) (xy 368.21676 -218.156215)
			(xy 368.172056 -218.18024) (xy 368.124196 -218.197124) (xy 368.09934 -218.202256) (xy 368.07648 -218.206574)
			(xy 367.871756 -218.561412) (xy 367.87963 -218.583256) (xy 367.888281 -218.609663) (xy 367.897598 -218.66444)
			(xy 367.898172 -218.692222) (xy 369.118388 -218.692222) (xy 369.118939 -218.66688) (xy 369.126707 -218.616793)
			(xy 369.142048 -218.568485) (xy 369.164601 -218.523094) (xy 369.193834 -218.481689) (xy 369.229059 -218.445245)
			(xy 369.269446 -218.41462) (xy 369.314044 -218.390537) (xy 369.361802 -218.373561) (xy 369.386612 -218.368372)
			(xy 369.409472 -218.364054) (xy 369.614704 -218.008708) (xy 369.60683 -217.98661) (xy 369.598361 -217.960367)
			(xy 369.589292 -217.905977) (xy 369.588796 -217.878406) (xy 369.589304 -217.852519) (xy 369.597403 -217.801381)
			(xy 369.613402 -217.752141) (xy 369.636908 -217.706009) (xy 369.66734 -217.664122) (xy 369.70395 -217.627512)
			(xy 369.745837 -217.59708) (xy 369.791969 -217.573574) (xy 369.841209 -217.557575) (xy 369.892347 -217.549476)
			(xy 369.944121 -217.549476) (xy 369.995259 -217.557575) (xy 370.044499 -217.573574) (xy 370.090631 -217.59708)
			(xy 370.132518 -217.627512) (xy 370.169128 -217.664122) (xy 370.19956 -217.706009) (xy 370.223066 -217.752141)
			(xy 370.239065 -217.801381) (xy 370.247164 -217.852519) (xy 370.247672 -217.878406) (xy 370.247225 -217.903782)
			(xy 370.239455 -217.953934) (xy 370.224085 -218.002302) (xy 370.201477 -218.047739) (xy 370.172167 -218.089171)
			(xy 370.13685 -218.125617) (xy 370.09636 -218.156215) (xy 370.051656 -218.18024) (xy 370.003796 -218.197124)
			(xy 369.97894 -218.202256) (xy 369.95608 -218.206574) (xy 369.751356 -218.561412) (xy 369.75923 -218.583256)
			(xy 369.767881 -218.609663) (xy 369.777198 -218.66444) (xy 369.777772 -218.692222) (xy 370.997988 -218.692222)
			(xy 370.998539 -218.66688) (xy 371.006307 -218.616793) (xy 371.021648 -218.568485) (xy 371.044201 -218.523094)
			(xy 371.073434 -218.481689) (xy 371.108659 -218.445245) (xy 371.149046 -218.41462) (xy 371.193644 -218.390537)
			(xy 371.241402 -218.373561) (xy 371.266212 -218.368372) (xy 371.289072 -218.364054) (xy 371.494304 -218.008708)
			(xy 371.48643 -217.98661) (xy 371.477961 -217.960367) (xy 371.468892 -217.905977) (xy 371.468396 -217.878406)
			(xy 371.468904 -217.852519) (xy 371.477003 -217.801381) (xy 371.493002 -217.752141) (xy 371.516508 -217.706009)
			(xy 371.54694 -217.664122) (xy 371.58355 -217.627512) (xy 371.625437 -217.59708) (xy 371.671569 -217.573574)
			(xy 371.720809 -217.557575) (xy 371.771947 -217.549476) (xy 371.823721 -217.549476) (xy 371.874859 -217.557575)
			(xy 371.924099 -217.573574) (xy 371.970231 -217.59708) (xy 372.012118 -217.627512) (xy 372.048728 -217.664122)
			(xy 372.07916 -217.706009) (xy 372.102666 -217.752141) (xy 372.118665 -217.801381) (xy 372.126764 -217.852519)
			(xy 372.127272 -217.878406) (xy 372.126825 -217.903782) (xy 372.119055 -217.953934) (xy 372.103685 -218.002302)
			(xy 372.081077 -218.047739) (xy 372.051767 -218.089171) (xy 372.01645 -218.125617) (xy 371.97596 -218.156215)
			(xy 371.931256 -218.18024) (xy 371.883396 -218.197124) (xy 371.85854 -218.202256) (xy 371.83568 -218.206574)
			(xy 371.630956 -218.561412) (xy 371.63883 -218.583256) (xy 371.647481 -218.609663) (xy 371.656798 -218.66444)
			(xy 371.657372 -218.692222) (xy 372.877588 -218.692222) (xy 372.878139 -218.66688) (xy 372.885907 -218.616793)
			(xy 372.901248 -218.568485) (xy 372.923801 -218.523094) (xy 372.953034 -218.481689) (xy 372.988259 -218.445245)
			(xy 373.028646 -218.41462) (xy 373.073244 -218.390537) (xy 373.121002 -218.373561) (xy 373.145812 -218.368372)
			(xy 373.168672 -218.364054) (xy 373.373904 -218.008708) (xy 373.36603 -217.98661) (xy 373.357561 -217.960367)
			(xy 373.348492 -217.905977) (xy 373.347996 -217.878406) (xy 373.348504 -217.852519) (xy 373.356603 -217.801381)
			(xy 373.372602 -217.752141) (xy 373.396108 -217.706009) (xy 373.42654 -217.664122) (xy 373.46315 -217.627512)
			(xy 373.505037 -217.59708) (xy 373.551169 -217.573574) (xy 373.600409 -217.557575) (xy 373.651547 -217.549476)
			(xy 373.703321 -217.549476) (xy 373.754459 -217.557575) (xy 373.803699 -217.573574) (xy 373.849831 -217.59708)
			(xy 373.891718 -217.627512) (xy 373.928328 -217.664122) (xy 373.95876 -217.706009) (xy 373.982266 -217.752141)
			(xy 373.998265 -217.801381) (xy 374.006364 -217.852519) (xy 374.006872 -217.878406) (xy 374.006425 -217.903782)
			(xy 373.998655 -217.953934) (xy 373.983285 -218.002302) (xy 373.960677 -218.047739) (xy 373.931367 -218.089171)
			(xy 373.89605 -218.125617) (xy 373.85556 -218.156215) (xy 373.810856 -218.18024) (xy 373.762996 -218.197124)
			(xy 373.73814 -218.202256) (xy 373.71528 -218.206574) (xy 373.510556 -218.561412) (xy 373.51843 -218.583256)
			(xy 373.527081 -218.609663) (xy 373.536398 -218.66444) (xy 373.536972 -218.692222) (xy 374.757188 -218.692222)
			(xy 374.757739 -218.66688) (xy 374.765507 -218.616793) (xy 374.780848 -218.568485) (xy 374.803401 -218.523094)
			(xy 374.832634 -218.481689) (xy 374.867859 -218.445245) (xy 374.908246 -218.41462) (xy 374.952844 -218.390537)
			(xy 375.000602 -218.373561) (xy 375.025412 -218.368372) (xy 375.048272 -218.364054) (xy 375.253504 -218.008708)
			(xy 375.24563 -217.98661) (xy 375.237161 -217.960367) (xy 375.228092 -217.905977) (xy 375.227596 -217.878406)
			(xy 375.228104 -217.852519) (xy 375.236203 -217.801381) (xy 375.252202 -217.752141) (xy 375.275708 -217.706009)
			(xy 375.30614 -217.664122) (xy 375.34275 -217.627512) (xy 375.384637 -217.59708) (xy 375.430769 -217.573574)
			(xy 375.480009 -217.557575) (xy 375.531147 -217.549476) (xy 375.582921 -217.549476) (xy 375.634059 -217.557575)
			(xy 375.683299 -217.573574) (xy 375.729431 -217.59708) (xy 375.771318 -217.627512) (xy 375.807928 -217.664122)
			(xy 375.83836 -217.706009) (xy 375.861866 -217.752141) (xy 375.877865 -217.801381) (xy 375.885964 -217.852519)
			(xy 375.886472 -217.878406) (xy 375.886025 -217.903782) (xy 375.878255 -217.953934) (xy 375.862885 -218.002302)
			(xy 375.840277 -218.047739) (xy 375.810967 -218.089171) (xy 375.77565 -218.125617) (xy 375.73516 -218.156215)
			(xy 375.690456 -218.18024) (xy 375.642596 -218.197124) (xy 375.61774 -218.202256) (xy 375.59488 -218.206574)
			(xy 375.390156 -218.561412) (xy 375.39803 -218.583256) (xy 375.406681 -218.609663) (xy 375.415998 -218.66444)
			(xy 375.416572 -218.692222) (xy 376.636788 -218.692222) (xy 376.637339 -218.66688) (xy 376.645107 -218.616793)
			(xy 376.660448 -218.568485) (xy 376.683001 -218.523094) (xy 376.712234 -218.481689) (xy 376.747459 -218.445245)
			(xy 376.787846 -218.41462) (xy 376.832444 -218.390537) (xy 376.880202 -218.373561) (xy 376.905012 -218.368372)
			(xy 376.927872 -218.364054) (xy 377.133104 -218.008708) (xy 377.12523 -217.98661) (xy 377.116761 -217.960367)
			(xy 377.107692 -217.905977) (xy 377.107196 -217.878406) (xy 377.107704 -217.852519) (xy 377.115803 -217.801381)
			(xy 377.131802 -217.752141) (xy 377.155308 -217.706009) (xy 377.18574 -217.664122) (xy 377.22235 -217.627512)
			(xy 377.264237 -217.59708) (xy 377.310369 -217.573574) (xy 377.359609 -217.557575) (xy 377.410747 -217.549476)
			(xy 377.462521 -217.549476) (xy 377.513659 -217.557575) (xy 377.562899 -217.573574) (xy 377.609031 -217.59708)
			(xy 377.650918 -217.627512) (xy 377.687528 -217.664122) (xy 377.71796 -217.706009) (xy 377.741466 -217.752141)
			(xy 377.757465 -217.801381) (xy 377.765564 -217.852519) (xy 377.766072 -217.878406) (xy 377.765625 -217.903782)
			(xy 377.757855 -217.953934) (xy 377.742485 -218.002302) (xy 377.719877 -218.047739) (xy 377.690567 -218.089171)
			(xy 377.65525 -218.125617) (xy 377.61476 -218.156215) (xy 377.570056 -218.18024) (xy 377.522196 -218.197124)
			(xy 377.49734 -218.202256) (xy 377.47448 -218.206574) (xy 377.269756 -218.561412) (xy 377.27763 -218.583256)
			(xy 377.286281 -218.609663) (xy 377.295598 -218.66444) (xy 377.296172 -218.692222) (xy 378.516388 -218.692222)
			(xy 378.516939 -218.66688) (xy 378.524707 -218.616793) (xy 378.540048 -218.568485) (xy 378.562601 -218.523094)
			(xy 378.591834 -218.481689) (xy 378.627059 -218.445245) (xy 378.667446 -218.41462) (xy 378.712044 -218.390537)
			(xy 378.759802 -218.373561) (xy 378.784612 -218.368372) (xy 378.807472 -218.364054) (xy 379.012704 -218.008708)
			(xy 379.00483 -217.98661) (xy 378.996361 -217.960367) (xy 378.987292 -217.905977) (xy 378.986796 -217.878406)
			(xy 378.987304 -217.852519) (xy 378.995403 -217.801381) (xy 379.011402 -217.752141) (xy 379.034908 -217.706009)
			(xy 379.06534 -217.664122) (xy 379.10195 -217.627512) (xy 379.143837 -217.59708) (xy 379.189969 -217.573574)
			(xy 379.239209 -217.557575) (xy 379.290347 -217.549476) (xy 379.342121 -217.549476) (xy 379.393259 -217.557575)
			(xy 379.442499 -217.573574) (xy 379.488631 -217.59708) (xy 379.530518 -217.627512) (xy 379.567128 -217.664122)
			(xy 379.59756 -217.706009) (xy 379.621066 -217.752141) (xy 379.637065 -217.801381) (xy 379.645164 -217.852519)
			(xy 379.645672 -217.878406) (xy 379.645225 -217.903782) (xy 379.637455 -217.953934) (xy 379.622085 -218.002302)
			(xy 379.599477 -218.047739) (xy 379.570167 -218.089171) (xy 379.53485 -218.125617) (xy 379.49436 -218.156215)
			(xy 379.449656 -218.18024) (xy 379.401796 -218.197124) (xy 379.37694 -218.202256) (xy 379.35408 -218.206574)
			(xy 379.149356 -218.561412) (xy 379.15723 -218.583256) (xy 379.165881 -218.609663) (xy 379.175198 -218.66444)
			(xy 379.175772 -218.692222) (xy 380.395988 -218.692222) (xy 380.396539 -218.66688) (xy 380.404307 -218.616793)
			(xy 380.419648 -218.568485) (xy 380.442201 -218.523094) (xy 380.471434 -218.481689) (xy 380.506659 -218.445245)
			(xy 380.547046 -218.41462) (xy 380.591644 -218.390537) (xy 380.639402 -218.373561) (xy 380.664212 -218.368372)
			(xy 380.687072 -218.364054) (xy 380.892304 -218.008708) (xy 380.88443 -217.98661) (xy 380.875961 -217.960367)
			(xy 380.866892 -217.905977) (xy 380.866396 -217.878406) (xy 380.866904 -217.852519) (xy 380.875003 -217.801381)
			(xy 380.891002 -217.752141) (xy 380.914508 -217.706009) (xy 380.94494 -217.664122) (xy 380.98155 -217.627512)
			(xy 381.023437 -217.59708) (xy 381.069569 -217.573574) (xy 381.118809 -217.557575) (xy 381.169947 -217.549476)
			(xy 381.221721 -217.549476) (xy 381.272859 -217.557575) (xy 381.322099 -217.573574) (xy 381.368231 -217.59708)
			(xy 381.410118 -217.627512) (xy 381.446728 -217.664122) (xy 381.47716 -217.706009) (xy 381.500666 -217.752141)
			(xy 381.516665 -217.801381) (xy 381.524764 -217.852519) (xy 381.525272 -217.878406) (xy 381.524825 -217.903782)
			(xy 381.517055 -217.953934) (xy 381.501685 -218.002302) (xy 381.479077 -218.047739) (xy 381.449767 -218.089171)
			(xy 381.41445 -218.125617) (xy 381.37396 -218.156215) (xy 381.329256 -218.18024) (xy 381.281396 -218.197124)
			(xy 381.25654 -218.202256) (xy 381.23368 -218.206574) (xy 381.028956 -218.561412) (xy 381.03683 -218.583256)
			(xy 381.045481 -218.609663) (xy 381.054798 -218.66444) (xy 381.055372 -218.692222) (xy 381.054864 -218.718129)
			(xy 381.046758 -218.769306) (xy 381.046055 -218.77147) (xy 406.002236 -218.77147) (xy 406.002236 -218.36253)
			(xy 406.002689 -218.352361) (xy 406.010463 -218.333567) (xy 406.02484 -218.319181) (xy 406.043629 -218.311395)
			(xy 406.053798 -218.310968) (xy 407.453338 -218.310968) (xy 407.463502 -218.311403) (xy 407.482278 -218.319196)
			(xy 407.496643 -218.333579) (xy 407.50441 -218.352365) (xy 407.5049 -218.36253) (xy 407.5049 -218.77147)
			(xy 410.102304 -218.77147) (xy 410.102304 -218.36253) (xy 410.102857 -218.352378) (xy 410.110615 -218.333616)
			(xy 410.124963 -218.319251) (xy 410.143715 -218.311469) (xy 410.153866 -218.310968) (xy 411.553406 -218.310968)
			(xy 411.563582 -218.31136) (xy 411.582382 -218.319152) (xy 411.596768 -218.333548) (xy 411.604547 -218.352354)
			(xy 411.604968 -218.36253) (xy 411.604968 -218.77147) (xy 413.546036 -218.77147) (xy 413.546036 -218.36253)
			(xy 413.546489 -218.352361) (xy 413.554263 -218.333567) (xy 413.56864 -218.319181) (xy 413.587429 -218.311395)
			(xy 413.597598 -218.310968) (xy 414.997138 -218.310968) (xy 415.007302 -218.311403) (xy 415.026078 -218.319196)
			(xy 415.040443 -218.333579) (xy 415.04821 -218.352365) (xy 415.0487 -218.36253) (xy 415.0487 -218.77147)
			(xy 417.646104 -218.77147) (xy 417.646104 -218.36253) (xy 417.646657 -218.352378) (xy 417.654415 -218.333616)
			(xy 417.668763 -218.319251) (xy 417.687515 -218.311469) (xy 417.697666 -218.310968) (xy 419.097206 -218.310968)
			(xy 419.107382 -218.31136) (xy 419.126182 -218.319152) (xy 419.140568 -218.333548) (xy 419.148347 -218.352354)
			(xy 419.148768 -218.36253) (xy 419.148768 -218.77147) (xy 421.089836 -218.77147) (xy 421.089836 -218.36253)
			(xy 421.090289 -218.352361) (xy 421.098063 -218.333567) (xy 421.11244 -218.319181) (xy 421.131229 -218.311395)
			(xy 421.141398 -218.310968) (xy 422.540938 -218.310968) (xy 422.551102 -218.311403) (xy 422.569878 -218.319196)
			(xy 422.584243 -218.333579) (xy 422.59201 -218.352365) (xy 422.5925 -218.36253) (xy 422.5925 -218.77147)
			(xy 425.189904 -218.77147) (xy 425.189904 -218.36253) (xy 425.190457 -218.352378) (xy 425.198215 -218.333616)
			(xy 425.212563 -218.319251) (xy 425.231315 -218.311469) (xy 425.241466 -218.310968) (xy 426.641006 -218.310968)
			(xy 426.651182 -218.31136) (xy 426.669982 -218.319152) (xy 426.684368 -218.333548) (xy 426.692147 -218.352354)
			(xy 426.692568 -218.36253) (xy 426.692568 -218.77147) (xy 428.633636 -218.77147) (xy 428.633636 -218.36253)
			(xy 428.634089 -218.352361) (xy 428.641863 -218.333567) (xy 428.65624 -218.319181) (xy 428.675029 -218.311395)
			(xy 428.685198 -218.310968) (xy 430.084738 -218.310968) (xy 430.094902 -218.311403) (xy 430.113678 -218.319196)
			(xy 430.128043 -218.333579) (xy 430.13581 -218.352365) (xy 430.1363 -218.36253) (xy 430.1363 -218.77147)
			(xy 432.733704 -218.77147) (xy 432.733704 -218.36253) (xy 432.734257 -218.352378) (xy 432.742015 -218.333616)
			(xy 432.756363 -218.319251) (xy 432.775115 -218.311469) (xy 432.785266 -218.310968) (xy 434.184806 -218.310968)
			(xy 434.194982 -218.31136) (xy 434.213782 -218.319152) (xy 434.228168 -218.333548) (xy 434.235947 -218.352354)
			(xy 434.236368 -218.36253) (xy 434.236368 -218.77147) (xy 436.177436 -218.77147) (xy 436.177436 -218.36253)
			(xy 436.177889 -218.352361) (xy 436.185663 -218.333567) (xy 436.20004 -218.319181) (xy 436.218829 -218.311395)
			(xy 436.228998 -218.310968) (xy 437.628538 -218.310968) (xy 437.638702 -218.311403) (xy 437.657478 -218.319196)
			(xy 437.671843 -218.333579) (xy 437.67961 -218.352365) (xy 437.6801 -218.36253) (xy 437.6801 -218.77147)
			(xy 440.277504 -218.77147) (xy 440.277504 -218.36253) (xy 440.278057 -218.352378) (xy 440.285815 -218.333616)
			(xy 440.300163 -218.319251) (xy 440.318915 -218.311469) (xy 440.329066 -218.310968) (xy 441.728606 -218.310968)
			(xy 441.738782 -218.31136) (xy 441.757582 -218.319152) (xy 441.771968 -218.333548) (xy 441.779747 -218.352354)
			(xy 441.780168 -218.36253) (xy 441.780168 -218.77147) (xy 443.721236 -218.77147) (xy 443.721236 -218.36253)
			(xy 443.721689 -218.352361) (xy 443.729463 -218.333567) (xy 443.74384 -218.319181) (xy 443.762629 -218.311395)
			(xy 443.772798 -218.310968) (xy 445.172338 -218.310968) (xy 445.182502 -218.311403) (xy 445.201278 -218.319196)
			(xy 445.215643 -218.333579) (xy 445.22341 -218.352365) (xy 445.2239 -218.36253) (xy 445.2239 -218.77147)
			(xy 447.821304 -218.77147) (xy 447.821304 -218.36253) (xy 447.821857 -218.352378) (xy 447.829615 -218.333616)
			(xy 447.843963 -218.319251) (xy 447.862715 -218.311469) (xy 447.872866 -218.310968) (xy 449.272406 -218.310968)
			(xy 449.282582 -218.31136) (xy 449.301382 -218.319152) (xy 449.315768 -218.333548) (xy 449.323547 -218.352354)
			(xy 449.323968 -218.36253) (xy 449.323968 -218.77147) (xy 451.265036 -218.77147) (xy 451.265036 -218.36253)
			(xy 451.265489 -218.352361) (xy 451.273263 -218.333567) (xy 451.28764 -218.319181) (xy 451.306429 -218.311395)
			(xy 451.316598 -218.310968) (xy 452.716138 -218.310968) (xy 452.726302 -218.311403) (xy 452.745078 -218.319196)
			(xy 452.759443 -218.333579) (xy 452.76721 -218.352365) (xy 452.7677 -218.36253) (xy 452.7677 -218.77147)
			(xy 455.365104 -218.77147) (xy 455.365104 -218.36253) (xy 455.365657 -218.352378) (xy 455.373415 -218.333616)
			(xy 455.387763 -218.319251) (xy 455.406515 -218.311469) (xy 455.416666 -218.310968) (xy 456.816206 -218.310968)
			(xy 456.826382 -218.31136) (xy 456.845182 -218.319152) (xy 456.859568 -218.333548) (xy 456.867347 -218.352354)
			(xy 456.867768 -218.36253) (xy 456.867768 -218.77147) (xy 458.808836 -218.77147) (xy 458.808836 -218.36253)
			(xy 458.809289 -218.352361) (xy 458.817063 -218.333567) (xy 458.83144 -218.319181) (xy 458.850229 -218.311395)
			(xy 458.860398 -218.310968) (xy 460.259938 -218.310968) (xy 460.270102 -218.311403) (xy 460.288878 -218.319196)
			(xy 460.303243 -218.333579) (xy 460.31101 -218.352365) (xy 460.3115 -218.36253) (xy 460.3115 -218.77147)
			(xy 462.908904 -218.77147) (xy 462.908904 -218.36253) (xy 462.909457 -218.352378) (xy 462.917215 -218.333616)
			(xy 462.931563 -218.319251) (xy 462.950315 -218.311469) (xy 462.960466 -218.310968) (xy 464.360006 -218.310968)
			(xy 464.370182 -218.31136) (xy 464.388982 -218.319152) (xy 464.403368 -218.333548) (xy 464.411147 -218.352354)
			(xy 464.411568 -218.36253) (xy 464.411568 -218.77147) (xy 464.411112 -218.781639) (xy 464.403338 -218.800432)
			(xy 464.388962 -218.814817) (xy 464.370175 -218.822604) (xy 464.360006 -218.823032) (xy 462.960466 -218.823032)
			(xy 462.950302 -218.822594) (xy 462.931527 -218.814803) (xy 462.917162 -218.80042) (xy 462.909394 -218.781634)
			(xy 462.908904 -218.77147) (xy 460.3115 -218.77147) (xy 460.310943 -218.781621) (xy 460.303186 -218.800383)
			(xy 460.28884 -218.814748) (xy 460.270089 -218.82253) (xy 460.259938 -218.823032) (xy 458.860398 -218.823032)
			(xy 458.850223 -218.822637) (xy 458.831422 -218.814846) (xy 458.817036 -218.800451) (xy 458.809257 -218.781646)
			(xy 458.808836 -218.77147) (xy 456.867768 -218.77147) (xy 456.867312 -218.781639) (xy 456.859538 -218.800432)
			(xy 456.845162 -218.814817) (xy 456.826375 -218.822604) (xy 456.816206 -218.823032) (xy 455.416666 -218.823032)
			(xy 455.406502 -218.822594) (xy 455.387727 -218.814803) (xy 455.373362 -218.80042) (xy 455.365594 -218.781634)
			(xy 455.365104 -218.77147) (xy 452.7677 -218.77147) (xy 452.767143 -218.781621) (xy 452.759386 -218.800383)
			(xy 452.74504 -218.814748) (xy 452.726289 -218.82253) (xy 452.716138 -218.823032) (xy 451.316598 -218.823032)
			(xy 451.306423 -218.822637) (xy 451.287622 -218.814846) (xy 451.273236 -218.800451) (xy 451.265457 -218.781646)
			(xy 451.265036 -218.77147) (xy 449.323968 -218.77147) (xy 449.323512 -218.781639) (xy 449.315738 -218.800432)
			(xy 449.301362 -218.814817) (xy 449.282575 -218.822604) (xy 449.272406 -218.823032) (xy 447.872866 -218.823032)
			(xy 447.862702 -218.822594) (xy 447.843927 -218.814803) (xy 447.829562 -218.80042) (xy 447.821794 -218.781634)
			(xy 447.821304 -218.77147) (xy 445.2239 -218.77147) (xy 445.223343 -218.781621) (xy 445.215586 -218.800383)
			(xy 445.20124 -218.814748) (xy 445.182489 -218.82253) (xy 445.172338 -218.823032) (xy 443.772798 -218.823032)
			(xy 443.762623 -218.822637) (xy 443.743822 -218.814846) (xy 443.729436 -218.800451) (xy 443.721657 -218.781646)
			(xy 443.721236 -218.77147) (xy 441.780168 -218.77147) (xy 441.779712 -218.781639) (xy 441.771938 -218.800432)
			(xy 441.757562 -218.814817) (xy 441.738775 -218.822604) (xy 441.728606 -218.823032) (xy 440.329066 -218.823032)
			(xy 440.318902 -218.822594) (xy 440.300127 -218.814803) (xy 440.285762 -218.80042) (xy 440.277994 -218.781634)
			(xy 440.277504 -218.77147) (xy 437.6801 -218.77147) (xy 437.679543 -218.781621) (xy 437.671786 -218.800383)
			(xy 437.65744 -218.814748) (xy 437.638689 -218.82253) (xy 437.628538 -218.823032) (xy 436.228998 -218.823032)
			(xy 436.218823 -218.822637) (xy 436.200022 -218.814846) (xy 436.185636 -218.800451) (xy 436.177857 -218.781646)
			(xy 436.177436 -218.77147) (xy 434.236368 -218.77147) (xy 434.235912 -218.781639) (xy 434.228138 -218.800432)
			(xy 434.213762 -218.814817) (xy 434.194975 -218.822604) (xy 434.184806 -218.823032) (xy 432.785266 -218.823032)
			(xy 432.775102 -218.822594) (xy 432.756327 -218.814803) (xy 432.741962 -218.80042) (xy 432.734194 -218.781634)
			(xy 432.733704 -218.77147) (xy 430.1363 -218.77147) (xy 430.135743 -218.781621) (xy 430.127986 -218.800383)
			(xy 430.11364 -218.814748) (xy 430.094889 -218.82253) (xy 430.084738 -218.823032) (xy 428.685198 -218.823032)
			(xy 428.675023 -218.822637) (xy 428.656222 -218.814846) (xy 428.641836 -218.800451) (xy 428.634057 -218.781646)
			(xy 428.633636 -218.77147) (xy 426.692568 -218.77147) (xy 426.692112 -218.781639) (xy 426.684338 -218.800432)
			(xy 426.669962 -218.814817) (xy 426.651175 -218.822604) (xy 426.641006 -218.823032) (xy 425.241466 -218.823032)
			(xy 425.231302 -218.822594) (xy 425.212527 -218.814803) (xy 425.198162 -218.80042) (xy 425.190394 -218.781634)
			(xy 425.189904 -218.77147) (xy 422.5925 -218.77147) (xy 422.591943 -218.781621) (xy 422.584186 -218.800383)
			(xy 422.56984 -218.814748) (xy 422.551089 -218.82253) (xy 422.540938 -218.823032) (xy 421.141398 -218.823032)
			(xy 421.131223 -218.822637) (xy 421.112422 -218.814846) (xy 421.098036 -218.800451) (xy 421.090257 -218.781646)
			(xy 421.089836 -218.77147) (xy 419.148768 -218.77147) (xy 419.148312 -218.781639) (xy 419.140538 -218.800432)
			(xy 419.126162 -218.814817) (xy 419.107375 -218.822604) (xy 419.097206 -218.823032) (xy 417.697666 -218.823032)
			(xy 417.687502 -218.822594) (xy 417.668727 -218.814803) (xy 417.654362 -218.80042) (xy 417.646594 -218.781634)
			(xy 417.646104 -218.77147) (xy 415.0487 -218.77147) (xy 415.048143 -218.781621) (xy 415.040386 -218.800383)
			(xy 415.02604 -218.814748) (xy 415.007289 -218.82253) (xy 414.997138 -218.823032) (xy 413.597598 -218.823032)
			(xy 413.587423 -218.822637) (xy 413.568622 -218.814846) (xy 413.554236 -218.800451) (xy 413.546457 -218.781646)
			(xy 413.546036 -218.77147) (xy 411.604968 -218.77147) (xy 411.604512 -218.781639) (xy 411.596738 -218.800432)
			(xy 411.582362 -218.814817) (xy 411.563575 -218.822604) (xy 411.553406 -218.823032) (xy 410.153866 -218.823032)
			(xy 410.143702 -218.822594) (xy 410.124927 -218.814803) (xy 410.110562 -218.80042) (xy 410.102794 -218.781634)
			(xy 410.102304 -218.77147) (xy 407.5049 -218.77147) (xy 407.504343 -218.781621) (xy 407.496586 -218.800383)
			(xy 407.48224 -218.814748) (xy 407.463489 -218.82253) (xy 407.453338 -218.823032) (xy 406.053798 -218.823032)
			(xy 406.043623 -218.822637) (xy 406.024822 -218.814846) (xy 406.010436 -218.800451) (xy 406.002657 -218.781646)
			(xy 406.002236 -218.77147) (xy 381.046055 -218.77147) (xy 381.030746 -218.818585) (xy 381.007223 -218.864752)
			(xy 380.976767 -218.906671) (xy 380.940129 -218.943309) (xy 380.89821 -218.973765) (xy 380.852043 -218.997288)
			(xy 380.802764 -219.0133) (xy 380.751587 -219.021406) (xy 380.699773 -219.021406) (xy 380.648596 -219.0133)
			(xy 380.599317 -218.997288) (xy 380.55315 -218.973765) (xy 380.511231 -218.943309) (xy 380.474593 -218.906671)
			(xy 380.444137 -218.864752) (xy 380.420614 -218.818585) (xy 380.404602 -218.769306) (xy 380.396496 -218.718129)
			(xy 380.395988 -218.692222) (xy 379.175772 -218.692222) (xy 379.175264 -218.718129) (xy 379.167158 -218.769306)
			(xy 379.151146 -218.818585) (xy 379.127623 -218.864752) (xy 379.097167 -218.906671) (xy 379.060529 -218.943309)
			(xy 379.01861 -218.973765) (xy 378.972443 -218.997288) (xy 378.923164 -219.0133) (xy 378.871987 -219.021406)
			(xy 378.820173 -219.021406) (xy 378.768996 -219.0133) (xy 378.719717 -218.997288) (xy 378.67355 -218.973765)
			(xy 378.631631 -218.943309) (xy 378.594993 -218.906671) (xy 378.564537 -218.864752) (xy 378.541014 -218.818585)
			(xy 378.525002 -218.769306) (xy 378.516896 -218.718129) (xy 378.516388 -218.692222) (xy 377.296172 -218.692222)
			(xy 377.295664 -218.718129) (xy 377.287558 -218.769306) (xy 377.271546 -218.818585) (xy 377.248023 -218.864752)
			(xy 377.217567 -218.906671) (xy 377.180929 -218.943309) (xy 377.13901 -218.973765) (xy 377.092843 -218.997288)
			(xy 377.043564 -219.0133) (xy 376.992387 -219.021406) (xy 376.940573 -219.021406) (xy 376.889396 -219.0133)
			(xy 376.840117 -218.997288) (xy 376.79395 -218.973765) (xy 376.752031 -218.943309) (xy 376.715393 -218.906671)
			(xy 376.684937 -218.864752) (xy 376.661414 -218.818585) (xy 376.645402 -218.769306) (xy 376.637296 -218.718129)
			(xy 376.636788 -218.692222) (xy 375.416572 -218.692222) (xy 375.416064 -218.718129) (xy 375.407958 -218.769306)
			(xy 375.391946 -218.818585) (xy 375.368423 -218.864752) (xy 375.337967 -218.906671) (xy 375.301329 -218.943309)
			(xy 375.25941 -218.973765) (xy 375.213243 -218.997288) (xy 375.163964 -219.0133) (xy 375.112787 -219.021406)
			(xy 375.060973 -219.021406) (xy 375.009796 -219.0133) (xy 374.960517 -218.997288) (xy 374.91435 -218.973765)
			(xy 374.872431 -218.943309) (xy 374.835793 -218.906671) (xy 374.805337 -218.864752) (xy 374.781814 -218.818585)
			(xy 374.765802 -218.769306) (xy 374.757696 -218.718129) (xy 374.757188 -218.692222) (xy 373.536972 -218.692222)
			(xy 373.536464 -218.718129) (xy 373.528358 -218.769306) (xy 373.512346 -218.818585) (xy 373.488823 -218.864752)
			(xy 373.458367 -218.906671) (xy 373.421729 -218.943309) (xy 373.37981 -218.973765) (xy 373.333643 -218.997288)
			(xy 373.284364 -219.0133) (xy 373.233187 -219.021406) (xy 373.181373 -219.021406) (xy 373.130196 -219.0133)
			(xy 373.080917 -218.997288) (xy 373.03475 -218.973765) (xy 372.992831 -218.943309) (xy 372.956193 -218.906671)
			(xy 372.925737 -218.864752) (xy 372.902214 -218.818585) (xy 372.886202 -218.769306) (xy 372.878096 -218.718129)
			(xy 372.877588 -218.692222) (xy 371.657372 -218.692222) (xy 371.656864 -218.718129) (xy 371.648758 -218.769306)
			(xy 371.632746 -218.818585) (xy 371.609223 -218.864752) (xy 371.578767 -218.906671) (xy 371.542129 -218.943309)
			(xy 371.50021 -218.973765) (xy 371.454043 -218.997288) (xy 371.404764 -219.0133) (xy 371.353587 -219.021406)
			(xy 371.301773 -219.021406) (xy 371.250596 -219.0133) (xy 371.201317 -218.997288) (xy 371.15515 -218.973765)
			(xy 371.113231 -218.943309) (xy 371.076593 -218.906671) (xy 371.046137 -218.864752) (xy 371.022614 -218.818585)
			(xy 371.006602 -218.769306) (xy 370.998496 -218.718129) (xy 370.997988 -218.692222) (xy 369.777772 -218.692222)
			(xy 369.777264 -218.718129) (xy 369.769158 -218.769306) (xy 369.753146 -218.818585) (xy 369.729623 -218.864752)
			(xy 369.699167 -218.906671) (xy 369.662529 -218.943309) (xy 369.62061 -218.973765) (xy 369.574443 -218.997288)
			(xy 369.525164 -219.0133) (xy 369.473987 -219.021406) (xy 369.422173 -219.021406) (xy 369.370996 -219.0133)
			(xy 369.321717 -218.997288) (xy 369.27555 -218.973765) (xy 369.233631 -218.943309) (xy 369.196993 -218.906671)
			(xy 369.166537 -218.864752) (xy 369.143014 -218.818585) (xy 369.127002 -218.769306) (xy 369.118896 -218.718129)
			(xy 369.118388 -218.692222) (xy 367.898172 -218.692222) (xy 367.897664 -218.718129) (xy 367.889558 -218.769306)
			(xy 367.873546 -218.818585) (xy 367.850023 -218.864752) (xy 367.819567 -218.906671) (xy 367.782929 -218.943309)
			(xy 367.74101 -218.973765) (xy 367.694843 -218.997288) (xy 367.645564 -219.0133) (xy 367.594387 -219.021406)
			(xy 367.542573 -219.021406) (xy 367.491396 -219.0133) (xy 367.442117 -218.997288) (xy 367.39595 -218.973765)
			(xy 367.354031 -218.943309) (xy 367.317393 -218.906671) (xy 367.286937 -218.864752) (xy 367.263414 -218.818585)
			(xy 367.247402 -218.769306) (xy 367.239296 -218.718129) (xy 367.238788 -218.692222) (xy 366.018572 -218.692222)
			(xy 366.018064 -218.718129) (xy 366.009958 -218.769306) (xy 365.993946 -218.818585) (xy 365.970423 -218.864752)
			(xy 365.939967 -218.906671) (xy 365.903329 -218.943309) (xy 365.86141 -218.973765) (xy 365.815243 -218.997288)
			(xy 365.765964 -219.0133) (xy 365.714787 -219.021406) (xy 365.662973 -219.021406) (xy 365.611796 -219.0133)
			(xy 365.562517 -218.997288) (xy 365.51635 -218.973765) (xy 365.474431 -218.943309) (xy 365.437793 -218.906671)
			(xy 365.407337 -218.864752) (xy 365.383814 -218.818585) (xy 365.367802 -218.769306) (xy 365.359696 -218.718129)
			(xy 365.359188 -218.692222) (xy 364.138972 -218.692222) (xy 364.138464 -218.718129) (xy 364.130358 -218.769306)
			(xy 364.114346 -218.818585) (xy 364.090823 -218.864752) (xy 364.060367 -218.906671) (xy 364.023729 -218.943309)
			(xy 363.98181 -218.973765) (xy 363.935643 -218.997288) (xy 363.886364 -219.0133) (xy 363.835187 -219.021406)
			(xy 363.783373 -219.021406) (xy 363.732196 -219.0133) (xy 363.682917 -218.997288) (xy 363.63675 -218.973765)
			(xy 363.594831 -218.943309) (xy 363.558193 -218.906671) (xy 363.527737 -218.864752) (xy 363.504214 -218.818585)
			(xy 363.488202 -218.769306) (xy 363.480096 -218.718129) (xy 363.479588 -218.692222) (xy 362.259372 -218.692222)
			(xy 362.258864 -218.718109) (xy 362.250765 -218.769247) (xy 362.234766 -218.818487) (xy 362.21126 -218.864619)
			(xy 362.180828 -218.906506) (xy 362.144218 -218.943116) (xy 362.102331 -218.973548) (xy 362.056199 -218.997054)
			(xy 362.006959 -219.013053) (xy 361.955821 -219.021152) (xy 361.904047 -219.021152) (xy 361.852909 -219.013053)
			(xy 361.803669 -218.997054) (xy 361.757537 -218.973548) (xy 361.71565 -218.943116) (xy 361.67904 -218.906506)
			(xy 361.648608 -218.864619) (xy 361.625102 -218.818487) (xy 361.609103 -218.769247) (xy 361.601004 -218.718109)
			(xy 361.600496 -218.692222) (xy 360.379772 -218.692222) (xy 360.379264 -218.718129) (xy 360.371158 -218.769306)
			(xy 360.355146 -218.818585) (xy 360.331623 -218.864752) (xy 360.301167 -218.906671) (xy 360.264529 -218.943309)
			(xy 360.22261 -218.973765) (xy 360.176443 -218.997288) (xy 360.127164 -219.0133) (xy 360.075987 -219.021406)
			(xy 360.024173 -219.021406) (xy 359.972996 -219.0133) (xy 359.923717 -218.997288) (xy 359.87755 -218.973765)
			(xy 359.835631 -218.943309) (xy 359.798993 -218.906671) (xy 359.768537 -218.864752) (xy 359.745014 -218.818585)
			(xy 359.729002 -218.769306) (xy 359.720896 -218.718129) (xy 359.720388 -218.692222) (xy 358.500172 -218.692222)
			(xy 358.499664 -218.718109) (xy 358.491565 -218.769247) (xy 358.475566 -218.818487) (xy 358.45206 -218.864619)
			(xy 358.421628 -218.906506) (xy 358.385018 -218.943116) (xy 358.343131 -218.973548) (xy 358.296999 -218.997054)
			(xy 358.247759 -219.013053) (xy 358.196621 -219.021152) (xy 358.144847 -219.021152) (xy 358.093709 -219.013053)
			(xy 358.044469 -218.997054) (xy 357.998337 -218.973548) (xy 357.95645 -218.943116) (xy 357.91984 -218.906506)
			(xy 357.889408 -218.864619) (xy 357.865902 -218.818487) (xy 357.849903 -218.769247) (xy 357.841804 -218.718109)
			(xy 357.841296 -218.692222) (xy 357.841831 -218.664514) (xy 357.851023 -218.609867) (xy 357.859584 -218.58351)
			(xy 357.867458 -218.561412) (xy 357.66248 -218.206574) (xy 357.63962 -218.202256) (xy 357.614783 -218.197156)
			(xy 357.567001 -218.180194) (xy 357.52238 -218.156114) (xy 357.481972 -218.125486) (xy 357.446732 -218.08903)
			(xy 357.417491 -218.047608) (xy 357.394937 -218.002196) (xy 357.379605 -217.953866) (xy 357.371854 -217.903758)
			(xy 357.371396 -217.878406) (xy 357.090472 -217.878406) (xy 357.089964 -217.904293) (xy 357.081865 -217.955431)
			(xy 357.065866 -218.004671) (xy 357.04236 -218.050803) (xy 357.011928 -218.09269) (xy 356.975318 -218.1293)
			(xy 356.933431 -218.159732) (xy 356.887299 -218.183238) (xy 356.838059 -218.199237) (xy 356.786921 -218.207336)
			(xy 356.735147 -218.207336) (xy 356.684009 -218.199237) (xy 356.634769 -218.183238) (xy 356.588637 -218.159732)
			(xy 356.54675 -218.1293) (xy 356.51014 -218.09269) (xy 356.479708 -218.050803) (xy 356.456202 -218.004671)
			(xy 356.440203 -217.955431) (xy 356.432104 -217.904293) (xy 356.431596 -217.878406) (xy 356.150672 -217.878406)
			(xy 356.150141 -217.906114) (xy 356.140946 -217.960761) (xy 356.132384 -217.987118) (xy 356.12451 -218.009216)
			(xy 356.329488 -218.364054) (xy 356.352348 -218.368372) (xy 356.377163 -218.373563) (xy 356.424941 -218.390515)
			(xy 356.469559 -218.414584) (xy 356.509965 -218.445202) (xy 356.545206 -218.481645) (xy 356.57445 -218.523056)
			(xy 356.597009 -218.568456) (xy 356.612349 -218.616776) (xy 356.620108 -218.666874) (xy 356.620572 -218.692222)
			(xy 356.620064 -218.718129) (xy 356.611958 -218.769306) (xy 356.595946 -218.818585) (xy 356.572423 -218.864752)
			(xy 356.541967 -218.906671) (xy 356.505329 -218.943309) (xy 356.46341 -218.973765) (xy 356.417243 -218.997288)
			(xy 356.367964 -219.0133) (xy 356.316787 -219.021406) (xy 356.264973 -219.021406) (xy 356.213796 -219.0133)
			(xy 356.164517 -218.997288) (xy 356.11835 -218.973765) (xy 356.076431 -218.943309) (xy 356.039793 -218.906671)
			(xy 356.009337 -218.864752) (xy 355.985814 -218.818585) (xy 355.969802 -218.769306) (xy 355.961696 -218.718129)
			(xy 355.961188 -218.692222) (xy 355.961788 -218.664505) (xy 355.971107 -218.609859) (xy 355.97973 -218.58351)
			(xy 355.987604 -218.561412) (xy 355.782626 -218.206574) (xy 355.759766 -218.202256) (xy 355.734962 -218.197073)
			(xy 355.687224 -218.180081) (xy 355.642649 -218.155985) (xy 355.602284 -218.125353) (xy 355.567082 -218.088906)
			(xy 355.53787 -218.047502) (xy 355.515337 -218.002116) (xy 355.500013 -217.953817) (xy 355.49226 -217.903742)
			(xy 355.491796 -217.878406) (xy 355.210872 -217.878406) (xy 355.210364 -217.904293) (xy 355.202265 -217.955431)
			(xy 355.186266 -218.004671) (xy 355.16276 -218.050803) (xy 355.132328 -218.09269) (xy 355.095718 -218.1293)
			(xy 355.053831 -218.159732) (xy 355.007699 -218.183238) (xy 354.958459 -218.199237) (xy 354.907321 -218.207336)
			(xy 354.855547 -218.207336) (xy 354.804409 -218.199237) (xy 354.755169 -218.183238) (xy 354.709037 -218.159732)
			(xy 354.66715 -218.1293) (xy 354.63054 -218.09269) (xy 354.600108 -218.050803) (xy 354.576602 -218.004671)
			(xy 354.560603 -217.955431) (xy 354.552504 -217.904293) (xy 354.551996 -217.878406) (xy 354.271072 -217.878406)
			(xy 354.270541 -217.906114) (xy 354.261346 -217.960761) (xy 354.252784 -217.987118) (xy 354.24491 -218.009216)
			(xy 354.449888 -218.364054) (xy 354.472748 -218.368372) (xy 354.497563 -218.373563) (xy 354.545341 -218.390515)
			(xy 354.589959 -218.414584) (xy 354.630365 -218.445202) (xy 354.665606 -218.481645) (xy 354.69485 -218.523056)
			(xy 354.717409 -218.568456) (xy 354.732749 -218.616776) (xy 354.740508 -218.666874) (xy 354.740972 -218.692222)
			(xy 354.740464 -218.718129) (xy 354.732358 -218.769306) (xy 354.716346 -218.818585) (xy 354.692823 -218.864752)
			(xy 354.662367 -218.906671) (xy 354.625729 -218.943309) (xy 354.58381 -218.973765) (xy 354.537643 -218.997288)
			(xy 354.488364 -219.0133) (xy 354.437187 -219.021406) (xy 354.385373 -219.021406) (xy 354.334196 -219.0133)
			(xy 354.284917 -218.997288) (xy 354.23875 -218.973765) (xy 354.196831 -218.943309) (xy 354.160193 -218.906671)
			(xy 354.129737 -218.864752) (xy 354.106214 -218.818585) (xy 354.090202 -218.769306) (xy 354.082096 -218.718129)
			(xy 354.081588 -218.692222) (xy 354.082188 -218.664505) (xy 354.091507 -218.609859) (xy 354.10013 -218.58351)
			(xy 354.108004 -218.561412) (xy 353.903026 -218.206574) (xy 353.880166 -218.202256) (xy 353.855362 -218.197073)
			(xy 353.807624 -218.180081) (xy 353.763049 -218.155985) (xy 353.722684 -218.125353) (xy 353.687482 -218.088906)
			(xy 353.65827 -218.047502) (xy 353.635737 -218.002116) (xy 353.620413 -217.953817) (xy 353.61266 -217.903742)
			(xy 353.612196 -217.878406) (xy 353.331272 -217.878406) (xy 353.330764 -217.904293) (xy 353.322665 -217.955431)
			(xy 353.306666 -218.004671) (xy 353.28316 -218.050803) (xy 353.252728 -218.09269) (xy 353.216118 -218.1293)
			(xy 353.174231 -218.159732) (xy 353.128099 -218.183238) (xy 353.078859 -218.199237) (xy 353.027721 -218.207336)
			(xy 352.975947 -218.207336) (xy 352.924809 -218.199237) (xy 352.875569 -218.183238) (xy 352.829437 -218.159732)
			(xy 352.78755 -218.1293) (xy 352.75094 -218.09269) (xy 352.720508 -218.050803) (xy 352.697002 -218.004671)
			(xy 352.681003 -217.955431) (xy 352.672904 -217.904293) (xy 352.672396 -217.878406) (xy 352.391472 -217.878406)
			(xy 352.390941 -217.906114) (xy 352.381746 -217.960761) (xy 352.373184 -217.987118) (xy 352.36531 -218.009216)
			(xy 352.570288 -218.364054) (xy 352.593148 -218.368372) (xy 352.617963 -218.373563) (xy 352.665741 -218.390515)
			(xy 352.710359 -218.414584) (xy 352.750765 -218.445202) (xy 352.786006 -218.481645) (xy 352.81525 -218.523056)
			(xy 352.837809 -218.568456) (xy 352.853149 -218.616776) (xy 352.860908 -218.666874) (xy 352.861372 -218.692222)
			(xy 352.860864 -218.718129) (xy 352.852758 -218.769306) (xy 352.836746 -218.818585) (xy 352.813223 -218.864752)
			(xy 352.782767 -218.906671) (xy 352.746129 -218.943309) (xy 352.70421 -218.973765) (xy 352.658043 -218.997288)
			(xy 352.608764 -219.0133) (xy 352.557587 -219.021406) (xy 352.505773 -219.021406) (xy 352.454596 -219.0133)
			(xy 352.405317 -218.997288) (xy 352.35915 -218.973765) (xy 352.317231 -218.943309) (xy 352.280593 -218.906671)
			(xy 352.250137 -218.864752) (xy 352.226614 -218.818585) (xy 352.210602 -218.769306) (xy 352.202496 -218.718129)
			(xy 352.201988 -218.692222) (xy 352.202588 -218.664505) (xy 352.211907 -218.609859) (xy 352.22053 -218.58351)
			(xy 352.228404 -218.561412) (xy 352.023426 -218.206574) (xy 352.000566 -218.202256) (xy 351.975762 -218.197073)
			(xy 351.928024 -218.180081) (xy 351.883449 -218.155985) (xy 351.843084 -218.125353) (xy 351.807882 -218.088906)
			(xy 351.77867 -218.047502) (xy 351.756137 -218.002116) (xy 351.740813 -217.953817) (xy 351.73306 -217.903742)
			(xy 351.732596 -217.878406) (xy 351.451672 -217.878406) (xy 351.451164 -217.904293) (xy 351.443065 -217.955431)
			(xy 351.427066 -218.004671) (xy 351.40356 -218.050803) (xy 351.373128 -218.09269) (xy 351.336518 -218.1293)
			(xy 351.294631 -218.159732) (xy 351.248499 -218.183238) (xy 351.199259 -218.199237) (xy 351.148121 -218.207336)
			(xy 351.096347 -218.207336) (xy 351.045209 -218.199237) (xy 350.995969 -218.183238) (xy 350.949837 -218.159732)
			(xy 350.90795 -218.1293) (xy 350.87134 -218.09269) (xy 350.840908 -218.050803) (xy 350.817402 -218.004671)
			(xy 350.801403 -217.955431) (xy 350.793304 -217.904293) (xy 350.792796 -217.878406) (xy 350.511872 -217.878406)
			(xy 350.511341 -217.906114) (xy 350.502146 -217.960761) (xy 350.493584 -217.987118) (xy 350.48571 -218.009216)
			(xy 350.690688 -218.364054) (xy 350.713548 -218.368372) (xy 350.738363 -218.373563) (xy 350.786141 -218.390515)
			(xy 350.830759 -218.414584) (xy 350.871165 -218.445202) (xy 350.906406 -218.481645) (xy 350.93565 -218.523056)
			(xy 350.958209 -218.568456) (xy 350.973549 -218.616776) (xy 350.981308 -218.666874) (xy 350.981772 -218.692222)
			(xy 350.981264 -218.718129) (xy 350.973158 -218.769306) (xy 350.957146 -218.818585) (xy 350.933623 -218.864752)
			(xy 350.903167 -218.906671) (xy 350.866529 -218.943309) (xy 350.82461 -218.973765) (xy 350.778443 -218.997288)
			(xy 350.729164 -219.0133) (xy 350.677987 -219.021406) (xy 350.626173 -219.021406) (xy 350.574996 -219.0133)
			(xy 350.525717 -218.997288) (xy 350.47955 -218.973765) (xy 350.437631 -218.943309) (xy 350.400993 -218.906671)
			(xy 350.370537 -218.864752) (xy 350.347014 -218.818585) (xy 350.331002 -218.769306) (xy 350.322896 -218.718129)
			(xy 350.322388 -218.692222) (xy 350.322988 -218.664505) (xy 350.332307 -218.609859) (xy 350.34093 -218.58351)
			(xy 350.348804 -218.561412) (xy 350.143826 -218.206574) (xy 350.120966 -218.202256) (xy 350.096162 -218.197073)
			(xy 350.048424 -218.180081) (xy 350.003849 -218.155985) (xy 349.963484 -218.125353) (xy 349.928282 -218.088906)
			(xy 349.89907 -218.047502) (xy 349.876537 -218.002116) (xy 349.861213 -217.953817) (xy 349.85346 -217.903742)
			(xy 349.852996 -217.878406) (xy 349.572072 -217.878406) (xy 349.571564 -217.904293) (xy 349.563465 -217.955431)
			(xy 349.547466 -218.004671) (xy 349.52396 -218.050803) (xy 349.493528 -218.09269) (xy 349.456918 -218.1293)
			(xy 349.415031 -218.159732) (xy 349.368899 -218.183238) (xy 349.319659 -218.199237) (xy 349.268521 -218.207336)
			(xy 349.216747 -218.207336) (xy 349.165609 -218.199237) (xy 349.116369 -218.183238) (xy 349.070237 -218.159732)
			(xy 349.02835 -218.1293) (xy 348.99174 -218.09269) (xy 348.961308 -218.050803) (xy 348.937802 -218.004671)
			(xy 348.921803 -217.955431) (xy 348.913704 -217.904293) (xy 348.913196 -217.878406) (xy 348.632272 -217.878406)
			(xy 348.631741 -217.906114) (xy 348.622546 -217.960761) (xy 348.613984 -217.987118) (xy 348.60611 -218.009216)
			(xy 348.811088 -218.364054) (xy 348.833948 -218.368372) (xy 348.858763 -218.373563) (xy 348.906541 -218.390515)
			(xy 348.951159 -218.414584) (xy 348.991565 -218.445202) (xy 349.026806 -218.481645) (xy 349.05605 -218.523056)
			(xy 349.078609 -218.568456) (xy 349.093949 -218.616776) (xy 349.101708 -218.666874) (xy 349.102172 -218.692222)
			(xy 349.101664 -218.718129) (xy 349.093558 -218.769306) (xy 349.077546 -218.818585) (xy 349.054023 -218.864752)
			(xy 349.023567 -218.906671) (xy 348.986929 -218.943309) (xy 348.94501 -218.973765) (xy 348.898843 -218.997288)
			(xy 348.849564 -219.0133) (xy 348.798387 -219.021406) (xy 348.746573 -219.021406) (xy 348.695396 -219.0133)
			(xy 348.646117 -218.997288) (xy 348.59995 -218.973765) (xy 348.558031 -218.943309) (xy 348.521393 -218.906671)
			(xy 348.490937 -218.864752) (xy 348.467414 -218.818585) (xy 348.451402 -218.769306) (xy 348.443296 -218.718129)
			(xy 348.442788 -218.692222) (xy 348.443388 -218.664505) (xy 348.452707 -218.609859) (xy 348.46133 -218.58351)
			(xy 348.469204 -218.561412) (xy 348.264226 -218.206574) (xy 348.241366 -218.202256) (xy 348.216562 -218.197073)
			(xy 348.168824 -218.180081) (xy 348.124249 -218.155985) (xy 348.083884 -218.125353) (xy 348.048682 -218.088906)
			(xy 348.01947 -218.047502) (xy 347.996937 -218.002116) (xy 347.981613 -217.953817) (xy 347.97386 -217.903742)
			(xy 347.973396 -217.878406) (xy 347.692472 -217.878406) (xy 347.691964 -217.904293) (xy 347.683865 -217.955431)
			(xy 347.667866 -218.004671) (xy 347.64436 -218.050803) (xy 347.613928 -218.09269) (xy 347.577318 -218.1293)
			(xy 347.535431 -218.159732) (xy 347.489299 -218.183238) (xy 347.440059 -218.199237) (xy 347.388921 -218.207336)
			(xy 347.337147 -218.207336) (xy 347.286009 -218.199237) (xy 347.236769 -218.183238) (xy 347.190637 -218.159732)
			(xy 347.14875 -218.1293) (xy 347.11214 -218.09269) (xy 347.081708 -218.050803) (xy 347.058202 -218.004671)
			(xy 347.042203 -217.955431) (xy 347.034104 -217.904293) (xy 347.033596 -217.878406) (xy 346.752672 -217.878406)
			(xy 346.752141 -217.906114) (xy 346.742946 -217.960761) (xy 346.734384 -217.987118) (xy 346.72651 -218.009216)
			(xy 346.931488 -218.364054) (xy 346.954348 -218.368372) (xy 346.979163 -218.373563) (xy 347.026941 -218.390515)
			(xy 347.071559 -218.414584) (xy 347.111965 -218.445202) (xy 347.147206 -218.481645) (xy 347.17645 -218.523056)
			(xy 347.199009 -218.568456) (xy 347.214349 -218.616776) (xy 347.222108 -218.666874) (xy 347.222572 -218.692222)
			(xy 347.222064 -218.718129) (xy 347.213958 -218.769306) (xy 347.197946 -218.818585) (xy 347.174423 -218.864752)
			(xy 347.143967 -218.906671) (xy 347.107329 -218.943309) (xy 347.06541 -218.973765) (xy 347.019243 -218.997288)
			(xy 346.969964 -219.0133) (xy 346.918787 -219.021406) (xy 346.866973 -219.021406) (xy 346.815796 -219.0133)
			(xy 346.766517 -218.997288) (xy 346.72035 -218.973765) (xy 346.678431 -218.943309) (xy 346.641793 -218.906671)
			(xy 346.611337 -218.864752) (xy 346.587814 -218.818585) (xy 346.571802 -218.769306) (xy 346.563696 -218.718129)
			(xy 346.563188 -218.692222) (xy 346.563788 -218.664505) (xy 346.573107 -218.609859) (xy 346.58173 -218.58351)
			(xy 346.589604 -218.561412) (xy 346.384626 -218.206574) (xy 346.361766 -218.202256) (xy 346.336962 -218.197073)
			(xy 346.289224 -218.180081) (xy 346.244649 -218.155985) (xy 346.204284 -218.125353) (xy 346.169082 -218.088906)
			(xy 346.13987 -218.047502) (xy 346.117337 -218.002116) (xy 346.102013 -217.953817) (xy 346.09426 -217.903742)
			(xy 346.093796 -217.878406) (xy 345.812872 -217.878406) (xy 345.812364 -217.904293) (xy 345.804265 -217.955431)
			(xy 345.788266 -218.004671) (xy 345.76476 -218.050803) (xy 345.734328 -218.09269) (xy 345.697718 -218.1293)
			(xy 345.655831 -218.159732) (xy 345.609699 -218.183238) (xy 345.560459 -218.199237) (xy 345.509321 -218.207336)
			(xy 345.457547 -218.207336) (xy 345.406409 -218.199237) (xy 345.357169 -218.183238) (xy 345.311037 -218.159732)
			(xy 345.26915 -218.1293) (xy 345.23254 -218.09269) (xy 345.202108 -218.050803) (xy 345.178602 -218.004671)
			(xy 345.162603 -217.955431) (xy 345.154504 -217.904293) (xy 345.153996 -217.878406) (xy 344.873072 -217.878406)
			(xy 344.872541 -217.906114) (xy 344.863346 -217.960761) (xy 344.854784 -217.987118) (xy 344.84691 -218.009216)
			(xy 345.051888 -218.364054) (xy 345.074748 -218.368372) (xy 345.099563 -218.373563) (xy 345.147341 -218.390515)
			(xy 345.191959 -218.414584) (xy 345.232365 -218.445202) (xy 345.267606 -218.481645) (xy 345.29685 -218.523056)
			(xy 345.319409 -218.568456) (xy 345.334749 -218.616776) (xy 345.342508 -218.666874) (xy 345.342972 -218.692222)
			(xy 345.342464 -218.718129) (xy 345.334358 -218.769306) (xy 345.318346 -218.818585) (xy 345.294823 -218.864752)
			(xy 345.264367 -218.906671) (xy 345.227729 -218.943309) (xy 345.18581 -218.973765) (xy 345.139643 -218.997288)
			(xy 345.090364 -219.0133) (xy 345.039187 -219.021406) (xy 344.987373 -219.021406) (xy 344.936196 -219.0133)
			(xy 344.886917 -218.997288) (xy 344.84075 -218.973765) (xy 344.798831 -218.943309) (xy 344.762193 -218.906671)
			(xy 344.731737 -218.864752) (xy 344.708214 -218.818585) (xy 344.692202 -218.769306) (xy 344.684096 -218.718129)
			(xy 344.683588 -218.692222) (xy 344.684188 -218.664505) (xy 344.693507 -218.609859) (xy 344.70213 -218.58351)
			(xy 344.710004 -218.561412) (xy 344.505026 -218.206574) (xy 344.482166 -218.202256) (xy 344.457362 -218.197073)
			(xy 344.409624 -218.180081) (xy 344.365049 -218.155985) (xy 344.324684 -218.125353) (xy 344.289482 -218.088906)
			(xy 344.26027 -218.047502) (xy 344.237737 -218.002116) (xy 344.222413 -217.953817) (xy 344.21466 -217.903742)
			(xy 344.214196 -217.878406) (xy 343.933272 -217.878406) (xy 343.932764 -217.904293) (xy 343.924665 -217.955431)
			(xy 343.908666 -218.004671) (xy 343.88516 -218.050803) (xy 343.854728 -218.09269) (xy 343.818118 -218.1293)
			(xy 343.776231 -218.159732) (xy 343.730099 -218.183238) (xy 343.680859 -218.199237) (xy 343.629721 -218.207336)
			(xy 343.577947 -218.207336) (xy 343.526809 -218.199237) (xy 343.477569 -218.183238) (xy 343.431437 -218.159732)
			(xy 343.38955 -218.1293) (xy 343.35294 -218.09269) (xy 343.322508 -218.050803) (xy 343.299002 -218.004671)
			(xy 343.283003 -217.955431) (xy 343.274904 -217.904293) (xy 343.274396 -217.878406) (xy 342.993472 -217.878406)
			(xy 342.992941 -217.906114) (xy 342.983746 -217.960761) (xy 342.975184 -217.987118) (xy 342.96731 -218.009216)
			(xy 343.172288 -218.364054) (xy 343.195148 -218.368372) (xy 343.219963 -218.373563) (xy 343.267741 -218.390515)
			(xy 343.312359 -218.414584) (xy 343.352765 -218.445202) (xy 343.388006 -218.481645) (xy 343.41725 -218.523056)
			(xy 343.439809 -218.568456) (xy 343.455149 -218.616776) (xy 343.462908 -218.666874) (xy 343.463372 -218.692222)
			(xy 343.462864 -218.718129) (xy 343.454758 -218.769306) (xy 343.438746 -218.818585) (xy 343.415223 -218.864752)
			(xy 343.384767 -218.906671) (xy 343.348129 -218.943309) (xy 343.30621 -218.973765) (xy 343.260043 -218.997288)
			(xy 343.210764 -219.0133) (xy 343.159587 -219.021406) (xy 343.107773 -219.021406) (xy 343.056596 -219.0133)
			(xy 343.007317 -218.997288) (xy 342.96115 -218.973765) (xy 342.919231 -218.943309) (xy 342.882593 -218.906671)
			(xy 342.852137 -218.864752) (xy 342.828614 -218.818585) (xy 342.812602 -218.769306) (xy 342.804496 -218.718129)
			(xy 342.803988 -218.692222) (xy 342.804588 -218.664505) (xy 342.813907 -218.609859) (xy 342.82253 -218.58351)
			(xy 342.830404 -218.561412) (xy 342.625426 -218.206574) (xy 342.602566 -218.202256) (xy 342.577762 -218.197073)
			(xy 342.530024 -218.180081) (xy 342.485449 -218.155985) (xy 342.445084 -218.125353) (xy 342.409882 -218.088906)
			(xy 342.38067 -218.047502) (xy 342.358137 -218.002116) (xy 342.342813 -217.953817) (xy 342.33506 -217.903742)
			(xy 342.334596 -217.878406) (xy 342.053672 -217.878406) (xy 342.053164 -217.904293) (xy 342.045065 -217.955431)
			(xy 342.029066 -218.004671) (xy 342.00556 -218.050803) (xy 341.975128 -218.09269) (xy 341.938518 -218.1293)
			(xy 341.896631 -218.159732) (xy 341.850499 -218.183238) (xy 341.801259 -218.199237) (xy 341.750121 -218.207336)
			(xy 341.698347 -218.207336) (xy 341.647209 -218.199237) (xy 341.597969 -218.183238) (xy 341.551837 -218.159732)
			(xy 341.50995 -218.1293) (xy 341.47334 -218.09269) (xy 341.442908 -218.050803) (xy 341.419402 -218.004671)
			(xy 341.403403 -217.955431) (xy 341.395304 -217.904293) (xy 341.394796 -217.878406) (xy 341.113872 -217.878406)
			(xy 341.113341 -217.906114) (xy 341.104146 -217.960761) (xy 341.095584 -217.987118) (xy 341.08771 -218.009216)
			(xy 341.292688 -218.364054) (xy 341.315548 -218.368372) (xy 341.340363 -218.373563) (xy 341.388141 -218.390515)
			(xy 341.432759 -218.414584) (xy 341.473165 -218.445202) (xy 341.508406 -218.481645) (xy 341.53765 -218.523056)
			(xy 341.560209 -218.568456) (xy 341.575549 -218.616776) (xy 341.583308 -218.666874) (xy 341.583772 -218.692222)
			(xy 341.583264 -218.718129) (xy 341.575158 -218.769306) (xy 341.559146 -218.818585) (xy 341.535623 -218.864752)
			(xy 341.505167 -218.906671) (xy 341.468529 -218.943309) (xy 341.42661 -218.973765) (xy 341.380443 -218.997288)
			(xy 341.331164 -219.0133) (xy 341.279987 -219.021406) (xy 341.228173 -219.021406) (xy 341.176996 -219.0133)
			(xy 341.127717 -218.997288) (xy 341.08155 -218.973765) (xy 341.039631 -218.943309) (xy 341.002993 -218.906671)
			(xy 340.972537 -218.864752) (xy 340.949014 -218.818585) (xy 340.933002 -218.769306) (xy 340.924896 -218.718129)
			(xy 340.924388 -218.692222) (xy 340.924988 -218.664505) (xy 340.934307 -218.609859) (xy 340.94293 -218.58351)
			(xy 340.950804 -218.561412) (xy 340.745826 -218.206574) (xy 340.722966 -218.202256) (xy 340.698162 -218.197073)
			(xy 340.650424 -218.180081) (xy 340.605849 -218.155985) (xy 340.565484 -218.125353) (xy 340.530282 -218.088906)
			(xy 340.50107 -218.047502) (xy 340.478537 -218.002116) (xy 340.463213 -217.953817) (xy 340.45546 -217.903742)
			(xy 340.454996 -217.878406) (xy 340.174072 -217.878406) (xy 340.173564 -217.904293) (xy 340.165465 -217.955431)
			(xy 340.149466 -218.004671) (xy 340.12596 -218.050803) (xy 340.095528 -218.09269) (xy 340.058918 -218.1293)
			(xy 340.017031 -218.159732) (xy 339.970899 -218.183238) (xy 339.921659 -218.199237) (xy 339.870521 -218.207336)
			(xy 339.818747 -218.207336) (xy 339.767609 -218.199237) (xy 339.718369 -218.183238) (xy 339.672237 -218.159732)
			(xy 339.63035 -218.1293) (xy 339.59374 -218.09269) (xy 339.563308 -218.050803) (xy 339.539802 -218.004671)
			(xy 339.523803 -217.955431) (xy 339.515704 -217.904293) (xy 339.515196 -217.878406) (xy 339.234272 -217.878406)
			(xy 339.233741 -217.906114) (xy 339.224546 -217.960761) (xy 339.215984 -217.987118) (xy 339.20811 -218.009216)
			(xy 339.413088 -218.364054) (xy 339.435948 -218.368372) (xy 339.460763 -218.373563) (xy 339.508541 -218.390515)
			(xy 339.553159 -218.414584) (xy 339.593565 -218.445202) (xy 339.628806 -218.481645) (xy 339.65805 -218.523056)
			(xy 339.680609 -218.568456) (xy 339.695949 -218.616776) (xy 339.703708 -218.666874) (xy 339.704172 -218.692222)
			(xy 339.703664 -218.718129) (xy 339.695558 -218.769306) (xy 339.679546 -218.818585) (xy 339.656023 -218.864752)
			(xy 339.625567 -218.906671) (xy 339.588929 -218.943309) (xy 339.54701 -218.973765) (xy 339.500843 -218.997288)
			(xy 339.451564 -219.0133) (xy 339.400387 -219.021406) (xy 339.348573 -219.021406) (xy 339.297396 -219.0133)
			(xy 339.248117 -218.997288) (xy 339.20195 -218.973765) (xy 339.160031 -218.943309) (xy 339.123393 -218.906671)
			(xy 339.092937 -218.864752) (xy 339.069414 -218.818585) (xy 339.053402 -218.769306) (xy 339.045296 -218.718129)
			(xy 339.044788 -218.692222) (xy 339.045388 -218.664505) (xy 339.054707 -218.609859) (xy 339.06333 -218.58351)
			(xy 339.071204 -218.561412) (xy 338.866226 -218.206574) (xy 338.843366 -218.202256) (xy 338.818562 -218.197073)
			(xy 338.770824 -218.180081) (xy 338.726249 -218.155985) (xy 338.685884 -218.125353) (xy 338.650682 -218.088906)
			(xy 338.62147 -218.047502) (xy 338.598937 -218.002116) (xy 338.583613 -217.953817) (xy 338.57586 -217.903742)
			(xy 338.575396 -217.878406) (xy 338.294472 -217.878406) (xy 338.293964 -217.904293) (xy 338.285865 -217.955431)
			(xy 338.269866 -218.004671) (xy 338.24636 -218.050803) (xy 338.215928 -218.09269) (xy 338.179318 -218.1293)
			(xy 338.137431 -218.159732) (xy 338.091299 -218.183238) (xy 338.042059 -218.199237) (xy 337.990921 -218.207336)
			(xy 337.939147 -218.207336) (xy 337.888009 -218.199237) (xy 337.838769 -218.183238) (xy 337.792637 -218.159732)
			(xy 337.75075 -218.1293) (xy 337.71414 -218.09269) (xy 337.683708 -218.050803) (xy 337.660202 -218.004671)
			(xy 337.644203 -217.955431) (xy 337.636104 -217.904293) (xy 337.635596 -217.878406) (xy 337.354672 -217.878406)
			(xy 337.354141 -217.906114) (xy 337.344946 -217.960761) (xy 337.336384 -217.987118) (xy 337.32851 -218.009216)
			(xy 337.533488 -218.364054) (xy 337.556348 -218.368372) (xy 337.581163 -218.373563) (xy 337.628941 -218.390515)
			(xy 337.673559 -218.414584) (xy 337.713965 -218.445202) (xy 337.749206 -218.481645) (xy 337.77845 -218.523056)
			(xy 337.801009 -218.568456) (xy 337.816349 -218.616776) (xy 337.824108 -218.666874) (xy 337.824572 -218.692222)
			(xy 337.824064 -218.718129) (xy 337.815958 -218.769306) (xy 337.799946 -218.818585) (xy 337.776423 -218.864752)
			(xy 337.745967 -218.906671) (xy 337.709329 -218.943309) (xy 337.66741 -218.973765) (xy 337.621243 -218.997288)
			(xy 337.571964 -219.0133) (xy 337.520787 -219.021406) (xy 337.468973 -219.021406) (xy 337.417796 -219.0133)
			(xy 337.368517 -218.997288) (xy 337.32235 -218.973765) (xy 337.280431 -218.943309) (xy 337.243793 -218.906671)
			(xy 337.213337 -218.864752) (xy 337.189814 -218.818585) (xy 337.173802 -218.769306) (xy 337.165696 -218.718129)
			(xy 337.165188 -218.692222) (xy 337.165788 -218.664505) (xy 337.175107 -218.609859) (xy 337.18373 -218.58351)
			(xy 337.191604 -218.561412) (xy 336.986626 -218.206574) (xy 336.963766 -218.202256) (xy 336.938962 -218.197073)
			(xy 336.891224 -218.180081) (xy 336.846649 -218.155985) (xy 336.806284 -218.125353) (xy 336.771082 -218.088906)
			(xy 336.74187 -218.047502) (xy 336.719337 -218.002116) (xy 336.704013 -217.953817) (xy 336.69626 -217.903742)
			(xy 336.695796 -217.878406) (xy 313.738768 -217.878406) (xy 313.738768 -217.921332) (xy 313.738404 -217.931492)
			(xy 313.730592 -217.950252) (xy 313.716177 -217.964575) (xy 313.697369 -217.972268) (xy 313.687206 -217.97264)
			(xy 312.287666 -217.97264) (xy 312.277535 -217.972201) (xy 312.258809 -217.964458) (xy 312.244453 -217.950157)
			(xy 312.236639 -217.931461) (xy 312.236104 -217.921332) (xy 306.194968 -217.921332) (xy 306.194604 -217.931492)
			(xy 306.186792 -217.950252) (xy 306.172377 -217.964575) (xy 306.153569 -217.972268) (xy 306.143406 -217.97264)
			(xy 304.743866 -217.97264) (xy 304.733735 -217.972201) (xy 304.715009 -217.964458) (xy 304.700653 -217.950157)
			(xy 304.692839 -217.931461) (xy 304.692304 -217.921332) (xy 298.651168 -217.921332) (xy 298.650804 -217.931492)
			(xy 298.642992 -217.950252) (xy 298.628577 -217.964575) (xy 298.609769 -217.972268) (xy 298.599606 -217.97264)
			(xy 297.200066 -217.97264) (xy 297.189935 -217.972201) (xy 297.171209 -217.964458) (xy 297.156853 -217.950157)
			(xy 297.149039 -217.931461) (xy 297.148504 -217.921332) (xy 291.107368 -217.921332) (xy 291.107004 -217.931492)
			(xy 291.099192 -217.950252) (xy 291.084777 -217.964575) (xy 291.065969 -217.972268) (xy 291.055806 -217.97264)
			(xy 289.656266 -217.97264) (xy 289.646135 -217.972201) (xy 289.627409 -217.964458) (xy 289.613053 -217.950157)
			(xy 289.605239 -217.931461) (xy 289.604704 -217.921332) (xy 283.563568 -217.921332) (xy 283.563204 -217.931492)
			(xy 283.555392 -217.950252) (xy 283.540977 -217.964575) (xy 283.522169 -217.972268) (xy 283.512006 -217.97264)
			(xy 282.112466 -217.97264) (xy 282.102335 -217.972201) (xy 282.083609 -217.964458) (xy 282.069253 -217.950157)
			(xy 282.061439 -217.931461) (xy 282.060904 -217.921332) (xy 276.019768 -217.921332) (xy 276.019404 -217.931492)
			(xy 276.011592 -217.950252) (xy 275.997177 -217.964575) (xy 275.978369 -217.972268) (xy 275.968206 -217.97264)
			(xy 274.568666 -217.97264) (xy 274.558535 -217.972201) (xy 274.539809 -217.964458) (xy 274.525453 -217.950157)
			(xy 274.517639 -217.931461) (xy 274.517104 -217.921332) (xy 268.475968 -217.921332) (xy 268.475604 -217.931492)
			(xy 268.467792 -217.950252) (xy 268.453377 -217.964575) (xy 268.434569 -217.972268) (xy 268.424406 -217.97264)
			(xy 267.024866 -217.97264) (xy 267.014735 -217.972201) (xy 266.996009 -217.964458) (xy 266.981653 -217.950157)
			(xy 266.973839 -217.931461) (xy 266.973304 -217.921332) (xy 260.932168 -217.921332) (xy 260.931804 -217.931492)
			(xy 260.923992 -217.950252) (xy 260.909577 -217.964575) (xy 260.890769 -217.972268) (xy 260.880606 -217.97264)
			(xy 259.481066 -217.97264) (xy 259.470935 -217.972201) (xy 259.452209 -217.964458) (xy 259.437853 -217.950157)
			(xy 259.430039 -217.931461) (xy 259.429504 -217.921332) (xy 216.4715 -217.921332) (xy 216.471105 -217.931488)
			(xy 216.463298 -217.950241) (xy 216.448894 -217.964564) (xy 216.430097 -217.972262) (xy 216.419938 -217.97264)
			(xy 215.020398 -217.97264) (xy 215.010269 -217.972174) (xy 214.991544 -217.964442) (xy 214.977187 -217.950149)
			(xy 214.969371 -217.931459) (xy 214.968836 -217.921332) (xy 208.9277 -217.921332) (xy 208.927305 -217.931488)
			(xy 208.919498 -217.950241) (xy 208.905094 -217.964564) (xy 208.886297 -217.972262) (xy 208.876138 -217.97264)
			(xy 207.476598 -217.97264) (xy 207.466469 -217.972174) (xy 207.447744 -217.964442) (xy 207.433387 -217.950149)
			(xy 207.425571 -217.931459) (xy 207.425036 -217.921332) (xy 201.3839 -217.921332) (xy 201.383505 -217.931488)
			(xy 201.375698 -217.950241) (xy 201.361294 -217.964564) (xy 201.342497 -217.972262) (xy 201.332338 -217.97264)
			(xy 199.932798 -217.97264) (xy 199.922669 -217.972174) (xy 199.903944 -217.964442) (xy 199.889587 -217.950149)
			(xy 199.881771 -217.931459) (xy 199.881236 -217.921332) (xy 193.8401 -217.921332) (xy 193.839705 -217.931488)
			(xy 193.831898 -217.950241) (xy 193.817494 -217.964564) (xy 193.798697 -217.972262) (xy 193.788538 -217.97264)
			(xy 192.388998 -217.97264) (xy 192.378869 -217.972174) (xy 192.360144 -217.964442) (xy 192.345787 -217.950149)
			(xy 192.337971 -217.931459) (xy 192.337436 -217.921332) (xy 186.2963 -217.921332) (xy 186.295905 -217.931488)
			(xy 186.288098 -217.950241) (xy 186.273694 -217.964564) (xy 186.254897 -217.972262) (xy 186.244738 -217.97264)
			(xy 184.845198 -217.97264) (xy 184.835069 -217.972174) (xy 184.816344 -217.964442) (xy 184.801987 -217.950149)
			(xy 184.794171 -217.931459) (xy 184.793636 -217.921332) (xy 178.7525 -217.921332) (xy 178.752105 -217.931488)
			(xy 178.744298 -217.950241) (xy 178.729894 -217.964564) (xy 178.711097 -217.972262) (xy 178.700938 -217.97264)
			(xy 177.301398 -217.97264) (xy 177.291269 -217.972174) (xy 177.272544 -217.964442) (xy 177.258187 -217.950149)
			(xy 177.250371 -217.931459) (xy 177.249836 -217.921332) (xy 171.2087 -217.921332) (xy 171.208305 -217.931488)
			(xy 171.200498 -217.950241) (xy 171.186094 -217.964564) (xy 171.167297 -217.972262) (xy 171.157138 -217.97264)
			(xy 169.757598 -217.97264) (xy 169.747469 -217.972174) (xy 169.728744 -217.964442) (xy 169.714387 -217.950149)
			(xy 169.706571 -217.931459) (xy 169.706036 -217.921332) (xy 163.6649 -217.921332) (xy 163.664505 -217.931488)
			(xy 163.656698 -217.950241) (xy 163.642294 -217.964564) (xy 163.623497 -217.972262) (xy 163.613338 -217.97264)
			(xy 162.213798 -217.97264) (xy 162.203669 -217.972174) (xy 162.184944 -217.964442) (xy 162.170587 -217.950149)
			(xy 162.162771 -217.931459) (xy 162.162236 -217.921332) (xy 134.521797 -217.921332) (xy 134.516397 -217.955431)
			(xy 134.500398 -218.004671) (xy 134.476892 -218.050803) (xy 134.44646 -218.09269) (xy 134.40985 -218.1293)
			(xy 134.367963 -218.159732) (xy 134.321831 -218.183238) (xy 134.272591 -218.199237) (xy 134.221453 -218.207336)
			(xy 134.169679 -218.207336) (xy 134.118541 -218.199237) (xy 134.069301 -218.183238) (xy 134.023169 -218.159732)
			(xy 133.981282 -218.1293) (xy 133.944672 -218.09269) (xy 133.91424 -218.050803) (xy 133.890734 -218.004671)
			(xy 133.874735 -217.955431) (xy 133.866636 -217.904293) (xy 133.866128 -217.878406) (xy 133.866662 -217.850698)
			(xy 133.875855 -217.796051) (xy 133.884416 -217.769694) (xy 133.89229 -217.747596) (xy 133.687312 -217.392504)
			(xy 133.664452 -217.388186) (xy 133.639596 -217.383069) (xy 133.591748 -217.366166) (xy 133.547056 -217.342128)
			(xy 133.506577 -217.311523) (xy 133.471267 -217.275076) (xy 133.441961 -217.233647) (xy 133.419352 -217.188215)
			(xy 133.403974 -217.139855) (xy 133.39619 -217.089709) (xy 133.39572 -217.064336) (xy 132.175504 -217.064336)
			(xy 132.174889 -217.091989) (xy 132.165569 -217.146507) (xy 132.156962 -217.172794) (xy 132.149342 -217.194892)
			(xy 132.354574 -217.550238) (xy 132.377434 -217.554556) (xy 132.402241 -217.559728) (xy 132.449979 -217.576721)
			(xy 132.494556 -217.600818) (xy 132.53492 -217.631451) (xy 132.570123 -217.6679) (xy 132.599334 -217.709305)
			(xy 132.621866 -217.754693) (xy 132.637189 -217.802993) (xy 132.644941 -217.85307) (xy 132.645404 -217.878406)
			(xy 132.644896 -217.904293) (xy 132.636797 -217.955431) (xy 132.620798 -218.004671) (xy 132.597292 -218.050803)
			(xy 132.56686 -218.09269) (xy 132.53025 -218.1293) (xy 132.488363 -218.159732) (xy 132.442231 -218.183238)
			(xy 132.392991 -218.199237) (xy 132.341853 -218.207336) (xy 132.290079 -218.207336) (xy 132.238941 -218.199237)
			(xy 132.189701 -218.183238) (xy 132.143569 -218.159732) (xy 132.101682 -218.1293) (xy 132.065072 -218.09269)
			(xy 132.03464 -218.050803) (xy 132.011134 -218.004671) (xy 131.995135 -217.955431) (xy 131.987036 -217.904293)
			(xy 131.986528 -217.878406) (xy 131.987062 -217.850698) (xy 131.996255 -217.796051) (xy 132.004816 -217.769694)
			(xy 132.01269 -217.747596) (xy 131.807712 -217.392504) (xy 131.784852 -217.388186) (xy 131.759996 -217.383069)
			(xy 131.712148 -217.366166) (xy 131.667456 -217.342128) (xy 131.626977 -217.311523) (xy 131.591667 -217.275076)
			(xy 131.562361 -217.233647) (xy 131.539752 -217.188215) (xy 131.524374 -217.139855) (xy 131.51659 -217.089709)
			(xy 131.51612 -217.064336) (xy 130.295904 -217.064336) (xy 130.295289 -217.091989) (xy 130.285969 -217.146507)
			(xy 130.277362 -217.172794) (xy 130.269742 -217.194892) (xy 130.474974 -217.550238) (xy 130.497834 -217.554556)
			(xy 130.522641 -217.559728) (xy 130.570379 -217.576721) (xy 130.614956 -217.600818) (xy 130.65532 -217.631451)
			(xy 130.690523 -217.6679) (xy 130.719734 -217.709305) (xy 130.742266 -217.754693) (xy 130.757589 -217.802993)
			(xy 130.765341 -217.85307) (xy 130.765804 -217.878406) (xy 130.765296 -217.904293) (xy 130.757197 -217.955431)
			(xy 130.741198 -218.004671) (xy 130.717692 -218.050803) (xy 130.68726 -218.09269) (xy 130.65065 -218.1293)
			(xy 130.608763 -218.159732) (xy 130.562631 -218.183238) (xy 130.513391 -218.199237) (xy 130.462253 -218.207336)
			(xy 130.410479 -218.207336) (xy 130.359341 -218.199237) (xy 130.310101 -218.183238) (xy 130.263969 -218.159732)
			(xy 130.222082 -218.1293) (xy 130.185472 -218.09269) (xy 130.15504 -218.050803) (xy 130.131534 -218.004671)
			(xy 130.115535 -217.955431) (xy 130.107436 -217.904293) (xy 130.106928 -217.878406) (xy 130.107462 -217.850698)
			(xy 130.116655 -217.796051) (xy 130.125216 -217.769694) (xy 130.13309 -217.747596) (xy 129.928112 -217.392504)
			(xy 129.905252 -217.388186) (xy 129.880396 -217.383069) (xy 129.832548 -217.366166) (xy 129.787856 -217.342128)
			(xy 129.747377 -217.311523) (xy 129.712067 -217.275076) (xy 129.682761 -217.233647) (xy 129.660152 -217.188215)
			(xy 129.644774 -217.139855) (xy 129.63699 -217.089709) (xy 129.63652 -217.064336) (xy 128.416304 -217.064336)
			(xy 128.415689 -217.091989) (xy 128.406369 -217.146507) (xy 128.397762 -217.172794) (xy 128.390142 -217.194892)
			(xy 128.595374 -217.550238) (xy 128.618234 -217.554556) (xy 128.643041 -217.559728) (xy 128.690779 -217.576721)
			(xy 128.735356 -217.600818) (xy 128.77572 -217.631451) (xy 128.810923 -217.6679) (xy 128.840134 -217.709305)
			(xy 128.862666 -217.754693) (xy 128.877989 -217.802993) (xy 128.885741 -217.85307) (xy 128.886204 -217.878406)
			(xy 128.885696 -217.904293) (xy 128.877597 -217.955431) (xy 128.861598 -218.004671) (xy 128.838092 -218.050803)
			(xy 128.80766 -218.09269) (xy 128.77105 -218.1293) (xy 128.729163 -218.159732) (xy 128.683031 -218.183238)
			(xy 128.633791 -218.199237) (xy 128.582653 -218.207336) (xy 128.530879 -218.207336) (xy 128.479741 -218.199237)
			(xy 128.430501 -218.183238) (xy 128.384369 -218.159732) (xy 128.342482 -218.1293) (xy 128.305872 -218.09269)
			(xy 128.27544 -218.050803) (xy 128.251934 -218.004671) (xy 128.235935 -217.955431) (xy 128.227836 -217.904293)
			(xy 128.227328 -217.878406) (xy 128.227862 -217.850698) (xy 128.237055 -217.796051) (xy 128.245616 -217.769694)
			(xy 128.25349 -217.747596) (xy 128.048512 -217.392504) (xy 128.025652 -217.388186) (xy 128.000796 -217.383069)
			(xy 127.952948 -217.366166) (xy 127.908256 -217.342128) (xy 127.867777 -217.311523) (xy 127.832467 -217.275076)
			(xy 127.803161 -217.233647) (xy 127.780552 -217.188215) (xy 127.765174 -217.139855) (xy 127.75739 -217.089709)
			(xy 127.75692 -217.064336) (xy 126.536704 -217.064336) (xy 126.536089 -217.091989) (xy 126.526769 -217.146507)
			(xy 126.518162 -217.172794) (xy 126.510542 -217.194892) (xy 126.715774 -217.550238) (xy 126.738634 -217.554556)
			(xy 126.763441 -217.559728) (xy 126.811179 -217.576721) (xy 126.855756 -217.600818) (xy 126.89612 -217.631451)
			(xy 126.931323 -217.6679) (xy 126.960534 -217.709305) (xy 126.983066 -217.754693) (xy 126.998389 -217.802993)
			(xy 127.006141 -217.85307) (xy 127.006604 -217.878406) (xy 127.006096 -217.904293) (xy 126.997997 -217.955431)
			(xy 126.981998 -218.004671) (xy 126.958492 -218.050803) (xy 126.92806 -218.09269) (xy 126.89145 -218.1293)
			(xy 126.849563 -218.159732) (xy 126.803431 -218.183238) (xy 126.754191 -218.199237) (xy 126.703053 -218.207336)
			(xy 126.651279 -218.207336) (xy 126.600141 -218.199237) (xy 126.550901 -218.183238) (xy 126.504769 -218.159732)
			(xy 126.462882 -218.1293) (xy 126.426272 -218.09269) (xy 126.39584 -218.050803) (xy 126.372334 -218.004671)
			(xy 126.356335 -217.955431) (xy 126.348236 -217.904293) (xy 126.347728 -217.878406) (xy 126.348262 -217.850698)
			(xy 126.357455 -217.796051) (xy 126.366016 -217.769694) (xy 126.37389 -217.747596) (xy 126.168912 -217.392504)
			(xy 126.146052 -217.388186) (xy 126.121196 -217.383069) (xy 126.073348 -217.366166) (xy 126.028656 -217.342128)
			(xy 125.988177 -217.311523) (xy 125.952867 -217.275076) (xy 125.923561 -217.233647) (xy 125.900952 -217.188215)
			(xy 125.885574 -217.139855) (xy 125.87779 -217.089709) (xy 125.87732 -217.064336) (xy 124.657104 -217.064336)
			(xy 124.656489 -217.091989) (xy 124.647169 -217.146507) (xy 124.638562 -217.172794) (xy 124.630942 -217.194892)
			(xy 124.836174 -217.550238) (xy 124.859034 -217.554556) (xy 124.883841 -217.559728) (xy 124.931579 -217.576721)
			(xy 124.976156 -217.600818) (xy 125.01652 -217.631451) (xy 125.051723 -217.6679) (xy 125.080934 -217.709305)
			(xy 125.103466 -217.754693) (xy 125.118789 -217.802993) (xy 125.126541 -217.85307) (xy 125.127004 -217.878406)
			(xy 125.126496 -217.904293) (xy 125.118397 -217.955431) (xy 125.102398 -218.004671) (xy 125.078892 -218.050803)
			(xy 125.04846 -218.09269) (xy 125.01185 -218.1293) (xy 124.969963 -218.159732) (xy 124.923831 -218.183238)
			(xy 124.874591 -218.199237) (xy 124.823453 -218.207336) (xy 124.771679 -218.207336) (xy 124.720541 -218.199237)
			(xy 124.671301 -218.183238) (xy 124.625169 -218.159732) (xy 124.583282 -218.1293) (xy 124.546672 -218.09269)
			(xy 124.51624 -218.050803) (xy 124.492734 -218.004671) (xy 124.476735 -217.955431) (xy 124.468636 -217.904293)
			(xy 124.468128 -217.878406) (xy 124.468662 -217.850698) (xy 124.477855 -217.796051) (xy 124.486416 -217.769694)
			(xy 124.49429 -217.747596) (xy 124.289312 -217.392504) (xy 124.266452 -217.388186) (xy 124.241596 -217.383069)
			(xy 124.193748 -217.366166) (xy 124.149056 -217.342128) (xy 124.108577 -217.311523) (xy 124.073267 -217.275076)
			(xy 124.043961 -217.233647) (xy 124.021352 -217.188215) (xy 124.005974 -217.139855) (xy 123.99819 -217.089709)
			(xy 123.99772 -217.064336) (xy 122.777504 -217.064336) (xy 122.776889 -217.091989) (xy 122.767569 -217.146507)
			(xy 122.758962 -217.172794) (xy 122.751342 -217.194892) (xy 122.956574 -217.550238) (xy 122.979434 -217.554556)
			(xy 123.004241 -217.559728) (xy 123.051979 -217.576721) (xy 123.096556 -217.600818) (xy 123.13692 -217.631451)
			(xy 123.172123 -217.6679) (xy 123.201334 -217.709305) (xy 123.223866 -217.754693) (xy 123.239189 -217.802993)
			(xy 123.246941 -217.85307) (xy 123.247404 -217.878406) (xy 123.246896 -217.904293) (xy 123.238797 -217.955431)
			(xy 123.222798 -218.004671) (xy 123.199292 -218.050803) (xy 123.16886 -218.09269) (xy 123.13225 -218.1293)
			(xy 123.090363 -218.159732) (xy 123.044231 -218.183238) (xy 122.994991 -218.199237) (xy 122.943853 -218.207336)
			(xy 122.892079 -218.207336) (xy 122.840941 -218.199237) (xy 122.791701 -218.183238) (xy 122.745569 -218.159732)
			(xy 122.703682 -218.1293) (xy 122.667072 -218.09269) (xy 122.63664 -218.050803) (xy 122.613134 -218.004671)
			(xy 122.597135 -217.955431) (xy 122.589036 -217.904293) (xy 122.588528 -217.878406) (xy 122.589062 -217.850698)
			(xy 122.598255 -217.796051) (xy 122.606816 -217.769694) (xy 122.61469 -217.747596) (xy 122.409712 -217.392504)
			(xy 122.386852 -217.388186) (xy 122.361996 -217.383069) (xy 122.314148 -217.366166) (xy 122.269456 -217.342128)
			(xy 122.228977 -217.311523) (xy 122.193667 -217.275076) (xy 122.164361 -217.233647) (xy 122.141752 -217.188215)
			(xy 122.126374 -217.139855) (xy 122.11859 -217.089709) (xy 122.11812 -217.064336) (xy 120.897904 -217.064336)
			(xy 120.897289 -217.091989) (xy 120.887969 -217.146507) (xy 120.879362 -217.172794) (xy 120.871742 -217.194892)
			(xy 121.076974 -217.550238) (xy 121.099834 -217.554556) (xy 121.124641 -217.559728) (xy 121.172379 -217.576721)
			(xy 121.216956 -217.600818) (xy 121.25732 -217.631451) (xy 121.292523 -217.6679) (xy 121.321734 -217.709305)
			(xy 121.344266 -217.754693) (xy 121.359589 -217.802993) (xy 121.367341 -217.85307) (xy 121.367804 -217.878406)
			(xy 121.367296 -217.904293) (xy 121.359197 -217.955431) (xy 121.343198 -218.004671) (xy 121.319692 -218.050803)
			(xy 121.28926 -218.09269) (xy 121.25265 -218.1293) (xy 121.210763 -218.159732) (xy 121.164631 -218.183238)
			(xy 121.115391 -218.199237) (xy 121.064253 -218.207336) (xy 121.012479 -218.207336) (xy 120.961341 -218.199237)
			(xy 120.912101 -218.183238) (xy 120.865969 -218.159732) (xy 120.824082 -218.1293) (xy 120.787472 -218.09269)
			(xy 120.75704 -218.050803) (xy 120.733534 -218.004671) (xy 120.717535 -217.955431) (xy 120.709436 -217.904293)
			(xy 120.708928 -217.878406) (xy 120.709462 -217.850698) (xy 120.718655 -217.796051) (xy 120.727216 -217.769694)
			(xy 120.73509 -217.747596) (xy 120.530112 -217.392504) (xy 120.507252 -217.388186) (xy 120.482396 -217.383069)
			(xy 120.434548 -217.366166) (xy 120.389856 -217.342128) (xy 120.349377 -217.311523) (xy 120.314067 -217.275076)
			(xy 120.284761 -217.233647) (xy 120.262152 -217.188215) (xy 120.246774 -217.139855) (xy 120.23899 -217.089709)
			(xy 120.23852 -217.064336) (xy 119.018304 -217.064336) (xy 119.017689 -217.091989) (xy 119.008369 -217.146507)
			(xy 118.999762 -217.172794) (xy 118.992142 -217.194892) (xy 119.197374 -217.550238) (xy 119.220234 -217.554556)
			(xy 119.245041 -217.559728) (xy 119.292779 -217.576721) (xy 119.337356 -217.600818) (xy 119.37772 -217.631451)
			(xy 119.412923 -217.6679) (xy 119.442134 -217.709305) (xy 119.464666 -217.754693) (xy 119.479989 -217.802993)
			(xy 119.487741 -217.85307) (xy 119.488204 -217.878406) (xy 119.487696 -217.904293) (xy 119.479597 -217.955431)
			(xy 119.463598 -218.004671) (xy 119.440092 -218.050803) (xy 119.40966 -218.09269) (xy 119.37305 -218.1293)
			(xy 119.331163 -218.159732) (xy 119.285031 -218.183238) (xy 119.235791 -218.199237) (xy 119.184653 -218.207336)
			(xy 119.132879 -218.207336) (xy 119.081741 -218.199237) (xy 119.032501 -218.183238) (xy 118.986369 -218.159732)
			(xy 118.944482 -218.1293) (xy 118.907872 -218.09269) (xy 118.87744 -218.050803) (xy 118.853934 -218.004671)
			(xy 118.837935 -217.955431) (xy 118.829836 -217.904293) (xy 118.829328 -217.878406) (xy 118.829862 -217.850698)
			(xy 118.839055 -217.796051) (xy 118.847616 -217.769694) (xy 118.85549 -217.747596) (xy 118.650512 -217.392504)
			(xy 118.627652 -217.388186) (xy 118.602796 -217.383069) (xy 118.554948 -217.366166) (xy 118.510256 -217.342128)
			(xy 118.469777 -217.311523) (xy 118.434467 -217.275076) (xy 118.405161 -217.233647) (xy 118.382552 -217.188215)
			(xy 118.367174 -217.139855) (xy 118.35939 -217.089709) (xy 118.35892 -217.064336) (xy 117.138704 -217.064336)
			(xy 117.138089 -217.091989) (xy 117.128769 -217.146507) (xy 117.120162 -217.172794) (xy 117.112542 -217.194892)
			(xy 117.317774 -217.550238) (xy 117.340634 -217.554556) (xy 117.365441 -217.559728) (xy 117.413179 -217.576721)
			(xy 117.457756 -217.600818) (xy 117.49812 -217.631451) (xy 117.533323 -217.6679) (xy 117.562534 -217.709305)
			(xy 117.585066 -217.754693) (xy 117.600389 -217.802993) (xy 117.608141 -217.85307) (xy 117.608604 -217.878406)
			(xy 117.608096 -217.904293) (xy 117.599997 -217.955431) (xy 117.583998 -218.004671) (xy 117.560492 -218.050803)
			(xy 117.53006 -218.09269) (xy 117.49345 -218.1293) (xy 117.451563 -218.159732) (xy 117.405431 -218.183238)
			(xy 117.356191 -218.199237) (xy 117.305053 -218.207336) (xy 117.253279 -218.207336) (xy 117.202141 -218.199237)
			(xy 117.152901 -218.183238) (xy 117.106769 -218.159732) (xy 117.064882 -218.1293) (xy 117.028272 -218.09269)
			(xy 116.99784 -218.050803) (xy 116.974334 -218.004671) (xy 116.958335 -217.955431) (xy 116.950236 -217.904293)
			(xy 116.949728 -217.878406) (xy 116.950262 -217.850698) (xy 116.959455 -217.796051) (xy 116.968016 -217.769694)
			(xy 116.97589 -217.747596) (xy 116.770912 -217.392504) (xy 116.748052 -217.388186) (xy 116.723196 -217.383069)
			(xy 116.675348 -217.366166) (xy 116.630656 -217.342128) (xy 116.590177 -217.311523) (xy 116.554867 -217.275076)
			(xy 116.525561 -217.233647) (xy 116.502952 -217.188215) (xy 116.487574 -217.139855) (xy 116.47979 -217.089709)
			(xy 116.47932 -217.064336) (xy 115.259104 -217.064336) (xy 115.258489 -217.091989) (xy 115.249169 -217.146507)
			(xy 115.240562 -217.172794) (xy 115.232942 -217.194892) (xy 115.438174 -217.550238) (xy 115.461034 -217.554556)
			(xy 115.485841 -217.559728) (xy 115.533579 -217.576721) (xy 115.578156 -217.600818) (xy 115.61852 -217.631451)
			(xy 115.653723 -217.6679) (xy 115.682934 -217.709305) (xy 115.705466 -217.754693) (xy 115.720789 -217.802993)
			(xy 115.728541 -217.85307) (xy 115.729004 -217.878406) (xy 115.728496 -217.904293) (xy 115.720397 -217.955431)
			(xy 115.704398 -218.004671) (xy 115.680892 -218.050803) (xy 115.65046 -218.09269) (xy 115.61385 -218.1293)
			(xy 115.571963 -218.159732) (xy 115.525831 -218.183238) (xy 115.476591 -218.199237) (xy 115.425453 -218.207336)
			(xy 115.373679 -218.207336) (xy 115.322541 -218.199237) (xy 115.273301 -218.183238) (xy 115.227169 -218.159732)
			(xy 115.185282 -218.1293) (xy 115.148672 -218.09269) (xy 115.11824 -218.050803) (xy 115.094734 -218.004671)
			(xy 115.078735 -217.955431) (xy 115.070636 -217.904293) (xy 115.070128 -217.878406) (xy 115.070662 -217.850698)
			(xy 115.079855 -217.796051) (xy 115.088416 -217.769694) (xy 115.09629 -217.747596) (xy 114.891312 -217.392504)
			(xy 114.868452 -217.388186) (xy 114.843596 -217.383069) (xy 114.795748 -217.366166) (xy 114.751056 -217.342128)
			(xy 114.710577 -217.311523) (xy 114.675267 -217.275076) (xy 114.645961 -217.233647) (xy 114.623352 -217.188215)
			(xy 114.607974 -217.139855) (xy 114.60019 -217.089709) (xy 114.59972 -217.064336) (xy 113.379504 -217.064336)
			(xy 113.378889 -217.091989) (xy 113.369569 -217.146507) (xy 113.360962 -217.172794) (xy 113.353342 -217.194892)
			(xy 113.558574 -217.550238) (xy 113.581434 -217.554556) (xy 113.606241 -217.559728) (xy 113.653979 -217.576721)
			(xy 113.698556 -217.600818) (xy 113.73892 -217.631451) (xy 113.774123 -217.6679) (xy 113.803334 -217.709305)
			(xy 113.825866 -217.754693) (xy 113.841189 -217.802993) (xy 113.848941 -217.85307) (xy 113.849404 -217.878406)
			(xy 113.848896 -217.904293) (xy 113.840797 -217.955431) (xy 113.824798 -218.004671) (xy 113.801292 -218.050803)
			(xy 113.77086 -218.09269) (xy 113.73425 -218.1293) (xy 113.692363 -218.159732) (xy 113.646231 -218.183238)
			(xy 113.596991 -218.199237) (xy 113.545853 -218.207336) (xy 113.494079 -218.207336) (xy 113.442941 -218.199237)
			(xy 113.393701 -218.183238) (xy 113.347569 -218.159732) (xy 113.305682 -218.1293) (xy 113.269072 -218.09269)
			(xy 113.23864 -218.050803) (xy 113.215134 -218.004671) (xy 113.199135 -217.955431) (xy 113.191036 -217.904293)
			(xy 113.190528 -217.878406) (xy 113.191062 -217.850698) (xy 113.200255 -217.796051) (xy 113.208816 -217.769694)
			(xy 113.21669 -217.747596) (xy 113.011712 -217.392504) (xy 112.988852 -217.388186) (xy 112.963996 -217.383069)
			(xy 112.916148 -217.366166) (xy 112.871456 -217.342128) (xy 112.830977 -217.311523) (xy 112.795667 -217.275076)
			(xy 112.766361 -217.233647) (xy 112.743752 -217.188215) (xy 112.728374 -217.139855) (xy 112.72059 -217.089709)
			(xy 112.72012 -217.064336) (xy 111.499904 -217.064336) (xy 111.499412 -217.08968) (xy 111.491635 -217.13977)
			(xy 111.476286 -217.188079) (xy 111.453725 -217.233471) (xy 111.424484 -217.274876) (xy 111.389252 -217.311319)
			(xy 111.348859 -217.341943) (xy 111.304255 -217.366024) (xy 111.256492 -217.382998) (xy 111.23168 -217.388186)
			(xy 111.20882 -217.392504) (xy 111.003842 -217.747596) (xy 111.011716 -217.76944) (xy 111.020306 -217.795856)
			(xy 111.029495 -217.850633) (xy 111.030004 -217.878406) (xy 111.029496 -217.904293) (xy 111.021397 -217.955431)
			(xy 111.005398 -218.004671) (xy 110.981892 -218.050803) (xy 110.95146 -218.09269) (xy 110.91485 -218.1293)
			(xy 110.872963 -218.159732) (xy 110.826831 -218.183238) (xy 110.777591 -218.199237) (xy 110.726453 -218.207336)
			(xy 110.674679 -218.207336) (xy 110.623541 -218.199237) (xy 110.574301 -218.183238) (xy 110.528169 -218.159732)
			(xy 110.486282 -218.1293) (xy 110.449672 -218.09269) (xy 110.41924 -218.050803) (xy 110.395734 -218.004671)
			(xy 110.379735 -217.955431) (xy 110.371636 -217.904293) (xy 110.371128 -217.878406) (xy 110.090204 -217.878406)
			(xy 110.089676 -217.906114) (xy 110.08048 -217.960761) (xy 110.071916 -217.987118) (xy 110.064296 -218.008962)
			(xy 110.269274 -218.364054) (xy 110.292134 -218.368372) (xy 110.316944 -218.373529) (xy 110.364684 -218.390523)
			(xy 110.409261 -218.414621) (xy 110.449626 -218.445257) (xy 110.484829 -218.481707) (xy 110.51404 -218.523115)
			(xy 110.536571 -218.568504) (xy 110.551892 -218.616807) (xy 110.559642 -218.666885) (xy 110.560104 -218.692222)
			(xy 111.78032 -218.692222) (xy 111.780845 -218.666878) (xy 111.788614 -218.616789) (xy 111.803957 -218.56848)
			(xy 111.826512 -218.523087) (xy 111.855749 -218.481681) (xy 111.890978 -218.445236) (xy 111.931369 -218.414613)
			(xy 111.97597 -218.390531) (xy 112.023732 -218.373559) (xy 112.048544 -218.368372) (xy 112.071404 -218.364054)
			(xy 112.276636 -218.008708) (xy 112.268762 -217.98661) (xy 112.260294 -217.960366) (xy 112.251224 -217.905977)
			(xy 112.250728 -217.878406) (xy 112.251236 -217.852519) (xy 112.259335 -217.801381) (xy 112.275334 -217.752141)
			(xy 112.29884 -217.706009) (xy 112.329272 -217.664122) (xy 112.365882 -217.627512) (xy 112.407769 -217.59708)
			(xy 112.453901 -217.573574) (xy 112.503141 -217.557575) (xy 112.554279 -217.549476) (xy 112.606053 -217.549476)
			(xy 112.657191 -217.557575) (xy 112.706431 -217.573574) (xy 112.752563 -217.59708) (xy 112.79445 -217.627512)
			(xy 112.83106 -217.664122) (xy 112.861492 -217.706009) (xy 112.884998 -217.752141) (xy 112.900997 -217.801381)
			(xy 112.909096 -217.852519) (xy 112.909604 -217.878406) (xy 112.909131 -217.90378) (xy 112.901362 -217.953931)
			(xy 112.885993 -218.002296) (xy 112.863388 -218.047732) (xy 112.834082 -218.089163) (xy 112.798768 -218.125609)
			(xy 112.758282 -218.156208) (xy 112.713582 -218.180235) (xy 112.665726 -218.197122) (xy 112.640872 -218.202256)
			(xy 112.618012 -218.206574) (xy 112.413288 -218.561412) (xy 112.421162 -218.583256) (xy 112.429814 -218.609662)
			(xy 112.43913 -218.66444) (xy 112.439704 -218.692222) (xy 113.660428 -218.692222) (xy 113.660908 -218.666887)
			(xy 113.668658 -218.616813) (xy 113.683979 -218.568515) (xy 113.70651 -218.52313) (xy 113.73572 -218.481727)
			(xy 113.770922 -218.445282) (xy 113.811285 -218.414651) (xy 113.855861 -218.390558) (xy 113.903598 -218.37357)
			(xy 113.928398 -218.368372) (xy 113.951258 -218.364054) (xy 114.156236 -218.008962) (xy 114.148616 -217.986864)
			(xy 114.140092 -217.960694) (xy 114.130901 -217.906431) (xy 114.130328 -217.878914) (xy 114.130328 -217.878406)
			(xy 114.130836 -217.852519) (xy 114.138935 -217.801381) (xy 114.154934 -217.752141) (xy 114.17844 -217.706009)
			(xy 114.208872 -217.664122) (xy 114.245482 -217.627512) (xy 114.287369 -217.59708) (xy 114.333501 -217.573574)
			(xy 114.382741 -217.557575) (xy 114.433879 -217.549476) (xy 114.485653 -217.549476) (xy 114.536791 -217.557575)
			(xy 114.586031 -217.573574) (xy 114.632163 -217.59708) (xy 114.67405 -217.627512) (xy 114.71066 -217.664122)
			(xy 114.741092 -217.706009) (xy 114.764598 -217.752141) (xy 114.780597 -217.801381) (xy 114.788696 -217.852519)
			(xy 114.789204 -217.878406) (xy 114.788769 -217.903771) (xy 114.781019 -217.953906) (xy 114.765673 -218.002259)
			(xy 114.743093 -218.047686) (xy 114.713814 -218.089114) (xy 114.678529 -218.125562) (xy 114.638071 -218.156167)
			(xy 114.593399 -218.180207) (xy 114.545568 -218.197111) (xy 114.520726 -218.202256) (xy 114.497866 -218.206574)
			(xy 114.293142 -218.561412) (xy 114.301016 -218.583256) (xy 114.309609 -218.609671) (xy 114.318797 -218.664449)
			(xy 114.319304 -218.692222) (xy 115.53952 -218.692222) (xy 115.540045 -218.666878) (xy 115.547814 -218.616789)
			(xy 115.563157 -218.56848) (xy 115.585712 -218.523087) (xy 115.614949 -218.481681) (xy 115.650178 -218.445236)
			(xy 115.690569 -218.414613) (xy 115.73517 -218.390531) (xy 115.782932 -218.373559) (xy 115.807744 -218.368372)
			(xy 115.830604 -218.364054) (xy 116.035836 -218.008708) (xy 116.027962 -217.98661) (xy 116.019494 -217.960366)
			(xy 116.010424 -217.905977) (xy 116.009928 -217.878406) (xy 116.010436 -217.852519) (xy 116.018535 -217.801381)
			(xy 116.034534 -217.752141) (xy 116.05804 -217.706009) (xy 116.088472 -217.664122) (xy 116.125082 -217.627512)
			(xy 116.166969 -217.59708) (xy 116.213101 -217.573574) (xy 116.262341 -217.557575) (xy 116.313479 -217.549476)
			(xy 116.365253 -217.549476) (xy 116.416391 -217.557575) (xy 116.465631 -217.573574) (xy 116.511763 -217.59708)
			(xy 116.55365 -217.627512) (xy 116.59026 -217.664122) (xy 116.620692 -217.706009) (xy 116.644198 -217.752141)
			(xy 116.660197 -217.801381) (xy 116.668296 -217.852519) (xy 116.668804 -217.878406) (xy 116.668331 -217.90378)
			(xy 116.660562 -217.953931) (xy 116.645193 -218.002296) (xy 116.622588 -218.047732) (xy 116.593282 -218.089163)
			(xy 116.557968 -218.125609) (xy 116.517482 -218.156208) (xy 116.472782 -218.180235) (xy 116.424926 -218.197122)
			(xy 116.400072 -218.202256) (xy 116.377212 -218.206574) (xy 116.172488 -218.561412) (xy 116.180362 -218.583256)
			(xy 116.189014 -218.609662) (xy 116.19833 -218.66444) (xy 116.198904 -218.692222) (xy 117.41912 -218.692222)
			(xy 117.419645 -218.666878) (xy 117.427414 -218.616789) (xy 117.442757 -218.56848) (xy 117.465312 -218.523087)
			(xy 117.494549 -218.481681) (xy 117.529778 -218.445236) (xy 117.570169 -218.414613) (xy 117.61477 -218.390531)
			(xy 117.662532 -218.373559) (xy 117.687344 -218.368372) (xy 117.710204 -218.364054) (xy 117.915436 -218.008708)
			(xy 117.907562 -217.98661) (xy 117.899094 -217.960366) (xy 117.890024 -217.905977) (xy 117.889528 -217.878406)
			(xy 117.890036 -217.852519) (xy 117.898135 -217.801381) (xy 117.914134 -217.752141) (xy 117.93764 -217.706009)
			(xy 117.968072 -217.664122) (xy 118.004682 -217.627512) (xy 118.046569 -217.59708) (xy 118.092701 -217.573574)
			(xy 118.141941 -217.557575) (xy 118.193079 -217.549476) (xy 118.244853 -217.549476) (xy 118.295991 -217.557575)
			(xy 118.345231 -217.573574) (xy 118.391363 -217.59708) (xy 118.43325 -217.627512) (xy 118.46986 -217.664122)
			(xy 118.500292 -217.706009) (xy 118.523798 -217.752141) (xy 118.539797 -217.801381) (xy 118.547896 -217.852519)
			(xy 118.548404 -217.878406) (xy 118.547931 -217.90378) (xy 118.540162 -217.953931) (xy 118.524793 -218.002296)
			(xy 118.502188 -218.047732) (xy 118.472882 -218.089163) (xy 118.437568 -218.125609) (xy 118.397082 -218.156208)
			(xy 118.352382 -218.180235) (xy 118.304526 -218.197122) (xy 118.279672 -218.202256) (xy 118.256812 -218.206574)
			(xy 118.052088 -218.561412) (xy 118.059962 -218.583256) (xy 118.068614 -218.609662) (xy 118.07793 -218.66444)
			(xy 118.078504 -218.692222) (xy 119.29872 -218.692222) (xy 119.299245 -218.666878) (xy 119.307014 -218.616789)
			(xy 119.322357 -218.56848) (xy 119.344912 -218.523087) (xy 119.374149 -218.481681) (xy 119.409378 -218.445236)
			(xy 119.449769 -218.414613) (xy 119.49437 -218.390531) (xy 119.542132 -218.373559) (xy 119.566944 -218.368372)
			(xy 119.589804 -218.364054) (xy 119.795036 -218.008708) (xy 119.787162 -217.98661) (xy 119.778694 -217.960366)
			(xy 119.769624 -217.905977) (xy 119.769128 -217.878406) (xy 119.769636 -217.852519) (xy 119.777735 -217.801381)
			(xy 119.793734 -217.752141) (xy 119.81724 -217.706009) (xy 119.847672 -217.664122) (xy 119.884282 -217.627512)
			(xy 119.926169 -217.59708) (xy 119.972301 -217.573574) (xy 120.021541 -217.557575) (xy 120.072679 -217.549476)
			(xy 120.124453 -217.549476) (xy 120.175591 -217.557575) (xy 120.224831 -217.573574) (xy 120.270963 -217.59708)
			(xy 120.31285 -217.627512) (xy 120.34946 -217.664122) (xy 120.379892 -217.706009) (xy 120.403398 -217.752141)
			(xy 120.419397 -217.801381) (xy 120.427496 -217.852519) (xy 120.428004 -217.878406) (xy 120.427531 -217.90378)
			(xy 120.419762 -217.953931) (xy 120.404393 -218.002296) (xy 120.381788 -218.047732) (xy 120.352482 -218.089163)
			(xy 120.317168 -218.125609) (xy 120.276682 -218.156208) (xy 120.231982 -218.180235) (xy 120.184126 -218.197122)
			(xy 120.159272 -218.202256) (xy 120.136412 -218.206574) (xy 119.931688 -218.561412) (xy 119.939562 -218.583256)
			(xy 119.948214 -218.609662) (xy 119.95753 -218.66444) (xy 119.958104 -218.692222) (xy 121.17832 -218.692222)
			(xy 121.178845 -218.666878) (xy 121.186614 -218.616789) (xy 121.201957 -218.56848) (xy 121.224512 -218.523087)
			(xy 121.253749 -218.481681) (xy 121.288978 -218.445236) (xy 121.329369 -218.414613) (xy 121.37397 -218.390531)
			(xy 121.421732 -218.373559) (xy 121.446544 -218.368372) (xy 121.469404 -218.364054) (xy 121.674636 -218.008708)
			(xy 121.666762 -217.98661) (xy 121.658294 -217.960366) (xy 121.649224 -217.905977) (xy 121.648728 -217.878406)
			(xy 121.649236 -217.852519) (xy 121.657335 -217.801381) (xy 121.673334 -217.752141) (xy 121.69684 -217.706009)
			(xy 121.727272 -217.664122) (xy 121.763882 -217.627512) (xy 121.805769 -217.59708) (xy 121.851901 -217.573574)
			(xy 121.901141 -217.557575) (xy 121.952279 -217.549476) (xy 122.004053 -217.549476) (xy 122.055191 -217.557575)
			(xy 122.104431 -217.573574) (xy 122.150563 -217.59708) (xy 122.19245 -217.627512) (xy 122.22906 -217.664122)
			(xy 122.259492 -217.706009) (xy 122.282998 -217.752141) (xy 122.298997 -217.801381) (xy 122.307096 -217.852519)
			(xy 122.307604 -217.878406) (xy 122.307131 -217.90378) (xy 122.299362 -217.953931) (xy 122.283993 -218.002296)
			(xy 122.261388 -218.047732) (xy 122.232082 -218.089163) (xy 122.196768 -218.125609) (xy 122.156282 -218.156208)
			(xy 122.111582 -218.180235) (xy 122.063726 -218.197122) (xy 122.038872 -218.202256) (xy 122.016012 -218.206574)
			(xy 121.811288 -218.561412) (xy 121.819162 -218.583256) (xy 121.827814 -218.609662) (xy 121.83713 -218.66444)
			(xy 121.837704 -218.692222) (xy 123.05792 -218.692222) (xy 123.058445 -218.666878) (xy 123.066214 -218.616789)
			(xy 123.081557 -218.56848) (xy 123.104112 -218.523087) (xy 123.133349 -218.481681) (xy 123.168578 -218.445236)
			(xy 123.208969 -218.414613) (xy 123.25357 -218.390531) (xy 123.301332 -218.373559) (xy 123.326144 -218.368372)
			(xy 123.349004 -218.364054) (xy 123.554236 -218.008708) (xy 123.546362 -217.98661) (xy 123.537894 -217.960366)
			(xy 123.528824 -217.905977) (xy 123.528328 -217.878406) (xy 123.528836 -217.852519) (xy 123.536935 -217.801381)
			(xy 123.552934 -217.752141) (xy 123.57644 -217.706009) (xy 123.606872 -217.664122) (xy 123.643482 -217.627512)
			(xy 123.685369 -217.59708) (xy 123.731501 -217.573574) (xy 123.780741 -217.557575) (xy 123.831879 -217.549476)
			(xy 123.883653 -217.549476) (xy 123.934791 -217.557575) (xy 123.984031 -217.573574) (xy 124.030163 -217.59708)
			(xy 124.07205 -217.627512) (xy 124.10866 -217.664122) (xy 124.139092 -217.706009) (xy 124.162598 -217.752141)
			(xy 124.178597 -217.801381) (xy 124.186696 -217.852519) (xy 124.187204 -217.878406) (xy 124.186731 -217.90378)
			(xy 124.178962 -217.953931) (xy 124.163593 -218.002296) (xy 124.140988 -218.047732) (xy 124.111682 -218.089163)
			(xy 124.076368 -218.125609) (xy 124.035882 -218.156208) (xy 123.991182 -218.180235) (xy 123.943326 -218.197122)
			(xy 123.918472 -218.202256) (xy 123.895612 -218.206574) (xy 123.690888 -218.561412) (xy 123.698762 -218.583256)
			(xy 123.707414 -218.609662) (xy 123.71673 -218.66444) (xy 123.717304 -218.692222) (xy 124.93752 -218.692222)
			(xy 124.938045 -218.666878) (xy 124.945814 -218.616789) (xy 124.961157 -218.56848) (xy 124.983712 -218.523087)
			(xy 125.012949 -218.481681) (xy 125.048178 -218.445236) (xy 125.088569 -218.414613) (xy 125.13317 -218.390531)
			(xy 125.180932 -218.373559) (xy 125.205744 -218.368372) (xy 125.228604 -218.364054) (xy 125.433836 -218.008708)
			(xy 125.425962 -217.98661) (xy 125.417494 -217.960366) (xy 125.408424 -217.905977) (xy 125.407928 -217.878406)
			(xy 125.408436 -217.852519) (xy 125.416535 -217.801381) (xy 125.432534 -217.752141) (xy 125.45604 -217.706009)
			(xy 125.486472 -217.664122) (xy 125.523082 -217.627512) (xy 125.564969 -217.59708) (xy 125.611101 -217.573574)
			(xy 125.660341 -217.557575) (xy 125.711479 -217.549476) (xy 125.763253 -217.549476) (xy 125.814391 -217.557575)
			(xy 125.863631 -217.573574) (xy 125.909763 -217.59708) (xy 125.95165 -217.627512) (xy 125.98826 -217.664122)
			(xy 126.018692 -217.706009) (xy 126.042198 -217.752141) (xy 126.058197 -217.801381) (xy 126.066296 -217.852519)
			(xy 126.066804 -217.878406) (xy 126.066331 -217.90378) (xy 126.058562 -217.953931) (xy 126.043193 -218.002296)
			(xy 126.020588 -218.047732) (xy 125.991282 -218.089163) (xy 125.955968 -218.125609) (xy 125.915482 -218.156208)
			(xy 125.870782 -218.180235) (xy 125.822926 -218.197122) (xy 125.798072 -218.202256) (xy 125.775212 -218.206574)
			(xy 125.570488 -218.561412) (xy 125.578362 -218.583256) (xy 125.587014 -218.609662) (xy 125.59633 -218.66444)
			(xy 125.596904 -218.692222) (xy 126.81712 -218.692222) (xy 126.817645 -218.666878) (xy 126.825414 -218.616789)
			(xy 126.840757 -218.56848) (xy 126.863312 -218.523087) (xy 126.892549 -218.481681) (xy 126.927778 -218.445236)
			(xy 126.968169 -218.414613) (xy 127.01277 -218.390531) (xy 127.060532 -218.373559) (xy 127.085344 -218.368372)
			(xy 127.108204 -218.364054) (xy 127.313436 -218.008708) (xy 127.305562 -217.98661) (xy 127.297094 -217.960366)
			(xy 127.288024 -217.905977) (xy 127.287528 -217.878406) (xy 127.288036 -217.852519) (xy 127.296135 -217.801381)
			(xy 127.312134 -217.752141) (xy 127.33564 -217.706009) (xy 127.366072 -217.664122) (xy 127.402682 -217.627512)
			(xy 127.444569 -217.59708) (xy 127.490701 -217.573574) (xy 127.539941 -217.557575) (xy 127.591079 -217.549476)
			(xy 127.642853 -217.549476) (xy 127.693991 -217.557575) (xy 127.743231 -217.573574) (xy 127.789363 -217.59708)
			(xy 127.83125 -217.627512) (xy 127.86786 -217.664122) (xy 127.898292 -217.706009) (xy 127.921798 -217.752141)
			(xy 127.937797 -217.801381) (xy 127.945896 -217.852519) (xy 127.946404 -217.878406) (xy 127.945931 -217.90378)
			(xy 127.938162 -217.953931) (xy 127.922793 -218.002296) (xy 127.900188 -218.047732) (xy 127.870882 -218.089163)
			(xy 127.835568 -218.125609) (xy 127.795082 -218.156208) (xy 127.750382 -218.180235) (xy 127.702526 -218.197122)
			(xy 127.677672 -218.202256) (xy 127.654812 -218.206574) (xy 127.450088 -218.561412) (xy 127.457962 -218.583256)
			(xy 127.466614 -218.609662) (xy 127.47593 -218.66444) (xy 127.476504 -218.692222) (xy 128.69672 -218.692222)
			(xy 128.697245 -218.666878) (xy 128.705014 -218.616789) (xy 128.720357 -218.56848) (xy 128.742912 -218.523087)
			(xy 128.772149 -218.481681) (xy 128.807378 -218.445236) (xy 128.847769 -218.414613) (xy 128.89237 -218.390531)
			(xy 128.940132 -218.373559) (xy 128.964944 -218.368372) (xy 128.987804 -218.364054) (xy 129.193036 -218.008708)
			(xy 129.185162 -217.98661) (xy 129.176694 -217.960366) (xy 129.167624 -217.905977) (xy 129.167128 -217.878406)
			(xy 129.167636 -217.852519) (xy 129.175735 -217.801381) (xy 129.191734 -217.752141) (xy 129.21524 -217.706009)
			(xy 129.245672 -217.664122) (xy 129.282282 -217.627512) (xy 129.324169 -217.59708) (xy 129.370301 -217.573574)
			(xy 129.419541 -217.557575) (xy 129.470679 -217.549476) (xy 129.522453 -217.549476) (xy 129.573591 -217.557575)
			(xy 129.622831 -217.573574) (xy 129.668963 -217.59708) (xy 129.71085 -217.627512) (xy 129.74746 -217.664122)
			(xy 129.777892 -217.706009) (xy 129.801398 -217.752141) (xy 129.817397 -217.801381) (xy 129.825496 -217.852519)
			(xy 129.826004 -217.878406) (xy 129.825531 -217.90378) (xy 129.817762 -217.953931) (xy 129.802393 -218.002296)
			(xy 129.779788 -218.047732) (xy 129.750482 -218.089163) (xy 129.715168 -218.125609) (xy 129.674682 -218.156208)
			(xy 129.629982 -218.180235) (xy 129.582126 -218.197122) (xy 129.557272 -218.202256) (xy 129.534412 -218.206574)
			(xy 129.329688 -218.561412) (xy 129.337562 -218.583256) (xy 129.346214 -218.609662) (xy 129.35553 -218.66444)
			(xy 129.356104 -218.692222) (xy 130.57632 -218.692222) (xy 130.576845 -218.666878) (xy 130.584614 -218.616789)
			(xy 130.599957 -218.56848) (xy 130.622512 -218.523087) (xy 130.651749 -218.481681) (xy 130.686978 -218.445236)
			(xy 130.727369 -218.414613) (xy 130.77197 -218.390531) (xy 130.819732 -218.373559) (xy 130.844544 -218.368372)
			(xy 130.867404 -218.364054) (xy 131.072636 -218.008708) (xy 131.064762 -217.98661) (xy 131.056294 -217.960366)
			(xy 131.047224 -217.905977) (xy 131.046728 -217.878406) (xy 131.047236 -217.852519) (xy 131.055335 -217.801381)
			(xy 131.071334 -217.752141) (xy 131.09484 -217.706009) (xy 131.125272 -217.664122) (xy 131.161882 -217.627512)
			(xy 131.203769 -217.59708) (xy 131.249901 -217.573574) (xy 131.299141 -217.557575) (xy 131.350279 -217.549476)
			(xy 131.402053 -217.549476) (xy 131.453191 -217.557575) (xy 131.502431 -217.573574) (xy 131.548563 -217.59708)
			(xy 131.59045 -217.627512) (xy 131.62706 -217.664122) (xy 131.657492 -217.706009) (xy 131.680998 -217.752141)
			(xy 131.696997 -217.801381) (xy 131.705096 -217.852519) (xy 131.705604 -217.878406) (xy 131.705131 -217.90378)
			(xy 131.697362 -217.953931) (xy 131.681993 -218.002296) (xy 131.659388 -218.047732) (xy 131.630082 -218.089163)
			(xy 131.594768 -218.125609) (xy 131.554282 -218.156208) (xy 131.509582 -218.180235) (xy 131.461726 -218.197122)
			(xy 131.436872 -218.202256) (xy 131.414012 -218.206574) (xy 131.209288 -218.561412) (xy 131.217162 -218.583256)
			(xy 131.225814 -218.609662) (xy 131.23513 -218.66444) (xy 131.235704 -218.692222) (xy 132.45592 -218.692222)
			(xy 132.456445 -218.666878) (xy 132.464214 -218.616789) (xy 132.479557 -218.56848) (xy 132.502112 -218.523087)
			(xy 132.531349 -218.481681) (xy 132.566578 -218.445236) (xy 132.606969 -218.414613) (xy 132.65157 -218.390531)
			(xy 132.699332 -218.373559) (xy 132.724144 -218.368372) (xy 132.747004 -218.364054) (xy 132.952236 -218.008708)
			(xy 132.944362 -217.98661) (xy 132.935894 -217.960366) (xy 132.926824 -217.905977) (xy 132.926328 -217.878406)
			(xy 132.926836 -217.852519) (xy 132.934935 -217.801381) (xy 132.950934 -217.752141) (xy 132.97444 -217.706009)
			(xy 133.004872 -217.664122) (xy 133.041482 -217.627512) (xy 133.083369 -217.59708) (xy 133.129501 -217.573574)
			(xy 133.178741 -217.557575) (xy 133.229879 -217.549476) (xy 133.281653 -217.549476) (xy 133.332791 -217.557575)
			(xy 133.382031 -217.573574) (xy 133.428163 -217.59708) (xy 133.47005 -217.627512) (xy 133.50666 -217.664122)
			(xy 133.537092 -217.706009) (xy 133.560598 -217.752141) (xy 133.576597 -217.801381) (xy 133.584696 -217.852519)
			(xy 133.585204 -217.878406) (xy 133.584731 -217.90378) (xy 133.576962 -217.953931) (xy 133.561593 -218.002296)
			(xy 133.538988 -218.047732) (xy 133.509682 -218.089163) (xy 133.474368 -218.125609) (xy 133.433882 -218.156208)
			(xy 133.389182 -218.180235) (xy 133.341326 -218.197122) (xy 133.316472 -218.202256) (xy 133.293612 -218.206574)
			(xy 133.088888 -218.561412) (xy 133.096762 -218.583256) (xy 133.105414 -218.609662) (xy 133.11473 -218.66444)
			(xy 133.115304 -218.692222) (xy 133.114796 -218.718129) (xy 133.10669 -218.769306) (xy 133.105987 -218.77147)
			(xy 158.062168 -218.77147) (xy 158.062168 -218.36253) (xy 158.062589 -218.352357) (xy 158.07037 -218.333557)
			(xy 158.084757 -218.31917) (xy 158.103557 -218.311389) (xy 158.11373 -218.310968) (xy 159.51327 -218.310968)
			(xy 159.523443 -218.311389) (xy 159.542243 -218.31917) (xy 159.55663 -218.333557) (xy 159.564411 -218.352357)
			(xy 159.564832 -218.36253) (xy 159.564832 -218.77147) (xy 162.162236 -218.77147) (xy 162.162236 -218.36253)
			(xy 162.162689 -218.352361) (xy 162.170463 -218.333567) (xy 162.18484 -218.319181) (xy 162.203629 -218.311395)
			(xy 162.213798 -218.310968) (xy 163.613338 -218.310968) (xy 163.623502 -218.311403) (xy 163.642278 -218.319196)
			(xy 163.656643 -218.333579) (xy 163.66441 -218.352365) (xy 163.6649 -218.36253) (xy 163.6649 -218.77147)
			(xy 165.605968 -218.77147) (xy 165.605968 -218.36253) (xy 165.606389 -218.352357) (xy 165.61417 -218.333557)
			(xy 165.628557 -218.31917) (xy 165.647357 -218.311389) (xy 165.65753 -218.310968) (xy 167.05707 -218.310968)
			(xy 167.067243 -218.311389) (xy 167.086043 -218.31917) (xy 167.10043 -218.333557) (xy 167.108211 -218.352357)
			(xy 167.108632 -218.36253) (xy 167.108632 -218.77147) (xy 169.706036 -218.77147) (xy 169.706036 -218.36253)
			(xy 169.706489 -218.352361) (xy 169.714263 -218.333567) (xy 169.72864 -218.319181) (xy 169.747429 -218.311395)
			(xy 169.757598 -218.310968) (xy 171.157138 -218.310968) (xy 171.167302 -218.311403) (xy 171.186078 -218.319196)
			(xy 171.200443 -218.333579) (xy 171.20821 -218.352365) (xy 171.2087 -218.36253) (xy 171.2087 -218.77147)
			(xy 173.149768 -218.77147) (xy 173.149768 -218.36253) (xy 173.150189 -218.352357) (xy 173.15797 -218.333557)
			(xy 173.172357 -218.31917) (xy 173.191157 -218.311389) (xy 173.20133 -218.310968) (xy 174.60087 -218.310968)
			(xy 174.611043 -218.311389) (xy 174.629843 -218.31917) (xy 174.64423 -218.333557) (xy 174.652011 -218.352357)
			(xy 174.652432 -218.36253) (xy 174.652432 -218.77147) (xy 177.249836 -218.77147) (xy 177.249836 -218.36253)
			(xy 177.250289 -218.352361) (xy 177.258063 -218.333567) (xy 177.27244 -218.319181) (xy 177.291229 -218.311395)
			(xy 177.301398 -218.310968) (xy 178.700938 -218.310968) (xy 178.711102 -218.311403) (xy 178.729878 -218.319196)
			(xy 178.744243 -218.333579) (xy 178.75201 -218.352365) (xy 178.7525 -218.36253) (xy 178.7525 -218.77147)
			(xy 180.693568 -218.77147) (xy 180.693568 -218.36253) (xy 180.693989 -218.352357) (xy 180.70177 -218.333557)
			(xy 180.716157 -218.31917) (xy 180.734957 -218.311389) (xy 180.74513 -218.310968) (xy 182.14467 -218.310968)
			(xy 182.154843 -218.311389) (xy 182.173643 -218.31917) (xy 182.18803 -218.333557) (xy 182.195811 -218.352357)
			(xy 182.196232 -218.36253) (xy 182.196232 -218.77147) (xy 184.793636 -218.77147) (xy 184.793636 -218.36253)
			(xy 184.794089 -218.352361) (xy 184.801863 -218.333567) (xy 184.81624 -218.319181) (xy 184.835029 -218.311395)
			(xy 184.845198 -218.310968) (xy 186.244738 -218.310968) (xy 186.254902 -218.311403) (xy 186.273678 -218.319196)
			(xy 186.288043 -218.333579) (xy 186.29581 -218.352365) (xy 186.2963 -218.36253) (xy 186.2963 -218.77147)
			(xy 188.237368 -218.77147) (xy 188.237368 -218.36253) (xy 188.237789 -218.352357) (xy 188.24557 -218.333557)
			(xy 188.259957 -218.31917) (xy 188.278757 -218.311389) (xy 188.28893 -218.310968) (xy 189.68847 -218.310968)
			(xy 189.698643 -218.311389) (xy 189.717443 -218.31917) (xy 189.73183 -218.333557) (xy 189.739611 -218.352357)
			(xy 189.740032 -218.36253) (xy 189.740032 -218.77147) (xy 192.337436 -218.77147) (xy 192.337436 -218.36253)
			(xy 192.337889 -218.352361) (xy 192.345663 -218.333567) (xy 192.36004 -218.319181) (xy 192.378829 -218.311395)
			(xy 192.388998 -218.310968) (xy 193.788538 -218.310968) (xy 193.798702 -218.311403) (xy 193.817478 -218.319196)
			(xy 193.831843 -218.333579) (xy 193.83961 -218.352365) (xy 193.8401 -218.36253) (xy 193.8401 -218.77147)
			(xy 195.781168 -218.77147) (xy 195.781168 -218.36253) (xy 195.781589 -218.352357) (xy 195.78937 -218.333557)
			(xy 195.803757 -218.31917) (xy 195.822557 -218.311389) (xy 195.83273 -218.310968) (xy 197.23227 -218.310968)
			(xy 197.242443 -218.311389) (xy 197.261243 -218.31917) (xy 197.27563 -218.333557) (xy 197.283411 -218.352357)
			(xy 197.283832 -218.36253) (xy 197.283832 -218.77147) (xy 199.881236 -218.77147) (xy 199.881236 -218.36253)
			(xy 199.881689 -218.352361) (xy 199.889463 -218.333567) (xy 199.90384 -218.319181) (xy 199.922629 -218.311395)
			(xy 199.932798 -218.310968) (xy 201.332338 -218.310968) (xy 201.342502 -218.311403) (xy 201.361278 -218.319196)
			(xy 201.375643 -218.333579) (xy 201.38341 -218.352365) (xy 201.3839 -218.36253) (xy 201.3839 -218.77147)
			(xy 203.324968 -218.77147) (xy 203.324968 -218.36253) (xy 203.325389 -218.352357) (xy 203.33317 -218.333557)
			(xy 203.347557 -218.31917) (xy 203.366357 -218.311389) (xy 203.37653 -218.310968) (xy 204.77607 -218.310968)
			(xy 204.786243 -218.311389) (xy 204.805043 -218.31917) (xy 204.81943 -218.333557) (xy 204.827211 -218.352357)
			(xy 204.827632 -218.36253) (xy 204.827632 -218.77147) (xy 207.425036 -218.77147) (xy 207.425036 -218.36253)
			(xy 207.425489 -218.352361) (xy 207.433263 -218.333567) (xy 207.44764 -218.319181) (xy 207.466429 -218.311395)
			(xy 207.476598 -218.310968) (xy 208.876138 -218.310968) (xy 208.886302 -218.311403) (xy 208.905078 -218.319196)
			(xy 208.919443 -218.333579) (xy 208.92721 -218.352365) (xy 208.9277 -218.36253) (xy 208.9277 -218.77147)
			(xy 210.868768 -218.77147) (xy 210.868768 -218.36253) (xy 210.869189 -218.352357) (xy 210.87697 -218.333557)
			(xy 210.891357 -218.31917) (xy 210.910157 -218.311389) (xy 210.92033 -218.310968) (xy 212.31987 -218.310968)
			(xy 212.330043 -218.311389) (xy 212.348843 -218.31917) (xy 212.36323 -218.333557) (xy 212.371011 -218.352357)
			(xy 212.371432 -218.36253) (xy 212.371432 -218.77147) (xy 214.968836 -218.77147) (xy 214.968836 -218.36253)
			(xy 214.969289 -218.352361) (xy 214.977063 -218.333567) (xy 214.99144 -218.319181) (xy 215.010229 -218.311395)
			(xy 215.020398 -218.310968) (xy 216.419938 -218.310968) (xy 216.430102 -218.311403) (xy 216.448878 -218.319196)
			(xy 216.463243 -218.333579) (xy 216.47101 -218.352365) (xy 216.4715 -218.36253) (xy 216.4715 -218.77147)
			(xy 255.329436 -218.77147) (xy 255.329436 -218.36253) (xy 255.329889 -218.352361) (xy 255.337663 -218.333567)
			(xy 255.35204 -218.319181) (xy 255.370829 -218.311395) (xy 255.380998 -218.310968) (xy 256.780538 -218.310968)
			(xy 256.790702 -218.311403) (xy 256.809478 -218.319196) (xy 256.823843 -218.333579) (xy 256.83161 -218.352365)
			(xy 256.8321 -218.36253) (xy 256.8321 -218.77147) (xy 259.429504 -218.77147) (xy 259.429504 -218.36253)
			(xy 259.430057 -218.352378) (xy 259.437815 -218.333616) (xy 259.452163 -218.319251) (xy 259.470915 -218.311469)
			(xy 259.481066 -218.310968) (xy 260.880606 -218.310968) (xy 260.890782 -218.31136) (xy 260.909582 -218.319152)
			(xy 260.923968 -218.333548) (xy 260.931747 -218.352354) (xy 260.932168 -218.36253) (xy 260.932168 -218.77147)
			(xy 262.873236 -218.77147) (xy 262.873236 -218.36253) (xy 262.873689 -218.352361) (xy 262.881463 -218.333567)
			(xy 262.89584 -218.319181) (xy 262.914629 -218.311395) (xy 262.924798 -218.310968) (xy 264.324338 -218.310968)
			(xy 264.334502 -218.311403) (xy 264.353278 -218.319196) (xy 264.367643 -218.333579) (xy 264.37541 -218.352365)
			(xy 264.3759 -218.36253) (xy 264.3759 -218.77147) (xy 266.973304 -218.77147) (xy 266.973304 -218.36253)
			(xy 266.973857 -218.352378) (xy 266.981615 -218.333616) (xy 266.995963 -218.319251) (xy 267.014715 -218.311469)
			(xy 267.024866 -218.310968) (xy 268.424406 -218.310968) (xy 268.434582 -218.31136) (xy 268.453382 -218.319152)
			(xy 268.467768 -218.333548) (xy 268.475547 -218.352354) (xy 268.475968 -218.36253) (xy 268.475968 -218.77147)
			(xy 270.417036 -218.77147) (xy 270.417036 -218.36253) (xy 270.417489 -218.352361) (xy 270.425263 -218.333567)
			(xy 270.43964 -218.319181) (xy 270.458429 -218.311395) (xy 270.468598 -218.310968) (xy 271.868138 -218.310968)
			(xy 271.878302 -218.311403) (xy 271.897078 -218.319196) (xy 271.911443 -218.333579) (xy 271.91921 -218.352365)
			(xy 271.9197 -218.36253) (xy 271.9197 -218.77147) (xy 274.517104 -218.77147) (xy 274.517104 -218.36253)
			(xy 274.517657 -218.352378) (xy 274.525415 -218.333616) (xy 274.539763 -218.319251) (xy 274.558515 -218.311469)
			(xy 274.568666 -218.310968) (xy 275.968206 -218.310968) (xy 275.978382 -218.31136) (xy 275.997182 -218.319152)
			(xy 276.011568 -218.333548) (xy 276.019347 -218.352354) (xy 276.019768 -218.36253) (xy 276.019768 -218.77147)
			(xy 277.960836 -218.77147) (xy 277.960836 -218.36253) (xy 277.961289 -218.352361) (xy 277.969063 -218.333567)
			(xy 277.98344 -218.319181) (xy 278.002229 -218.311395) (xy 278.012398 -218.310968) (xy 279.411938 -218.310968)
			(xy 279.422102 -218.311403) (xy 279.440878 -218.319196) (xy 279.455243 -218.333579) (xy 279.46301 -218.352365)
			(xy 279.4635 -218.36253) (xy 279.4635 -218.77147) (xy 282.060904 -218.77147) (xy 282.060904 -218.36253)
			(xy 282.061457 -218.352378) (xy 282.069215 -218.333616) (xy 282.083563 -218.319251) (xy 282.102315 -218.311469)
			(xy 282.112466 -218.310968) (xy 283.512006 -218.310968) (xy 283.522182 -218.31136) (xy 283.540982 -218.319152)
			(xy 283.555368 -218.333548) (xy 283.563147 -218.352354) (xy 283.563568 -218.36253) (xy 283.563568 -218.77147)
			(xy 285.504636 -218.77147) (xy 285.504636 -218.36253) (xy 285.505089 -218.352361) (xy 285.512863 -218.333567)
			(xy 285.52724 -218.319181) (xy 285.546029 -218.311395) (xy 285.556198 -218.310968) (xy 286.955738 -218.310968)
			(xy 286.965902 -218.311403) (xy 286.984678 -218.319196) (xy 286.999043 -218.333579) (xy 287.00681 -218.352365)
			(xy 287.0073 -218.36253) (xy 287.0073 -218.77147) (xy 289.604704 -218.77147) (xy 289.604704 -218.36253)
			(xy 289.605257 -218.352378) (xy 289.613015 -218.333616) (xy 289.627363 -218.319251) (xy 289.646115 -218.311469)
			(xy 289.656266 -218.310968) (xy 291.055806 -218.310968) (xy 291.065982 -218.31136) (xy 291.084782 -218.319152)
			(xy 291.099168 -218.333548) (xy 291.106947 -218.352354) (xy 291.107368 -218.36253) (xy 291.107368 -218.77147)
			(xy 293.048436 -218.77147) (xy 293.048436 -218.36253) (xy 293.048889 -218.352361) (xy 293.056663 -218.333567)
			(xy 293.07104 -218.319181) (xy 293.089829 -218.311395) (xy 293.099998 -218.310968) (xy 294.499538 -218.310968)
			(xy 294.509702 -218.311403) (xy 294.528478 -218.319196) (xy 294.542843 -218.333579) (xy 294.55061 -218.352365)
			(xy 294.5511 -218.36253) (xy 294.5511 -218.77147) (xy 297.148504 -218.77147) (xy 297.148504 -218.36253)
			(xy 297.149057 -218.352378) (xy 297.156815 -218.333616) (xy 297.171163 -218.319251) (xy 297.189915 -218.311469)
			(xy 297.200066 -218.310968) (xy 298.599606 -218.310968) (xy 298.609782 -218.31136) (xy 298.628582 -218.319152)
			(xy 298.642968 -218.333548) (xy 298.650747 -218.352354) (xy 298.651168 -218.36253) (xy 298.651168 -218.77147)
			(xy 300.592236 -218.77147) (xy 300.592236 -218.36253) (xy 300.592689 -218.352361) (xy 300.600463 -218.333567)
			(xy 300.61484 -218.319181) (xy 300.633629 -218.311395) (xy 300.643798 -218.310968) (xy 302.043338 -218.310968)
			(xy 302.053502 -218.311403) (xy 302.072278 -218.319196) (xy 302.086643 -218.333579) (xy 302.09441 -218.352365)
			(xy 302.0949 -218.36253) (xy 302.0949 -218.77147) (xy 304.692304 -218.77147) (xy 304.692304 -218.36253)
			(xy 304.692857 -218.352378) (xy 304.700615 -218.333616) (xy 304.714963 -218.319251) (xy 304.733715 -218.311469)
			(xy 304.743866 -218.310968) (xy 306.143406 -218.310968) (xy 306.153582 -218.31136) (xy 306.172382 -218.319152)
			(xy 306.186768 -218.333548) (xy 306.194547 -218.352354) (xy 306.194968 -218.36253) (xy 306.194968 -218.77147)
			(xy 308.136036 -218.77147) (xy 308.136036 -218.36253) (xy 308.136489 -218.352361) (xy 308.144263 -218.333567)
			(xy 308.15864 -218.319181) (xy 308.177429 -218.311395) (xy 308.187598 -218.310968) (xy 309.587138 -218.310968)
			(xy 309.597302 -218.311403) (xy 309.616078 -218.319196) (xy 309.630443 -218.333579) (xy 309.63821 -218.352365)
			(xy 309.6387 -218.36253) (xy 309.6387 -218.77147) (xy 312.236104 -218.77147) (xy 312.236104 -218.36253)
			(xy 312.236657 -218.352378) (xy 312.244415 -218.333616) (xy 312.258763 -218.319251) (xy 312.277515 -218.311469)
			(xy 312.287666 -218.310968) (xy 313.687206 -218.310968) (xy 313.697382 -218.31136) (xy 313.716182 -218.319152)
			(xy 313.730568 -218.333548) (xy 313.738347 -218.352354) (xy 313.738768 -218.36253) (xy 313.738768 -218.77147)
			(xy 313.738312 -218.781639) (xy 313.730538 -218.800432) (xy 313.716162 -218.814817) (xy 313.697375 -218.822604)
			(xy 313.687206 -218.823032) (xy 312.287666 -218.823032) (xy 312.277502 -218.822594) (xy 312.258727 -218.814803)
			(xy 312.244362 -218.80042) (xy 312.236594 -218.781634) (xy 312.236104 -218.77147) (xy 309.6387 -218.77147)
			(xy 309.638143 -218.781621) (xy 309.630386 -218.800383) (xy 309.61604 -218.814748) (xy 309.597289 -218.82253)
			(xy 309.587138 -218.823032) (xy 308.187598 -218.823032) (xy 308.177423 -218.822637) (xy 308.158622 -218.814846)
			(xy 308.144236 -218.800451) (xy 308.136457 -218.781646) (xy 308.136036 -218.77147) (xy 306.194968 -218.77147)
			(xy 306.194512 -218.781639) (xy 306.186738 -218.800432) (xy 306.172362 -218.814817) (xy 306.153575 -218.822604)
			(xy 306.143406 -218.823032) (xy 304.743866 -218.823032) (xy 304.733702 -218.822594) (xy 304.714927 -218.814803)
			(xy 304.700562 -218.80042) (xy 304.692794 -218.781634) (xy 304.692304 -218.77147) (xy 302.0949 -218.77147)
			(xy 302.094343 -218.781621) (xy 302.086586 -218.800383) (xy 302.07224 -218.814748) (xy 302.053489 -218.82253)
			(xy 302.043338 -218.823032) (xy 300.643798 -218.823032) (xy 300.633623 -218.822637) (xy 300.614822 -218.814846)
			(xy 300.600436 -218.800451) (xy 300.592657 -218.781646) (xy 300.592236 -218.77147) (xy 298.651168 -218.77147)
			(xy 298.650712 -218.781639) (xy 298.642938 -218.800432) (xy 298.628562 -218.814817) (xy 298.609775 -218.822604)
			(xy 298.599606 -218.823032) (xy 297.200066 -218.823032) (xy 297.189902 -218.822594) (xy 297.171127 -218.814803)
			(xy 297.156762 -218.80042) (xy 297.148994 -218.781634) (xy 297.148504 -218.77147) (xy 294.5511 -218.77147)
			(xy 294.550543 -218.781621) (xy 294.542786 -218.800383) (xy 294.52844 -218.814748) (xy 294.509689 -218.82253)
			(xy 294.499538 -218.823032) (xy 293.099998 -218.823032) (xy 293.089823 -218.822637) (xy 293.071022 -218.814846)
			(xy 293.056636 -218.800451) (xy 293.048857 -218.781646) (xy 293.048436 -218.77147) (xy 291.107368 -218.77147)
			(xy 291.106912 -218.781639) (xy 291.099138 -218.800432) (xy 291.084762 -218.814817) (xy 291.065975 -218.822604)
			(xy 291.055806 -218.823032) (xy 289.656266 -218.823032) (xy 289.646102 -218.822594) (xy 289.627327 -218.814803)
			(xy 289.612962 -218.80042) (xy 289.605194 -218.781634) (xy 289.604704 -218.77147) (xy 287.0073 -218.77147)
			(xy 287.006743 -218.781621) (xy 286.998986 -218.800383) (xy 286.98464 -218.814748) (xy 286.965889 -218.82253)
			(xy 286.955738 -218.823032) (xy 285.556198 -218.823032) (xy 285.546023 -218.822637) (xy 285.527222 -218.814846)
			(xy 285.512836 -218.800451) (xy 285.505057 -218.781646) (xy 285.504636 -218.77147) (xy 283.563568 -218.77147)
			(xy 283.563112 -218.781639) (xy 283.555338 -218.800432) (xy 283.540962 -218.814817) (xy 283.522175 -218.822604)
			(xy 283.512006 -218.823032) (xy 282.112466 -218.823032) (xy 282.102302 -218.822594) (xy 282.083527 -218.814803)
			(xy 282.069162 -218.80042) (xy 282.061394 -218.781634) (xy 282.060904 -218.77147) (xy 279.4635 -218.77147)
			(xy 279.462943 -218.781621) (xy 279.455186 -218.800383) (xy 279.44084 -218.814748) (xy 279.422089 -218.82253)
			(xy 279.411938 -218.823032) (xy 278.012398 -218.823032) (xy 278.002223 -218.822637) (xy 277.983422 -218.814846)
			(xy 277.969036 -218.800451) (xy 277.961257 -218.781646) (xy 277.960836 -218.77147) (xy 276.019768 -218.77147)
			(xy 276.019312 -218.781639) (xy 276.011538 -218.800432) (xy 275.997162 -218.814817) (xy 275.978375 -218.822604)
			(xy 275.968206 -218.823032) (xy 274.568666 -218.823032) (xy 274.558502 -218.822594) (xy 274.539727 -218.814803)
			(xy 274.525362 -218.80042) (xy 274.517594 -218.781634) (xy 274.517104 -218.77147) (xy 271.9197 -218.77147)
			(xy 271.919143 -218.781621) (xy 271.911386 -218.800383) (xy 271.89704 -218.814748) (xy 271.878289 -218.82253)
			(xy 271.868138 -218.823032) (xy 270.468598 -218.823032) (xy 270.458423 -218.822637) (xy 270.439622 -218.814846)
			(xy 270.425236 -218.800451) (xy 270.417457 -218.781646) (xy 270.417036 -218.77147) (xy 268.475968 -218.77147)
			(xy 268.475512 -218.781639) (xy 268.467738 -218.800432) (xy 268.453362 -218.814817) (xy 268.434575 -218.822604)
			(xy 268.424406 -218.823032) (xy 267.024866 -218.823032) (xy 267.014702 -218.822594) (xy 266.995927 -218.814803)
			(xy 266.981562 -218.80042) (xy 266.973794 -218.781634) (xy 266.973304 -218.77147) (xy 264.3759 -218.77147)
			(xy 264.375343 -218.781621) (xy 264.367586 -218.800383) (xy 264.35324 -218.814748) (xy 264.334489 -218.82253)
			(xy 264.324338 -218.823032) (xy 262.924798 -218.823032) (xy 262.914623 -218.822637) (xy 262.895822 -218.814846)
			(xy 262.881436 -218.800451) (xy 262.873657 -218.781646) (xy 262.873236 -218.77147) (xy 260.932168 -218.77147)
			(xy 260.931712 -218.781639) (xy 260.923938 -218.800432) (xy 260.909562 -218.814817) (xy 260.890775 -218.822604)
			(xy 260.880606 -218.823032) (xy 259.481066 -218.823032) (xy 259.470902 -218.822594) (xy 259.452127 -218.814803)
			(xy 259.437762 -218.80042) (xy 259.429994 -218.781634) (xy 259.429504 -218.77147) (xy 256.8321 -218.77147)
			(xy 256.831543 -218.781621) (xy 256.823786 -218.800383) (xy 256.80944 -218.814748) (xy 256.790689 -218.82253)
			(xy 256.780538 -218.823032) (xy 255.380998 -218.823032) (xy 255.370823 -218.822637) (xy 255.352022 -218.814846)
			(xy 255.337636 -218.800451) (xy 255.329857 -218.781646) (xy 255.329436 -218.77147) (xy 216.4715 -218.77147)
			(xy 216.470943 -218.781621) (xy 216.463186 -218.800383) (xy 216.44884 -218.814748) (xy 216.430089 -218.82253)
			(xy 216.419938 -218.823032) (xy 215.020398 -218.823032) (xy 215.010223 -218.822637) (xy 214.991422 -218.814846)
			(xy 214.977036 -218.800451) (xy 214.969257 -218.781646) (xy 214.968836 -218.77147) (xy 212.371432 -218.77147)
			(xy 212.371011 -218.781643) (xy 212.36323 -218.800443) (xy 212.348843 -218.81483) (xy 212.330043 -218.822611)
			(xy 212.31987 -218.823032) (xy 210.92033 -218.823032) (xy 210.910157 -218.822611) (xy 210.891357 -218.81483)
			(xy 210.87697 -218.800443) (xy 210.869189 -218.781643) (xy 210.868768 -218.77147) (xy 208.9277 -218.77147)
			(xy 208.927143 -218.781621) (xy 208.919386 -218.800383) (xy 208.90504 -218.814748) (xy 208.886289 -218.82253)
			(xy 208.876138 -218.823032) (xy 207.476598 -218.823032) (xy 207.466423 -218.822637) (xy 207.447622 -218.814846)
			(xy 207.433236 -218.800451) (xy 207.425457 -218.781646) (xy 207.425036 -218.77147) (xy 204.827632 -218.77147)
			(xy 204.827211 -218.781643) (xy 204.81943 -218.800443) (xy 204.805043 -218.81483) (xy 204.786243 -218.822611)
			(xy 204.77607 -218.823032) (xy 203.37653 -218.823032) (xy 203.366357 -218.822611) (xy 203.347557 -218.81483)
			(xy 203.33317 -218.800443) (xy 203.325389 -218.781643) (xy 203.324968 -218.77147) (xy 201.3839 -218.77147)
			(xy 201.383343 -218.781621) (xy 201.375586 -218.800383) (xy 201.36124 -218.814748) (xy 201.342489 -218.82253)
			(xy 201.332338 -218.823032) (xy 199.932798 -218.823032) (xy 199.922623 -218.822637) (xy 199.903822 -218.814846)
			(xy 199.889436 -218.800451) (xy 199.881657 -218.781646) (xy 199.881236 -218.77147) (xy 197.283832 -218.77147)
			(xy 197.283411 -218.781643) (xy 197.27563 -218.800443) (xy 197.261243 -218.81483) (xy 197.242443 -218.822611)
			(xy 197.23227 -218.823032) (xy 195.83273 -218.823032) (xy 195.822557 -218.822611) (xy 195.803757 -218.81483)
			(xy 195.78937 -218.800443) (xy 195.781589 -218.781643) (xy 195.781168 -218.77147) (xy 193.8401 -218.77147)
			(xy 193.839543 -218.781621) (xy 193.831786 -218.800383) (xy 193.81744 -218.814748) (xy 193.798689 -218.82253)
			(xy 193.788538 -218.823032) (xy 192.388998 -218.823032) (xy 192.378823 -218.822637) (xy 192.360022 -218.814846)
			(xy 192.345636 -218.800451) (xy 192.337857 -218.781646) (xy 192.337436 -218.77147) (xy 189.740032 -218.77147)
			(xy 189.739611 -218.781643) (xy 189.73183 -218.800443) (xy 189.717443 -218.81483) (xy 189.698643 -218.822611)
			(xy 189.68847 -218.823032) (xy 188.28893 -218.823032) (xy 188.278757 -218.822611) (xy 188.259957 -218.81483)
			(xy 188.24557 -218.800443) (xy 188.237789 -218.781643) (xy 188.237368 -218.77147) (xy 186.2963 -218.77147)
			(xy 186.295743 -218.781621) (xy 186.287986 -218.800383) (xy 186.27364 -218.814748) (xy 186.254889 -218.82253)
			(xy 186.244738 -218.823032) (xy 184.845198 -218.823032) (xy 184.835023 -218.822637) (xy 184.816222 -218.814846)
			(xy 184.801836 -218.800451) (xy 184.794057 -218.781646) (xy 184.793636 -218.77147) (xy 182.196232 -218.77147)
			(xy 182.195811 -218.781643) (xy 182.18803 -218.800443) (xy 182.173643 -218.81483) (xy 182.154843 -218.822611)
			(xy 182.14467 -218.823032) (xy 180.74513 -218.823032) (xy 180.734957 -218.822611) (xy 180.716157 -218.81483)
			(xy 180.70177 -218.800443) (xy 180.693989 -218.781643) (xy 180.693568 -218.77147) (xy 178.7525 -218.77147)
			(xy 178.751943 -218.781621) (xy 178.744186 -218.800383) (xy 178.72984 -218.814748) (xy 178.711089 -218.82253)
			(xy 178.700938 -218.823032) (xy 177.301398 -218.823032) (xy 177.291223 -218.822637) (xy 177.272422 -218.814846)
			(xy 177.258036 -218.800451) (xy 177.250257 -218.781646) (xy 177.249836 -218.77147) (xy 174.652432 -218.77147)
			(xy 174.652011 -218.781643) (xy 174.64423 -218.800443) (xy 174.629843 -218.81483) (xy 174.611043 -218.822611)
			(xy 174.60087 -218.823032) (xy 173.20133 -218.823032) (xy 173.191157 -218.822611) (xy 173.172357 -218.81483)
			(xy 173.15797 -218.800443) (xy 173.150189 -218.781643) (xy 173.149768 -218.77147) (xy 171.2087 -218.77147)
			(xy 171.208143 -218.781621) (xy 171.200386 -218.800383) (xy 171.18604 -218.814748) (xy 171.167289 -218.82253)
			(xy 171.157138 -218.823032) (xy 169.757598 -218.823032) (xy 169.747423 -218.822637) (xy 169.728622 -218.814846)
			(xy 169.714236 -218.800451) (xy 169.706457 -218.781646) (xy 169.706036 -218.77147) (xy 167.108632 -218.77147)
			(xy 167.108211 -218.781643) (xy 167.10043 -218.800443) (xy 167.086043 -218.81483) (xy 167.067243 -218.822611)
			(xy 167.05707 -218.823032) (xy 165.65753 -218.823032) (xy 165.647357 -218.822611) (xy 165.628557 -218.81483)
			(xy 165.61417 -218.800443) (xy 165.606389 -218.781643) (xy 165.605968 -218.77147) (xy 163.6649 -218.77147)
			(xy 163.664343 -218.781621) (xy 163.656586 -218.800383) (xy 163.64224 -218.814748) (xy 163.623489 -218.82253)
			(xy 163.613338 -218.823032) (xy 162.213798 -218.823032) (xy 162.203623 -218.822637) (xy 162.184822 -218.814846)
			(xy 162.170436 -218.800451) (xy 162.162657 -218.781646) (xy 162.162236 -218.77147) (xy 159.564832 -218.77147)
			(xy 159.564411 -218.781643) (xy 159.55663 -218.800443) (xy 159.542243 -218.81483) (xy 159.523443 -218.822611)
			(xy 159.51327 -218.823032) (xy 158.11373 -218.823032) (xy 158.103557 -218.822611) (xy 158.084757 -218.81483)
			(xy 158.07037 -218.800443) (xy 158.062589 -218.781643) (xy 158.062168 -218.77147) (xy 133.105987 -218.77147)
			(xy 133.090678 -218.818585) (xy 133.067155 -218.864752) (xy 133.036699 -218.906671) (xy 133.000061 -218.943309)
			(xy 132.958142 -218.973765) (xy 132.911975 -218.997288) (xy 132.862696 -219.0133) (xy 132.811519 -219.021406)
			(xy 132.759705 -219.021406) (xy 132.708528 -219.0133) (xy 132.659249 -218.997288) (xy 132.613082 -218.973765)
			(xy 132.571163 -218.943309) (xy 132.534525 -218.906671) (xy 132.504069 -218.864752) (xy 132.480546 -218.818585)
			(xy 132.464534 -218.769306) (xy 132.456428 -218.718129) (xy 132.45592 -218.692222) (xy 131.235704 -218.692222)
			(xy 131.235196 -218.718129) (xy 131.22709 -218.769306) (xy 131.211078 -218.818585) (xy 131.187555 -218.864752)
			(xy 131.157099 -218.906671) (xy 131.120461 -218.943309) (xy 131.078542 -218.973765) (xy 131.032375 -218.997288)
			(xy 130.983096 -219.0133) (xy 130.931919 -219.021406) (xy 130.880105 -219.021406) (xy 130.828928 -219.0133)
			(xy 130.779649 -218.997288) (xy 130.733482 -218.973765) (xy 130.691563 -218.943309) (xy 130.654925 -218.906671)
			(xy 130.624469 -218.864752) (xy 130.600946 -218.818585) (xy 130.584934 -218.769306) (xy 130.576828 -218.718129)
			(xy 130.57632 -218.692222) (xy 129.356104 -218.692222) (xy 129.355596 -218.718129) (xy 129.34749 -218.769306)
			(xy 129.331478 -218.818585) (xy 129.307955 -218.864752) (xy 129.277499 -218.906671) (xy 129.240861 -218.943309)
			(xy 129.198942 -218.973765) (xy 129.152775 -218.997288) (xy 129.103496 -219.0133) (xy 129.052319 -219.021406)
			(xy 129.000505 -219.021406) (xy 128.949328 -219.0133) (xy 128.900049 -218.997288) (xy 128.853882 -218.973765)
			(xy 128.811963 -218.943309) (xy 128.775325 -218.906671) (xy 128.744869 -218.864752) (xy 128.721346 -218.818585)
			(xy 128.705334 -218.769306) (xy 128.697228 -218.718129) (xy 128.69672 -218.692222) (xy 127.476504 -218.692222)
			(xy 127.475996 -218.718129) (xy 127.46789 -218.769306) (xy 127.451878 -218.818585) (xy 127.428355 -218.864752)
			(xy 127.397899 -218.906671) (xy 127.361261 -218.943309) (xy 127.319342 -218.973765) (xy 127.273175 -218.997288)
			(xy 127.223896 -219.0133) (xy 127.172719 -219.021406) (xy 127.120905 -219.021406) (xy 127.069728 -219.0133)
			(xy 127.020449 -218.997288) (xy 126.974282 -218.973765) (xy 126.932363 -218.943309) (xy 126.895725 -218.906671)
			(xy 126.865269 -218.864752) (xy 126.841746 -218.818585) (xy 126.825734 -218.769306) (xy 126.817628 -218.718129)
			(xy 126.81712 -218.692222) (xy 125.596904 -218.692222) (xy 125.596396 -218.718129) (xy 125.58829 -218.769306)
			(xy 125.572278 -218.818585) (xy 125.548755 -218.864752) (xy 125.518299 -218.906671) (xy 125.481661 -218.943309)
			(xy 125.439742 -218.973765) (xy 125.393575 -218.997288) (xy 125.344296 -219.0133) (xy 125.293119 -219.021406)
			(xy 125.241305 -219.021406) (xy 125.190128 -219.0133) (xy 125.140849 -218.997288) (xy 125.094682 -218.973765)
			(xy 125.052763 -218.943309) (xy 125.016125 -218.906671) (xy 124.985669 -218.864752) (xy 124.962146 -218.818585)
			(xy 124.946134 -218.769306) (xy 124.938028 -218.718129) (xy 124.93752 -218.692222) (xy 123.717304 -218.692222)
			(xy 123.716796 -218.718129) (xy 123.70869 -218.769306) (xy 123.692678 -218.818585) (xy 123.669155 -218.864752)
			(xy 123.638699 -218.906671) (xy 123.602061 -218.943309) (xy 123.560142 -218.973765) (xy 123.513975 -218.997288)
			(xy 123.464696 -219.0133) (xy 123.413519 -219.021406) (xy 123.361705 -219.021406) (xy 123.310528 -219.0133)
			(xy 123.261249 -218.997288) (xy 123.215082 -218.973765) (xy 123.173163 -218.943309) (xy 123.136525 -218.906671)
			(xy 123.106069 -218.864752) (xy 123.082546 -218.818585) (xy 123.066534 -218.769306) (xy 123.058428 -218.718129)
			(xy 123.05792 -218.692222) (xy 121.837704 -218.692222) (xy 121.837196 -218.718129) (xy 121.82909 -218.769306)
			(xy 121.813078 -218.818585) (xy 121.789555 -218.864752) (xy 121.759099 -218.906671) (xy 121.722461 -218.943309)
			(xy 121.680542 -218.973765) (xy 121.634375 -218.997288) (xy 121.585096 -219.0133) (xy 121.533919 -219.021406)
			(xy 121.482105 -219.021406) (xy 121.430928 -219.0133) (xy 121.381649 -218.997288) (xy 121.335482 -218.973765)
			(xy 121.293563 -218.943309) (xy 121.256925 -218.906671) (xy 121.226469 -218.864752) (xy 121.202946 -218.818585)
			(xy 121.186934 -218.769306) (xy 121.178828 -218.718129) (xy 121.17832 -218.692222) (xy 119.958104 -218.692222)
			(xy 119.957596 -218.718129) (xy 119.94949 -218.769306) (xy 119.933478 -218.818585) (xy 119.909955 -218.864752)
			(xy 119.879499 -218.906671) (xy 119.842861 -218.943309) (xy 119.800942 -218.973765) (xy 119.754775 -218.997288)
			(xy 119.705496 -219.0133) (xy 119.654319 -219.021406) (xy 119.602505 -219.021406) (xy 119.551328 -219.0133)
			(xy 119.502049 -218.997288) (xy 119.455882 -218.973765) (xy 119.413963 -218.943309) (xy 119.377325 -218.906671)
			(xy 119.346869 -218.864752) (xy 119.323346 -218.818585) (xy 119.307334 -218.769306) (xy 119.299228 -218.718129)
			(xy 119.29872 -218.692222) (xy 118.078504 -218.692222) (xy 118.077996 -218.718129) (xy 118.06989 -218.769306)
			(xy 118.053878 -218.818585) (xy 118.030355 -218.864752) (xy 117.999899 -218.906671) (xy 117.963261 -218.943309)
			(xy 117.921342 -218.973765) (xy 117.875175 -218.997288) (xy 117.825896 -219.0133) (xy 117.774719 -219.021406)
			(xy 117.722905 -219.021406) (xy 117.671728 -219.0133) (xy 117.622449 -218.997288) (xy 117.576282 -218.973765)
			(xy 117.534363 -218.943309) (xy 117.497725 -218.906671) (xy 117.467269 -218.864752) (xy 117.443746 -218.818585)
			(xy 117.427734 -218.769306) (xy 117.419628 -218.718129) (xy 117.41912 -218.692222) (xy 116.198904 -218.692222)
			(xy 116.198396 -218.718129) (xy 116.19029 -218.769306) (xy 116.174278 -218.818585) (xy 116.150755 -218.864752)
			(xy 116.120299 -218.906671) (xy 116.083661 -218.943309) (xy 116.041742 -218.973765) (xy 115.995575 -218.997288)
			(xy 115.946296 -219.0133) (xy 115.895119 -219.021406) (xy 115.843305 -219.021406) (xy 115.792128 -219.0133)
			(xy 115.742849 -218.997288) (xy 115.696682 -218.973765) (xy 115.654763 -218.943309) (xy 115.618125 -218.906671)
			(xy 115.587669 -218.864752) (xy 115.564146 -218.818585) (xy 115.548134 -218.769306) (xy 115.540028 -218.718129)
			(xy 115.53952 -218.692222) (xy 114.319304 -218.692222) (xy 114.318796 -218.718109) (xy 114.310697 -218.769247)
			(xy 114.294698 -218.818487) (xy 114.271192 -218.864619) (xy 114.24076 -218.906506) (xy 114.20415 -218.943116)
			(xy 114.162263 -218.973548) (xy 114.116131 -218.997054) (xy 114.066891 -219.013053) (xy 114.015753 -219.021152)
			(xy 113.963979 -219.021152) (xy 113.912841 -219.013053) (xy 113.863601 -218.997054) (xy 113.817469 -218.973548)
			(xy 113.775582 -218.943116) (xy 113.738972 -218.906506) (xy 113.70854 -218.864619) (xy 113.685034 -218.818487)
			(xy 113.669035 -218.769247) (xy 113.660936 -218.718109) (xy 113.660428 -218.692222) (xy 112.439704 -218.692222)
			(xy 112.439196 -218.718129) (xy 112.43109 -218.769306) (xy 112.415078 -218.818585) (xy 112.391555 -218.864752)
			(xy 112.361099 -218.906671) (xy 112.324461 -218.943309) (xy 112.282542 -218.973765) (xy 112.236375 -218.997288)
			(xy 112.187096 -219.0133) (xy 112.135919 -219.021406) (xy 112.084105 -219.021406) (xy 112.032928 -219.0133)
			(xy 111.983649 -218.997288) (xy 111.937482 -218.973765) (xy 111.895563 -218.943309) (xy 111.858925 -218.906671)
			(xy 111.828469 -218.864752) (xy 111.804946 -218.818585) (xy 111.788934 -218.769306) (xy 111.780828 -218.718129)
			(xy 111.78032 -218.692222) (xy 110.560104 -218.692222) (xy 110.559596 -218.718109) (xy 110.551497 -218.769247)
			(xy 110.535498 -218.818487) (xy 110.511992 -218.864619) (xy 110.48156 -218.906506) (xy 110.44495 -218.943116)
			(xy 110.403063 -218.973548) (xy 110.356931 -218.997054) (xy 110.307691 -219.013053) (xy 110.256553 -219.021152)
			(xy 110.204779 -219.021152) (xy 110.153641 -219.013053) (xy 110.104401 -218.997054) (xy 110.058269 -218.973548)
			(xy 110.016382 -218.943116) (xy 109.979772 -218.906506) (xy 109.94934 -218.864619) (xy 109.925834 -218.818487)
			(xy 109.909835 -218.769247) (xy 109.901736 -218.718109) (xy 109.901228 -218.692222) (xy 109.901766 -218.664514)
			(xy 109.910956 -218.609868) (xy 109.919516 -218.58351) (xy 109.92739 -218.561412) (xy 109.722412 -218.206574)
			(xy 109.699552 -218.202256) (xy 109.67472 -218.197133) (xy 109.626938 -218.180175) (xy 109.582316 -218.1561)
			(xy 109.541908 -218.125474) (xy 109.506667 -218.089022) (xy 109.477424 -218.047602) (xy 109.45487 -218.002192)
			(xy 109.439537 -217.953864) (xy 109.431786 -217.903757) (xy 109.431328 -217.878406) (xy 109.150404 -217.878406)
			(xy 109.149896 -217.904293) (xy 109.141797 -217.955431) (xy 109.125798 -218.004671) (xy 109.102292 -218.050803)
			(xy 109.07186 -218.09269) (xy 109.03525 -218.1293) (xy 108.993363 -218.159732) (xy 108.947231 -218.183238)
			(xy 108.897991 -218.199237) (xy 108.846853 -218.207336) (xy 108.795079 -218.207336) (xy 108.743941 -218.199237)
			(xy 108.694701 -218.183238) (xy 108.648569 -218.159732) (xy 108.606682 -218.1293) (xy 108.570072 -218.09269)
			(xy 108.53964 -218.050803) (xy 108.516134 -218.004671) (xy 108.500135 -217.955431) (xy 108.492036 -217.904293)
			(xy 108.491528 -217.878406) (xy 108.210604 -217.878406) (xy 108.210076 -217.906114) (xy 108.20088 -217.960761)
			(xy 108.192316 -217.987118) (xy 108.184442 -218.009216) (xy 108.38942 -218.364054) (xy 108.41228 -218.368372)
			(xy 108.4371 -218.37354) (xy 108.484878 -218.390497) (xy 108.529495 -218.41457) (xy 108.5699 -218.44519)
			(xy 108.60514 -218.481637) (xy 108.634384 -218.52305) (xy 108.656942 -218.568452) (xy 108.672281 -218.616773)
			(xy 108.680041 -218.666873) (xy 108.680504 -218.692222) (xy 108.679996 -218.718129) (xy 108.67189 -218.769306)
			(xy 108.655878 -218.818585) (xy 108.632355 -218.864752) (xy 108.601899 -218.906671) (xy 108.565261 -218.943309)
			(xy 108.523342 -218.973765) (xy 108.477175 -218.997288) (xy 108.427896 -219.0133) (xy 108.376719 -219.021406)
			(xy 108.324905 -219.021406) (xy 108.273728 -219.0133) (xy 108.224449 -218.997288) (xy 108.178282 -218.973765)
			(xy 108.136363 -218.943309) (xy 108.099725 -218.906671) (xy 108.069269 -218.864752) (xy 108.045746 -218.818585)
			(xy 108.029734 -218.769306) (xy 108.021628 -218.718129) (xy 108.02112 -218.692222) (xy 108.021718 -218.664505)
			(xy 108.031039 -218.609858) (xy 108.039662 -218.58351) (xy 108.047536 -218.561412) (xy 107.842558 -218.206574)
			(xy 107.819698 -218.202256) (xy 107.794899 -218.197049) (xy 107.747162 -218.180062) (xy 107.702585 -218.15597)
			(xy 107.66222 -218.125341) (xy 107.627017 -218.088897) (xy 107.597804 -218.047495) (xy 107.575271 -218.002112)
			(xy 107.559946 -217.953814) (xy 107.552192 -217.903741) (xy 107.551728 -217.878406) (xy 107.270804 -217.878406)
			(xy 107.270296 -217.904293) (xy 107.262197 -217.955431) (xy 107.246198 -218.004671) (xy 107.222692 -218.050803)
			(xy 107.19226 -218.09269) (xy 107.15565 -218.1293) (xy 107.113763 -218.159732) (xy 107.067631 -218.183238)
			(xy 107.018391 -218.199237) (xy 106.967253 -218.207336) (xy 106.915479 -218.207336) (xy 106.864341 -218.199237)
			(xy 106.815101 -218.183238) (xy 106.768969 -218.159732) (xy 106.727082 -218.1293) (xy 106.690472 -218.09269)
			(xy 106.66004 -218.050803) (xy 106.636534 -218.004671) (xy 106.620535 -217.955431) (xy 106.612436 -217.904293)
			(xy 106.611928 -217.878406) (xy 106.331004 -217.878406) (xy 106.330476 -217.906114) (xy 106.32128 -217.960761)
			(xy 106.312716 -217.987118) (xy 106.304842 -218.009216) (xy 106.50982 -218.364054) (xy 106.53268 -218.368372)
			(xy 106.5575 -218.37354) (xy 106.605278 -218.390497) (xy 106.649895 -218.41457) (xy 106.6903 -218.44519)
			(xy 106.72554 -218.481637) (xy 106.754784 -218.52305) (xy 106.777342 -218.568452) (xy 106.792681 -218.616773)
			(xy 106.800441 -218.666873) (xy 106.800904 -218.692222) (xy 106.800396 -218.718129) (xy 106.79229 -218.769306)
			(xy 106.776278 -218.818585) (xy 106.752755 -218.864752) (xy 106.722299 -218.906671) (xy 106.685661 -218.943309)
			(xy 106.643742 -218.973765) (xy 106.597575 -218.997288) (xy 106.548296 -219.0133) (xy 106.497119 -219.021406)
			(xy 106.445305 -219.021406) (xy 106.394128 -219.0133) (xy 106.344849 -218.997288) (xy 106.298682 -218.973765)
			(xy 106.256763 -218.943309) (xy 106.220125 -218.906671) (xy 106.189669 -218.864752) (xy 106.166146 -218.818585)
			(xy 106.150134 -218.769306) (xy 106.142028 -218.718129) (xy 106.14152 -218.692222) (xy 106.142118 -218.664505)
			(xy 106.151439 -218.609858) (xy 106.160062 -218.58351) (xy 106.167936 -218.561412) (xy 105.962958 -218.206574)
			(xy 105.940098 -218.202256) (xy 105.915299 -218.197049) (xy 105.867562 -218.180062) (xy 105.822985 -218.15597)
			(xy 105.78262 -218.125341) (xy 105.747417 -218.088897) (xy 105.718204 -218.047495) (xy 105.695671 -218.002112)
			(xy 105.680346 -217.953814) (xy 105.672592 -217.903741) (xy 105.672128 -217.878406) (xy 105.391204 -217.878406)
			(xy 105.390696 -217.904293) (xy 105.382597 -217.955431) (xy 105.366598 -218.004671) (xy 105.343092 -218.050803)
			(xy 105.31266 -218.09269) (xy 105.27605 -218.1293) (xy 105.234163 -218.159732) (xy 105.188031 -218.183238)
			(xy 105.138791 -218.199237) (xy 105.087653 -218.207336) (xy 105.035879 -218.207336) (xy 104.984741 -218.199237)
			(xy 104.935501 -218.183238) (xy 104.889369 -218.159732) (xy 104.847482 -218.1293) (xy 104.810872 -218.09269)
			(xy 104.78044 -218.050803) (xy 104.756934 -218.004671) (xy 104.740935 -217.955431) (xy 104.732836 -217.904293)
			(xy 104.732328 -217.878406) (xy 104.451404 -217.878406) (xy 104.450876 -217.906114) (xy 104.44168 -217.960761)
			(xy 104.433116 -217.987118) (xy 104.425242 -218.009216) (xy 104.63022 -218.364054) (xy 104.65308 -218.368372)
			(xy 104.6779 -218.37354) (xy 104.725678 -218.390497) (xy 104.770295 -218.41457) (xy 104.8107 -218.44519)
			(xy 104.84594 -218.481637) (xy 104.875184 -218.52305) (xy 104.897742 -218.568452) (xy 104.913081 -218.616773)
			(xy 104.920841 -218.666873) (xy 104.921304 -218.692222) (xy 104.920796 -218.718129) (xy 104.91269 -218.769306)
			(xy 104.896678 -218.818585) (xy 104.873155 -218.864752) (xy 104.842699 -218.906671) (xy 104.806061 -218.943309)
			(xy 104.764142 -218.973765) (xy 104.717975 -218.997288) (xy 104.668696 -219.0133) (xy 104.617519 -219.021406)
			(xy 104.565705 -219.021406) (xy 104.514528 -219.0133) (xy 104.465249 -218.997288) (xy 104.419082 -218.973765)
			(xy 104.377163 -218.943309) (xy 104.340525 -218.906671) (xy 104.310069 -218.864752) (xy 104.286546 -218.818585)
			(xy 104.270534 -218.769306) (xy 104.262428 -218.718129) (xy 104.26192 -218.692222) (xy 104.262518 -218.664505)
			(xy 104.271839 -218.609858) (xy 104.280462 -218.58351) (xy 104.288336 -218.561412) (xy 104.083358 -218.206574)
			(xy 104.060498 -218.202256) (xy 104.035699 -218.197049) (xy 103.987962 -218.180062) (xy 103.943385 -218.15597)
			(xy 103.90302 -218.125341) (xy 103.867817 -218.088897) (xy 103.838604 -218.047495) (xy 103.816071 -218.002112)
			(xy 103.800746 -217.953814) (xy 103.792992 -217.903741) (xy 103.792528 -217.878406) (xy 103.511604 -217.878406)
			(xy 103.511096 -217.904293) (xy 103.502997 -217.955431) (xy 103.486998 -218.004671) (xy 103.463492 -218.050803)
			(xy 103.43306 -218.09269) (xy 103.39645 -218.1293) (xy 103.354563 -218.159732) (xy 103.308431 -218.183238)
			(xy 103.259191 -218.199237) (xy 103.208053 -218.207336) (xy 103.156279 -218.207336) (xy 103.105141 -218.199237)
			(xy 103.055901 -218.183238) (xy 103.009769 -218.159732) (xy 102.967882 -218.1293) (xy 102.931272 -218.09269)
			(xy 102.90084 -218.050803) (xy 102.877334 -218.004671) (xy 102.861335 -217.955431) (xy 102.853236 -217.904293)
			(xy 102.852728 -217.878406) (xy 102.571804 -217.878406) (xy 102.571276 -217.906114) (xy 102.56208 -217.960761)
			(xy 102.553516 -217.987118) (xy 102.545642 -218.009216) (xy 102.75062 -218.364054) (xy 102.77348 -218.368372)
			(xy 102.7983 -218.37354) (xy 102.846078 -218.390497) (xy 102.890695 -218.41457) (xy 102.9311 -218.44519)
			(xy 102.96634 -218.481637) (xy 102.995584 -218.52305) (xy 103.018142 -218.568452) (xy 103.033481 -218.616773)
			(xy 103.041241 -218.666873) (xy 103.041704 -218.692222) (xy 103.041196 -218.718129) (xy 103.03309 -218.769306)
			(xy 103.017078 -218.818585) (xy 102.993555 -218.864752) (xy 102.963099 -218.906671) (xy 102.926461 -218.943309)
			(xy 102.884542 -218.973765) (xy 102.838375 -218.997288) (xy 102.789096 -219.0133) (xy 102.737919 -219.021406)
			(xy 102.686105 -219.021406) (xy 102.634928 -219.0133) (xy 102.585649 -218.997288) (xy 102.539482 -218.973765)
			(xy 102.497563 -218.943309) (xy 102.460925 -218.906671) (xy 102.430469 -218.864752) (xy 102.406946 -218.818585)
			(xy 102.390934 -218.769306) (xy 102.382828 -218.718129) (xy 102.38232 -218.692222) (xy 102.382918 -218.664505)
			(xy 102.392239 -218.609858) (xy 102.400862 -218.58351) (xy 102.408736 -218.561412) (xy 102.203758 -218.206574)
			(xy 102.180898 -218.202256) (xy 102.156099 -218.197049) (xy 102.108362 -218.180062) (xy 102.063785 -218.15597)
			(xy 102.02342 -218.125341) (xy 101.988217 -218.088897) (xy 101.959004 -218.047495) (xy 101.936471 -218.002112)
			(xy 101.921146 -217.953814) (xy 101.913392 -217.903741) (xy 101.912928 -217.878406) (xy 101.632004 -217.878406)
			(xy 101.631496 -217.904293) (xy 101.623397 -217.955431) (xy 101.607398 -218.004671) (xy 101.583892 -218.050803)
			(xy 101.55346 -218.09269) (xy 101.51685 -218.1293) (xy 101.474963 -218.159732) (xy 101.428831 -218.183238)
			(xy 101.379591 -218.199237) (xy 101.328453 -218.207336) (xy 101.276679 -218.207336) (xy 101.225541 -218.199237)
			(xy 101.176301 -218.183238) (xy 101.130169 -218.159732) (xy 101.088282 -218.1293) (xy 101.051672 -218.09269)
			(xy 101.02124 -218.050803) (xy 100.997734 -218.004671) (xy 100.981735 -217.955431) (xy 100.973636 -217.904293)
			(xy 100.973128 -217.878406) (xy 100.692204 -217.878406) (xy 100.691676 -217.906114) (xy 100.68248 -217.960761)
			(xy 100.673916 -217.987118) (xy 100.666042 -218.009216) (xy 100.87102 -218.364054) (xy 100.89388 -218.368372)
			(xy 100.9187 -218.37354) (xy 100.966478 -218.390497) (xy 101.011095 -218.41457) (xy 101.0515 -218.44519)
			(xy 101.08674 -218.481637) (xy 101.115984 -218.52305) (xy 101.138542 -218.568452) (xy 101.153881 -218.616773)
			(xy 101.161641 -218.666873) (xy 101.162104 -218.692222) (xy 101.161596 -218.718129) (xy 101.15349 -218.769306)
			(xy 101.137478 -218.818585) (xy 101.113955 -218.864752) (xy 101.083499 -218.906671) (xy 101.046861 -218.943309)
			(xy 101.004942 -218.973765) (xy 100.958775 -218.997288) (xy 100.909496 -219.0133) (xy 100.858319 -219.021406)
			(xy 100.806505 -219.021406) (xy 100.755328 -219.0133) (xy 100.706049 -218.997288) (xy 100.659882 -218.973765)
			(xy 100.617963 -218.943309) (xy 100.581325 -218.906671) (xy 100.550869 -218.864752) (xy 100.527346 -218.818585)
			(xy 100.511334 -218.769306) (xy 100.503228 -218.718129) (xy 100.50272 -218.692222) (xy 100.503318 -218.664505)
			(xy 100.512639 -218.609858) (xy 100.521262 -218.58351) (xy 100.529136 -218.561412) (xy 100.324158 -218.206574)
			(xy 100.301298 -218.202256) (xy 100.276499 -218.197049) (xy 100.228762 -218.180062) (xy 100.184185 -218.15597)
			(xy 100.14382 -218.125341) (xy 100.108617 -218.088897) (xy 100.079404 -218.047495) (xy 100.056871 -218.002112)
			(xy 100.041546 -217.953814) (xy 100.033792 -217.903741) (xy 100.033328 -217.878406) (xy 99.752404 -217.878406)
			(xy 99.751896 -217.904293) (xy 99.743797 -217.955431) (xy 99.727798 -218.004671) (xy 99.704292 -218.050803)
			(xy 99.67386 -218.09269) (xy 99.63725 -218.1293) (xy 99.595363 -218.159732) (xy 99.549231 -218.183238)
			(xy 99.499991 -218.199237) (xy 99.448853 -218.207336) (xy 99.397079 -218.207336) (xy 99.345941 -218.199237)
			(xy 99.296701 -218.183238) (xy 99.250569 -218.159732) (xy 99.208682 -218.1293) (xy 99.172072 -218.09269)
			(xy 99.14164 -218.050803) (xy 99.118134 -218.004671) (xy 99.102135 -217.955431) (xy 99.094036 -217.904293)
			(xy 99.093528 -217.878406) (xy 98.812604 -217.878406) (xy 98.812076 -217.906114) (xy 98.80288 -217.960761)
			(xy 98.794316 -217.987118) (xy 98.786442 -218.009216) (xy 98.99142 -218.364054) (xy 99.01428 -218.368372)
			(xy 99.0391 -218.37354) (xy 99.086878 -218.390497) (xy 99.131495 -218.41457) (xy 99.1719 -218.44519)
			(xy 99.20714 -218.481637) (xy 99.236384 -218.52305) (xy 99.258942 -218.568452) (xy 99.274281 -218.616773)
			(xy 99.282041 -218.666873) (xy 99.282504 -218.692222) (xy 99.281996 -218.718129) (xy 99.27389 -218.769306)
			(xy 99.257878 -218.818585) (xy 99.234355 -218.864752) (xy 99.203899 -218.906671) (xy 99.167261 -218.943309)
			(xy 99.125342 -218.973765) (xy 99.079175 -218.997288) (xy 99.029896 -219.0133) (xy 98.978719 -219.021406)
			(xy 98.926905 -219.021406) (xy 98.875728 -219.0133) (xy 98.826449 -218.997288) (xy 98.780282 -218.973765)
			(xy 98.738363 -218.943309) (xy 98.701725 -218.906671) (xy 98.671269 -218.864752) (xy 98.647746 -218.818585)
			(xy 98.631734 -218.769306) (xy 98.623628 -218.718129) (xy 98.62312 -218.692222) (xy 98.623718 -218.664505)
			(xy 98.633039 -218.609858) (xy 98.641662 -218.58351) (xy 98.649536 -218.561412) (xy 98.444558 -218.206574)
			(xy 98.421698 -218.202256) (xy 98.396899 -218.197049) (xy 98.349162 -218.180062) (xy 98.304585 -218.15597)
			(xy 98.26422 -218.125341) (xy 98.229017 -218.088897) (xy 98.199804 -218.047495) (xy 98.177271 -218.002112)
			(xy 98.161946 -217.953814) (xy 98.154192 -217.903741) (xy 98.153728 -217.878406) (xy 97.872804 -217.878406)
			(xy 97.872296 -217.904293) (xy 97.864197 -217.955431) (xy 97.848198 -218.004671) (xy 97.824692 -218.050803)
			(xy 97.79426 -218.09269) (xy 97.75765 -218.1293) (xy 97.715763 -218.159732) (xy 97.669631 -218.183238)
			(xy 97.620391 -218.199237) (xy 97.569253 -218.207336) (xy 97.517479 -218.207336) (xy 97.466341 -218.199237)
			(xy 97.417101 -218.183238) (xy 97.370969 -218.159732) (xy 97.329082 -218.1293) (xy 97.292472 -218.09269)
			(xy 97.26204 -218.050803) (xy 97.238534 -218.004671) (xy 97.222535 -217.955431) (xy 97.214436 -217.904293)
			(xy 97.213928 -217.878406) (xy 96.933004 -217.878406) (xy 96.932476 -217.906114) (xy 96.92328 -217.960761)
			(xy 96.914716 -217.987118) (xy 96.906842 -218.009216) (xy 97.11182 -218.364054) (xy 97.13468 -218.368372)
			(xy 97.1595 -218.37354) (xy 97.207278 -218.390497) (xy 97.251895 -218.41457) (xy 97.2923 -218.44519)
			(xy 97.32754 -218.481637) (xy 97.356784 -218.52305) (xy 97.379342 -218.568452) (xy 97.394681 -218.616773)
			(xy 97.402441 -218.666873) (xy 97.402904 -218.692222) (xy 97.402396 -218.718129) (xy 97.39429 -218.769306)
			(xy 97.378278 -218.818585) (xy 97.354755 -218.864752) (xy 97.324299 -218.906671) (xy 97.287661 -218.943309)
			(xy 97.245742 -218.973765) (xy 97.199575 -218.997288) (xy 97.150296 -219.0133) (xy 97.099119 -219.021406)
			(xy 97.047305 -219.021406) (xy 96.996128 -219.0133) (xy 96.946849 -218.997288) (xy 96.900682 -218.973765)
			(xy 96.858763 -218.943309) (xy 96.822125 -218.906671) (xy 96.791669 -218.864752) (xy 96.768146 -218.818585)
			(xy 96.752134 -218.769306) (xy 96.744028 -218.718129) (xy 96.74352 -218.692222) (xy 96.744118 -218.664505)
			(xy 96.753439 -218.609858) (xy 96.762062 -218.58351) (xy 96.769936 -218.561412) (xy 96.564958 -218.206574)
			(xy 96.542098 -218.202256) (xy 96.517299 -218.197049) (xy 96.469562 -218.180062) (xy 96.424985 -218.15597)
			(xy 96.38462 -218.125341) (xy 96.349417 -218.088897) (xy 96.320204 -218.047495) (xy 96.297671 -218.002112)
			(xy 96.282346 -217.953814) (xy 96.274592 -217.903741) (xy 96.274128 -217.878406) (xy 95.993204 -217.878406)
			(xy 95.992696 -217.904293) (xy 95.984597 -217.955431) (xy 95.968598 -218.004671) (xy 95.945092 -218.050803)
			(xy 95.91466 -218.09269) (xy 95.87805 -218.1293) (xy 95.836163 -218.159732) (xy 95.790031 -218.183238)
			(xy 95.740791 -218.199237) (xy 95.689653 -218.207336) (xy 95.637879 -218.207336) (xy 95.586741 -218.199237)
			(xy 95.537501 -218.183238) (xy 95.491369 -218.159732) (xy 95.449482 -218.1293) (xy 95.412872 -218.09269)
			(xy 95.38244 -218.050803) (xy 95.358934 -218.004671) (xy 95.342935 -217.955431) (xy 95.334836 -217.904293)
			(xy 95.334328 -217.878406) (xy 95.053404 -217.878406) (xy 95.052876 -217.906114) (xy 95.04368 -217.960761)
			(xy 95.035116 -217.987118) (xy 95.027242 -218.009216) (xy 95.23222 -218.364054) (xy 95.25508 -218.368372)
			(xy 95.2799 -218.37354) (xy 95.327678 -218.390497) (xy 95.372295 -218.41457) (xy 95.4127 -218.44519)
			(xy 95.44794 -218.481637) (xy 95.477184 -218.52305) (xy 95.499742 -218.568452) (xy 95.515081 -218.616773)
			(xy 95.522841 -218.666873) (xy 95.523304 -218.692222) (xy 95.522796 -218.718129) (xy 95.51469 -218.769306)
			(xy 95.498678 -218.818585) (xy 95.475155 -218.864752) (xy 95.444699 -218.906671) (xy 95.408061 -218.943309)
			(xy 95.366142 -218.973765) (xy 95.319975 -218.997288) (xy 95.270696 -219.0133) (xy 95.219519 -219.021406)
			(xy 95.167705 -219.021406) (xy 95.116528 -219.0133) (xy 95.067249 -218.997288) (xy 95.021082 -218.973765)
			(xy 94.979163 -218.943309) (xy 94.942525 -218.906671) (xy 94.912069 -218.864752) (xy 94.888546 -218.818585)
			(xy 94.872534 -218.769306) (xy 94.864428 -218.718129) (xy 94.86392 -218.692222) (xy 94.864518 -218.664505)
			(xy 94.873839 -218.609858) (xy 94.882462 -218.58351) (xy 94.890336 -218.561412) (xy 94.685358 -218.206574)
			(xy 94.662498 -218.202256) (xy 94.637699 -218.197049) (xy 94.589962 -218.180062) (xy 94.545385 -218.15597)
			(xy 94.50502 -218.125341) (xy 94.469817 -218.088897) (xy 94.440604 -218.047495) (xy 94.418071 -218.002112)
			(xy 94.402746 -217.953814) (xy 94.394992 -217.903741) (xy 94.394528 -217.878406) (xy 94.113604 -217.878406)
			(xy 94.113096 -217.904293) (xy 94.104997 -217.955431) (xy 94.088998 -218.004671) (xy 94.065492 -218.050803)
			(xy 94.03506 -218.09269) (xy 93.99845 -218.1293) (xy 93.956563 -218.159732) (xy 93.910431 -218.183238)
			(xy 93.861191 -218.199237) (xy 93.810053 -218.207336) (xy 93.758279 -218.207336) (xy 93.707141 -218.199237)
			(xy 93.657901 -218.183238) (xy 93.611769 -218.159732) (xy 93.569882 -218.1293) (xy 93.533272 -218.09269)
			(xy 93.50284 -218.050803) (xy 93.479334 -218.004671) (xy 93.463335 -217.955431) (xy 93.455236 -217.904293)
			(xy 93.454728 -217.878406) (xy 93.173804 -217.878406) (xy 93.173276 -217.906114) (xy 93.16408 -217.960761)
			(xy 93.155516 -217.987118) (xy 93.147642 -218.009216) (xy 93.35262 -218.364054) (xy 93.37548 -218.368372)
			(xy 93.4003 -218.37354) (xy 93.448078 -218.390497) (xy 93.492695 -218.41457) (xy 93.5331 -218.44519)
			(xy 93.56834 -218.481637) (xy 93.597584 -218.52305) (xy 93.620142 -218.568452) (xy 93.635481 -218.616773)
			(xy 93.643241 -218.666873) (xy 93.643704 -218.692222) (xy 93.643196 -218.718129) (xy 93.63509 -218.769306)
			(xy 93.619078 -218.818585) (xy 93.595555 -218.864752) (xy 93.565099 -218.906671) (xy 93.528461 -218.943309)
			(xy 93.486542 -218.973765) (xy 93.440375 -218.997288) (xy 93.391096 -219.0133) (xy 93.339919 -219.021406)
			(xy 93.288105 -219.021406) (xy 93.236928 -219.0133) (xy 93.187649 -218.997288) (xy 93.141482 -218.973765)
			(xy 93.099563 -218.943309) (xy 93.062925 -218.906671) (xy 93.032469 -218.864752) (xy 93.008946 -218.818585)
			(xy 92.992934 -218.769306) (xy 92.984828 -218.718129) (xy 92.98432 -218.692222) (xy 92.984918 -218.664505)
			(xy 92.994239 -218.609858) (xy 93.002862 -218.58351) (xy 93.010736 -218.561412) (xy 92.805758 -218.206574)
			(xy 92.782898 -218.202256) (xy 92.758099 -218.197049) (xy 92.710362 -218.180062) (xy 92.665785 -218.15597)
			(xy 92.62542 -218.125341) (xy 92.590217 -218.088897) (xy 92.561004 -218.047495) (xy 92.538471 -218.002112)
			(xy 92.523146 -217.953814) (xy 92.515392 -217.903741) (xy 92.514928 -217.878406) (xy 92.234004 -217.878406)
			(xy 92.233496 -217.904293) (xy 92.225397 -217.955431) (xy 92.209398 -218.004671) (xy 92.185892 -218.050803)
			(xy 92.15546 -218.09269) (xy 92.11885 -218.1293) (xy 92.076963 -218.159732) (xy 92.030831 -218.183238)
			(xy 91.981591 -218.199237) (xy 91.930453 -218.207336) (xy 91.878679 -218.207336) (xy 91.827541 -218.199237)
			(xy 91.778301 -218.183238) (xy 91.732169 -218.159732) (xy 91.690282 -218.1293) (xy 91.653672 -218.09269)
			(xy 91.62324 -218.050803) (xy 91.599734 -218.004671) (xy 91.583735 -217.955431) (xy 91.575636 -217.904293)
			(xy 91.575128 -217.878406) (xy 91.294204 -217.878406) (xy 91.293676 -217.906114) (xy 91.28448 -217.960761)
			(xy 91.275916 -217.987118) (xy 91.268042 -218.009216) (xy 91.47302 -218.364054) (xy 91.49588 -218.368372)
			(xy 91.5207 -218.37354) (xy 91.568478 -218.390497) (xy 91.613095 -218.41457) (xy 91.6535 -218.44519)
			(xy 91.68874 -218.481637) (xy 91.717984 -218.52305) (xy 91.740542 -218.568452) (xy 91.755881 -218.616773)
			(xy 91.763641 -218.666873) (xy 91.764104 -218.692222) (xy 91.763596 -218.718129) (xy 91.75549 -218.769306)
			(xy 91.739478 -218.818585) (xy 91.715955 -218.864752) (xy 91.685499 -218.906671) (xy 91.648861 -218.943309)
			(xy 91.606942 -218.973765) (xy 91.560775 -218.997288) (xy 91.511496 -219.0133) (xy 91.460319 -219.021406)
			(xy 91.408505 -219.021406) (xy 91.357328 -219.0133) (xy 91.308049 -218.997288) (xy 91.261882 -218.973765)
			(xy 91.219963 -218.943309) (xy 91.183325 -218.906671) (xy 91.152869 -218.864752) (xy 91.129346 -218.818585)
			(xy 91.113334 -218.769306) (xy 91.105228 -218.718129) (xy 91.10472 -218.692222) (xy 91.105318 -218.664505)
			(xy 91.114639 -218.609858) (xy 91.123262 -218.58351) (xy 91.131136 -218.561412) (xy 90.926158 -218.206574)
			(xy 90.903298 -218.202256) (xy 90.878499 -218.197049) (xy 90.830762 -218.180062) (xy 90.786185 -218.15597)
			(xy 90.74582 -218.125341) (xy 90.710617 -218.088897) (xy 90.681404 -218.047495) (xy 90.658871 -218.002112)
			(xy 90.643546 -217.953814) (xy 90.635792 -217.903741) (xy 90.635328 -217.878406) (xy 90.354404 -217.878406)
			(xy 90.353896 -217.904293) (xy 90.345797 -217.955431) (xy 90.329798 -218.004671) (xy 90.306292 -218.050803)
			(xy 90.27586 -218.09269) (xy 90.23925 -218.1293) (xy 90.197363 -218.159732) (xy 90.151231 -218.183238)
			(xy 90.101991 -218.199237) (xy 90.050853 -218.207336) (xy 89.999079 -218.207336) (xy 89.947941 -218.199237)
			(xy 89.898701 -218.183238) (xy 89.852569 -218.159732) (xy 89.810682 -218.1293) (xy 89.774072 -218.09269)
			(xy 89.74364 -218.050803) (xy 89.720134 -218.004671) (xy 89.704135 -217.955431) (xy 89.696036 -217.904293)
			(xy 89.695528 -217.878406) (xy 89.414604 -217.878406) (xy 89.414076 -217.906114) (xy 89.40488 -217.960761)
			(xy 89.396316 -217.987118) (xy 89.388442 -218.009216) (xy 89.59342 -218.364054) (xy 89.61628 -218.368372)
			(xy 89.6411 -218.37354) (xy 89.688878 -218.390497) (xy 89.733495 -218.41457) (xy 89.7739 -218.44519)
			(xy 89.80914 -218.481637) (xy 89.838384 -218.52305) (xy 89.860942 -218.568452) (xy 89.876281 -218.616773)
			(xy 89.884041 -218.666873) (xy 89.884504 -218.692222) (xy 89.883996 -218.718129) (xy 89.87589 -218.769306)
			(xy 89.859878 -218.818585) (xy 89.836355 -218.864752) (xy 89.805899 -218.906671) (xy 89.769261 -218.943309)
			(xy 89.727342 -218.973765) (xy 89.681175 -218.997288) (xy 89.631896 -219.0133) (xy 89.580719 -219.021406)
			(xy 89.528905 -219.021406) (xy 89.477728 -219.0133) (xy 89.428449 -218.997288) (xy 89.382282 -218.973765)
			(xy 89.340363 -218.943309) (xy 89.303725 -218.906671) (xy 89.273269 -218.864752) (xy 89.249746 -218.818585)
			(xy 89.233734 -218.769306) (xy 89.225628 -218.718129) (xy 89.22512 -218.692222) (xy 89.225718 -218.664505)
			(xy 89.235039 -218.609858) (xy 89.243662 -218.58351) (xy 89.251536 -218.561412) (xy 89.046558 -218.206574)
			(xy 89.023698 -218.202256) (xy 88.998899 -218.197049) (xy 88.951162 -218.180062) (xy 88.906585 -218.15597)
			(xy 88.86622 -218.125341) (xy 88.831017 -218.088897) (xy 88.801804 -218.047495) (xy 88.779271 -218.002112)
			(xy 88.763946 -217.953814) (xy 88.756192 -217.903741) (xy 88.755728 -217.878406) (xy 65.7987 -217.878406)
			(xy 65.7987 -217.921332) (xy 65.798305 -217.931488) (xy 65.790498 -217.950241) (xy 65.776094 -217.964564)
			(xy 65.757297 -217.972262) (xy 65.747138 -217.97264) (xy 64.347598 -217.97264) (xy 64.337469 -217.972174)
			(xy 64.318744 -217.964442) (xy 64.304387 -217.950149) (xy 64.296571 -217.931459) (xy 64.296036 -217.921332)
			(xy 58.2549 -217.921332) (xy 58.254505 -217.931488) (xy 58.246698 -217.950241) (xy 58.232294 -217.964564)
			(xy 58.213497 -217.972262) (xy 58.203338 -217.97264) (xy 56.803798 -217.97264) (xy 56.793669 -217.972174)
			(xy 56.774944 -217.964442) (xy 56.760587 -217.950149) (xy 56.752771 -217.931459) (xy 56.752236 -217.921332)
			(xy 50.7111 -217.921332) (xy 50.710705 -217.931488) (xy 50.702898 -217.950241) (xy 50.688494 -217.964564)
			(xy 50.669697 -217.972262) (xy 50.659538 -217.97264) (xy 49.259998 -217.97264) (xy 49.249869 -217.972174)
			(xy 49.231144 -217.964442) (xy 49.216787 -217.950149) (xy 49.208971 -217.931459) (xy 49.208436 -217.921332)
			(xy 43.1673 -217.921332) (xy 43.166905 -217.931488) (xy 43.159098 -217.950241) (xy 43.144694 -217.964564)
			(xy 43.125897 -217.972262) (xy 43.115738 -217.97264) (xy 41.716198 -217.97264) (xy 41.706069 -217.972174)
			(xy 41.687344 -217.964442) (xy 41.672987 -217.950149) (xy 41.665171 -217.931459) (xy 41.664636 -217.921332)
			(xy 35.6235 -217.921332) (xy 35.623105 -217.931488) (xy 35.615298 -217.950241) (xy 35.600894 -217.964564)
			(xy 35.582097 -217.972262) (xy 35.571938 -217.97264) (xy 34.172398 -217.97264) (xy 34.162269 -217.972174)
			(xy 34.143544 -217.964442) (xy 34.129187 -217.950149) (xy 34.121371 -217.931459) (xy 34.120836 -217.921332)
			(xy 28.0797 -217.921332) (xy 28.079305 -217.931488) (xy 28.071498 -217.950241) (xy 28.057094 -217.964564)
			(xy 28.038297 -217.972262) (xy 28.028138 -217.97264) (xy 26.628598 -217.97264) (xy 26.618469 -217.972174)
			(xy 26.599744 -217.964442) (xy 26.585387 -217.950149) (xy 26.577571 -217.931459) (xy 26.577036 -217.921332)
			(xy 20.5359 -217.921332) (xy 20.535505 -217.931488) (xy 20.527698 -217.950241) (xy 20.513294 -217.964564)
			(xy 20.494497 -217.972262) (xy 20.484338 -217.97264) (xy 19.084798 -217.97264) (xy 19.074669 -217.972174)
			(xy 19.055944 -217.964442) (xy 19.041587 -217.950149) (xy 19.033771 -217.931459) (xy 19.033236 -217.921332)
			(xy 12.9921 -217.921332) (xy 12.991705 -217.931488) (xy 12.983898 -217.950241) (xy 12.969494 -217.964564)
			(xy 12.950697 -217.972262) (xy 12.940538 -217.97264) (xy 11.540998 -217.97264) (xy 11.530869 -217.972174)
			(xy 11.512144 -217.964442) (xy 11.497787 -217.950149) (xy 11.489971 -217.931459) (xy 11.489436 -217.921332)
			(xy 2.509012 -217.921332) (xy 2.509012 -218.77147) (xy 7.389368 -218.77147) (xy 7.389368 -218.36253)
			(xy 7.389789 -218.352357) (xy 7.39757 -218.333557) (xy 7.411957 -218.31917) (xy 7.430757 -218.311389)
			(xy 7.44093 -218.310968) (xy 8.84047 -218.310968) (xy 8.850643 -218.311389) (xy 8.869443 -218.31917)
			(xy 8.88383 -218.333557) (xy 8.891611 -218.352357) (xy 8.892032 -218.36253) (xy 8.892032 -218.77147)
			(xy 11.489436 -218.77147) (xy 11.489436 -218.36253) (xy 11.489889 -218.352361) (xy 11.497663 -218.333567)
			(xy 11.51204 -218.319181) (xy 11.530829 -218.311395) (xy 11.540998 -218.310968) (xy 12.940538 -218.310968)
			(xy 12.950702 -218.311403) (xy 12.969478 -218.319196) (xy 12.983843 -218.333579) (xy 12.99161 -218.352365)
			(xy 12.9921 -218.36253) (xy 12.9921 -218.77147) (xy 14.933168 -218.77147) (xy 14.933168 -218.36253)
			(xy 14.933589 -218.352357) (xy 14.94137 -218.333557) (xy 14.955757 -218.31917) (xy 14.974557 -218.311389)
			(xy 14.98473 -218.310968) (xy 16.38427 -218.310968) (xy 16.394443 -218.311389) (xy 16.413243 -218.31917)
			(xy 16.42763 -218.333557) (xy 16.435411 -218.352357) (xy 16.435832 -218.36253) (xy 16.435832 -218.77147)
			(xy 19.033236 -218.77147) (xy 19.033236 -218.36253) (xy 19.033689 -218.352361) (xy 19.041463 -218.333567)
			(xy 19.05584 -218.319181) (xy 19.074629 -218.311395) (xy 19.084798 -218.310968) (xy 20.484338 -218.310968)
			(xy 20.494502 -218.311403) (xy 20.513278 -218.319196) (xy 20.527643 -218.333579) (xy 20.53541 -218.352365)
			(xy 20.5359 -218.36253) (xy 20.5359 -218.77147) (xy 22.476968 -218.77147) (xy 22.476968 -218.36253)
			(xy 22.477389 -218.352357) (xy 22.48517 -218.333557) (xy 22.499557 -218.31917) (xy 22.518357 -218.311389)
			(xy 22.52853 -218.310968) (xy 23.92807 -218.310968) (xy 23.938243 -218.311389) (xy 23.957043 -218.31917)
			(xy 23.97143 -218.333557) (xy 23.979211 -218.352357) (xy 23.979632 -218.36253) (xy 23.979632 -218.77147)
			(xy 26.577036 -218.77147) (xy 26.577036 -218.36253) (xy 26.577489 -218.352361) (xy 26.585263 -218.333567)
			(xy 26.59964 -218.319181) (xy 26.618429 -218.311395) (xy 26.628598 -218.310968) (xy 28.028138 -218.310968)
			(xy 28.038302 -218.311403) (xy 28.057078 -218.319196) (xy 28.071443 -218.333579) (xy 28.07921 -218.352365)
			(xy 28.0797 -218.36253) (xy 28.0797 -218.77147) (xy 30.020768 -218.77147) (xy 30.020768 -218.36253)
			(xy 30.021189 -218.352357) (xy 30.02897 -218.333557) (xy 30.043357 -218.31917) (xy 30.062157 -218.311389)
			(xy 30.07233 -218.310968) (xy 31.47187 -218.310968) (xy 31.482043 -218.311389) (xy 31.500843 -218.31917)
			(xy 31.51523 -218.333557) (xy 31.523011 -218.352357) (xy 31.523432 -218.36253) (xy 31.523432 -218.77147)
			(xy 34.120836 -218.77147) (xy 34.120836 -218.36253) (xy 34.121289 -218.352361) (xy 34.129063 -218.333567)
			(xy 34.14344 -218.319181) (xy 34.162229 -218.311395) (xy 34.172398 -218.310968) (xy 35.571938 -218.310968)
			(xy 35.582102 -218.311403) (xy 35.600878 -218.319196) (xy 35.615243 -218.333579) (xy 35.62301 -218.352365)
			(xy 35.6235 -218.36253) (xy 35.6235 -218.77147) (xy 37.564568 -218.77147) (xy 37.564568 -218.36253)
			(xy 37.564989 -218.352357) (xy 37.57277 -218.333557) (xy 37.587157 -218.31917) (xy 37.605957 -218.311389)
			(xy 37.61613 -218.310968) (xy 39.01567 -218.310968) (xy 39.025843 -218.311389) (xy 39.044643 -218.31917)
			(xy 39.05903 -218.333557) (xy 39.066811 -218.352357) (xy 39.067232 -218.36253) (xy 39.067232 -218.77147)
			(xy 41.664636 -218.77147) (xy 41.664636 -218.36253) (xy 41.665089 -218.352361) (xy 41.672863 -218.333567)
			(xy 41.68724 -218.319181) (xy 41.706029 -218.311395) (xy 41.716198 -218.310968) (xy 43.115738 -218.310968)
			(xy 43.125902 -218.311403) (xy 43.144678 -218.319196) (xy 43.159043 -218.333579) (xy 43.16681 -218.352365)
			(xy 43.1673 -218.36253) (xy 43.1673 -218.77147) (xy 45.108368 -218.77147) (xy 45.108368 -218.36253)
			(xy 45.108789 -218.352357) (xy 45.11657 -218.333557) (xy 45.130957 -218.31917) (xy 45.149757 -218.311389)
			(xy 45.15993 -218.310968) (xy 46.55947 -218.310968) (xy 46.569643 -218.311389) (xy 46.588443 -218.31917)
			(xy 46.60283 -218.333557) (xy 46.610611 -218.352357) (xy 46.611032 -218.36253) (xy 46.611032 -218.77147)
			(xy 49.208436 -218.77147) (xy 49.208436 -218.36253) (xy 49.208889 -218.352361) (xy 49.216663 -218.333567)
			(xy 49.23104 -218.319181) (xy 49.249829 -218.311395) (xy 49.259998 -218.310968) (xy 50.659538 -218.310968)
			(xy 50.669702 -218.311403) (xy 50.688478 -218.319196) (xy 50.702843 -218.333579) (xy 50.71061 -218.352365)
			(xy 50.7111 -218.36253) (xy 50.7111 -218.77147) (xy 52.652168 -218.77147) (xy 52.652168 -218.36253)
			(xy 52.652589 -218.352357) (xy 52.66037 -218.333557) (xy 52.674757 -218.31917) (xy 52.693557 -218.311389)
			(xy 52.70373 -218.310968) (xy 54.10327 -218.310968) (xy 54.113443 -218.311389) (xy 54.132243 -218.31917)
			(xy 54.14663 -218.333557) (xy 54.154411 -218.352357) (xy 54.154832 -218.36253) (xy 54.154832 -218.77147)
			(xy 56.752236 -218.77147) (xy 56.752236 -218.36253) (xy 56.752689 -218.352361) (xy 56.760463 -218.333567)
			(xy 56.77484 -218.319181) (xy 56.793629 -218.311395) (xy 56.803798 -218.310968) (xy 58.203338 -218.310968)
			(xy 58.213502 -218.311403) (xy 58.232278 -218.319196) (xy 58.246643 -218.333579) (xy 58.25441 -218.352365)
			(xy 58.2549 -218.36253) (xy 58.2549 -218.77147) (xy 60.195968 -218.77147) (xy 60.195968 -218.36253)
			(xy 60.196389 -218.352357) (xy 60.20417 -218.333557) (xy 60.218557 -218.31917) (xy 60.237357 -218.311389)
			(xy 60.24753 -218.310968) (xy 61.64707 -218.310968) (xy 61.657243 -218.311389) (xy 61.676043 -218.31917)
			(xy 61.69043 -218.333557) (xy 61.698211 -218.352357) (xy 61.698632 -218.36253) (xy 61.698632 -218.77147)
			(xy 64.296036 -218.77147) (xy 64.296036 -218.36253) (xy 64.296489 -218.352361) (xy 64.304263 -218.333567)
			(xy 64.31864 -218.319181) (xy 64.337429 -218.311395) (xy 64.347598 -218.310968) (xy 65.747138 -218.310968)
			(xy 65.757302 -218.311403) (xy 65.776078 -218.319196) (xy 65.790443 -218.333579) (xy 65.79821 -218.352365)
			(xy 65.7987 -218.36253) (xy 65.7987 -218.77147) (xy 65.798143 -218.781621) (xy 65.790386 -218.800383)
			(xy 65.77604 -218.814748) (xy 65.757289 -218.82253) (xy 65.747138 -218.823032) (xy 64.347598 -218.823032)
			(xy 64.337423 -218.822637) (xy 64.318622 -218.814846) (xy 64.304236 -218.800451) (xy 64.296457 -218.781646)
			(xy 64.296036 -218.77147) (xy 61.698632 -218.77147) (xy 61.698211 -218.781643) (xy 61.69043 -218.800443)
			(xy 61.676043 -218.81483) (xy 61.657243 -218.822611) (xy 61.64707 -218.823032) (xy 60.24753 -218.823032)
			(xy 60.237357 -218.822611) (xy 60.218557 -218.81483) (xy 60.20417 -218.800443) (xy 60.196389 -218.781643)
			(xy 60.195968 -218.77147) (xy 58.2549 -218.77147) (xy 58.254343 -218.781621) (xy 58.246586 -218.800383)
			(xy 58.23224 -218.814748) (xy 58.213489 -218.82253) (xy 58.203338 -218.823032) (xy 56.803798 -218.823032)
			(xy 56.793623 -218.822637) (xy 56.774822 -218.814846) (xy 56.760436 -218.800451) (xy 56.752657 -218.781646)
			(xy 56.752236 -218.77147) (xy 54.154832 -218.77147) (xy 54.154411 -218.781643) (xy 54.14663 -218.800443)
			(xy 54.132243 -218.81483) (xy 54.113443 -218.822611) (xy 54.10327 -218.823032) (xy 52.70373 -218.823032)
			(xy 52.693557 -218.822611) (xy 52.674757 -218.81483) (xy 52.66037 -218.800443) (xy 52.652589 -218.781643)
			(xy 52.652168 -218.77147) (xy 50.7111 -218.77147) (xy 50.710543 -218.781621) (xy 50.702786 -218.800383)
			(xy 50.68844 -218.814748) (xy 50.669689 -218.82253) (xy 50.659538 -218.823032) (xy 49.259998 -218.823032)
			(xy 49.249823 -218.822637) (xy 49.231022 -218.814846) (xy 49.216636 -218.800451) (xy 49.208857 -218.781646)
			(xy 49.208436 -218.77147) (xy 46.611032 -218.77147) (xy 46.610611 -218.781643) (xy 46.60283 -218.800443)
			(xy 46.588443 -218.81483) (xy 46.569643 -218.822611) (xy 46.55947 -218.823032) (xy 45.15993 -218.823032)
			(xy 45.149757 -218.822611) (xy 45.130957 -218.81483) (xy 45.11657 -218.800443) (xy 45.108789 -218.781643)
			(xy 45.108368 -218.77147) (xy 43.1673 -218.77147) (xy 43.166743 -218.781621) (xy 43.158986 -218.800383)
			(xy 43.14464 -218.814748) (xy 43.125889 -218.82253) (xy 43.115738 -218.823032) (xy 41.716198 -218.823032)
			(xy 41.706023 -218.822637) (xy 41.687222 -218.814846) (xy 41.672836 -218.800451) (xy 41.665057 -218.781646)
			(xy 41.664636 -218.77147) (xy 39.067232 -218.77147) (xy 39.066811 -218.781643) (xy 39.05903 -218.800443)
			(xy 39.044643 -218.81483) (xy 39.025843 -218.822611) (xy 39.01567 -218.823032) (xy 37.61613 -218.823032)
			(xy 37.605957 -218.822611) (xy 37.587157 -218.81483) (xy 37.57277 -218.800443) (xy 37.564989 -218.781643)
			(xy 37.564568 -218.77147) (xy 35.6235 -218.77147) (xy 35.622943 -218.781621) (xy 35.615186 -218.800383)
			(xy 35.60084 -218.814748) (xy 35.582089 -218.82253) (xy 35.571938 -218.823032) (xy 34.172398 -218.823032)
			(xy 34.162223 -218.822637) (xy 34.143422 -218.814846) (xy 34.129036 -218.800451) (xy 34.121257 -218.781646)
			(xy 34.120836 -218.77147) (xy 31.523432 -218.77147) (xy 31.523011 -218.781643) (xy 31.51523 -218.800443)
			(xy 31.500843 -218.81483) (xy 31.482043 -218.822611) (xy 31.47187 -218.823032) (xy 30.07233 -218.823032)
			(xy 30.062157 -218.822611) (xy 30.043357 -218.81483) (xy 30.02897 -218.800443) (xy 30.021189 -218.781643)
			(xy 30.020768 -218.77147) (xy 28.0797 -218.77147) (xy 28.079143 -218.781621) (xy 28.071386 -218.800383)
			(xy 28.05704 -218.814748) (xy 28.038289 -218.82253) (xy 28.028138 -218.823032) (xy 26.628598 -218.823032)
			(xy 26.618423 -218.822637) (xy 26.599622 -218.814846) (xy 26.585236 -218.800451) (xy 26.577457 -218.781646)
			(xy 26.577036 -218.77147) (xy 23.979632 -218.77147) (xy 23.979211 -218.781643) (xy 23.97143 -218.800443)
			(xy 23.957043 -218.81483) (xy 23.938243 -218.822611) (xy 23.92807 -218.823032) (xy 22.52853 -218.823032)
			(xy 22.518357 -218.822611) (xy 22.499557 -218.81483) (xy 22.48517 -218.800443) (xy 22.477389 -218.781643)
			(xy 22.476968 -218.77147) (xy 20.5359 -218.77147) (xy 20.535343 -218.781621) (xy 20.527586 -218.800383)
			(xy 20.51324 -218.814748) (xy 20.494489 -218.82253) (xy 20.484338 -218.823032) (xy 19.084798 -218.823032)
			(xy 19.074623 -218.822637) (xy 19.055822 -218.814846) (xy 19.041436 -218.800451) (xy 19.033657 -218.781646)
			(xy 19.033236 -218.77147) (xy 16.435832 -218.77147) (xy 16.435411 -218.781643) (xy 16.42763 -218.800443)
			(xy 16.413243 -218.81483) (xy 16.394443 -218.822611) (xy 16.38427 -218.823032) (xy 14.98473 -218.823032)
			(xy 14.974557 -218.822611) (xy 14.955757 -218.81483) (xy 14.94137 -218.800443) (xy 14.933589 -218.781643)
			(xy 14.933168 -218.77147) (xy 12.9921 -218.77147) (xy 12.991543 -218.781621) (xy 12.983786 -218.800383)
			(xy 12.96944 -218.814748) (xy 12.950689 -218.82253) (xy 12.940538 -218.823032) (xy 11.540998 -218.823032)
			(xy 11.530823 -218.822637) (xy 11.512022 -218.814846) (xy 11.497636 -218.800451) (xy 11.489857 -218.781646)
			(xy 11.489436 -218.77147) (xy 8.892032 -218.77147) (xy 8.891611 -218.781643) (xy 8.88383 -218.800443)
			(xy 8.869443 -218.81483) (xy 8.850643 -218.822611) (xy 8.84047 -218.823032) (xy 7.44093 -218.823032)
			(xy 7.430757 -218.822611) (xy 7.411957 -218.81483) (xy 7.39757 -218.800443) (xy 7.389789 -218.781643)
			(xy 7.389368 -218.77147) (xy 2.509012 -218.77147) (xy 2.509012 -219.621354) (xy 7.389368 -219.621354)
			(xy 7.389368 -219.212414) (xy 7.389776 -219.20224) (xy 7.397562 -219.183439) (xy 7.411953 -219.169053)
			(xy 7.430755 -219.161273) (xy 7.44093 -219.160852) (xy 8.84047 -219.160852) (xy 8.850641 -219.161289)
			(xy 8.869438 -219.169067) (xy 8.883824 -219.183449) (xy 8.891608 -219.202243) (xy 8.892032 -219.212414)
			(xy 8.892032 -219.621354) (xy 14.933168 -219.621354) (xy 14.933168 -219.212414) (xy 14.933576 -219.20224)
			(xy 14.941362 -219.183439) (xy 14.955753 -219.169053) (xy 14.974555 -219.161273) (xy 14.98473 -219.160852)
			(xy 16.38427 -219.160852) (xy 16.394441 -219.161289) (xy 16.413238 -219.169067) (xy 16.427624 -219.183449)
			(xy 16.435408 -219.202243) (xy 16.435832 -219.212414) (xy 16.435832 -219.621354) (xy 22.476968 -219.621354)
			(xy 22.476968 -219.212414) (xy 22.477376 -219.20224) (xy 22.485162 -219.183439) (xy 22.499553 -219.169053)
			(xy 22.518355 -219.161273) (xy 22.52853 -219.160852) (xy 23.92807 -219.160852) (xy 23.938241 -219.161289)
			(xy 23.957038 -219.169067) (xy 23.971424 -219.183449) (xy 23.979208 -219.202243) (xy 23.979632 -219.212414)
			(xy 23.979632 -219.621354) (xy 30.020768 -219.621354) (xy 30.020768 -219.212414) (xy 30.021176 -219.20224)
			(xy 30.028962 -219.183439) (xy 30.043353 -219.169053) (xy 30.062155 -219.161273) (xy 30.07233 -219.160852)
			(xy 31.47187 -219.160852) (xy 31.482041 -219.161289) (xy 31.500838 -219.169067) (xy 31.515224 -219.183449)
			(xy 31.523008 -219.202243) (xy 31.523432 -219.212414) (xy 31.523432 -219.621354) (xy 37.564568 -219.621354)
			(xy 37.564568 -219.212414) (xy 37.564976 -219.20224) (xy 37.572762 -219.183439) (xy 37.587153 -219.169053)
			(xy 37.605955 -219.161273) (xy 37.61613 -219.160852) (xy 39.01567 -219.160852) (xy 39.025841 -219.161289)
			(xy 39.044638 -219.169067) (xy 39.059024 -219.183449) (xy 39.066808 -219.202243) (xy 39.067232 -219.212414)
			(xy 39.067232 -219.621354) (xy 45.108368 -219.621354) (xy 45.108368 -219.212414) (xy 45.108776 -219.20224)
			(xy 45.116562 -219.183439) (xy 45.130953 -219.169053) (xy 45.149755 -219.161273) (xy 45.15993 -219.160852)
			(xy 46.55947 -219.160852) (xy 46.569641 -219.161289) (xy 46.588438 -219.169067) (xy 46.602824 -219.183449)
			(xy 46.610608 -219.202243) (xy 46.611032 -219.212414) (xy 46.611032 -219.621354) (xy 52.652168 -219.621354)
			(xy 52.652168 -219.212414) (xy 52.652576 -219.20224) (xy 52.660362 -219.183439) (xy 52.674753 -219.169053)
			(xy 52.693555 -219.161273) (xy 52.70373 -219.160852) (xy 54.10327 -219.160852) (xy 54.113441 -219.161289)
			(xy 54.132238 -219.169067) (xy 54.146624 -219.183449) (xy 54.154408 -219.202243) (xy 54.154832 -219.212414)
			(xy 54.154832 -219.621354) (xy 60.195968 -219.621354) (xy 60.195968 -219.212414) (xy 60.196376 -219.20224)
			(xy 60.204162 -219.183439) (xy 60.218553 -219.169053) (xy 60.237355 -219.161273) (xy 60.24753 -219.160852)
			(xy 61.64707 -219.160852) (xy 61.657241 -219.161289) (xy 61.676038 -219.169067) (xy 61.690424 -219.183449)
			(xy 61.698208 -219.202243) (xy 61.698632 -219.212414) (xy 61.698632 -219.621354) (xy 158.062168 -219.621354)
			(xy 158.062168 -219.212414) (xy 158.062576 -219.20224) (xy 158.070362 -219.183439) (xy 158.084753 -219.169053)
			(xy 158.103555 -219.161273) (xy 158.11373 -219.160852) (xy 159.51327 -219.160852) (xy 159.523441 -219.161289)
			(xy 159.542238 -219.169067) (xy 159.556624 -219.183449) (xy 159.564408 -219.202243) (xy 159.564832 -219.212414)
			(xy 159.564832 -219.621354) (xy 165.605968 -219.621354) (xy 165.605968 -219.212414) (xy 165.606376 -219.20224)
			(xy 165.614162 -219.183439) (xy 165.628553 -219.169053) (xy 165.647355 -219.161273) (xy 165.65753 -219.160852)
			(xy 167.05707 -219.160852) (xy 167.067241 -219.161289) (xy 167.086038 -219.169067) (xy 167.100424 -219.183449)
			(xy 167.108208 -219.202243) (xy 167.108632 -219.212414) (xy 167.108632 -219.621354) (xy 173.149768 -219.621354)
			(xy 173.149768 -219.212414) (xy 173.150176 -219.20224) (xy 173.157962 -219.183439) (xy 173.172353 -219.169053)
			(xy 173.191155 -219.161273) (xy 173.20133 -219.160852) (xy 174.60087 -219.160852) (xy 174.611041 -219.161289)
			(xy 174.629838 -219.169067) (xy 174.644224 -219.183449) (xy 174.652008 -219.202243) (xy 174.652432 -219.212414)
			(xy 174.652432 -219.621354) (xy 180.693568 -219.621354) (xy 180.693568 -219.212414) (xy 180.693976 -219.20224)
			(xy 180.701762 -219.183439) (xy 180.716153 -219.169053) (xy 180.734955 -219.161273) (xy 180.74513 -219.160852)
			(xy 182.14467 -219.160852) (xy 182.154841 -219.161289) (xy 182.173638 -219.169067) (xy 182.188024 -219.183449)
			(xy 182.195808 -219.202243) (xy 182.196232 -219.212414) (xy 182.196232 -219.621354) (xy 188.237368 -219.621354)
			(xy 188.237368 -219.212414) (xy 188.237776 -219.20224) (xy 188.245562 -219.183439) (xy 188.259953 -219.169053)
			(xy 188.278755 -219.161273) (xy 188.28893 -219.160852) (xy 189.68847 -219.160852) (xy 189.698641 -219.161289)
			(xy 189.717438 -219.169067) (xy 189.731824 -219.183449) (xy 189.739608 -219.202243) (xy 189.740032 -219.212414)
			(xy 189.740032 -219.621354) (xy 195.781168 -219.621354) (xy 195.781168 -219.212414) (xy 195.781576 -219.20224)
			(xy 195.789362 -219.183439) (xy 195.803753 -219.169053) (xy 195.822555 -219.161273) (xy 195.83273 -219.160852)
			(xy 197.23227 -219.160852) (xy 197.242441 -219.161289) (xy 197.261238 -219.169067) (xy 197.275624 -219.183449)
			(xy 197.283408 -219.202243) (xy 197.283832 -219.212414) (xy 197.283832 -219.621354) (xy 203.324968 -219.621354)
			(xy 203.324968 -219.212414) (xy 203.325376 -219.20224) (xy 203.333162 -219.183439) (xy 203.347553 -219.169053)
			(xy 203.366355 -219.161273) (xy 203.37653 -219.160852) (xy 204.77607 -219.160852) (xy 204.786241 -219.161289)
			(xy 204.805038 -219.169067) (xy 204.819424 -219.183449) (xy 204.827208 -219.202243) (xy 204.827632 -219.212414)
			(xy 204.827632 -219.621354) (xy 210.868768 -219.621354) (xy 210.868768 -219.212414) (xy 210.869176 -219.20224)
			(xy 210.876962 -219.183439) (xy 210.891353 -219.169053) (xy 210.910155 -219.161273) (xy 210.92033 -219.160852)
			(xy 212.31987 -219.160852) (xy 212.330041 -219.161289) (xy 212.348838 -219.169067) (xy 212.363224 -219.183449)
			(xy 212.371008 -219.202243) (xy 212.371432 -219.212414) (xy 212.371432 -219.621354) (xy 255.329436 -219.621354)
			(xy 255.329436 -219.212414) (xy 255.329875 -219.202244) (xy 255.337655 -219.183449) (xy 255.352036 -219.169064)
			(xy 255.370828 -219.161278) (xy 255.380998 -219.160852) (xy 256.780538 -219.160852) (xy 256.7907 -219.161303)
			(xy 256.809473 -219.169092) (xy 256.823837 -219.183471) (xy 256.831608 -219.202252) (xy 256.8321 -219.212414)
			(xy 256.8321 -219.621354) (xy 262.873236 -219.621354) (xy 262.873236 -219.212414) (xy 262.873675 -219.202244)
			(xy 262.881455 -219.183449) (xy 262.895836 -219.169064) (xy 262.914628 -219.161278) (xy 262.924798 -219.160852)
			(xy 264.324338 -219.160852) (xy 264.3345 -219.161303) (xy 264.353273 -219.169092) (xy 264.367637 -219.183471)
			(xy 264.375408 -219.202252) (xy 264.3759 -219.212414) (xy 264.3759 -219.621354) (xy 270.417036 -219.621354)
			(xy 270.417036 -219.212414) (xy 270.417475 -219.202244) (xy 270.425255 -219.183449) (xy 270.439636 -219.169064)
			(xy 270.458428 -219.161278) (xy 270.468598 -219.160852) (xy 271.868138 -219.160852) (xy 271.8783 -219.161303)
			(xy 271.897073 -219.169092) (xy 271.911437 -219.183471) (xy 271.919208 -219.202252) (xy 271.9197 -219.212414)
			(xy 271.9197 -219.621354) (xy 277.960836 -219.621354) (xy 277.960836 -219.212414) (xy 277.961275 -219.202244)
			(xy 277.969055 -219.183449) (xy 277.983436 -219.169064) (xy 278.002228 -219.161278) (xy 278.012398 -219.160852)
			(xy 279.411938 -219.160852) (xy 279.4221 -219.161303) (xy 279.440873 -219.169092) (xy 279.455237 -219.183471)
			(xy 279.463008 -219.202252) (xy 279.4635 -219.212414) (xy 279.4635 -219.621354) (xy 285.504636 -219.621354)
			(xy 285.504636 -219.212414) (xy 285.505075 -219.202244) (xy 285.512855 -219.183449) (xy 285.527236 -219.169064)
			(xy 285.546028 -219.161278) (xy 285.556198 -219.160852) (xy 286.955738 -219.160852) (xy 286.9659 -219.161303)
			(xy 286.984673 -219.169092) (xy 286.999037 -219.183471) (xy 287.006808 -219.202252) (xy 287.0073 -219.212414)
			(xy 287.0073 -219.621354) (xy 293.048436 -219.621354) (xy 293.048436 -219.212414) (xy 293.048875 -219.202244)
			(xy 293.056655 -219.183449) (xy 293.071036 -219.169064) (xy 293.089828 -219.161278) (xy 293.099998 -219.160852)
			(xy 294.499538 -219.160852) (xy 294.5097 -219.161303) (xy 294.528473 -219.169092) (xy 294.542837 -219.183471)
			(xy 294.550608 -219.202252) (xy 294.5511 -219.212414) (xy 294.5511 -219.621354) (xy 300.592236 -219.621354)
			(xy 300.592236 -219.212414) (xy 300.592675 -219.202244) (xy 300.600455 -219.183449) (xy 300.614836 -219.169064)
			(xy 300.633628 -219.161278) (xy 300.643798 -219.160852) (xy 302.043338 -219.160852) (xy 302.0535 -219.161303)
			(xy 302.072273 -219.169092) (xy 302.086637 -219.183471) (xy 302.094408 -219.202252) (xy 302.0949 -219.212414)
			(xy 302.0949 -219.621354) (xy 308.136036 -219.621354) (xy 308.136036 -219.212414) (xy 308.136475 -219.202244)
			(xy 308.144255 -219.183449) (xy 308.158636 -219.169064) (xy 308.177428 -219.161278) (xy 308.187598 -219.160852)
			(xy 309.587138 -219.160852) (xy 309.5973 -219.161303) (xy 309.616073 -219.169092) (xy 309.630437 -219.183471)
			(xy 309.638208 -219.202252) (xy 309.6387 -219.212414) (xy 309.6387 -219.621354) (xy 406.002236 -219.621354)
			(xy 406.002236 -219.212414) (xy 406.002675 -219.202244) (xy 406.010455 -219.183449) (xy 406.024836 -219.169064)
			(xy 406.043628 -219.161278) (xy 406.053798 -219.160852) (xy 407.453338 -219.160852) (xy 407.4635 -219.161303)
			(xy 407.482273 -219.169092) (xy 407.496637 -219.183471) (xy 407.504408 -219.202252) (xy 407.5049 -219.212414)
			(xy 407.5049 -219.621354) (xy 413.546036 -219.621354) (xy 413.546036 -219.212414) (xy 413.546475 -219.202244)
			(xy 413.554255 -219.183449) (xy 413.568636 -219.169064) (xy 413.587428 -219.161278) (xy 413.597598 -219.160852)
			(xy 414.997138 -219.160852) (xy 415.0073 -219.161303) (xy 415.026073 -219.169092) (xy 415.040437 -219.183471)
			(xy 415.048208 -219.202252) (xy 415.0487 -219.212414) (xy 415.0487 -219.621354) (xy 421.089836 -219.621354)
			(xy 421.089836 -219.212414) (xy 421.090275 -219.202244) (xy 421.098055 -219.183449) (xy 421.112436 -219.169064)
			(xy 421.131228 -219.161278) (xy 421.141398 -219.160852) (xy 422.540938 -219.160852) (xy 422.5511 -219.161303)
			(xy 422.569873 -219.169092) (xy 422.584237 -219.183471) (xy 422.592008 -219.202252) (xy 422.5925 -219.212414)
			(xy 422.5925 -219.621354) (xy 428.633636 -219.621354) (xy 428.633636 -219.212414) (xy 428.634075 -219.202244)
			(xy 428.641855 -219.183449) (xy 428.656236 -219.169064) (xy 428.675028 -219.161278) (xy 428.685198 -219.160852)
			(xy 430.084738 -219.160852) (xy 430.0949 -219.161303) (xy 430.113673 -219.169092) (xy 430.128037 -219.183471)
			(xy 430.135808 -219.202252) (xy 430.1363 -219.212414) (xy 430.1363 -219.621354) (xy 436.177436 -219.621354)
			(xy 436.177436 -219.212414) (xy 436.177875 -219.202244) (xy 436.185655 -219.183449) (xy 436.200036 -219.169064)
			(xy 436.218828 -219.161278) (xy 436.228998 -219.160852) (xy 437.628538 -219.160852) (xy 437.6387 -219.161303)
			(xy 437.657473 -219.169092) (xy 437.671837 -219.183471) (xy 437.679608 -219.202252) (xy 437.6801 -219.212414)
			(xy 437.6801 -219.621354) (xy 443.721236 -219.621354) (xy 443.721236 -219.212414) (xy 443.721675 -219.202244)
			(xy 443.729455 -219.183449) (xy 443.743836 -219.169064) (xy 443.762628 -219.161278) (xy 443.772798 -219.160852)
			(xy 445.172338 -219.160852) (xy 445.1825 -219.161303) (xy 445.201273 -219.169092) (xy 445.215637 -219.183471)
			(xy 445.223408 -219.202252) (xy 445.2239 -219.212414) (xy 445.2239 -219.621354) (xy 451.265036 -219.621354)
			(xy 451.265036 -219.212414) (xy 451.265475 -219.202244) (xy 451.273255 -219.183449) (xy 451.287636 -219.169064)
			(xy 451.306428 -219.161278) (xy 451.316598 -219.160852) (xy 452.716138 -219.160852) (xy 452.7263 -219.161303)
			(xy 452.745073 -219.169092) (xy 452.759437 -219.183471) (xy 452.767208 -219.202252) (xy 452.7677 -219.212414)
			(xy 452.7677 -219.621354) (xy 458.808836 -219.621354) (xy 458.808836 -219.212414) (xy 458.809275 -219.202244)
			(xy 458.817055 -219.183449) (xy 458.831436 -219.169064) (xy 458.850228 -219.161278) (xy 458.860398 -219.160852)
			(xy 460.259938 -219.160852) (xy 460.2701 -219.161303) (xy 460.288873 -219.169092) (xy 460.303237 -219.183471)
			(xy 460.311008 -219.202252) (xy 460.3115 -219.212414) (xy 460.3115 -219.621354) (xy 460.310999 -219.631518)
			(xy 460.303237 -219.650304) (xy 460.288875 -219.664689) (xy 460.270101 -219.672483) (xy 460.259938 -219.672916)
			(xy 458.860398 -219.672916) (xy 458.850221 -219.672537) (xy 458.831417 -219.664742) (xy 458.817031 -219.650343)
			(xy 458.809254 -219.631532) (xy 458.808836 -219.621354) (xy 452.7677 -219.621354) (xy 452.767199 -219.631518)
			(xy 452.759437 -219.650304) (xy 452.745075 -219.664689) (xy 452.726301 -219.672483) (xy 452.716138 -219.672916)
			(xy 451.316598 -219.672916) (xy 451.306421 -219.672537) (xy 451.287617 -219.664742) (xy 451.273231 -219.650343)
			(xy 451.265454 -219.631532) (xy 451.265036 -219.621354) (xy 445.2239 -219.621354) (xy 445.223399 -219.631518)
			(xy 445.215637 -219.650304) (xy 445.201275 -219.664689) (xy 445.182501 -219.672483) (xy 445.172338 -219.672916)
			(xy 443.772798 -219.672916) (xy 443.762621 -219.672537) (xy 443.743817 -219.664742) (xy 443.729431 -219.650343)
			(xy 443.721654 -219.631532) (xy 443.721236 -219.621354) (xy 437.6801 -219.621354) (xy 437.679599 -219.631518)
			(xy 437.671837 -219.650304) (xy 437.657475 -219.664689) (xy 437.638701 -219.672483) (xy 437.628538 -219.672916)
			(xy 436.228998 -219.672916) (xy 436.218821 -219.672537) (xy 436.200017 -219.664742) (xy 436.185631 -219.650343)
			(xy 436.177854 -219.631532) (xy 436.177436 -219.621354) (xy 430.1363 -219.621354) (xy 430.135799 -219.631518)
			(xy 430.128037 -219.650304) (xy 430.113675 -219.664689) (xy 430.094901 -219.672483) (xy 430.084738 -219.672916)
			(xy 428.685198 -219.672916) (xy 428.675021 -219.672537) (xy 428.656217 -219.664742) (xy 428.641831 -219.650343)
			(xy 428.634054 -219.631532) (xy 428.633636 -219.621354) (xy 422.5925 -219.621354) (xy 422.591999 -219.631518)
			(xy 422.584237 -219.650304) (xy 422.569875 -219.664689) (xy 422.551101 -219.672483) (xy 422.540938 -219.672916)
			(xy 421.141398 -219.672916) (xy 421.131221 -219.672537) (xy 421.112417 -219.664742) (xy 421.098031 -219.650343)
			(xy 421.090254 -219.631532) (xy 421.089836 -219.621354) (xy 415.0487 -219.621354) (xy 415.048199 -219.631518)
			(xy 415.040437 -219.650304) (xy 415.026075 -219.664689) (xy 415.007301 -219.672483) (xy 414.997138 -219.672916)
			(xy 413.597598 -219.672916) (xy 413.587421 -219.672537) (xy 413.568617 -219.664742) (xy 413.554231 -219.650343)
			(xy 413.546454 -219.631532) (xy 413.546036 -219.621354) (xy 407.5049 -219.621354) (xy 407.504399 -219.631518)
			(xy 407.496637 -219.650304) (xy 407.482275 -219.664689) (xy 407.463501 -219.672483) (xy 407.453338 -219.672916)
			(xy 406.053798 -219.672916) (xy 406.043621 -219.672537) (xy 406.024817 -219.664742) (xy 406.010431 -219.650343)
			(xy 406.002654 -219.631532) (xy 406.002236 -219.621354) (xy 309.6387 -219.621354) (xy 309.638199 -219.631518)
			(xy 309.630437 -219.650304) (xy 309.616075 -219.664689) (xy 309.597301 -219.672483) (xy 309.587138 -219.672916)
			(xy 308.187598 -219.672916) (xy 308.177421 -219.672537) (xy 308.158617 -219.664742) (xy 308.144231 -219.650343)
			(xy 308.136454 -219.631532) (xy 308.136036 -219.621354) (xy 302.0949 -219.621354) (xy 302.094399 -219.631518)
			(xy 302.086637 -219.650304) (xy 302.072275 -219.664689) (xy 302.053501 -219.672483) (xy 302.043338 -219.672916)
			(xy 300.643798 -219.672916) (xy 300.633621 -219.672537) (xy 300.614817 -219.664742) (xy 300.600431 -219.650343)
			(xy 300.592654 -219.631532) (xy 300.592236 -219.621354) (xy 294.5511 -219.621354) (xy 294.550599 -219.631518)
			(xy 294.542837 -219.650304) (xy 294.528475 -219.664689) (xy 294.509701 -219.672483) (xy 294.499538 -219.672916)
			(xy 293.099998 -219.672916) (xy 293.089821 -219.672537) (xy 293.071017 -219.664742) (xy 293.056631 -219.650343)
			(xy 293.048854 -219.631532) (xy 293.048436 -219.621354) (xy 287.0073 -219.621354) (xy 287.006799 -219.631518)
			(xy 286.999037 -219.650304) (xy 286.984675 -219.664689) (xy 286.965901 -219.672483) (xy 286.955738 -219.672916)
			(xy 285.556198 -219.672916) (xy 285.546021 -219.672537) (xy 285.527217 -219.664742) (xy 285.512831 -219.650343)
			(xy 285.505054 -219.631532) (xy 285.504636 -219.621354) (xy 279.4635 -219.621354) (xy 279.462999 -219.631518)
			(xy 279.455237 -219.650304) (xy 279.440875 -219.664689) (xy 279.422101 -219.672483) (xy 279.411938 -219.672916)
			(xy 278.012398 -219.672916) (xy 278.002221 -219.672537) (xy 277.983417 -219.664742) (xy 277.969031 -219.650343)
			(xy 277.961254 -219.631532) (xy 277.960836 -219.621354) (xy 271.9197 -219.621354) (xy 271.919199 -219.631518)
			(xy 271.911437 -219.650304) (xy 271.897075 -219.664689) (xy 271.878301 -219.672483) (xy 271.868138 -219.672916)
			(xy 270.468598 -219.672916) (xy 270.458421 -219.672537) (xy 270.439617 -219.664742) (xy 270.425231 -219.650343)
			(xy 270.417454 -219.631532) (xy 270.417036 -219.621354) (xy 264.3759 -219.621354) (xy 264.375399 -219.631518)
			(xy 264.367637 -219.650304) (xy 264.353275 -219.664689) (xy 264.334501 -219.672483) (xy 264.324338 -219.672916)
			(xy 262.924798 -219.672916) (xy 262.914621 -219.672537) (xy 262.895817 -219.664742) (xy 262.881431 -219.650343)
			(xy 262.873654 -219.631532) (xy 262.873236 -219.621354) (xy 256.8321 -219.621354) (xy 256.831599 -219.631518)
			(xy 256.823837 -219.650304) (xy 256.809475 -219.664689) (xy 256.790701 -219.672483) (xy 256.780538 -219.672916)
			(xy 255.380998 -219.672916) (xy 255.370821 -219.672537) (xy 255.352017 -219.664742) (xy 255.337631 -219.650343)
			(xy 255.329854 -219.631532) (xy 255.329436 -219.621354) (xy 212.371432 -219.621354) (xy 212.370998 -219.631526)
			(xy 212.363222 -219.650326) (xy 212.348839 -219.664713) (xy 212.330042 -219.672495) (xy 212.31987 -219.672916)
			(xy 210.92033 -219.672916) (xy 210.910155 -219.67251) (xy 210.891352 -219.664727) (xy 210.876964 -219.650335)
			(xy 210.869187 -219.631529) (xy 210.868768 -219.621354) (xy 204.827632 -219.621354) (xy 204.827198 -219.631526)
			(xy 204.819422 -219.650326) (xy 204.805039 -219.664713) (xy 204.786242 -219.672495) (xy 204.77607 -219.672916)
			(xy 203.37653 -219.672916) (xy 203.366355 -219.67251) (xy 203.347552 -219.664727) (xy 203.333164 -219.650335)
			(xy 203.325387 -219.631529) (xy 203.324968 -219.621354) (xy 197.283832 -219.621354) (xy 197.283398 -219.631526)
			(xy 197.275622 -219.650326) (xy 197.261239 -219.664713) (xy 197.242442 -219.672495) (xy 197.23227 -219.672916)
			(xy 195.83273 -219.672916) (xy 195.822555 -219.67251) (xy 195.803752 -219.664727) (xy 195.789364 -219.650335)
			(xy 195.781587 -219.631529) (xy 195.781168 -219.621354) (xy 189.740032 -219.621354) (xy 189.739598 -219.631526)
			(xy 189.731822 -219.650326) (xy 189.717439 -219.664713) (xy 189.698642 -219.672495) (xy 189.68847 -219.672916)
			(xy 188.28893 -219.672916) (xy 188.278755 -219.67251) (xy 188.259952 -219.664727) (xy 188.245564 -219.650335)
			(xy 188.237787 -219.631529) (xy 188.237368 -219.621354) (xy 182.196232 -219.621354) (xy 182.195798 -219.631526)
			(xy 182.188022 -219.650326) (xy 182.173639 -219.664713) (xy 182.154842 -219.672495) (xy 182.14467 -219.672916)
			(xy 180.74513 -219.672916) (xy 180.734955 -219.67251) (xy 180.716152 -219.664727) (xy 180.701764 -219.650335)
			(xy 180.693987 -219.631529) (xy 180.693568 -219.621354) (xy 174.652432 -219.621354) (xy 174.651998 -219.631526)
			(xy 174.644222 -219.650326) (xy 174.629839 -219.664713) (xy 174.611042 -219.672495) (xy 174.60087 -219.672916)
			(xy 173.20133 -219.672916) (xy 173.191155 -219.67251) (xy 173.172352 -219.664727) (xy 173.157964 -219.650335)
			(xy 173.150187 -219.631529) (xy 173.149768 -219.621354) (xy 167.108632 -219.621354) (xy 167.108198 -219.631526)
			(xy 167.100422 -219.650326) (xy 167.086039 -219.664713) (xy 167.067242 -219.672495) (xy 167.05707 -219.672916)
			(xy 165.65753 -219.672916) (xy 165.647355 -219.67251) (xy 165.628552 -219.664727) (xy 165.614164 -219.650335)
			(xy 165.606387 -219.631529) (xy 165.605968 -219.621354) (xy 159.564832 -219.621354) (xy 159.564398 -219.631526)
			(xy 159.556622 -219.650326) (xy 159.542239 -219.664713) (xy 159.523442 -219.672495) (xy 159.51327 -219.672916)
			(xy 158.11373 -219.672916) (xy 158.103555 -219.67251) (xy 158.084752 -219.664727) (xy 158.070364 -219.650335)
			(xy 158.062587 -219.631529) (xy 158.062168 -219.621354) (xy 61.698632 -219.621354) (xy 61.698198 -219.631526)
			(xy 61.690422 -219.650326) (xy 61.676039 -219.664713) (xy 61.657242 -219.672495) (xy 61.64707 -219.672916)
			(xy 60.24753 -219.672916) (xy 60.237355 -219.67251) (xy 60.218552 -219.664727) (xy 60.204164 -219.650335)
			(xy 60.196387 -219.631529) (xy 60.195968 -219.621354) (xy 54.154832 -219.621354) (xy 54.154398 -219.631526)
			(xy 54.146622 -219.650326) (xy 54.132239 -219.664713) (xy 54.113442 -219.672495) (xy 54.10327 -219.672916)
			(xy 52.70373 -219.672916) (xy 52.693555 -219.67251) (xy 52.674752 -219.664727) (xy 52.660364 -219.650335)
			(xy 52.652587 -219.631529) (xy 52.652168 -219.621354) (xy 46.611032 -219.621354) (xy 46.610598 -219.631526)
			(xy 46.602822 -219.650326) (xy 46.588439 -219.664713) (xy 46.569642 -219.672495) (xy 46.55947 -219.672916)
			(xy 45.15993 -219.672916) (xy 45.149755 -219.67251) (xy 45.130952 -219.664727) (xy 45.116564 -219.650335)
			(xy 45.108787 -219.631529) (xy 45.108368 -219.621354) (xy 39.067232 -219.621354) (xy 39.066798 -219.631526)
			(xy 39.059022 -219.650326) (xy 39.044639 -219.664713) (xy 39.025842 -219.672495) (xy 39.01567 -219.672916)
			(xy 37.61613 -219.672916) (xy 37.605955 -219.67251) (xy 37.587152 -219.664727) (xy 37.572764 -219.650335)
			(xy 37.564987 -219.631529) (xy 37.564568 -219.621354) (xy 31.523432 -219.621354) (xy 31.522998 -219.631526)
			(xy 31.515222 -219.650326) (xy 31.500839 -219.664713) (xy 31.482042 -219.672495) (xy 31.47187 -219.672916)
			(xy 30.07233 -219.672916) (xy 30.062155 -219.67251) (xy 30.043352 -219.664727) (xy 30.028964 -219.650335)
			(xy 30.021187 -219.631529) (xy 30.020768 -219.621354) (xy 23.979632 -219.621354) (xy 23.979198 -219.631526)
			(xy 23.971422 -219.650326) (xy 23.957039 -219.664713) (xy 23.938242 -219.672495) (xy 23.92807 -219.672916)
			(xy 22.52853 -219.672916) (xy 22.518355 -219.67251) (xy 22.499552 -219.664727) (xy 22.485164 -219.650335)
			(xy 22.477387 -219.631529) (xy 22.476968 -219.621354) (xy 16.435832 -219.621354) (xy 16.435398 -219.631526)
			(xy 16.427622 -219.650326) (xy 16.413239 -219.664713) (xy 16.394442 -219.672495) (xy 16.38427 -219.672916)
			(xy 14.98473 -219.672916) (xy 14.974555 -219.67251) (xy 14.955752 -219.664727) (xy 14.941364 -219.650335)
			(xy 14.933587 -219.631529) (xy 14.933168 -219.621354) (xy 8.892032 -219.621354) (xy 8.891598 -219.631526)
			(xy 8.883822 -219.650326) (xy 8.869439 -219.664713) (xy 8.850642 -219.672495) (xy 8.84047 -219.672916)
			(xy 7.44093 -219.672916) (xy 7.430755 -219.67251) (xy 7.411952 -219.664727) (xy 7.397564 -219.650335)
			(xy 7.389787 -219.631529) (xy 7.389368 -219.621354) (xy 2.509012 -219.621354) (xy 2.509012 -220.471492)
			(xy 11.489436 -220.471492) (xy 11.489436 -220.062552) (xy 11.489783 -220.05239) (xy 11.497601 -220.03363)
			(xy 11.512021 -220.019307) (xy 11.530834 -220.011616) (xy 11.540998 -220.011244) (xy 12.940538 -220.011244)
			(xy 12.950668 -220.011696) (xy 12.96939 -220.019437) (xy 12.983746 -220.033733) (xy 12.991563 -220.052424)
			(xy 12.9921 -220.062552) (xy 12.9921 -220.471492) (xy 19.033236 -220.471492) (xy 19.033236 -220.062552)
			(xy 19.033583 -220.05239) (xy 19.041401 -220.03363) (xy 19.055821 -220.019307) (xy 19.074634 -220.011616)
			(xy 19.084798 -220.011244) (xy 20.484338 -220.011244) (xy 20.494468 -220.011696) (xy 20.51319 -220.019437)
			(xy 20.527546 -220.033733) (xy 20.535363 -220.052424) (xy 20.5359 -220.062552) (xy 20.5359 -220.471492)
			(xy 26.577036 -220.471492) (xy 26.577036 -220.062552) (xy 26.577383 -220.05239) (xy 26.585201 -220.03363)
			(xy 26.599621 -220.019307) (xy 26.618434 -220.011616) (xy 26.628598 -220.011244) (xy 28.028138 -220.011244)
			(xy 28.038268 -220.011696) (xy 28.05699 -220.019437) (xy 28.071346 -220.033733) (xy 28.079163 -220.052424)
			(xy 28.0797 -220.062552) (xy 28.0797 -220.471492) (xy 34.120836 -220.471492) (xy 34.120836 -220.062552)
			(xy 34.121183 -220.05239) (xy 34.129001 -220.03363) (xy 34.143421 -220.019307) (xy 34.162234 -220.011616)
			(xy 34.172398 -220.011244) (xy 35.571938 -220.011244) (xy 35.582068 -220.011696) (xy 35.60079 -220.019437)
			(xy 35.615146 -220.033733) (xy 35.622963 -220.052424) (xy 35.6235 -220.062552) (xy 35.6235 -220.471492)
			(xy 41.664636 -220.471492) (xy 41.664636 -220.062552) (xy 41.664983 -220.05239) (xy 41.672801 -220.03363)
			(xy 41.687221 -220.019307) (xy 41.706034 -220.011616) (xy 41.716198 -220.011244) (xy 43.115738 -220.011244)
			(xy 43.125868 -220.011696) (xy 43.14459 -220.019437) (xy 43.158946 -220.033733) (xy 43.166763 -220.052424)
			(xy 43.1673 -220.062552) (xy 43.1673 -220.471492) (xy 49.208436 -220.471492) (xy 49.208436 -220.062552)
			(xy 49.208783 -220.05239) (xy 49.216601 -220.03363) (xy 49.231021 -220.019307) (xy 49.249834 -220.011616)
			(xy 49.259998 -220.011244) (xy 50.659538 -220.011244) (xy 50.669668 -220.011696) (xy 50.68839 -220.019437)
			(xy 50.702746 -220.033733) (xy 50.710563 -220.052424) (xy 50.7111 -220.062552) (xy 50.7111 -220.471492)
			(xy 56.752236 -220.471492) (xy 56.752236 -220.062552) (xy 56.752583 -220.05239) (xy 56.760401 -220.03363)
			(xy 56.774821 -220.019307) (xy 56.793634 -220.011616) (xy 56.803798 -220.011244) (xy 58.203338 -220.011244)
			(xy 58.213468 -220.011696) (xy 58.23219 -220.019437) (xy 58.246546 -220.033733) (xy 58.254363 -220.052424)
			(xy 58.2549 -220.062552) (xy 58.2549 -220.471492) (xy 64.296036 -220.471492) (xy 64.296036 -220.062552)
			(xy 64.296383 -220.05239) (xy 64.304201 -220.03363) (xy 64.318621 -220.019307) (xy 64.337434 -220.011616)
			(xy 64.347598 -220.011244) (xy 65.747138 -220.011244) (xy 65.757268 -220.011696) (xy 65.77599 -220.019437)
			(xy 65.790346 -220.033733) (xy 65.798163 -220.052424) (xy 65.7987 -220.062552) (xy 65.7987 -220.471492)
			(xy 65.798272 -220.481646) (xy 65.790479 -220.500398) (xy 65.776084 -220.514721) (xy 65.757294 -220.522421)
			(xy 65.747138 -220.5228) (xy 64.347598 -220.5228) (xy 64.337476 -220.522276) (xy 64.318763 -220.514555)
			(xy 64.304408 -220.500281) (xy 64.296582 -220.481611) (xy 64.296036 -220.471492) (xy 58.2549 -220.471492)
			(xy 58.254472 -220.481646) (xy 58.246679 -220.500398) (xy 58.232284 -220.514721) (xy 58.213494 -220.522421)
			(xy 58.203338 -220.5228) (xy 56.803798 -220.5228) (xy 56.793676 -220.522276) (xy 56.774963 -220.514555)
			(xy 56.760608 -220.500281) (xy 56.752782 -220.481611) (xy 56.752236 -220.471492) (xy 50.7111 -220.471492)
			(xy 50.710672 -220.481646) (xy 50.702879 -220.500398) (xy 50.688484 -220.514721) (xy 50.669694 -220.522421)
			(xy 50.659538 -220.5228) (xy 49.259998 -220.5228) (xy 49.249876 -220.522276) (xy 49.231163 -220.514555)
			(xy 49.216808 -220.500281) (xy 49.208982 -220.481611) (xy 49.208436 -220.471492) (xy 43.1673 -220.471492)
			(xy 43.166872 -220.481646) (xy 43.159079 -220.500398) (xy 43.144684 -220.514721) (xy 43.125894 -220.522421)
			(xy 43.115738 -220.5228) (xy 41.716198 -220.5228) (xy 41.706076 -220.522276) (xy 41.687363 -220.514555)
			(xy 41.673008 -220.500281) (xy 41.665182 -220.481611) (xy 41.664636 -220.471492) (xy 35.6235 -220.471492)
			(xy 35.623072 -220.481646) (xy 35.615279 -220.500398) (xy 35.600884 -220.514721) (xy 35.582094 -220.522421)
			(xy 35.571938 -220.5228) (xy 34.172398 -220.5228) (xy 34.162276 -220.522276) (xy 34.143563 -220.514555)
			(xy 34.129208 -220.500281) (xy 34.121382 -220.481611) (xy 34.120836 -220.471492) (xy 28.0797 -220.471492)
			(xy 28.079272 -220.481646) (xy 28.071479 -220.500398) (xy 28.057084 -220.514721) (xy 28.038294 -220.522421)
			(xy 28.028138 -220.5228) (xy 26.628598 -220.5228) (xy 26.618476 -220.522276) (xy 26.599763 -220.514555)
			(xy 26.585408 -220.500281) (xy 26.577582 -220.481611) (xy 26.577036 -220.471492) (xy 20.5359 -220.471492)
			(xy 20.535472 -220.481646) (xy 20.527679 -220.500398) (xy 20.513284 -220.514721) (xy 20.494494 -220.522421)
			(xy 20.484338 -220.5228) (xy 19.084798 -220.5228) (xy 19.074676 -220.522276) (xy 19.055963 -220.514555)
			(xy 19.041608 -220.500281) (xy 19.033782 -220.481611) (xy 19.033236 -220.471492) (xy 12.9921 -220.471492)
			(xy 12.991672 -220.481646) (xy 12.983879 -220.500398) (xy 12.969484 -220.514721) (xy 12.950694 -220.522421)
			(xy 12.940538 -220.5228) (xy 11.540998 -220.5228) (xy 11.530876 -220.522276) (xy 11.512163 -220.514555)
			(xy 11.497808 -220.500281) (xy 11.489982 -220.481611) (xy 11.489436 -220.471492) (xy 2.509012 -220.471492)
			(xy 2.509012 -221.321376) (xy 7.389368 -221.321376) (xy 7.389368 -220.912436) (xy 7.389851 -220.902288)
			(xy 7.397628 -220.883543) (xy 7.412006 -220.869219) (xy 7.430781 -220.861513) (xy 7.44093 -220.861128)
			(xy 8.84047 -220.861128) (xy 8.850593 -220.861651) (xy 8.869312 -220.869366) (xy 8.883669 -220.883642)
			(xy 8.891491 -220.902316) (xy 8.892032 -220.912436) (xy 8.892032 -221.321376) (xy 14.933168 -221.321376)
			(xy 14.933168 -220.912436) (xy 14.933651 -220.902288) (xy 14.941428 -220.883543) (xy 14.955806 -220.869219)
			(xy 14.974581 -220.861513) (xy 14.98473 -220.861128) (xy 16.38427 -220.861128) (xy 16.394393 -220.861651)
			(xy 16.413112 -220.869366) (xy 16.427469 -220.883642) (xy 16.435291 -220.902316) (xy 16.435832 -220.912436)
			(xy 16.435832 -221.321376) (xy 22.476968 -221.321376) (xy 22.476968 -220.912436) (xy 22.477451 -220.902288)
			(xy 22.485228 -220.883543) (xy 22.499606 -220.869219) (xy 22.518381 -220.861513) (xy 22.52853 -220.861128)
			(xy 23.92807 -220.861128) (xy 23.938193 -220.861651) (xy 23.956912 -220.869366) (xy 23.971269 -220.883642)
			(xy 23.979091 -220.902316) (xy 23.979632 -220.912436) (xy 23.979632 -221.321376) (xy 30.020768 -221.321376)
			(xy 30.020768 -220.912436) (xy 30.021251 -220.902288) (xy 30.029028 -220.883543) (xy 30.043406 -220.869219)
			(xy 30.062181 -220.861513) (xy 30.07233 -220.861128) (xy 31.47187 -220.861128) (xy 31.481993 -220.861651)
			(xy 31.500712 -220.869366) (xy 31.515069 -220.883642) (xy 31.522891 -220.902316) (xy 31.523432 -220.912436)
			(xy 31.523432 -221.321376) (xy 37.564568 -221.321376) (xy 37.564568 -220.912436) (xy 37.565051 -220.902288)
			(xy 37.572828 -220.883543) (xy 37.587206 -220.869219) (xy 37.605981 -220.861513) (xy 37.61613 -220.861128)
			(xy 39.01567 -220.861128) (xy 39.025793 -220.861651) (xy 39.044512 -220.869366) (xy 39.058869 -220.883642)
			(xy 39.066691 -220.902316) (xy 39.067232 -220.912436) (xy 39.067232 -221.321376) (xy 45.108368 -221.321376)
			(xy 45.108368 -220.912436) (xy 45.108851 -220.902288) (xy 45.116628 -220.883543) (xy 45.131006 -220.869219)
			(xy 45.149781 -220.861513) (xy 45.15993 -220.861128) (xy 46.55947 -220.861128) (xy 46.569593 -220.861651)
			(xy 46.588312 -220.869366) (xy 46.602669 -220.883642) (xy 46.610491 -220.902316) (xy 46.611032 -220.912436)
			(xy 46.611032 -221.321376) (xy 52.652168 -221.321376) (xy 52.652168 -220.912436) (xy 52.652651 -220.902288)
			(xy 52.660428 -220.883543) (xy 52.674806 -220.869219) (xy 52.693581 -220.861513) (xy 52.70373 -220.861128)
			(xy 54.10327 -220.861128) (xy 54.113393 -220.861651) (xy 54.132112 -220.869366) (xy 54.146469 -220.883642)
			(xy 54.154291 -220.902316) (xy 54.154832 -220.912436) (xy 54.154832 -221.321376) (xy 60.195968 -221.321376)
			(xy 60.195968 -220.912436) (xy 60.196451 -220.902288) (xy 60.204228 -220.883543) (xy 60.218606 -220.869219)
			(xy 60.237381 -220.861513) (xy 60.24753 -220.861128) (xy 61.64707 -220.861128) (xy 61.657193 -220.861651)
			(xy 61.675912 -220.869366) (xy 61.690269 -220.883642) (xy 61.698091 -220.902316) (xy 61.698632 -220.912436)
			(xy 61.698632 -221.133924) (xy 88.755728 -221.133924) (xy 88.756236 -221.108037) (xy 88.764335 -221.056899)
			(xy 88.780334 -221.007659) (xy 88.80384 -220.961527) (xy 88.834272 -220.91964) (xy 88.870882 -220.88303)
			(xy 88.912769 -220.852598) (xy 88.958901 -220.829092) (xy 89.008141 -220.813093) (xy 89.059279 -220.804994)
			(xy 89.111053 -220.804994) (xy 89.162191 -220.813093) (xy 89.211431 -220.829092) (xy 89.257563 -220.852598)
			(xy 89.29945 -220.88303) (xy 89.33606 -220.91964) (xy 89.366492 -220.961527) (xy 89.389998 -221.007659)
			(xy 89.405997 -221.056899) (xy 89.414096 -221.108037) (xy 89.414604 -221.133924) (xy 89.695528 -221.133924)
			(xy 89.69601 -221.108589) (xy 89.70376 -221.058515) (xy 89.71908 -221.010217) (xy 89.741611 -220.964832)
			(xy 89.770821 -220.923429) (xy 89.806022 -220.886984) (xy 89.846386 -220.856354) (xy 89.890961 -220.83226)
			(xy 89.938698 -220.815272) (xy 89.963498 -220.810074) (xy 89.986358 -220.805756) (xy 90.191336 -220.450664)
			(xy 90.183462 -220.42882) (xy 90.174829 -220.402408) (xy 90.1655 -220.347635) (xy 90.16492 -220.319854)
			(xy 90.165428 -220.293947) (xy 90.173534 -220.24277) (xy 90.189546 -220.193491) (xy 90.213069 -220.147324)
			(xy 90.243525 -220.105405) (xy 90.280163 -220.068767) (xy 90.322082 -220.038311) (xy 90.368249 -220.014788)
			(xy 90.417528 -219.998776) (xy 90.468705 -219.99067) (xy 90.520519 -219.99067) (xy 90.571696 -219.998776)
			(xy 90.620975 -220.014788) (xy 90.667142 -220.038311) (xy 90.709061 -220.068767) (xy 90.745699 -220.105405)
			(xy 90.776155 -220.147324) (xy 90.799678 -220.193491) (xy 90.81569 -220.24277) (xy 90.823796 -220.293947)
			(xy 90.824304 -220.319854) (xy 90.823828 -220.345199) (xy 90.816049 -220.395289) (xy 90.800697 -220.443599)
			(xy 90.778134 -220.48899) (xy 90.748891 -220.530396) (xy 90.713657 -220.566839) (xy 90.673262 -220.597461)
			(xy 90.628657 -220.621543) (xy 90.580893 -220.638516) (xy 90.55608 -220.643704) (xy 90.53322 -220.648022)
			(xy 90.328242 -221.003114) (xy 90.336116 -221.024958) (xy 90.34471 -221.051373) (xy 90.353897 -221.106151)
			(xy 90.354404 -221.133924) (xy 90.635328 -221.133924) (xy 90.635836 -221.108037) (xy 90.643935 -221.056899)
			(xy 90.659934 -221.007659) (xy 90.68344 -220.961527) (xy 90.713872 -220.91964) (xy 90.750482 -220.88303)
			(xy 90.792369 -220.852598) (xy 90.838501 -220.829092) (xy 90.887741 -220.813093) (xy 90.938879 -220.804994)
			(xy 90.990653 -220.804994) (xy 91.041791 -220.813093) (xy 91.091031 -220.829092) (xy 91.137163 -220.852598)
			(xy 91.17905 -220.88303) (xy 91.21566 -220.91964) (xy 91.246092 -220.961527) (xy 91.269598 -221.007659)
			(xy 91.285597 -221.056899) (xy 91.293696 -221.108037) (xy 91.294204 -221.133924) (xy 91.575128 -221.133924)
			(xy 91.57561 -221.108589) (xy 91.58336 -221.058515) (xy 91.59868 -221.010217) (xy 91.621211 -220.964832)
			(xy 91.650421 -220.923429) (xy 91.685622 -220.886984) (xy 91.725986 -220.856354) (xy 91.770561 -220.83226)
			(xy 91.818298 -220.815272) (xy 91.843098 -220.810074) (xy 91.865958 -220.805756) (xy 92.070936 -220.450664)
			(xy 92.063062 -220.42882) (xy 92.054429 -220.402408) (xy 92.0451 -220.347635) (xy 92.04452 -220.319854)
			(xy 92.045028 -220.293947) (xy 92.053134 -220.24277) (xy 92.069146 -220.193491) (xy 92.092669 -220.147324)
			(xy 92.123125 -220.105405) (xy 92.159763 -220.068767) (xy 92.201682 -220.038311) (xy 92.247849 -220.014788)
			(xy 92.297128 -219.998776) (xy 92.348305 -219.99067) (xy 92.400119 -219.99067) (xy 92.451296 -219.998776)
			(xy 92.500575 -220.014788) (xy 92.546742 -220.038311) (xy 92.588661 -220.068767) (xy 92.625299 -220.105405)
			(xy 92.655755 -220.147324) (xy 92.679278 -220.193491) (xy 92.69529 -220.24277) (xy 92.703396 -220.293947)
			(xy 92.703904 -220.319854) (xy 92.703428 -220.345199) (xy 92.695649 -220.395289) (xy 92.680297 -220.443599)
			(xy 92.657734 -220.48899) (xy 92.628491 -220.530396) (xy 92.593257 -220.566839) (xy 92.552862 -220.597461)
			(xy 92.508257 -220.621543) (xy 92.460493 -220.638516) (xy 92.43568 -220.643704) (xy 92.41282 -220.648022)
			(xy 92.207842 -221.003114) (xy 92.215716 -221.024958) (xy 92.22431 -221.051373) (xy 92.233497 -221.106151)
			(xy 92.234004 -221.133924) (xy 92.514928 -221.133924) (xy 92.515436 -221.108037) (xy 92.523535 -221.056899)
			(xy 92.539534 -221.007659) (xy 92.56304 -220.961527) (xy 92.593472 -220.91964) (xy 92.630082 -220.88303)
			(xy 92.671969 -220.852598) (xy 92.718101 -220.829092) (xy 92.767341 -220.813093) (xy 92.818479 -220.804994)
			(xy 92.870253 -220.804994) (xy 92.921391 -220.813093) (xy 92.970631 -220.829092) (xy 93.016763 -220.852598)
			(xy 93.05865 -220.88303) (xy 93.09526 -220.91964) (xy 93.125692 -220.961527) (xy 93.149198 -221.007659)
			(xy 93.165197 -221.056899) (xy 93.173296 -221.108037) (xy 93.173804 -221.133924) (xy 93.454728 -221.133924)
			(xy 93.45521 -221.108589) (xy 93.46296 -221.058515) (xy 93.47828 -221.010217) (xy 93.500811 -220.964832)
			(xy 93.530021 -220.923429) (xy 93.565222 -220.886984) (xy 93.605586 -220.856354) (xy 93.650161 -220.83226)
			(xy 93.697898 -220.815272) (xy 93.722698 -220.810074) (xy 93.745558 -220.805756) (xy 93.950536 -220.450664)
			(xy 93.942662 -220.42882) (xy 93.934029 -220.402408) (xy 93.9247 -220.347635) (xy 93.92412 -220.319854)
			(xy 93.924628 -220.293947) (xy 93.932734 -220.24277) (xy 93.948746 -220.193491) (xy 93.972269 -220.147324)
			(xy 94.002725 -220.105405) (xy 94.039363 -220.068767) (xy 94.081282 -220.038311) (xy 94.127449 -220.014788)
			(xy 94.176728 -219.998776) (xy 94.227905 -219.99067) (xy 94.279719 -219.99067) (xy 94.330896 -219.998776)
			(xy 94.380175 -220.014788) (xy 94.426342 -220.038311) (xy 94.468261 -220.068767) (xy 94.504899 -220.105405)
			(xy 94.535355 -220.147324) (xy 94.558878 -220.193491) (xy 94.57489 -220.24277) (xy 94.582996 -220.293947)
			(xy 94.583504 -220.319854) (xy 94.583028 -220.345199) (xy 94.575249 -220.395289) (xy 94.559897 -220.443599)
			(xy 94.537334 -220.48899) (xy 94.508091 -220.530396) (xy 94.472857 -220.566839) (xy 94.432462 -220.597461)
			(xy 94.387857 -220.621543) (xy 94.340093 -220.638516) (xy 94.31528 -220.643704) (xy 94.29242 -220.648022)
			(xy 94.087442 -221.003114) (xy 94.095316 -221.024958) (xy 94.10391 -221.051373) (xy 94.113097 -221.106151)
			(xy 94.113604 -221.133924) (xy 94.394528 -221.133924) (xy 94.395036 -221.108037) (xy 94.403135 -221.056899)
			(xy 94.419134 -221.007659) (xy 94.44264 -220.961527) (xy 94.473072 -220.91964) (xy 94.509682 -220.88303)
			(xy 94.551569 -220.852598) (xy 94.597701 -220.829092) (xy 94.646941 -220.813093) (xy 94.698079 -220.804994)
			(xy 94.749853 -220.804994) (xy 94.800991 -220.813093) (xy 94.850231 -220.829092) (xy 94.896363 -220.852598)
			(xy 94.93825 -220.88303) (xy 94.97486 -220.91964) (xy 95.005292 -220.961527) (xy 95.028798 -221.007659)
			(xy 95.044797 -221.056899) (xy 95.052896 -221.108037) (xy 95.053404 -221.133924) (xy 95.334328 -221.133924)
			(xy 95.33481 -221.108589) (xy 95.34256 -221.058515) (xy 95.35788 -221.010217) (xy 95.380411 -220.964832)
			(xy 95.409621 -220.923429) (xy 95.444822 -220.886984) (xy 95.485186 -220.856354) (xy 95.529761 -220.83226)
			(xy 95.577498 -220.815272) (xy 95.602298 -220.810074) (xy 95.625158 -220.805756) (xy 95.830136 -220.450664)
			(xy 95.822262 -220.42882) (xy 95.813629 -220.402408) (xy 95.8043 -220.347635) (xy 95.80372 -220.319854)
			(xy 95.804228 -220.293947) (xy 95.812334 -220.24277) (xy 95.828346 -220.193491) (xy 95.851869 -220.147324)
			(xy 95.882325 -220.105405) (xy 95.918963 -220.068767) (xy 95.960882 -220.038311) (xy 96.007049 -220.014788)
			(xy 96.056328 -219.998776) (xy 96.107505 -219.99067) (xy 96.159319 -219.99067) (xy 96.210496 -219.998776)
			(xy 96.259775 -220.014788) (xy 96.305942 -220.038311) (xy 96.347861 -220.068767) (xy 96.384499 -220.105405)
			(xy 96.414955 -220.147324) (xy 96.438478 -220.193491) (xy 96.45449 -220.24277) (xy 96.462596 -220.293947)
			(xy 96.463104 -220.319854) (xy 96.462628 -220.345199) (xy 96.454849 -220.395289) (xy 96.439497 -220.443599)
			(xy 96.416934 -220.48899) (xy 96.387691 -220.530396) (xy 96.352457 -220.566839) (xy 96.312062 -220.597461)
			(xy 96.267457 -220.621543) (xy 96.219693 -220.638516) (xy 96.19488 -220.643704) (xy 96.17202 -220.648022)
			(xy 95.967042 -221.003114) (xy 95.974916 -221.024958) (xy 95.98351 -221.051373) (xy 95.992697 -221.106151)
			(xy 95.993204 -221.133924) (xy 96.274128 -221.133924) (xy 96.274636 -221.108037) (xy 96.282735 -221.056899)
			(xy 96.298734 -221.007659) (xy 96.32224 -220.961527) (xy 96.352672 -220.91964) (xy 96.389282 -220.88303)
			(xy 96.431169 -220.852598) (xy 96.477301 -220.829092) (xy 96.526541 -220.813093) (xy 96.577679 -220.804994)
			(xy 96.629453 -220.804994) (xy 96.680591 -220.813093) (xy 96.729831 -220.829092) (xy 96.775963 -220.852598)
			(xy 96.81785 -220.88303) (xy 96.85446 -220.91964) (xy 96.884892 -220.961527) (xy 96.908398 -221.007659)
			(xy 96.924397 -221.056899) (xy 96.932496 -221.108037) (xy 96.933004 -221.133924) (xy 97.213928 -221.133924)
			(xy 97.21441 -221.108589) (xy 97.22216 -221.058515) (xy 97.23748 -221.010217) (xy 97.260011 -220.964832)
			(xy 97.289221 -220.923429) (xy 97.324422 -220.886984) (xy 97.364786 -220.856354) (xy 97.409361 -220.83226)
			(xy 97.457098 -220.815272) (xy 97.481898 -220.810074) (xy 97.504758 -220.805756) (xy 97.709736 -220.450664)
			(xy 97.701862 -220.42882) (xy 97.693229 -220.402408) (xy 97.6839 -220.347635) (xy 97.68332 -220.319854)
			(xy 97.683828 -220.293947) (xy 97.691934 -220.24277) (xy 97.707946 -220.193491) (xy 97.731469 -220.147324)
			(xy 97.761925 -220.105405) (xy 97.798563 -220.068767) (xy 97.840482 -220.038311) (xy 97.886649 -220.014788)
			(xy 97.935928 -219.998776) (xy 97.987105 -219.99067) (xy 98.038919 -219.99067) (xy 98.090096 -219.998776)
			(xy 98.139375 -220.014788) (xy 98.185542 -220.038311) (xy 98.227461 -220.068767) (xy 98.264099 -220.105405)
			(xy 98.294555 -220.147324) (xy 98.318078 -220.193491) (xy 98.33409 -220.24277) (xy 98.342196 -220.293947)
			(xy 98.342704 -220.319854) (xy 98.342228 -220.345199) (xy 98.334449 -220.395289) (xy 98.319097 -220.443599)
			(xy 98.296534 -220.48899) (xy 98.267291 -220.530396) (xy 98.232057 -220.566839) (xy 98.191662 -220.597461)
			(xy 98.147057 -220.621543) (xy 98.099293 -220.638516) (xy 98.07448 -220.643704) (xy 98.05162 -220.648022)
			(xy 97.846642 -221.003114) (xy 97.854516 -221.024958) (xy 97.86311 -221.051373) (xy 97.872297 -221.106151)
			(xy 97.872804 -221.133924) (xy 98.153728 -221.133924) (xy 98.154236 -221.108037) (xy 98.162335 -221.056899)
			(xy 98.178334 -221.007659) (xy 98.20184 -220.961527) (xy 98.232272 -220.91964) (xy 98.268882 -220.88303)
			(xy 98.310769 -220.852598) (xy 98.356901 -220.829092) (xy 98.406141 -220.813093) (xy 98.457279 -220.804994)
			(xy 98.509053 -220.804994) (xy 98.560191 -220.813093) (xy 98.609431 -220.829092) (xy 98.655563 -220.852598)
			(xy 98.69745 -220.88303) (xy 98.73406 -220.91964) (xy 98.764492 -220.961527) (xy 98.787998 -221.007659)
			(xy 98.803997 -221.056899) (xy 98.812096 -221.108037) (xy 98.812604 -221.133924) (xy 99.093528 -221.133924)
			(xy 99.09401 -221.108589) (xy 99.10176 -221.058515) (xy 99.11708 -221.010217) (xy 99.139611 -220.964832)
			(xy 99.168821 -220.923429) (xy 99.204022 -220.886984) (xy 99.244386 -220.856354) (xy 99.288961 -220.83226)
			(xy 99.336698 -220.815272) (xy 99.361498 -220.810074) (xy 99.384358 -220.805756) (xy 99.589336 -220.450664)
			(xy 99.581462 -220.42882) (xy 99.572829 -220.402408) (xy 99.5635 -220.347635) (xy 99.56292 -220.319854)
			(xy 99.563428 -220.293947) (xy 99.571534 -220.24277) (xy 99.587546 -220.193491) (xy 99.611069 -220.147324)
			(xy 99.641525 -220.105405) (xy 99.678163 -220.068767) (xy 99.720082 -220.038311) (xy 99.766249 -220.014788)
			(xy 99.815528 -219.998776) (xy 99.866705 -219.99067) (xy 99.918519 -219.99067) (xy 99.969696 -219.998776)
			(xy 100.018975 -220.014788) (xy 100.065142 -220.038311) (xy 100.107061 -220.068767) (xy 100.143699 -220.105405)
			(xy 100.174155 -220.147324) (xy 100.197678 -220.193491) (xy 100.21369 -220.24277) (xy 100.221796 -220.293947)
			(xy 100.222304 -220.319854) (xy 100.221828 -220.345199) (xy 100.214049 -220.395289) (xy 100.198697 -220.443599)
			(xy 100.176134 -220.48899) (xy 100.146891 -220.530396) (xy 100.111657 -220.566839) (xy 100.071262 -220.597461)
			(xy 100.026657 -220.621543) (xy 99.978893 -220.638516) (xy 99.95408 -220.643704) (xy 99.93122 -220.648022)
			(xy 99.726242 -221.003114) (xy 99.734116 -221.024958) (xy 99.74271 -221.051373) (xy 99.751897 -221.106151)
			(xy 99.752404 -221.133924) (xy 100.033328 -221.133924) (xy 100.033836 -221.108037) (xy 100.041935 -221.056899)
			(xy 100.057934 -221.007659) (xy 100.08144 -220.961527) (xy 100.111872 -220.91964) (xy 100.148482 -220.88303)
			(xy 100.190369 -220.852598) (xy 100.236501 -220.829092) (xy 100.285741 -220.813093) (xy 100.336879 -220.804994)
			(xy 100.388653 -220.804994) (xy 100.439791 -220.813093) (xy 100.489031 -220.829092) (xy 100.535163 -220.852598)
			(xy 100.57705 -220.88303) (xy 100.61366 -220.91964) (xy 100.644092 -220.961527) (xy 100.667598 -221.007659)
			(xy 100.683597 -221.056899) (xy 100.691696 -221.108037) (xy 100.692204 -221.133924) (xy 100.973128 -221.133924)
			(xy 100.97361 -221.108589) (xy 100.98136 -221.058515) (xy 100.99668 -221.010217) (xy 101.019211 -220.964832)
			(xy 101.048421 -220.923429) (xy 101.083622 -220.886984) (xy 101.123986 -220.856354) (xy 101.168561 -220.83226)
			(xy 101.216298 -220.815272) (xy 101.241098 -220.810074) (xy 101.263958 -220.805756) (xy 101.468936 -220.450664)
			(xy 101.461062 -220.42882) (xy 101.452429 -220.402408) (xy 101.4431 -220.347635) (xy 101.44252 -220.319854)
			(xy 101.443028 -220.293947) (xy 101.451134 -220.24277) (xy 101.467146 -220.193491) (xy 101.490669 -220.147324)
			(xy 101.521125 -220.105405) (xy 101.557763 -220.068767) (xy 101.599682 -220.038311) (xy 101.645849 -220.014788)
			(xy 101.695128 -219.998776) (xy 101.746305 -219.99067) (xy 101.798119 -219.99067) (xy 101.849296 -219.998776)
			(xy 101.898575 -220.014788) (xy 101.944742 -220.038311) (xy 101.986661 -220.068767) (xy 102.023299 -220.105405)
			(xy 102.053755 -220.147324) (xy 102.077278 -220.193491) (xy 102.09329 -220.24277) (xy 102.101396 -220.293947)
			(xy 102.101904 -220.319854) (xy 102.101428 -220.345199) (xy 102.093649 -220.395289) (xy 102.078297 -220.443599)
			(xy 102.055734 -220.48899) (xy 102.026491 -220.530396) (xy 101.991257 -220.566839) (xy 101.950862 -220.597461)
			(xy 101.906257 -220.621543) (xy 101.858493 -220.638516) (xy 101.83368 -220.643704) (xy 101.81082 -220.648022)
			(xy 101.605842 -221.003114) (xy 101.613716 -221.024958) (xy 101.62231 -221.051373) (xy 101.631497 -221.106151)
			(xy 101.632004 -221.133924) (xy 101.912928 -221.133924) (xy 101.913436 -221.108037) (xy 101.921535 -221.056899)
			(xy 101.937534 -221.007659) (xy 101.96104 -220.961527) (xy 101.991472 -220.91964) (xy 102.028082 -220.88303)
			(xy 102.069969 -220.852598) (xy 102.116101 -220.829092) (xy 102.165341 -220.813093) (xy 102.216479 -220.804994)
			(xy 102.268253 -220.804994) (xy 102.319391 -220.813093) (xy 102.368631 -220.829092) (xy 102.414763 -220.852598)
			(xy 102.45665 -220.88303) (xy 102.49326 -220.91964) (xy 102.523692 -220.961527) (xy 102.547198 -221.007659)
			(xy 102.563197 -221.056899) (xy 102.571296 -221.108037) (xy 102.571804 -221.133924) (xy 102.852728 -221.133924)
			(xy 102.85321 -221.108589) (xy 102.86096 -221.058515) (xy 102.87628 -221.010217) (xy 102.898811 -220.964832)
			(xy 102.928021 -220.923429) (xy 102.963222 -220.886984) (xy 103.003586 -220.856354) (xy 103.048161 -220.83226)
			(xy 103.095898 -220.815272) (xy 103.120698 -220.810074) (xy 103.143558 -220.805756) (xy 103.348536 -220.450664)
			(xy 103.340662 -220.42882) (xy 103.332029 -220.402408) (xy 103.3227 -220.347635) (xy 103.32212 -220.319854)
			(xy 103.322628 -220.293947) (xy 103.330734 -220.24277) (xy 103.346746 -220.193491) (xy 103.370269 -220.147324)
			(xy 103.400725 -220.105405) (xy 103.437363 -220.068767) (xy 103.479282 -220.038311) (xy 103.525449 -220.014788)
			(xy 103.574728 -219.998776) (xy 103.625905 -219.99067) (xy 103.677719 -219.99067) (xy 103.728896 -219.998776)
			(xy 103.778175 -220.014788) (xy 103.824342 -220.038311) (xy 103.866261 -220.068767) (xy 103.902899 -220.105405)
			(xy 103.933355 -220.147324) (xy 103.956878 -220.193491) (xy 103.97289 -220.24277) (xy 103.980996 -220.293947)
			(xy 103.981504 -220.319854) (xy 105.20172 -220.319854) (xy 105.202228 -220.293947) (xy 105.210334 -220.24277)
			(xy 105.226346 -220.193491) (xy 105.249869 -220.147324) (xy 105.280325 -220.105405) (xy 105.316963 -220.068767)
			(xy 105.358882 -220.038311) (xy 105.405049 -220.014788) (xy 105.454328 -219.998776) (xy 105.505505 -219.99067)
			(xy 105.557319 -219.99067) (xy 105.608496 -219.998776) (xy 105.657775 -220.014788) (xy 105.703942 -220.038311)
			(xy 105.745861 -220.068767) (xy 105.782499 -220.105405) (xy 105.812955 -220.147324) (xy 105.836478 -220.193491)
			(xy 105.85249 -220.24277) (xy 105.860596 -220.293947) (xy 105.861104 -220.319854) (xy 107.08132 -220.319854)
			(xy 107.081828 -220.293947) (xy 107.089934 -220.24277) (xy 107.105946 -220.193491) (xy 107.129469 -220.147324)
			(xy 107.159925 -220.105405) (xy 107.196563 -220.068767) (xy 107.238482 -220.038311) (xy 107.284649 -220.014788)
			(xy 107.333928 -219.998776) (xy 107.385105 -219.99067) (xy 107.436919 -219.99067) (xy 107.488096 -219.998776)
			(xy 107.537375 -220.014788) (xy 107.583542 -220.038311) (xy 107.625461 -220.068767) (xy 107.662099 -220.105405)
			(xy 107.692555 -220.147324) (xy 107.716078 -220.193491) (xy 107.73209 -220.24277) (xy 107.740196 -220.293947)
			(xy 107.740704 -220.319854) (xy 108.96092 -220.319854) (xy 108.961428 -220.293947) (xy 108.969534 -220.24277)
			(xy 108.985546 -220.193491) (xy 109.009069 -220.147324) (xy 109.039525 -220.105405) (xy 109.076163 -220.068767)
			(xy 109.118082 -220.038311) (xy 109.164249 -220.014788) (xy 109.213528 -219.998776) (xy 109.264705 -219.99067)
			(xy 109.316519 -219.99067) (xy 109.367696 -219.998776) (xy 109.416975 -220.014788) (xy 109.463142 -220.038311)
			(xy 109.505061 -220.068767) (xy 109.541699 -220.105405) (xy 109.572155 -220.147324) (xy 109.595678 -220.193491)
			(xy 109.61169 -220.24277) (xy 109.619796 -220.293947) (xy 109.620304 -220.319854) (xy 110.84052 -220.319854)
			(xy 110.841028 -220.293947) (xy 110.849134 -220.24277) (xy 110.865146 -220.193491) (xy 110.888669 -220.147324)
			(xy 110.919125 -220.105405) (xy 110.955763 -220.068767) (xy 110.997682 -220.038311) (xy 111.043849 -220.014788)
			(xy 111.093128 -219.998776) (xy 111.144305 -219.99067) (xy 111.196119 -219.99067) (xy 111.247296 -219.998776)
			(xy 111.296575 -220.014788) (xy 111.342742 -220.038311) (xy 111.384661 -220.068767) (xy 111.421299 -220.105405)
			(xy 111.451755 -220.147324) (xy 111.475278 -220.193491) (xy 111.49129 -220.24277) (xy 111.499396 -220.293947)
			(xy 111.499904 -220.319854) (xy 112.72012 -220.319854) (xy 112.720628 -220.293947) (xy 112.728734 -220.24277)
			(xy 112.744746 -220.193491) (xy 112.768269 -220.147324) (xy 112.798725 -220.105405) (xy 112.835363 -220.068767)
			(xy 112.877282 -220.038311) (xy 112.923449 -220.014788) (xy 112.972728 -219.998776) (xy 113.023905 -219.99067)
			(xy 113.075719 -219.99067) (xy 113.126896 -219.998776) (xy 113.176175 -220.014788) (xy 113.222342 -220.038311)
			(xy 113.264261 -220.068767) (xy 113.300899 -220.105405) (xy 113.331355 -220.147324) (xy 113.354878 -220.193491)
			(xy 113.37089 -220.24277) (xy 113.378996 -220.293947) (xy 113.379504 -220.319854) (xy 114.59972 -220.319854)
			(xy 114.600228 -220.293947) (xy 114.608334 -220.24277) (xy 114.624346 -220.193491) (xy 114.647869 -220.147324)
			(xy 114.678325 -220.105405) (xy 114.714963 -220.068767) (xy 114.756882 -220.038311) (xy 114.803049 -220.014788)
			(xy 114.852328 -219.998776) (xy 114.903505 -219.99067) (xy 114.955319 -219.99067) (xy 115.006496 -219.998776)
			(xy 115.055775 -220.014788) (xy 115.101942 -220.038311) (xy 115.143861 -220.068767) (xy 115.180499 -220.105405)
			(xy 115.210955 -220.147324) (xy 115.234478 -220.193491) (xy 115.25049 -220.24277) (xy 115.258596 -220.293947)
			(xy 115.259104 -220.319854) (xy 116.47932 -220.319854) (xy 116.479828 -220.293947) (xy 116.487934 -220.24277)
			(xy 116.503946 -220.193491) (xy 116.527469 -220.147324) (xy 116.557925 -220.105405) (xy 116.594563 -220.068767)
			(xy 116.636482 -220.038311) (xy 116.682649 -220.014788) (xy 116.731928 -219.998776) (xy 116.783105 -219.99067)
			(xy 116.834919 -219.99067) (xy 116.886096 -219.998776) (xy 116.935375 -220.014788) (xy 116.981542 -220.038311)
			(xy 117.023461 -220.068767) (xy 117.060099 -220.105405) (xy 117.090555 -220.147324) (xy 117.114078 -220.193491)
			(xy 117.13009 -220.24277) (xy 117.138196 -220.293947) (xy 117.138704 -220.319854) (xy 118.35892 -220.319854)
			(xy 118.359428 -220.293947) (xy 118.367534 -220.24277) (xy 118.383546 -220.193491) (xy 118.407069 -220.147324)
			(xy 118.437525 -220.105405) (xy 118.474163 -220.068767) (xy 118.516082 -220.038311) (xy 118.562249 -220.014788)
			(xy 118.611528 -219.998776) (xy 118.662705 -219.99067) (xy 118.714519 -219.99067) (xy 118.765696 -219.998776)
			(xy 118.814975 -220.014788) (xy 118.861142 -220.038311) (xy 118.903061 -220.068767) (xy 118.939699 -220.105405)
			(xy 118.970155 -220.147324) (xy 118.993678 -220.193491) (xy 119.00969 -220.24277) (xy 119.017796 -220.293947)
			(xy 119.018304 -220.319854) (xy 120.23852 -220.319854) (xy 120.239028 -220.293947) (xy 120.247134 -220.24277)
			(xy 120.263146 -220.193491) (xy 120.286669 -220.147324) (xy 120.317125 -220.105405) (xy 120.353763 -220.068767)
			(xy 120.395682 -220.038311) (xy 120.441849 -220.014788) (xy 120.491128 -219.998776) (xy 120.542305 -219.99067)
			(xy 120.594119 -219.99067) (xy 120.645296 -219.998776) (xy 120.694575 -220.014788) (xy 120.740742 -220.038311)
			(xy 120.782661 -220.068767) (xy 120.819299 -220.105405) (xy 120.849755 -220.147324) (xy 120.873278 -220.193491)
			(xy 120.88929 -220.24277) (xy 120.897396 -220.293947) (xy 120.897904 -220.319854) (xy 122.11812 -220.319854)
			(xy 122.118628 -220.293947) (xy 122.126734 -220.24277) (xy 122.142746 -220.193491) (xy 122.166269 -220.147324)
			(xy 122.196725 -220.105405) (xy 122.233363 -220.068767) (xy 122.275282 -220.038311) (xy 122.321449 -220.014788)
			(xy 122.370728 -219.998776) (xy 122.421905 -219.99067) (xy 122.473719 -219.99067) (xy 122.524896 -219.998776)
			(xy 122.574175 -220.014788) (xy 122.620342 -220.038311) (xy 122.662261 -220.068767) (xy 122.698899 -220.105405)
			(xy 122.729355 -220.147324) (xy 122.752878 -220.193491) (xy 122.76889 -220.24277) (xy 122.776996 -220.293947)
			(xy 122.777504 -220.319854) (xy 123.99772 -220.319854) (xy 123.998228 -220.293947) (xy 124.006334 -220.24277)
			(xy 124.022346 -220.193491) (xy 124.045869 -220.147324) (xy 124.076325 -220.105405) (xy 124.112963 -220.068767)
			(xy 124.154882 -220.038311) (xy 124.201049 -220.014788) (xy 124.250328 -219.998776) (xy 124.301505 -219.99067)
			(xy 124.353319 -219.99067) (xy 124.404496 -219.998776) (xy 124.453775 -220.014788) (xy 124.499942 -220.038311)
			(xy 124.541861 -220.068767) (xy 124.578499 -220.105405) (xy 124.608955 -220.147324) (xy 124.632478 -220.193491)
			(xy 124.64849 -220.24277) (xy 124.656596 -220.293947) (xy 124.657104 -220.319854) (xy 125.87732 -220.319854)
			(xy 125.877828 -220.293947) (xy 125.885934 -220.24277) (xy 125.901946 -220.193491) (xy 125.925469 -220.147324)
			(xy 125.955925 -220.105405) (xy 125.992563 -220.068767) (xy 126.034482 -220.038311) (xy 126.080649 -220.014788)
			(xy 126.129928 -219.998776) (xy 126.181105 -219.99067) (xy 126.232919 -219.99067) (xy 126.284096 -219.998776)
			(xy 126.333375 -220.014788) (xy 126.379542 -220.038311) (xy 126.421461 -220.068767) (xy 126.458099 -220.105405)
			(xy 126.488555 -220.147324) (xy 126.512078 -220.193491) (xy 126.52809 -220.24277) (xy 126.536196 -220.293947)
			(xy 126.536704 -220.319854) (xy 127.75692 -220.319854) (xy 127.757428 -220.293947) (xy 127.765534 -220.24277)
			(xy 127.781546 -220.193491) (xy 127.805069 -220.147324) (xy 127.835525 -220.105405) (xy 127.872163 -220.068767)
			(xy 127.914082 -220.038311) (xy 127.960249 -220.014788) (xy 128.009528 -219.998776) (xy 128.060705 -219.99067)
			(xy 128.112519 -219.99067) (xy 128.163696 -219.998776) (xy 128.212975 -220.014788) (xy 128.259142 -220.038311)
			(xy 128.301061 -220.068767) (xy 128.337699 -220.105405) (xy 128.368155 -220.147324) (xy 128.391678 -220.193491)
			(xy 128.40769 -220.24277) (xy 128.415796 -220.293947) (xy 128.416304 -220.319854) (xy 129.63652 -220.319854)
			(xy 129.637028 -220.293947) (xy 129.645134 -220.24277) (xy 129.661146 -220.193491) (xy 129.684669 -220.147324)
			(xy 129.715125 -220.105405) (xy 129.751763 -220.068767) (xy 129.793682 -220.038311) (xy 129.839849 -220.014788)
			(xy 129.889128 -219.998776) (xy 129.940305 -219.99067) (xy 129.992119 -219.99067) (xy 130.043296 -219.998776)
			(xy 130.092575 -220.014788) (xy 130.138742 -220.038311) (xy 130.180661 -220.068767) (xy 130.217299 -220.105405)
			(xy 130.247755 -220.147324) (xy 130.271278 -220.193491) (xy 130.28729 -220.24277) (xy 130.295396 -220.293947)
			(xy 130.295904 -220.319854) (xy 131.51612 -220.319854) (xy 131.516628 -220.293947) (xy 131.524734 -220.24277)
			(xy 131.540746 -220.193491) (xy 131.564269 -220.147324) (xy 131.594725 -220.105405) (xy 131.631363 -220.068767)
			(xy 131.673282 -220.038311) (xy 131.719449 -220.014788) (xy 131.768728 -219.998776) (xy 131.819905 -219.99067)
			(xy 131.871719 -219.99067) (xy 131.922896 -219.998776) (xy 131.972175 -220.014788) (xy 132.018342 -220.038311)
			(xy 132.060261 -220.068767) (xy 132.096899 -220.105405) (xy 132.127355 -220.147324) (xy 132.150878 -220.193491)
			(xy 132.16689 -220.24277) (xy 132.174996 -220.293947) (xy 132.175504 -220.319854) (xy 133.396228 -220.319854)
			(xy 133.396736 -220.293967) (xy 133.404835 -220.242829) (xy 133.420834 -220.193589) (xy 133.44434 -220.147457)
			(xy 133.474772 -220.10557) (xy 133.511382 -220.06896) (xy 133.553269 -220.038528) (xy 133.599401 -220.015022)
			(xy 133.648641 -219.999023) (xy 133.699779 -219.990924) (xy 133.751553 -219.990924) (xy 133.802691 -219.999023)
			(xy 133.851931 -220.015022) (xy 133.898063 -220.038528) (xy 133.93995 -220.06896) (xy 133.97656 -220.10557)
			(xy 134.006992 -220.147457) (xy 134.030498 -220.193589) (xy 134.046497 -220.242829) (xy 134.054596 -220.293967)
			(xy 134.055104 -220.319854) (xy 134.054563 -220.347562) (xy 134.045375 -220.402208) (xy 134.036816 -220.428566)
			(xy 134.029196 -220.450664) (xy 134.041219 -220.471492) (xy 162.162236 -220.471492) (xy 162.162236 -220.062552)
			(xy 162.162583 -220.05239) (xy 162.170401 -220.03363) (xy 162.184821 -220.019307) (xy 162.203634 -220.011616)
			(xy 162.213798 -220.011244) (xy 163.613338 -220.011244) (xy 163.623468 -220.011696) (xy 163.64219 -220.019437)
			(xy 163.656546 -220.033733) (xy 163.664363 -220.052424) (xy 163.6649 -220.062552) (xy 163.6649 -220.471492)
			(xy 169.706036 -220.471492) (xy 169.706036 -220.062552) (xy 169.706383 -220.05239) (xy 169.714201 -220.03363)
			(xy 169.728621 -220.019307) (xy 169.747434 -220.011616) (xy 169.757598 -220.011244) (xy 171.157138 -220.011244)
			(xy 171.167268 -220.011696) (xy 171.18599 -220.019437) (xy 171.200346 -220.033733) (xy 171.208163 -220.052424)
			(xy 171.2087 -220.062552) (xy 171.2087 -220.471492) (xy 177.249836 -220.471492) (xy 177.249836 -220.062552)
			(xy 177.250183 -220.05239) (xy 177.258001 -220.03363) (xy 177.272421 -220.019307) (xy 177.291234 -220.011616)
			(xy 177.301398 -220.011244) (xy 178.700938 -220.011244) (xy 178.711068 -220.011696) (xy 178.72979 -220.019437)
			(xy 178.744146 -220.033733) (xy 178.751963 -220.052424) (xy 178.7525 -220.062552) (xy 178.7525 -220.471492)
			(xy 184.793636 -220.471492) (xy 184.793636 -220.062552) (xy 184.793983 -220.05239) (xy 184.801801 -220.03363)
			(xy 184.816221 -220.019307) (xy 184.835034 -220.011616) (xy 184.845198 -220.011244) (xy 186.244738 -220.011244)
			(xy 186.254868 -220.011696) (xy 186.27359 -220.019437) (xy 186.287946 -220.033733) (xy 186.295763 -220.052424)
			(xy 186.2963 -220.062552) (xy 186.2963 -220.471492) (xy 192.337436 -220.471492) (xy 192.337436 -220.062552)
			(xy 192.337783 -220.05239) (xy 192.345601 -220.03363) (xy 192.360021 -220.019307) (xy 192.378834 -220.011616)
			(xy 192.388998 -220.011244) (xy 193.788538 -220.011244) (xy 193.798668 -220.011696) (xy 193.81739 -220.019437)
			(xy 193.831746 -220.033733) (xy 193.839563 -220.052424) (xy 193.8401 -220.062552) (xy 193.8401 -220.471492)
			(xy 199.881236 -220.471492) (xy 199.881236 -220.062552) (xy 199.881583 -220.05239) (xy 199.889401 -220.03363)
			(xy 199.903821 -220.019307) (xy 199.922634 -220.011616) (xy 199.932798 -220.011244) (xy 201.332338 -220.011244)
			(xy 201.342468 -220.011696) (xy 201.36119 -220.019437) (xy 201.375546 -220.033733) (xy 201.383363 -220.052424)
			(xy 201.3839 -220.062552) (xy 201.3839 -220.471492) (xy 207.425036 -220.471492) (xy 207.425036 -220.062552)
			(xy 207.425383 -220.05239) (xy 207.433201 -220.03363) (xy 207.447621 -220.019307) (xy 207.466434 -220.011616)
			(xy 207.476598 -220.011244) (xy 208.876138 -220.011244) (xy 208.886268 -220.011696) (xy 208.90499 -220.019437)
			(xy 208.919346 -220.033733) (xy 208.927163 -220.052424) (xy 208.9277 -220.062552) (xy 208.9277 -220.471492)
			(xy 214.968836 -220.471492) (xy 214.968836 -220.062552) (xy 214.969183 -220.05239) (xy 214.977001 -220.03363)
			(xy 214.991421 -220.019307) (xy 215.010234 -220.011616) (xy 215.020398 -220.011244) (xy 216.419938 -220.011244)
			(xy 216.430068 -220.011696) (xy 216.44879 -220.019437) (xy 216.463146 -220.033733) (xy 216.470963 -220.052424)
			(xy 216.4715 -220.062552) (xy 216.4715 -220.471492) (xy 259.429504 -220.471492) (xy 259.429504 -220.062552)
			(xy 259.429883 -220.052394) (xy 259.437695 -220.03364) (xy 259.452104 -220.019318) (xy 259.470906 -220.011621)
			(xy 259.481066 -220.011244) (xy 260.880606 -220.011244) (xy 260.890734 -220.011722) (xy 260.909456 -220.019452)
			(xy 260.923812 -220.033741) (xy 260.93163 -220.052427) (xy 260.932168 -220.062552) (xy 260.932168 -220.471492)
			(xy 266.973304 -220.471492) (xy 266.973304 -220.062552) (xy 266.973683 -220.052394) (xy 266.981495 -220.03364)
			(xy 266.995904 -220.019318) (xy 267.014706 -220.011621) (xy 267.024866 -220.011244) (xy 268.424406 -220.011244)
			(xy 268.434534 -220.011722) (xy 268.453256 -220.019452) (xy 268.467612 -220.033741) (xy 268.47543 -220.052427)
			(xy 268.475968 -220.062552) (xy 268.475968 -220.471492) (xy 274.517104 -220.471492) (xy 274.517104 -220.062552)
			(xy 274.517483 -220.052394) (xy 274.525295 -220.03364) (xy 274.539704 -220.019318) (xy 274.558506 -220.011621)
			(xy 274.568666 -220.011244) (xy 275.968206 -220.011244) (xy 275.978334 -220.011722) (xy 275.997056 -220.019452)
			(xy 276.011412 -220.033741) (xy 276.01923 -220.052427) (xy 276.019768 -220.062552) (xy 276.019768 -220.471492)
			(xy 282.060904 -220.471492) (xy 282.060904 -220.062552) (xy 282.061283 -220.052394) (xy 282.069095 -220.03364)
			(xy 282.083504 -220.019318) (xy 282.102306 -220.011621) (xy 282.112466 -220.011244) (xy 283.512006 -220.011244)
			(xy 283.522134 -220.011722) (xy 283.540856 -220.019452) (xy 283.555212 -220.033741) (xy 283.56303 -220.052427)
			(xy 283.563568 -220.062552) (xy 283.563568 -220.471492) (xy 289.604704 -220.471492) (xy 289.604704 -220.062552)
			(xy 289.605083 -220.052394) (xy 289.612895 -220.03364) (xy 289.627304 -220.019318) (xy 289.646106 -220.011621)
			(xy 289.656266 -220.011244) (xy 291.055806 -220.011244) (xy 291.065934 -220.011722) (xy 291.084656 -220.019452)
			(xy 291.099012 -220.033741) (xy 291.10683 -220.052427) (xy 291.107368 -220.062552) (xy 291.107368 -220.471492)
			(xy 297.148504 -220.471492) (xy 297.148504 -220.062552) (xy 297.148883 -220.052394) (xy 297.156695 -220.03364)
			(xy 297.171104 -220.019318) (xy 297.189906 -220.011621) (xy 297.200066 -220.011244) (xy 298.599606 -220.011244)
			(xy 298.609734 -220.011722) (xy 298.628456 -220.019452) (xy 298.642812 -220.033741) (xy 298.65063 -220.052427)
			(xy 298.651168 -220.062552) (xy 298.651168 -220.471492) (xy 304.692304 -220.471492) (xy 304.692304 -220.062552)
			(xy 304.692683 -220.052394) (xy 304.700495 -220.03364) (xy 304.714904 -220.019318) (xy 304.733706 -220.011621)
			(xy 304.743866 -220.011244) (xy 306.143406 -220.011244) (xy 306.153534 -220.011722) (xy 306.172256 -220.019452)
			(xy 306.186612 -220.033741) (xy 306.19443 -220.052427) (xy 306.194968 -220.062552) (xy 306.194968 -220.471492)
			(xy 312.236104 -220.471492) (xy 312.236104 -220.062552) (xy 312.236483 -220.052394) (xy 312.244295 -220.03364)
			(xy 312.258704 -220.019318) (xy 312.277506 -220.011621) (xy 312.287666 -220.011244) (xy 313.687206 -220.011244)
			(xy 313.697334 -220.011722) (xy 313.716056 -220.019452) (xy 313.730412 -220.033741) (xy 313.73823 -220.052427)
			(xy 313.738768 -220.062552) (xy 313.738768 -220.471492) (xy 313.738371 -220.48165) (xy 313.730572 -220.500408)
			(xy 313.716167 -220.514733) (xy 313.697366 -220.522427) (xy 313.687206 -220.5228) (xy 312.287666 -220.5228)
			(xy 312.277542 -220.522303) (xy 312.258828 -220.514571) (xy 312.244474 -220.500289) (xy 312.236649 -220.481613)
			(xy 312.236104 -220.471492) (xy 306.194968 -220.471492) (xy 306.194571 -220.48165) (xy 306.186772 -220.500408)
			(xy 306.172367 -220.514733) (xy 306.153566 -220.522427) (xy 306.143406 -220.5228) (xy 304.743866 -220.5228)
			(xy 304.733742 -220.522303) (xy 304.715028 -220.514571) (xy 304.700674 -220.500289) (xy 304.692849 -220.481613)
			(xy 304.692304 -220.471492) (xy 298.651168 -220.471492) (xy 298.650771 -220.48165) (xy 298.642972 -220.500408)
			(xy 298.628567 -220.514733) (xy 298.609766 -220.522427) (xy 298.599606 -220.5228) (xy 297.200066 -220.5228)
			(xy 297.189942 -220.522303) (xy 297.171228 -220.514571) (xy 297.156874 -220.500289) (xy 297.149049 -220.481613)
			(xy 297.148504 -220.471492) (xy 291.107368 -220.471492) (xy 291.106971 -220.48165) (xy 291.099172 -220.500408)
			(xy 291.084767 -220.514733) (xy 291.065966 -220.522427) (xy 291.055806 -220.5228) (xy 289.656266 -220.5228)
			(xy 289.646142 -220.522303) (xy 289.627428 -220.514571) (xy 289.613074 -220.500289) (xy 289.605249 -220.481613)
			(xy 289.604704 -220.471492) (xy 283.563568 -220.471492) (xy 283.563171 -220.48165) (xy 283.555372 -220.500408)
			(xy 283.540967 -220.514733) (xy 283.522166 -220.522427) (xy 283.512006 -220.5228) (xy 282.112466 -220.5228)
			(xy 282.102342 -220.522303) (xy 282.083628 -220.514571) (xy 282.069274 -220.500289) (xy 282.061449 -220.481613)
			(xy 282.060904 -220.471492) (xy 276.019768 -220.471492) (xy 276.019371 -220.48165) (xy 276.011572 -220.500408)
			(xy 275.997167 -220.514733) (xy 275.978366 -220.522427) (xy 275.968206 -220.5228) (xy 274.568666 -220.5228)
			(xy 274.558542 -220.522303) (xy 274.539828 -220.514571) (xy 274.525474 -220.500289) (xy 274.517649 -220.481613)
			(xy 274.517104 -220.471492) (xy 268.475968 -220.471492) (xy 268.475571 -220.48165) (xy 268.467772 -220.500408)
			(xy 268.453367 -220.514733) (xy 268.434566 -220.522427) (xy 268.424406 -220.5228) (xy 267.024866 -220.5228)
			(xy 267.014742 -220.522303) (xy 266.996028 -220.514571) (xy 266.981674 -220.500289) (xy 266.973849 -220.481613)
			(xy 266.973304 -220.471492) (xy 260.932168 -220.471492) (xy 260.931771 -220.48165) (xy 260.923972 -220.500408)
			(xy 260.909567 -220.514733) (xy 260.890766 -220.522427) (xy 260.880606 -220.5228) (xy 259.481066 -220.5228)
			(xy 259.470942 -220.522303) (xy 259.452228 -220.514571) (xy 259.437874 -220.500289) (xy 259.430049 -220.481613)
			(xy 259.429504 -220.471492) (xy 216.4715 -220.471492) (xy 216.471072 -220.481646) (xy 216.463279 -220.500398)
			(xy 216.448884 -220.514721) (xy 216.430094 -220.522421) (xy 216.419938 -220.5228) (xy 215.020398 -220.5228)
			(xy 215.010276 -220.522276) (xy 214.991563 -220.514555) (xy 214.977208 -220.500281) (xy 214.969382 -220.481611)
			(xy 214.968836 -220.471492) (xy 208.9277 -220.471492) (xy 208.927272 -220.481646) (xy 208.919479 -220.500398)
			(xy 208.905084 -220.514721) (xy 208.886294 -220.522421) (xy 208.876138 -220.5228) (xy 207.476598 -220.5228)
			(xy 207.466476 -220.522276) (xy 207.447763 -220.514555) (xy 207.433408 -220.500281) (xy 207.425582 -220.481611)
			(xy 207.425036 -220.471492) (xy 201.3839 -220.471492) (xy 201.383472 -220.481646) (xy 201.375679 -220.500398)
			(xy 201.361284 -220.514721) (xy 201.342494 -220.522421) (xy 201.332338 -220.5228) (xy 199.932798 -220.5228)
			(xy 199.922676 -220.522276) (xy 199.903963 -220.514555) (xy 199.889608 -220.500281) (xy 199.881782 -220.481611)
			(xy 199.881236 -220.471492) (xy 193.8401 -220.471492) (xy 193.839672 -220.481646) (xy 193.831879 -220.500398)
			(xy 193.817484 -220.514721) (xy 193.798694 -220.522421) (xy 193.788538 -220.5228) (xy 192.388998 -220.5228)
			(xy 192.378876 -220.522276) (xy 192.360163 -220.514555) (xy 192.345808 -220.500281) (xy 192.337982 -220.481611)
			(xy 192.337436 -220.471492) (xy 186.2963 -220.471492) (xy 186.295872 -220.481646) (xy 186.288079 -220.500398)
			(xy 186.273684 -220.514721) (xy 186.254894 -220.522421) (xy 186.244738 -220.5228) (xy 184.845198 -220.5228)
			(xy 184.835076 -220.522276) (xy 184.816363 -220.514555) (xy 184.802008 -220.500281) (xy 184.794182 -220.481611)
			(xy 184.793636 -220.471492) (xy 178.7525 -220.471492) (xy 178.752072 -220.481646) (xy 178.744279 -220.500398)
			(xy 178.729884 -220.514721) (xy 178.711094 -220.522421) (xy 178.700938 -220.5228) (xy 177.301398 -220.5228)
			(xy 177.291276 -220.522276) (xy 177.272563 -220.514555) (xy 177.258208 -220.500281) (xy 177.250382 -220.481611)
			(xy 177.249836 -220.471492) (xy 171.2087 -220.471492) (xy 171.208272 -220.481646) (xy 171.200479 -220.500398)
			(xy 171.186084 -220.514721) (xy 171.167294 -220.522421) (xy 171.157138 -220.5228) (xy 169.757598 -220.5228)
			(xy 169.747476 -220.522276) (xy 169.728763 -220.514555) (xy 169.714408 -220.500281) (xy 169.706582 -220.481611)
			(xy 169.706036 -220.471492) (xy 163.6649 -220.471492) (xy 163.664472 -220.481646) (xy 163.656679 -220.500398)
			(xy 163.642284 -220.514721) (xy 163.623494 -220.522421) (xy 163.613338 -220.5228) (xy 162.213798 -220.5228)
			(xy 162.203676 -220.522276) (xy 162.184963 -220.514555) (xy 162.170608 -220.500281) (xy 162.162782 -220.481611)
			(xy 162.162236 -220.471492) (xy 134.041219 -220.471492) (xy 134.234174 -220.805756) (xy 134.257034 -220.810074)
			(xy 134.281845 -220.815229) (xy 134.329584 -220.832223) (xy 134.374162 -220.856322) (xy 134.414527 -220.886957)
			(xy 134.44973 -220.923408) (xy 134.47894 -220.964816) (xy 134.501472 -221.010206) (xy 134.516792 -221.058509)
			(xy 134.524542 -221.108587) (xy 134.525004 -221.133924) (xy 134.524496 -221.159811) (xy 134.516397 -221.210949)
			(xy 134.500398 -221.260189) (xy 134.476892 -221.306321) (xy 134.44646 -221.348208) (xy 134.40985 -221.384818)
			(xy 134.367963 -221.41525) (xy 134.321831 -221.438756) (xy 134.272591 -221.454755) (xy 134.221453 -221.462854)
			(xy 134.169679 -221.462854) (xy 134.118541 -221.454755) (xy 134.069301 -221.438756) (xy 134.023169 -221.41525)
			(xy 133.981282 -221.384818) (xy 133.944672 -221.348208) (xy 133.91424 -221.306321) (xy 133.890734 -221.260189)
			(xy 133.874735 -221.210949) (xy 133.866636 -221.159811) (xy 133.866128 -221.133924) (xy 133.866667 -221.106216)
			(xy 133.875856 -221.05157) (xy 133.884416 -221.025212) (xy 133.89229 -221.003114) (xy 133.687312 -220.648022)
			(xy 133.664452 -220.643704) (xy 133.639631 -220.638536) (xy 133.591852 -220.621582) (xy 133.547233 -220.59751)
			(xy 133.506826 -220.56689) (xy 133.471585 -220.530444) (xy 133.442341 -220.48903) (xy 133.419784 -220.443627)
			(xy 133.404447 -220.395304) (xy 133.39669 -220.345203) (xy 133.396228 -220.319854) (xy 132.175504 -220.319854)
			(xy 132.174894 -220.347507) (xy 132.165571 -220.402025) (xy 132.156962 -220.428312) (xy 132.149342 -220.45041)
			(xy 132.354574 -220.805756) (xy 132.377434 -220.810074) (xy 132.402245 -220.815229) (xy 132.449984 -220.832223)
			(xy 132.494562 -220.856322) (xy 132.534927 -220.886957) (xy 132.57013 -220.923408) (xy 132.59934 -220.964816)
			(xy 132.621872 -221.010206) (xy 132.637192 -221.058509) (xy 132.644942 -221.108587) (xy 132.645404 -221.133924)
			(xy 132.644896 -221.159811) (xy 132.636797 -221.210949) (xy 132.620798 -221.260189) (xy 132.597292 -221.306321)
			(xy 132.56686 -221.348208) (xy 132.53025 -221.384818) (xy 132.488363 -221.41525) (xy 132.442231 -221.438756)
			(xy 132.392991 -221.454755) (xy 132.341853 -221.462854) (xy 132.290079 -221.462854) (xy 132.238941 -221.454755)
			(xy 132.189701 -221.438756) (xy 132.143569 -221.41525) (xy 132.101682 -221.384818) (xy 132.065072 -221.348208)
			(xy 132.03464 -221.306321) (xy 132.011134 -221.260189) (xy 131.995135 -221.210949) (xy 131.987036 -221.159811)
			(xy 131.986528 -221.133924) (xy 131.987067 -221.106216) (xy 131.996256 -221.05157) (xy 132.004816 -221.025212)
			(xy 132.01269 -221.003114) (xy 131.807712 -220.648022) (xy 131.784852 -220.643704) (xy 131.76 -220.63857)
			(xy 131.712153 -220.621668) (xy 131.667462 -220.597632) (xy 131.626984 -220.567029) (xy 131.591674 -220.530584)
			(xy 131.562368 -220.489157) (xy 131.539757 -220.443728) (xy 131.524377 -220.39537) (xy 131.516591 -220.345226)
			(xy 131.51612 -220.319854) (xy 130.295904 -220.319854) (xy 130.295294 -220.347507) (xy 130.285971 -220.402025)
			(xy 130.277362 -220.428312) (xy 130.269742 -220.45041) (xy 130.474974 -220.805756) (xy 130.497834 -220.810074)
			(xy 130.522645 -220.815229) (xy 130.570384 -220.832223) (xy 130.614962 -220.856322) (xy 130.655327 -220.886957)
			(xy 130.69053 -220.923408) (xy 130.71974 -220.964816) (xy 130.742272 -221.010206) (xy 130.757592 -221.058509)
			(xy 130.765342 -221.108587) (xy 130.765804 -221.133924) (xy 130.765296 -221.159811) (xy 130.757197 -221.210949)
			(xy 130.741198 -221.260189) (xy 130.717692 -221.306321) (xy 130.68726 -221.348208) (xy 130.65065 -221.384818)
			(xy 130.608763 -221.41525) (xy 130.562631 -221.438756) (xy 130.513391 -221.454755) (xy 130.462253 -221.462854)
			(xy 130.410479 -221.462854) (xy 130.359341 -221.454755) (xy 130.310101 -221.438756) (xy 130.263969 -221.41525)
			(xy 130.222082 -221.384818) (xy 130.185472 -221.348208) (xy 130.15504 -221.306321) (xy 130.131534 -221.260189)
			(xy 130.115535 -221.210949) (xy 130.107436 -221.159811) (xy 130.106928 -221.133924) (xy 130.107467 -221.106216)
			(xy 130.116656 -221.05157) (xy 130.125216 -221.025212) (xy 130.13309 -221.003114) (xy 129.928112 -220.648022)
			(xy 129.905252 -220.643704) (xy 129.8804 -220.63857) (xy 129.832553 -220.621668) (xy 129.787862 -220.597632)
			(xy 129.747384 -220.567029) (xy 129.712074 -220.530584) (xy 129.682768 -220.489157) (xy 129.660157 -220.443728)
			(xy 129.644777 -220.39537) (xy 129.636991 -220.345226) (xy 129.63652 -220.319854) (xy 128.416304 -220.319854)
			(xy 128.415694 -220.347507) (xy 128.406371 -220.402025) (xy 128.397762 -220.428312) (xy 128.390142 -220.45041)
			(xy 128.595374 -220.805756) (xy 128.618234 -220.810074) (xy 128.643045 -220.815229) (xy 128.690784 -220.832223)
			(xy 128.735362 -220.856322) (xy 128.775727 -220.886957) (xy 128.81093 -220.923408) (xy 128.84014 -220.964816)
			(xy 128.862672 -221.010206) (xy 128.877992 -221.058509) (xy 128.885742 -221.108587) (xy 128.886204 -221.133924)
			(xy 128.885696 -221.159811) (xy 128.877597 -221.210949) (xy 128.861598 -221.260189) (xy 128.838092 -221.306321)
			(xy 128.80766 -221.348208) (xy 128.77105 -221.384818) (xy 128.729163 -221.41525) (xy 128.683031 -221.438756)
			(xy 128.633791 -221.454755) (xy 128.582653 -221.462854) (xy 128.530879 -221.462854) (xy 128.479741 -221.454755)
			(xy 128.430501 -221.438756) (xy 128.384369 -221.41525) (xy 128.342482 -221.384818) (xy 128.305872 -221.348208)
			(xy 128.27544 -221.306321) (xy 128.251934 -221.260189) (xy 128.235935 -221.210949) (xy 128.227836 -221.159811)
			(xy 128.227328 -221.133924) (xy 128.227867 -221.106216) (xy 128.237056 -221.05157) (xy 128.245616 -221.025212)
			(xy 128.25349 -221.003114) (xy 128.048512 -220.648022) (xy 128.025652 -220.643704) (xy 128.0008 -220.63857)
			(xy 127.952953 -220.621668) (xy 127.908262 -220.597632) (xy 127.867784 -220.567029) (xy 127.832474 -220.530584)
			(xy 127.803168 -220.489157) (xy 127.780557 -220.443728) (xy 127.765177 -220.39537) (xy 127.757391 -220.345226)
			(xy 127.75692 -220.319854) (xy 126.536704 -220.319854) (xy 126.536094 -220.347507) (xy 126.526771 -220.402025)
			(xy 126.518162 -220.428312) (xy 126.510542 -220.45041) (xy 126.715774 -220.805756) (xy 126.738634 -220.810074)
			(xy 126.763445 -220.815229) (xy 126.811184 -220.832223) (xy 126.855762 -220.856322) (xy 126.896127 -220.886957)
			(xy 126.93133 -220.923408) (xy 126.96054 -220.964816) (xy 126.983072 -221.010206) (xy 126.998392 -221.058509)
			(xy 127.006142 -221.108587) (xy 127.006604 -221.133924) (xy 127.006096 -221.159811) (xy 126.997997 -221.210949)
			(xy 126.981998 -221.260189) (xy 126.958492 -221.306321) (xy 126.92806 -221.348208) (xy 126.89145 -221.384818)
			(xy 126.849563 -221.41525) (xy 126.803431 -221.438756) (xy 126.754191 -221.454755) (xy 126.703053 -221.462854)
			(xy 126.651279 -221.462854) (xy 126.600141 -221.454755) (xy 126.550901 -221.438756) (xy 126.504769 -221.41525)
			(xy 126.462882 -221.384818) (xy 126.426272 -221.348208) (xy 126.39584 -221.306321) (xy 126.372334 -221.260189)
			(xy 126.356335 -221.210949) (xy 126.348236 -221.159811) (xy 126.347728 -221.133924) (xy 126.348267 -221.106216)
			(xy 126.357456 -221.05157) (xy 126.366016 -221.025212) (xy 126.37389 -221.003114) (xy 126.168912 -220.648022)
			(xy 126.146052 -220.643704) (xy 126.1212 -220.63857) (xy 126.073353 -220.621668) (xy 126.028662 -220.597632)
			(xy 125.988184 -220.567029) (xy 125.952874 -220.530584) (xy 125.923568 -220.489157) (xy 125.900957 -220.443728)
			(xy 125.885577 -220.39537) (xy 125.877791 -220.345226) (xy 125.87732 -220.319854) (xy 124.657104 -220.319854)
			(xy 124.656494 -220.347507) (xy 124.647171 -220.402025) (xy 124.638562 -220.428312) (xy 124.630942 -220.45041)
			(xy 124.836174 -220.805756) (xy 124.859034 -220.810074) (xy 124.883845 -220.815229) (xy 124.931584 -220.832223)
			(xy 124.976162 -220.856322) (xy 125.016527 -220.886957) (xy 125.05173 -220.923408) (xy 125.08094 -220.964816)
			(xy 125.103472 -221.010206) (xy 125.118792 -221.058509) (xy 125.126542 -221.108587) (xy 125.127004 -221.133924)
			(xy 125.126496 -221.159811) (xy 125.118397 -221.210949) (xy 125.102398 -221.260189) (xy 125.078892 -221.306321)
			(xy 125.04846 -221.348208) (xy 125.01185 -221.384818) (xy 124.969963 -221.41525) (xy 124.923831 -221.438756)
			(xy 124.874591 -221.454755) (xy 124.823453 -221.462854) (xy 124.771679 -221.462854) (xy 124.720541 -221.454755)
			(xy 124.671301 -221.438756) (xy 124.625169 -221.41525) (xy 124.583282 -221.384818) (xy 124.546672 -221.348208)
			(xy 124.51624 -221.306321) (xy 124.492734 -221.260189) (xy 124.476735 -221.210949) (xy 124.468636 -221.159811)
			(xy 124.468128 -221.133924) (xy 124.468667 -221.106216) (xy 124.477856 -221.05157) (xy 124.486416 -221.025212)
			(xy 124.49429 -221.003114) (xy 124.289312 -220.648022) (xy 124.266452 -220.643704) (xy 124.2416 -220.63857)
			(xy 124.193753 -220.621668) (xy 124.149062 -220.597632) (xy 124.108584 -220.567029) (xy 124.073274 -220.530584)
			(xy 124.043968 -220.489157) (xy 124.021357 -220.443728) (xy 124.005977 -220.39537) (xy 123.998191 -220.345226)
			(xy 123.99772 -220.319854) (xy 122.777504 -220.319854) (xy 122.776894 -220.347507) (xy 122.767571 -220.402025)
			(xy 122.758962 -220.428312) (xy 122.751342 -220.45041) (xy 122.956574 -220.805756) (xy 122.979434 -220.810074)
			(xy 123.004245 -220.815229) (xy 123.051984 -220.832223) (xy 123.096562 -220.856322) (xy 123.136927 -220.886957)
			(xy 123.17213 -220.923408) (xy 123.20134 -220.964816) (xy 123.223872 -221.010206) (xy 123.239192 -221.058509)
			(xy 123.246942 -221.108587) (xy 123.247404 -221.133924) (xy 123.246896 -221.159811) (xy 123.238797 -221.210949)
			(xy 123.222798 -221.260189) (xy 123.199292 -221.306321) (xy 123.16886 -221.348208) (xy 123.13225 -221.384818)
			(xy 123.090363 -221.41525) (xy 123.044231 -221.438756) (xy 122.994991 -221.454755) (xy 122.943853 -221.462854)
			(xy 122.892079 -221.462854) (xy 122.840941 -221.454755) (xy 122.791701 -221.438756) (xy 122.745569 -221.41525)
			(xy 122.703682 -221.384818) (xy 122.667072 -221.348208) (xy 122.63664 -221.306321) (xy 122.613134 -221.260189)
			(xy 122.597135 -221.210949) (xy 122.589036 -221.159811) (xy 122.588528 -221.133924) (xy 122.589067 -221.106216)
			(xy 122.598256 -221.05157) (xy 122.606816 -221.025212) (xy 122.61469 -221.003114) (xy 122.409712 -220.648022)
			(xy 122.386852 -220.643704) (xy 122.362 -220.63857) (xy 122.314153 -220.621668) (xy 122.269462 -220.597632)
			(xy 122.228984 -220.567029) (xy 122.193674 -220.530584) (xy 122.164368 -220.489157) (xy 122.141757 -220.443728)
			(xy 122.126377 -220.39537) (xy 122.118591 -220.345226) (xy 122.11812 -220.319854) (xy 120.897904 -220.319854)
			(xy 120.897294 -220.347507) (xy 120.887971 -220.402025) (xy 120.879362 -220.428312) (xy 120.871742 -220.45041)
			(xy 121.076974 -220.805756) (xy 121.099834 -220.810074) (xy 121.124645 -220.815229) (xy 121.172384 -220.832223)
			(xy 121.216962 -220.856322) (xy 121.257327 -220.886957) (xy 121.29253 -220.923408) (xy 121.32174 -220.964816)
			(xy 121.344272 -221.010206) (xy 121.359592 -221.058509) (xy 121.367342 -221.108587) (xy 121.367804 -221.133924)
			(xy 121.367296 -221.159811) (xy 121.359197 -221.210949) (xy 121.343198 -221.260189) (xy 121.319692 -221.306321)
			(xy 121.28926 -221.348208) (xy 121.25265 -221.384818) (xy 121.210763 -221.41525) (xy 121.164631 -221.438756)
			(xy 121.115391 -221.454755) (xy 121.064253 -221.462854) (xy 121.012479 -221.462854) (xy 120.961341 -221.454755)
			(xy 120.912101 -221.438756) (xy 120.865969 -221.41525) (xy 120.824082 -221.384818) (xy 120.787472 -221.348208)
			(xy 120.75704 -221.306321) (xy 120.733534 -221.260189) (xy 120.717535 -221.210949) (xy 120.709436 -221.159811)
			(xy 120.708928 -221.133924) (xy 120.709467 -221.106216) (xy 120.718656 -221.05157) (xy 120.727216 -221.025212)
			(xy 120.73509 -221.003114) (xy 120.530112 -220.648022) (xy 120.507252 -220.643704) (xy 120.4824 -220.63857)
			(xy 120.434553 -220.621668) (xy 120.389862 -220.597632) (xy 120.349384 -220.567029) (xy 120.314074 -220.530584)
			(xy 120.284768 -220.489157) (xy 120.262157 -220.443728) (xy 120.246777 -220.39537) (xy 120.238991 -220.345226)
			(xy 120.23852 -220.319854) (xy 119.018304 -220.319854) (xy 119.017694 -220.347507) (xy 119.008371 -220.402025)
			(xy 118.999762 -220.428312) (xy 118.992142 -220.45041) (xy 119.197374 -220.805756) (xy 119.220234 -220.810074)
			(xy 119.245045 -220.815229) (xy 119.292784 -220.832223) (xy 119.337362 -220.856322) (xy 119.377727 -220.886957)
			(xy 119.41293 -220.923408) (xy 119.44214 -220.964816) (xy 119.464672 -221.010206) (xy 119.479992 -221.058509)
			(xy 119.487742 -221.108587) (xy 119.488204 -221.133924) (xy 119.487696 -221.159811) (xy 119.479597 -221.210949)
			(xy 119.463598 -221.260189) (xy 119.440092 -221.306321) (xy 119.40966 -221.348208) (xy 119.37305 -221.384818)
			(xy 119.331163 -221.41525) (xy 119.285031 -221.438756) (xy 119.235791 -221.454755) (xy 119.184653 -221.462854)
			(xy 119.132879 -221.462854) (xy 119.081741 -221.454755) (xy 119.032501 -221.438756) (xy 118.986369 -221.41525)
			(xy 118.944482 -221.384818) (xy 118.907872 -221.348208) (xy 118.87744 -221.306321) (xy 118.853934 -221.260189)
			(xy 118.837935 -221.210949) (xy 118.829836 -221.159811) (xy 118.829328 -221.133924) (xy 118.829867 -221.106216)
			(xy 118.839056 -221.05157) (xy 118.847616 -221.025212) (xy 118.85549 -221.003114) (xy 118.650512 -220.648022)
			(xy 118.627652 -220.643704) (xy 118.6028 -220.63857) (xy 118.554953 -220.621668) (xy 118.510262 -220.597632)
			(xy 118.469784 -220.567029) (xy 118.434474 -220.530584) (xy 118.405168 -220.489157) (xy 118.382557 -220.443728)
			(xy 118.367177 -220.39537) (xy 118.359391 -220.345226) (xy 118.35892 -220.319854) (xy 117.138704 -220.319854)
			(xy 117.138094 -220.347507) (xy 117.128771 -220.402025) (xy 117.120162 -220.428312) (xy 117.112542 -220.45041)
			(xy 117.317774 -220.805756) (xy 117.340634 -220.810074) (xy 117.365445 -220.815229) (xy 117.413184 -220.832223)
			(xy 117.457762 -220.856322) (xy 117.498127 -220.886957) (xy 117.53333 -220.923408) (xy 117.56254 -220.964816)
			(xy 117.585072 -221.010206) (xy 117.600392 -221.058509) (xy 117.608142 -221.108587) (xy 117.608604 -221.133924)
			(xy 117.608096 -221.159811) (xy 117.599997 -221.210949) (xy 117.583998 -221.260189) (xy 117.560492 -221.306321)
			(xy 117.53006 -221.348208) (xy 117.49345 -221.384818) (xy 117.451563 -221.41525) (xy 117.405431 -221.438756)
			(xy 117.356191 -221.454755) (xy 117.305053 -221.462854) (xy 117.253279 -221.462854) (xy 117.202141 -221.454755)
			(xy 117.152901 -221.438756) (xy 117.106769 -221.41525) (xy 117.064882 -221.384818) (xy 117.028272 -221.348208)
			(xy 116.99784 -221.306321) (xy 116.974334 -221.260189) (xy 116.958335 -221.210949) (xy 116.950236 -221.159811)
			(xy 116.949728 -221.133924) (xy 116.950267 -221.106216) (xy 116.959456 -221.05157) (xy 116.968016 -221.025212)
			(xy 116.97589 -221.003114) (xy 116.770912 -220.648022) (xy 116.748052 -220.643704) (xy 116.7232 -220.63857)
			(xy 116.675353 -220.621668) (xy 116.630662 -220.597632) (xy 116.590184 -220.567029) (xy 116.554874 -220.530584)
			(xy 116.525568 -220.489157) (xy 116.502957 -220.443728) (xy 116.487577 -220.39537) (xy 116.479791 -220.345226)
			(xy 116.47932 -220.319854) (xy 115.259104 -220.319854) (xy 115.258494 -220.347507) (xy 115.249171 -220.402025)
			(xy 115.240562 -220.428312) (xy 115.232942 -220.45041) (xy 115.438174 -220.805756) (xy 115.461034 -220.810074)
			(xy 115.485845 -220.815229) (xy 115.533584 -220.832223) (xy 115.578162 -220.856322) (xy 115.618527 -220.886957)
			(xy 115.65373 -220.923408) (xy 115.68294 -220.964816) (xy 115.705472 -221.010206) (xy 115.720792 -221.058509)
			(xy 115.728542 -221.108587) (xy 115.729004 -221.133924) (xy 115.728496 -221.159811) (xy 115.720397 -221.210949)
			(xy 115.704398 -221.260189) (xy 115.680892 -221.306321) (xy 115.65046 -221.348208) (xy 115.61385 -221.384818)
			(xy 115.571963 -221.41525) (xy 115.525831 -221.438756) (xy 115.476591 -221.454755) (xy 115.425453 -221.462854)
			(xy 115.373679 -221.462854) (xy 115.322541 -221.454755) (xy 115.273301 -221.438756) (xy 115.227169 -221.41525)
			(xy 115.185282 -221.384818) (xy 115.148672 -221.348208) (xy 115.11824 -221.306321) (xy 115.094734 -221.260189)
			(xy 115.078735 -221.210949) (xy 115.070636 -221.159811) (xy 115.070128 -221.133924) (xy 115.070667 -221.106216)
			(xy 115.079856 -221.05157) (xy 115.088416 -221.025212) (xy 115.09629 -221.003114) (xy 114.891312 -220.648022)
			(xy 114.868452 -220.643704) (xy 114.8436 -220.63857) (xy 114.795753 -220.621668) (xy 114.751062 -220.597632)
			(xy 114.710584 -220.567029) (xy 114.675274 -220.530584) (xy 114.645968 -220.489157) (xy 114.623357 -220.443728)
			(xy 114.607977 -220.39537) (xy 114.600191 -220.345226) (xy 114.59972 -220.319854) (xy 113.379504 -220.319854)
			(xy 113.378894 -220.347507) (xy 113.369571 -220.402025) (xy 113.360962 -220.428312) (xy 113.353342 -220.45041)
			(xy 113.558574 -220.805756) (xy 113.581434 -220.810074) (xy 113.606245 -220.815229) (xy 113.653984 -220.832223)
			(xy 113.698562 -220.856322) (xy 113.738927 -220.886957) (xy 113.77413 -220.923408) (xy 113.80334 -220.964816)
			(xy 113.825872 -221.010206) (xy 113.841192 -221.058509) (xy 113.848942 -221.108587) (xy 113.849404 -221.133924)
			(xy 113.848896 -221.159811) (xy 113.840797 -221.210949) (xy 113.824798 -221.260189) (xy 113.801292 -221.306321)
			(xy 113.77086 -221.348208) (xy 113.73425 -221.384818) (xy 113.692363 -221.41525) (xy 113.646231 -221.438756)
			(xy 113.596991 -221.454755) (xy 113.545853 -221.462854) (xy 113.494079 -221.462854) (xy 113.442941 -221.454755)
			(xy 113.393701 -221.438756) (xy 113.347569 -221.41525) (xy 113.305682 -221.384818) (xy 113.269072 -221.348208)
			(xy 113.23864 -221.306321) (xy 113.215134 -221.260189) (xy 113.199135 -221.210949) (xy 113.191036 -221.159811)
			(xy 113.190528 -221.133924) (xy 113.191067 -221.106216) (xy 113.200256 -221.05157) (xy 113.208816 -221.025212)
			(xy 113.21669 -221.003114) (xy 113.011712 -220.648022) (xy 112.988852 -220.643704) (xy 112.964 -220.63857)
			(xy 112.916153 -220.621668) (xy 112.871462 -220.597632) (xy 112.830984 -220.567029) (xy 112.795674 -220.530584)
			(xy 112.766368 -220.489157) (xy 112.743757 -220.443728) (xy 112.728377 -220.39537) (xy 112.720591 -220.345226)
			(xy 112.72012 -220.319854) (xy 111.499904 -220.319854) (xy 111.499294 -220.347507) (xy 111.489971 -220.402025)
			(xy 111.481362 -220.428312) (xy 111.473742 -220.45041) (xy 111.678974 -220.805756) (xy 111.701834 -220.810074)
			(xy 111.726645 -220.815229) (xy 111.774384 -220.832223) (xy 111.818962 -220.856322) (xy 111.859327 -220.886957)
			(xy 111.89453 -220.923408) (xy 111.92374 -220.964816) (xy 111.946272 -221.010206) (xy 111.961592 -221.058509)
			(xy 111.969342 -221.108587) (xy 111.969804 -221.133924) (xy 111.969296 -221.159811) (xy 111.961197 -221.210949)
			(xy 111.945198 -221.260189) (xy 111.921692 -221.306321) (xy 111.89126 -221.348208) (xy 111.85465 -221.384818)
			(xy 111.812763 -221.41525) (xy 111.766631 -221.438756) (xy 111.717391 -221.454755) (xy 111.666253 -221.462854)
			(xy 111.614479 -221.462854) (xy 111.563341 -221.454755) (xy 111.514101 -221.438756) (xy 111.467969 -221.41525)
			(xy 111.426082 -221.384818) (xy 111.389472 -221.348208) (xy 111.35904 -221.306321) (xy 111.335534 -221.260189)
			(xy 111.319535 -221.210949) (xy 111.311436 -221.159811) (xy 111.310928 -221.133924) (xy 111.311467 -221.106216)
			(xy 111.320656 -221.05157) (xy 111.329216 -221.025212) (xy 111.33709 -221.003114) (xy 111.132112 -220.648022)
			(xy 111.109252 -220.643704) (xy 111.0844 -220.63857) (xy 111.036553 -220.621668) (xy 110.991862 -220.597632)
			(xy 110.951384 -220.567029) (xy 110.916074 -220.530584) (xy 110.886768 -220.489157) (xy 110.864157 -220.443728)
			(xy 110.848777 -220.39537) (xy 110.840991 -220.345226) (xy 110.84052 -220.319854) (xy 109.620304 -220.319854)
			(xy 109.619694 -220.347507) (xy 109.610371 -220.402025) (xy 109.601762 -220.428312) (xy 109.594142 -220.45041)
			(xy 109.799374 -220.805756) (xy 109.822234 -220.810074) (xy 109.847045 -220.815229) (xy 109.894784 -220.832223)
			(xy 109.939362 -220.856322) (xy 109.979727 -220.886957) (xy 110.01493 -220.923408) (xy 110.04414 -220.964816)
			(xy 110.066672 -221.010206) (xy 110.081992 -221.058509) (xy 110.089742 -221.108587) (xy 110.090204 -221.133924)
			(xy 110.089696 -221.159811) (xy 110.081597 -221.210949) (xy 110.065598 -221.260189) (xy 110.042092 -221.306321)
			(xy 110.01166 -221.348208) (xy 109.97505 -221.384818) (xy 109.933163 -221.41525) (xy 109.887031 -221.438756)
			(xy 109.837791 -221.454755) (xy 109.786653 -221.462854) (xy 109.734879 -221.462854) (xy 109.683741 -221.454755)
			(xy 109.634501 -221.438756) (xy 109.588369 -221.41525) (xy 109.546482 -221.384818) (xy 109.509872 -221.348208)
			(xy 109.47944 -221.306321) (xy 109.455934 -221.260189) (xy 109.439935 -221.210949) (xy 109.431836 -221.159811)
			(xy 109.431328 -221.133924) (xy 109.431867 -221.106216) (xy 109.441056 -221.05157) (xy 109.449616 -221.025212)
			(xy 109.45749 -221.003114) (xy 109.252512 -220.648022) (xy 109.229652 -220.643704) (xy 109.2048 -220.63857)
			(xy 109.156953 -220.621668) (xy 109.112262 -220.597632) (xy 109.071784 -220.567029) (xy 109.036474 -220.530584)
			(xy 109.007168 -220.489157) (xy 108.984557 -220.443728) (xy 108.969177 -220.39537) (xy 108.961391 -220.345226)
			(xy 108.96092 -220.319854) (xy 107.740704 -220.319854) (xy 107.740094 -220.347507) (xy 107.730771 -220.402025)
			(xy 107.722162 -220.428312) (xy 107.714542 -220.45041) (xy 107.919774 -220.805756) (xy 107.942634 -220.810074)
			(xy 107.967445 -220.815229) (xy 108.015184 -220.832223) (xy 108.059762 -220.856322) (xy 108.100127 -220.886957)
			(xy 108.13533 -220.923408) (xy 108.16454 -220.964816) (xy 108.187072 -221.010206) (xy 108.202392 -221.058509)
			(xy 108.210142 -221.108587) (xy 108.210604 -221.133924) (xy 108.210096 -221.159811) (xy 108.201997 -221.210949)
			(xy 108.185998 -221.260189) (xy 108.162492 -221.306321) (xy 108.13206 -221.348208) (xy 108.09545 -221.384818)
			(xy 108.053563 -221.41525) (xy 108.007431 -221.438756) (xy 107.958191 -221.454755) (xy 107.907053 -221.462854)
			(xy 107.855279 -221.462854) (xy 107.804141 -221.454755) (xy 107.754901 -221.438756) (xy 107.708769 -221.41525)
			(xy 107.666882 -221.384818) (xy 107.630272 -221.348208) (xy 107.59984 -221.306321) (xy 107.576334 -221.260189)
			(xy 107.560335 -221.210949) (xy 107.552236 -221.159811) (xy 107.551728 -221.133924) (xy 107.552267 -221.106216)
			(xy 107.561456 -221.05157) (xy 107.570016 -221.025212) (xy 107.57789 -221.003114) (xy 107.372912 -220.648022)
			(xy 107.350052 -220.643704) (xy 107.3252 -220.63857) (xy 107.277353 -220.621668) (xy 107.232662 -220.597632)
			(xy 107.192184 -220.567029) (xy 107.156874 -220.530584) (xy 107.127568 -220.489157) (xy 107.104957 -220.443728)
			(xy 107.089577 -220.39537) (xy 107.081791 -220.345226) (xy 107.08132 -220.319854) (xy 105.861104 -220.319854)
			(xy 105.860494 -220.347507) (xy 105.851171 -220.402025) (xy 105.842562 -220.428312) (xy 105.834942 -220.45041)
			(xy 106.040174 -220.805756) (xy 106.063034 -220.810074) (xy 106.087845 -220.815229) (xy 106.135584 -220.832223)
			(xy 106.180162 -220.856322) (xy 106.220527 -220.886957) (xy 106.25573 -220.923408) (xy 106.28494 -220.964816)
			(xy 106.307472 -221.010206) (xy 106.322792 -221.058509) (xy 106.330542 -221.108587) (xy 106.331004 -221.133924)
			(xy 106.330496 -221.159811) (xy 106.322397 -221.210949) (xy 106.306398 -221.260189) (xy 106.282892 -221.306321)
			(xy 106.25246 -221.348208) (xy 106.21585 -221.384818) (xy 106.173963 -221.41525) (xy 106.127831 -221.438756)
			(xy 106.078591 -221.454755) (xy 106.027453 -221.462854) (xy 105.975679 -221.462854) (xy 105.924541 -221.454755)
			(xy 105.875301 -221.438756) (xy 105.829169 -221.41525) (xy 105.787282 -221.384818) (xy 105.750672 -221.348208)
			(xy 105.72024 -221.306321) (xy 105.696734 -221.260189) (xy 105.680735 -221.210949) (xy 105.672636 -221.159811)
			(xy 105.672128 -221.133924) (xy 105.672667 -221.106216) (xy 105.681856 -221.05157) (xy 105.690416 -221.025212)
			(xy 105.69829 -221.003114) (xy 105.493312 -220.648022) (xy 105.470452 -220.643704) (xy 105.4456 -220.63857)
			(xy 105.397753 -220.621668) (xy 105.353062 -220.597632) (xy 105.312584 -220.567029) (xy 105.277274 -220.530584)
			(xy 105.247968 -220.489157) (xy 105.225357 -220.443728) (xy 105.209977 -220.39537) (xy 105.202191 -220.345226)
			(xy 105.20172 -220.319854) (xy 103.981504 -220.319854) (xy 103.981028 -220.345199) (xy 103.973249 -220.395289)
			(xy 103.957897 -220.443599) (xy 103.935334 -220.48899) (xy 103.906091 -220.530396) (xy 103.870857 -220.566839)
			(xy 103.830462 -220.597461) (xy 103.785857 -220.621543) (xy 103.738093 -220.638516) (xy 103.71328 -220.643704)
			(xy 103.69042 -220.648022) (xy 103.485442 -221.003114) (xy 103.493316 -221.024958) (xy 103.50191 -221.051373)
			(xy 103.511097 -221.106151) (xy 103.511604 -221.133924) (xy 103.511096 -221.159811) (xy 103.502997 -221.210949)
			(xy 103.486998 -221.260189) (xy 103.463492 -221.306321) (xy 103.43306 -221.348208) (xy 103.39645 -221.384818)
			(xy 103.354563 -221.41525) (xy 103.308431 -221.438756) (xy 103.259191 -221.454755) (xy 103.208053 -221.462854)
			(xy 103.156279 -221.462854) (xy 103.105141 -221.454755) (xy 103.055901 -221.438756) (xy 103.009769 -221.41525)
			(xy 102.967882 -221.384818) (xy 102.931272 -221.348208) (xy 102.90084 -221.306321) (xy 102.877334 -221.260189)
			(xy 102.861335 -221.210949) (xy 102.853236 -221.159811) (xy 102.852728 -221.133924) (xy 102.571804 -221.133924)
			(xy 102.57128 -221.161632) (xy 102.562081 -221.216279) (xy 102.553516 -221.242636) (xy 102.545642 -221.264734)
			(xy 102.75062 -221.619572) (xy 102.77348 -221.62389) (xy 102.798305 -221.629041) (xy 102.846083 -221.645999)
			(xy 102.890702 -221.670074) (xy 102.931107 -221.700696) (xy 102.966347 -221.737145) (xy 102.99559 -221.778561)
			(xy 103.018147 -221.823965) (xy 103.033485 -221.872289) (xy 103.041242 -221.92239) (xy 103.041704 -221.94774)
			(xy 104.26192 -221.94774) (xy 104.262371 -221.922394) (xy 104.270152 -221.872302) (xy 104.285506 -221.82399)
			(xy 104.308072 -221.778597) (xy 104.337318 -221.737192) (xy 104.372555 -221.700749) (xy 104.412954 -221.670127)
			(xy 104.457562 -221.646047) (xy 104.50533 -221.629076) (xy 104.530144 -221.62389) (xy 104.553004 -221.619572)
			(xy 104.758236 -221.264226) (xy 104.750362 -221.242128) (xy 104.741898 -221.215883) (xy 104.732825 -221.161495)
			(xy 104.732328 -221.133924) (xy 104.732836 -221.108037) (xy 104.740935 -221.056899) (xy 104.756934 -221.007659)
			(xy 104.78044 -220.961527) (xy 104.810872 -220.91964) (xy 104.847482 -220.88303) (xy 104.889369 -220.852598)
			(xy 104.935501 -220.829092) (xy 104.984741 -220.813093) (xy 105.035879 -220.804994) (xy 105.087653 -220.804994)
			(xy 105.138791 -220.813093) (xy 105.188031 -220.829092) (xy 105.234163 -220.852598) (xy 105.27605 -220.88303)
			(xy 105.31266 -220.91964) (xy 105.343092 -220.961527) (xy 105.366598 -221.007659) (xy 105.382597 -221.056899)
			(xy 105.390696 -221.108037) (xy 105.391204 -221.133924) (xy 105.390748 -221.159299) (xy 105.382976 -221.20945)
			(xy 105.367604 -221.257815) (xy 105.344997 -221.303251) (xy 105.315689 -221.344682) (xy 105.280373 -221.381128)
			(xy 105.239885 -221.411727) (xy 105.195184 -221.435754) (xy 105.147326 -221.452641) (xy 105.122472 -221.457774)
			(xy 105.099612 -221.462092) (xy 104.894888 -221.81693) (xy 104.902762 -221.838774) (xy 104.911419 -221.865179)
			(xy 104.920732 -221.919958) (xy 104.921304 -221.94774) (xy 106.14152 -221.94774) (xy 106.141971 -221.922394)
			(xy 106.149752 -221.872302) (xy 106.165106 -221.82399) (xy 106.187672 -221.778597) (xy 106.216918 -221.737192)
			(xy 106.252155 -221.700749) (xy 106.292554 -221.670127) (xy 106.337162 -221.646047) (xy 106.38493 -221.629076)
			(xy 106.409744 -221.62389) (xy 106.432604 -221.619572) (xy 106.637836 -221.264226) (xy 106.629962 -221.242128)
			(xy 106.621498 -221.215883) (xy 106.612425 -221.161495) (xy 106.611928 -221.133924) (xy 106.612436 -221.108037)
			(xy 106.620535 -221.056899) (xy 106.636534 -221.007659) (xy 106.66004 -220.961527) (xy 106.690472 -220.91964)
			(xy 106.727082 -220.88303) (xy 106.768969 -220.852598) (xy 106.815101 -220.829092) (xy 106.864341 -220.813093)
			(xy 106.915479 -220.804994) (xy 106.967253 -220.804994) (xy 107.018391 -220.813093) (xy 107.067631 -220.829092)
			(xy 107.113763 -220.852598) (xy 107.15565 -220.88303) (xy 107.19226 -220.91964) (xy 107.222692 -220.961527)
			(xy 107.246198 -221.007659) (xy 107.262197 -221.056899) (xy 107.270296 -221.108037) (xy 107.270804 -221.133924)
			(xy 107.270348 -221.159299) (xy 107.262576 -221.20945) (xy 107.247204 -221.257815) (xy 107.224597 -221.303251)
			(xy 107.195289 -221.344682) (xy 107.159973 -221.381128) (xy 107.119485 -221.411727) (xy 107.074784 -221.435754)
			(xy 107.026926 -221.452641) (xy 107.002072 -221.457774) (xy 106.979212 -221.462092) (xy 106.774488 -221.81693)
			(xy 106.782362 -221.838774) (xy 106.791019 -221.865179) (xy 106.800332 -221.919958) (xy 106.800904 -221.94774)
			(xy 108.02112 -221.94774) (xy 108.021571 -221.922394) (xy 108.029352 -221.872302) (xy 108.044706 -221.82399)
			(xy 108.067272 -221.778597) (xy 108.096518 -221.737192) (xy 108.131755 -221.700749) (xy 108.172154 -221.670127)
			(xy 108.216762 -221.646047) (xy 108.26453 -221.629076) (xy 108.289344 -221.62389) (xy 108.312204 -221.619572)
			(xy 108.517436 -221.264226) (xy 108.509562 -221.242128) (xy 108.501098 -221.215883) (xy 108.492025 -221.161495)
			(xy 108.491528 -221.133924) (xy 108.492036 -221.108037) (xy 108.500135 -221.056899) (xy 108.516134 -221.007659)
			(xy 108.53964 -220.961527) (xy 108.570072 -220.91964) (xy 108.606682 -220.88303) (xy 108.648569 -220.852598)
			(xy 108.694701 -220.829092) (xy 108.743941 -220.813093) (xy 108.795079 -220.804994) (xy 108.846853 -220.804994)
			(xy 108.897991 -220.813093) (xy 108.947231 -220.829092) (xy 108.993363 -220.852598) (xy 109.03525 -220.88303)
			(xy 109.07186 -220.91964) (xy 109.102292 -220.961527) (xy 109.125798 -221.007659) (xy 109.141797 -221.056899)
			(xy 109.149896 -221.108037) (xy 109.150404 -221.133924) (xy 109.149948 -221.159299) (xy 109.142176 -221.20945)
			(xy 109.126804 -221.257815) (xy 109.104197 -221.303251) (xy 109.074889 -221.344682) (xy 109.039573 -221.381128)
			(xy 108.999085 -221.411727) (xy 108.954384 -221.435754) (xy 108.906526 -221.452641) (xy 108.881672 -221.457774)
			(xy 108.858812 -221.462092) (xy 108.654088 -221.81693) (xy 108.661962 -221.838774) (xy 108.670619 -221.865179)
			(xy 108.679932 -221.919958) (xy 108.680504 -221.94774) (xy 109.901228 -221.94774) (xy 109.901634 -221.922403)
			(xy 109.909396 -221.872326) (xy 109.924728 -221.824026) (xy 109.947269 -221.77864) (xy 109.976489 -221.737238)
			(xy 110.011699 -221.700794) (xy 110.05207 -221.670165) (xy 110.096652 -221.646074) (xy 110.144395 -221.629087)
			(xy 110.169198 -221.62389) (xy 110.192058 -221.619572) (xy 110.397036 -221.26448) (xy 110.389416 -221.242382)
			(xy 110.380897 -221.216211) (xy 110.371703 -221.161949) (xy 110.371128 -221.134432) (xy 110.371128 -221.133924)
			(xy 110.371636 -221.108037) (xy 110.379735 -221.056899) (xy 110.395734 -221.007659) (xy 110.41924 -220.961527)
			(xy 110.449672 -220.91964) (xy 110.486282 -220.88303) (xy 110.528169 -220.852598) (xy 110.574301 -220.829092)
			(xy 110.623541 -220.813093) (xy 110.674679 -220.804994) (xy 110.726453 -220.804994) (xy 110.777591 -220.813093)
			(xy 110.826831 -220.829092) (xy 110.872963 -220.852598) (xy 110.91485 -220.88303) (xy 110.95146 -220.91964)
			(xy 110.981892 -220.961527) (xy 111.005398 -221.007659) (xy 111.021397 -221.056899) (xy 111.029496 -221.108037)
			(xy 111.030004 -221.133924) (xy 111.029585 -221.15929) (xy 111.021833 -221.209425) (xy 111.006484 -221.257778)
			(xy 110.983902 -221.303206) (xy 110.954621 -221.344633) (xy 110.919333 -221.381081) (xy 110.878874 -221.411686)
			(xy 110.8342 -221.435725) (xy 110.786369 -221.45263) (xy 110.761526 -221.457774) (xy 110.738666 -221.462092)
			(xy 110.533942 -221.81693) (xy 110.541816 -221.838774) (xy 110.550414 -221.865187) (xy 110.559598 -221.919967)
			(xy 110.560104 -221.94774) (xy 111.78032 -221.94774) (xy 111.780771 -221.922394) (xy 111.788552 -221.872302)
			(xy 111.803906 -221.82399) (xy 111.826472 -221.778597) (xy 111.855718 -221.737192) (xy 111.890955 -221.700749)
			(xy 111.931354 -221.670127) (xy 111.975962 -221.646047) (xy 112.02373 -221.629076) (xy 112.048544 -221.62389)
			(xy 112.071404 -221.619572) (xy 112.276636 -221.264226) (xy 112.268762 -221.242128) (xy 112.260298 -221.215883)
			(xy 112.251225 -221.161495) (xy 112.250728 -221.133924) (xy 112.251236 -221.108037) (xy 112.259335 -221.056899)
			(xy 112.275334 -221.007659) (xy 112.29884 -220.961527) (xy 112.329272 -220.91964) (xy 112.365882 -220.88303)
			(xy 112.407769 -220.852598) (xy 112.453901 -220.829092) (xy 112.503141 -220.813093) (xy 112.554279 -220.804994)
			(xy 112.606053 -220.804994) (xy 112.657191 -220.813093) (xy 112.706431 -220.829092) (xy 112.752563 -220.852598)
			(xy 112.79445 -220.88303) (xy 112.83106 -220.91964) (xy 112.861492 -220.961527) (xy 112.884998 -221.007659)
			(xy 112.900997 -221.056899) (xy 112.909096 -221.108037) (xy 112.909604 -221.133924) (xy 112.909148 -221.159299)
			(xy 112.901376 -221.20945) (xy 112.886004 -221.257815) (xy 112.863397 -221.303251) (xy 112.834089 -221.344682)
			(xy 112.798773 -221.381128) (xy 112.758285 -221.411727) (xy 112.713584 -221.435754) (xy 112.665726 -221.452641)
			(xy 112.640872 -221.457774) (xy 112.618012 -221.462092) (xy 112.413288 -221.81693) (xy 112.421162 -221.838774)
			(xy 112.429819 -221.865179) (xy 112.439132 -221.919958) (xy 112.439704 -221.94774) (xy 113.660428 -221.94774)
			(xy 113.660834 -221.922403) (xy 113.668596 -221.872326) (xy 113.683928 -221.824026) (xy 113.706469 -221.77864)
			(xy 113.735689 -221.737238) (xy 113.770899 -221.700794) (xy 113.81127 -221.670165) (xy 113.855852 -221.646074)
			(xy 113.903595 -221.629087) (xy 113.928398 -221.62389) (xy 113.951258 -221.619572) (xy 114.156236 -221.26448)
			(xy 114.148616 -221.242382) (xy 114.140097 -221.216211) (xy 114.130903 -221.161949) (xy 114.130328 -221.134432)
			(xy 114.130328 -221.133924) (xy 114.130836 -221.108037) (xy 114.138935 -221.056899) (xy 114.154934 -221.007659)
			(xy 114.17844 -220.961527) (xy 114.208872 -220.91964) (xy 114.245482 -220.88303) (xy 114.287369 -220.852598)
			(xy 114.333501 -220.829092) (xy 114.382741 -220.813093) (xy 114.433879 -220.804994) (xy 114.485653 -220.804994)
			(xy 114.536791 -220.813093) (xy 114.586031 -220.829092) (xy 114.632163 -220.852598) (xy 114.67405 -220.88303)
			(xy 114.71066 -220.91964) (xy 114.741092 -220.961527) (xy 114.764598 -221.007659) (xy 114.780597 -221.056899)
			(xy 114.788696 -221.108037) (xy 114.789204 -221.133924) (xy 114.788785 -221.15929) (xy 114.781033 -221.209425)
			(xy 114.765684 -221.257778) (xy 114.743102 -221.303206) (xy 114.713821 -221.344633) (xy 114.678533 -221.381081)
			(xy 114.638074 -221.411686) (xy 114.5934 -221.435725) (xy 114.545569 -221.45263) (xy 114.520726 -221.457774)
			(xy 114.497866 -221.462092) (xy 114.293142 -221.81693) (xy 114.301016 -221.838774) (xy 114.309614 -221.865187)
			(xy 114.318798 -221.919967) (xy 114.319304 -221.94774) (xy 115.53952 -221.94774) (xy 115.539971 -221.922394)
			(xy 115.547752 -221.872302) (xy 115.563106 -221.82399) (xy 115.585672 -221.778597) (xy 115.614918 -221.737192)
			(xy 115.650155 -221.700749) (xy 115.690554 -221.670127) (xy 115.735162 -221.646047) (xy 115.78293 -221.629076)
			(xy 115.807744 -221.62389) (xy 115.830604 -221.619572) (xy 116.035836 -221.264226) (xy 116.027962 -221.242128)
			(xy 116.019498 -221.215883) (xy 116.010425 -221.161495) (xy 116.009928 -221.133924) (xy 116.010436 -221.108037)
			(xy 116.018535 -221.056899) (xy 116.034534 -221.007659) (xy 116.05804 -220.961527) (xy 116.088472 -220.91964)
			(xy 116.125082 -220.88303) (xy 116.166969 -220.852598) (xy 116.213101 -220.829092) (xy 116.262341 -220.813093)
			(xy 116.313479 -220.804994) (xy 116.365253 -220.804994) (xy 116.416391 -220.813093) (xy 116.465631 -220.829092)
			(xy 116.511763 -220.852598) (xy 116.55365 -220.88303) (xy 116.59026 -220.91964) (xy 116.620692 -220.961527)
			(xy 116.644198 -221.007659) (xy 116.660197 -221.056899) (xy 116.668296 -221.108037) (xy 116.668804 -221.133924)
			(xy 116.668348 -221.159299) (xy 116.660576 -221.20945) (xy 116.645204 -221.257815) (xy 116.622597 -221.303251)
			(xy 116.593289 -221.344682) (xy 116.557973 -221.381128) (xy 116.517485 -221.411727) (xy 116.472784 -221.435754)
			(xy 116.424926 -221.452641) (xy 116.400072 -221.457774) (xy 116.377212 -221.462092) (xy 116.172488 -221.81693)
			(xy 116.180362 -221.838774) (xy 116.189019 -221.865179) (xy 116.198332 -221.919958) (xy 116.198904 -221.94774)
			(xy 117.41912 -221.94774) (xy 117.419571 -221.922394) (xy 117.427352 -221.872302) (xy 117.442706 -221.82399)
			(xy 117.465272 -221.778597) (xy 117.494518 -221.737192) (xy 117.529755 -221.700749) (xy 117.570154 -221.670127)
			(xy 117.614762 -221.646047) (xy 117.66253 -221.629076) (xy 117.687344 -221.62389) (xy 117.710204 -221.619572)
			(xy 117.915436 -221.264226) (xy 117.907562 -221.242128) (xy 117.899098 -221.215883) (xy 117.890025 -221.161495)
			(xy 117.889528 -221.133924) (xy 117.890036 -221.108037) (xy 117.898135 -221.056899) (xy 117.914134 -221.007659)
			(xy 117.93764 -220.961527) (xy 117.968072 -220.91964) (xy 118.004682 -220.88303) (xy 118.046569 -220.852598)
			(xy 118.092701 -220.829092) (xy 118.141941 -220.813093) (xy 118.193079 -220.804994) (xy 118.244853 -220.804994)
			(xy 118.295991 -220.813093) (xy 118.345231 -220.829092) (xy 118.391363 -220.852598) (xy 118.43325 -220.88303)
			(xy 118.46986 -220.91964) (xy 118.500292 -220.961527) (xy 118.523798 -221.007659) (xy 118.539797 -221.056899)
			(xy 118.547896 -221.108037) (xy 118.548404 -221.133924) (xy 118.547948 -221.159299) (xy 118.540176 -221.20945)
			(xy 118.524804 -221.257815) (xy 118.502197 -221.303251) (xy 118.472889 -221.344682) (xy 118.437573 -221.381128)
			(xy 118.397085 -221.411727) (xy 118.352384 -221.435754) (xy 118.304526 -221.452641) (xy 118.279672 -221.457774)
			(xy 118.256812 -221.462092) (xy 118.052088 -221.81693) (xy 118.059962 -221.838774) (xy 118.068619 -221.865179)
			(xy 118.077932 -221.919958) (xy 118.078504 -221.94774) (xy 121.17832 -221.94774) (xy 121.178771 -221.922394)
			(xy 121.186552 -221.872302) (xy 121.201906 -221.82399) (xy 121.224472 -221.778597) (xy 121.253718 -221.737192)
			(xy 121.288955 -221.700749) (xy 121.329354 -221.670127) (xy 121.373962 -221.646047) (xy 121.42173 -221.629076)
			(xy 121.446544 -221.62389) (xy 121.469404 -221.619572) (xy 121.674636 -221.264226) (xy 121.666762 -221.242128)
			(xy 121.658298 -221.215883) (xy 121.649225 -221.161495) (xy 121.648728 -221.133924) (xy 121.649236 -221.108037)
			(xy 121.657335 -221.056899) (xy 121.673334 -221.007659) (xy 121.69684 -220.961527) (xy 121.727272 -220.91964)
			(xy 121.763882 -220.88303) (xy 121.805769 -220.852598) (xy 121.851901 -220.829092) (xy 121.901141 -220.813093)
			(xy 121.952279 -220.804994) (xy 122.004053 -220.804994) (xy 122.055191 -220.813093) (xy 122.104431 -220.829092)
			(xy 122.150563 -220.852598) (xy 122.19245 -220.88303) (xy 122.22906 -220.91964) (xy 122.259492 -220.961527)
			(xy 122.282998 -221.007659) (xy 122.298997 -221.056899) (xy 122.307096 -221.108037) (xy 122.307604 -221.133924)
			(xy 122.307148 -221.159299) (xy 122.299376 -221.20945) (xy 122.284004 -221.257815) (xy 122.261397 -221.303251)
			(xy 122.232089 -221.344682) (xy 122.196773 -221.381128) (xy 122.156285 -221.411727) (xy 122.111584 -221.435754)
			(xy 122.063726 -221.452641) (xy 122.038872 -221.457774) (xy 122.016012 -221.462092) (xy 121.811288 -221.81693)
			(xy 121.819162 -221.838774) (xy 121.827819 -221.865179) (xy 121.837132 -221.919958) (xy 121.837704 -221.94774)
			(xy 123.05792 -221.94774) (xy 123.058371 -221.922394) (xy 123.066152 -221.872302) (xy 123.081506 -221.82399)
			(xy 123.104072 -221.778597) (xy 123.133318 -221.737192) (xy 123.168555 -221.700749) (xy 123.208954 -221.670127)
			(xy 123.253562 -221.646047) (xy 123.30133 -221.629076) (xy 123.326144 -221.62389) (xy 123.349004 -221.619572)
			(xy 123.554236 -221.264226) (xy 123.546362 -221.242128) (xy 123.537898 -221.215883) (xy 123.528825 -221.161495)
			(xy 123.528328 -221.133924) (xy 123.528836 -221.108037) (xy 123.536935 -221.056899) (xy 123.552934 -221.007659)
			(xy 123.57644 -220.961527) (xy 123.606872 -220.91964) (xy 123.643482 -220.88303) (xy 123.685369 -220.852598)
			(xy 123.731501 -220.829092) (xy 123.780741 -220.813093) (xy 123.831879 -220.804994) (xy 123.883653 -220.804994)
			(xy 123.934791 -220.813093) (xy 123.984031 -220.829092) (xy 124.030163 -220.852598) (xy 124.07205 -220.88303)
			(xy 124.10866 -220.91964) (xy 124.139092 -220.961527) (xy 124.162598 -221.007659) (xy 124.178597 -221.056899)
			(xy 124.186696 -221.108037) (xy 124.187204 -221.133924) (xy 124.186748 -221.159299) (xy 124.178976 -221.20945)
			(xy 124.163604 -221.257815) (xy 124.140997 -221.303251) (xy 124.111689 -221.344682) (xy 124.076373 -221.381128)
			(xy 124.035885 -221.411727) (xy 123.991184 -221.435754) (xy 123.943326 -221.452641) (xy 123.918472 -221.457774)
			(xy 123.895612 -221.462092) (xy 123.690888 -221.81693) (xy 123.698762 -221.838774) (xy 123.707419 -221.865179)
			(xy 123.716732 -221.919958) (xy 123.717304 -221.94774) (xy 124.93752 -221.94774) (xy 124.937971 -221.922394)
			(xy 124.945752 -221.872302) (xy 124.961106 -221.82399) (xy 124.983672 -221.778597) (xy 125.012918 -221.737192)
			(xy 125.048155 -221.700749) (xy 125.088554 -221.670127) (xy 125.133162 -221.646047) (xy 125.18093 -221.629076)
			(xy 125.205744 -221.62389) (xy 125.228604 -221.619572) (xy 125.433836 -221.264226) (xy 125.425962 -221.242128)
			(xy 125.417498 -221.215883) (xy 125.408425 -221.161495) (xy 125.407928 -221.133924) (xy 125.408436 -221.108037)
			(xy 125.416535 -221.056899) (xy 125.432534 -221.007659) (xy 125.45604 -220.961527) (xy 125.486472 -220.91964)
			(xy 125.523082 -220.88303) (xy 125.564969 -220.852598) (xy 125.611101 -220.829092) (xy 125.660341 -220.813093)
			(xy 125.711479 -220.804994) (xy 125.763253 -220.804994) (xy 125.814391 -220.813093) (xy 125.863631 -220.829092)
			(xy 125.909763 -220.852598) (xy 125.95165 -220.88303) (xy 125.98826 -220.91964) (xy 126.018692 -220.961527)
			(xy 126.042198 -221.007659) (xy 126.058197 -221.056899) (xy 126.066296 -221.108037) (xy 126.066804 -221.133924)
			(xy 126.066348 -221.159299) (xy 126.058576 -221.20945) (xy 126.043204 -221.257815) (xy 126.020597 -221.303251)
			(xy 125.991289 -221.344682) (xy 125.955973 -221.381128) (xy 125.915485 -221.411727) (xy 125.870784 -221.435754)
			(xy 125.822926 -221.452641) (xy 125.798072 -221.457774) (xy 125.775212 -221.462092) (xy 125.570488 -221.81693)
			(xy 125.578362 -221.838774) (xy 125.587019 -221.865179) (xy 125.596332 -221.919958) (xy 125.596904 -221.94774)
			(xy 126.81712 -221.94774) (xy 126.817571 -221.922394) (xy 126.825352 -221.872302) (xy 126.840706 -221.82399)
			(xy 126.863272 -221.778597) (xy 126.892518 -221.737192) (xy 126.927755 -221.700749) (xy 126.968154 -221.670127)
			(xy 127.012762 -221.646047) (xy 127.06053 -221.629076) (xy 127.085344 -221.62389) (xy 127.108204 -221.619572)
			(xy 127.313436 -221.264226) (xy 127.305562 -221.242128) (xy 127.297098 -221.215883) (xy 127.288025 -221.161495)
			(xy 127.287528 -221.133924) (xy 127.288036 -221.108037) (xy 127.296135 -221.056899) (xy 127.312134 -221.007659)
			(xy 127.33564 -220.961527) (xy 127.366072 -220.91964) (xy 127.402682 -220.88303) (xy 127.444569 -220.852598)
			(xy 127.490701 -220.829092) (xy 127.539941 -220.813093) (xy 127.591079 -220.804994) (xy 127.642853 -220.804994)
			(xy 127.693991 -220.813093) (xy 127.743231 -220.829092) (xy 127.789363 -220.852598) (xy 127.83125 -220.88303)
			(xy 127.86786 -220.91964) (xy 127.898292 -220.961527) (xy 127.921798 -221.007659) (xy 127.937797 -221.056899)
			(xy 127.945896 -221.108037) (xy 127.946404 -221.133924) (xy 127.945948 -221.159299) (xy 127.938176 -221.20945)
			(xy 127.922804 -221.257815) (xy 127.900197 -221.303251) (xy 127.870889 -221.344682) (xy 127.835573 -221.381128)
			(xy 127.795085 -221.411727) (xy 127.750384 -221.435754) (xy 127.702526 -221.452641) (xy 127.677672 -221.457774)
			(xy 127.654812 -221.462092) (xy 127.450088 -221.81693) (xy 127.457962 -221.838774) (xy 127.466619 -221.865179)
			(xy 127.475932 -221.919958) (xy 127.476504 -221.94774) (xy 128.69672 -221.94774) (xy 128.697171 -221.922394)
			(xy 128.704952 -221.872302) (xy 128.720306 -221.82399) (xy 128.742872 -221.778597) (xy 128.772118 -221.737192)
			(xy 128.807355 -221.700749) (xy 128.847754 -221.670127) (xy 128.892362 -221.646047) (xy 128.94013 -221.629076)
			(xy 128.964944 -221.62389) (xy 128.987804 -221.619572) (xy 129.193036 -221.264226) (xy 129.185162 -221.242128)
			(xy 129.176698 -221.215883) (xy 129.167625 -221.161495) (xy 129.167128 -221.133924) (xy 129.167636 -221.108037)
			(xy 129.175735 -221.056899) (xy 129.191734 -221.007659) (xy 129.21524 -220.961527) (xy 129.245672 -220.91964)
			(xy 129.282282 -220.88303) (xy 129.324169 -220.852598) (xy 129.370301 -220.829092) (xy 129.419541 -220.813093)
			(xy 129.470679 -220.804994) (xy 129.522453 -220.804994) (xy 129.573591 -220.813093) (xy 129.622831 -220.829092)
			(xy 129.668963 -220.852598) (xy 129.71085 -220.88303) (xy 129.74746 -220.91964) (xy 129.777892 -220.961527)
			(xy 129.801398 -221.007659) (xy 129.817397 -221.056899) (xy 129.825496 -221.108037) (xy 129.826004 -221.133924)
			(xy 129.825548 -221.159299) (xy 129.817776 -221.20945) (xy 129.802404 -221.257815) (xy 129.779797 -221.303251)
			(xy 129.750489 -221.344682) (xy 129.715173 -221.381128) (xy 129.674685 -221.411727) (xy 129.629984 -221.435754)
			(xy 129.582126 -221.452641) (xy 129.557272 -221.457774) (xy 129.534412 -221.462092) (xy 129.329688 -221.81693)
			(xy 129.337562 -221.838774) (xy 129.346219 -221.865179) (xy 129.355532 -221.919958) (xy 129.356104 -221.94774)
			(xy 130.57632 -221.94774) (xy 130.576771 -221.922394) (xy 130.584552 -221.872302) (xy 130.599906 -221.82399)
			(xy 130.622472 -221.778597) (xy 130.651718 -221.737192) (xy 130.686955 -221.700749) (xy 130.727354 -221.670127)
			(xy 130.771962 -221.646047) (xy 130.81973 -221.629076) (xy 130.844544 -221.62389) (xy 130.867404 -221.619572)
			(xy 131.072636 -221.264226) (xy 131.064762 -221.242128) (xy 131.056298 -221.215883) (xy 131.047225 -221.161495)
			(xy 131.046728 -221.133924) (xy 131.047236 -221.108037) (xy 131.055335 -221.056899) (xy 131.071334 -221.007659)
			(xy 131.09484 -220.961527) (xy 131.125272 -220.91964) (xy 131.161882 -220.88303) (xy 131.203769 -220.852598)
			(xy 131.249901 -220.829092) (xy 131.299141 -220.813093) (xy 131.350279 -220.804994) (xy 131.402053 -220.804994)
			(xy 131.453191 -220.813093) (xy 131.502431 -220.829092) (xy 131.548563 -220.852598) (xy 131.59045 -220.88303)
			(xy 131.62706 -220.91964) (xy 131.657492 -220.961527) (xy 131.680998 -221.007659) (xy 131.696997 -221.056899)
			(xy 131.705096 -221.108037) (xy 131.705604 -221.133924) (xy 131.705148 -221.159299) (xy 131.697376 -221.20945)
			(xy 131.682004 -221.257815) (xy 131.659397 -221.303251) (xy 131.630089 -221.344682) (xy 131.594773 -221.381128)
			(xy 131.554285 -221.411727) (xy 131.509584 -221.435754) (xy 131.461726 -221.452641) (xy 131.436872 -221.457774)
			(xy 131.414012 -221.462092) (xy 131.209288 -221.81693) (xy 131.217162 -221.838774) (xy 131.225819 -221.865179)
			(xy 131.235132 -221.919958) (xy 131.235704 -221.94774) (xy 132.45592 -221.94774) (xy 132.456371 -221.922394)
			(xy 132.464152 -221.872302) (xy 132.479506 -221.82399) (xy 132.502072 -221.778597) (xy 132.531318 -221.737192)
			(xy 132.566555 -221.700749) (xy 132.606954 -221.670127) (xy 132.651562 -221.646047) (xy 132.69933 -221.629076)
			(xy 132.724144 -221.62389) (xy 132.747004 -221.619572) (xy 132.951982 -221.263972) (xy 132.944362 -221.242128)
			(xy 132.935911 -221.215946) (xy 132.92684 -221.161685) (xy 132.926328 -221.134178) (xy 132.926328 -221.133924)
			(xy 132.926836 -221.108037) (xy 132.934935 -221.056899) (xy 132.950934 -221.007659) (xy 132.97444 -220.961527)
			(xy 133.004872 -220.91964) (xy 133.041482 -220.88303) (xy 133.083369 -220.852598) (xy 133.129501 -220.829092)
			(xy 133.178741 -220.813093) (xy 133.229879 -220.804994) (xy 133.281653 -220.804994) (xy 133.332791 -220.813093)
			(xy 133.382031 -220.829092) (xy 133.428163 -220.852598) (xy 133.47005 -220.88303) (xy 133.50666 -220.91964)
			(xy 133.537092 -220.961527) (xy 133.560598 -221.007659) (xy 133.576597 -221.056899) (xy 133.584696 -221.108037)
			(xy 133.585204 -221.133924) (xy 133.584785 -221.15929) (xy 133.577033 -221.209425) (xy 133.561684 -221.257778)
			(xy 133.539102 -221.303206) (xy 133.509821 -221.344633) (xy 133.474533 -221.381081) (xy 133.434074 -221.411686)
			(xy 133.3894 -221.435725) (xy 133.341569 -221.45263) (xy 133.316726 -221.457774) (xy 133.293866 -221.462092)
			(xy 133.089142 -221.81693) (xy 133.096762 -221.838774) (xy 133.105377 -221.865059) (xy 133.114698 -221.919578)
			(xy 133.115304 -221.947232) (xy 133.115304 -221.94774) (xy 134.33552 -221.94774) (xy 134.335971 -221.922394)
			(xy 134.343752 -221.872302) (xy 134.359106 -221.82399) (xy 134.381672 -221.778597) (xy 134.410918 -221.737192)
			(xy 134.446155 -221.700749) (xy 134.486554 -221.670127) (xy 134.531162 -221.646047) (xy 134.57893 -221.629076)
			(xy 134.603744 -221.62389) (xy 134.626604 -221.619572) (xy 134.831582 -221.263972) (xy 134.823962 -221.242128)
			(xy 134.815511 -221.215946) (xy 134.80644 -221.161685) (xy 134.805928 -221.134178) (xy 134.805928 -221.133924)
			(xy 134.806436 -221.108037) (xy 134.814535 -221.056899) (xy 134.830534 -221.007659) (xy 134.85404 -220.961527)
			(xy 134.884472 -220.91964) (xy 134.921082 -220.88303) (xy 134.962969 -220.852598) (xy 135.009101 -220.829092)
			(xy 135.058341 -220.813093) (xy 135.109479 -220.804994) (xy 135.161253 -220.804994) (xy 135.212391 -220.813093)
			(xy 135.261631 -220.829092) (xy 135.307763 -220.852598) (xy 135.34965 -220.88303) (xy 135.38626 -220.91964)
			(xy 135.416692 -220.961527) (xy 135.440198 -221.007659) (xy 135.456197 -221.056899) (xy 135.464296 -221.108037)
			(xy 135.464804 -221.133924) (xy 135.464385 -221.15929) (xy 135.456633 -221.209425) (xy 135.441284 -221.257778)
			(xy 135.418702 -221.303206) (xy 135.405859 -221.321376) (xy 158.062168 -221.321376) (xy 158.062168 -220.912436)
			(xy 158.062651 -220.902288) (xy 158.070428 -220.883543) (xy 158.084806 -220.869219) (xy 158.103581 -220.861513)
			(xy 158.11373 -220.861128) (xy 159.51327 -220.861128) (xy 159.523393 -220.861651) (xy 159.542112 -220.869366)
			(xy 159.556469 -220.883642) (xy 159.564291 -220.902316) (xy 159.564832 -220.912436) (xy 159.564832 -221.321376)
			(xy 165.605968 -221.321376) (xy 165.605968 -220.912436) (xy 165.606451 -220.902288) (xy 165.614228 -220.883543)
			(xy 165.628606 -220.869219) (xy 165.647381 -220.861513) (xy 165.65753 -220.861128) (xy 167.05707 -220.861128)
			(xy 167.067193 -220.861651) (xy 167.085912 -220.869366) (xy 167.100269 -220.883642) (xy 167.108091 -220.902316)
			(xy 167.108632 -220.912436) (xy 167.108632 -221.321376) (xy 173.149768 -221.321376) (xy 173.149768 -220.912436)
			(xy 173.150251 -220.902288) (xy 173.158028 -220.883543) (xy 173.172406 -220.869219) (xy 173.191181 -220.861513)
			(xy 173.20133 -220.861128) (xy 174.60087 -220.861128) (xy 174.610993 -220.861651) (xy 174.629712 -220.869366)
			(xy 174.644069 -220.883642) (xy 174.651891 -220.902316) (xy 174.652432 -220.912436) (xy 174.652432 -221.321376)
			(xy 180.693568 -221.321376) (xy 180.693568 -220.912436) (xy 180.694051 -220.902288) (xy 180.701828 -220.883543)
			(xy 180.716206 -220.869219) (xy 180.734981 -220.861513) (xy 180.74513 -220.861128) (xy 182.14467 -220.861128)
			(xy 182.154793 -220.861651) (xy 182.173512 -220.869366) (xy 182.187869 -220.883642) (xy 182.195691 -220.902316)
			(xy 182.196232 -220.912436) (xy 182.196232 -221.321376) (xy 188.237368 -221.321376) (xy 188.237368 -220.912436)
			(xy 188.237851 -220.902288) (xy 188.245628 -220.883543) (xy 188.260006 -220.869219) (xy 188.278781 -220.861513)
			(xy 188.28893 -220.861128) (xy 189.68847 -220.861128) (xy 189.698593 -220.861651) (xy 189.717312 -220.869366)
			(xy 189.731669 -220.883642) (xy 189.739491 -220.902316) (xy 189.740032 -220.912436) (xy 189.740032 -221.321376)
			(xy 195.781168 -221.321376) (xy 195.781168 -220.912436) (xy 195.781651 -220.902288) (xy 195.789428 -220.883543)
			(xy 195.803806 -220.869219) (xy 195.822581 -220.861513) (xy 195.83273 -220.861128) (xy 197.23227 -220.861128)
			(xy 197.242393 -220.861651) (xy 197.261112 -220.869366) (xy 197.275469 -220.883642) (xy 197.283291 -220.902316)
			(xy 197.283832 -220.912436) (xy 197.283832 -221.321376) (xy 203.324968 -221.321376) (xy 203.324968 -220.912436)
			(xy 203.325451 -220.902288) (xy 203.333228 -220.883543) (xy 203.347606 -220.869219) (xy 203.366381 -220.861513)
			(xy 203.37653 -220.861128) (xy 204.77607 -220.861128) (xy 204.786193 -220.861651) (xy 204.804912 -220.869366)
			(xy 204.819269 -220.883642) (xy 204.827091 -220.902316) (xy 204.827632 -220.912436) (xy 204.827632 -221.321376)
			(xy 210.868768 -221.321376) (xy 210.868768 -220.912436) (xy 210.869251 -220.902288) (xy 210.877028 -220.883543)
			(xy 210.891406 -220.869219) (xy 210.910181 -220.861513) (xy 210.92033 -220.861128) (xy 212.31987 -220.861128)
			(xy 212.329993 -220.861651) (xy 212.348712 -220.869366) (xy 212.363069 -220.883642) (xy 212.370891 -220.902316)
			(xy 212.371432 -220.912436) (xy 212.371432 -221.321376) (xy 255.329436 -221.321376) (xy 255.329436 -220.912436)
			(xy 255.329852 -220.90228) (xy 255.337642 -220.883521) (xy 255.352042 -220.869195) (xy 255.37084 -220.861501)
			(xy 255.380998 -220.861128) (xy 256.780538 -220.861128) (xy 256.790666 -220.861595) (xy 256.809385 -220.869333)
			(xy 256.82374 -220.883625) (xy 256.83156 -220.902311) (xy 256.8321 -220.912436) (xy 256.8321 -221.321376)
			(xy 262.873236 -221.321376) (xy 262.873236 -220.912436) (xy 262.873652 -220.90228) (xy 262.881442 -220.883521)
			(xy 262.895842 -220.869195) (xy 262.91464 -220.861501) (xy 262.924798 -220.861128) (xy 264.324338 -220.861128)
			(xy 264.334466 -220.861595) (xy 264.353185 -220.869333) (xy 264.36754 -220.883625) (xy 264.37536 -220.902311)
			(xy 264.3759 -220.912436) (xy 264.3759 -221.321376) (xy 270.417036 -221.321376) (xy 270.417036 -220.912436)
			(xy 270.417452 -220.90228) (xy 270.425242 -220.883521) (xy 270.439642 -220.869195) (xy 270.45844 -220.861501)
			(xy 270.468598 -220.861128) (xy 271.868138 -220.861128) (xy 271.878266 -220.861595) (xy 271.896985 -220.869333)
			(xy 271.91134 -220.883625) (xy 271.91916 -220.902311) (xy 271.9197 -220.912436) (xy 271.9197 -221.321376)
			(xy 277.960836 -221.321376) (xy 277.960836 -220.912436) (xy 277.961252 -220.90228) (xy 277.969042 -220.883521)
			(xy 277.983442 -220.869195) (xy 278.00224 -220.861501) (xy 278.012398 -220.861128) (xy 279.411938 -220.861128)
			(xy 279.422066 -220.861595) (xy 279.440785 -220.869333) (xy 279.45514 -220.883625) (xy 279.46296 -220.902311)
			(xy 279.4635 -220.912436) (xy 279.4635 -221.321376) (xy 285.504636 -221.321376) (xy 285.504636 -220.912436)
			(xy 285.505052 -220.90228) (xy 285.512842 -220.883521) (xy 285.527242 -220.869195) (xy 285.54604 -220.861501)
			(xy 285.556198 -220.861128) (xy 286.955738 -220.861128) (xy 286.965866 -220.861595) (xy 286.984585 -220.869333)
			(xy 286.99894 -220.883625) (xy 287.00676 -220.902311) (xy 287.0073 -220.912436) (xy 287.0073 -221.321376)
			(xy 293.048436 -221.321376) (xy 293.048436 -220.912436) (xy 293.048852 -220.90228) (xy 293.056642 -220.883521)
			(xy 293.071042 -220.869195) (xy 293.08984 -220.861501) (xy 293.099998 -220.861128) (xy 294.499538 -220.861128)
			(xy 294.509666 -220.861595) (xy 294.528385 -220.869333) (xy 294.54274 -220.883625) (xy 294.55056 -220.902311)
			(xy 294.5511 -220.912436) (xy 294.5511 -221.321376) (xy 300.592236 -221.321376) (xy 300.592236 -220.912436)
			(xy 300.592652 -220.90228) (xy 300.600442 -220.883521) (xy 300.614842 -220.869195) (xy 300.63364 -220.861501)
			(xy 300.643798 -220.861128) (xy 302.043338 -220.861128) (xy 302.053466 -220.861595) (xy 302.072185 -220.869333)
			(xy 302.08654 -220.883625) (xy 302.09436 -220.902311) (xy 302.0949 -220.912436) (xy 302.0949 -221.321376)
			(xy 308.136036 -221.321376) (xy 308.136036 -220.912436) (xy 308.136452 -220.90228) (xy 308.144242 -220.883521)
			(xy 308.158642 -220.869195) (xy 308.17744 -220.861501) (xy 308.187598 -220.861128) (xy 309.587138 -220.861128)
			(xy 309.597266 -220.861595) (xy 309.615985 -220.869333) (xy 309.63034 -220.883625) (xy 309.63816 -220.902311)
			(xy 309.6387 -220.912436) (xy 309.6387 -221.133924) (xy 336.695796 -221.133924) (xy 336.696304 -221.108037)
			(xy 336.704403 -221.056899) (xy 336.720402 -221.007659) (xy 336.743908 -220.961527) (xy 336.77434 -220.91964)
			(xy 336.81095 -220.88303) (xy 336.852837 -220.852598) (xy 336.898969 -220.829092) (xy 336.948209 -220.813093)
			(xy 336.999347 -220.804994) (xy 337.051121 -220.804994) (xy 337.102259 -220.813093) (xy 337.151499 -220.829092)
			(xy 337.197631 -220.852598) (xy 337.239518 -220.88303) (xy 337.276128 -220.91964) (xy 337.30656 -220.961527)
			(xy 337.330066 -221.007659) (xy 337.346065 -221.056899) (xy 337.354164 -221.108037) (xy 337.354672 -221.133924)
			(xy 337.635596 -221.133924) (xy 337.636104 -221.10859) (xy 337.643853 -221.058519) (xy 337.659172 -221.010223)
			(xy 337.6817 -220.96484) (xy 337.710906 -220.923438) (xy 337.746104 -220.886992) (xy 337.786463 -220.856361)
			(xy 337.831034 -220.832266) (xy 337.878767 -220.815274) (xy 337.903566 -220.810074) (xy 337.926426 -220.805756)
			(xy 338.131404 -220.450664) (xy 338.12353 -220.42882) (xy 338.114896 -220.402408) (xy 338.105568 -220.347635)
			(xy 338.104988 -220.319854) (xy 338.105496 -220.293947) (xy 338.113602 -220.24277) (xy 338.129614 -220.193491)
			(xy 338.153137 -220.147324) (xy 338.183593 -220.105405) (xy 338.220231 -220.068767) (xy 338.26215 -220.038311)
			(xy 338.308317 -220.014788) (xy 338.357596 -219.998776) (xy 338.408773 -219.99067) (xy 338.460587 -219.99067)
			(xy 338.511764 -219.998776) (xy 338.561043 -220.014788) (xy 338.60721 -220.038311) (xy 338.649129 -220.068767)
			(xy 338.685767 -220.105405) (xy 338.716223 -220.147324) (xy 338.739746 -220.193491) (xy 338.755758 -220.24277)
			(xy 338.763864 -220.293947) (xy 338.764372 -220.319854) (xy 338.763922 -220.3452) (xy 338.756142 -220.395293)
			(xy 338.740788 -220.443604) (xy 338.718222 -220.488998) (xy 338.688976 -220.530404) (xy 338.653739 -220.566847)
			(xy 338.61334 -220.597469) (xy 338.568731 -220.621548) (xy 338.520963 -220.638518) (xy 338.496148 -220.643704)
			(xy 338.473288 -220.648022) (xy 338.26831 -221.003114) (xy 338.276184 -221.024958) (xy 338.284777 -221.051373)
			(xy 338.293965 -221.106151) (xy 338.294472 -221.133924) (xy 338.575396 -221.133924) (xy 338.575904 -221.108037)
			(xy 338.584003 -221.056899) (xy 338.600002 -221.007659) (xy 338.623508 -220.961527) (xy 338.65394 -220.91964)
			(xy 338.69055 -220.88303) (xy 338.732437 -220.852598) (xy 338.778569 -220.829092) (xy 338.827809 -220.813093)
			(xy 338.878947 -220.804994) (xy 338.930721 -220.804994) (xy 338.981859 -220.813093) (xy 339.031099 -220.829092)
			(xy 339.077231 -220.852598) (xy 339.119118 -220.88303) (xy 339.155728 -220.91964) (xy 339.18616 -220.961527)
			(xy 339.209666 -221.007659) (xy 339.225665 -221.056899) (xy 339.233764 -221.108037) (xy 339.234272 -221.133924)
			(xy 339.515196 -221.133924) (xy 339.515704 -221.10859) (xy 339.523453 -221.058519) (xy 339.538772 -221.010223)
			(xy 339.5613 -220.96484) (xy 339.590506 -220.923438) (xy 339.625704 -220.886992) (xy 339.666063 -220.856361)
			(xy 339.710634 -220.832266) (xy 339.758367 -220.815274) (xy 339.783166 -220.810074) (xy 339.806026 -220.805756)
			(xy 340.011004 -220.450664) (xy 340.00313 -220.42882) (xy 339.994496 -220.402408) (xy 339.985168 -220.347635)
			(xy 339.984588 -220.319854) (xy 339.985096 -220.293947) (xy 339.993202 -220.24277) (xy 340.009214 -220.193491)
			(xy 340.032737 -220.147324) (xy 340.063193 -220.105405) (xy 340.099831 -220.068767) (xy 340.14175 -220.038311)
			(xy 340.187917 -220.014788) (xy 340.237196 -219.998776) (xy 340.288373 -219.99067) (xy 340.340187 -219.99067)
			(xy 340.391364 -219.998776) (xy 340.440643 -220.014788) (xy 340.48681 -220.038311) (xy 340.528729 -220.068767)
			(xy 340.565367 -220.105405) (xy 340.595823 -220.147324) (xy 340.619346 -220.193491) (xy 340.635358 -220.24277)
			(xy 340.643464 -220.293947) (xy 340.643972 -220.319854) (xy 340.643522 -220.3452) (xy 340.635742 -220.395293)
			(xy 340.620388 -220.443604) (xy 340.597822 -220.488998) (xy 340.568576 -220.530404) (xy 340.533339 -220.566847)
			(xy 340.49294 -220.597469) (xy 340.448331 -220.621548) (xy 340.400563 -220.638518) (xy 340.375748 -220.643704)
			(xy 340.352888 -220.648022) (xy 340.14791 -221.003114) (xy 340.155784 -221.024958) (xy 340.164377 -221.051373)
			(xy 340.173565 -221.106151) (xy 340.174072 -221.133924) (xy 340.454996 -221.133924) (xy 340.455504 -221.108037)
			(xy 340.463603 -221.056899) (xy 340.479602 -221.007659) (xy 340.503108 -220.961527) (xy 340.53354 -220.91964)
			(xy 340.57015 -220.88303) (xy 340.612037 -220.852598) (xy 340.658169 -220.829092) (xy 340.707409 -220.813093)
			(xy 340.758547 -220.804994) (xy 340.810321 -220.804994) (xy 340.861459 -220.813093) (xy 340.910699 -220.829092)
			(xy 340.956831 -220.852598) (xy 340.998718 -220.88303) (xy 341.035328 -220.91964) (xy 341.06576 -220.961527)
			(xy 341.089266 -221.007659) (xy 341.105265 -221.056899) (xy 341.113364 -221.108037) (xy 341.113872 -221.133924)
			(xy 341.394796 -221.133924) (xy 341.395304 -221.10859) (xy 341.403053 -221.058519) (xy 341.418372 -221.010223)
			(xy 341.4409 -220.96484) (xy 341.470106 -220.923438) (xy 341.505304 -220.886992) (xy 341.545663 -220.856361)
			(xy 341.590234 -220.832266) (xy 341.637967 -220.815274) (xy 341.662766 -220.810074) (xy 341.685626 -220.805756)
			(xy 341.890604 -220.450664) (xy 341.88273 -220.42882) (xy 341.874096 -220.402408) (xy 341.864768 -220.347635)
			(xy 341.864188 -220.319854) (xy 341.864696 -220.293947) (xy 341.872802 -220.24277) (xy 341.888814 -220.193491)
			(xy 341.912337 -220.147324) (xy 341.942793 -220.105405) (xy 341.979431 -220.068767) (xy 342.02135 -220.038311)
			(xy 342.067517 -220.014788) (xy 342.116796 -219.998776) (xy 342.167973 -219.99067) (xy 342.219787 -219.99067)
			(xy 342.270964 -219.998776) (xy 342.320243 -220.014788) (xy 342.36641 -220.038311) (xy 342.408329 -220.068767)
			(xy 342.444967 -220.105405) (xy 342.475423 -220.147324) (xy 342.498946 -220.193491) (xy 342.514958 -220.24277)
			(xy 342.523064 -220.293947) (xy 342.523572 -220.319854) (xy 342.523122 -220.3452) (xy 342.515342 -220.395293)
			(xy 342.499988 -220.443604) (xy 342.477422 -220.488998) (xy 342.448176 -220.530404) (xy 342.412939 -220.566847)
			(xy 342.37254 -220.597469) (xy 342.327931 -220.621548) (xy 342.280163 -220.638518) (xy 342.255348 -220.643704)
			(xy 342.232488 -220.648022) (xy 342.02751 -221.003114) (xy 342.035384 -221.024958) (xy 342.043977 -221.051373)
			(xy 342.053165 -221.106151) (xy 342.053672 -221.133924) (xy 342.334596 -221.133924) (xy 342.335104 -221.108037)
			(xy 342.343203 -221.056899) (xy 342.359202 -221.007659) (xy 342.382708 -220.961527) (xy 342.41314 -220.91964)
			(xy 342.44975 -220.88303) (xy 342.491637 -220.852598) (xy 342.537769 -220.829092) (xy 342.587009 -220.813093)
			(xy 342.638147 -220.804994) (xy 342.689921 -220.804994) (xy 342.741059 -220.813093) (xy 342.790299 -220.829092)
			(xy 342.836431 -220.852598) (xy 342.878318 -220.88303) (xy 342.914928 -220.91964) (xy 342.94536 -220.961527)
			(xy 342.968866 -221.007659) (xy 342.984865 -221.056899) (xy 342.992964 -221.108037) (xy 342.993472 -221.133924)
			(xy 343.274396 -221.133924) (xy 343.274904 -221.10859) (xy 343.282653 -221.058519) (xy 343.297972 -221.010223)
			(xy 343.3205 -220.96484) (xy 343.349706 -220.923438) (xy 343.384904 -220.886992) (xy 343.425263 -220.856361)
			(xy 343.469834 -220.832266) (xy 343.517567 -220.815274) (xy 343.542366 -220.810074) (xy 343.565226 -220.805756)
			(xy 343.770204 -220.450664) (xy 343.76233 -220.42882) (xy 343.753696 -220.402408) (xy 343.744368 -220.347635)
			(xy 343.743788 -220.319854) (xy 343.744296 -220.293947) (xy 343.752402 -220.24277) (xy 343.768414 -220.193491)
			(xy 343.791937 -220.147324) (xy 343.822393 -220.105405) (xy 343.859031 -220.068767) (xy 343.90095 -220.038311)
			(xy 343.947117 -220.014788) (xy 343.996396 -219.998776) (xy 344.047573 -219.99067) (xy 344.099387 -219.99067)
			(xy 344.150564 -219.998776) (xy 344.199843 -220.014788) (xy 344.24601 -220.038311) (xy 344.287929 -220.068767)
			(xy 344.324567 -220.105405) (xy 344.355023 -220.147324) (xy 344.378546 -220.193491) (xy 344.394558 -220.24277)
			(xy 344.402664 -220.293947) (xy 344.403172 -220.319854) (xy 344.402722 -220.3452) (xy 344.394942 -220.395293)
			(xy 344.379588 -220.443604) (xy 344.357022 -220.488998) (xy 344.327776 -220.530404) (xy 344.292539 -220.566847)
			(xy 344.25214 -220.597469) (xy 344.207531 -220.621548) (xy 344.159763 -220.638518) (xy 344.134948 -220.643704)
			(xy 344.112088 -220.648022) (xy 343.90711 -221.003114) (xy 343.914984 -221.024958) (xy 343.923577 -221.051373)
			(xy 343.932765 -221.106151) (xy 343.933272 -221.133924) (xy 344.214196 -221.133924) (xy 344.214704 -221.108037)
			(xy 344.222803 -221.056899) (xy 344.238802 -221.007659) (xy 344.262308 -220.961527) (xy 344.29274 -220.91964)
			(xy 344.32935 -220.88303) (xy 344.371237 -220.852598) (xy 344.417369 -220.829092) (xy 344.466609 -220.813093)
			(xy 344.517747 -220.804994) (xy 344.569521 -220.804994) (xy 344.620659 -220.813093) (xy 344.669899 -220.829092)
			(xy 344.716031 -220.852598) (xy 344.757918 -220.88303) (xy 344.794528 -220.91964) (xy 344.82496 -220.961527)
			(xy 344.848466 -221.007659) (xy 344.864465 -221.056899) (xy 344.872564 -221.108037) (xy 344.873072 -221.133924)
			(xy 345.153996 -221.133924) (xy 345.154504 -221.10859) (xy 345.162253 -221.058519) (xy 345.177572 -221.010223)
			(xy 345.2001 -220.96484) (xy 345.229306 -220.923438) (xy 345.264504 -220.886992) (xy 345.304863 -220.856361)
			(xy 345.349434 -220.832266) (xy 345.397167 -220.815274) (xy 345.421966 -220.810074) (xy 345.444826 -220.805756)
			(xy 345.649804 -220.450664) (xy 345.64193 -220.42882) (xy 345.633296 -220.402408) (xy 345.623968 -220.347635)
			(xy 345.623388 -220.319854) (xy 345.623896 -220.293947) (xy 345.632002 -220.24277) (xy 345.648014 -220.193491)
			(xy 345.671537 -220.147324) (xy 345.701993 -220.105405) (xy 345.738631 -220.068767) (xy 345.78055 -220.038311)
			(xy 345.826717 -220.014788) (xy 345.875996 -219.998776) (xy 345.927173 -219.99067) (xy 345.978987 -219.99067)
			(xy 346.030164 -219.998776) (xy 346.079443 -220.014788) (xy 346.12561 -220.038311) (xy 346.167529 -220.068767)
			(xy 346.204167 -220.105405) (xy 346.234623 -220.147324) (xy 346.258146 -220.193491) (xy 346.274158 -220.24277)
			(xy 346.282264 -220.293947) (xy 346.282772 -220.319854) (xy 346.282322 -220.3452) (xy 346.274542 -220.395293)
			(xy 346.259188 -220.443604) (xy 346.236622 -220.488998) (xy 346.207376 -220.530404) (xy 346.172139 -220.566847)
			(xy 346.13174 -220.597469) (xy 346.087131 -220.621548) (xy 346.039363 -220.638518) (xy 346.014548 -220.643704)
			(xy 345.991688 -220.648022) (xy 345.78671 -221.003114) (xy 345.794584 -221.024958) (xy 345.803177 -221.051373)
			(xy 345.812365 -221.106151) (xy 345.812872 -221.133924) (xy 346.093796 -221.133924) (xy 346.094304 -221.108037)
			(xy 346.102403 -221.056899) (xy 346.118402 -221.007659) (xy 346.141908 -220.961527) (xy 346.17234 -220.91964)
			(xy 346.20895 -220.88303) (xy 346.250837 -220.852598) (xy 346.296969 -220.829092) (xy 346.346209 -220.813093)
			(xy 346.397347 -220.804994) (xy 346.449121 -220.804994) (xy 346.500259 -220.813093) (xy 346.549499 -220.829092)
			(xy 346.595631 -220.852598) (xy 346.637518 -220.88303) (xy 346.674128 -220.91964) (xy 346.70456 -220.961527)
			(xy 346.728066 -221.007659) (xy 346.744065 -221.056899) (xy 346.752164 -221.108037) (xy 346.752672 -221.133924)
			(xy 347.033596 -221.133924) (xy 347.034104 -221.10859) (xy 347.041853 -221.058519) (xy 347.057172 -221.010223)
			(xy 347.0797 -220.96484) (xy 347.108906 -220.923438) (xy 347.144104 -220.886992) (xy 347.184463 -220.856361)
			(xy 347.229034 -220.832266) (xy 347.276767 -220.815274) (xy 347.301566 -220.810074) (xy 347.324426 -220.805756)
			(xy 347.529404 -220.450664) (xy 347.52153 -220.42882) (xy 347.512896 -220.402408) (xy 347.503568 -220.347635)
			(xy 347.502988 -220.319854) (xy 347.503496 -220.293947) (xy 347.511602 -220.24277) (xy 347.527614 -220.193491)
			(xy 347.551137 -220.147324) (xy 347.581593 -220.105405) (xy 347.618231 -220.068767) (xy 347.66015 -220.038311)
			(xy 347.706317 -220.014788) (xy 347.755596 -219.998776) (xy 347.806773 -219.99067) (xy 347.858587 -219.99067)
			(xy 347.909764 -219.998776) (xy 347.959043 -220.014788) (xy 348.00521 -220.038311) (xy 348.047129 -220.068767)
			(xy 348.083767 -220.105405) (xy 348.114223 -220.147324) (xy 348.137746 -220.193491) (xy 348.153758 -220.24277)
			(xy 348.161864 -220.293947) (xy 348.162372 -220.319854) (xy 348.161922 -220.3452) (xy 348.154142 -220.395293)
			(xy 348.138788 -220.443604) (xy 348.116222 -220.488998) (xy 348.086976 -220.530404) (xy 348.051739 -220.566847)
			(xy 348.01134 -220.597469) (xy 347.966731 -220.621548) (xy 347.918963 -220.638518) (xy 347.894148 -220.643704)
			(xy 347.871288 -220.648022) (xy 347.66631 -221.003114) (xy 347.674184 -221.024958) (xy 347.682777 -221.051373)
			(xy 347.691965 -221.106151) (xy 347.692472 -221.133924) (xy 347.973396 -221.133924) (xy 347.973904 -221.108037)
			(xy 347.982003 -221.056899) (xy 347.998002 -221.007659) (xy 348.021508 -220.961527) (xy 348.05194 -220.91964)
			(xy 348.08855 -220.88303) (xy 348.130437 -220.852598) (xy 348.176569 -220.829092) (xy 348.225809 -220.813093)
			(xy 348.276947 -220.804994) (xy 348.328721 -220.804994) (xy 348.379859 -220.813093) (xy 348.429099 -220.829092)
			(xy 348.475231 -220.852598) (xy 348.517118 -220.88303) (xy 348.553728 -220.91964) (xy 348.58416 -220.961527)
			(xy 348.607666 -221.007659) (xy 348.623665 -221.056899) (xy 348.631764 -221.108037) (xy 348.632272 -221.133924)
			(xy 348.913196 -221.133924) (xy 348.913704 -221.10859) (xy 348.921453 -221.058519) (xy 348.936772 -221.010223)
			(xy 348.9593 -220.96484) (xy 348.988506 -220.923438) (xy 349.023704 -220.886992) (xy 349.064063 -220.856361)
			(xy 349.108634 -220.832266) (xy 349.156367 -220.815274) (xy 349.181166 -220.810074) (xy 349.204026 -220.805756)
			(xy 349.409004 -220.450664) (xy 349.40113 -220.42882) (xy 349.392496 -220.402408) (xy 349.383168 -220.347635)
			(xy 349.382588 -220.319854) (xy 349.383096 -220.293947) (xy 349.391202 -220.24277) (xy 349.407214 -220.193491)
			(xy 349.430737 -220.147324) (xy 349.461193 -220.105405) (xy 349.497831 -220.068767) (xy 349.53975 -220.038311)
			(xy 349.585917 -220.014788) (xy 349.635196 -219.998776) (xy 349.686373 -219.99067) (xy 349.738187 -219.99067)
			(xy 349.789364 -219.998776) (xy 349.838643 -220.014788) (xy 349.88481 -220.038311) (xy 349.926729 -220.068767)
			(xy 349.963367 -220.105405) (xy 349.993823 -220.147324) (xy 350.017346 -220.193491) (xy 350.033358 -220.24277)
			(xy 350.041464 -220.293947) (xy 350.041972 -220.319854) (xy 350.041522 -220.3452) (xy 350.033742 -220.395293)
			(xy 350.018388 -220.443604) (xy 349.995822 -220.488998) (xy 349.966576 -220.530404) (xy 349.931339 -220.566847)
			(xy 349.89094 -220.597469) (xy 349.846331 -220.621548) (xy 349.798563 -220.638518) (xy 349.773748 -220.643704)
			(xy 349.750888 -220.648022) (xy 349.54591 -221.003114) (xy 349.553784 -221.024958) (xy 349.562377 -221.051373)
			(xy 349.571565 -221.106151) (xy 349.572072 -221.133924) (xy 349.852996 -221.133924) (xy 349.853504 -221.108037)
			(xy 349.861603 -221.056899) (xy 349.877602 -221.007659) (xy 349.901108 -220.961527) (xy 349.93154 -220.91964)
			(xy 349.96815 -220.88303) (xy 350.010037 -220.852598) (xy 350.056169 -220.829092) (xy 350.105409 -220.813093)
			(xy 350.156547 -220.804994) (xy 350.208321 -220.804994) (xy 350.259459 -220.813093) (xy 350.308699 -220.829092)
			(xy 350.354831 -220.852598) (xy 350.396718 -220.88303) (xy 350.433328 -220.91964) (xy 350.46376 -220.961527)
			(xy 350.487266 -221.007659) (xy 350.503265 -221.056899) (xy 350.511364 -221.108037) (xy 350.511872 -221.133924)
			(xy 350.792796 -221.133924) (xy 350.793304 -221.10859) (xy 350.801053 -221.058519) (xy 350.816372 -221.010223)
			(xy 350.8389 -220.96484) (xy 350.868106 -220.923438) (xy 350.903304 -220.886992) (xy 350.943663 -220.856361)
			(xy 350.988234 -220.832266) (xy 351.035967 -220.815274) (xy 351.060766 -220.810074) (xy 351.083626 -220.805756)
			(xy 351.288604 -220.450664) (xy 351.28073 -220.42882) (xy 351.272096 -220.402408) (xy 351.262768 -220.347635)
			(xy 351.262188 -220.319854) (xy 351.262696 -220.293947) (xy 351.270802 -220.24277) (xy 351.286814 -220.193491)
			(xy 351.310337 -220.147324) (xy 351.340793 -220.105405) (xy 351.377431 -220.068767) (xy 351.41935 -220.038311)
			(xy 351.465517 -220.014788) (xy 351.514796 -219.998776) (xy 351.565973 -219.99067) (xy 351.617787 -219.99067)
			(xy 351.668964 -219.998776) (xy 351.718243 -220.014788) (xy 351.76441 -220.038311) (xy 351.806329 -220.068767)
			(xy 351.842967 -220.105405) (xy 351.873423 -220.147324) (xy 351.896946 -220.193491) (xy 351.912958 -220.24277)
			(xy 351.921064 -220.293947) (xy 351.921572 -220.319854) (xy 353.141788 -220.319854) (xy 353.142296 -220.293947)
			(xy 353.150402 -220.24277) (xy 353.166414 -220.193491) (xy 353.189937 -220.147324) (xy 353.220393 -220.105405)
			(xy 353.257031 -220.068767) (xy 353.29895 -220.038311) (xy 353.345117 -220.014788) (xy 353.394396 -219.998776)
			(xy 353.445573 -219.99067) (xy 353.497387 -219.99067) (xy 353.548564 -219.998776) (xy 353.597843 -220.014788)
			(xy 353.64401 -220.038311) (xy 353.685929 -220.068767) (xy 353.722567 -220.105405) (xy 353.753023 -220.147324)
			(xy 353.776546 -220.193491) (xy 353.792558 -220.24277) (xy 353.800664 -220.293947) (xy 353.801172 -220.319854)
			(xy 355.021388 -220.319854) (xy 355.021896 -220.293947) (xy 355.030002 -220.24277) (xy 355.046014 -220.193491)
			(xy 355.069537 -220.147324) (xy 355.099993 -220.105405) (xy 355.136631 -220.068767) (xy 355.17855 -220.038311)
			(xy 355.224717 -220.014788) (xy 355.273996 -219.998776) (xy 355.325173 -219.99067) (xy 355.376987 -219.99067)
			(xy 355.428164 -219.998776) (xy 355.477443 -220.014788) (xy 355.52361 -220.038311) (xy 355.565529 -220.068767)
			(xy 355.602167 -220.105405) (xy 355.632623 -220.147324) (xy 355.656146 -220.193491) (xy 355.672158 -220.24277)
			(xy 355.680264 -220.293947) (xy 355.680772 -220.319854) (xy 356.900988 -220.319854) (xy 356.901496 -220.293947)
			(xy 356.909602 -220.24277) (xy 356.925614 -220.193491) (xy 356.949137 -220.147324) (xy 356.979593 -220.105405)
			(xy 357.016231 -220.068767) (xy 357.05815 -220.038311) (xy 357.104317 -220.014788) (xy 357.153596 -219.998776)
			(xy 357.204773 -219.99067) (xy 357.256587 -219.99067) (xy 357.307764 -219.998776) (xy 357.357043 -220.014788)
			(xy 357.40321 -220.038311) (xy 357.445129 -220.068767) (xy 357.481767 -220.105405) (xy 357.512223 -220.147324)
			(xy 357.535746 -220.193491) (xy 357.551758 -220.24277) (xy 357.559864 -220.293947) (xy 357.560372 -220.319854)
			(xy 358.780588 -220.319854) (xy 358.781096 -220.293947) (xy 358.789202 -220.24277) (xy 358.805214 -220.193491)
			(xy 358.828737 -220.147324) (xy 358.859193 -220.105405) (xy 358.895831 -220.068767) (xy 358.93775 -220.038311)
			(xy 358.983917 -220.014788) (xy 359.033196 -219.998776) (xy 359.084373 -219.99067) (xy 359.136187 -219.99067)
			(xy 359.187364 -219.998776) (xy 359.236643 -220.014788) (xy 359.28281 -220.038311) (xy 359.324729 -220.068767)
			(xy 359.361367 -220.105405) (xy 359.391823 -220.147324) (xy 359.415346 -220.193491) (xy 359.431358 -220.24277)
			(xy 359.439464 -220.293947) (xy 359.439972 -220.319854) (xy 360.660188 -220.319854) (xy 360.660696 -220.293947)
			(xy 360.668802 -220.24277) (xy 360.684814 -220.193491) (xy 360.708337 -220.147324) (xy 360.738793 -220.105405)
			(xy 360.775431 -220.068767) (xy 360.81735 -220.038311) (xy 360.863517 -220.014788) (xy 360.912796 -219.998776)
			(xy 360.963973 -219.99067) (xy 361.015787 -219.99067) (xy 361.066964 -219.998776) (xy 361.116243 -220.014788)
			(xy 361.16241 -220.038311) (xy 361.204329 -220.068767) (xy 361.240967 -220.105405) (xy 361.271423 -220.147324)
			(xy 361.294946 -220.193491) (xy 361.310958 -220.24277) (xy 361.319064 -220.293947) (xy 361.319572 -220.319854)
			(xy 362.539788 -220.319854) (xy 362.540296 -220.293947) (xy 362.548402 -220.24277) (xy 362.564414 -220.193491)
			(xy 362.587937 -220.147324) (xy 362.618393 -220.105405) (xy 362.655031 -220.068767) (xy 362.69695 -220.038311)
			(xy 362.743117 -220.014788) (xy 362.792396 -219.998776) (xy 362.843573 -219.99067) (xy 362.895387 -219.99067)
			(xy 362.946564 -219.998776) (xy 362.995843 -220.014788) (xy 363.04201 -220.038311) (xy 363.083929 -220.068767)
			(xy 363.120567 -220.105405) (xy 363.151023 -220.147324) (xy 363.174546 -220.193491) (xy 363.190558 -220.24277)
			(xy 363.198664 -220.293947) (xy 363.199172 -220.319854) (xy 364.419388 -220.319854) (xy 364.419896 -220.293947)
			(xy 364.428002 -220.24277) (xy 364.444014 -220.193491) (xy 364.467537 -220.147324) (xy 364.497993 -220.105405)
			(xy 364.534631 -220.068767) (xy 364.57655 -220.038311) (xy 364.622717 -220.014788) (xy 364.671996 -219.998776)
			(xy 364.723173 -219.99067) (xy 364.774987 -219.99067) (xy 364.826164 -219.998776) (xy 364.875443 -220.014788)
			(xy 364.92161 -220.038311) (xy 364.963529 -220.068767) (xy 365.000167 -220.105405) (xy 365.030623 -220.147324)
			(xy 365.054146 -220.193491) (xy 365.070158 -220.24277) (xy 365.078264 -220.293947) (xy 365.078772 -220.319854)
			(xy 366.298988 -220.319854) (xy 366.299496 -220.293947) (xy 366.307602 -220.24277) (xy 366.323614 -220.193491)
			(xy 366.347137 -220.147324) (xy 366.377593 -220.105405) (xy 366.414231 -220.068767) (xy 366.45615 -220.038311)
			(xy 366.502317 -220.014788) (xy 366.551596 -219.998776) (xy 366.602773 -219.99067) (xy 366.654587 -219.99067)
			(xy 366.705764 -219.998776) (xy 366.755043 -220.014788) (xy 366.80121 -220.038311) (xy 366.843129 -220.068767)
			(xy 366.879767 -220.105405) (xy 366.910223 -220.147324) (xy 366.933746 -220.193491) (xy 366.949758 -220.24277)
			(xy 366.957864 -220.293947) (xy 366.958372 -220.319854) (xy 368.178588 -220.319854) (xy 368.179096 -220.293947)
			(xy 368.187202 -220.24277) (xy 368.203214 -220.193491) (xy 368.226737 -220.147324) (xy 368.257193 -220.105405)
			(xy 368.293831 -220.068767) (xy 368.33575 -220.038311) (xy 368.381917 -220.014788) (xy 368.431196 -219.998776)
			(xy 368.482373 -219.99067) (xy 368.534187 -219.99067) (xy 368.585364 -219.998776) (xy 368.634643 -220.014788)
			(xy 368.68081 -220.038311) (xy 368.722729 -220.068767) (xy 368.759367 -220.105405) (xy 368.789823 -220.147324)
			(xy 368.813346 -220.193491) (xy 368.829358 -220.24277) (xy 368.837464 -220.293947) (xy 368.837972 -220.319854)
			(xy 370.058188 -220.319854) (xy 370.058696 -220.293947) (xy 370.066802 -220.24277) (xy 370.082814 -220.193491)
			(xy 370.106337 -220.147324) (xy 370.136793 -220.105405) (xy 370.173431 -220.068767) (xy 370.21535 -220.038311)
			(xy 370.261517 -220.014788) (xy 370.310796 -219.998776) (xy 370.361973 -219.99067) (xy 370.413787 -219.99067)
			(xy 370.464964 -219.998776) (xy 370.514243 -220.014788) (xy 370.56041 -220.038311) (xy 370.602329 -220.068767)
			(xy 370.638967 -220.105405) (xy 370.669423 -220.147324) (xy 370.692946 -220.193491) (xy 370.708958 -220.24277)
			(xy 370.717064 -220.293947) (xy 370.717572 -220.319854) (xy 371.937788 -220.319854) (xy 371.938296 -220.293947)
			(xy 371.946402 -220.24277) (xy 371.962414 -220.193491) (xy 371.985937 -220.147324) (xy 372.016393 -220.105405)
			(xy 372.053031 -220.068767) (xy 372.09495 -220.038311) (xy 372.141117 -220.014788) (xy 372.190396 -219.998776)
			(xy 372.241573 -219.99067) (xy 372.293387 -219.99067) (xy 372.344564 -219.998776) (xy 372.393843 -220.014788)
			(xy 372.44001 -220.038311) (xy 372.481929 -220.068767) (xy 372.518567 -220.105405) (xy 372.549023 -220.147324)
			(xy 372.572546 -220.193491) (xy 372.588558 -220.24277) (xy 372.596664 -220.293947) (xy 372.597172 -220.319854)
			(xy 373.817388 -220.319854) (xy 373.817896 -220.293947) (xy 373.826002 -220.24277) (xy 373.842014 -220.193491)
			(xy 373.865537 -220.147324) (xy 373.895993 -220.105405) (xy 373.932631 -220.068767) (xy 373.97455 -220.038311)
			(xy 374.020717 -220.014788) (xy 374.069996 -219.998776) (xy 374.121173 -219.99067) (xy 374.172987 -219.99067)
			(xy 374.224164 -219.998776) (xy 374.273443 -220.014788) (xy 374.31961 -220.038311) (xy 374.361529 -220.068767)
			(xy 374.398167 -220.105405) (xy 374.428623 -220.147324) (xy 374.452146 -220.193491) (xy 374.468158 -220.24277)
			(xy 374.476264 -220.293947) (xy 374.476772 -220.319854) (xy 375.696988 -220.319854) (xy 375.697496 -220.293947)
			(xy 375.705602 -220.24277) (xy 375.721614 -220.193491) (xy 375.745137 -220.147324) (xy 375.775593 -220.105405)
			(xy 375.812231 -220.068767) (xy 375.85415 -220.038311) (xy 375.900317 -220.014788) (xy 375.949596 -219.998776)
			(xy 376.000773 -219.99067) (xy 376.052587 -219.99067) (xy 376.103764 -219.998776) (xy 376.153043 -220.014788)
			(xy 376.19921 -220.038311) (xy 376.241129 -220.068767) (xy 376.277767 -220.105405) (xy 376.308223 -220.147324)
			(xy 376.331746 -220.193491) (xy 376.347758 -220.24277) (xy 376.355864 -220.293947) (xy 376.356372 -220.319854)
			(xy 377.576588 -220.319854) (xy 377.577096 -220.293947) (xy 377.585202 -220.24277) (xy 377.601214 -220.193491)
			(xy 377.624737 -220.147324) (xy 377.655193 -220.105405) (xy 377.691831 -220.068767) (xy 377.73375 -220.038311)
			(xy 377.779917 -220.014788) (xy 377.829196 -219.998776) (xy 377.880373 -219.99067) (xy 377.932187 -219.99067)
			(xy 377.983364 -219.998776) (xy 378.032643 -220.014788) (xy 378.07881 -220.038311) (xy 378.120729 -220.068767)
			(xy 378.157367 -220.105405) (xy 378.187823 -220.147324) (xy 378.211346 -220.193491) (xy 378.227358 -220.24277)
			(xy 378.235464 -220.293947) (xy 378.235972 -220.319854) (xy 379.456188 -220.319854) (xy 379.456696 -220.293947)
			(xy 379.464802 -220.24277) (xy 379.480814 -220.193491) (xy 379.504337 -220.147324) (xy 379.534793 -220.105405)
			(xy 379.571431 -220.068767) (xy 379.61335 -220.038311) (xy 379.659517 -220.014788) (xy 379.708796 -219.998776)
			(xy 379.759973 -219.99067) (xy 379.811787 -219.99067) (xy 379.862964 -219.998776) (xy 379.912243 -220.014788)
			(xy 379.95841 -220.038311) (xy 380.000329 -220.068767) (xy 380.036967 -220.105405) (xy 380.067423 -220.147324)
			(xy 380.090946 -220.193491) (xy 380.106958 -220.24277) (xy 380.115064 -220.293947) (xy 380.115572 -220.319854)
			(xy 381.336296 -220.319854) (xy 381.336804 -220.293967) (xy 381.344903 -220.242829) (xy 381.360902 -220.193589)
			(xy 381.384408 -220.147457) (xy 381.41484 -220.10557) (xy 381.45145 -220.06896) (xy 381.493337 -220.038528)
			(xy 381.539469 -220.015022) (xy 381.588709 -219.999023) (xy 381.639847 -219.990924) (xy 381.691621 -219.990924)
			(xy 381.742759 -219.999023) (xy 381.791999 -220.015022) (xy 381.838131 -220.038528) (xy 381.880018 -220.06896)
			(xy 381.916628 -220.10557) (xy 381.94706 -220.147457) (xy 381.970566 -220.193589) (xy 381.986565 -220.242829)
			(xy 381.994664 -220.293967) (xy 381.995172 -220.319854) (xy 381.994628 -220.347561) (xy 381.985442 -220.402208)
			(xy 381.976884 -220.428566) (xy 381.969264 -220.450664) (xy 381.981287 -220.471492) (xy 410.102304 -220.471492)
			(xy 410.102304 -220.062552) (xy 410.102683 -220.052394) (xy 410.110495 -220.03364) (xy 410.124904 -220.019318)
			(xy 410.143706 -220.011621) (xy 410.153866 -220.011244) (xy 411.553406 -220.011244) (xy 411.563534 -220.011722)
			(xy 411.582256 -220.019452) (xy 411.596612 -220.033741) (xy 411.60443 -220.052427) (xy 411.604968 -220.062552)
			(xy 411.604968 -220.471492) (xy 417.646104 -220.471492) (xy 417.646104 -220.062552) (xy 417.646483 -220.052394)
			(xy 417.654295 -220.03364) (xy 417.668704 -220.019318) (xy 417.687506 -220.011621) (xy 417.697666 -220.011244)
			(xy 419.097206 -220.011244) (xy 419.107334 -220.011722) (xy 419.126056 -220.019452) (xy 419.140412 -220.033741)
			(xy 419.14823 -220.052427) (xy 419.148768 -220.062552) (xy 419.148768 -220.471492) (xy 425.189904 -220.471492)
			(xy 425.189904 -220.062552) (xy 425.190283 -220.052394) (xy 425.198095 -220.03364) (xy 425.212504 -220.019318)
			(xy 425.231306 -220.011621) (xy 425.241466 -220.011244) (xy 426.641006 -220.011244) (xy 426.651134 -220.011722)
			(xy 426.669856 -220.019452) (xy 426.684212 -220.033741) (xy 426.69203 -220.052427) (xy 426.692568 -220.062552)
			(xy 426.692568 -220.471492) (xy 432.733704 -220.471492) (xy 432.733704 -220.062552) (xy 432.734083 -220.052394)
			(xy 432.741895 -220.03364) (xy 432.756304 -220.019318) (xy 432.775106 -220.011621) (xy 432.785266 -220.011244)
			(xy 434.184806 -220.011244) (xy 434.194934 -220.011722) (xy 434.213656 -220.019452) (xy 434.228012 -220.033741)
			(xy 434.23583 -220.052427) (xy 434.236368 -220.062552) (xy 434.236368 -220.471492) (xy 440.277504 -220.471492)
			(xy 440.277504 -220.062552) (xy 440.277883 -220.052394) (xy 440.285695 -220.03364) (xy 440.300104 -220.019318)
			(xy 440.318906 -220.011621) (xy 440.329066 -220.011244) (xy 441.728606 -220.011244) (xy 441.738734 -220.011722)
			(xy 441.757456 -220.019452) (xy 441.771812 -220.033741) (xy 441.77963 -220.052427) (xy 441.780168 -220.062552)
			(xy 441.780168 -220.471492) (xy 447.821304 -220.471492) (xy 447.821304 -220.062552) (xy 447.821683 -220.052394)
			(xy 447.829495 -220.03364) (xy 447.843904 -220.019318) (xy 447.862706 -220.011621) (xy 447.872866 -220.011244)
			(xy 449.272406 -220.011244) (xy 449.282534 -220.011722) (xy 449.301256 -220.019452) (xy 449.315612 -220.033741)
			(xy 449.32343 -220.052427) (xy 449.323968 -220.062552) (xy 449.323968 -220.471492) (xy 455.365104 -220.471492)
			(xy 455.365104 -220.062552) (xy 455.365483 -220.052394) (xy 455.373295 -220.03364) (xy 455.387704 -220.019318)
			(xy 455.406506 -220.011621) (xy 455.416666 -220.011244) (xy 456.816206 -220.011244) (xy 456.826334 -220.011722)
			(xy 456.845056 -220.019452) (xy 456.859412 -220.033741) (xy 456.86723 -220.052427) (xy 456.867768 -220.062552)
			(xy 456.867768 -220.471492) (xy 462.908904 -220.471492) (xy 462.908904 -220.062552) (xy 462.909283 -220.052394)
			(xy 462.917095 -220.03364) (xy 462.931504 -220.019318) (xy 462.950306 -220.011621) (xy 462.960466 -220.011244)
			(xy 464.360006 -220.011244) (xy 464.370134 -220.011722) (xy 464.388856 -220.019452) (xy 464.403212 -220.033741)
			(xy 464.41103 -220.052427) (xy 464.411568 -220.062552) (xy 464.411568 -220.471492) (xy 464.411171 -220.48165)
			(xy 464.403372 -220.500408) (xy 464.388967 -220.514733) (xy 464.370166 -220.522427) (xy 464.360006 -220.5228)
			(xy 462.960466 -220.5228) (xy 462.950342 -220.522303) (xy 462.931628 -220.514571) (xy 462.917274 -220.500289)
			(xy 462.909449 -220.481613) (xy 462.908904 -220.471492) (xy 456.867768 -220.471492) (xy 456.867371 -220.48165)
			(xy 456.859572 -220.500408) (xy 456.845167 -220.514733) (xy 456.826366 -220.522427) (xy 456.816206 -220.5228)
			(xy 455.416666 -220.5228) (xy 455.406542 -220.522303) (xy 455.387828 -220.514571) (xy 455.373474 -220.500289)
			(xy 455.365649 -220.481613) (xy 455.365104 -220.471492) (xy 449.323968 -220.471492) (xy 449.323571 -220.48165)
			(xy 449.315772 -220.500408) (xy 449.301367 -220.514733) (xy 449.282566 -220.522427) (xy 449.272406 -220.5228)
			(xy 447.872866 -220.5228) (xy 447.862742 -220.522303) (xy 447.844028 -220.514571) (xy 447.829674 -220.500289)
			(xy 447.821849 -220.481613) (xy 447.821304 -220.471492) (xy 441.780168 -220.471492) (xy 441.779771 -220.48165)
			(xy 441.771972 -220.500408) (xy 441.757567 -220.514733) (xy 441.738766 -220.522427) (xy 441.728606 -220.5228)
			(xy 440.329066 -220.5228) (xy 440.318942 -220.522303) (xy 440.300228 -220.514571) (xy 440.285874 -220.500289)
			(xy 440.278049 -220.481613) (xy 440.277504 -220.471492) (xy 434.236368 -220.471492) (xy 434.235971 -220.48165)
			(xy 434.228172 -220.500408) (xy 434.213767 -220.514733) (xy 434.194966 -220.522427) (xy 434.184806 -220.5228)
			(xy 432.785266 -220.5228) (xy 432.775142 -220.522303) (xy 432.756428 -220.514571) (xy 432.742074 -220.500289)
			(xy 432.734249 -220.481613) (xy 432.733704 -220.471492) (xy 426.692568 -220.471492) (xy 426.692171 -220.48165)
			(xy 426.684372 -220.500408) (xy 426.669967 -220.514733) (xy 426.651166 -220.522427) (xy 426.641006 -220.5228)
			(xy 425.241466 -220.5228) (xy 425.231342 -220.522303) (xy 425.212628 -220.514571) (xy 425.198274 -220.500289)
			(xy 425.190449 -220.481613) (xy 425.189904 -220.471492) (xy 419.148768 -220.471492) (xy 419.148371 -220.48165)
			(xy 419.140572 -220.500408) (xy 419.126167 -220.514733) (xy 419.107366 -220.522427) (xy 419.097206 -220.5228)
			(xy 417.697666 -220.5228) (xy 417.687542 -220.522303) (xy 417.668828 -220.514571) (xy 417.654474 -220.500289)
			(xy 417.646649 -220.481613) (xy 417.646104 -220.471492) (xy 411.604968 -220.471492) (xy 411.604571 -220.48165)
			(xy 411.596772 -220.500408) (xy 411.582367 -220.514733) (xy 411.563566 -220.522427) (xy 411.553406 -220.5228)
			(xy 410.153866 -220.5228) (xy 410.143742 -220.522303) (xy 410.125028 -220.514571) (xy 410.110674 -220.500289)
			(xy 410.102849 -220.481613) (xy 410.102304 -220.471492) (xy 381.981287 -220.471492) (xy 382.174242 -220.805756)
			(xy 382.197102 -220.810074) (xy 382.221908 -220.815252) (xy 382.269647 -220.832242) (xy 382.314225 -220.856337)
			(xy 382.354591 -220.886969) (xy 382.389795 -220.923417) (xy 382.419006 -220.964822) (xy 382.441538 -221.01021)
			(xy 382.45686 -221.058511) (xy 382.46461 -221.108588) (xy 382.465072 -221.133924) (xy 382.464564 -221.159811)
			(xy 382.456465 -221.210949) (xy 382.440466 -221.260189) (xy 382.41696 -221.306321) (xy 382.386528 -221.348208)
			(xy 382.349918 -221.384818) (xy 382.308031 -221.41525) (xy 382.261899 -221.438756) (xy 382.212659 -221.454755)
			(xy 382.161521 -221.462854) (xy 382.109747 -221.462854) (xy 382.058609 -221.454755) (xy 382.009369 -221.438756)
			(xy 381.963237 -221.41525) (xy 381.92135 -221.384818) (xy 381.88474 -221.348208) (xy 381.854308 -221.306321)
			(xy 381.830802 -221.260189) (xy 381.814803 -221.210949) (xy 381.806704 -221.159811) (xy 381.806196 -221.133924)
			(xy 381.806732 -221.106216) (xy 381.815923 -221.051569) (xy 381.824484 -221.025212) (xy 381.832358 -221.003114)
			(xy 381.62738 -220.648022) (xy 381.60452 -220.643704) (xy 381.579694 -220.638559) (xy 381.531915 -220.6216)
			(xy 381.487296 -220.597525) (xy 381.446891 -220.566902) (xy 381.41165 -220.530452) (xy 381.382408 -220.489036)
			(xy 381.359851 -220.44363) (xy 381.344514 -220.395306) (xy 381.336758 -220.345204) (xy 381.336296 -220.319854)
			(xy 380.115572 -220.319854) (xy 380.114963 -220.347508) (xy 380.105639 -220.402026) (xy 380.09703 -220.428312)
			(xy 380.08941 -220.45041) (xy 380.294642 -220.805756) (xy 380.317502 -220.810074) (xy 380.342308 -220.815252)
			(xy 380.390047 -220.832242) (xy 380.434625 -220.856337) (xy 380.474991 -220.886969) (xy 380.510195 -220.923417)
			(xy 380.539406 -220.964822) (xy 380.561938 -221.01021) (xy 380.57726 -221.058511) (xy 380.58501 -221.108588)
			(xy 380.585472 -221.133924) (xy 380.584964 -221.159811) (xy 380.576865 -221.210949) (xy 380.560866 -221.260189)
			(xy 380.53736 -221.306321) (xy 380.506928 -221.348208) (xy 380.470318 -221.384818) (xy 380.428431 -221.41525)
			(xy 380.382299 -221.438756) (xy 380.333059 -221.454755) (xy 380.281921 -221.462854) (xy 380.230147 -221.462854)
			(xy 380.179009 -221.454755) (xy 380.129769 -221.438756) (xy 380.083637 -221.41525) (xy 380.04175 -221.384818)
			(xy 380.00514 -221.348208) (xy 379.974708 -221.306321) (xy 379.951202 -221.260189) (xy 379.935203 -221.210949)
			(xy 379.927104 -221.159811) (xy 379.926596 -221.133924) (xy 379.927132 -221.106216) (xy 379.936323 -221.051569)
			(xy 379.944884 -221.025212) (xy 379.952758 -221.003114) (xy 379.74778 -220.648022) (xy 379.72492 -220.643704)
			(xy 379.700079 -220.638521) (xy 379.652232 -220.621628) (xy 379.60754 -220.5976) (xy 379.567059 -220.567005)
			(xy 379.531748 -220.530566) (xy 379.502439 -220.489145) (xy 379.479827 -220.44372) (xy 379.464446 -220.395365)
			(xy 379.456659 -220.345225) (xy 379.456188 -220.319854) (xy 378.235972 -220.319854) (xy 378.235363 -220.347508)
			(xy 378.226039 -220.402026) (xy 378.21743 -220.428312) (xy 378.20981 -220.45041) (xy 378.415042 -220.805756)
			(xy 378.437902 -220.810074) (xy 378.462708 -220.815252) (xy 378.510447 -220.832242) (xy 378.555025 -220.856337)
			(xy 378.595391 -220.886969) (xy 378.630595 -220.923417) (xy 378.659806 -220.964822) (xy 378.682338 -221.01021)
			(xy 378.69766 -221.058511) (xy 378.70541 -221.108588) (xy 378.705872 -221.133924) (xy 378.705364 -221.159811)
			(xy 378.697265 -221.210949) (xy 378.681266 -221.260189) (xy 378.65776 -221.306321) (xy 378.627328 -221.348208)
			(xy 378.590718 -221.384818) (xy 378.548831 -221.41525) (xy 378.502699 -221.438756) (xy 378.453459 -221.454755)
			(xy 378.402321 -221.462854) (xy 378.350547 -221.462854) (xy 378.299409 -221.454755) (xy 378.250169 -221.438756)
			(xy 378.204037 -221.41525) (xy 378.16215 -221.384818) (xy 378.12554 -221.348208) (xy 378.095108 -221.306321)
			(xy 378.071602 -221.260189) (xy 378.055603 -221.210949) (xy 378.047504 -221.159811) (xy 378.046996 -221.133924)
			(xy 378.047532 -221.106216) (xy 378.056723 -221.051569) (xy 378.065284 -221.025212) (xy 378.073158 -221.003114)
			(xy 377.86818 -220.648022) (xy 377.84532 -220.643704) (xy 377.820479 -220.638521) (xy 377.772632 -220.621628)
			(xy 377.72794 -220.5976) (xy 377.687459 -220.567005) (xy 377.652148 -220.530566) (xy 377.622839 -220.489145)
			(xy 377.600227 -220.44372) (xy 377.584846 -220.395365) (xy 377.577059 -220.345225) (xy 377.576588 -220.319854)
			(xy 376.356372 -220.319854) (xy 376.355763 -220.347508) (xy 376.346439 -220.402026) (xy 376.33783 -220.428312)
			(xy 376.33021 -220.45041) (xy 376.535442 -220.805756) (xy 376.558302 -220.810074) (xy 376.583108 -220.815252)
			(xy 376.630847 -220.832242) (xy 376.675425 -220.856337) (xy 376.715791 -220.886969) (xy 376.750995 -220.923417)
			(xy 376.780206 -220.964822) (xy 376.802738 -221.01021) (xy 376.81806 -221.058511) (xy 376.82581 -221.108588)
			(xy 376.826272 -221.133924) (xy 376.825764 -221.159811) (xy 376.817665 -221.210949) (xy 376.801666 -221.260189)
			(xy 376.77816 -221.306321) (xy 376.747728 -221.348208) (xy 376.711118 -221.384818) (xy 376.669231 -221.41525)
			(xy 376.623099 -221.438756) (xy 376.573859 -221.454755) (xy 376.522721 -221.462854) (xy 376.470947 -221.462854)
			(xy 376.419809 -221.454755) (xy 376.370569 -221.438756) (xy 376.324437 -221.41525) (xy 376.28255 -221.384818)
			(xy 376.24594 -221.348208) (xy 376.215508 -221.306321) (xy 376.192002 -221.260189) (xy 376.176003 -221.210949)
			(xy 376.167904 -221.159811) (xy 376.167396 -221.133924) (xy 376.167932 -221.106216) (xy 376.177123 -221.051569)
			(xy 376.185684 -221.025212) (xy 376.193558 -221.003114) (xy 375.98858 -220.648022) (xy 375.96572 -220.643704)
			(xy 375.940879 -220.638521) (xy 375.893032 -220.621628) (xy 375.84834 -220.5976) (xy 375.807859 -220.567005)
			(xy 375.772548 -220.530566) (xy 375.743239 -220.489145) (xy 375.720627 -220.44372) (xy 375.705246 -220.395365)
			(xy 375.697459 -220.345225) (xy 375.696988 -220.319854) (xy 374.476772 -220.319854) (xy 374.476163 -220.347508)
			(xy 374.466839 -220.402026) (xy 374.45823 -220.428312) (xy 374.45061 -220.45041) (xy 374.655842 -220.805756)
			(xy 374.678702 -220.810074) (xy 374.703508 -220.815252) (xy 374.751247 -220.832242) (xy 374.795825 -220.856337)
			(xy 374.836191 -220.886969) (xy 374.871395 -220.923417) (xy 374.900606 -220.964822) (xy 374.923138 -221.01021)
			(xy 374.93846 -221.058511) (xy 374.94621 -221.108588) (xy 374.946672 -221.133924) (xy 374.946164 -221.159811)
			(xy 374.938065 -221.210949) (xy 374.922066 -221.260189) (xy 374.89856 -221.306321) (xy 374.868128 -221.348208)
			(xy 374.831518 -221.384818) (xy 374.789631 -221.41525) (xy 374.743499 -221.438756) (xy 374.694259 -221.454755)
			(xy 374.643121 -221.462854) (xy 374.591347 -221.462854) (xy 374.540209 -221.454755) (xy 374.490969 -221.438756)
			(xy 374.444837 -221.41525) (xy 374.40295 -221.384818) (xy 374.36634 -221.348208) (xy 374.335908 -221.306321)
			(xy 374.312402 -221.260189) (xy 374.296403 -221.210949) (xy 374.288304 -221.159811) (xy 374.287796 -221.133924)
			(xy 374.288332 -221.106216) (xy 374.297523 -221.051569) (xy 374.306084 -221.025212) (xy 374.313958 -221.003114)
			(xy 374.10898 -220.648022) (xy 374.08612 -220.643704) (xy 374.061279 -220.638521) (xy 374.013432 -220.621628)
			(xy 373.96874 -220.5976) (xy 373.928259 -220.567005) (xy 373.892948 -220.530566) (xy 373.863639 -220.489145)
			(xy 373.841027 -220.44372) (xy 373.825646 -220.395365) (xy 373.817859 -220.345225) (xy 373.817388 -220.319854)
			(xy 372.597172 -220.319854) (xy 372.596563 -220.347508) (xy 372.587239 -220.402026) (xy 372.57863 -220.428312)
			(xy 372.57101 -220.45041) (xy 372.776242 -220.805756) (xy 372.799102 -220.810074) (xy 372.823908 -220.815252)
			(xy 372.871647 -220.832242) (xy 372.916225 -220.856337) (xy 372.956591 -220.886969) (xy 372.991795 -220.923417)
			(xy 373.021006 -220.964822) (xy 373.043538 -221.01021) (xy 373.05886 -221.058511) (xy 373.06661 -221.108588)
			(xy 373.067072 -221.133924) (xy 373.066564 -221.159811) (xy 373.058465 -221.210949) (xy 373.042466 -221.260189)
			(xy 373.01896 -221.306321) (xy 372.988528 -221.348208) (xy 372.951918 -221.384818) (xy 372.910031 -221.41525)
			(xy 372.863899 -221.438756) (xy 372.814659 -221.454755) (xy 372.763521 -221.462854) (xy 372.711747 -221.462854)
			(xy 372.660609 -221.454755) (xy 372.611369 -221.438756) (xy 372.565237 -221.41525) (xy 372.52335 -221.384818)
			(xy 372.48674 -221.348208) (xy 372.456308 -221.306321) (xy 372.432802 -221.260189) (xy 372.416803 -221.210949)
			(xy 372.408704 -221.159811) (xy 372.408196 -221.133924) (xy 372.408732 -221.106216) (xy 372.417923 -221.051569)
			(xy 372.426484 -221.025212) (xy 372.434358 -221.003114) (xy 372.22938 -220.648022) (xy 372.20652 -220.643704)
			(xy 372.181679 -220.638521) (xy 372.133832 -220.621628) (xy 372.08914 -220.5976) (xy 372.048659 -220.567005)
			(xy 372.013348 -220.530566) (xy 371.984039 -220.489145) (xy 371.961427 -220.44372) (xy 371.946046 -220.395365)
			(xy 371.938259 -220.345225) (xy 371.937788 -220.319854) (xy 370.717572 -220.319854) (xy 370.716963 -220.347508)
			(xy 370.707639 -220.402026) (xy 370.69903 -220.428312) (xy 370.69141 -220.45041) (xy 370.896642 -220.805756)
			(xy 370.919502 -220.810074) (xy 370.944308 -220.815252) (xy 370.992047 -220.832242) (xy 371.036625 -220.856337)
			(xy 371.076991 -220.886969) (xy 371.112195 -220.923417) (xy 371.141406 -220.964822) (xy 371.163938 -221.01021)
			(xy 371.17926 -221.058511) (xy 371.18701 -221.108588) (xy 371.187472 -221.133924) (xy 371.186964 -221.159811)
			(xy 371.178865 -221.210949) (xy 371.162866 -221.260189) (xy 371.13936 -221.306321) (xy 371.108928 -221.348208)
			(xy 371.072318 -221.384818) (xy 371.030431 -221.41525) (xy 370.984299 -221.438756) (xy 370.935059 -221.454755)
			(xy 370.883921 -221.462854) (xy 370.832147 -221.462854) (xy 370.781009 -221.454755) (xy 370.731769 -221.438756)
			(xy 370.685637 -221.41525) (xy 370.64375 -221.384818) (xy 370.60714 -221.348208) (xy 370.576708 -221.306321)
			(xy 370.553202 -221.260189) (xy 370.537203 -221.210949) (xy 370.529104 -221.159811) (xy 370.528596 -221.133924)
			(xy 370.529132 -221.106216) (xy 370.538323 -221.051569) (xy 370.546884 -221.025212) (xy 370.554758 -221.003114)
			(xy 370.34978 -220.648022) (xy 370.32692 -220.643704) (xy 370.302079 -220.638521) (xy 370.254232 -220.621628)
			(xy 370.20954 -220.5976) (xy 370.169059 -220.567005) (xy 370.133748 -220.530566) (xy 370.104439 -220.489145)
			(xy 370.081827 -220.44372) (xy 370.066446 -220.395365) (xy 370.058659 -220.345225) (xy 370.058188 -220.319854)
			(xy 368.837972 -220.319854) (xy 368.837363 -220.347508) (xy 368.828039 -220.402026) (xy 368.81943 -220.428312)
			(xy 368.81181 -220.45041) (xy 369.017042 -220.805756) (xy 369.039902 -220.810074) (xy 369.064708 -220.815252)
			(xy 369.112447 -220.832242) (xy 369.157025 -220.856337) (xy 369.197391 -220.886969) (xy 369.232595 -220.923417)
			(xy 369.261806 -220.964822) (xy 369.284338 -221.01021) (xy 369.29966 -221.058511) (xy 369.30741 -221.108588)
			(xy 369.307872 -221.133924) (xy 369.307364 -221.159811) (xy 369.299265 -221.210949) (xy 369.283266 -221.260189)
			(xy 369.25976 -221.306321) (xy 369.229328 -221.348208) (xy 369.192718 -221.384818) (xy 369.150831 -221.41525)
			(xy 369.104699 -221.438756) (xy 369.055459 -221.454755) (xy 369.004321 -221.462854) (xy 368.952547 -221.462854)
			(xy 368.901409 -221.454755) (xy 368.852169 -221.438756) (xy 368.806037 -221.41525) (xy 368.76415 -221.384818)
			(xy 368.72754 -221.348208) (xy 368.697108 -221.306321) (xy 368.673602 -221.260189) (xy 368.657603 -221.210949)
			(xy 368.649504 -221.159811) (xy 368.648996 -221.133924) (xy 368.649532 -221.106216) (xy 368.658723 -221.051569)
			(xy 368.667284 -221.025212) (xy 368.675158 -221.003114) (xy 368.47018 -220.648022) (xy 368.44732 -220.643704)
			(xy 368.422479 -220.638521) (xy 368.374632 -220.621628) (xy 368.32994 -220.5976) (xy 368.289459 -220.567005)
			(xy 368.254148 -220.530566) (xy 368.224839 -220.489145) (xy 368.202227 -220.44372) (xy 368.186846 -220.395365)
			(xy 368.179059 -220.345225) (xy 368.178588 -220.319854) (xy 366.958372 -220.319854) (xy 366.957763 -220.347508)
			(xy 366.948439 -220.402026) (xy 366.93983 -220.428312) (xy 366.93221 -220.45041) (xy 367.137442 -220.805756)
			(xy 367.160302 -220.810074) (xy 367.185108 -220.815252) (xy 367.232847 -220.832242) (xy 367.277425 -220.856337)
			(xy 367.317791 -220.886969) (xy 367.352995 -220.923417) (xy 367.382206 -220.964822) (xy 367.404738 -221.01021)
			(xy 367.42006 -221.058511) (xy 367.42781 -221.108588) (xy 367.428272 -221.133924) (xy 367.427764 -221.159811)
			(xy 367.419665 -221.210949) (xy 367.403666 -221.260189) (xy 367.38016 -221.306321) (xy 367.349728 -221.348208)
			(xy 367.313118 -221.384818) (xy 367.271231 -221.41525) (xy 367.225099 -221.438756) (xy 367.175859 -221.454755)
			(xy 367.124721 -221.462854) (xy 367.072947 -221.462854) (xy 367.021809 -221.454755) (xy 366.972569 -221.438756)
			(xy 366.926437 -221.41525) (xy 366.88455 -221.384818) (xy 366.84794 -221.348208) (xy 366.817508 -221.306321)
			(xy 366.794002 -221.260189) (xy 366.778003 -221.210949) (xy 366.769904 -221.159811) (xy 366.769396 -221.133924)
			(xy 366.769932 -221.106216) (xy 366.779123 -221.051569) (xy 366.787684 -221.025212) (xy 366.795558 -221.003114)
			(xy 366.59058 -220.648022) (xy 366.56772 -220.643704) (xy 366.542879 -220.638521) (xy 366.495032 -220.621628)
			(xy 366.45034 -220.5976) (xy 366.409859 -220.567005) (xy 366.374548 -220.530566) (xy 366.345239 -220.489145)
			(xy 366.322627 -220.44372) (xy 366.307246 -220.395365) (xy 366.299459 -220.345225) (xy 366.298988 -220.319854)
			(xy 365.078772 -220.319854) (xy 365.078163 -220.347508) (xy 365.068839 -220.402026) (xy 365.06023 -220.428312)
			(xy 365.05261 -220.45041) (xy 365.257842 -220.805756) (xy 365.280702 -220.810074) (xy 365.305508 -220.815252)
			(xy 365.353247 -220.832242) (xy 365.397825 -220.856337) (xy 365.438191 -220.886969) (xy 365.473395 -220.923417)
			(xy 365.502606 -220.964822) (xy 365.525138 -221.01021) (xy 365.54046 -221.058511) (xy 365.54821 -221.108588)
			(xy 365.548672 -221.133924) (xy 365.548164 -221.159811) (xy 365.540065 -221.210949) (xy 365.524066 -221.260189)
			(xy 365.50056 -221.306321) (xy 365.470128 -221.348208) (xy 365.433518 -221.384818) (xy 365.391631 -221.41525)
			(xy 365.345499 -221.438756) (xy 365.296259 -221.454755) (xy 365.245121 -221.462854) (xy 365.193347 -221.462854)
			(xy 365.142209 -221.454755) (xy 365.092969 -221.438756) (xy 365.046837 -221.41525) (xy 365.00495 -221.384818)
			(xy 364.96834 -221.348208) (xy 364.937908 -221.306321) (xy 364.914402 -221.260189) (xy 364.898403 -221.210949)
			(xy 364.890304 -221.159811) (xy 364.889796 -221.133924) (xy 364.890332 -221.106216) (xy 364.899523 -221.051569)
			(xy 364.908084 -221.025212) (xy 364.915958 -221.003114) (xy 364.71098 -220.648022) (xy 364.68812 -220.643704)
			(xy 364.663279 -220.638521) (xy 364.615432 -220.621628) (xy 364.57074 -220.5976) (xy 364.530259 -220.567005)
			(xy 364.494948 -220.530566) (xy 364.465639 -220.489145) (xy 364.443027 -220.44372) (xy 364.427646 -220.395365)
			(xy 364.419859 -220.345225) (xy 364.419388 -220.319854) (xy 363.199172 -220.319854) (xy 363.198563 -220.347508)
			(xy 363.189239 -220.402026) (xy 363.18063 -220.428312) (xy 363.17301 -220.45041) (xy 363.378242 -220.805756)
			(xy 363.401102 -220.810074) (xy 363.425908 -220.815252) (xy 363.473647 -220.832242) (xy 363.518225 -220.856337)
			(xy 363.558591 -220.886969) (xy 363.593795 -220.923417) (xy 363.623006 -220.964822) (xy 363.645538 -221.01021)
			(xy 363.66086 -221.058511) (xy 363.66861 -221.108588) (xy 363.669072 -221.133924) (xy 363.668564 -221.159811)
			(xy 363.660465 -221.210949) (xy 363.644466 -221.260189) (xy 363.62096 -221.306321) (xy 363.590528 -221.348208)
			(xy 363.553918 -221.384818) (xy 363.512031 -221.41525) (xy 363.465899 -221.438756) (xy 363.416659 -221.454755)
			(xy 363.365521 -221.462854) (xy 363.313747 -221.462854) (xy 363.262609 -221.454755) (xy 363.213369 -221.438756)
			(xy 363.167237 -221.41525) (xy 363.12535 -221.384818) (xy 363.08874 -221.348208) (xy 363.058308 -221.306321)
			(xy 363.034802 -221.260189) (xy 363.018803 -221.210949) (xy 363.010704 -221.159811) (xy 363.010196 -221.133924)
			(xy 363.010732 -221.106216) (xy 363.019923 -221.051569) (xy 363.028484 -221.025212) (xy 363.036358 -221.003114)
			(xy 362.83138 -220.648022) (xy 362.80852 -220.643704) (xy 362.783679 -220.638521) (xy 362.735832 -220.621628)
			(xy 362.69114 -220.5976) (xy 362.650659 -220.567005) (xy 362.615348 -220.530566) (xy 362.586039 -220.489145)
			(xy 362.563427 -220.44372) (xy 362.548046 -220.395365) (xy 362.540259 -220.345225) (xy 362.539788 -220.319854)
			(xy 361.319572 -220.319854) (xy 361.318963 -220.347508) (xy 361.309639 -220.402026) (xy 361.30103 -220.428312)
			(xy 361.29341 -220.45041) (xy 361.498642 -220.805756) (xy 361.521502 -220.810074) (xy 361.546308 -220.815252)
			(xy 361.594047 -220.832242) (xy 361.638625 -220.856337) (xy 361.678991 -220.886969) (xy 361.714195 -220.923417)
			(xy 361.743406 -220.964822) (xy 361.765938 -221.01021) (xy 361.78126 -221.058511) (xy 361.78901 -221.108588)
			(xy 361.789472 -221.133924) (xy 361.788964 -221.159811) (xy 361.780865 -221.210949) (xy 361.764866 -221.260189)
			(xy 361.74136 -221.306321) (xy 361.710928 -221.348208) (xy 361.674318 -221.384818) (xy 361.632431 -221.41525)
			(xy 361.586299 -221.438756) (xy 361.537059 -221.454755) (xy 361.485921 -221.462854) (xy 361.434147 -221.462854)
			(xy 361.383009 -221.454755) (xy 361.333769 -221.438756) (xy 361.287637 -221.41525) (xy 361.24575 -221.384818)
			(xy 361.20914 -221.348208) (xy 361.178708 -221.306321) (xy 361.155202 -221.260189) (xy 361.139203 -221.210949)
			(xy 361.131104 -221.159811) (xy 361.130596 -221.133924) (xy 361.131132 -221.106216) (xy 361.140323 -221.051569)
			(xy 361.148884 -221.025212) (xy 361.156758 -221.003114) (xy 360.95178 -220.648022) (xy 360.92892 -220.643704)
			(xy 360.904079 -220.638521) (xy 360.856232 -220.621628) (xy 360.81154 -220.5976) (xy 360.771059 -220.567005)
			(xy 360.735748 -220.530566) (xy 360.706439 -220.489145) (xy 360.683827 -220.44372) (xy 360.668446 -220.395365)
			(xy 360.660659 -220.345225) (xy 360.660188 -220.319854) (xy 359.439972 -220.319854) (xy 359.439363 -220.347508)
			(xy 359.430039 -220.402026) (xy 359.42143 -220.428312) (xy 359.41381 -220.45041) (xy 359.619042 -220.805756)
			(xy 359.641902 -220.810074) (xy 359.666708 -220.815252) (xy 359.714447 -220.832242) (xy 359.759025 -220.856337)
			(xy 359.799391 -220.886969) (xy 359.834595 -220.923417) (xy 359.863806 -220.964822) (xy 359.886338 -221.01021)
			(xy 359.90166 -221.058511) (xy 359.90941 -221.108588) (xy 359.909872 -221.133924) (xy 359.909364 -221.159811)
			(xy 359.901265 -221.210949) (xy 359.885266 -221.260189) (xy 359.86176 -221.306321) (xy 359.831328 -221.348208)
			(xy 359.794718 -221.384818) (xy 359.752831 -221.41525) (xy 359.706699 -221.438756) (xy 359.657459 -221.454755)
			(xy 359.606321 -221.462854) (xy 359.554547 -221.462854) (xy 359.503409 -221.454755) (xy 359.454169 -221.438756)
			(xy 359.408037 -221.41525) (xy 359.36615 -221.384818) (xy 359.32954 -221.348208) (xy 359.299108 -221.306321)
			(xy 359.275602 -221.260189) (xy 359.259603 -221.210949) (xy 359.251504 -221.159811) (xy 359.250996 -221.133924)
			(xy 359.251532 -221.106216) (xy 359.260723 -221.051569) (xy 359.269284 -221.025212) (xy 359.277158 -221.003114)
			(xy 359.07218 -220.648022) (xy 359.04932 -220.643704) (xy 359.024479 -220.638521) (xy 358.976632 -220.621628)
			(xy 358.93194 -220.5976) (xy 358.891459 -220.567005) (xy 358.856148 -220.530566) (xy 358.826839 -220.489145)
			(xy 358.804227 -220.44372) (xy 358.788846 -220.395365) (xy 358.781059 -220.345225) (xy 358.780588 -220.319854)
			(xy 357.560372 -220.319854) (xy 357.559763 -220.347508) (xy 357.550439 -220.402026) (xy 357.54183 -220.428312)
			(xy 357.53421 -220.45041) (xy 357.739442 -220.805756) (xy 357.762302 -220.810074) (xy 357.787108 -220.815252)
			(xy 357.834847 -220.832242) (xy 357.879425 -220.856337) (xy 357.919791 -220.886969) (xy 357.954995 -220.923417)
			(xy 357.984206 -220.964822) (xy 358.006738 -221.01021) (xy 358.02206 -221.058511) (xy 358.02981 -221.108588)
			(xy 358.030272 -221.133924) (xy 358.029764 -221.159811) (xy 358.021665 -221.210949) (xy 358.005666 -221.260189)
			(xy 357.98216 -221.306321) (xy 357.951728 -221.348208) (xy 357.915118 -221.384818) (xy 357.873231 -221.41525)
			(xy 357.827099 -221.438756) (xy 357.777859 -221.454755) (xy 357.726721 -221.462854) (xy 357.674947 -221.462854)
			(xy 357.623809 -221.454755) (xy 357.574569 -221.438756) (xy 357.528437 -221.41525) (xy 357.48655 -221.384818)
			(xy 357.44994 -221.348208) (xy 357.419508 -221.306321) (xy 357.396002 -221.260189) (xy 357.380003 -221.210949)
			(xy 357.371904 -221.159811) (xy 357.371396 -221.133924) (xy 357.371932 -221.106216) (xy 357.381123 -221.051569)
			(xy 357.389684 -221.025212) (xy 357.397558 -221.003114) (xy 357.19258 -220.648022) (xy 357.16972 -220.643704)
			(xy 357.144879 -220.638521) (xy 357.097032 -220.621628) (xy 357.05234 -220.5976) (xy 357.011859 -220.567005)
			(xy 356.976548 -220.530566) (xy 356.947239 -220.489145) (xy 356.924627 -220.44372) (xy 356.909246 -220.395365)
			(xy 356.901459 -220.345225) (xy 356.900988 -220.319854) (xy 355.680772 -220.319854) (xy 355.680163 -220.347508)
			(xy 355.670839 -220.402026) (xy 355.66223 -220.428312) (xy 355.65461 -220.45041) (xy 355.859842 -220.805756)
			(xy 355.882702 -220.810074) (xy 355.907508 -220.815252) (xy 355.955247 -220.832242) (xy 355.999825 -220.856337)
			(xy 356.040191 -220.886969) (xy 356.075395 -220.923417) (xy 356.104606 -220.964822) (xy 356.127138 -221.01021)
			(xy 356.14246 -221.058511) (xy 356.15021 -221.108588) (xy 356.150672 -221.133924) (xy 356.150164 -221.159811)
			(xy 356.142065 -221.210949) (xy 356.126066 -221.260189) (xy 356.10256 -221.306321) (xy 356.072128 -221.348208)
			(xy 356.035518 -221.384818) (xy 355.993631 -221.41525) (xy 355.947499 -221.438756) (xy 355.898259 -221.454755)
			(xy 355.847121 -221.462854) (xy 355.795347 -221.462854) (xy 355.744209 -221.454755) (xy 355.694969 -221.438756)
			(xy 355.648837 -221.41525) (xy 355.60695 -221.384818) (xy 355.57034 -221.348208) (xy 355.539908 -221.306321)
			(xy 355.516402 -221.260189) (xy 355.500403 -221.210949) (xy 355.492304 -221.159811) (xy 355.491796 -221.133924)
			(xy 355.492332 -221.106216) (xy 355.501523 -221.051569) (xy 355.510084 -221.025212) (xy 355.517958 -221.003114)
			(xy 355.31298 -220.648022) (xy 355.29012 -220.643704) (xy 355.265279 -220.638521) (xy 355.217432 -220.621628)
			(xy 355.17274 -220.5976) (xy 355.132259 -220.567005) (xy 355.096948 -220.530566) (xy 355.067639 -220.489145)
			(xy 355.045027 -220.44372) (xy 355.029646 -220.395365) (xy 355.021859 -220.345225) (xy 355.021388 -220.319854)
			(xy 353.801172 -220.319854) (xy 353.800563 -220.347508) (xy 353.791239 -220.402026) (xy 353.78263 -220.428312)
			(xy 353.77501 -220.45041) (xy 353.980242 -220.805756) (xy 354.003102 -220.810074) (xy 354.027908 -220.815252)
			(xy 354.075647 -220.832242) (xy 354.120225 -220.856337) (xy 354.160591 -220.886969) (xy 354.195795 -220.923417)
			(xy 354.225006 -220.964822) (xy 354.247538 -221.01021) (xy 354.26286 -221.058511) (xy 354.27061 -221.108588)
			(xy 354.271072 -221.133924) (xy 354.270564 -221.159811) (xy 354.262465 -221.210949) (xy 354.246466 -221.260189)
			(xy 354.22296 -221.306321) (xy 354.192528 -221.348208) (xy 354.155918 -221.384818) (xy 354.114031 -221.41525)
			(xy 354.067899 -221.438756) (xy 354.018659 -221.454755) (xy 353.967521 -221.462854) (xy 353.915747 -221.462854)
			(xy 353.864609 -221.454755) (xy 353.815369 -221.438756) (xy 353.769237 -221.41525) (xy 353.72735 -221.384818)
			(xy 353.69074 -221.348208) (xy 353.660308 -221.306321) (xy 353.636802 -221.260189) (xy 353.620803 -221.210949)
			(xy 353.612704 -221.159811) (xy 353.612196 -221.133924) (xy 353.612732 -221.106216) (xy 353.621923 -221.051569)
			(xy 353.630484 -221.025212) (xy 353.638358 -221.003114) (xy 353.43338 -220.648022) (xy 353.41052 -220.643704)
			(xy 353.385679 -220.638521) (xy 353.337832 -220.621628) (xy 353.29314 -220.5976) (xy 353.252659 -220.567005)
			(xy 353.217348 -220.530566) (xy 353.188039 -220.489145) (xy 353.165427 -220.44372) (xy 353.150046 -220.395365)
			(xy 353.142259 -220.345225) (xy 353.141788 -220.319854) (xy 351.921572 -220.319854) (xy 351.921122 -220.3452)
			(xy 351.913342 -220.395293) (xy 351.897988 -220.443604) (xy 351.875422 -220.488998) (xy 351.846176 -220.530404)
			(xy 351.810939 -220.566847) (xy 351.77054 -220.597469) (xy 351.725931 -220.621548) (xy 351.678163 -220.638518)
			(xy 351.653348 -220.643704) (xy 351.630488 -220.648022) (xy 351.42551 -221.003114) (xy 351.433384 -221.024958)
			(xy 351.441977 -221.051373) (xy 351.451165 -221.106151) (xy 351.451672 -221.133924) (xy 351.451164 -221.159811)
			(xy 351.443065 -221.210949) (xy 351.427066 -221.260189) (xy 351.40356 -221.306321) (xy 351.373128 -221.348208)
			(xy 351.336518 -221.384818) (xy 351.294631 -221.41525) (xy 351.248499 -221.438756) (xy 351.199259 -221.454755)
			(xy 351.148121 -221.462854) (xy 351.096347 -221.462854) (xy 351.045209 -221.454755) (xy 350.995969 -221.438756)
			(xy 350.949837 -221.41525) (xy 350.90795 -221.384818) (xy 350.87134 -221.348208) (xy 350.840908 -221.306321)
			(xy 350.817402 -221.260189) (xy 350.801403 -221.210949) (xy 350.793304 -221.159811) (xy 350.792796 -221.133924)
			(xy 350.511872 -221.133924) (xy 350.511345 -221.161632) (xy 350.502148 -221.216279) (xy 350.493584 -221.242636)
			(xy 350.48571 -221.264734) (xy 350.690688 -221.619572) (xy 350.713548 -221.62389) (xy 350.738367 -221.629064)
			(xy 350.786146 -221.646018) (xy 350.830765 -221.670088) (xy 350.871172 -221.700708) (xy 350.906413 -221.737154)
			(xy 350.935657 -221.778566) (xy 350.958214 -221.823969) (xy 350.973552 -221.872291) (xy 350.98131 -221.922391)
			(xy 350.981772 -221.94774) (xy 352.201988 -221.94774) (xy 352.202465 -221.922395) (xy 352.210245 -221.872306)
			(xy 352.225597 -221.823996) (xy 352.24816 -221.778605) (xy 352.277403 -221.7372) (xy 352.312637 -221.700757)
			(xy 352.353031 -221.670134) (xy 352.397636 -221.646052) (xy 352.445399 -221.629078) (xy 352.470212 -221.62389)
			(xy 352.493072 -221.619572) (xy 352.698304 -221.264226) (xy 352.69043 -221.242128) (xy 352.681965 -221.215883)
			(xy 352.672893 -221.161495) (xy 352.672396 -221.133924) (xy 352.672904 -221.108037) (xy 352.681003 -221.056899)
			(xy 352.697002 -221.007659) (xy 352.720508 -220.961527) (xy 352.75094 -220.91964) (xy 352.78755 -220.88303)
			(xy 352.829437 -220.852598) (xy 352.875569 -220.829092) (xy 352.924809 -220.813093) (xy 352.975947 -220.804994)
			(xy 353.027721 -220.804994) (xy 353.078859 -220.813093) (xy 353.128099 -220.829092) (xy 353.174231 -220.852598)
			(xy 353.216118 -220.88303) (xy 353.252728 -220.91964) (xy 353.28316 -220.961527) (xy 353.306666 -221.007659)
			(xy 353.322665 -221.056899) (xy 353.330764 -221.108037) (xy 353.331272 -221.133924) (xy 353.330842 -221.1593)
			(xy 353.323069 -221.209454) (xy 353.307696 -221.257821) (xy 353.285086 -221.303259) (xy 353.255774 -221.344691)
			(xy 353.220455 -221.381137) (xy 353.179963 -221.411734) (xy 353.135258 -221.435759) (xy 353.087396 -221.452643)
			(xy 353.06254 -221.457774) (xy 353.03968 -221.462092) (xy 352.834956 -221.81693) (xy 352.84283 -221.838774)
			(xy 352.851486 -221.865179) (xy 352.8608 -221.919958) (xy 352.861372 -221.94774) (xy 354.081588 -221.94774)
			(xy 354.082065 -221.922395) (xy 354.089845 -221.872306) (xy 354.105197 -221.823996) (xy 354.12776 -221.778605)
			(xy 354.157003 -221.7372) (xy 354.192237 -221.700757) (xy 354.232631 -221.670134) (xy 354.277236 -221.646052)
			(xy 354.324999 -221.629078) (xy 354.349812 -221.62389) (xy 354.372672 -221.619572) (xy 354.577904 -221.264226)
			(xy 354.57003 -221.242128) (xy 354.561565 -221.215883) (xy 354.552493 -221.161495) (xy 354.551996 -221.133924)
			(xy 354.552504 -221.108037) (xy 354.560603 -221.056899) (xy 354.576602 -221.007659) (xy 354.600108 -220.961527)
			(xy 354.63054 -220.91964) (xy 354.66715 -220.88303) (xy 354.709037 -220.852598) (xy 354.755169 -220.829092)
			(xy 354.804409 -220.813093) (xy 354.855547 -220.804994) (xy 354.907321 -220.804994) (xy 354.958459 -220.813093)
			(xy 355.007699 -220.829092) (xy 355.053831 -220.852598) (xy 355.095718 -220.88303) (xy 355.132328 -220.91964)
			(xy 355.16276 -220.961527) (xy 355.186266 -221.007659) (xy 355.202265 -221.056899) (xy 355.210364 -221.108037)
			(xy 355.210872 -221.133924) (xy 355.210442 -221.1593) (xy 355.202669 -221.209454) (xy 355.187296 -221.257821)
			(xy 355.164686 -221.303259) (xy 355.135374 -221.344691) (xy 355.100055 -221.381137) (xy 355.059563 -221.411734)
			(xy 355.014858 -221.435759) (xy 354.966996 -221.452643) (xy 354.94214 -221.457774) (xy 354.91928 -221.462092)
			(xy 354.714556 -221.81693) (xy 354.72243 -221.838774) (xy 354.731086 -221.865179) (xy 354.7404 -221.919958)
			(xy 354.740972 -221.94774) (xy 355.961188 -221.94774) (xy 355.961665 -221.922395) (xy 355.969445 -221.872306)
			(xy 355.984797 -221.823996) (xy 356.00736 -221.778605) (xy 356.036603 -221.7372) (xy 356.071837 -221.700757)
			(xy 356.112231 -221.670134) (xy 356.156836 -221.646052) (xy 356.204599 -221.629078) (xy 356.229412 -221.62389)
			(xy 356.252272 -221.619572) (xy 356.457504 -221.264226) (xy 356.44963 -221.242128) (xy 356.441165 -221.215883)
			(xy 356.432093 -221.161495) (xy 356.431596 -221.133924) (xy 356.432104 -221.108037) (xy 356.440203 -221.056899)
			(xy 356.456202 -221.007659) (xy 356.479708 -220.961527) (xy 356.51014 -220.91964) (xy 356.54675 -220.88303)
			(xy 356.588637 -220.852598) (xy 356.634769 -220.829092) (xy 356.684009 -220.813093) (xy 356.735147 -220.804994)
			(xy 356.786921 -220.804994) (xy 356.838059 -220.813093) (xy 356.887299 -220.829092) (xy 356.933431 -220.852598)
			(xy 356.975318 -220.88303) (xy 357.011928 -220.91964) (xy 357.04236 -220.961527) (xy 357.065866 -221.007659)
			(xy 357.081865 -221.056899) (xy 357.089964 -221.108037) (xy 357.090472 -221.133924) (xy 357.090042 -221.1593)
			(xy 357.082269 -221.209454) (xy 357.066896 -221.257821) (xy 357.044286 -221.303259) (xy 357.014974 -221.344691)
			(xy 356.979655 -221.381137) (xy 356.939163 -221.411734) (xy 356.894458 -221.435759) (xy 356.846596 -221.452643)
			(xy 356.82174 -221.457774) (xy 356.79888 -221.462092) (xy 356.594156 -221.81693) (xy 356.60203 -221.838774)
			(xy 356.610686 -221.865179) (xy 356.62 -221.919958) (xy 356.620572 -221.94774) (xy 357.841296 -221.94774)
			(xy 357.841727 -221.922404) (xy 357.849489 -221.872329) (xy 357.864819 -221.824032) (xy 357.887358 -221.778648)
			(xy 357.916574 -221.737246) (xy 357.95178 -221.700802) (xy 357.992148 -221.670172) (xy 358.036725 -221.646079)
			(xy 358.084465 -221.629089) (xy 358.109266 -221.62389) (xy 358.132126 -221.619572) (xy 358.337104 -221.26448)
			(xy 358.329484 -221.242382) (xy 358.320964 -221.216211) (xy 358.311771 -221.161949) (xy 358.311196 -221.134432)
			(xy 358.311196 -221.133924) (xy 358.311704 -221.108037) (xy 358.319803 -221.056899) (xy 358.335802 -221.007659)
			(xy 358.359308 -220.961527) (xy 358.38974 -220.91964) (xy 358.42635 -220.88303) (xy 358.468237 -220.852598)
			(xy 358.514369 -220.829092) (xy 358.563609 -220.813093) (xy 358.614747 -220.804994) (xy 358.666521 -220.804994)
			(xy 358.717659 -220.813093) (xy 358.766899 -220.829092) (xy 358.813031 -220.852598) (xy 358.854918 -220.88303)
			(xy 358.891528 -220.91964) (xy 358.92196 -220.961527) (xy 358.945466 -221.007659) (xy 358.961465 -221.056899)
			(xy 358.969564 -221.108037) (xy 358.970072 -221.133924) (xy 358.969679 -221.159291) (xy 358.961926 -221.209429)
			(xy 358.946575 -221.257784) (xy 358.923991 -221.303213) (xy 358.894706 -221.344642) (xy 358.859415 -221.381089)
			(xy 358.818952 -221.411694) (xy 358.774274 -221.435731) (xy 358.726438 -221.452632) (xy 358.701594 -221.457774)
			(xy 358.678734 -221.462092) (xy 358.47401 -221.81693) (xy 358.481884 -221.838774) (xy 358.490481 -221.865188)
			(xy 358.499666 -221.919967) (xy 358.500172 -221.94774) (xy 359.720388 -221.94774) (xy 359.720865 -221.922395)
			(xy 359.728645 -221.872306) (xy 359.743997 -221.823996) (xy 359.76656 -221.778605) (xy 359.795803 -221.7372)
			(xy 359.831037 -221.700757) (xy 359.871431 -221.670134) (xy 359.916036 -221.646052) (xy 359.963799 -221.629078)
			(xy 359.988612 -221.62389) (xy 360.011472 -221.619572) (xy 360.216704 -221.264226) (xy 360.20883 -221.242128)
			(xy 360.200365 -221.215883) (xy 360.191293 -221.161495) (xy 360.190796 -221.133924) (xy 360.191304 -221.108037)
			(xy 360.199403 -221.056899) (xy 360.215402 -221.007659) (xy 360.238908 -220.961527) (xy 360.26934 -220.91964)
			(xy 360.30595 -220.88303) (xy 360.347837 -220.852598) (xy 360.393969 -220.829092) (xy 360.443209 -220.813093)
			(xy 360.494347 -220.804994) (xy 360.546121 -220.804994) (xy 360.597259 -220.813093) (xy 360.646499 -220.829092)
			(xy 360.692631 -220.852598) (xy 360.734518 -220.88303) (xy 360.771128 -220.91964) (xy 360.80156 -220.961527)
			(xy 360.825066 -221.007659) (xy 360.841065 -221.056899) (xy 360.849164 -221.108037) (xy 360.849672 -221.133924)
			(xy 360.849242 -221.1593) (xy 360.841469 -221.209454) (xy 360.826096 -221.257821) (xy 360.803486 -221.303259)
			(xy 360.774174 -221.344691) (xy 360.738855 -221.381137) (xy 360.698363 -221.411734) (xy 360.653658 -221.435759)
			(xy 360.605796 -221.452643) (xy 360.58094 -221.457774) (xy 360.55808 -221.462092) (xy 360.353356 -221.81693)
			(xy 360.36123 -221.838774) (xy 360.369886 -221.865179) (xy 360.3792 -221.919958) (xy 360.379772 -221.94774)
			(xy 361.600496 -221.94774) (xy 361.600927 -221.922404) (xy 361.608689 -221.872329) (xy 361.624019 -221.824032)
			(xy 361.646558 -221.778648) (xy 361.675774 -221.737246) (xy 361.71098 -221.700802) (xy 361.751348 -221.670172)
			(xy 361.795925 -221.646079) (xy 361.843665 -221.629089) (xy 361.868466 -221.62389) (xy 361.891326 -221.619572)
			(xy 362.096304 -221.26448) (xy 362.088684 -221.242382) (xy 362.080164 -221.216211) (xy 362.070971 -221.161949)
			(xy 362.070396 -221.134432) (xy 362.070396 -221.133924) (xy 362.070904 -221.108037) (xy 362.079003 -221.056899)
			(xy 362.095002 -221.007659) (xy 362.118508 -220.961527) (xy 362.14894 -220.91964) (xy 362.18555 -220.88303)
			(xy 362.227437 -220.852598) (xy 362.273569 -220.829092) (xy 362.322809 -220.813093) (xy 362.373947 -220.804994)
			(xy 362.425721 -220.804994) (xy 362.476859 -220.813093) (xy 362.526099 -220.829092) (xy 362.572231 -220.852598)
			(xy 362.614118 -220.88303) (xy 362.650728 -220.91964) (xy 362.68116 -220.961527) (xy 362.704666 -221.007659)
			(xy 362.720665 -221.056899) (xy 362.728764 -221.108037) (xy 362.729272 -221.133924) (xy 362.728879 -221.159291)
			(xy 362.721126 -221.209429) (xy 362.705775 -221.257784) (xy 362.683191 -221.303213) (xy 362.653906 -221.344642)
			(xy 362.618615 -221.381089) (xy 362.578152 -221.411694) (xy 362.533474 -221.435731) (xy 362.485638 -221.452632)
			(xy 362.460794 -221.457774) (xy 362.437934 -221.462092) (xy 362.23321 -221.81693) (xy 362.241084 -221.838774)
			(xy 362.249681 -221.865188) (xy 362.258866 -221.919967) (xy 362.259372 -221.94774) (xy 363.479588 -221.94774)
			(xy 363.480065 -221.922395) (xy 363.487845 -221.872306) (xy 363.503197 -221.823996) (xy 363.52576 -221.778605)
			(xy 363.555003 -221.7372) (xy 363.590237 -221.700757) (xy 363.630631 -221.670134) (xy 363.675236 -221.646052)
			(xy 363.722999 -221.629078) (xy 363.747812 -221.62389) (xy 363.770672 -221.619572) (xy 363.975904 -221.264226)
			(xy 363.96803 -221.242128) (xy 363.959565 -221.215883) (xy 363.950493 -221.161495) (xy 363.949996 -221.133924)
			(xy 363.950504 -221.108037) (xy 363.958603 -221.056899) (xy 363.974602 -221.007659) (xy 363.998108 -220.961527)
			(xy 364.02854 -220.91964) (xy 364.06515 -220.88303) (xy 364.107037 -220.852598) (xy 364.153169 -220.829092)
			(xy 364.202409 -220.813093) (xy 364.253547 -220.804994) (xy 364.305321 -220.804994) (xy 364.356459 -220.813093)
			(xy 364.405699 -220.829092) (xy 364.451831 -220.852598) (xy 364.493718 -220.88303) (xy 364.530328 -220.91964)
			(xy 364.56076 -220.961527) (xy 364.584266 -221.007659) (xy 364.600265 -221.056899) (xy 364.608364 -221.108037)
			(xy 364.608872 -221.133924) (xy 364.608442 -221.1593) (xy 364.600669 -221.209454) (xy 364.585296 -221.257821)
			(xy 364.562686 -221.303259) (xy 364.533374 -221.344691) (xy 364.498055 -221.381137) (xy 364.457563 -221.411734)
			(xy 364.412858 -221.435759) (xy 364.364996 -221.452643) (xy 364.34014 -221.457774) (xy 364.31728 -221.462092)
			(xy 364.112556 -221.81693) (xy 364.12043 -221.838774) (xy 364.129086 -221.865179) (xy 364.1384 -221.919958)
			(xy 364.138972 -221.94774) (xy 365.359188 -221.94774) (xy 365.359665 -221.922395) (xy 365.367445 -221.872306)
			(xy 365.382797 -221.823996) (xy 365.40536 -221.778605) (xy 365.434603 -221.7372) (xy 365.469837 -221.700757)
			(xy 365.510231 -221.670134) (xy 365.554836 -221.646052) (xy 365.602599 -221.629078) (xy 365.627412 -221.62389)
			(xy 365.650272 -221.619572) (xy 365.855504 -221.264226) (xy 365.84763 -221.242128) (xy 365.839165 -221.215883)
			(xy 365.830093 -221.161495) (xy 365.829596 -221.133924) (xy 365.830104 -221.108037) (xy 365.838203 -221.056899)
			(xy 365.854202 -221.007659) (xy 365.877708 -220.961527) (xy 365.90814 -220.91964) (xy 365.94475 -220.88303)
			(xy 365.986637 -220.852598) (xy 366.032769 -220.829092) (xy 366.082009 -220.813093) (xy 366.133147 -220.804994)
			(xy 366.184921 -220.804994) (xy 366.236059 -220.813093) (xy 366.285299 -220.829092) (xy 366.331431 -220.852598)
			(xy 366.373318 -220.88303) (xy 366.409928 -220.91964) (xy 366.44036 -220.961527) (xy 366.463866 -221.007659)
			(xy 366.479865 -221.056899) (xy 366.487964 -221.108037) (xy 366.488472 -221.133924) (xy 366.488042 -221.1593)
			(xy 366.480269 -221.209454) (xy 366.464896 -221.257821) (xy 366.442286 -221.303259) (xy 366.412974 -221.344691)
			(xy 366.377655 -221.381137) (xy 366.337163 -221.411734) (xy 366.292458 -221.435759) (xy 366.244596 -221.452643)
			(xy 366.21974 -221.457774) (xy 366.19688 -221.462092) (xy 365.992156 -221.81693) (xy 366.00003 -221.838774)
			(xy 366.008686 -221.865179) (xy 366.018 -221.919958) (xy 366.018572 -221.94774) (xy 369.118388 -221.94774)
			(xy 369.118865 -221.922395) (xy 369.126645 -221.872306) (xy 369.141997 -221.823996) (xy 369.16456 -221.778605)
			(xy 369.193803 -221.7372) (xy 369.229037 -221.700757) (xy 369.269431 -221.670134) (xy 369.314036 -221.646052)
			(xy 369.361799 -221.629078) (xy 369.386612 -221.62389) (xy 369.409472 -221.619572) (xy 369.614704 -221.264226)
			(xy 369.60683 -221.242128) (xy 369.598365 -221.215883) (xy 369.589293 -221.161495) (xy 369.588796 -221.133924)
			(xy 369.589304 -221.108037) (xy 369.597403 -221.056899) (xy 369.613402 -221.007659) (xy 369.636908 -220.961527)
			(xy 369.66734 -220.91964) (xy 369.70395 -220.88303) (xy 369.745837 -220.852598) (xy 369.791969 -220.829092)
			(xy 369.841209 -220.813093) (xy 369.892347 -220.804994) (xy 369.944121 -220.804994) (xy 369.995259 -220.813093)
			(xy 370.044499 -220.829092) (xy 370.090631 -220.852598) (xy 370.132518 -220.88303) (xy 370.169128 -220.91964)
			(xy 370.19956 -220.961527) (xy 370.223066 -221.007659) (xy 370.239065 -221.056899) (xy 370.247164 -221.108037)
			(xy 370.247672 -221.133924) (xy 370.247242 -221.1593) (xy 370.239469 -221.209454) (xy 370.224096 -221.257821)
			(xy 370.201486 -221.303259) (xy 370.172174 -221.344691) (xy 370.136855 -221.381137) (xy 370.096363 -221.411734)
			(xy 370.051658 -221.435759) (xy 370.003796 -221.452643) (xy 369.97894 -221.457774) (xy 369.95608 -221.462092)
			(xy 369.751356 -221.81693) (xy 369.75923 -221.838774) (xy 369.767886 -221.865179) (xy 369.7772 -221.919958)
			(xy 369.777772 -221.94774) (xy 370.997988 -221.94774) (xy 370.998465 -221.922395) (xy 371.006245 -221.872306)
			(xy 371.021597 -221.823996) (xy 371.04416 -221.778605) (xy 371.073403 -221.7372) (xy 371.108637 -221.700757)
			(xy 371.149031 -221.670134) (xy 371.193636 -221.646052) (xy 371.241399 -221.629078) (xy 371.266212 -221.62389)
			(xy 371.289072 -221.619572) (xy 371.494304 -221.264226) (xy 371.48643 -221.242128) (xy 371.477965 -221.215883)
			(xy 371.468893 -221.161495) (xy 371.468396 -221.133924) (xy 371.468904 -221.108037) (xy 371.477003 -221.056899)
			(xy 371.493002 -221.007659) (xy 371.516508 -220.961527) (xy 371.54694 -220.91964) (xy 371.58355 -220.88303)
			(xy 371.625437 -220.852598) (xy 371.671569 -220.829092) (xy 371.720809 -220.813093) (xy 371.771947 -220.804994)
			(xy 371.823721 -220.804994) (xy 371.874859 -220.813093) (xy 371.924099 -220.829092) (xy 371.970231 -220.852598)
			(xy 372.012118 -220.88303) (xy 372.048728 -220.91964) (xy 372.07916 -220.961527) (xy 372.102666 -221.007659)
			(xy 372.118665 -221.056899) (xy 372.126764 -221.108037) (xy 372.127272 -221.133924) (xy 372.126842 -221.1593)
			(xy 372.119069 -221.209454) (xy 372.103696 -221.257821) (xy 372.081086 -221.303259) (xy 372.051774 -221.344691)
			(xy 372.016455 -221.381137) (xy 371.975963 -221.411734) (xy 371.931258 -221.435759) (xy 371.883396 -221.452643)
			(xy 371.85854 -221.457774) (xy 371.83568 -221.462092) (xy 371.630956 -221.81693) (xy 371.63883 -221.838774)
			(xy 371.647486 -221.865179) (xy 371.6568 -221.919958) (xy 371.657372 -221.94774) (xy 372.877588 -221.94774)
			(xy 372.878065 -221.922395) (xy 372.885845 -221.872306) (xy 372.901197 -221.823996) (xy 372.92376 -221.778605)
			(xy 372.953003 -221.7372) (xy 372.988237 -221.700757) (xy 373.028631 -221.670134) (xy 373.073236 -221.646052)
			(xy 373.120999 -221.629078) (xy 373.145812 -221.62389) (xy 373.168672 -221.619572) (xy 373.373904 -221.264226)
			(xy 373.36603 -221.242128) (xy 373.357565 -221.215883) (xy 373.348493 -221.161495) (xy 373.347996 -221.133924)
			(xy 373.348504 -221.108037) (xy 373.356603 -221.056899) (xy 373.372602 -221.007659) (xy 373.396108 -220.961527)
			(xy 373.42654 -220.91964) (xy 373.46315 -220.88303) (xy 373.505037 -220.852598) (xy 373.551169 -220.829092)
			(xy 373.600409 -220.813093) (xy 373.651547 -220.804994) (xy 373.703321 -220.804994) (xy 373.754459 -220.813093)
			(xy 373.803699 -220.829092) (xy 373.849831 -220.852598) (xy 373.891718 -220.88303) (xy 373.928328 -220.91964)
			(xy 373.95876 -220.961527) (xy 373.982266 -221.007659) (xy 373.998265 -221.056899) (xy 374.006364 -221.108037)
			(xy 374.006872 -221.133924) (xy 374.006442 -221.1593) (xy 373.998669 -221.209454) (xy 373.983296 -221.257821)
			(xy 373.960686 -221.303259) (xy 373.931374 -221.344691) (xy 373.896055 -221.381137) (xy 373.855563 -221.411734)
			(xy 373.810858 -221.435759) (xy 373.762996 -221.452643) (xy 373.73814 -221.457774) (xy 373.71528 -221.462092)
			(xy 373.510556 -221.81693) (xy 373.51843 -221.838774) (xy 373.527086 -221.865179) (xy 373.5364 -221.919958)
			(xy 373.536972 -221.94774) (xy 374.757188 -221.94774) (xy 374.757665 -221.922395) (xy 374.765445 -221.872306)
			(xy 374.780797 -221.823996) (xy 374.80336 -221.778605) (xy 374.832603 -221.7372) (xy 374.867837 -221.700757)
			(xy 374.908231 -221.670134) (xy 374.952836 -221.646052) (xy 375.000599 -221.629078) (xy 375.025412 -221.62389)
			(xy 375.048272 -221.619572) (xy 375.253504 -221.264226) (xy 375.24563 -221.242128) (xy 375.237165 -221.215883)
			(xy 375.228093 -221.161495) (xy 375.227596 -221.133924) (xy 375.228104 -221.108037) (xy 375.236203 -221.056899)
			(xy 375.252202 -221.007659) (xy 375.275708 -220.961527) (xy 375.30614 -220.91964) (xy 375.34275 -220.88303)
			(xy 375.384637 -220.852598) (xy 375.430769 -220.829092) (xy 375.480009 -220.813093) (xy 375.531147 -220.804994)
			(xy 375.582921 -220.804994) (xy 375.634059 -220.813093) (xy 375.683299 -220.829092) (xy 375.729431 -220.852598)
			(xy 375.771318 -220.88303) (xy 375.807928 -220.91964) (xy 375.83836 -220.961527) (xy 375.861866 -221.007659)
			(xy 375.877865 -221.056899) (xy 375.885964 -221.108037) (xy 375.886472 -221.133924) (xy 375.886042 -221.1593)
			(xy 375.878269 -221.209454) (xy 375.862896 -221.257821) (xy 375.840286 -221.303259) (xy 375.810974 -221.344691)
			(xy 375.775655 -221.381137) (xy 375.735163 -221.411734) (xy 375.690458 -221.435759) (xy 375.642596 -221.452643)
			(xy 375.61774 -221.457774) (xy 375.59488 -221.462092) (xy 375.390156 -221.81693) (xy 375.39803 -221.838774)
			(xy 375.406686 -221.865179) (xy 375.416 -221.919958) (xy 375.416572 -221.94774) (xy 376.636788 -221.94774)
			(xy 376.637265 -221.922395) (xy 376.645045 -221.872306) (xy 376.660397 -221.823996) (xy 376.68296 -221.778605)
			(xy 376.712203 -221.7372) (xy 376.747437 -221.700757) (xy 376.787831 -221.670134) (xy 376.832436 -221.646052)
			(xy 376.880199 -221.629078) (xy 376.905012 -221.62389) (xy 376.927872 -221.619572) (xy 377.133104 -221.264226)
			(xy 377.12523 -221.242128) (xy 377.116765 -221.215883) (xy 377.107693 -221.161495) (xy 377.107196 -221.133924)
			(xy 377.107704 -221.108037) (xy 377.115803 -221.056899) (xy 377.131802 -221.007659) (xy 377.155308 -220.961527)
			(xy 377.18574 -220.91964) (xy 377.22235 -220.88303) (xy 377.264237 -220.852598) (xy 377.310369 -220.829092)
			(xy 377.359609 -220.813093) (xy 377.410747 -220.804994) (xy 377.462521 -220.804994) (xy 377.513659 -220.813093)
			(xy 377.562899 -220.829092) (xy 377.609031 -220.852598) (xy 377.650918 -220.88303) (xy 377.687528 -220.91964)
			(xy 377.71796 -220.961527) (xy 377.741466 -221.007659) (xy 377.757465 -221.056899) (xy 377.765564 -221.108037)
			(xy 377.766072 -221.133924) (xy 377.765642 -221.1593) (xy 377.757869 -221.209454) (xy 377.742496 -221.257821)
			(xy 377.719886 -221.303259) (xy 377.690574 -221.344691) (xy 377.655255 -221.381137) (xy 377.614763 -221.411734)
			(xy 377.570058 -221.435759) (xy 377.522196 -221.452643) (xy 377.49734 -221.457774) (xy 377.47448 -221.462092)
			(xy 377.269756 -221.81693) (xy 377.27763 -221.838774) (xy 377.286286 -221.865179) (xy 377.2956 -221.919958)
			(xy 377.296172 -221.94774) (xy 378.516388 -221.94774) (xy 378.516865 -221.922395) (xy 378.524645 -221.872306)
			(xy 378.539997 -221.823996) (xy 378.56256 -221.778605) (xy 378.591803 -221.7372) (xy 378.627037 -221.700757)
			(xy 378.667431 -221.670134) (xy 378.712036 -221.646052) (xy 378.759799 -221.629078) (xy 378.784612 -221.62389)
			(xy 378.807472 -221.619572) (xy 379.012704 -221.264226) (xy 379.00483 -221.242128) (xy 378.996365 -221.215883)
			(xy 378.987293 -221.161495) (xy 378.986796 -221.133924) (xy 378.987304 -221.108037) (xy 378.995403 -221.056899)
			(xy 379.011402 -221.007659) (xy 379.034908 -220.961527) (xy 379.06534 -220.91964) (xy 379.10195 -220.88303)
			(xy 379.143837 -220.852598) (xy 379.189969 -220.829092) (xy 379.239209 -220.813093) (xy 379.290347 -220.804994)
			(xy 379.342121 -220.804994) (xy 379.393259 -220.813093) (xy 379.442499 -220.829092) (xy 379.488631 -220.852598)
			(xy 379.530518 -220.88303) (xy 379.567128 -220.91964) (xy 379.59756 -220.961527) (xy 379.621066 -221.007659)
			(xy 379.637065 -221.056899) (xy 379.645164 -221.108037) (xy 379.645672 -221.133924) (xy 379.645242 -221.1593)
			(xy 379.637469 -221.209454) (xy 379.622096 -221.257821) (xy 379.599486 -221.303259) (xy 379.570174 -221.344691)
			(xy 379.534855 -221.381137) (xy 379.494363 -221.411734) (xy 379.449658 -221.435759) (xy 379.401796 -221.452643)
			(xy 379.37694 -221.457774) (xy 379.35408 -221.462092) (xy 379.149356 -221.81693) (xy 379.15723 -221.838774)
			(xy 379.165886 -221.865179) (xy 379.1752 -221.919958) (xy 379.175772 -221.94774) (xy 380.395988 -221.94774)
			(xy 380.396465 -221.922395) (xy 380.404245 -221.872306) (xy 380.419597 -221.823996) (xy 380.44216 -221.778605)
			(xy 380.471403 -221.7372) (xy 380.506637 -221.700757) (xy 380.547031 -221.670134) (xy 380.591636 -221.646052)
			(xy 380.639399 -221.629078) (xy 380.664212 -221.62389) (xy 380.687072 -221.619572) (xy 380.89205 -221.263972)
			(xy 380.88443 -221.242128) (xy 380.875981 -221.215945) (xy 380.866909 -221.161685) (xy 380.866396 -221.134178)
			(xy 380.866396 -221.133924) (xy 380.866904 -221.108037) (xy 380.875003 -221.056899) (xy 380.891002 -221.007659)
			(xy 380.914508 -220.961527) (xy 380.94494 -220.91964) (xy 380.98155 -220.88303) (xy 381.023437 -220.852598)
			(xy 381.069569 -220.829092) (xy 381.118809 -220.813093) (xy 381.169947 -220.804994) (xy 381.221721 -220.804994)
			(xy 381.272859 -220.813093) (xy 381.322099 -220.829092) (xy 381.368231 -220.852598) (xy 381.410118 -220.88303)
			(xy 381.446728 -220.91964) (xy 381.47716 -220.961527) (xy 381.500666 -221.007659) (xy 381.516665 -221.056899)
			(xy 381.524764 -221.108037) (xy 381.525272 -221.133924) (xy 381.524879 -221.159291) (xy 381.517126 -221.209429)
			(xy 381.501775 -221.257784) (xy 381.479191 -221.303213) (xy 381.449906 -221.344642) (xy 381.414615 -221.381089)
			(xy 381.374152 -221.411694) (xy 381.329474 -221.435731) (xy 381.281638 -221.452632) (xy 381.256794 -221.457774)
			(xy 381.233934 -221.462092) (xy 381.02921 -221.81693) (xy 381.03683 -221.838774) (xy 381.045444 -221.865059)
			(xy 381.054766 -221.919578) (xy 381.055372 -221.947232) (xy 381.055372 -221.94774) (xy 382.275588 -221.94774)
			(xy 382.276065 -221.922395) (xy 382.283845 -221.872306) (xy 382.299197 -221.823996) (xy 382.32176 -221.778605)
			(xy 382.351003 -221.7372) (xy 382.386237 -221.700757) (xy 382.426631 -221.670134) (xy 382.471236 -221.646052)
			(xy 382.518999 -221.629078) (xy 382.543812 -221.62389) (xy 382.566672 -221.619572) (xy 382.77165 -221.263972)
			(xy 382.76403 -221.242128) (xy 382.755581 -221.215945) (xy 382.746509 -221.161685) (xy 382.745996 -221.134178)
			(xy 382.745996 -221.133924) (xy 382.746504 -221.108037) (xy 382.754603 -221.056899) (xy 382.770602 -221.007659)
			(xy 382.794108 -220.961527) (xy 382.82454 -220.91964) (xy 382.86115 -220.88303) (xy 382.903037 -220.852598)
			(xy 382.949169 -220.829092) (xy 382.998409 -220.813093) (xy 383.049547 -220.804994) (xy 383.101321 -220.804994)
			(xy 383.152459 -220.813093) (xy 383.201699 -220.829092) (xy 383.247831 -220.852598) (xy 383.289718 -220.88303)
			(xy 383.326328 -220.91964) (xy 383.35676 -220.961527) (xy 383.380266 -221.007659) (xy 383.396265 -221.056899)
			(xy 383.404364 -221.108037) (xy 383.404872 -221.133924) (xy 383.404479 -221.159291) (xy 383.396726 -221.209429)
			(xy 383.381375 -221.257784) (xy 383.358791 -221.303213) (xy 383.345952 -221.321376) (xy 406.002236 -221.321376)
			(xy 406.002236 -220.912436) (xy 406.002652 -220.90228) (xy 406.010442 -220.883521) (xy 406.024842 -220.869195)
			(xy 406.04364 -220.861501) (xy 406.053798 -220.861128) (xy 407.453338 -220.861128) (xy 407.463466 -220.861595)
			(xy 407.482185 -220.869333) (xy 407.49654 -220.883625) (xy 407.50436 -220.902311) (xy 407.5049 -220.912436)
			(xy 407.5049 -221.321376) (xy 413.546036 -221.321376) (xy 413.546036 -220.912436) (xy 413.546452 -220.90228)
			(xy 413.554242 -220.883521) (xy 413.568642 -220.869195) (xy 413.58744 -220.861501) (xy 413.597598 -220.861128)
			(xy 414.997138 -220.861128) (xy 415.007266 -220.861595) (xy 415.025985 -220.869333) (xy 415.04034 -220.883625)
			(xy 415.04816 -220.902311) (xy 415.0487 -220.912436) (xy 415.0487 -221.321376) (xy 421.089836 -221.321376)
			(xy 421.089836 -220.912436) (xy 421.090252 -220.90228) (xy 421.098042 -220.883521) (xy 421.112442 -220.869195)
			(xy 421.13124 -220.861501) (xy 421.141398 -220.861128) (xy 422.540938 -220.861128) (xy 422.551066 -220.861595)
			(xy 422.569785 -220.869333) (xy 422.58414 -220.883625) (xy 422.59196 -220.902311) (xy 422.5925 -220.912436)
			(xy 422.5925 -221.321376) (xy 428.633636 -221.321376) (xy 428.633636 -220.912436) (xy 428.634052 -220.90228)
			(xy 428.641842 -220.883521) (xy 428.656242 -220.869195) (xy 428.67504 -220.861501) (xy 428.685198 -220.861128)
			(xy 430.084738 -220.861128) (xy 430.094866 -220.861595) (xy 430.113585 -220.869333) (xy 430.12794 -220.883625)
			(xy 430.13576 -220.902311) (xy 430.1363 -220.912436) (xy 430.1363 -221.321376) (xy 436.177436 -221.321376)
			(xy 436.177436 -220.912436) (xy 436.177852 -220.90228) (xy 436.185642 -220.883521) (xy 436.200042 -220.869195)
			(xy 436.21884 -220.861501) (xy 436.228998 -220.861128) (xy 437.628538 -220.861128) (xy 437.638666 -220.861595)
			(xy 437.657385 -220.869333) (xy 437.67174 -220.883625) (xy 437.67956 -220.902311) (xy 437.6801 -220.912436)
			(xy 437.6801 -221.321376) (xy 443.721236 -221.321376) (xy 443.721236 -220.912436) (xy 443.721652 -220.90228)
			(xy 443.729442 -220.883521) (xy 443.743842 -220.869195) (xy 443.76264 -220.861501) (xy 443.772798 -220.861128)
			(xy 445.172338 -220.861128) (xy 445.182466 -220.861595) (xy 445.201185 -220.869333) (xy 445.21554 -220.883625)
			(xy 445.22336 -220.902311) (xy 445.2239 -220.912436) (xy 445.2239 -221.321376) (xy 451.265036 -221.321376)
			(xy 451.265036 -220.912436) (xy 451.265452 -220.90228) (xy 451.273242 -220.883521) (xy 451.287642 -220.869195)
			(xy 451.30644 -220.861501) (xy 451.316598 -220.861128) (xy 452.716138 -220.861128) (xy 452.726266 -220.861595)
			(xy 452.744985 -220.869333) (xy 452.75934 -220.883625) (xy 452.76716 -220.902311) (xy 452.7677 -220.912436)
			(xy 452.7677 -221.321376) (xy 458.808836 -221.321376) (xy 458.808836 -220.912436) (xy 458.809252 -220.90228)
			(xy 458.817042 -220.883521) (xy 458.831442 -220.869195) (xy 458.85024 -220.861501) (xy 458.860398 -220.861128)
			(xy 460.259938 -220.861128) (xy 460.270066 -220.861595) (xy 460.288785 -220.869333) (xy 460.30314 -220.883625)
			(xy 460.31096 -220.902311) (xy 460.3115 -220.912436) (xy 460.3115 -221.321376) (xy 460.311059 -221.331529)
			(xy 460.303271 -221.350281) (xy 460.28888 -221.364605) (xy 460.270092 -221.372305) (xy 460.259938 -221.372684)
			(xy 458.860398 -221.372684) (xy 458.850274 -221.372176) (xy 458.831558 -221.364452) (xy 458.817202 -221.350172)
			(xy 458.809379 -221.331497) (xy 458.808836 -221.321376) (xy 452.7677 -221.321376) (xy 452.767259 -221.331529)
			(xy 452.759471 -221.350281) (xy 452.74508 -221.364605) (xy 452.726292 -221.372305) (xy 452.716138 -221.372684)
			(xy 451.316598 -221.372684) (xy 451.306474 -221.372176) (xy 451.287758 -221.364452) (xy 451.273402 -221.350172)
			(xy 451.265579 -221.331497) (xy 451.265036 -221.321376) (xy 445.2239 -221.321376) (xy 445.223459 -221.331529)
			(xy 445.215671 -221.350281) (xy 445.20128 -221.364605) (xy 445.182492 -221.372305) (xy 445.172338 -221.372684)
			(xy 443.772798 -221.372684) (xy 443.762674 -221.372176) (xy 443.743958 -221.364452) (xy 443.729602 -221.350172)
			(xy 443.721779 -221.331497) (xy 443.721236 -221.321376) (xy 437.6801 -221.321376) (xy 437.679659 -221.331529)
			(xy 437.671871 -221.350281) (xy 437.65748 -221.364605) (xy 437.638692 -221.372305) (xy 437.628538 -221.372684)
			(xy 436.228998 -221.372684) (xy 436.218874 -221.372176) (xy 436.200158 -221.364452) (xy 436.185802 -221.350172)
			(xy 436.177979 -221.331497) (xy 436.177436 -221.321376) (xy 430.1363 -221.321376) (xy 430.135859 -221.331529)
			(xy 430.128071 -221.350281) (xy 430.11368 -221.364605) (xy 430.094892 -221.372305) (xy 430.084738 -221.372684)
			(xy 428.685198 -221.372684) (xy 428.675074 -221.372176) (xy 428.656358 -221.364452) (xy 428.642002 -221.350172)
			(xy 428.634179 -221.331497) (xy 428.633636 -221.321376) (xy 422.5925 -221.321376) (xy 422.592059 -221.331529)
			(xy 422.584271 -221.350281) (xy 422.56988 -221.364605) (xy 422.551092 -221.372305) (xy 422.540938 -221.372684)
			(xy 421.141398 -221.372684) (xy 421.131274 -221.372176) (xy 421.112558 -221.364452) (xy 421.098202 -221.350172)
			(xy 421.090379 -221.331497) (xy 421.089836 -221.321376) (xy 415.0487 -221.321376) (xy 415.048259 -221.331529)
			(xy 415.040471 -221.350281) (xy 415.02608 -221.364605) (xy 415.007292 -221.372305) (xy 414.997138 -221.372684)
			(xy 413.597598 -221.372684) (xy 413.587474 -221.372176) (xy 413.568758 -221.364452) (xy 413.554402 -221.350172)
			(xy 413.546579 -221.331497) (xy 413.546036 -221.321376) (xy 407.5049 -221.321376) (xy 407.504459 -221.331529)
			(xy 407.496671 -221.350281) (xy 407.48228 -221.364605) (xy 407.463492 -221.372305) (xy 407.453338 -221.372684)
			(xy 406.053798 -221.372684) (xy 406.043674 -221.372176) (xy 406.024958 -221.364452) (xy 406.010602 -221.350172)
			(xy 406.002779 -221.331497) (xy 406.002236 -221.321376) (xy 383.345952 -221.321376) (xy 383.329506 -221.344642)
			(xy 383.294215 -221.381089) (xy 383.253752 -221.411694) (xy 383.209074 -221.435731) (xy 383.161238 -221.452632)
			(xy 383.136394 -221.457774) (xy 383.113534 -221.462092) (xy 382.90881 -221.81693) (xy 382.91643 -221.838774)
			(xy 382.925044 -221.865059) (xy 382.934366 -221.919578) (xy 382.934972 -221.947232) (xy 382.934972 -221.94774)
			(xy 382.934464 -221.973647) (xy 382.926358 -222.024824) (xy 382.910346 -222.074103) (xy 382.886823 -222.12027)
			(xy 382.856367 -222.162189) (xy 382.847042 -222.171514) (xy 410.102304 -222.171514) (xy 410.102304 -221.762574)
			(xy 410.102811 -221.752419) (xy 410.110588 -221.733655) (xy 410.124949 -221.719292) (xy 410.143711 -221.711513)
			(xy 410.153866 -221.711012) (xy 411.553406 -221.711012) (xy 411.563561 -221.711528) (xy 411.582325 -221.7193)
			(xy 411.596689 -221.733658) (xy 411.604468 -221.752419) (xy 411.604968 -221.762574) (xy 411.604968 -222.171514)
			(xy 417.646104 -222.171514) (xy 417.646104 -221.762574) (xy 417.646611 -221.752419) (xy 417.654388 -221.733655)
			(xy 417.668749 -221.719292) (xy 417.687511 -221.711513) (xy 417.697666 -221.711012) (xy 419.097206 -221.711012)
			(xy 419.107361 -221.711528) (xy 419.126125 -221.7193) (xy 419.140489 -221.733658) (xy 419.148268 -221.752419)
			(xy 419.148768 -221.762574) (xy 419.148768 -222.171514) (xy 425.189904 -222.171514) (xy 425.189904 -221.762574)
			(xy 425.190411 -221.752419) (xy 425.198188 -221.733655) (xy 425.212549 -221.719292) (xy 425.231311 -221.711513)
			(xy 425.241466 -221.711012) (xy 426.641006 -221.711012) (xy 426.651161 -221.711528) (xy 426.669925 -221.7193)
			(xy 426.684289 -221.733658) (xy 426.692068 -221.752419) (xy 426.692568 -221.762574) (xy 426.692568 -222.171514)
			(xy 432.733704 -222.171514) (xy 432.733704 -221.762574) (xy 432.734211 -221.752419) (xy 432.741988 -221.733655)
			(xy 432.756349 -221.719292) (xy 432.775111 -221.711513) (xy 432.785266 -221.711012) (xy 434.184806 -221.711012)
			(xy 434.194961 -221.711528) (xy 434.213725 -221.7193) (xy 434.228089 -221.733658) (xy 434.235868 -221.752419)
			(xy 434.236368 -221.762574) (xy 434.236368 -222.171514) (xy 440.277504 -222.171514) (xy 440.277504 -221.762574)
			(xy 440.278011 -221.752419) (xy 440.285788 -221.733655) (xy 440.300149 -221.719292) (xy 440.318911 -221.711513)
			(xy 440.329066 -221.711012) (xy 441.728606 -221.711012) (xy 441.738761 -221.711528) (xy 441.757525 -221.7193)
			(xy 441.771889 -221.733658) (xy 441.779668 -221.752419) (xy 441.780168 -221.762574) (xy 441.780168 -222.171514)
			(xy 447.821304 -222.171514) (xy 447.821304 -221.762574) (xy 447.821811 -221.752419) (xy 447.829588 -221.733655)
			(xy 447.843949 -221.719292) (xy 447.862711 -221.711513) (xy 447.872866 -221.711012) (xy 449.272406 -221.711012)
			(xy 449.282561 -221.711528) (xy 449.301325 -221.7193) (xy 449.315689 -221.733658) (xy 449.323468 -221.752419)
			(xy 449.323968 -221.762574) (xy 449.323968 -222.171514) (xy 455.365104 -222.171514) (xy 455.365104 -221.762574)
			(xy 455.365611 -221.752419) (xy 455.373388 -221.733655) (xy 455.387749 -221.719292) (xy 455.406511 -221.711513)
			(xy 455.416666 -221.711012) (xy 456.816206 -221.711012) (xy 456.826361 -221.711528) (xy 456.845125 -221.7193)
			(xy 456.859489 -221.733658) (xy 456.867268 -221.752419) (xy 456.867768 -221.762574) (xy 456.867768 -222.171514)
			(xy 462.908904 -222.171514) (xy 462.908904 -221.762574) (xy 462.909411 -221.752419) (xy 462.917188 -221.733655)
			(xy 462.931549 -221.719292) (xy 462.950311 -221.711513) (xy 462.960466 -221.711012) (xy 464.360006 -221.711012)
			(xy 464.370161 -221.711528) (xy 464.388925 -221.7193) (xy 464.403289 -221.733658) (xy 464.411068 -221.752419)
			(xy 464.411568 -221.762574) (xy 464.411568 -222.171514) (xy 464.411078 -222.181672) (xy 464.4033 -222.20044)
			(xy 464.388933 -222.214805) (xy 464.370164 -222.22258) (xy 464.360006 -222.223076) (xy 462.960466 -222.223076)
			(xy 462.950308 -222.222595) (xy 462.931541 -222.214812) (xy 462.917177 -222.200443) (xy 462.909401 -222.181672)
			(xy 462.908904 -222.171514) (xy 456.867768 -222.171514) (xy 456.867278 -222.181672) (xy 456.8595 -222.20044)
			(xy 456.845133 -222.214805) (xy 456.826364 -222.22258) (xy 456.816206 -222.223076) (xy 455.416666 -222.223076)
			(xy 455.406508 -222.222595) (xy 455.387741 -222.214812) (xy 455.373377 -222.200443) (xy 455.365601 -222.181672)
			(xy 455.365104 -222.171514) (xy 449.323968 -222.171514) (xy 449.323478 -222.181672) (xy 449.3157 -222.20044)
			(xy 449.301333 -222.214805) (xy 449.282564 -222.22258) (xy 449.272406 -222.223076) (xy 447.872866 -222.223076)
			(xy 447.862708 -222.222595) (xy 447.843941 -222.214812) (xy 447.829577 -222.200443) (xy 447.821801 -222.181672)
			(xy 447.821304 -222.171514) (xy 441.780168 -222.171514) (xy 441.779678 -222.181672) (xy 441.7719 -222.20044)
			(xy 441.757533 -222.214805) (xy 441.738764 -222.22258) (xy 441.728606 -222.223076) (xy 440.329066 -222.223076)
			(xy 440.318908 -222.222595) (xy 440.300141 -222.214812) (xy 440.285777 -222.200443) (xy 440.278001 -222.181672)
			(xy 440.277504 -222.171514) (xy 434.236368 -222.171514) (xy 434.235878 -222.181672) (xy 434.2281 -222.20044)
			(xy 434.213733 -222.214805) (xy 434.194964 -222.22258) (xy 434.184806 -222.223076) (xy 432.785266 -222.223076)
			(xy 432.775108 -222.222595) (xy 432.756341 -222.214812) (xy 432.741977 -222.200443) (xy 432.734201 -222.181672)
			(xy 432.733704 -222.171514) (xy 426.692568 -222.171514) (xy 426.692078 -222.181672) (xy 426.6843 -222.20044)
			(xy 426.669933 -222.214805) (xy 426.651164 -222.22258) (xy 426.641006 -222.223076) (xy 425.241466 -222.223076)
			(xy 425.231308 -222.222595) (xy 425.212541 -222.214812) (xy 425.198177 -222.200443) (xy 425.190401 -222.181672)
			(xy 425.189904 -222.171514) (xy 419.148768 -222.171514) (xy 419.148278 -222.181672) (xy 419.1405 -222.20044)
			(xy 419.126133 -222.214805) (xy 419.107364 -222.22258) (xy 419.097206 -222.223076) (xy 417.697666 -222.223076)
			(xy 417.687508 -222.222595) (xy 417.668741 -222.214812) (xy 417.654377 -222.200443) (xy 417.646601 -222.181672)
			(xy 417.646104 -222.171514) (xy 411.604968 -222.171514) (xy 411.604478 -222.181672) (xy 411.5967 -222.20044)
			(xy 411.582333 -222.214805) (xy 411.563564 -222.22258) (xy 411.553406 -222.223076) (xy 410.153866 -222.223076)
			(xy 410.143708 -222.222595) (xy 410.124941 -222.214812) (xy 410.110577 -222.200443) (xy 410.102801 -222.181672)
			(xy 410.102304 -222.171514) (xy 382.847042 -222.171514) (xy 382.819729 -222.198827) (xy 382.77781 -222.229283)
			(xy 382.731643 -222.252806) (xy 382.682364 -222.268818) (xy 382.631187 -222.276924) (xy 382.579373 -222.276924)
			(xy 382.528196 -222.268818) (xy 382.478917 -222.252806) (xy 382.43275 -222.229283) (xy 382.390831 -222.198827)
			(xy 382.354193 -222.162189) (xy 382.323737 -222.12027) (xy 382.300214 -222.074103) (xy 382.284202 -222.024824)
			(xy 382.276096 -221.973647) (xy 382.275588 -221.94774) (xy 381.055372 -221.94774) (xy 381.054864 -221.973647)
			(xy 381.046758 -222.024824) (xy 381.030746 -222.074103) (xy 381.007223 -222.12027) (xy 380.976767 -222.162189)
			(xy 380.940129 -222.198827) (xy 380.89821 -222.229283) (xy 380.852043 -222.252806) (xy 380.802764 -222.268818)
			(xy 380.751587 -222.276924) (xy 380.699773 -222.276924) (xy 380.648596 -222.268818) (xy 380.599317 -222.252806)
			(xy 380.55315 -222.229283) (xy 380.511231 -222.198827) (xy 380.474593 -222.162189) (xy 380.444137 -222.12027)
			(xy 380.420614 -222.074103) (xy 380.404602 -222.024824) (xy 380.396496 -221.973647) (xy 380.395988 -221.94774)
			(xy 379.175772 -221.94774) (xy 379.175264 -221.973647) (xy 379.167158 -222.024824) (xy 379.151146 -222.074103)
			(xy 379.127623 -222.12027) (xy 379.097167 -222.162189) (xy 379.060529 -222.198827) (xy 379.01861 -222.229283)
			(xy 378.972443 -222.252806) (xy 378.923164 -222.268818) (xy 378.871987 -222.276924) (xy 378.820173 -222.276924)
			(xy 378.768996 -222.268818) (xy 378.719717 -222.252806) (xy 378.67355 -222.229283) (xy 378.631631 -222.198827)
			(xy 378.594993 -222.162189) (xy 378.564537 -222.12027) (xy 378.541014 -222.074103) (xy 378.525002 -222.024824)
			(xy 378.516896 -221.973647) (xy 378.516388 -221.94774) (xy 377.296172 -221.94774) (xy 377.295664 -221.973647)
			(xy 377.287558 -222.024824) (xy 377.271546 -222.074103) (xy 377.248023 -222.12027) (xy 377.217567 -222.162189)
			(xy 377.180929 -222.198827) (xy 377.13901 -222.229283) (xy 377.092843 -222.252806) (xy 377.043564 -222.268818)
			(xy 376.992387 -222.276924) (xy 376.940573 -222.276924) (xy 376.889396 -222.268818) (xy 376.840117 -222.252806)
			(xy 376.79395 -222.229283) (xy 376.752031 -222.198827) (xy 376.715393 -222.162189) (xy 376.684937 -222.12027)
			(xy 376.661414 -222.074103) (xy 376.645402 -222.024824) (xy 376.637296 -221.973647) (xy 376.636788 -221.94774)
			(xy 375.416572 -221.94774) (xy 375.416064 -221.973647) (xy 375.407958 -222.024824) (xy 375.391946 -222.074103)
			(xy 375.368423 -222.12027) (xy 375.337967 -222.162189) (xy 375.301329 -222.198827) (xy 375.25941 -222.229283)
			(xy 375.213243 -222.252806) (xy 375.163964 -222.268818) (xy 375.112787 -222.276924) (xy 375.060973 -222.276924)
			(xy 375.009796 -222.268818) (xy 374.960517 -222.252806) (xy 374.91435 -222.229283) (xy 374.872431 -222.198827)
			(xy 374.835793 -222.162189) (xy 374.805337 -222.12027) (xy 374.781814 -222.074103) (xy 374.765802 -222.024824)
			(xy 374.757696 -221.973647) (xy 374.757188 -221.94774) (xy 373.536972 -221.94774) (xy 373.536464 -221.973647)
			(xy 373.528358 -222.024824) (xy 373.512346 -222.074103) (xy 373.488823 -222.12027) (xy 373.458367 -222.162189)
			(xy 373.421729 -222.198827) (xy 373.37981 -222.229283) (xy 373.333643 -222.252806) (xy 373.284364 -222.268818)
			(xy 373.233187 -222.276924) (xy 373.181373 -222.276924) (xy 373.130196 -222.268818) (xy 373.080917 -222.252806)
			(xy 373.03475 -222.229283) (xy 372.992831 -222.198827) (xy 372.956193 -222.162189) (xy 372.925737 -222.12027)
			(xy 372.902214 -222.074103) (xy 372.886202 -222.024824) (xy 372.878096 -221.973647) (xy 372.877588 -221.94774)
			(xy 371.657372 -221.94774) (xy 371.656864 -221.973647) (xy 371.648758 -222.024824) (xy 371.632746 -222.074103)
			(xy 371.609223 -222.12027) (xy 371.578767 -222.162189) (xy 371.542129 -222.198827) (xy 371.50021 -222.229283)
			(xy 371.454043 -222.252806) (xy 371.404764 -222.268818) (xy 371.353587 -222.276924) (xy 371.301773 -222.276924)
			(xy 371.250596 -222.268818) (xy 371.201317 -222.252806) (xy 371.15515 -222.229283) (xy 371.113231 -222.198827)
			(xy 371.076593 -222.162189) (xy 371.046137 -222.12027) (xy 371.022614 -222.074103) (xy 371.006602 -222.024824)
			(xy 370.998496 -221.973647) (xy 370.997988 -221.94774) (xy 369.777772 -221.94774) (xy 369.777264 -221.973647)
			(xy 369.769158 -222.024824) (xy 369.753146 -222.074103) (xy 369.729623 -222.12027) (xy 369.699167 -222.162189)
			(xy 369.662529 -222.198827) (xy 369.62061 -222.229283) (xy 369.574443 -222.252806) (xy 369.525164 -222.268818)
			(xy 369.473987 -222.276924) (xy 369.422173 -222.276924) (xy 369.370996 -222.268818) (xy 369.321717 -222.252806)
			(xy 369.27555 -222.229283) (xy 369.233631 -222.198827) (xy 369.196993 -222.162189) (xy 369.166537 -222.12027)
			(xy 369.143014 -222.074103) (xy 369.127002 -222.024824) (xy 369.118896 -221.973647) (xy 369.118388 -221.94774)
			(xy 366.018572 -221.94774) (xy 366.018064 -221.973647) (xy 366.009958 -222.024824) (xy 365.993946 -222.074103)
			(xy 365.970423 -222.12027) (xy 365.939967 -222.162189) (xy 365.903329 -222.198827) (xy 365.86141 -222.229283)
			(xy 365.815243 -222.252806) (xy 365.765964 -222.268818) (xy 365.714787 -222.276924) (xy 365.662973 -222.276924)
			(xy 365.611796 -222.268818) (xy 365.562517 -222.252806) (xy 365.51635 -222.229283) (xy 365.474431 -222.198827)
			(xy 365.437793 -222.162189) (xy 365.407337 -222.12027) (xy 365.383814 -222.074103) (xy 365.367802 -222.024824)
			(xy 365.359696 -221.973647) (xy 365.359188 -221.94774) (xy 364.138972 -221.94774) (xy 364.138464 -221.973647)
			(xy 364.130358 -222.024824) (xy 364.114346 -222.074103) (xy 364.090823 -222.12027) (xy 364.060367 -222.162189)
			(xy 364.023729 -222.198827) (xy 363.98181 -222.229283) (xy 363.935643 -222.252806) (xy 363.886364 -222.268818)
			(xy 363.835187 -222.276924) (xy 363.783373 -222.276924) (xy 363.732196 -222.268818) (xy 363.682917 -222.252806)
			(xy 363.63675 -222.229283) (xy 363.594831 -222.198827) (xy 363.558193 -222.162189) (xy 363.527737 -222.12027)
			(xy 363.504214 -222.074103) (xy 363.488202 -222.024824) (xy 363.480096 -221.973647) (xy 363.479588 -221.94774)
			(xy 362.259372 -221.94774) (xy 362.258864 -221.973627) (xy 362.250765 -222.024765) (xy 362.234766 -222.074005)
			(xy 362.21126 -222.120137) (xy 362.180828 -222.162024) (xy 362.144218 -222.198634) (xy 362.102331 -222.229066)
			(xy 362.056199 -222.252572) (xy 362.006959 -222.268571) (xy 361.955821 -222.27667) (xy 361.904047 -222.27667)
			(xy 361.852909 -222.268571) (xy 361.803669 -222.252572) (xy 361.757537 -222.229066) (xy 361.71565 -222.198634)
			(xy 361.67904 -222.162024) (xy 361.648608 -222.120137) (xy 361.625102 -222.074005) (xy 361.609103 -222.024765)
			(xy 361.601004 -221.973627) (xy 361.600496 -221.94774) (xy 360.379772 -221.94774) (xy 360.379264 -221.973647)
			(xy 360.371158 -222.024824) (xy 360.355146 -222.074103) (xy 360.331623 -222.12027) (xy 360.301167 -222.162189)
			(xy 360.264529 -222.198827) (xy 360.22261 -222.229283) (xy 360.176443 -222.252806) (xy 360.127164 -222.268818)
			(xy 360.075987 -222.276924) (xy 360.024173 -222.276924) (xy 359.972996 -222.268818) (xy 359.923717 -222.252806)
			(xy 359.87755 -222.229283) (xy 359.835631 -222.198827) (xy 359.798993 -222.162189) (xy 359.768537 -222.12027)
			(xy 359.745014 -222.074103) (xy 359.729002 -222.024824) (xy 359.720896 -221.973647) (xy 359.720388 -221.94774)
			(xy 358.500172 -221.94774) (xy 358.499664 -221.973627) (xy 358.491565 -222.024765) (xy 358.475566 -222.074005)
			(xy 358.45206 -222.120137) (xy 358.421628 -222.162024) (xy 358.385018 -222.198634) (xy 358.343131 -222.229066)
			(xy 358.296999 -222.252572) (xy 358.247759 -222.268571) (xy 358.196621 -222.27667) (xy 358.144847 -222.27667)
			(xy 358.093709 -222.268571) (xy 358.044469 -222.252572) (xy 357.998337 -222.229066) (xy 357.95645 -222.198634)
			(xy 357.91984 -222.162024) (xy 357.889408 -222.120137) (xy 357.865902 -222.074005) (xy 357.849903 -222.024765)
			(xy 357.841804 -221.973627) (xy 357.841296 -221.94774) (xy 356.620572 -221.94774) (xy 356.620064 -221.973647)
			(xy 356.611958 -222.024824) (xy 356.595946 -222.074103) (xy 356.572423 -222.12027) (xy 356.541967 -222.162189)
			(xy 356.505329 -222.198827) (xy 356.46341 -222.229283) (xy 356.417243 -222.252806) (xy 356.367964 -222.268818)
			(xy 356.316787 -222.276924) (xy 356.264973 -222.276924) (xy 356.213796 -222.268818) (xy 356.164517 -222.252806)
			(xy 356.11835 -222.229283) (xy 356.076431 -222.198827) (xy 356.039793 -222.162189) (xy 356.009337 -222.12027)
			(xy 355.985814 -222.074103) (xy 355.969802 -222.024824) (xy 355.961696 -221.973647) (xy 355.961188 -221.94774)
			(xy 354.740972 -221.94774) (xy 354.740464 -221.973647) (xy 354.732358 -222.024824) (xy 354.716346 -222.074103)
			(xy 354.692823 -222.12027) (xy 354.662367 -222.162189) (xy 354.625729 -222.198827) (xy 354.58381 -222.229283)
			(xy 354.537643 -222.252806) (xy 354.488364 -222.268818) (xy 354.437187 -222.276924) (xy 354.385373 -222.276924)
			(xy 354.334196 -222.268818) (xy 354.284917 -222.252806) (xy 354.23875 -222.229283) (xy 354.196831 -222.198827)
			(xy 354.160193 -222.162189) (xy 354.129737 -222.12027) (xy 354.106214 -222.074103) (xy 354.090202 -222.024824)
			(xy 354.082096 -221.973647) (xy 354.081588 -221.94774) (xy 352.861372 -221.94774) (xy 352.860864 -221.973647)
			(xy 352.852758 -222.024824) (xy 352.836746 -222.074103) (xy 352.813223 -222.12027) (xy 352.782767 -222.162189)
			(xy 352.746129 -222.198827) (xy 352.70421 -222.229283) (xy 352.658043 -222.252806) (xy 352.608764 -222.268818)
			(xy 352.557587 -222.276924) (xy 352.505773 -222.276924) (xy 352.454596 -222.268818) (xy 352.405317 -222.252806)
			(xy 352.35915 -222.229283) (xy 352.317231 -222.198827) (xy 352.280593 -222.162189) (xy 352.250137 -222.12027)
			(xy 352.226614 -222.074103) (xy 352.210602 -222.024824) (xy 352.202496 -221.973647) (xy 352.201988 -221.94774)
			(xy 350.981772 -221.94774) (xy 350.981264 -221.973647) (xy 350.973158 -222.024824) (xy 350.957146 -222.074103)
			(xy 350.933623 -222.12027) (xy 350.903167 -222.162189) (xy 350.866529 -222.198827) (xy 350.82461 -222.229283)
			(xy 350.778443 -222.252806) (xy 350.729164 -222.268818) (xy 350.677987 -222.276924) (xy 350.626173 -222.276924)
			(xy 350.574996 -222.268818) (xy 350.525717 -222.252806) (xy 350.47955 -222.229283) (xy 350.437631 -222.198827)
			(xy 350.400993 -222.162189) (xy 350.370537 -222.12027) (xy 350.347014 -222.074103) (xy 350.331002 -222.024824)
			(xy 350.322896 -221.973647) (xy 350.322388 -221.94774) (xy 350.322992 -221.920023) (xy 350.332309 -221.865377)
			(xy 350.34093 -221.839028) (xy 350.348804 -221.81693) (xy 350.143826 -221.462092) (xy 350.120966 -221.457774)
			(xy 350.096166 -221.452574) (xy 350.04843 -221.435583) (xy 350.003855 -221.411489) (xy 349.963491 -221.380859)
			(xy 349.928289 -221.344414) (xy 349.899076 -221.303012) (xy 349.876542 -221.257629) (xy 349.861217 -221.209332)
			(xy 349.853461 -221.159259) (xy 349.852996 -221.133924) (xy 349.572072 -221.133924) (xy 349.571564 -221.159811)
			(xy 349.563465 -221.210949) (xy 349.547466 -221.260189) (xy 349.52396 -221.306321) (xy 349.493528 -221.348208)
			(xy 349.456918 -221.384818) (xy 349.415031 -221.41525) (xy 349.368899 -221.438756) (xy 349.319659 -221.454755)
			(xy 349.268521 -221.462854) (xy 349.216747 -221.462854) (xy 349.165609 -221.454755) (xy 349.116369 -221.438756)
			(xy 349.070237 -221.41525) (xy 349.02835 -221.384818) (xy 348.99174 -221.348208) (xy 348.961308 -221.306321)
			(xy 348.937802 -221.260189) (xy 348.921803 -221.210949) (xy 348.913704 -221.159811) (xy 348.913196 -221.133924)
			(xy 348.632272 -221.133924) (xy 348.631745 -221.161632) (xy 348.622548 -221.216279) (xy 348.613984 -221.242636)
			(xy 348.60611 -221.264734) (xy 348.811088 -221.619572) (xy 348.833948 -221.62389) (xy 348.858767 -221.629064)
			(xy 348.906546 -221.646018) (xy 348.951165 -221.670088) (xy 348.991572 -221.700708) (xy 349.026813 -221.737154)
			(xy 349.056057 -221.778566) (xy 349.078614 -221.823969) (xy 349.093952 -221.872291) (xy 349.10171 -221.922391)
			(xy 349.102172 -221.94774) (xy 349.101664 -221.973647) (xy 349.093558 -222.024824) (xy 349.077546 -222.074103)
			(xy 349.054023 -222.12027) (xy 349.023567 -222.162189) (xy 348.986929 -222.198827) (xy 348.94501 -222.229283)
			(xy 348.898843 -222.252806) (xy 348.849564 -222.268818) (xy 348.798387 -222.276924) (xy 348.746573 -222.276924)
			(xy 348.695396 -222.268818) (xy 348.646117 -222.252806) (xy 348.59995 -222.229283) (xy 348.558031 -222.198827)
			(xy 348.521393 -222.162189) (xy 348.490937 -222.12027) (xy 348.467414 -222.074103) (xy 348.451402 -222.024824)
			(xy 348.443296 -221.973647) (xy 348.442788 -221.94774) (xy 348.443392 -221.920023) (xy 348.452709 -221.865377)
			(xy 348.46133 -221.839028) (xy 348.469204 -221.81693) (xy 348.264226 -221.462092) (xy 348.241366 -221.457774)
			(xy 348.216566 -221.452574) (xy 348.16883 -221.435583) (xy 348.124255 -221.411489) (xy 348.083891 -221.380859)
			(xy 348.048689 -221.344414) (xy 348.019476 -221.303012) (xy 347.996942 -221.257629) (xy 347.981617 -221.209332)
			(xy 347.973861 -221.159259) (xy 347.973396 -221.133924) (xy 347.692472 -221.133924) (xy 347.691964 -221.159811)
			(xy 347.683865 -221.210949) (xy 347.667866 -221.260189) (xy 347.64436 -221.306321) (xy 347.613928 -221.348208)
			(xy 347.577318 -221.384818) (xy 347.535431 -221.41525) (xy 347.489299 -221.438756) (xy 347.440059 -221.454755)
			(xy 347.388921 -221.462854) (xy 347.337147 -221.462854) (xy 347.286009 -221.454755) (xy 347.236769 -221.438756)
			(xy 347.190637 -221.41525) (xy 347.14875 -221.384818) (xy 347.11214 -221.348208) (xy 347.081708 -221.306321)
			(xy 347.058202 -221.260189) (xy 347.042203 -221.210949) (xy 347.034104 -221.159811) (xy 347.033596 -221.133924)
			(xy 346.752672 -221.133924) (xy 346.752145 -221.161632) (xy 346.742948 -221.216279) (xy 346.734384 -221.242636)
			(xy 346.72651 -221.264734) (xy 346.931488 -221.619572) (xy 346.954348 -221.62389) (xy 346.979167 -221.629064)
			(xy 347.026946 -221.646018) (xy 347.071565 -221.670088) (xy 347.111972 -221.700708) (xy 347.147213 -221.737154)
			(xy 347.176457 -221.778566) (xy 347.199014 -221.823969) (xy 347.214352 -221.872291) (xy 347.22211 -221.922391)
			(xy 347.222572 -221.94774) (xy 347.222064 -221.973647) (xy 347.213958 -222.024824) (xy 347.197946 -222.074103)
			(xy 347.174423 -222.12027) (xy 347.143967 -222.162189) (xy 347.107329 -222.198827) (xy 347.06541 -222.229283)
			(xy 347.019243 -222.252806) (xy 346.969964 -222.268818) (xy 346.918787 -222.276924) (xy 346.866973 -222.276924)
			(xy 346.815796 -222.268818) (xy 346.766517 -222.252806) (xy 346.72035 -222.229283) (xy 346.678431 -222.198827)
			(xy 346.641793 -222.162189) (xy 346.611337 -222.12027) (xy 346.587814 -222.074103) (xy 346.571802 -222.024824)
			(xy 346.563696 -221.973647) (xy 346.563188 -221.94774) (xy 346.563792 -221.920023) (xy 346.573109 -221.865377)
			(xy 346.58173 -221.839028) (xy 346.589604 -221.81693) (xy 346.384626 -221.462092) (xy 346.361766 -221.457774)
			(xy 346.336966 -221.452574) (xy 346.28923 -221.435583) (xy 346.244655 -221.411489) (xy 346.204291 -221.380859)
			(xy 346.169089 -221.344414) (xy 346.139876 -221.303012) (xy 346.117342 -221.257629) (xy 346.102017 -221.209332)
			(xy 346.094261 -221.159259) (xy 346.093796 -221.133924) (xy 345.812872 -221.133924) (xy 345.812364 -221.159811)
			(xy 345.804265 -221.210949) (xy 345.788266 -221.260189) (xy 345.76476 -221.306321) (xy 345.734328 -221.348208)
			(xy 345.697718 -221.384818) (xy 345.655831 -221.41525) (xy 345.609699 -221.438756) (xy 345.560459 -221.454755)
			(xy 345.509321 -221.462854) (xy 345.457547 -221.462854) (xy 345.406409 -221.454755) (xy 345.357169 -221.438756)
			(xy 345.311037 -221.41525) (xy 345.26915 -221.384818) (xy 345.23254 -221.348208) (xy 345.202108 -221.306321)
			(xy 345.178602 -221.260189) (xy 345.162603 -221.210949) (xy 345.154504 -221.159811) (xy 345.153996 -221.133924)
			(xy 344.873072 -221.133924) (xy 344.872545 -221.161632) (xy 344.863348 -221.216279) (xy 344.854784 -221.242636)
			(xy 344.84691 -221.264734) (xy 345.051888 -221.619572) (xy 345.074748 -221.62389) (xy 345.099567 -221.629064)
			(xy 345.147346 -221.646018) (xy 345.191965 -221.670088) (xy 345.232372 -221.700708) (xy 345.267613 -221.737154)
			(xy 345.296857 -221.778566) (xy 345.319414 -221.823969) (xy 345.334752 -221.872291) (xy 345.34251 -221.922391)
			(xy 345.342972 -221.94774) (xy 345.342464 -221.973647) (xy 345.334358 -222.024824) (xy 345.318346 -222.074103)
			(xy 345.294823 -222.12027) (xy 345.264367 -222.162189) (xy 345.227729 -222.198827) (xy 345.18581 -222.229283)
			(xy 345.139643 -222.252806) (xy 345.090364 -222.268818) (xy 345.039187 -222.276924) (xy 344.987373 -222.276924)
			(xy 344.936196 -222.268818) (xy 344.886917 -222.252806) (xy 344.84075 -222.229283) (xy 344.798831 -222.198827)
			(xy 344.762193 -222.162189) (xy 344.731737 -222.12027) (xy 344.708214 -222.074103) (xy 344.692202 -222.024824)
			(xy 344.684096 -221.973647) (xy 344.683588 -221.94774) (xy 344.684192 -221.920023) (xy 344.693509 -221.865377)
			(xy 344.70213 -221.839028) (xy 344.710004 -221.81693) (xy 344.505026 -221.462092) (xy 344.482166 -221.457774)
			(xy 344.457366 -221.452574) (xy 344.40963 -221.435583) (xy 344.365055 -221.411489) (xy 344.324691 -221.380859)
			(xy 344.289489 -221.344414) (xy 344.260276 -221.303012) (xy 344.237742 -221.257629) (xy 344.222417 -221.209332)
			(xy 344.214661 -221.159259) (xy 344.214196 -221.133924) (xy 343.933272 -221.133924) (xy 343.932764 -221.159811)
			(xy 343.924665 -221.210949) (xy 343.908666 -221.260189) (xy 343.88516 -221.306321) (xy 343.854728 -221.348208)
			(xy 343.818118 -221.384818) (xy 343.776231 -221.41525) (xy 343.730099 -221.438756) (xy 343.680859 -221.454755)
			(xy 343.629721 -221.462854) (xy 343.577947 -221.462854) (xy 343.526809 -221.454755) (xy 343.477569 -221.438756)
			(xy 343.431437 -221.41525) (xy 343.38955 -221.384818) (xy 343.35294 -221.348208) (xy 343.322508 -221.306321)
			(xy 343.299002 -221.260189) (xy 343.283003 -221.210949) (xy 343.274904 -221.159811) (xy 343.274396 -221.133924)
			(xy 342.993472 -221.133924) (xy 342.992945 -221.161632) (xy 342.983748 -221.216279) (xy 342.975184 -221.242636)
			(xy 342.96731 -221.264734) (xy 343.172288 -221.619572) (xy 343.195148 -221.62389) (xy 343.219967 -221.629064)
			(xy 343.267746 -221.646018) (xy 343.312365 -221.670088) (xy 343.352772 -221.700708) (xy 343.388013 -221.737154)
			(xy 343.417257 -221.778566) (xy 343.439814 -221.823969) (xy 343.455152 -221.872291) (xy 343.46291 -221.922391)
			(xy 343.463372 -221.94774) (xy 343.462864 -221.973647) (xy 343.454758 -222.024824) (xy 343.438746 -222.074103)
			(xy 343.415223 -222.12027) (xy 343.384767 -222.162189) (xy 343.348129 -222.198827) (xy 343.30621 -222.229283)
			(xy 343.260043 -222.252806) (xy 343.210764 -222.268818) (xy 343.159587 -222.276924) (xy 343.107773 -222.276924)
			(xy 343.056596 -222.268818) (xy 343.007317 -222.252806) (xy 342.96115 -222.229283) (xy 342.919231 -222.198827)
			(xy 342.882593 -222.162189) (xy 342.852137 -222.12027) (xy 342.828614 -222.074103) (xy 342.812602 -222.024824)
			(xy 342.804496 -221.973647) (xy 342.803988 -221.94774) (xy 342.804592 -221.920023) (xy 342.813909 -221.865377)
			(xy 342.82253 -221.839028) (xy 342.830404 -221.81693) (xy 342.625426 -221.462092) (xy 342.602566 -221.457774)
			(xy 342.577766 -221.452574) (xy 342.53003 -221.435583) (xy 342.485455 -221.411489) (xy 342.445091 -221.380859)
			(xy 342.409889 -221.344414) (xy 342.380676 -221.303012) (xy 342.358142 -221.257629) (xy 342.342817 -221.209332)
			(xy 342.335061 -221.159259) (xy 342.334596 -221.133924) (xy 342.053672 -221.133924) (xy 342.053164 -221.159811)
			(xy 342.045065 -221.210949) (xy 342.029066 -221.260189) (xy 342.00556 -221.306321) (xy 341.975128 -221.348208)
			(xy 341.938518 -221.384818) (xy 341.896631 -221.41525) (xy 341.850499 -221.438756) (xy 341.801259 -221.454755)
			(xy 341.750121 -221.462854) (xy 341.698347 -221.462854) (xy 341.647209 -221.454755) (xy 341.597969 -221.438756)
			(xy 341.551837 -221.41525) (xy 341.50995 -221.384818) (xy 341.47334 -221.348208) (xy 341.442908 -221.306321)
			(xy 341.419402 -221.260189) (xy 341.403403 -221.210949) (xy 341.395304 -221.159811) (xy 341.394796 -221.133924)
			(xy 341.113872 -221.133924) (xy 341.113345 -221.161632) (xy 341.104148 -221.216279) (xy 341.095584 -221.242636)
			(xy 341.08771 -221.264734) (xy 341.292688 -221.619572) (xy 341.315548 -221.62389) (xy 341.340367 -221.629064)
			(xy 341.388146 -221.646018) (xy 341.432765 -221.670088) (xy 341.473172 -221.700708) (xy 341.508413 -221.737154)
			(xy 341.537657 -221.778566) (xy 341.560214 -221.823969) (xy 341.575552 -221.872291) (xy 341.58331 -221.922391)
			(xy 341.583772 -221.94774) (xy 341.583264 -221.973647) (xy 341.575158 -222.024824) (xy 341.559146 -222.074103)
			(xy 341.535623 -222.12027) (xy 341.505167 -222.162189) (xy 341.468529 -222.198827) (xy 341.42661 -222.229283)
			(xy 341.380443 -222.252806) (xy 341.331164 -222.268818) (xy 341.279987 -222.276924) (xy 341.228173 -222.276924)
			(xy 341.176996 -222.268818) (xy 341.127717 -222.252806) (xy 341.08155 -222.229283) (xy 341.039631 -222.198827)
			(xy 341.002993 -222.162189) (xy 340.972537 -222.12027) (xy 340.949014 -222.074103) (xy 340.933002 -222.024824)
			(xy 340.924896 -221.973647) (xy 340.924388 -221.94774) (xy 340.924992 -221.920023) (xy 340.934309 -221.865377)
			(xy 340.94293 -221.839028) (xy 340.950804 -221.81693) (xy 340.745826 -221.462092) (xy 340.722966 -221.457774)
			(xy 340.698166 -221.452574) (xy 340.65043 -221.435583) (xy 340.605855 -221.411489) (xy 340.565491 -221.380859)
			(xy 340.530289 -221.344414) (xy 340.501076 -221.303012) (xy 340.478542 -221.257629) (xy 340.463217 -221.209332)
			(xy 340.455461 -221.159259) (xy 340.454996 -221.133924) (xy 340.174072 -221.133924) (xy 340.173564 -221.159811)
			(xy 340.165465 -221.210949) (xy 340.149466 -221.260189) (xy 340.12596 -221.306321) (xy 340.095528 -221.348208)
			(xy 340.058918 -221.384818) (xy 340.017031 -221.41525) (xy 339.970899 -221.438756) (xy 339.921659 -221.454755)
			(xy 339.870521 -221.462854) (xy 339.818747 -221.462854) (xy 339.767609 -221.454755) (xy 339.718369 -221.438756)
			(xy 339.672237 -221.41525) (xy 339.63035 -221.384818) (xy 339.59374 -221.348208) (xy 339.563308 -221.306321)
			(xy 339.539802 -221.260189) (xy 339.523803 -221.210949) (xy 339.515704 -221.159811) (xy 339.515196 -221.133924)
			(xy 339.234272 -221.133924) (xy 339.233745 -221.161632) (xy 339.224548 -221.216279) (xy 339.215984 -221.242636)
			(xy 339.20811 -221.264734) (xy 339.413088 -221.619572) (xy 339.435948 -221.62389) (xy 339.460767 -221.629064)
			(xy 339.508546 -221.646018) (xy 339.553165 -221.670088) (xy 339.593572 -221.700708) (xy 339.628813 -221.737154)
			(xy 339.658057 -221.778566) (xy 339.680614 -221.823969) (xy 339.695952 -221.872291) (xy 339.70371 -221.922391)
			(xy 339.704172 -221.94774) (xy 339.703664 -221.973647) (xy 339.695558 -222.024824) (xy 339.679546 -222.074103)
			(xy 339.656023 -222.12027) (xy 339.625567 -222.162189) (xy 339.588929 -222.198827) (xy 339.54701 -222.229283)
			(xy 339.500843 -222.252806) (xy 339.451564 -222.268818) (xy 339.400387 -222.276924) (xy 339.348573 -222.276924)
			(xy 339.297396 -222.268818) (xy 339.248117 -222.252806) (xy 339.20195 -222.229283) (xy 339.160031 -222.198827)
			(xy 339.123393 -222.162189) (xy 339.092937 -222.12027) (xy 339.069414 -222.074103) (xy 339.053402 -222.024824)
			(xy 339.045296 -221.973647) (xy 339.044788 -221.94774) (xy 339.045392 -221.920023) (xy 339.054709 -221.865377)
			(xy 339.06333 -221.839028) (xy 339.071204 -221.81693) (xy 338.866226 -221.462092) (xy 338.843366 -221.457774)
			(xy 338.818566 -221.452574) (xy 338.77083 -221.435583) (xy 338.726255 -221.411489) (xy 338.685891 -221.380859)
			(xy 338.650689 -221.344414) (xy 338.621476 -221.303012) (xy 338.598942 -221.257629) (xy 338.583617 -221.209332)
			(xy 338.575861 -221.159259) (xy 338.575396 -221.133924) (xy 338.294472 -221.133924) (xy 338.293964 -221.159811)
			(xy 338.285865 -221.210949) (xy 338.269866 -221.260189) (xy 338.24636 -221.306321) (xy 338.215928 -221.348208)
			(xy 338.179318 -221.384818) (xy 338.137431 -221.41525) (xy 338.091299 -221.438756) (xy 338.042059 -221.454755)
			(xy 337.990921 -221.462854) (xy 337.939147 -221.462854) (xy 337.888009 -221.454755) (xy 337.838769 -221.438756)
			(xy 337.792637 -221.41525) (xy 337.75075 -221.384818) (xy 337.71414 -221.348208) (xy 337.683708 -221.306321)
			(xy 337.660202 -221.260189) (xy 337.644203 -221.210949) (xy 337.636104 -221.159811) (xy 337.635596 -221.133924)
			(xy 337.354672 -221.133924) (xy 337.354145 -221.161632) (xy 337.344948 -221.216279) (xy 337.336384 -221.242636)
			(xy 337.32851 -221.264734) (xy 337.533488 -221.619572) (xy 337.556348 -221.62389) (xy 337.581167 -221.629064)
			(xy 337.628946 -221.646018) (xy 337.673565 -221.670088) (xy 337.713972 -221.700708) (xy 337.749213 -221.737154)
			(xy 337.778457 -221.778566) (xy 337.801014 -221.823969) (xy 337.816352 -221.872291) (xy 337.82411 -221.922391)
			(xy 337.824572 -221.94774) (xy 337.824064 -221.973647) (xy 337.815958 -222.024824) (xy 337.799946 -222.074103)
			(xy 337.776423 -222.12027) (xy 337.745967 -222.162189) (xy 337.709329 -222.198827) (xy 337.66741 -222.229283)
			(xy 337.621243 -222.252806) (xy 337.571964 -222.268818) (xy 337.520787 -222.276924) (xy 337.468973 -222.276924)
			(xy 337.417796 -222.268818) (xy 337.368517 -222.252806) (xy 337.32235 -222.229283) (xy 337.280431 -222.198827)
			(xy 337.243793 -222.162189) (xy 337.213337 -222.12027) (xy 337.189814 -222.074103) (xy 337.173802 -222.024824)
			(xy 337.165696 -221.973647) (xy 337.165188 -221.94774) (xy 337.165792 -221.920023) (xy 337.175109 -221.865377)
			(xy 337.18373 -221.839028) (xy 337.191604 -221.81693) (xy 336.986626 -221.462092) (xy 336.963766 -221.457774)
			(xy 336.938966 -221.452574) (xy 336.89123 -221.435583) (xy 336.846655 -221.411489) (xy 336.806291 -221.380859)
			(xy 336.771089 -221.344414) (xy 336.741876 -221.303012) (xy 336.719342 -221.257629) (xy 336.704017 -221.209332)
			(xy 336.696261 -221.159259) (xy 336.695796 -221.133924) (xy 309.6387 -221.133924) (xy 309.6387 -221.321376)
			(xy 309.638259 -221.331529) (xy 309.630471 -221.350281) (xy 309.61608 -221.364605) (xy 309.597292 -221.372305)
			(xy 309.587138 -221.372684) (xy 308.187598 -221.372684) (xy 308.177474 -221.372176) (xy 308.158758 -221.364452)
			(xy 308.144402 -221.350172) (xy 308.136579 -221.331497) (xy 308.136036 -221.321376) (xy 302.0949 -221.321376)
			(xy 302.094459 -221.331529) (xy 302.086671 -221.350281) (xy 302.07228 -221.364605) (xy 302.053492 -221.372305)
			(xy 302.043338 -221.372684) (xy 300.643798 -221.372684) (xy 300.633674 -221.372176) (xy 300.614958 -221.364452)
			(xy 300.600602 -221.350172) (xy 300.592779 -221.331497) (xy 300.592236 -221.321376) (xy 294.5511 -221.321376)
			(xy 294.550659 -221.331529) (xy 294.542871 -221.350281) (xy 294.52848 -221.364605) (xy 294.509692 -221.372305)
			(xy 294.499538 -221.372684) (xy 293.099998 -221.372684) (xy 293.089874 -221.372176) (xy 293.071158 -221.364452)
			(xy 293.056802 -221.350172) (xy 293.048979 -221.331497) (xy 293.048436 -221.321376) (xy 287.0073 -221.321376)
			(xy 287.006859 -221.331529) (xy 286.999071 -221.350281) (xy 286.98468 -221.364605) (xy 286.965892 -221.372305)
			(xy 286.955738 -221.372684) (xy 285.556198 -221.372684) (xy 285.546074 -221.372176) (xy 285.527358 -221.364452)
			(xy 285.513002 -221.350172) (xy 285.505179 -221.331497) (xy 285.504636 -221.321376) (xy 279.4635 -221.321376)
			(xy 279.463059 -221.331529) (xy 279.455271 -221.350281) (xy 279.44088 -221.364605) (xy 279.422092 -221.372305)
			(xy 279.411938 -221.372684) (xy 278.012398 -221.372684) (xy 278.002274 -221.372176) (xy 277.983558 -221.364452)
			(xy 277.969202 -221.350172) (xy 277.961379 -221.331497) (xy 277.960836 -221.321376) (xy 271.9197 -221.321376)
			(xy 271.919259 -221.331529) (xy 271.911471 -221.350281) (xy 271.89708 -221.364605) (xy 271.878292 -221.372305)
			(xy 271.868138 -221.372684) (xy 270.468598 -221.372684) (xy 270.458474 -221.372176) (xy 270.439758 -221.364452)
			(xy 270.425402 -221.350172) (xy 270.417579 -221.331497) (xy 270.417036 -221.321376) (xy 264.3759 -221.321376)
			(xy 264.375459 -221.331529) (xy 264.367671 -221.350281) (xy 264.35328 -221.364605) (xy 264.334492 -221.372305)
			(xy 264.324338 -221.372684) (xy 262.924798 -221.372684) (xy 262.914674 -221.372176) (xy 262.895958 -221.364452)
			(xy 262.881602 -221.350172) (xy 262.873779 -221.331497) (xy 262.873236 -221.321376) (xy 256.8321 -221.321376)
			(xy 256.831659 -221.331529) (xy 256.823871 -221.350281) (xy 256.80948 -221.364605) (xy 256.790692 -221.372305)
			(xy 256.780538 -221.372684) (xy 255.380998 -221.372684) (xy 255.370874 -221.372176) (xy 255.352158 -221.364452)
			(xy 255.337802 -221.350172) (xy 255.329979 -221.331497) (xy 255.329436 -221.321376) (xy 212.371432 -221.321376)
			(xy 212.37096 -221.331525) (xy 212.363178 -221.35027) (xy 212.348797 -221.364594) (xy 212.33002 -221.3723)
			(xy 212.31987 -221.372684) (xy 210.92033 -221.372684) (xy 210.910208 -221.37215) (xy 210.891492 -221.364436)
			(xy 210.877136 -221.350165) (xy 210.869311 -221.331495) (xy 210.868768 -221.321376) (xy 204.827632 -221.321376)
			(xy 204.82716 -221.331525) (xy 204.819378 -221.35027) (xy 204.804997 -221.364594) (xy 204.78622 -221.3723)
			(xy 204.77607 -221.372684) (xy 203.37653 -221.372684) (xy 203.366408 -221.37215) (xy 203.347692 -221.364436)
			(xy 203.333336 -221.350165) (xy 203.325511 -221.331495) (xy 203.324968 -221.321376) (xy 197.283832 -221.321376)
			(xy 197.28336 -221.331525) (xy 197.275578 -221.35027) (xy 197.261197 -221.364594) (xy 197.24242 -221.3723)
			(xy 197.23227 -221.372684) (xy 195.83273 -221.372684) (xy 195.822608 -221.37215) (xy 195.803892 -221.364436)
			(xy 195.789536 -221.350165) (xy 195.781711 -221.331495) (xy 195.781168 -221.321376) (xy 189.740032 -221.321376)
			(xy 189.73956 -221.331525) (xy 189.731778 -221.35027) (xy 189.717397 -221.364594) (xy 189.69862 -221.3723)
			(xy 189.68847 -221.372684) (xy 188.28893 -221.372684) (xy 188.278808 -221.37215) (xy 188.260092 -221.364436)
			(xy 188.245736 -221.350165) (xy 188.237911 -221.331495) (xy 188.237368 -221.321376) (xy 182.196232 -221.321376)
			(xy 182.19576 -221.331525) (xy 182.187978 -221.35027) (xy 182.173597 -221.364594) (xy 182.15482 -221.3723)
			(xy 182.14467 -221.372684) (xy 180.74513 -221.372684) (xy 180.735008 -221.37215) (xy 180.716292 -221.364436)
			(xy 180.701936 -221.350165) (xy 180.694111 -221.331495) (xy 180.693568 -221.321376) (xy 174.652432 -221.321376)
			(xy 174.65196 -221.331525) (xy 174.644178 -221.35027) (xy 174.629797 -221.364594) (xy 174.61102 -221.3723)
			(xy 174.60087 -221.372684) (xy 173.20133 -221.372684) (xy 173.191208 -221.37215) (xy 173.172492 -221.364436)
			(xy 173.158136 -221.350165) (xy 173.150311 -221.331495) (xy 173.149768 -221.321376) (xy 167.108632 -221.321376)
			(xy 167.10816 -221.331525) (xy 167.100378 -221.35027) (xy 167.085997 -221.364594) (xy 167.06722 -221.3723)
			(xy 167.05707 -221.372684) (xy 165.65753 -221.372684) (xy 165.647408 -221.37215) (xy 165.628692 -221.364436)
			(xy 165.614336 -221.350165) (xy 165.606511 -221.331495) (xy 165.605968 -221.321376) (xy 159.564832 -221.321376)
			(xy 159.56436 -221.331525) (xy 159.556578 -221.35027) (xy 159.542197 -221.364594) (xy 159.52342 -221.3723)
			(xy 159.51327 -221.372684) (xy 158.11373 -221.372684) (xy 158.103608 -221.37215) (xy 158.084892 -221.364436)
			(xy 158.070536 -221.350165) (xy 158.062711 -221.331495) (xy 158.062168 -221.321376) (xy 135.405859 -221.321376)
			(xy 135.389421 -221.344633) (xy 135.354133 -221.381081) (xy 135.313674 -221.411686) (xy 135.269 -221.435725)
			(xy 135.221169 -221.45263) (xy 135.196326 -221.457774) (xy 135.173466 -221.462092) (xy 134.968742 -221.81693)
			(xy 134.976362 -221.838774) (xy 134.984977 -221.865059) (xy 134.994298 -221.919578) (xy 134.994904 -221.947232)
			(xy 134.994904 -221.94774) (xy 134.994396 -221.973647) (xy 134.98629 -222.024824) (xy 134.970278 -222.074103)
			(xy 134.946755 -222.12027) (xy 134.916299 -222.162189) (xy 134.906974 -222.171514) (xy 162.162236 -222.171514)
			(xy 162.162236 -221.762574) (xy 162.162712 -221.752415) (xy 162.170495 -221.733645) (xy 162.184866 -221.719281)
			(xy 162.203639 -221.711507) (xy 162.213798 -221.711012) (xy 163.613338 -221.711012) (xy 163.623495 -221.711502)
			(xy 163.64226 -221.719284) (xy 163.656623 -221.73365) (xy 163.664401 -221.752417) (xy 163.6649 -221.762574)
			(xy 163.6649 -222.171514) (xy 169.706036 -222.171514) (xy 169.706036 -221.762574) (xy 169.706512 -221.752415)
			(xy 169.714295 -221.733645) (xy 169.728666 -221.719281) (xy 169.747439 -221.711507) (xy 169.757598 -221.711012)
			(xy 171.157138 -221.711012) (xy 171.167295 -221.711502) (xy 171.18606 -221.719284) (xy 171.200423 -221.73365)
			(xy 171.208201 -221.752417) (xy 171.2087 -221.762574) (xy 171.2087 -222.171514) (xy 177.249836 -222.171514)
			(xy 177.249836 -221.762574) (xy 177.250312 -221.752415) (xy 177.258095 -221.733645) (xy 177.272466 -221.719281)
			(xy 177.291239 -221.711507) (xy 177.301398 -221.711012) (xy 178.700938 -221.711012) (xy 178.711095 -221.711502)
			(xy 178.72986 -221.719284) (xy 178.744223 -221.73365) (xy 178.752001 -221.752417) (xy 178.7525 -221.762574)
			(xy 178.7525 -222.171514) (xy 184.793636 -222.171514) (xy 184.793636 -221.762574) (xy 184.794112 -221.752415)
			(xy 184.801895 -221.733645) (xy 184.816266 -221.719281) (xy 184.835039 -221.711507) (xy 184.845198 -221.711012)
			(xy 186.244738 -221.711012) (xy 186.254895 -221.711502) (xy 186.27366 -221.719284) (xy 186.288023 -221.73365)
			(xy 186.295801 -221.752417) (xy 186.2963 -221.762574) (xy 186.2963 -222.171514) (xy 192.337436 -222.171514)
			(xy 192.337436 -221.762574) (xy 192.337912 -221.752415) (xy 192.345695 -221.733645) (xy 192.360066 -221.719281)
			(xy 192.378839 -221.711507) (xy 192.388998 -221.711012) (xy 193.788538 -221.711012) (xy 193.798695 -221.711502)
			(xy 193.81746 -221.719284) (xy 193.831823 -221.73365) (xy 193.839601 -221.752417) (xy 193.8401 -221.762574)
			(xy 193.8401 -222.171514) (xy 199.881236 -222.171514) (xy 199.881236 -221.762574) (xy 199.881712 -221.752415)
			(xy 199.889495 -221.733645) (xy 199.903866 -221.719281) (xy 199.922639 -221.711507) (xy 199.932798 -221.711012)
			(xy 201.332338 -221.711012) (xy 201.342495 -221.711502) (xy 201.36126 -221.719284) (xy 201.375623 -221.73365)
			(xy 201.383401 -221.752417) (xy 201.3839 -221.762574) (xy 201.3839 -222.171514) (xy 207.425036 -222.171514)
			(xy 207.425036 -221.762574) (xy 207.425512 -221.752415) (xy 207.433295 -221.733645) (xy 207.447666 -221.719281)
			(xy 207.466439 -221.711507) (xy 207.476598 -221.711012) (xy 208.876138 -221.711012) (xy 208.886295 -221.711502)
			(xy 208.90506 -221.719284) (xy 208.919423 -221.73365) (xy 208.927201 -221.752417) (xy 208.9277 -221.762574)
			(xy 208.9277 -222.171514) (xy 214.968836 -222.171514) (xy 214.968836 -221.762574) (xy 214.969312 -221.752415)
			(xy 214.977095 -221.733645) (xy 214.991466 -221.719281) (xy 215.010239 -221.711507) (xy 215.020398 -221.711012)
			(xy 216.419938 -221.711012) (xy 216.430095 -221.711502) (xy 216.44886 -221.719284) (xy 216.463223 -221.73365)
			(xy 216.471001 -221.752417) (xy 216.4715 -221.762574) (xy 216.4715 -222.171514) (xy 259.429504 -222.171514)
			(xy 259.429504 -221.762574) (xy 259.430011 -221.752419) (xy 259.437788 -221.733655) (xy 259.452149 -221.719292)
			(xy 259.470911 -221.711513) (xy 259.481066 -221.711012) (xy 260.880606 -221.711012) (xy 260.890761 -221.711528)
			(xy 260.909525 -221.7193) (xy 260.923889 -221.733658) (xy 260.931668 -221.752419) (xy 260.932168 -221.762574)
			(xy 260.932168 -222.171514) (xy 266.973304 -222.171514) (xy 266.973304 -221.762574) (xy 266.973811 -221.752419)
			(xy 266.981588 -221.733655) (xy 266.995949 -221.719292) (xy 267.014711 -221.711513) (xy 267.024866 -221.711012)
			(xy 268.424406 -221.711012) (xy 268.434561 -221.711528) (xy 268.453325 -221.7193) (xy 268.467689 -221.733658)
			(xy 268.475468 -221.752419) (xy 268.475968 -221.762574) (xy 268.475968 -222.171514) (xy 274.517104 -222.171514)
			(xy 274.517104 -221.762574) (xy 274.517611 -221.752419) (xy 274.525388 -221.733655) (xy 274.539749 -221.719292)
			(xy 274.558511 -221.711513) (xy 274.568666 -221.711012) (xy 275.968206 -221.711012) (xy 275.978361 -221.711528)
			(xy 275.997125 -221.7193) (xy 276.011489 -221.733658) (xy 276.019268 -221.752419) (xy 276.019768 -221.762574)
			(xy 276.019768 -222.171514) (xy 282.060904 -222.171514) (xy 282.060904 -221.762574) (xy 282.061411 -221.752419)
			(xy 282.069188 -221.733655) (xy 282.083549 -221.719292) (xy 282.102311 -221.711513) (xy 282.112466 -221.711012)
			(xy 283.512006 -221.711012) (xy 283.522161 -221.711528) (xy 283.540925 -221.7193) (xy 283.555289 -221.733658)
			(xy 283.563068 -221.752419) (xy 283.563568 -221.762574) (xy 283.563568 -222.171514) (xy 289.604704 -222.171514)
			(xy 289.604704 -221.762574) (xy 289.605211 -221.752419) (xy 289.612988 -221.733655) (xy 289.627349 -221.719292)
			(xy 289.646111 -221.711513) (xy 289.656266 -221.711012) (xy 291.055806 -221.711012) (xy 291.065961 -221.711528)
			(xy 291.084725 -221.7193) (xy 291.099089 -221.733658) (xy 291.106868 -221.752419) (xy 291.107368 -221.762574)
			(xy 291.107368 -222.171514) (xy 297.148504 -222.171514) (xy 297.148504 -221.762574) (xy 297.149011 -221.752419)
			(xy 297.156788 -221.733655) (xy 297.171149 -221.719292) (xy 297.189911 -221.711513) (xy 297.200066 -221.711012)
			(xy 298.599606 -221.711012) (xy 298.609761 -221.711528) (xy 298.628525 -221.7193) (xy 298.642889 -221.733658)
			(xy 298.650668 -221.752419) (xy 298.651168 -221.762574) (xy 298.651168 -222.171514) (xy 304.692304 -222.171514)
			(xy 304.692304 -221.762574) (xy 304.692811 -221.752419) (xy 304.700588 -221.733655) (xy 304.714949 -221.719292)
			(xy 304.733711 -221.711513) (xy 304.743866 -221.711012) (xy 306.143406 -221.711012) (xy 306.153561 -221.711528)
			(xy 306.172325 -221.7193) (xy 306.186689 -221.733658) (xy 306.194468 -221.752419) (xy 306.194968 -221.762574)
			(xy 306.194968 -222.171514) (xy 312.236104 -222.171514) (xy 312.236104 -221.762574) (xy 312.236611 -221.752419)
			(xy 312.244388 -221.733655) (xy 312.258749 -221.719292) (xy 312.277511 -221.711513) (xy 312.287666 -221.711012)
			(xy 313.687206 -221.711012) (xy 313.697361 -221.711528) (xy 313.716125 -221.7193) (xy 313.730489 -221.733658)
			(xy 313.738268 -221.752419) (xy 313.738768 -221.762574) (xy 313.738768 -222.171514) (xy 313.738278 -222.181672)
			(xy 313.7305 -222.20044) (xy 313.716133 -222.214805) (xy 313.697364 -222.22258) (xy 313.687206 -222.223076)
			(xy 312.287666 -222.223076) (xy 312.277508 -222.222595) (xy 312.258741 -222.214812) (xy 312.244377 -222.200443)
			(xy 312.236601 -222.181672) (xy 312.236104 -222.171514) (xy 306.194968 -222.171514) (xy 306.194478 -222.181672)
			(xy 306.1867 -222.20044) (xy 306.172333 -222.214805) (xy 306.153564 -222.22258) (xy 306.143406 -222.223076)
			(xy 304.743866 -222.223076) (xy 304.733708 -222.222595) (xy 304.714941 -222.214812) (xy 304.700577 -222.200443)
			(xy 304.692801 -222.181672) (xy 304.692304 -222.171514) (xy 298.651168 -222.171514) (xy 298.650678 -222.181672)
			(xy 298.6429 -222.20044) (xy 298.628533 -222.214805) (xy 298.609764 -222.22258) (xy 298.599606 -222.223076)
			(xy 297.200066 -222.223076) (xy 297.189908 -222.222595) (xy 297.171141 -222.214812) (xy 297.156777 -222.200443)
			(xy 297.149001 -222.181672) (xy 297.148504 -222.171514) (xy 291.107368 -222.171514) (xy 291.106878 -222.181672)
			(xy 291.0991 -222.20044) (xy 291.084733 -222.214805) (xy 291.065964 -222.22258) (xy 291.055806 -222.223076)
			(xy 289.656266 -222.223076) (xy 289.646108 -222.222595) (xy 289.627341 -222.214812) (xy 289.612977 -222.200443)
			(xy 289.605201 -222.181672) (xy 289.604704 -222.171514) (xy 283.563568 -222.171514) (xy 283.563078 -222.181672)
			(xy 283.5553 -222.20044) (xy 283.540933 -222.214805) (xy 283.522164 -222.22258) (xy 283.512006 -222.223076)
			(xy 282.112466 -222.223076) (xy 282.102308 -222.222595) (xy 282.083541 -222.214812) (xy 282.069177 -222.200443)
			(xy 282.061401 -222.181672) (xy 282.060904 -222.171514) (xy 276.019768 -222.171514) (xy 276.019278 -222.181672)
			(xy 276.0115 -222.20044) (xy 275.997133 -222.214805) (xy 275.978364 -222.22258) (xy 275.968206 -222.223076)
			(xy 274.568666 -222.223076) (xy 274.558508 -222.222595) (xy 274.539741 -222.214812) (xy 274.525377 -222.200443)
			(xy 274.517601 -222.181672) (xy 274.517104 -222.171514) (xy 268.475968 -222.171514) (xy 268.475478 -222.181672)
			(xy 268.4677 -222.20044) (xy 268.453333 -222.214805) (xy 268.434564 -222.22258) (xy 268.424406 -222.223076)
			(xy 267.024866 -222.223076) (xy 267.014708 -222.222595) (xy 266.995941 -222.214812) (xy 266.981577 -222.200443)
			(xy 266.973801 -222.181672) (xy 266.973304 -222.171514) (xy 260.932168 -222.171514) (xy 260.931678 -222.181672)
			(xy 260.9239 -222.20044) (xy 260.909533 -222.214805) (xy 260.890764 -222.22258) (xy 260.880606 -222.223076)
			(xy 259.481066 -222.223076) (xy 259.470908 -222.222595) (xy 259.452141 -222.214812) (xy 259.437777 -222.200443)
			(xy 259.430001 -222.181672) (xy 259.429504 -222.171514) (xy 216.4715 -222.171514) (xy 216.470979 -222.181668)
			(xy 216.463207 -222.20043) (xy 216.44885 -222.214793) (xy 216.430092 -222.222574) (xy 216.419938 -222.223076)
			(xy 215.020398 -222.223076) (xy 215.010242 -222.222569) (xy 214.991475 -222.214796) (xy 214.977111 -222.200435)
			(xy 214.969334 -222.18167) (xy 214.968836 -222.171514) (xy 208.9277 -222.171514) (xy 208.927179 -222.181668)
			(xy 208.919407 -222.20043) (xy 208.90505 -222.214793) (xy 208.886292 -222.222574) (xy 208.876138 -222.223076)
			(xy 207.476598 -222.223076) (xy 207.466442 -222.222569) (xy 207.447675 -222.214796) (xy 207.433311 -222.200435)
			(xy 207.425534 -222.18167) (xy 207.425036 -222.171514) (xy 201.3839 -222.171514) (xy 201.383379 -222.181668)
			(xy 201.375607 -222.20043) (xy 201.36125 -222.214793) (xy 201.342492 -222.222574) (xy 201.332338 -222.223076)
			(xy 199.932798 -222.223076) (xy 199.922642 -222.222569) (xy 199.903875 -222.214796) (xy 199.889511 -222.200435)
			(xy 199.881734 -222.18167) (xy 199.881236 -222.171514) (xy 193.8401 -222.171514) (xy 193.839579 -222.181668)
			(xy 193.831807 -222.20043) (xy 193.81745 -222.214793) (xy 193.798692 -222.222574) (xy 193.788538 -222.223076)
			(xy 192.388998 -222.223076) (xy 192.378842 -222.222569) (xy 192.360075 -222.214796) (xy 192.345711 -222.200435)
			(xy 192.337934 -222.18167) (xy 192.337436 -222.171514) (xy 186.2963 -222.171514) (xy 186.295779 -222.181668)
			(xy 186.288007 -222.20043) (xy 186.27365 -222.214793) (xy 186.254892 -222.222574) (xy 186.244738 -222.223076)
			(xy 184.845198 -222.223076) (xy 184.835042 -222.222569) (xy 184.816275 -222.214796) (xy 184.801911 -222.200435)
			(xy 184.794134 -222.18167) (xy 184.793636 -222.171514) (xy 178.7525 -222.171514) (xy 178.751979 -222.181668)
			(xy 178.744207 -222.20043) (xy 178.72985 -222.214793) (xy 178.711092 -222.222574) (xy 178.700938 -222.223076)
			(xy 177.301398 -222.223076) (xy 177.291242 -222.222569) (xy 177.272475 -222.214796) (xy 177.258111 -222.200435)
			(xy 177.250334 -222.18167) (xy 177.249836 -222.171514) (xy 171.2087 -222.171514) (xy 171.208179 -222.181668)
			(xy 171.200407 -222.20043) (xy 171.18605 -222.214793) (xy 171.167292 -222.222574) (xy 171.157138 -222.223076)
			(xy 169.757598 -222.223076) (xy 169.747442 -222.222569) (xy 169.728675 -222.214796) (xy 169.714311 -222.200435)
			(xy 169.706534 -222.18167) (xy 169.706036 -222.171514) (xy 163.6649 -222.171514) (xy 163.664379 -222.181668)
			(xy 163.656607 -222.20043) (xy 163.64225 -222.214793) (xy 163.623492 -222.222574) (xy 163.613338 -222.223076)
			(xy 162.213798 -222.223076) (xy 162.203642 -222.222569) (xy 162.184875 -222.214796) (xy 162.170511 -222.200435)
			(xy 162.162734 -222.18167) (xy 162.162236 -222.171514) (xy 134.906974 -222.171514) (xy 134.879661 -222.198827)
			(xy 134.837742 -222.229283) (xy 134.791575 -222.252806) (xy 134.742296 -222.268818) (xy 134.691119 -222.276924)
			(xy 134.639305 -222.276924) (xy 134.588128 -222.268818) (xy 134.538849 -222.252806) (xy 134.492682 -222.229283)
			(xy 134.450763 -222.198827) (xy 134.414125 -222.162189) (xy 134.383669 -222.12027) (xy 134.360146 -222.074103)
			(xy 134.344134 -222.024824) (xy 134.336028 -221.973647) (xy 134.33552 -221.94774) (xy 133.115304 -221.94774)
			(xy 133.114796 -221.973647) (xy 133.10669 -222.024824) (xy 133.090678 -222.074103) (xy 133.067155 -222.12027)
			(xy 133.036699 -222.162189) (xy 133.000061 -222.198827) (xy 132.958142 -222.229283) (xy 132.911975 -222.252806)
			(xy 132.862696 -222.268818) (xy 132.811519 -222.276924) (xy 132.759705 -222.276924) (xy 132.708528 -222.268818)
			(xy 132.659249 -222.252806) (xy 132.613082 -222.229283) (xy 132.571163 -222.198827) (xy 132.534525 -222.162189)
			(xy 132.504069 -222.12027) (xy 132.480546 -222.074103) (xy 132.464534 -222.024824) (xy 132.456428 -221.973647)
			(xy 132.45592 -221.94774) (xy 131.235704 -221.94774) (xy 131.235196 -221.973647) (xy 131.22709 -222.024824)
			(xy 131.211078 -222.074103) (xy 131.187555 -222.12027) (xy 131.157099 -222.162189) (xy 131.120461 -222.198827)
			(xy 131.078542 -222.229283) (xy 131.032375 -222.252806) (xy 130.983096 -222.268818) (xy 130.931919 -222.276924)
			(xy 130.880105 -222.276924) (xy 130.828928 -222.268818) (xy 130.779649 -222.252806) (xy 130.733482 -222.229283)
			(xy 130.691563 -222.198827) (xy 130.654925 -222.162189) (xy 130.624469 -222.12027) (xy 130.600946 -222.074103)
			(xy 130.584934 -222.024824) (xy 130.576828 -221.973647) (xy 130.57632 -221.94774) (xy 129.356104 -221.94774)
			(xy 129.355596 -221.973647) (xy 129.34749 -222.024824) (xy 129.331478 -222.074103) (xy 129.307955 -222.12027)
			(xy 129.277499 -222.162189) (xy 129.240861 -222.198827) (xy 129.198942 -222.229283) (xy 129.152775 -222.252806)
			(xy 129.103496 -222.268818) (xy 129.052319 -222.276924) (xy 129.000505 -222.276924) (xy 128.949328 -222.268818)
			(xy 128.900049 -222.252806) (xy 128.853882 -222.229283) (xy 128.811963 -222.198827) (xy 128.775325 -222.162189)
			(xy 128.744869 -222.12027) (xy 128.721346 -222.074103) (xy 128.705334 -222.024824) (xy 128.697228 -221.973647)
			(xy 128.69672 -221.94774) (xy 127.476504 -221.94774) (xy 127.475996 -221.973647) (xy 127.46789 -222.024824)
			(xy 127.451878 -222.074103) (xy 127.428355 -222.12027) (xy 127.397899 -222.162189) (xy 127.361261 -222.198827)
			(xy 127.319342 -222.229283) (xy 127.273175 -222.252806) (xy 127.223896 -222.268818) (xy 127.172719 -222.276924)
			(xy 127.120905 -222.276924) (xy 127.069728 -222.268818) (xy 127.020449 -222.252806) (xy 126.974282 -222.229283)
			(xy 126.932363 -222.198827) (xy 126.895725 -222.162189) (xy 126.865269 -222.12027) (xy 126.841746 -222.074103)
			(xy 126.825734 -222.024824) (xy 126.817628 -221.973647) (xy 126.81712 -221.94774) (xy 125.596904 -221.94774)
			(xy 125.596396 -221.973647) (xy 125.58829 -222.024824) (xy 125.572278 -222.074103) (xy 125.548755 -222.12027)
			(xy 125.518299 -222.162189) (xy 125.481661 -222.198827) (xy 125.439742 -222.229283) (xy 125.393575 -222.252806)
			(xy 125.344296 -222.268818) (xy 125.293119 -222.276924) (xy 125.241305 -222.276924) (xy 125.190128 -222.268818)
			(xy 125.140849 -222.252806) (xy 125.094682 -222.229283) (xy 125.052763 -222.198827) (xy 125.016125 -222.162189)
			(xy 124.985669 -222.12027) (xy 124.962146 -222.074103) (xy 124.946134 -222.024824) (xy 124.938028 -221.973647)
			(xy 124.93752 -221.94774) (xy 123.717304 -221.94774) (xy 123.716796 -221.973647) (xy 123.70869 -222.024824)
			(xy 123.692678 -222.074103) (xy 123.669155 -222.12027) (xy 123.638699 -222.162189) (xy 123.602061 -222.198827)
			(xy 123.560142 -222.229283) (xy 123.513975 -222.252806) (xy 123.464696 -222.268818) (xy 123.413519 -222.276924)
			(xy 123.361705 -222.276924) (xy 123.310528 -222.268818) (xy 123.261249 -222.252806) (xy 123.215082 -222.229283)
			(xy 123.173163 -222.198827) (xy 123.136525 -222.162189) (xy 123.106069 -222.12027) (xy 123.082546 -222.074103)
			(xy 123.066534 -222.024824) (xy 123.058428 -221.973647) (xy 123.05792 -221.94774) (xy 121.837704 -221.94774)
			(xy 121.837196 -221.973647) (xy 121.82909 -222.024824) (xy 121.813078 -222.074103) (xy 121.789555 -222.12027)
			(xy 121.759099 -222.162189) (xy 121.722461 -222.198827) (xy 121.680542 -222.229283) (xy 121.634375 -222.252806)
			(xy 121.585096 -222.268818) (xy 121.533919 -222.276924) (xy 121.482105 -222.276924) (xy 121.430928 -222.268818)
			(xy 121.381649 -222.252806) (xy 121.335482 -222.229283) (xy 121.293563 -222.198827) (xy 121.256925 -222.162189)
			(xy 121.226469 -222.12027) (xy 121.202946 -222.074103) (xy 121.186934 -222.024824) (xy 121.178828 -221.973647)
			(xy 121.17832 -221.94774) (xy 118.078504 -221.94774) (xy 118.077996 -221.973647) (xy 118.06989 -222.024824)
			(xy 118.053878 -222.074103) (xy 118.030355 -222.12027) (xy 117.999899 -222.162189) (xy 117.963261 -222.198827)
			(xy 117.921342 -222.229283) (xy 117.875175 -222.252806) (xy 117.825896 -222.268818) (xy 117.774719 -222.276924)
			(xy 117.722905 -222.276924) (xy 117.671728 -222.268818) (xy 117.622449 -222.252806) (xy 117.576282 -222.229283)
			(xy 117.534363 -222.198827) (xy 117.497725 -222.162189) (xy 117.467269 -222.12027) (xy 117.443746 -222.074103)
			(xy 117.427734 -222.024824) (xy 117.419628 -221.973647) (xy 117.41912 -221.94774) (xy 116.198904 -221.94774)
			(xy 116.198396 -221.973647) (xy 116.19029 -222.024824) (xy 116.174278 -222.074103) (xy 116.150755 -222.12027)
			(xy 116.120299 -222.162189) (xy 116.083661 -222.198827) (xy 116.041742 -222.229283) (xy 115.995575 -222.252806)
			(xy 115.946296 -222.268818) (xy 115.895119 -222.276924) (xy 115.843305 -222.276924) (xy 115.792128 -222.268818)
			(xy 115.742849 -222.252806) (xy 115.696682 -222.229283) (xy 115.654763 -222.198827) (xy 115.618125 -222.162189)
			(xy 115.587669 -222.12027) (xy 115.564146 -222.074103) (xy 115.548134 -222.024824) (xy 115.540028 -221.973647)
			(xy 115.53952 -221.94774) (xy 114.319304 -221.94774) (xy 114.318796 -221.973627) (xy 114.310697 -222.024765)
			(xy 114.294698 -222.074005) (xy 114.271192 -222.120137) (xy 114.24076 -222.162024) (xy 114.20415 -222.198634)
			(xy 114.162263 -222.229066) (xy 114.116131 -222.252572) (xy 114.066891 -222.268571) (xy 114.015753 -222.27667)
			(xy 113.963979 -222.27667) (xy 113.912841 -222.268571) (xy 113.863601 -222.252572) (xy 113.817469 -222.229066)
			(xy 113.775582 -222.198634) (xy 113.738972 -222.162024) (xy 113.70854 -222.120137) (xy 113.685034 -222.074005)
			(xy 113.669035 -222.024765) (xy 113.660936 -221.973627) (xy 113.660428 -221.94774) (xy 112.439704 -221.94774)
			(xy 112.439196 -221.973647) (xy 112.43109 -222.024824) (xy 112.415078 -222.074103) (xy 112.391555 -222.12027)
			(xy 112.361099 -222.162189) (xy 112.324461 -222.198827) (xy 112.282542 -222.229283) (xy 112.236375 -222.252806)
			(xy 112.187096 -222.268818) (xy 112.135919 -222.276924) (xy 112.084105 -222.276924) (xy 112.032928 -222.268818)
			(xy 111.983649 -222.252806) (xy 111.937482 -222.229283) (xy 111.895563 -222.198827) (xy 111.858925 -222.162189)
			(xy 111.828469 -222.12027) (xy 111.804946 -222.074103) (xy 111.788934 -222.024824) (xy 111.780828 -221.973647)
			(xy 111.78032 -221.94774) (xy 110.560104 -221.94774) (xy 110.559596 -221.973627) (xy 110.551497 -222.024765)
			(xy 110.535498 -222.074005) (xy 110.511992 -222.120137) (xy 110.48156 -222.162024) (xy 110.44495 -222.198634)
			(xy 110.403063 -222.229066) (xy 110.356931 -222.252572) (xy 110.307691 -222.268571) (xy 110.256553 -222.27667)
			(xy 110.204779 -222.27667) (xy 110.153641 -222.268571) (xy 110.104401 -222.252572) (xy 110.058269 -222.229066)
			(xy 110.016382 -222.198634) (xy 109.979772 -222.162024) (xy 109.94934 -222.120137) (xy 109.925834 -222.074005)
			(xy 109.909835 -222.024765) (xy 109.901736 -221.973627) (xy 109.901228 -221.94774) (xy 108.680504 -221.94774)
			(xy 108.679996 -221.973647) (xy 108.67189 -222.024824) (xy 108.655878 -222.074103) (xy 108.632355 -222.12027)
			(xy 108.601899 -222.162189) (xy 108.565261 -222.198827) (xy 108.523342 -222.229283) (xy 108.477175 -222.252806)
			(xy 108.427896 -222.268818) (xy 108.376719 -222.276924) (xy 108.324905 -222.276924) (xy 108.273728 -222.268818)
			(xy 108.224449 -222.252806) (xy 108.178282 -222.229283) (xy 108.136363 -222.198827) (xy 108.099725 -222.162189)
			(xy 108.069269 -222.12027) (xy 108.045746 -222.074103) (xy 108.029734 -222.024824) (xy 108.021628 -221.973647)
			(xy 108.02112 -221.94774) (xy 106.800904 -221.94774) (xy 106.800396 -221.973647) (xy 106.79229 -222.024824)
			(xy 106.776278 -222.074103) (xy 106.752755 -222.12027) (xy 106.722299 -222.162189) (xy 106.685661 -222.198827)
			(xy 106.643742 -222.229283) (xy 106.597575 -222.252806) (xy 106.548296 -222.268818) (xy 106.497119 -222.276924)
			(xy 106.445305 -222.276924) (xy 106.394128 -222.268818) (xy 106.344849 -222.252806) (xy 106.298682 -222.229283)
			(xy 106.256763 -222.198827) (xy 106.220125 -222.162189) (xy 106.189669 -222.12027) (xy 106.166146 -222.074103)
			(xy 106.150134 -222.024824) (xy 106.142028 -221.973647) (xy 106.14152 -221.94774) (xy 104.921304 -221.94774)
			(xy 104.920796 -221.973647) (xy 104.91269 -222.024824) (xy 104.896678 -222.074103) (xy 104.873155 -222.12027)
			(xy 104.842699 -222.162189) (xy 104.806061 -222.198827) (xy 104.764142 -222.229283) (xy 104.717975 -222.252806)
			(xy 104.668696 -222.268818) (xy 104.617519 -222.276924) (xy 104.565705 -222.276924) (xy 104.514528 -222.268818)
			(xy 104.465249 -222.252806) (xy 104.419082 -222.229283) (xy 104.377163 -222.198827) (xy 104.340525 -222.162189)
			(xy 104.310069 -222.12027) (xy 104.286546 -222.074103) (xy 104.270534 -222.024824) (xy 104.262428 -221.973647)
			(xy 104.26192 -221.94774) (xy 103.041704 -221.94774) (xy 103.041196 -221.973647) (xy 103.03309 -222.024824)
			(xy 103.017078 -222.074103) (xy 102.993555 -222.12027) (xy 102.963099 -222.162189) (xy 102.926461 -222.198827)
			(xy 102.884542 -222.229283) (xy 102.838375 -222.252806) (xy 102.789096 -222.268818) (xy 102.737919 -222.276924)
			(xy 102.686105 -222.276924) (xy 102.634928 -222.268818) (xy 102.585649 -222.252806) (xy 102.539482 -222.229283)
			(xy 102.497563 -222.198827) (xy 102.460925 -222.162189) (xy 102.430469 -222.12027) (xy 102.406946 -222.074103)
			(xy 102.390934 -222.024824) (xy 102.382828 -221.973647) (xy 102.38232 -221.94774) (xy 102.382923 -221.920023)
			(xy 102.39224 -221.865377) (xy 102.400862 -221.839028) (xy 102.408736 -221.81693) (xy 102.203758 -221.462092)
			(xy 102.180898 -221.457774) (xy 102.156103 -221.45255) (xy 102.108367 -221.435564) (xy 102.063792 -221.411474)
			(xy 102.023427 -221.380847) (xy 101.988224 -221.344405) (xy 101.959011 -221.303006) (xy 101.936476 -221.257625)
			(xy 101.92115 -221.20933) (xy 101.913394 -221.159258) (xy 101.912928 -221.133924) (xy 101.632004 -221.133924)
			(xy 101.631496 -221.159811) (xy 101.623397 -221.210949) (xy 101.607398 -221.260189) (xy 101.583892 -221.306321)
			(xy 101.55346 -221.348208) (xy 101.51685 -221.384818) (xy 101.474963 -221.41525) (xy 101.428831 -221.438756)
			(xy 101.379591 -221.454755) (xy 101.328453 -221.462854) (xy 101.276679 -221.462854) (xy 101.225541 -221.454755)
			(xy 101.176301 -221.438756) (xy 101.130169 -221.41525) (xy 101.088282 -221.384818) (xy 101.051672 -221.348208)
			(xy 101.02124 -221.306321) (xy 100.997734 -221.260189) (xy 100.981735 -221.210949) (xy 100.973636 -221.159811)
			(xy 100.973128 -221.133924) (xy 100.692204 -221.133924) (xy 100.69168 -221.161632) (xy 100.682481 -221.216279)
			(xy 100.673916 -221.242636) (xy 100.666042 -221.264734) (xy 100.87102 -221.619572) (xy 100.89388 -221.62389)
			(xy 100.918705 -221.629041) (xy 100.966483 -221.645999) (xy 101.011102 -221.670074) (xy 101.051507 -221.700696)
			(xy 101.086747 -221.737145) (xy 101.11599 -221.778561) (xy 101.138547 -221.823965) (xy 101.153885 -221.872289)
			(xy 101.161642 -221.92239) (xy 101.162104 -221.94774) (xy 101.161596 -221.973647) (xy 101.15349 -222.024824)
			(xy 101.137478 -222.074103) (xy 101.113955 -222.12027) (xy 101.083499 -222.162189) (xy 101.046861 -222.198827)
			(xy 101.004942 -222.229283) (xy 100.958775 -222.252806) (xy 100.909496 -222.268818) (xy 100.858319 -222.276924)
			(xy 100.806505 -222.276924) (xy 100.755328 -222.268818) (xy 100.706049 -222.252806) (xy 100.659882 -222.229283)
			(xy 100.617963 -222.198827) (xy 100.581325 -222.162189) (xy 100.550869 -222.12027) (xy 100.527346 -222.074103)
			(xy 100.511334 -222.024824) (xy 100.503228 -221.973647) (xy 100.50272 -221.94774) (xy 100.503323 -221.920023)
			(xy 100.51264 -221.865377) (xy 100.521262 -221.839028) (xy 100.529136 -221.81693) (xy 100.324158 -221.462092)
			(xy 100.301298 -221.457774) (xy 100.276503 -221.45255) (xy 100.228767 -221.435564) (xy 100.184192 -221.411474)
			(xy 100.143827 -221.380847) (xy 100.108624 -221.344405) (xy 100.079411 -221.303006) (xy 100.056876 -221.257625)
			(xy 100.04155 -221.20933) (xy 100.033794 -221.159258) (xy 100.033328 -221.133924) (xy 99.752404 -221.133924)
			(xy 99.751896 -221.159811) (xy 99.743797 -221.210949) (xy 99.727798 -221.260189) (xy 99.704292 -221.306321)
			(xy 99.67386 -221.348208) (xy 99.63725 -221.384818) (xy 99.595363 -221.41525) (xy 99.549231 -221.438756)
			(xy 99.499991 -221.454755) (xy 99.448853 -221.462854) (xy 99.397079 -221.462854) (xy 99.345941 -221.454755)
			(xy 99.296701 -221.438756) (xy 99.250569 -221.41525) (xy 99.208682 -221.384818) (xy 99.172072 -221.348208)
			(xy 99.14164 -221.306321) (xy 99.118134 -221.260189) (xy 99.102135 -221.210949) (xy 99.094036 -221.159811)
			(xy 99.093528 -221.133924) (xy 98.812604 -221.133924) (xy 98.81208 -221.161632) (xy 98.802881 -221.216279)
			(xy 98.794316 -221.242636) (xy 98.786442 -221.264734) (xy 98.99142 -221.619572) (xy 99.01428 -221.62389)
			(xy 99.039105 -221.629041) (xy 99.086883 -221.645999) (xy 99.131502 -221.670074) (xy 99.171907 -221.700696)
			(xy 99.207147 -221.737145) (xy 99.23639 -221.778561) (xy 99.258947 -221.823965) (xy 99.274285 -221.872289)
			(xy 99.282042 -221.92239) (xy 99.282504 -221.94774) (xy 99.281996 -221.973647) (xy 99.27389 -222.024824)
			(xy 99.257878 -222.074103) (xy 99.234355 -222.12027) (xy 99.203899 -222.162189) (xy 99.167261 -222.198827)
			(xy 99.125342 -222.229283) (xy 99.079175 -222.252806) (xy 99.029896 -222.268818) (xy 98.978719 -222.276924)
			(xy 98.926905 -222.276924) (xy 98.875728 -222.268818) (xy 98.826449 -222.252806) (xy 98.780282 -222.229283)
			(xy 98.738363 -222.198827) (xy 98.701725 -222.162189) (xy 98.671269 -222.12027) (xy 98.647746 -222.074103)
			(xy 98.631734 -222.024824) (xy 98.623628 -221.973647) (xy 98.62312 -221.94774) (xy 98.623723 -221.920023)
			(xy 98.63304 -221.865377) (xy 98.641662 -221.839028) (xy 98.649536 -221.81693) (xy 98.444558 -221.462092)
			(xy 98.421698 -221.457774) (xy 98.396903 -221.45255) (xy 98.349167 -221.435564) (xy 98.304592 -221.411474)
			(xy 98.264227 -221.380847) (xy 98.229024 -221.344405) (xy 98.199811 -221.303006) (xy 98.177276 -221.257625)
			(xy 98.16195 -221.20933) (xy 98.154194 -221.159258) (xy 98.153728 -221.133924) (xy 97.872804 -221.133924)
			(xy 97.872296 -221.159811) (xy 97.864197 -221.210949) (xy 97.848198 -221.260189) (xy 97.824692 -221.306321)
			(xy 97.79426 -221.348208) (xy 97.75765 -221.384818) (xy 97.715763 -221.41525) (xy 97.669631 -221.438756)
			(xy 97.620391 -221.454755) (xy 97.569253 -221.462854) (xy 97.517479 -221.462854) (xy 97.466341 -221.454755)
			(xy 97.417101 -221.438756) (xy 97.370969 -221.41525) (xy 97.329082 -221.384818) (xy 97.292472 -221.348208)
			(xy 97.26204 -221.306321) (xy 97.238534 -221.260189) (xy 97.222535 -221.210949) (xy 97.214436 -221.159811)
			(xy 97.213928 -221.133924) (xy 96.933004 -221.133924) (xy 96.93248 -221.161632) (xy 96.923281 -221.216279)
			(xy 96.914716 -221.242636) (xy 96.906842 -221.264734) (xy 97.11182 -221.619572) (xy 97.13468 -221.62389)
			(xy 97.159505 -221.629041) (xy 97.207283 -221.645999) (xy 97.251902 -221.670074) (xy 97.292307 -221.700696)
			(xy 97.327547 -221.737145) (xy 97.35679 -221.778561) (xy 97.379347 -221.823965) (xy 97.394685 -221.872289)
			(xy 97.402442 -221.92239) (xy 97.402904 -221.94774) (xy 97.402396 -221.973647) (xy 97.39429 -222.024824)
			(xy 97.378278 -222.074103) (xy 97.354755 -222.12027) (xy 97.324299 -222.162189) (xy 97.287661 -222.198827)
			(xy 97.245742 -222.229283) (xy 97.199575 -222.252806) (xy 97.150296 -222.268818) (xy 97.099119 -222.276924)
			(xy 97.047305 -222.276924) (xy 96.996128 -222.268818) (xy 96.946849 -222.252806) (xy 96.900682 -222.229283)
			(xy 96.858763 -222.198827) (xy 96.822125 -222.162189) (xy 96.791669 -222.12027) (xy 96.768146 -222.074103)
			(xy 96.752134 -222.024824) (xy 96.744028 -221.973647) (xy 96.74352 -221.94774) (xy 96.744123 -221.920023)
			(xy 96.75344 -221.865377) (xy 96.762062 -221.839028) (xy 96.769936 -221.81693) (xy 96.564958 -221.462092)
			(xy 96.542098 -221.457774) (xy 96.517303 -221.45255) (xy 96.469567 -221.435564) (xy 96.424992 -221.411474)
			(xy 96.384627 -221.380847) (xy 96.349424 -221.344405) (xy 96.320211 -221.303006) (xy 96.297676 -221.257625)
			(xy 96.28235 -221.20933) (xy 96.274594 -221.159258) (xy 96.274128 -221.133924) (xy 95.993204 -221.133924)
			(xy 95.992696 -221.159811) (xy 95.984597 -221.210949) (xy 95.968598 -221.260189) (xy 95.945092 -221.306321)
			(xy 95.91466 -221.348208) (xy 95.87805 -221.384818) (xy 95.836163 -221.41525) (xy 95.790031 -221.438756)
			(xy 95.740791 -221.454755) (xy 95.689653 -221.462854) (xy 95.637879 -221.462854) (xy 95.586741 -221.454755)
			(xy 95.537501 -221.438756) (xy 95.491369 -221.41525) (xy 95.449482 -221.384818) (xy 95.412872 -221.348208)
			(xy 95.38244 -221.306321) (xy 95.358934 -221.260189) (xy 95.342935 -221.210949) (xy 95.334836 -221.159811)
			(xy 95.334328 -221.133924) (xy 95.053404 -221.133924) (xy 95.05288 -221.161632) (xy 95.043681 -221.216279)
			(xy 95.035116 -221.242636) (xy 95.027242 -221.264734) (xy 95.23222 -221.619572) (xy 95.25508 -221.62389)
			(xy 95.279905 -221.629041) (xy 95.327683 -221.645999) (xy 95.372302 -221.670074) (xy 95.412707 -221.700696)
			(xy 95.447947 -221.737145) (xy 95.47719 -221.778561) (xy 95.499747 -221.823965) (xy 95.515085 -221.872289)
			(xy 95.522842 -221.92239) (xy 95.523304 -221.94774) (xy 95.522796 -221.973647) (xy 95.51469 -222.024824)
			(xy 95.498678 -222.074103) (xy 95.475155 -222.12027) (xy 95.444699 -222.162189) (xy 95.408061 -222.198827)
			(xy 95.366142 -222.229283) (xy 95.319975 -222.252806) (xy 95.270696 -222.268818) (xy 95.219519 -222.276924)
			(xy 95.167705 -222.276924) (xy 95.116528 -222.268818) (xy 95.067249 -222.252806) (xy 95.021082 -222.229283)
			(xy 94.979163 -222.198827) (xy 94.942525 -222.162189) (xy 94.912069 -222.12027) (xy 94.888546 -222.074103)
			(xy 94.872534 -222.024824) (xy 94.864428 -221.973647) (xy 94.86392 -221.94774) (xy 94.864523 -221.920023)
			(xy 94.87384 -221.865377) (xy 94.882462 -221.839028) (xy 94.890336 -221.81693) (xy 94.685358 -221.462092)
			(xy 94.662498 -221.457774) (xy 94.637703 -221.45255) (xy 94.589967 -221.435564) (xy 94.545392 -221.411474)
			(xy 94.505027 -221.380847) (xy 94.469824 -221.344405) (xy 94.440611 -221.303006) (xy 94.418076 -221.257625)
			(xy 94.40275 -221.20933) (xy 94.394994 -221.159258) (xy 94.394528 -221.133924) (xy 94.113604 -221.133924)
			(xy 94.113096 -221.159811) (xy 94.104997 -221.210949) (xy 94.088998 -221.260189) (xy 94.065492 -221.306321)
			(xy 94.03506 -221.348208) (xy 93.99845 -221.384818) (xy 93.956563 -221.41525) (xy 93.910431 -221.438756)
			(xy 93.861191 -221.454755) (xy 93.810053 -221.462854) (xy 93.758279 -221.462854) (xy 93.707141 -221.454755)
			(xy 93.657901 -221.438756) (xy 93.611769 -221.41525) (xy 93.569882 -221.384818) (xy 93.533272 -221.348208)
			(xy 93.50284 -221.306321) (xy 93.479334 -221.260189) (xy 93.463335 -221.210949) (xy 93.455236 -221.159811)
			(xy 93.454728 -221.133924) (xy 93.173804 -221.133924) (xy 93.17328 -221.161632) (xy 93.164081 -221.216279)
			(xy 93.155516 -221.242636) (xy 93.147642 -221.264734) (xy 93.35262 -221.619572) (xy 93.37548 -221.62389)
			(xy 93.400305 -221.629041) (xy 93.448083 -221.645999) (xy 93.492702 -221.670074) (xy 93.533107 -221.700696)
			(xy 93.568347 -221.737145) (xy 93.59759 -221.778561) (xy 93.620147 -221.823965) (xy 93.635485 -221.872289)
			(xy 93.643242 -221.92239) (xy 93.643704 -221.94774) (xy 93.643196 -221.973647) (xy 93.63509 -222.024824)
			(xy 93.619078 -222.074103) (xy 93.595555 -222.12027) (xy 93.565099 -222.162189) (xy 93.528461 -222.198827)
			(xy 93.486542 -222.229283) (xy 93.440375 -222.252806) (xy 93.391096 -222.268818) (xy 93.339919 -222.276924)
			(xy 93.288105 -222.276924) (xy 93.236928 -222.268818) (xy 93.187649 -222.252806) (xy 93.141482 -222.229283)
			(xy 93.099563 -222.198827) (xy 93.062925 -222.162189) (xy 93.032469 -222.12027) (xy 93.008946 -222.074103)
			(xy 92.992934 -222.024824) (xy 92.984828 -221.973647) (xy 92.98432 -221.94774) (xy 92.984923 -221.920023)
			(xy 92.99424 -221.865377) (xy 93.002862 -221.839028) (xy 93.010736 -221.81693) (xy 92.805758 -221.462092)
			(xy 92.782898 -221.457774) (xy 92.758103 -221.45255) (xy 92.710367 -221.435564) (xy 92.665792 -221.411474)
			(xy 92.625427 -221.380847) (xy 92.590224 -221.344405) (xy 92.561011 -221.303006) (xy 92.538476 -221.257625)
			(xy 92.52315 -221.20933) (xy 92.515394 -221.159258) (xy 92.514928 -221.133924) (xy 92.234004 -221.133924)
			(xy 92.233496 -221.159811) (xy 92.225397 -221.210949) (xy 92.209398 -221.260189) (xy 92.185892 -221.306321)
			(xy 92.15546 -221.348208) (xy 92.11885 -221.384818) (xy 92.076963 -221.41525) (xy 92.030831 -221.438756)
			(xy 91.981591 -221.454755) (xy 91.930453 -221.462854) (xy 91.878679 -221.462854) (xy 91.827541 -221.454755)
			(xy 91.778301 -221.438756) (xy 91.732169 -221.41525) (xy 91.690282 -221.384818) (xy 91.653672 -221.348208)
			(xy 91.62324 -221.306321) (xy 91.599734 -221.260189) (xy 91.583735 -221.210949) (xy 91.575636 -221.159811)
			(xy 91.575128 -221.133924) (xy 91.294204 -221.133924) (xy 91.29368 -221.161632) (xy 91.284481 -221.216279)
			(xy 91.275916 -221.242636) (xy 91.268042 -221.264734) (xy 91.47302 -221.619572) (xy 91.49588 -221.62389)
			(xy 91.520705 -221.629041) (xy 91.568483 -221.645999) (xy 91.613102 -221.670074) (xy 91.653507 -221.700696)
			(xy 91.688747 -221.737145) (xy 91.71799 -221.778561) (xy 91.740547 -221.823965) (xy 91.755885 -221.872289)
			(xy 91.763642 -221.92239) (xy 91.764104 -221.94774) (xy 91.763596 -221.973647) (xy 91.75549 -222.024824)
			(xy 91.739478 -222.074103) (xy 91.715955 -222.12027) (xy 91.685499 -222.162189) (xy 91.648861 -222.198827)
			(xy 91.606942 -222.229283) (xy 91.560775 -222.252806) (xy 91.511496 -222.268818) (xy 91.460319 -222.276924)
			(xy 91.408505 -222.276924) (xy 91.357328 -222.268818) (xy 91.308049 -222.252806) (xy 91.261882 -222.229283)
			(xy 91.219963 -222.198827) (xy 91.183325 -222.162189) (xy 91.152869 -222.12027) (xy 91.129346 -222.074103)
			(xy 91.113334 -222.024824) (xy 91.105228 -221.973647) (xy 91.10472 -221.94774) (xy 91.105323 -221.920023)
			(xy 91.11464 -221.865377) (xy 91.123262 -221.839028) (xy 91.131136 -221.81693) (xy 90.926158 -221.462092)
			(xy 90.903298 -221.457774) (xy 90.878503 -221.45255) (xy 90.830767 -221.435564) (xy 90.786192 -221.411474)
			(xy 90.745827 -221.380847) (xy 90.710624 -221.344405) (xy 90.681411 -221.303006) (xy 90.658876 -221.257625)
			(xy 90.64355 -221.20933) (xy 90.635794 -221.159258) (xy 90.635328 -221.133924) (xy 90.354404 -221.133924)
			(xy 90.353896 -221.159811) (xy 90.345797 -221.210949) (xy 90.329798 -221.260189) (xy 90.306292 -221.306321)
			(xy 90.27586 -221.348208) (xy 90.23925 -221.384818) (xy 90.197363 -221.41525) (xy 90.151231 -221.438756)
			(xy 90.101991 -221.454755) (xy 90.050853 -221.462854) (xy 89.999079 -221.462854) (xy 89.947941 -221.454755)
			(xy 89.898701 -221.438756) (xy 89.852569 -221.41525) (xy 89.810682 -221.384818) (xy 89.774072 -221.348208)
			(xy 89.74364 -221.306321) (xy 89.720134 -221.260189) (xy 89.704135 -221.210949) (xy 89.696036 -221.159811)
			(xy 89.695528 -221.133924) (xy 89.414604 -221.133924) (xy 89.41408 -221.161632) (xy 89.404881 -221.216279)
			(xy 89.396316 -221.242636) (xy 89.388442 -221.264734) (xy 89.59342 -221.619572) (xy 89.61628 -221.62389)
			(xy 89.641105 -221.629041) (xy 89.688883 -221.645999) (xy 89.733502 -221.670074) (xy 89.773907 -221.700696)
			(xy 89.809147 -221.737145) (xy 89.83839 -221.778561) (xy 89.860947 -221.823965) (xy 89.876285 -221.872289)
			(xy 89.884042 -221.92239) (xy 89.884504 -221.94774) (xy 89.883996 -221.973647) (xy 89.87589 -222.024824)
			(xy 89.859878 -222.074103) (xy 89.836355 -222.12027) (xy 89.805899 -222.162189) (xy 89.769261 -222.198827)
			(xy 89.727342 -222.229283) (xy 89.681175 -222.252806) (xy 89.631896 -222.268818) (xy 89.580719 -222.276924)
			(xy 89.528905 -222.276924) (xy 89.477728 -222.268818) (xy 89.428449 -222.252806) (xy 89.382282 -222.229283)
			(xy 89.340363 -222.198827) (xy 89.303725 -222.162189) (xy 89.273269 -222.12027) (xy 89.249746 -222.074103)
			(xy 89.233734 -222.024824) (xy 89.225628 -221.973647) (xy 89.22512 -221.94774) (xy 89.225723 -221.920023)
			(xy 89.23504 -221.865377) (xy 89.243662 -221.839028) (xy 89.251536 -221.81693) (xy 89.046558 -221.462092)
			(xy 89.023698 -221.457774) (xy 88.998903 -221.45255) (xy 88.951167 -221.435564) (xy 88.906592 -221.411474)
			(xy 88.866227 -221.380847) (xy 88.831024 -221.344405) (xy 88.801811 -221.303006) (xy 88.779276 -221.257625)
			(xy 88.76395 -221.20933) (xy 88.756194 -221.159258) (xy 88.755728 -221.133924) (xy 61.698632 -221.133924)
			(xy 61.698632 -221.321376) (xy 61.69816 -221.331525) (xy 61.690378 -221.35027) (xy 61.675997 -221.364594)
			(xy 61.65722 -221.3723) (xy 61.64707 -221.372684) (xy 60.24753 -221.372684) (xy 60.237408 -221.37215)
			(xy 60.218692 -221.364436) (xy 60.204336 -221.350165) (xy 60.196511 -221.331495) (xy 60.195968 -221.321376)
			(xy 54.154832 -221.321376) (xy 54.15436 -221.331525) (xy 54.146578 -221.35027) (xy 54.132197 -221.364594)
			(xy 54.11342 -221.3723) (xy 54.10327 -221.372684) (xy 52.70373 -221.372684) (xy 52.693608 -221.37215)
			(xy 52.674892 -221.364436) (xy 52.660536 -221.350165) (xy 52.652711 -221.331495) (xy 52.652168 -221.321376)
			(xy 46.611032 -221.321376) (xy 46.61056 -221.331525) (xy 46.602778 -221.35027) (xy 46.588397 -221.364594)
			(xy 46.56962 -221.3723) (xy 46.55947 -221.372684) (xy 45.15993 -221.372684) (xy 45.149808 -221.37215)
			(xy 45.131092 -221.364436) (xy 45.116736 -221.350165) (xy 45.108911 -221.331495) (xy 45.108368 -221.321376)
			(xy 39.067232 -221.321376) (xy 39.06676 -221.331525) (xy 39.058978 -221.35027) (xy 39.044597 -221.364594)
			(xy 39.02582 -221.3723) (xy 39.01567 -221.372684) (xy 37.61613 -221.372684) (xy 37.606008 -221.37215)
			(xy 37.587292 -221.364436) (xy 37.572936 -221.350165) (xy 37.565111 -221.331495) (xy 37.564568 -221.321376)
			(xy 31.523432 -221.321376) (xy 31.52296 -221.331525) (xy 31.515178 -221.35027) (xy 31.500797 -221.364594)
			(xy 31.48202 -221.3723) (xy 31.47187 -221.372684) (xy 30.07233 -221.372684) (xy 30.062208 -221.37215)
			(xy 30.043492 -221.364436) (xy 30.029136 -221.350165) (xy 30.021311 -221.331495) (xy 30.020768 -221.321376)
			(xy 23.979632 -221.321376) (xy 23.97916 -221.331525) (xy 23.971378 -221.35027) (xy 23.956997 -221.364594)
			(xy 23.93822 -221.3723) (xy 23.92807 -221.372684) (xy 22.52853 -221.372684) (xy 22.518408 -221.37215)
			(xy 22.499692 -221.364436) (xy 22.485336 -221.350165) (xy 22.477511 -221.331495) (xy 22.476968 -221.321376)
			(xy 16.435832 -221.321376) (xy 16.43536 -221.331525) (xy 16.427578 -221.35027) (xy 16.413197 -221.364594)
			(xy 16.39442 -221.3723) (xy 16.38427 -221.372684) (xy 14.98473 -221.372684) (xy 14.974608 -221.37215)
			(xy 14.955892 -221.364436) (xy 14.941536 -221.350165) (xy 14.933711 -221.331495) (xy 14.933168 -221.321376)
			(xy 8.892032 -221.321376) (xy 8.89156 -221.331525) (xy 8.883778 -221.35027) (xy 8.869397 -221.364594)
			(xy 8.85062 -221.3723) (xy 8.84047 -221.372684) (xy 7.44093 -221.372684) (xy 7.430808 -221.37215)
			(xy 7.412092 -221.364436) (xy 7.397736 -221.350165) (xy 7.389911 -221.331495) (xy 7.389368 -221.321376)
			(xy 2.509012 -221.321376) (xy 2.509012 -222.171514) (xy 11.489436 -222.171514) (xy 11.489436 -221.762574)
			(xy 11.489912 -221.752415) (xy 11.497695 -221.733645) (xy 11.512066 -221.719281) (xy 11.530839 -221.711507)
			(xy 11.540998 -221.711012) (xy 12.940538 -221.711012) (xy 12.950695 -221.711502) (xy 12.96946 -221.719284)
			(xy 12.983823 -221.73365) (xy 12.991601 -221.752417) (xy 12.9921 -221.762574) (xy 12.9921 -222.171514)
			(xy 19.033236 -222.171514) (xy 19.033236 -221.762574) (xy 19.033712 -221.752415) (xy 19.041495 -221.733645)
			(xy 19.055866 -221.719281) (xy 19.074639 -221.711507) (xy 19.084798 -221.711012) (xy 20.484338 -221.711012)
			(xy 20.494495 -221.711502) (xy 20.51326 -221.719284) (xy 20.527623 -221.73365) (xy 20.535401 -221.752417)
			(xy 20.5359 -221.762574) (xy 20.5359 -222.171514) (xy 26.577036 -222.171514) (xy 26.577036 -221.762574)
			(xy 26.577512 -221.752415) (xy 26.585295 -221.733645) (xy 26.599666 -221.719281) (xy 26.618439 -221.711507)
			(xy 26.628598 -221.711012) (xy 28.028138 -221.711012) (xy 28.038295 -221.711502) (xy 28.05706 -221.719284)
			(xy 28.071423 -221.73365) (xy 28.079201 -221.752417) (xy 28.0797 -221.762574) (xy 28.0797 -222.171514)
			(xy 34.120836 -222.171514) (xy 34.120836 -221.762574) (xy 34.121312 -221.752415) (xy 34.129095 -221.733645)
			(xy 34.143466 -221.719281) (xy 34.162239 -221.711507) (xy 34.172398 -221.711012) (xy 35.571938 -221.711012)
			(xy 35.582095 -221.711502) (xy 35.60086 -221.719284) (xy 35.615223 -221.73365) (xy 35.623001 -221.752417)
			(xy 35.6235 -221.762574) (xy 35.6235 -222.171514) (xy 41.664636 -222.171514) (xy 41.664636 -221.762574)
			(xy 41.665112 -221.752415) (xy 41.672895 -221.733645) (xy 41.687266 -221.719281) (xy 41.706039 -221.711507)
			(xy 41.716198 -221.711012) (xy 43.115738 -221.711012) (xy 43.125895 -221.711502) (xy 43.14466 -221.719284)
			(xy 43.159023 -221.73365) (xy 43.166801 -221.752417) (xy 43.1673 -221.762574) (xy 43.1673 -222.171514)
			(xy 49.208436 -222.171514) (xy 49.208436 -221.762574) (xy 49.208912 -221.752415) (xy 49.216695 -221.733645)
			(xy 49.231066 -221.719281) (xy 49.249839 -221.711507) (xy 49.259998 -221.711012) (xy 50.659538 -221.711012)
			(xy 50.669695 -221.711502) (xy 50.68846 -221.719284) (xy 50.702823 -221.73365) (xy 50.710601 -221.752417)
			(xy 50.7111 -221.762574) (xy 50.7111 -222.171514) (xy 56.752236 -222.171514) (xy 56.752236 -221.762574)
			(xy 56.752712 -221.752415) (xy 56.760495 -221.733645) (xy 56.774866 -221.719281) (xy 56.793639 -221.711507)
			(xy 56.803798 -221.711012) (xy 58.203338 -221.711012) (xy 58.213495 -221.711502) (xy 58.23226 -221.719284)
			(xy 58.246623 -221.73365) (xy 58.254401 -221.752417) (xy 58.2549 -221.762574) (xy 58.2549 -222.171514)
			(xy 64.296036 -222.171514) (xy 64.296036 -221.762574) (xy 64.296512 -221.752415) (xy 64.304295 -221.733645)
			(xy 64.318666 -221.719281) (xy 64.337439 -221.711507) (xy 64.347598 -221.711012) (xy 65.747138 -221.711012)
			(xy 65.757295 -221.711502) (xy 65.77606 -221.719284) (xy 65.790423 -221.73365) (xy 65.798201 -221.752417)
			(xy 65.7987 -221.762574) (xy 65.7987 -222.171514) (xy 65.798179 -222.181668) (xy 65.790407 -222.20043)
			(xy 65.77605 -222.214793) (xy 65.757292 -222.222574) (xy 65.747138 -222.223076) (xy 64.347598 -222.223076)
			(xy 64.337442 -222.222569) (xy 64.318675 -222.214796) (xy 64.304311 -222.200435) (xy 64.296534 -222.18167)
			(xy 64.296036 -222.171514) (xy 58.2549 -222.171514) (xy 58.254379 -222.181668) (xy 58.246607 -222.20043)
			(xy 58.23225 -222.214793) (xy 58.213492 -222.222574) (xy 58.203338 -222.223076) (xy 56.803798 -222.223076)
			(xy 56.793642 -222.222569) (xy 56.774875 -222.214796) (xy 56.760511 -222.200435) (xy 56.752734 -222.18167)
			(xy 56.752236 -222.171514) (xy 50.7111 -222.171514) (xy 50.710579 -222.181668) (xy 50.702807 -222.20043)
			(xy 50.68845 -222.214793) (xy 50.669692 -222.222574) (xy 50.659538 -222.223076) (xy 49.259998 -222.223076)
			(xy 49.249842 -222.222569) (xy 49.231075 -222.214796) (xy 49.216711 -222.200435) (xy 49.208934 -222.18167)
			(xy 49.208436 -222.171514) (xy 43.1673 -222.171514) (xy 43.166779 -222.181668) (xy 43.159007 -222.20043)
			(xy 43.14465 -222.214793) (xy 43.125892 -222.222574) (xy 43.115738 -222.223076) (xy 41.716198 -222.223076)
			(xy 41.706042 -222.222569) (xy 41.687275 -222.214796) (xy 41.672911 -222.200435) (xy 41.665134 -222.18167)
			(xy 41.664636 -222.171514) (xy 35.6235 -222.171514) (xy 35.622979 -222.181668) (xy 35.615207 -222.20043)
			(xy 35.60085 -222.214793) (xy 35.582092 -222.222574) (xy 35.571938 -222.223076) (xy 34.172398 -222.223076)
			(xy 34.162242 -222.222569) (xy 34.143475 -222.214796) (xy 34.129111 -222.200435) (xy 34.121334 -222.18167)
			(xy 34.120836 -222.171514) (xy 28.0797 -222.171514) (xy 28.079179 -222.181668) (xy 28.071407 -222.20043)
			(xy 28.05705 -222.214793) (xy 28.038292 -222.222574) (xy 28.028138 -222.223076) (xy 26.628598 -222.223076)
			(xy 26.618442 -222.222569) (xy 26.599675 -222.214796) (xy 26.585311 -222.200435) (xy 26.577534 -222.18167)
			(xy 26.577036 -222.171514) (xy 20.5359 -222.171514) (xy 20.535379 -222.181668) (xy 20.527607 -222.20043)
			(xy 20.51325 -222.214793) (xy 20.494492 -222.222574) (xy 20.484338 -222.223076) (xy 19.084798 -222.223076)
			(xy 19.074642 -222.222569) (xy 19.055875 -222.214796) (xy 19.041511 -222.200435) (xy 19.033734 -222.18167)
			(xy 19.033236 -222.171514) (xy 12.9921 -222.171514) (xy 12.991579 -222.181668) (xy 12.983807 -222.20043)
			(xy 12.96945 -222.214793) (xy 12.950692 -222.222574) (xy 12.940538 -222.223076) (xy 11.540998 -222.223076)
			(xy 11.530842 -222.222569) (xy 11.512075 -222.214796) (xy 11.497711 -222.200435) (xy 11.489934 -222.18167)
			(xy 11.489436 -222.171514) (xy 2.509012 -222.171514) (xy 2.509012 -223.021398) (xy 7.389368 -223.021398)
			(xy 7.389368 -222.612458) (xy 7.3898 -222.602294) (xy 7.397594 -222.583518) (xy 7.411978 -222.569153)
			(xy 7.430765 -222.561386) (xy 7.44093 -222.560896) (xy 8.84047 -222.560896) (xy 8.850621 -222.561457)
			(xy 8.869381 -222.569213) (xy 8.883746 -222.583558) (xy 8.891529 -222.602308) (xy 8.892032 -222.612458)
			(xy 8.892032 -223.021398) (xy 14.933168 -223.021398) (xy 14.933168 -222.612458) (xy 14.9336 -222.602294)
			(xy 14.941394 -222.583518) (xy 14.955778 -222.569153) (xy 14.974565 -222.561386) (xy 14.98473 -222.560896)
			(xy 16.38427 -222.560896) (xy 16.394421 -222.561457) (xy 16.413181 -222.569213) (xy 16.427546 -222.583558)
			(xy 16.435329 -222.602308) (xy 16.435832 -222.612458) (xy 16.435832 -223.021398) (xy 22.476968 -223.021398)
			(xy 22.476968 -222.612458) (xy 22.4774 -222.602294) (xy 22.485194 -222.583518) (xy 22.499578 -222.569153)
			(xy 22.518365 -222.561386) (xy 22.52853 -222.560896) (xy 23.92807 -222.560896) (xy 23.938221 -222.561457)
			(xy 23.956981 -222.569213) (xy 23.971346 -222.583558) (xy 23.979129 -222.602308) (xy 23.979632 -222.612458)
			(xy 23.979632 -223.021398) (xy 30.020768 -223.021398) (xy 30.020768 -222.612458) (xy 30.0212 -222.602294)
			(xy 30.028994 -222.583518) (xy 30.043378 -222.569153) (xy 30.062165 -222.561386) (xy 30.07233 -222.560896)
			(xy 31.47187 -222.560896) (xy 31.482021 -222.561457) (xy 31.500781 -222.569213) (xy 31.515146 -222.583558)
			(xy 31.522929 -222.602308) (xy 31.523432 -222.612458) (xy 31.523432 -223.021398) (xy 37.564568 -223.021398)
			(xy 37.564568 -222.612458) (xy 37.565 -222.602294) (xy 37.572794 -222.583518) (xy 37.587178 -222.569153)
			(xy 37.605965 -222.561386) (xy 37.61613 -222.560896) (xy 39.01567 -222.560896) (xy 39.025821 -222.561457)
			(xy 39.044581 -222.569213) (xy 39.058946 -222.583558) (xy 39.066729 -222.602308) (xy 39.067232 -222.612458)
			(xy 39.067232 -223.021398) (xy 45.108368 -223.021398) (xy 45.108368 -222.612458) (xy 45.1088 -222.602294)
			(xy 45.116594 -222.583518) (xy 45.130978 -222.569153) (xy 45.149765 -222.561386) (xy 45.15993 -222.560896)
			(xy 46.55947 -222.560896) (xy 46.569621 -222.561457) (xy 46.588381 -222.569213) (xy 46.602746 -222.583558)
			(xy 46.610529 -222.602308) (xy 46.611032 -222.612458) (xy 46.611032 -223.021398) (xy 52.652168 -223.021398)
			(xy 52.652168 -222.612458) (xy 52.6526 -222.602294) (xy 52.660394 -222.583518) (xy 52.674778 -222.569153)
			(xy 52.693565 -222.561386) (xy 52.70373 -222.560896) (xy 54.10327 -222.560896) (xy 54.113421 -222.561457)
			(xy 54.132181 -222.569213) (xy 54.146546 -222.583558) (xy 54.154329 -222.602308) (xy 54.154832 -222.612458)
			(xy 54.154832 -223.021398) (xy 60.195968 -223.021398) (xy 60.195968 -222.612458) (xy 60.1964 -222.602294)
			(xy 60.204194 -222.583518) (xy 60.218578 -222.569153) (xy 60.237365 -222.561386) (xy 60.24753 -222.560896)
			(xy 61.64707 -222.560896) (xy 61.657221 -222.561457) (xy 61.675981 -222.569213) (xy 61.690346 -222.583558)
			(xy 61.698129 -222.602308) (xy 61.698632 -222.612458) (xy 61.698632 -223.021398) (xy 158.062168 -223.021398)
			(xy 158.062168 -222.612458) (xy 158.0626 -222.602294) (xy 158.070394 -222.583518) (xy 158.084778 -222.569153)
			(xy 158.103565 -222.561386) (xy 158.11373 -222.560896) (xy 159.51327 -222.560896) (xy 159.523421 -222.561457)
			(xy 159.542181 -222.569213) (xy 159.556546 -222.583558) (xy 159.564329 -222.602308) (xy 159.564832 -222.612458)
			(xy 159.564832 -223.021398) (xy 165.605968 -223.021398) (xy 165.605968 -222.612458) (xy 165.6064 -222.602294)
			(xy 165.614194 -222.583518) (xy 165.628578 -222.569153) (xy 165.647365 -222.561386) (xy 165.65753 -222.560896)
			(xy 167.05707 -222.560896) (xy 167.067221 -222.561457) (xy 167.085981 -222.569213) (xy 167.100346 -222.583558)
			(xy 167.108129 -222.602308) (xy 167.108632 -222.612458) (xy 167.108632 -223.021398) (xy 173.149768 -223.021398)
			(xy 173.149768 -222.612458) (xy 173.1502 -222.602294) (xy 173.157994 -222.583518) (xy 173.172378 -222.569153)
			(xy 173.191165 -222.561386) (xy 173.20133 -222.560896) (xy 174.60087 -222.560896) (xy 174.611021 -222.561457)
			(xy 174.629781 -222.569213) (xy 174.644146 -222.583558) (xy 174.651929 -222.602308) (xy 174.652432 -222.612458)
			(xy 174.652432 -223.021398) (xy 180.693568 -223.021398) (xy 180.693568 -222.612458) (xy 180.694 -222.602294)
			(xy 180.701794 -222.583518) (xy 180.716178 -222.569153) (xy 180.734965 -222.561386) (xy 180.74513 -222.560896)
			(xy 182.14467 -222.560896) (xy 182.154821 -222.561457) (xy 182.173581 -222.569213) (xy 182.187946 -222.583558)
			(xy 182.195729 -222.602308) (xy 182.196232 -222.612458) (xy 182.196232 -223.021398) (xy 188.237368 -223.021398)
			(xy 188.237368 -222.612458) (xy 188.2378 -222.602294) (xy 188.245594 -222.583518) (xy 188.259978 -222.569153)
			(xy 188.278765 -222.561386) (xy 188.28893 -222.560896) (xy 189.68847 -222.560896) (xy 189.698621 -222.561457)
			(xy 189.717381 -222.569213) (xy 189.731746 -222.583558) (xy 189.739529 -222.602308) (xy 189.740032 -222.612458)
			(xy 189.740032 -223.021398) (xy 195.781168 -223.021398) (xy 195.781168 -222.612458) (xy 195.7816 -222.602294)
			(xy 195.789394 -222.583518) (xy 195.803778 -222.569153) (xy 195.822565 -222.561386) (xy 195.83273 -222.560896)
			(xy 197.23227 -222.560896) (xy 197.242421 -222.561457) (xy 197.261181 -222.569213) (xy 197.275546 -222.583558)
			(xy 197.283329 -222.602308) (xy 197.283832 -222.612458) (xy 197.283832 -223.021398) (xy 203.324968 -223.021398)
			(xy 203.324968 -222.612458) (xy 203.3254 -222.602294) (xy 203.333194 -222.583518) (xy 203.347578 -222.569153)
			(xy 203.366365 -222.561386) (xy 203.37653 -222.560896) (xy 204.77607 -222.560896) (xy 204.786221 -222.561457)
			(xy 204.804981 -222.569213) (xy 204.819346 -222.583558) (xy 204.827129 -222.602308) (xy 204.827632 -222.612458)
			(xy 204.827632 -223.021398) (xy 210.868768 -223.021398) (xy 210.868768 -222.612458) (xy 210.8692 -222.602294)
			(xy 210.876994 -222.583518) (xy 210.891378 -222.569153) (xy 210.910165 -222.561386) (xy 210.92033 -222.560896)
			(xy 212.31987 -222.560896) (xy 212.330021 -222.561457) (xy 212.348781 -222.569213) (xy 212.363146 -222.583558)
			(xy 212.370929 -222.602308) (xy 212.371432 -222.612458) (xy 212.371432 -223.021398) (xy 255.329436 -223.021398)
			(xy 255.329436 -222.612458) (xy 255.329899 -222.602298) (xy 255.337687 -222.583528) (xy 255.352062 -222.569164)
			(xy 255.370837 -222.561391) (xy 255.380998 -222.560896) (xy 256.780538 -222.560896) (xy 256.790693 -222.561401)
			(xy 256.809455 -222.56918) (xy 256.823817 -222.583542) (xy 256.831598 -222.602303) (xy 256.8321 -222.612458)
			(xy 256.8321 -223.021398) (xy 262.873236 -223.021398) (xy 262.873236 -222.612458) (xy 262.873699 -222.602298)
			(xy 262.881487 -222.583528) (xy 262.895862 -222.569164) (xy 262.914637 -222.561391) (xy 262.924798 -222.560896)
			(xy 264.324338 -222.560896) (xy 264.334493 -222.561401) (xy 264.353255 -222.56918) (xy 264.367617 -222.583542)
			(xy 264.375398 -222.602303) (xy 264.3759 -222.612458) (xy 264.3759 -223.021398) (xy 270.417036 -223.021398)
			(xy 270.417036 -222.612458) (xy 270.417499 -222.602298) (xy 270.425287 -222.583528) (xy 270.439662 -222.569164)
			(xy 270.458437 -222.561391) (xy 270.468598 -222.560896) (xy 271.868138 -222.560896) (xy 271.878293 -222.561401)
			(xy 271.897055 -222.56918) (xy 271.911417 -222.583542) (xy 271.919198 -222.602303) (xy 271.9197 -222.612458)
			(xy 271.9197 -223.021398) (xy 277.960836 -223.021398) (xy 277.960836 -222.612458) (xy 277.961299 -222.602298)
			(xy 277.969087 -222.583528) (xy 277.983462 -222.569164) (xy 278.002237 -222.561391) (xy 278.012398 -222.560896)
			(xy 279.411938 -222.560896) (xy 279.422093 -222.561401) (xy 279.440855 -222.56918) (xy 279.455217 -222.583542)
			(xy 279.462998 -222.602303) (xy 279.4635 -222.612458) (xy 279.4635 -223.021398) (xy 285.504636 -223.021398)
			(xy 285.504636 -222.612458) (xy 285.505099 -222.602298) (xy 285.512887 -222.583528) (xy 285.527262 -222.569164)
			(xy 285.546037 -222.561391) (xy 285.556198 -222.560896) (xy 286.955738 -222.560896) (xy 286.965893 -222.561401)
			(xy 286.984655 -222.56918) (xy 286.999017 -222.583542) (xy 287.006798 -222.602303) (xy 287.0073 -222.612458)
			(xy 287.0073 -223.021398) (xy 293.048436 -223.021398) (xy 293.048436 -222.612458) (xy 293.048899 -222.602298)
			(xy 293.056687 -222.583528) (xy 293.071062 -222.569164) (xy 293.089837 -222.561391) (xy 293.099998 -222.560896)
			(xy 294.499538 -222.560896) (xy 294.509693 -222.561401) (xy 294.528455 -222.56918) (xy 294.542817 -222.583542)
			(xy 294.550598 -222.602303) (xy 294.5511 -222.612458) (xy 294.5511 -223.021398) (xy 300.592236 -223.021398)
			(xy 300.592236 -222.612458) (xy 300.592699 -222.602298) (xy 300.600487 -222.583528) (xy 300.614862 -222.569164)
			(xy 300.633637 -222.561391) (xy 300.643798 -222.560896) (xy 302.043338 -222.560896) (xy 302.053493 -222.561401)
			(xy 302.072255 -222.56918) (xy 302.086617 -222.583542) (xy 302.094398 -222.602303) (xy 302.0949 -222.612458)
			(xy 302.0949 -223.021398) (xy 308.136036 -223.021398) (xy 308.136036 -222.612458) (xy 308.136499 -222.602298)
			(xy 308.144287 -222.583528) (xy 308.158662 -222.569164) (xy 308.177437 -222.561391) (xy 308.187598 -222.560896)
			(xy 309.587138 -222.560896) (xy 309.597293 -222.561401) (xy 309.616055 -222.56918) (xy 309.630417 -222.583542)
			(xy 309.638198 -222.602303) (xy 309.6387 -222.612458) (xy 309.6387 -223.021398) (xy 406.002236 -223.021398)
			(xy 406.002236 -222.612458) (xy 406.002699 -222.602298) (xy 406.010487 -222.583528) (xy 406.024862 -222.569164)
			(xy 406.043637 -222.561391) (xy 406.053798 -222.560896) (xy 407.453338 -222.560896) (xy 407.463493 -222.561401)
			(xy 407.482255 -222.56918) (xy 407.496617 -222.583542) (xy 407.504398 -222.602303) (xy 407.5049 -222.612458)
			(xy 407.5049 -223.021398) (xy 413.546036 -223.021398) (xy 413.546036 -222.612458) (xy 413.546499 -222.602298)
			(xy 413.554287 -222.583528) (xy 413.568662 -222.569164) (xy 413.587437 -222.561391) (xy 413.597598 -222.560896)
			(xy 414.997138 -222.560896) (xy 415.007293 -222.561401) (xy 415.026055 -222.56918) (xy 415.040417 -222.583542)
			(xy 415.048198 -222.602303) (xy 415.0487 -222.612458) (xy 415.0487 -223.021398) (xy 421.089836 -223.021398)
			(xy 421.089836 -222.612458) (xy 421.090299 -222.602298) (xy 421.098087 -222.583528) (xy 421.112462 -222.569164)
			(xy 421.131237 -222.561391) (xy 421.141398 -222.560896) (xy 422.540938 -222.560896) (xy 422.551093 -222.561401)
			(xy 422.569855 -222.56918) (xy 422.584217 -222.583542) (xy 422.591998 -222.602303) (xy 422.5925 -222.612458)
			(xy 422.5925 -223.021398) (xy 428.633636 -223.021398) (xy 428.633636 -222.612458) (xy 428.634099 -222.602298)
			(xy 428.641887 -222.583528) (xy 428.656262 -222.569164) (xy 428.675037 -222.561391) (xy 428.685198 -222.560896)
			(xy 430.084738 -222.560896) (xy 430.094893 -222.561401) (xy 430.113655 -222.56918) (xy 430.128017 -222.583542)
			(xy 430.135798 -222.602303) (xy 430.1363 -222.612458) (xy 430.1363 -223.021398) (xy 436.177436 -223.021398)
			(xy 436.177436 -222.612458) (xy 436.177899 -222.602298) (xy 436.185687 -222.583528) (xy 436.200062 -222.569164)
			(xy 436.218837 -222.561391) (xy 436.228998 -222.560896) (xy 437.628538 -222.560896) (xy 437.638693 -222.561401)
			(xy 437.657455 -222.56918) (xy 437.671817 -222.583542) (xy 437.679598 -222.602303) (xy 437.6801 -222.612458)
			(xy 437.6801 -223.021398) (xy 443.721236 -223.021398) (xy 443.721236 -222.612458) (xy 443.721699 -222.602298)
			(xy 443.729487 -222.583528) (xy 443.743862 -222.569164) (xy 443.762637 -222.561391) (xy 443.772798 -222.560896)
			(xy 445.172338 -222.560896) (xy 445.182493 -222.561401) (xy 445.201255 -222.56918) (xy 445.215617 -222.583542)
			(xy 445.223398 -222.602303) (xy 445.2239 -222.612458) (xy 445.2239 -223.021398) (xy 451.265036 -223.021398)
			(xy 451.265036 -222.612458) (xy 451.265499 -222.602298) (xy 451.273287 -222.583528) (xy 451.287662 -222.569164)
			(xy 451.306437 -222.561391) (xy 451.316598 -222.560896) (xy 452.716138 -222.560896) (xy 452.726293 -222.561401)
			(xy 452.745055 -222.56918) (xy 452.759417 -222.583542) (xy 452.767198 -222.602303) (xy 452.7677 -222.612458)
			(xy 452.7677 -223.021398) (xy 458.808836 -223.021398) (xy 458.808836 -222.612458) (xy 458.809299 -222.602298)
			(xy 458.817087 -222.583528) (xy 458.831462 -222.569164) (xy 458.850237 -222.561391) (xy 458.860398 -222.560896)
			(xy 460.259938 -222.560896) (xy 460.270093 -222.561401) (xy 460.288855 -222.56918) (xy 460.303217 -222.583542)
			(xy 460.310998 -222.602303) (xy 460.3115 -222.612458) (xy 460.3115 -223.021398) (xy 460.310966 -223.031551)
			(xy 460.303199 -223.050313) (xy 460.288846 -223.064677) (xy 460.270091 -223.072458) (xy 460.259938 -223.07296)
			(xy 458.860398 -223.07296) (xy 458.85024 -223.072468) (xy 458.83147 -223.064693) (xy 458.817105 -223.050326)
			(xy 458.809331 -223.031556) (xy 458.808836 -223.021398) (xy 452.7677 -223.021398) (xy 452.767166 -223.031551)
			(xy 452.759399 -223.050313) (xy 452.745046 -223.064677) (xy 452.726291 -223.072458) (xy 452.716138 -223.07296)
			(xy 451.316598 -223.07296) (xy 451.30644 -223.072468) (xy 451.28767 -223.064693) (xy 451.273305 -223.050326)
			(xy 451.265531 -223.031556) (xy 451.265036 -223.021398) (xy 445.2239 -223.021398) (xy 445.223366 -223.031551)
			(xy 445.215599 -223.050313) (xy 445.201246 -223.064677) (xy 445.182491 -223.072458) (xy 445.172338 -223.07296)
			(xy 443.772798 -223.07296) (xy 443.76264 -223.072468) (xy 443.74387 -223.064693) (xy 443.729505 -223.050326)
			(xy 443.721731 -223.031556) (xy 443.721236 -223.021398) (xy 437.6801 -223.021398) (xy 437.679566 -223.031551)
			(xy 437.671799 -223.050313) (xy 437.657446 -223.064677) (xy 437.638691 -223.072458) (xy 437.628538 -223.07296)
			(xy 436.228998 -223.07296) (xy 436.21884 -223.072468) (xy 436.20007 -223.064693) (xy 436.185705 -223.050326)
			(xy 436.177931 -223.031556) (xy 436.177436 -223.021398) (xy 430.1363 -223.021398) (xy 430.135766 -223.031551)
			(xy 430.127999 -223.050313) (xy 430.113646 -223.064677) (xy 430.094891 -223.072458) (xy 430.084738 -223.07296)
			(xy 428.685198 -223.07296) (xy 428.67504 -223.072468) (xy 428.65627 -223.064693) (xy 428.641905 -223.050326)
			(xy 428.634131 -223.031556) (xy 428.633636 -223.021398) (xy 422.5925 -223.021398) (xy 422.591966 -223.031551)
			(xy 422.584199 -223.050313) (xy 422.569846 -223.064677) (xy 422.551091 -223.072458) (xy 422.540938 -223.07296)
			(xy 421.141398 -223.07296) (xy 421.13124 -223.072468) (xy 421.11247 -223.064693) (xy 421.098105 -223.050326)
			(xy 421.090331 -223.031556) (xy 421.089836 -223.021398) (xy 415.0487 -223.021398) (xy 415.048166 -223.031551)
			(xy 415.040399 -223.050313) (xy 415.026046 -223.064677) (xy 415.007291 -223.072458) (xy 414.997138 -223.07296)
			(xy 413.597598 -223.07296) (xy 413.58744 -223.072468) (xy 413.56867 -223.064693) (xy 413.554305 -223.050326)
			(xy 413.546531 -223.031556) (xy 413.546036 -223.021398) (xy 407.5049 -223.021398) (xy 407.504366 -223.031551)
			(xy 407.496599 -223.050313) (xy 407.482246 -223.064677) (xy 407.463491 -223.072458) (xy 407.453338 -223.07296)
			(xy 406.053798 -223.07296) (xy 406.04364 -223.072468) (xy 406.02487 -223.064693) (xy 406.010505 -223.050326)
			(xy 406.002731 -223.031556) (xy 406.002236 -223.021398) (xy 309.6387 -223.021398) (xy 309.638166 -223.031551)
			(xy 309.630399 -223.050313) (xy 309.616046 -223.064677) (xy 309.597291 -223.072458) (xy 309.587138 -223.07296)
			(xy 308.187598 -223.07296) (xy 308.17744 -223.072468) (xy 308.15867 -223.064693) (xy 308.144305 -223.050326)
			(xy 308.136531 -223.031556) (xy 308.136036 -223.021398) (xy 302.0949 -223.021398) (xy 302.094366 -223.031551)
			(xy 302.086599 -223.050313) (xy 302.072246 -223.064677) (xy 302.053491 -223.072458) (xy 302.043338 -223.07296)
			(xy 300.643798 -223.07296) (xy 300.63364 -223.072468) (xy 300.61487 -223.064693) (xy 300.600505 -223.050326)
			(xy 300.592731 -223.031556) (xy 300.592236 -223.021398) (xy 294.5511 -223.021398) (xy 294.550566 -223.031551)
			(xy 294.542799 -223.050313) (xy 294.528446 -223.064677) (xy 294.509691 -223.072458) (xy 294.499538 -223.07296)
			(xy 293.099998 -223.07296) (xy 293.08984 -223.072468) (xy 293.07107 -223.064693) (xy 293.056705 -223.050326)
			(xy 293.048931 -223.031556) (xy 293.048436 -223.021398) (xy 287.0073 -223.021398) (xy 287.006766 -223.031551)
			(xy 286.998999 -223.050313) (xy 286.984646 -223.064677) (xy 286.965891 -223.072458) (xy 286.955738 -223.07296)
			(xy 285.556198 -223.07296) (xy 285.54604 -223.072468) (xy 285.52727 -223.064693) (xy 285.512905 -223.050326)
			(xy 285.505131 -223.031556) (xy 285.504636 -223.021398) (xy 279.4635 -223.021398) (xy 279.462966 -223.031551)
			(xy 279.455199 -223.050313) (xy 279.440846 -223.064677) (xy 279.422091 -223.072458) (xy 279.411938 -223.07296)
			(xy 278.012398 -223.07296) (xy 278.00224 -223.072468) (xy 277.98347 -223.064693) (xy 277.969105 -223.050326)
			(xy 277.961331 -223.031556) (xy 277.960836 -223.021398) (xy 271.9197 -223.021398) (xy 271.919166 -223.031551)
			(xy 271.911399 -223.050313) (xy 271.897046 -223.064677) (xy 271.878291 -223.072458) (xy 271.868138 -223.07296)
			(xy 270.468598 -223.07296) (xy 270.45844 -223.072468) (xy 270.43967 -223.064693) (xy 270.425305 -223.050326)
			(xy 270.417531 -223.031556) (xy 270.417036 -223.021398) (xy 264.3759 -223.021398) (xy 264.375366 -223.031551)
			(xy 264.367599 -223.050313) (xy 264.353246 -223.064677) (xy 264.334491 -223.072458) (xy 264.324338 -223.07296)
			(xy 262.924798 -223.07296) (xy 262.91464 -223.072468) (xy 262.89587 -223.064693) (xy 262.881505 -223.050326)
			(xy 262.873731 -223.031556) (xy 262.873236 -223.021398) (xy 256.8321 -223.021398) (xy 256.831566 -223.031551)
			(xy 256.823799 -223.050313) (xy 256.809446 -223.064677) (xy 256.790691 -223.072458) (xy 256.780538 -223.07296)
			(xy 255.380998 -223.07296) (xy 255.37084 -223.072468) (xy 255.35207 -223.064693) (xy 255.337705 -223.050326)
			(xy 255.329931 -223.031556) (xy 255.329436 -223.021398) (xy 212.371432 -223.021398) (xy 212.371034 -223.031573)
			(xy 212.363244 -223.050374) (xy 212.34885 -223.06476) (xy 212.330045 -223.072539) (xy 212.31987 -223.07296)
			(xy 210.92033 -223.07296) (xy 210.91016 -223.072511) (xy 210.891366 -223.064736) (xy 210.87698 -223.050358)
			(xy 210.869194 -223.031568) (xy 210.868768 -223.021398) (xy 204.827632 -223.021398) (xy 204.827234 -223.031573)
			(xy 204.819444 -223.050374) (xy 204.80505 -223.06476) (xy 204.786245 -223.072539) (xy 204.77607 -223.07296)
			(xy 203.37653 -223.07296) (xy 203.36636 -223.072511) (xy 203.347566 -223.064736) (xy 203.33318 -223.050358)
			(xy 203.325394 -223.031568) (xy 203.324968 -223.021398) (xy 197.283832 -223.021398) (xy 197.283434 -223.031573)
			(xy 197.275644 -223.050374) (xy 197.26125 -223.06476) (xy 197.242445 -223.072539) (xy 197.23227 -223.07296)
			(xy 195.83273 -223.07296) (xy 195.82256 -223.072511) (xy 195.803766 -223.064736) (xy 195.78938 -223.050358)
			(xy 195.781594 -223.031568) (xy 195.781168 -223.021398) (xy 189.740032 -223.021398) (xy 189.739634 -223.031573)
			(xy 189.731844 -223.050374) (xy 189.71745 -223.06476) (xy 189.698645 -223.072539) (xy 189.68847 -223.07296)
			(xy 188.28893 -223.07296) (xy 188.27876 -223.072511) (xy 188.259966 -223.064736) (xy 188.24558 -223.050358)
			(xy 188.237794 -223.031568) (xy 188.237368 -223.021398) (xy 182.196232 -223.021398) (xy 182.195834 -223.031573)
			(xy 182.188044 -223.050374) (xy 182.17365 -223.06476) (xy 182.154845 -223.072539) (xy 182.14467 -223.07296)
			(xy 180.74513 -223.07296) (xy 180.73496 -223.072511) (xy 180.716166 -223.064736) (xy 180.70178 -223.050358)
			(xy 180.693994 -223.031568) (xy 180.693568 -223.021398) (xy 174.652432 -223.021398) (xy 174.652034 -223.031573)
			(xy 174.644244 -223.050374) (xy 174.62985 -223.06476) (xy 174.611045 -223.072539) (xy 174.60087 -223.07296)
			(xy 173.20133 -223.07296) (xy 173.19116 -223.072511) (xy 173.172366 -223.064736) (xy 173.15798 -223.050358)
			(xy 173.150194 -223.031568) (xy 173.149768 -223.021398) (xy 167.108632 -223.021398) (xy 167.108234 -223.031573)
			(xy 167.100444 -223.050374) (xy 167.08605 -223.06476) (xy 167.067245 -223.072539) (xy 167.05707 -223.07296)
			(xy 165.65753 -223.07296) (xy 165.64736 -223.072511) (xy 165.628566 -223.064736) (xy 165.61418 -223.050358)
			(xy 165.606394 -223.031568) (xy 165.605968 -223.021398) (xy 159.564832 -223.021398) (xy 159.564434 -223.031573)
			(xy 159.556644 -223.050374) (xy 159.54225 -223.06476) (xy 159.523445 -223.072539) (xy 159.51327 -223.07296)
			(xy 158.11373 -223.07296) (xy 158.10356 -223.072511) (xy 158.084766 -223.064736) (xy 158.07038 -223.050358)
			(xy 158.062594 -223.031568) (xy 158.062168 -223.021398) (xy 61.698632 -223.021398) (xy 61.698234 -223.031573)
			(xy 61.690444 -223.050374) (xy 61.67605 -223.06476) (xy 61.657245 -223.072539) (xy 61.64707 -223.07296)
			(xy 60.24753 -223.07296) (xy 60.23736 -223.072511) (xy 60.218566 -223.064736) (xy 60.20418 -223.050358)
			(xy 60.196394 -223.031568) (xy 60.195968 -223.021398) (xy 54.154832 -223.021398) (xy 54.154434 -223.031573)
			(xy 54.146644 -223.050374) (xy 54.13225 -223.06476) (xy 54.113445 -223.072539) (xy 54.10327 -223.07296)
			(xy 52.70373 -223.07296) (xy 52.69356 -223.072511) (xy 52.674766 -223.064736) (xy 52.66038 -223.050358)
			(xy 52.652594 -223.031568) (xy 52.652168 -223.021398) (xy 46.611032 -223.021398) (xy 46.610634 -223.031573)
			(xy 46.602844 -223.050374) (xy 46.58845 -223.06476) (xy 46.569645 -223.072539) (xy 46.55947 -223.07296)
			(xy 45.15993 -223.07296) (xy 45.14976 -223.072511) (xy 45.130966 -223.064736) (xy 45.11658 -223.050358)
			(xy 45.108794 -223.031568) (xy 45.108368 -223.021398) (xy 39.067232 -223.021398) (xy 39.066834 -223.031573)
			(xy 39.059044 -223.050374) (xy 39.04465 -223.06476) (xy 39.025845 -223.072539) (xy 39.01567 -223.07296)
			(xy 37.61613 -223.07296) (xy 37.60596 -223.072511) (xy 37.587166 -223.064736) (xy 37.57278 -223.050358)
			(xy 37.564994 -223.031568) (xy 37.564568 -223.021398) (xy 31.523432 -223.021398) (xy 31.523034 -223.031573)
			(xy 31.515244 -223.050374) (xy 31.50085 -223.06476) (xy 31.482045 -223.072539) (xy 31.47187 -223.07296)
			(xy 30.07233 -223.07296) (xy 30.06216 -223.072511) (xy 30.043366 -223.064736) (xy 30.02898 -223.050358)
			(xy 30.021194 -223.031568) (xy 30.020768 -223.021398) (xy 23.979632 -223.021398) (xy 23.979234 -223.031573)
			(xy 23.971444 -223.050374) (xy 23.95705 -223.06476) (xy 23.938245 -223.072539) (xy 23.92807 -223.07296)
			(xy 22.52853 -223.07296) (xy 22.51836 -223.072511) (xy 22.499566 -223.064736) (xy 22.48518 -223.050358)
			(xy 22.477394 -223.031568) (xy 22.476968 -223.021398) (xy 16.435832 -223.021398) (xy 16.435434 -223.031573)
			(xy 16.427644 -223.050374) (xy 16.41325 -223.06476) (xy 16.394445 -223.072539) (xy 16.38427 -223.07296)
			(xy 14.98473 -223.07296) (xy 14.97456 -223.072511) (xy 14.955766 -223.064736) (xy 14.94138 -223.050358)
			(xy 14.933594 -223.031568) (xy 14.933168 -223.021398) (xy 8.892032 -223.021398) (xy 8.891634 -223.031573)
			(xy 8.883844 -223.050374) (xy 8.86945 -223.06476) (xy 8.850645 -223.072539) (xy 8.84047 -223.07296)
			(xy 7.44093 -223.07296) (xy 7.43076 -223.072511) (xy 7.411966 -223.064736) (xy 7.39758 -223.050358)
			(xy 7.389794 -223.031568) (xy 7.389368 -223.021398) (xy 2.509012 -223.021398) (xy 2.509012 -223.871536)
			(xy 11.489436 -223.871536) (xy 11.489436 -223.462596) (xy 11.489819 -223.452437) (xy 11.497623 -223.433678)
			(xy 11.512032 -223.419353) (xy 11.530837 -223.41166) (xy 11.540998 -223.411288) (xy 12.940538 -223.411288)
			(xy 12.950661 -223.411794) (xy 12.969373 -223.419525) (xy 12.983726 -223.433804) (xy 12.991553 -223.452476)
			(xy 12.9921 -223.462596) (xy 12.9921 -223.871536) (xy 19.033236 -223.871536) (xy 19.033236 -223.462596)
			(xy 19.033619 -223.452437) (xy 19.041423 -223.433678) (xy 19.055832 -223.419353) (xy 19.074637 -223.41166)
			(xy 19.084798 -223.411288) (xy 20.484338 -223.411288) (xy 20.494461 -223.411794) (xy 20.513173 -223.419525)
			(xy 20.527526 -223.433804) (xy 20.535353 -223.452476) (xy 20.5359 -223.462596) (xy 20.5359 -223.871536)
			(xy 26.577036 -223.871536) (xy 26.577036 -223.462596) (xy 26.577419 -223.452437) (xy 26.585223 -223.433678)
			(xy 26.599632 -223.419353) (xy 26.618437 -223.41166) (xy 26.628598 -223.411288) (xy 28.028138 -223.411288)
			(xy 28.038261 -223.411794) (xy 28.056973 -223.419525) (xy 28.071326 -223.433804) (xy 28.079153 -223.452476)
			(xy 28.0797 -223.462596) (xy 28.0797 -223.871536) (xy 34.120836 -223.871536) (xy 34.120836 -223.462596)
			(xy 34.121219 -223.452437) (xy 34.129023 -223.433678) (xy 34.143432 -223.419353) (xy 34.162237 -223.41166)
			(xy 34.172398 -223.411288) (xy 35.571938 -223.411288) (xy 35.582061 -223.411794) (xy 35.600773 -223.419525)
			(xy 35.615126 -223.433804) (xy 35.622953 -223.452476) (xy 35.6235 -223.462596) (xy 35.6235 -223.871536)
			(xy 41.664636 -223.871536) (xy 41.664636 -223.462596) (xy 41.665019 -223.452437) (xy 41.672823 -223.433678)
			(xy 41.687232 -223.419353) (xy 41.706037 -223.41166) (xy 41.716198 -223.411288) (xy 43.115738 -223.411288)
			(xy 43.125861 -223.411794) (xy 43.144573 -223.419525) (xy 43.158926 -223.433804) (xy 43.166753 -223.452476)
			(xy 43.1673 -223.462596) (xy 43.1673 -223.871536) (xy 49.208436 -223.871536) (xy 49.208436 -223.462596)
			(xy 49.208819 -223.452437) (xy 49.216623 -223.433678) (xy 49.231032 -223.419353) (xy 49.249837 -223.41166)
			(xy 49.259998 -223.411288) (xy 50.659538 -223.411288) (xy 50.669661 -223.411794) (xy 50.688373 -223.419525)
			(xy 50.702726 -223.433804) (xy 50.710553 -223.452476) (xy 50.7111 -223.462596) (xy 50.7111 -223.871536)
			(xy 56.752236 -223.871536) (xy 56.752236 -223.462596) (xy 56.752619 -223.452437) (xy 56.760423 -223.433678)
			(xy 56.774832 -223.419353) (xy 56.793637 -223.41166) (xy 56.803798 -223.411288) (xy 58.203338 -223.411288)
			(xy 58.213461 -223.411794) (xy 58.232173 -223.419525) (xy 58.246526 -223.433804) (xy 58.254353 -223.452476)
			(xy 58.2549 -223.462596) (xy 58.2549 -223.871536) (xy 64.296036 -223.871536) (xy 64.296036 -223.462596)
			(xy 64.296419 -223.452437) (xy 64.304223 -223.433678) (xy 64.318632 -223.419353) (xy 64.337437 -223.41166)
			(xy 64.347598 -223.411288) (xy 65.747138 -223.411288) (xy 65.757261 -223.411794) (xy 65.775973 -223.419525)
			(xy 65.790326 -223.433804) (xy 65.798153 -223.452476) (xy 65.7987 -223.462596) (xy 65.7987 -223.871536)
			(xy 65.798308 -223.881692) (xy 65.7905 -223.900446) (xy 65.776095 -223.914768) (xy 65.757297 -223.922466)
			(xy 65.747138 -223.922844) (xy 64.347598 -223.922844) (xy 64.337469 -223.922374) (xy 64.318745 -223.914643)
			(xy 64.304388 -223.900351) (xy 64.296572 -223.881662) (xy 64.296036 -223.871536) (xy 58.2549 -223.871536)
			(xy 58.254508 -223.881692) (xy 58.2467 -223.900446) (xy 58.232295 -223.914768) (xy 58.213497 -223.922466)
			(xy 58.203338 -223.922844) (xy 56.803798 -223.922844) (xy 56.793669 -223.922374) (xy 56.774945 -223.914643)
			(xy 56.760588 -223.900351) (xy 56.752772 -223.881662) (xy 56.752236 -223.871536) (xy 50.7111 -223.871536)
			(xy 50.710708 -223.881692) (xy 50.7029 -223.900446) (xy 50.688495 -223.914768) (xy 50.669697 -223.922466)
			(xy 50.659538 -223.922844) (xy 49.259998 -223.922844) (xy 49.249869 -223.922374) (xy 49.231145 -223.914643)
			(xy 49.216788 -223.900351) (xy 49.208972 -223.881662) (xy 49.208436 -223.871536) (xy 43.1673 -223.871536)
			(xy 43.166908 -223.881692) (xy 43.1591 -223.900446) (xy 43.144695 -223.914768) (xy 43.125897 -223.922466)
			(xy 43.115738 -223.922844) (xy 41.716198 -223.922844) (xy 41.706069 -223.922374) (xy 41.687345 -223.914643)
			(xy 41.672988 -223.900351) (xy 41.665172 -223.881662) (xy 41.664636 -223.871536) (xy 35.6235 -223.871536)
			(xy 35.623108 -223.881692) (xy 35.6153 -223.900446) (xy 35.600895 -223.914768) (xy 35.582097 -223.922466)
			(xy 35.571938 -223.922844) (xy 34.172398 -223.922844) (xy 34.162269 -223.922374) (xy 34.143545 -223.914643)
			(xy 34.129188 -223.900351) (xy 34.121372 -223.881662) (xy 34.120836 -223.871536) (xy 28.0797 -223.871536)
			(xy 28.079308 -223.881692) (xy 28.0715 -223.900446) (xy 28.057095 -223.914768) (xy 28.038297 -223.922466)
			(xy 28.028138 -223.922844) (xy 26.628598 -223.922844) (xy 26.618469 -223.922374) (xy 26.599745 -223.914643)
			(xy 26.585388 -223.900351) (xy 26.577572 -223.881662) (xy 26.577036 -223.871536) (xy 20.5359 -223.871536)
			(xy 20.535508 -223.881692) (xy 20.5277 -223.900446) (xy 20.513295 -223.914768) (xy 20.494497 -223.922466)
			(xy 20.484338 -223.922844) (xy 19.084798 -223.922844) (xy 19.074669 -223.922374) (xy 19.055945 -223.914643)
			(xy 19.041588 -223.900351) (xy 19.033772 -223.881662) (xy 19.033236 -223.871536) (xy 12.9921 -223.871536)
			(xy 12.991708 -223.881692) (xy 12.9839 -223.900446) (xy 12.969495 -223.914768) (xy 12.950697 -223.922466)
			(xy 12.940538 -223.922844) (xy 11.540998 -223.922844) (xy 11.530869 -223.922374) (xy 11.512145 -223.914643)
			(xy 11.497788 -223.900351) (xy 11.489972 -223.881662) (xy 11.489436 -223.871536) (xy 2.509012 -223.871536)
			(xy 2.509012 -224.72142) (xy 7.389368 -224.72142) (xy 7.389368 -224.31248) (xy 7.389804 -224.302329)
			(xy 7.397601 -224.283582) (xy 7.411992 -224.26926) (xy 7.430777 -224.261555) (xy 7.44093 -224.261172)
			(xy 8.84047 -224.261172) (xy 8.850599 -224.261652) (xy 8.869325 -224.269376) (xy 8.883684 -224.283665)
			(xy 8.891499 -224.302354) (xy 8.892032 -224.31248) (xy 8.892032 -224.72142) (xy 14.933168 -224.72142)
			(xy 14.933168 -224.31248) (xy 14.933604 -224.302329) (xy 14.941401 -224.283582) (xy 14.955792 -224.26926)
			(xy 14.974577 -224.261555) (xy 14.98473 -224.261172) (xy 16.38427 -224.261172) (xy 16.394399 -224.261652)
			(xy 16.413125 -224.269376) (xy 16.427484 -224.283665) (xy 16.435299 -224.302354) (xy 16.435832 -224.31248)
			(xy 16.435832 -224.72142) (xy 22.476968 -224.72142) (xy 22.476968 -224.31248) (xy 22.477404 -224.302329)
			(xy 22.485201 -224.283582) (xy 22.499592 -224.26926) (xy 22.518377 -224.261555) (xy 22.52853 -224.261172)
			(xy 23.92807 -224.261172) (xy 23.938199 -224.261652) (xy 23.956925 -224.269376) (xy 23.971284 -224.283665)
			(xy 23.979099 -224.302354) (xy 23.979632 -224.31248) (xy 23.979632 -224.72142) (xy 30.020768 -224.72142)
			(xy 30.020768 -224.31248) (xy 30.021204 -224.302329) (xy 30.029001 -224.283582) (xy 30.043392 -224.26926)
			(xy 30.062177 -224.261555) (xy 30.07233 -224.261172) (xy 31.47187 -224.261172) (xy 31.481999 -224.261652)
			(xy 31.500725 -224.269376) (xy 31.515084 -224.283665) (xy 31.522899 -224.302354) (xy 31.523432 -224.31248)
			(xy 31.523432 -224.72142) (xy 37.564568 -224.72142) (xy 37.564568 -224.31248) (xy 37.565004 -224.302329)
			(xy 37.572801 -224.283582) (xy 37.587192 -224.26926) (xy 37.605977 -224.261555) (xy 37.61613 -224.261172)
			(xy 39.01567 -224.261172) (xy 39.025799 -224.261652) (xy 39.044525 -224.269376) (xy 39.058884 -224.283665)
			(xy 39.066699 -224.302354) (xy 39.067232 -224.31248) (xy 39.067232 -224.72142) (xy 45.108368 -224.72142)
			(xy 45.108368 -224.31248) (xy 45.108804 -224.302329) (xy 45.116601 -224.283582) (xy 45.130992 -224.26926)
			(xy 45.149777 -224.261555) (xy 45.15993 -224.261172) (xy 46.55947 -224.261172) (xy 46.569599 -224.261652)
			(xy 46.588325 -224.269376) (xy 46.602684 -224.283665) (xy 46.610499 -224.302354) (xy 46.611032 -224.31248)
			(xy 46.611032 -224.72142) (xy 52.652168 -224.72142) (xy 52.652168 -224.31248) (xy 52.652604 -224.302329)
			(xy 52.660401 -224.283582) (xy 52.674792 -224.26926) (xy 52.693577 -224.261555) (xy 52.70373 -224.261172)
			(xy 54.10327 -224.261172) (xy 54.113399 -224.261652) (xy 54.132125 -224.269376) (xy 54.146484 -224.283665)
			(xy 54.154299 -224.302354) (xy 54.154832 -224.31248) (xy 54.154832 -224.72142) (xy 60.195968 -224.72142)
			(xy 60.195968 -224.31248) (xy 60.196404 -224.302329) (xy 60.204201 -224.283582) (xy 60.218592 -224.26926)
			(xy 60.237377 -224.261555) (xy 60.24753 -224.261172) (xy 61.64707 -224.261172) (xy 61.657199 -224.261652)
			(xy 61.675925 -224.269376) (xy 61.690284 -224.283665) (xy 61.698099 -224.302354) (xy 61.698632 -224.31248)
			(xy 61.698632 -224.389442) (xy 89.695528 -224.389442) (xy 89.695935 -224.364105) (xy 89.703697 -224.314028)
			(xy 89.719029 -224.265728) (xy 89.74157 -224.220343) (xy 89.770789 -224.17894) (xy 89.805999 -224.142496)
			(xy 89.84637 -224.111867) (xy 89.890952 -224.087776) (xy 89.938695 -224.070789) (xy 89.963498 -224.065592)
			(xy 89.986358 -224.061274) (xy 90.191082 -223.706182) (xy 90.183462 -223.684338) (xy 90.174817 -223.657995)
			(xy 90.165504 -223.603345) (xy 90.16492 -223.575626) (xy 90.165428 -223.549719) (xy 90.173534 -223.498542)
			(xy 90.189546 -223.449263) (xy 90.213069 -223.403096) (xy 90.243525 -223.361177) (xy 90.280163 -223.324539)
			(xy 90.322082 -223.294083) (xy 90.368249 -223.27056) (xy 90.417528 -223.254548) (xy 90.468705 -223.246442)
			(xy 90.520519 -223.246442) (xy 90.571696 -223.254548) (xy 90.620975 -223.27056) (xy 90.667142 -223.294083)
			(xy 90.709061 -223.324539) (xy 90.745699 -223.361177) (xy 90.776155 -223.403096) (xy 90.799678 -223.449263)
			(xy 90.81569 -223.498542) (xy 90.823796 -223.549719) (xy 90.824304 -223.575626) (xy 90.823803 -223.60097)
			(xy 90.816028 -223.651059) (xy 90.800679 -223.699368) (xy 90.77812 -223.74476) (xy 90.74888 -223.786165)
			(xy 90.713649 -223.822609) (xy 90.673257 -223.853232) (xy 90.628654 -223.877314) (xy 90.580892 -223.894288)
			(xy 90.55608 -223.899476) (xy 90.53322 -223.903794) (xy 90.328496 -224.258632) (xy 90.336116 -224.280476)
			(xy 90.344672 -224.306769) (xy 90.353865 -224.361289) (xy 90.354404 -224.388934) (xy 90.354404 -224.389442)
			(xy 90.635328 -224.389442) (xy 90.635836 -224.363555) (xy 90.643935 -224.312417) (xy 90.659934 -224.263177)
			(xy 90.68344 -224.217045) (xy 90.713872 -224.175158) (xy 90.750482 -224.138548) (xy 90.792369 -224.108116)
			(xy 90.838501 -224.08461) (xy 90.887741 -224.068611) (xy 90.938879 -224.060512) (xy 90.990653 -224.060512)
			(xy 91.041791 -224.068611) (xy 91.091031 -224.08461) (xy 91.137163 -224.108116) (xy 91.17905 -224.138548)
			(xy 91.21566 -224.175158) (xy 91.246092 -224.217045) (xy 91.269598 -224.263177) (xy 91.285597 -224.312417)
			(xy 91.293696 -224.363555) (xy 91.294204 -224.389442) (xy 92.514928 -224.389442) (xy 92.515436 -224.363555)
			(xy 92.523535 -224.312417) (xy 92.539534 -224.263177) (xy 92.56304 -224.217045) (xy 92.593472 -224.175158)
			(xy 92.630082 -224.138548) (xy 92.671969 -224.108116) (xy 92.718101 -224.08461) (xy 92.767341 -224.068611)
			(xy 92.818479 -224.060512) (xy 92.870253 -224.060512) (xy 92.921391 -224.068611) (xy 92.970631 -224.08461)
			(xy 93.016763 -224.108116) (xy 93.05865 -224.138548) (xy 93.09526 -224.175158) (xy 93.125692 -224.217045)
			(xy 93.149198 -224.263177) (xy 93.165197 -224.312417) (xy 93.173296 -224.363555) (xy 93.173804 -224.389442)
			(xy 93.454728 -224.389442) (xy 93.455135 -224.364105) (xy 93.462897 -224.314028) (xy 93.478229 -224.265728)
			(xy 93.50077 -224.220343) (xy 93.529989 -224.17894) (xy 93.565199 -224.142496) (xy 93.60557 -224.111867)
			(xy 93.650152 -224.087776) (xy 93.697895 -224.070789) (xy 93.722698 -224.065592) (xy 93.745558 -224.061274)
			(xy 93.950282 -223.706436) (xy 93.942662 -223.684338) (xy 93.934031 -223.657991) (xy 93.92471 -223.603344)
			(xy 93.92412 -223.575626) (xy 93.924628 -223.549719) (xy 93.932734 -223.498542) (xy 93.948746 -223.449263)
			(xy 93.972269 -223.403096) (xy 94.002725 -223.361177) (xy 94.039363 -223.324539) (xy 94.081282 -223.294083)
			(xy 94.127449 -223.27056) (xy 94.176728 -223.254548) (xy 94.227905 -223.246442) (xy 94.279719 -223.246442)
			(xy 94.330896 -223.254548) (xy 94.380175 -223.27056) (xy 94.426342 -223.294083) (xy 94.468261 -223.324539)
			(xy 94.504899 -223.361177) (xy 94.535355 -223.403096) (xy 94.558878 -223.449263) (xy 94.57489 -223.498542)
			(xy 94.582996 -223.549719) (xy 94.583504 -223.575626) (xy 94.583087 -223.600992) (xy 94.575334 -223.651127)
			(xy 94.559985 -223.69948) (xy 94.537403 -223.744908) (xy 94.508122 -223.786336) (xy 94.472834 -223.822783)
			(xy 94.432375 -223.853388) (xy 94.387701 -223.877427) (xy 94.339869 -223.894332) (xy 94.315026 -223.899476)
			(xy 94.292166 -223.903794) (xy 94.087442 -224.258632) (xy 94.095316 -224.280476) (xy 94.10389 -224.306896)
			(xy 94.11309 -224.36167) (xy 94.113604 -224.389442) (xy 94.394528 -224.389442) (xy 94.395036 -224.363555)
			(xy 94.403135 -224.312417) (xy 94.419134 -224.263177) (xy 94.44264 -224.217045) (xy 94.473072 -224.175158)
			(xy 94.509682 -224.138548) (xy 94.551569 -224.108116) (xy 94.597701 -224.08461) (xy 94.646941 -224.068611)
			(xy 94.698079 -224.060512) (xy 94.749853 -224.060512) (xy 94.800991 -224.068611) (xy 94.850231 -224.08461)
			(xy 94.896363 -224.108116) (xy 94.93825 -224.138548) (xy 94.97486 -224.175158) (xy 95.005292 -224.217045)
			(xy 95.028798 -224.263177) (xy 95.044797 -224.312417) (xy 95.052896 -224.363555) (xy 95.053404 -224.389442)
			(xy 95.334328 -224.389442) (xy 95.334735 -224.364105) (xy 95.342497 -224.314028) (xy 95.357829 -224.265728)
			(xy 95.38037 -224.220343) (xy 95.409589 -224.17894) (xy 95.444799 -224.142496) (xy 95.48517 -224.111867)
			(xy 95.529752 -224.087776) (xy 95.577495 -224.070789) (xy 95.602298 -224.065592) (xy 95.625158 -224.061274)
			(xy 95.829882 -223.706436) (xy 95.822262 -223.684338) (xy 95.813631 -223.657991) (xy 95.80431 -223.603344)
			(xy 95.80372 -223.575626) (xy 95.804228 -223.549719) (xy 95.812334 -223.498542) (xy 95.828346 -223.449263)
			(xy 95.851869 -223.403096) (xy 95.882325 -223.361177) (xy 95.918963 -223.324539) (xy 95.960882 -223.294083)
			(xy 96.007049 -223.27056) (xy 96.056328 -223.254548) (xy 96.107505 -223.246442) (xy 96.159319 -223.246442)
			(xy 96.210496 -223.254548) (xy 96.259775 -223.27056) (xy 96.305942 -223.294083) (xy 96.347861 -223.324539)
			(xy 96.384499 -223.361177) (xy 96.414955 -223.403096) (xy 96.438478 -223.449263) (xy 96.45449 -223.498542)
			(xy 96.462596 -223.549719) (xy 96.463104 -223.575626) (xy 96.462687 -223.600992) (xy 96.454934 -223.651127)
			(xy 96.439585 -223.69948) (xy 96.417003 -223.744908) (xy 96.387722 -223.786336) (xy 96.352434 -223.822783)
			(xy 96.311975 -223.853388) (xy 96.267301 -223.877427) (xy 96.219469 -223.894332) (xy 96.194626 -223.899476)
			(xy 96.171766 -223.903794) (xy 95.967042 -224.258632) (xy 95.974916 -224.280476) (xy 95.98349 -224.306896)
			(xy 95.99269 -224.36167) (xy 95.993204 -224.389442) (xy 96.274128 -224.389442) (xy 96.274636 -224.363555)
			(xy 96.282735 -224.312417) (xy 96.298734 -224.263177) (xy 96.32224 -224.217045) (xy 96.352672 -224.175158)
			(xy 96.389282 -224.138548) (xy 96.431169 -224.108116) (xy 96.477301 -224.08461) (xy 96.526541 -224.068611)
			(xy 96.577679 -224.060512) (xy 96.629453 -224.060512) (xy 96.680591 -224.068611) (xy 96.729831 -224.08461)
			(xy 96.775963 -224.108116) (xy 96.81785 -224.138548) (xy 96.85446 -224.175158) (xy 96.884892 -224.217045)
			(xy 96.908398 -224.263177) (xy 96.924397 -224.312417) (xy 96.932496 -224.363555) (xy 96.933004 -224.389442)
			(xy 97.213928 -224.389442) (xy 97.214335 -224.364105) (xy 97.222097 -224.314028) (xy 97.237429 -224.265728)
			(xy 97.25997 -224.220343) (xy 97.289189 -224.17894) (xy 97.324399 -224.142496) (xy 97.36477 -224.111867)
			(xy 97.409352 -224.087776) (xy 97.457095 -224.070789) (xy 97.481898 -224.065592) (xy 97.504758 -224.061274)
			(xy 97.709482 -223.706436) (xy 97.701862 -223.684338) (xy 97.693231 -223.657991) (xy 97.68391 -223.603344)
			(xy 97.68332 -223.575626) (xy 97.683828 -223.549719) (xy 97.691934 -223.498542) (xy 97.707946 -223.449263)
			(xy 97.731469 -223.403096) (xy 97.761925 -223.361177) (xy 97.798563 -223.324539) (xy 97.840482 -223.294083)
			(xy 97.886649 -223.27056) (xy 97.935928 -223.254548) (xy 97.987105 -223.246442) (xy 98.038919 -223.246442)
			(xy 98.090096 -223.254548) (xy 98.139375 -223.27056) (xy 98.185542 -223.294083) (xy 98.227461 -223.324539)
			(xy 98.264099 -223.361177) (xy 98.294555 -223.403096) (xy 98.318078 -223.449263) (xy 98.33409 -223.498542)
			(xy 98.342196 -223.549719) (xy 98.342704 -223.575626) (xy 98.342287 -223.600992) (xy 98.334534 -223.651127)
			(xy 98.319185 -223.69948) (xy 98.296603 -223.744908) (xy 98.267322 -223.786336) (xy 98.232034 -223.822783)
			(xy 98.191575 -223.853388) (xy 98.146901 -223.877427) (xy 98.099069 -223.894332) (xy 98.074226 -223.899476)
			(xy 98.051366 -223.903794) (xy 97.846642 -224.258632) (xy 97.854516 -224.280476) (xy 97.86309 -224.306896)
			(xy 97.87229 -224.36167) (xy 97.872804 -224.389442) (xy 98.153728 -224.389442) (xy 98.154236 -224.363555)
			(xy 98.162335 -224.312417) (xy 98.178334 -224.263177) (xy 98.20184 -224.217045) (xy 98.232272 -224.175158)
			(xy 98.268882 -224.138548) (xy 98.310769 -224.108116) (xy 98.356901 -224.08461) (xy 98.406141 -224.068611)
			(xy 98.457279 -224.060512) (xy 98.509053 -224.060512) (xy 98.560191 -224.068611) (xy 98.609431 -224.08461)
			(xy 98.655563 -224.108116) (xy 98.69745 -224.138548) (xy 98.73406 -224.175158) (xy 98.764492 -224.217045)
			(xy 98.787998 -224.263177) (xy 98.803997 -224.312417) (xy 98.812096 -224.363555) (xy 98.812604 -224.389442)
			(xy 99.093528 -224.389442) (xy 99.093935 -224.364105) (xy 99.101697 -224.314028) (xy 99.117029 -224.265728)
			(xy 99.13957 -224.220343) (xy 99.168789 -224.17894) (xy 99.203999 -224.142496) (xy 99.24437 -224.111867)
			(xy 99.288952 -224.087776) (xy 99.336695 -224.070789) (xy 99.361498 -224.065592) (xy 99.384358 -224.061274)
			(xy 99.589082 -223.706436) (xy 99.581462 -223.684338) (xy 99.572831 -223.657991) (xy 99.56351 -223.603344)
			(xy 99.56292 -223.575626) (xy 99.563428 -223.549719) (xy 99.571534 -223.498542) (xy 99.587546 -223.449263)
			(xy 99.611069 -223.403096) (xy 99.641525 -223.361177) (xy 99.678163 -223.324539) (xy 99.720082 -223.294083)
			(xy 99.766249 -223.27056) (xy 99.815528 -223.254548) (xy 99.866705 -223.246442) (xy 99.918519 -223.246442)
			(xy 99.969696 -223.254548) (xy 100.018975 -223.27056) (xy 100.065142 -223.294083) (xy 100.107061 -223.324539)
			(xy 100.143699 -223.361177) (xy 100.174155 -223.403096) (xy 100.197678 -223.449263) (xy 100.21369 -223.498542)
			(xy 100.221796 -223.549719) (xy 100.222304 -223.575626) (xy 100.221887 -223.600992) (xy 100.214134 -223.651127)
			(xy 100.198785 -223.69948) (xy 100.176203 -223.744908) (xy 100.146922 -223.786336) (xy 100.111634 -223.822783)
			(xy 100.071175 -223.853388) (xy 100.026501 -223.877427) (xy 99.978669 -223.894332) (xy 99.953826 -223.899476)
			(xy 99.930966 -223.903794) (xy 99.726242 -224.258632) (xy 99.734116 -224.280476) (xy 99.74269 -224.306896)
			(xy 99.75189 -224.36167) (xy 99.752404 -224.389442) (xy 100.033328 -224.389442) (xy 100.033836 -224.363555)
			(xy 100.041935 -224.312417) (xy 100.057934 -224.263177) (xy 100.08144 -224.217045) (xy 100.111872 -224.175158)
			(xy 100.148482 -224.138548) (xy 100.190369 -224.108116) (xy 100.236501 -224.08461) (xy 100.285741 -224.068611)
			(xy 100.336879 -224.060512) (xy 100.388653 -224.060512) (xy 100.439791 -224.068611) (xy 100.489031 -224.08461)
			(xy 100.535163 -224.108116) (xy 100.57705 -224.138548) (xy 100.61366 -224.175158) (xy 100.644092 -224.217045)
			(xy 100.667598 -224.263177) (xy 100.683597 -224.312417) (xy 100.691696 -224.363555) (xy 100.692204 -224.389442)
			(xy 100.973128 -224.389442) (xy 100.973535 -224.364105) (xy 100.981297 -224.314028) (xy 100.996629 -224.265728)
			(xy 101.01917 -224.220343) (xy 101.048389 -224.17894) (xy 101.083599 -224.142496) (xy 101.12397 -224.111867)
			(xy 101.168552 -224.087776) (xy 101.216295 -224.070789) (xy 101.241098 -224.065592) (xy 101.263958 -224.061274)
			(xy 101.468682 -223.706436) (xy 101.461062 -223.684338) (xy 101.452431 -223.657991) (xy 101.44311 -223.603344)
			(xy 101.44252 -223.575626) (xy 101.443028 -223.549719) (xy 101.451134 -223.498542) (xy 101.467146 -223.449263)
			(xy 101.490669 -223.403096) (xy 101.521125 -223.361177) (xy 101.557763 -223.324539) (xy 101.599682 -223.294083)
			(xy 101.645849 -223.27056) (xy 101.695128 -223.254548) (xy 101.746305 -223.246442) (xy 101.798119 -223.246442)
			(xy 101.849296 -223.254548) (xy 101.898575 -223.27056) (xy 101.944742 -223.294083) (xy 101.986661 -223.324539)
			(xy 102.023299 -223.361177) (xy 102.053755 -223.403096) (xy 102.077278 -223.449263) (xy 102.09329 -223.498542)
			(xy 102.101396 -223.549719) (xy 102.101904 -223.575626) (xy 102.101487 -223.600992) (xy 102.093734 -223.651127)
			(xy 102.078385 -223.69948) (xy 102.055803 -223.744908) (xy 102.026522 -223.786336) (xy 101.991234 -223.822783)
			(xy 101.950775 -223.853388) (xy 101.906101 -223.877427) (xy 101.858269 -223.894332) (xy 101.833426 -223.899476)
			(xy 101.810566 -223.903794) (xy 101.605842 -224.258632) (xy 101.613716 -224.280476) (xy 101.62229 -224.306896)
			(xy 101.63149 -224.36167) (xy 101.632004 -224.389442) (xy 101.912928 -224.389442) (xy 101.913436 -224.363555)
			(xy 101.921535 -224.312417) (xy 101.937534 -224.263177) (xy 101.96104 -224.217045) (xy 101.991472 -224.175158)
			(xy 102.028082 -224.138548) (xy 102.069969 -224.108116) (xy 102.116101 -224.08461) (xy 102.165341 -224.068611)
			(xy 102.216479 -224.060512) (xy 102.268253 -224.060512) (xy 102.319391 -224.068611) (xy 102.368631 -224.08461)
			(xy 102.414763 -224.108116) (xy 102.45665 -224.138548) (xy 102.49326 -224.175158) (xy 102.523692 -224.217045)
			(xy 102.547198 -224.263177) (xy 102.563197 -224.312417) (xy 102.571296 -224.363555) (xy 102.571804 -224.389442)
			(xy 102.852728 -224.389442) (xy 102.853135 -224.364105) (xy 102.860897 -224.314028) (xy 102.876229 -224.265728)
			(xy 102.89877 -224.220343) (xy 102.927989 -224.17894) (xy 102.963199 -224.142496) (xy 103.00357 -224.111867)
			(xy 103.048152 -224.087776) (xy 103.095895 -224.070789) (xy 103.120698 -224.065592) (xy 103.143558 -224.061274)
			(xy 103.348282 -223.706436) (xy 103.340662 -223.684338) (xy 103.332031 -223.657991) (xy 103.32271 -223.603344)
			(xy 103.32212 -223.575626) (xy 103.322628 -223.549719) (xy 103.330734 -223.498542) (xy 103.346746 -223.449263)
			(xy 103.370269 -223.403096) (xy 103.400725 -223.361177) (xy 103.437363 -223.324539) (xy 103.479282 -223.294083)
			(xy 103.525449 -223.27056) (xy 103.574728 -223.254548) (xy 103.625905 -223.246442) (xy 103.677719 -223.246442)
			(xy 103.728896 -223.254548) (xy 103.778175 -223.27056) (xy 103.824342 -223.294083) (xy 103.866261 -223.324539)
			(xy 103.902899 -223.361177) (xy 103.933355 -223.403096) (xy 103.956878 -223.449263) (xy 103.97289 -223.498542)
			(xy 103.980996 -223.549719) (xy 103.981504 -223.575626) (xy 103.981087 -223.600992) (xy 103.973334 -223.651127)
			(xy 103.957985 -223.69948) (xy 103.935403 -223.744908) (xy 103.906122 -223.786336) (xy 103.870834 -223.822783)
			(xy 103.830375 -223.853388) (xy 103.785701 -223.877427) (xy 103.737869 -223.894332) (xy 103.713026 -223.899476)
			(xy 103.690166 -223.903794) (xy 103.485442 -224.258632) (xy 103.493316 -224.280476) (xy 103.50189 -224.306896)
			(xy 103.51109 -224.36167) (xy 103.511604 -224.389442) (xy 103.792528 -224.389442) (xy 103.793036 -224.363555)
			(xy 103.801135 -224.312417) (xy 103.817134 -224.263177) (xy 103.84064 -224.217045) (xy 103.871072 -224.175158)
			(xy 103.907682 -224.138548) (xy 103.949569 -224.108116) (xy 103.995701 -224.08461) (xy 104.044941 -224.068611)
			(xy 104.096079 -224.060512) (xy 104.147853 -224.060512) (xy 104.198991 -224.068611) (xy 104.248231 -224.08461)
			(xy 104.294363 -224.108116) (xy 104.33625 -224.138548) (xy 104.37286 -224.175158) (xy 104.403292 -224.217045)
			(xy 104.426798 -224.263177) (xy 104.442797 -224.312417) (xy 104.450896 -224.363555) (xy 104.451404 -224.389442)
			(xy 104.732328 -224.389442) (xy 104.732735 -224.364105) (xy 104.740497 -224.314028) (xy 104.755829 -224.265728)
			(xy 104.77837 -224.220343) (xy 104.807589 -224.17894) (xy 104.842799 -224.142496) (xy 104.88317 -224.111867)
			(xy 104.927752 -224.087776) (xy 104.975495 -224.070789) (xy 105.000298 -224.065592) (xy 105.023158 -224.061274)
			(xy 105.227882 -223.706436) (xy 105.220262 -223.684338) (xy 105.211631 -223.657991) (xy 105.20231 -223.603344)
			(xy 105.20172 -223.575626) (xy 105.202228 -223.549719) (xy 105.210334 -223.498542) (xy 105.226346 -223.449263)
			(xy 105.249869 -223.403096) (xy 105.280325 -223.361177) (xy 105.316963 -223.324539) (xy 105.358882 -223.294083)
			(xy 105.405049 -223.27056) (xy 105.454328 -223.254548) (xy 105.505505 -223.246442) (xy 105.557319 -223.246442)
			(xy 105.608496 -223.254548) (xy 105.657775 -223.27056) (xy 105.703942 -223.294083) (xy 105.745861 -223.324539)
			(xy 105.782499 -223.361177) (xy 105.812955 -223.403096) (xy 105.836478 -223.449263) (xy 105.85249 -223.498542)
			(xy 105.860596 -223.549719) (xy 105.861104 -223.575626) (xy 105.860687 -223.600992) (xy 105.852934 -223.651127)
			(xy 105.837585 -223.69948) (xy 105.815003 -223.744908) (xy 105.785722 -223.786336) (xy 105.750434 -223.822783)
			(xy 105.709975 -223.853388) (xy 105.665301 -223.877427) (xy 105.617469 -223.894332) (xy 105.592626 -223.899476)
			(xy 105.569766 -223.903794) (xy 105.365042 -224.258632) (xy 105.372916 -224.280476) (xy 105.38149 -224.306896)
			(xy 105.39069 -224.36167) (xy 105.391204 -224.389442) (xy 105.672128 -224.389442) (xy 105.672636 -224.363555)
			(xy 105.680735 -224.312417) (xy 105.696734 -224.263177) (xy 105.72024 -224.217045) (xy 105.750672 -224.175158)
			(xy 105.787282 -224.138548) (xy 105.829169 -224.108116) (xy 105.875301 -224.08461) (xy 105.924541 -224.068611)
			(xy 105.975679 -224.060512) (xy 106.027453 -224.060512) (xy 106.078591 -224.068611) (xy 106.127831 -224.08461)
			(xy 106.173963 -224.108116) (xy 106.21585 -224.138548) (xy 106.25246 -224.175158) (xy 106.282892 -224.217045)
			(xy 106.306398 -224.263177) (xy 106.322397 -224.312417) (xy 106.330496 -224.363555) (xy 106.331004 -224.389442)
			(xy 106.611928 -224.389442) (xy 106.612335 -224.364105) (xy 106.620097 -224.314028) (xy 106.635429 -224.265728)
			(xy 106.65797 -224.220343) (xy 106.687189 -224.17894) (xy 106.722399 -224.142496) (xy 106.76277 -224.111867)
			(xy 106.807352 -224.087776) (xy 106.855095 -224.070789) (xy 106.879898 -224.065592) (xy 106.902758 -224.061274)
			(xy 107.107482 -223.706436) (xy 107.099862 -223.684338) (xy 107.091231 -223.657991) (xy 107.08191 -223.603344)
			(xy 107.08132 -223.575626) (xy 107.081828 -223.549719) (xy 107.089934 -223.498542) (xy 107.105946 -223.449263)
			(xy 107.129469 -223.403096) (xy 107.159925 -223.361177) (xy 107.196563 -223.324539) (xy 107.238482 -223.294083)
			(xy 107.284649 -223.27056) (xy 107.333928 -223.254548) (xy 107.385105 -223.246442) (xy 107.436919 -223.246442)
			(xy 107.488096 -223.254548) (xy 107.537375 -223.27056) (xy 107.583542 -223.294083) (xy 107.625461 -223.324539)
			(xy 107.662099 -223.361177) (xy 107.692555 -223.403096) (xy 107.716078 -223.449263) (xy 107.73209 -223.498542)
			(xy 107.740196 -223.549719) (xy 107.740704 -223.575626) (xy 107.740287 -223.600992) (xy 107.732534 -223.651127)
			(xy 107.717185 -223.69948) (xy 107.694603 -223.744908) (xy 107.665322 -223.786336) (xy 107.630034 -223.822783)
			(xy 107.589575 -223.853388) (xy 107.544901 -223.877427) (xy 107.497069 -223.894332) (xy 107.472226 -223.899476)
			(xy 107.449366 -223.903794) (xy 107.244642 -224.258632) (xy 107.252516 -224.280476) (xy 107.26109 -224.306896)
			(xy 107.27029 -224.36167) (xy 107.270804 -224.389442) (xy 107.551728 -224.389442) (xy 107.552236 -224.363555)
			(xy 107.560335 -224.312417) (xy 107.576334 -224.263177) (xy 107.59984 -224.217045) (xy 107.630272 -224.175158)
			(xy 107.666882 -224.138548) (xy 107.708769 -224.108116) (xy 107.754901 -224.08461) (xy 107.804141 -224.068611)
			(xy 107.855279 -224.060512) (xy 107.907053 -224.060512) (xy 107.958191 -224.068611) (xy 108.007431 -224.08461)
			(xy 108.053563 -224.108116) (xy 108.09545 -224.138548) (xy 108.13206 -224.175158) (xy 108.162492 -224.217045)
			(xy 108.185998 -224.263177) (xy 108.201997 -224.312417) (xy 108.210096 -224.363555) (xy 108.210604 -224.389442)
			(xy 108.491528 -224.389442) (xy 108.491935 -224.364105) (xy 108.499697 -224.314028) (xy 108.515029 -224.265728)
			(xy 108.53757 -224.220343) (xy 108.566789 -224.17894) (xy 108.601999 -224.142496) (xy 108.64237 -224.111867)
			(xy 108.686952 -224.087776) (xy 108.734695 -224.070789) (xy 108.759498 -224.065592) (xy 108.782358 -224.061274)
			(xy 108.987082 -223.706436) (xy 108.979462 -223.684338) (xy 108.970831 -223.657991) (xy 108.96151 -223.603344)
			(xy 108.96092 -223.575626) (xy 108.961428 -223.549719) (xy 108.969534 -223.498542) (xy 108.985546 -223.449263)
			(xy 109.009069 -223.403096) (xy 109.039525 -223.361177) (xy 109.076163 -223.324539) (xy 109.118082 -223.294083)
			(xy 109.164249 -223.27056) (xy 109.213528 -223.254548) (xy 109.264705 -223.246442) (xy 109.316519 -223.246442)
			(xy 109.367696 -223.254548) (xy 109.416975 -223.27056) (xy 109.463142 -223.294083) (xy 109.505061 -223.324539)
			(xy 109.541699 -223.361177) (xy 109.572155 -223.403096) (xy 109.595678 -223.449263) (xy 109.61169 -223.498542)
			(xy 109.619796 -223.549719) (xy 109.620304 -223.575626) (xy 109.619887 -223.600992) (xy 109.612134 -223.651127)
			(xy 109.596785 -223.69948) (xy 109.574203 -223.744908) (xy 109.544922 -223.786336) (xy 109.509634 -223.822783)
			(xy 109.469175 -223.853388) (xy 109.424501 -223.877427) (xy 109.376669 -223.894332) (xy 109.351826 -223.899476)
			(xy 109.328966 -223.903794) (xy 109.124242 -224.258632) (xy 109.132116 -224.280476) (xy 109.14069 -224.306896)
			(xy 109.14989 -224.36167) (xy 109.150404 -224.389442) (xy 109.431328 -224.389442) (xy 109.431836 -224.363555)
			(xy 109.439935 -224.312417) (xy 109.455934 -224.263177) (xy 109.47944 -224.217045) (xy 109.509872 -224.175158)
			(xy 109.546482 -224.138548) (xy 109.588369 -224.108116) (xy 109.634501 -224.08461) (xy 109.683741 -224.068611)
			(xy 109.734879 -224.060512) (xy 109.786653 -224.060512) (xy 109.837791 -224.068611) (xy 109.887031 -224.08461)
			(xy 109.933163 -224.108116) (xy 109.97505 -224.138548) (xy 110.01166 -224.175158) (xy 110.042092 -224.217045)
			(xy 110.065598 -224.263177) (xy 110.081597 -224.312417) (xy 110.089696 -224.363555) (xy 110.090204 -224.389442)
			(xy 110.371128 -224.389442) (xy 110.371535 -224.364105) (xy 110.379297 -224.314028) (xy 110.394629 -224.265728)
			(xy 110.41717 -224.220343) (xy 110.446389 -224.17894) (xy 110.481599 -224.142496) (xy 110.52197 -224.111867)
			(xy 110.566552 -224.087776) (xy 110.614295 -224.070789) (xy 110.639098 -224.065592) (xy 110.661958 -224.061274)
			(xy 110.866682 -223.706436) (xy 110.859062 -223.684338) (xy 110.850431 -223.657991) (xy 110.84111 -223.603344)
			(xy 110.84052 -223.575626) (xy 110.841028 -223.549719) (xy 110.849134 -223.498542) (xy 110.865146 -223.449263)
			(xy 110.888669 -223.403096) (xy 110.919125 -223.361177) (xy 110.955763 -223.324539) (xy 110.997682 -223.294083)
			(xy 111.043849 -223.27056) (xy 111.093128 -223.254548) (xy 111.144305 -223.246442) (xy 111.196119 -223.246442)
			(xy 111.247296 -223.254548) (xy 111.296575 -223.27056) (xy 111.342742 -223.294083) (xy 111.384661 -223.324539)
			(xy 111.421299 -223.361177) (xy 111.451755 -223.403096) (xy 111.475278 -223.449263) (xy 111.49129 -223.498542)
			(xy 111.499396 -223.549719) (xy 111.499904 -223.575626) (xy 111.499487 -223.600992) (xy 111.491734 -223.651127)
			(xy 111.476385 -223.69948) (xy 111.453803 -223.744908) (xy 111.424522 -223.786336) (xy 111.389234 -223.822783)
			(xy 111.348775 -223.853388) (xy 111.304101 -223.877427) (xy 111.256269 -223.894332) (xy 111.231426 -223.899476)
			(xy 111.208566 -223.903794) (xy 111.003842 -224.258632) (xy 111.011716 -224.280476) (xy 111.02029 -224.306896)
			(xy 111.02949 -224.36167) (xy 111.030004 -224.389442) (xy 111.310928 -224.389442) (xy 111.311436 -224.363555)
			(xy 111.319535 -224.312417) (xy 111.335534 -224.263177) (xy 111.35904 -224.217045) (xy 111.389472 -224.175158)
			(xy 111.426082 -224.138548) (xy 111.467969 -224.108116) (xy 111.514101 -224.08461) (xy 111.563341 -224.068611)
			(xy 111.614479 -224.060512) (xy 111.666253 -224.060512) (xy 111.717391 -224.068611) (xy 111.766631 -224.08461)
			(xy 111.812763 -224.108116) (xy 111.85465 -224.138548) (xy 111.89126 -224.175158) (xy 111.921692 -224.217045)
			(xy 111.945198 -224.263177) (xy 111.961197 -224.312417) (xy 111.969296 -224.363555) (xy 111.969804 -224.389442)
			(xy 112.250728 -224.389442) (xy 112.251135 -224.364105) (xy 112.258897 -224.314028) (xy 112.274229 -224.265728)
			(xy 112.29677 -224.220343) (xy 112.325989 -224.17894) (xy 112.361199 -224.142496) (xy 112.40157 -224.111867)
			(xy 112.446152 -224.087776) (xy 112.493895 -224.070789) (xy 112.518698 -224.065592) (xy 112.541558 -224.061274)
			(xy 112.746282 -223.706436) (xy 112.738662 -223.684338) (xy 112.730031 -223.657991) (xy 112.72071 -223.603344)
			(xy 112.72012 -223.575626) (xy 112.720628 -223.549719) (xy 112.728734 -223.498542) (xy 112.744746 -223.449263)
			(xy 112.768269 -223.403096) (xy 112.798725 -223.361177) (xy 112.835363 -223.324539) (xy 112.877282 -223.294083)
			(xy 112.923449 -223.27056) (xy 112.972728 -223.254548) (xy 113.023905 -223.246442) (xy 113.075719 -223.246442)
			(xy 113.126896 -223.254548) (xy 113.176175 -223.27056) (xy 113.222342 -223.294083) (xy 113.264261 -223.324539)
			(xy 113.300899 -223.361177) (xy 113.331355 -223.403096) (xy 113.354878 -223.449263) (xy 113.37089 -223.498542)
			(xy 113.378996 -223.549719) (xy 113.379504 -223.575626) (xy 113.379087 -223.600992) (xy 113.371334 -223.651127)
			(xy 113.355985 -223.69948) (xy 113.333403 -223.744908) (xy 113.304122 -223.786336) (xy 113.268834 -223.822783)
			(xy 113.228375 -223.853388) (xy 113.183701 -223.877427) (xy 113.135869 -223.894332) (xy 113.111026 -223.899476)
			(xy 113.088166 -223.903794) (xy 112.883442 -224.258632) (xy 112.891316 -224.280476) (xy 112.89989 -224.306896)
			(xy 112.90909 -224.36167) (xy 112.909604 -224.389442) (xy 113.190528 -224.389442) (xy 113.191036 -224.363555)
			(xy 113.199135 -224.312417) (xy 113.215134 -224.263177) (xy 113.23864 -224.217045) (xy 113.269072 -224.175158)
			(xy 113.305682 -224.138548) (xy 113.347569 -224.108116) (xy 113.393701 -224.08461) (xy 113.442941 -224.068611)
			(xy 113.494079 -224.060512) (xy 113.545853 -224.060512) (xy 113.596991 -224.068611) (xy 113.646231 -224.08461)
			(xy 113.692363 -224.108116) (xy 113.73425 -224.138548) (xy 113.77086 -224.175158) (xy 113.801292 -224.217045)
			(xy 113.824798 -224.263177) (xy 113.840797 -224.312417) (xy 113.848896 -224.363555) (xy 113.849404 -224.389442)
			(xy 114.130328 -224.389442) (xy 114.130735 -224.364105) (xy 114.138497 -224.314028) (xy 114.153829 -224.265728)
			(xy 114.17637 -224.220343) (xy 114.205589 -224.17894) (xy 114.240799 -224.142496) (xy 114.28117 -224.111867)
			(xy 114.325752 -224.087776) (xy 114.373495 -224.070789) (xy 114.398298 -224.065592) (xy 114.421158 -224.061274)
			(xy 114.626136 -223.706182) (xy 114.618516 -223.684084) (xy 114.609997 -223.657912) (xy 114.600803 -223.603651)
			(xy 114.600228 -223.576134) (xy 114.600228 -223.575626) (xy 114.600736 -223.549739) (xy 114.608835 -223.498601)
			(xy 114.624834 -223.449361) (xy 114.64834 -223.403229) (xy 114.678772 -223.361342) (xy 114.715382 -223.324732)
			(xy 114.757269 -223.2943) (xy 114.803401 -223.270794) (xy 114.852641 -223.254795) (xy 114.903779 -223.246696)
			(xy 114.955553 -223.246696) (xy 115.006691 -223.254795) (xy 115.055931 -223.270794) (xy 115.102063 -223.2943)
			(xy 115.14395 -223.324732) (xy 115.18056 -223.361342) (xy 115.210992 -223.403229) (xy 115.234498 -223.449361)
			(xy 115.250497 -223.498601) (xy 115.258596 -223.549739) (xy 115.259104 -223.575626) (xy 115.258687 -223.600992)
			(xy 115.250934 -223.651127) (xy 115.235585 -223.69948) (xy 115.213003 -223.744908) (xy 115.183722 -223.786336)
			(xy 115.148434 -223.822783) (xy 115.107975 -223.853388) (xy 115.063301 -223.877427) (xy 115.015469 -223.894332)
			(xy 114.990626 -223.899476) (xy 114.967766 -223.903794) (xy 114.763042 -224.258632) (xy 114.770916 -224.280476)
			(xy 114.77949 -224.306896) (xy 114.78869 -224.36167) (xy 114.789204 -224.389442) (xy 115.070128 -224.389442)
			(xy 115.070636 -224.363555) (xy 115.078735 -224.312417) (xy 115.094734 -224.263177) (xy 115.11824 -224.217045)
			(xy 115.148672 -224.175158) (xy 115.185282 -224.138548) (xy 115.227169 -224.108116) (xy 115.273301 -224.08461)
			(xy 115.322541 -224.068611) (xy 115.373679 -224.060512) (xy 115.425453 -224.060512) (xy 115.476591 -224.068611)
			(xy 115.525831 -224.08461) (xy 115.571963 -224.108116) (xy 115.61385 -224.138548) (xy 115.65046 -224.175158)
			(xy 115.680892 -224.217045) (xy 115.704398 -224.263177) (xy 115.720397 -224.312417) (xy 115.728496 -224.363555)
			(xy 115.729004 -224.389442) (xy 116.009928 -224.389442) (xy 116.010335 -224.364105) (xy 116.018097 -224.314028)
			(xy 116.033429 -224.265728) (xy 116.05597 -224.220343) (xy 116.085189 -224.17894) (xy 116.120399 -224.142496)
			(xy 116.16077 -224.111867) (xy 116.205352 -224.087776) (xy 116.253095 -224.070789) (xy 116.277898 -224.065592)
			(xy 116.300758 -224.061274) (xy 116.505482 -223.706436) (xy 116.497862 -223.684338) (xy 116.489231 -223.657991)
			(xy 116.47991 -223.603344) (xy 116.47932 -223.575626) (xy 116.479828 -223.549719) (xy 116.487934 -223.498542)
			(xy 116.503946 -223.449263) (xy 116.527469 -223.403096) (xy 116.557925 -223.361177) (xy 116.594563 -223.324539)
			(xy 116.636482 -223.294083) (xy 116.682649 -223.27056) (xy 116.731928 -223.254548) (xy 116.783105 -223.246442)
			(xy 116.834919 -223.246442) (xy 116.886096 -223.254548) (xy 116.935375 -223.27056) (xy 116.981542 -223.294083)
			(xy 117.023461 -223.324539) (xy 117.060099 -223.361177) (xy 117.090555 -223.403096) (xy 117.114078 -223.449263)
			(xy 117.13009 -223.498542) (xy 117.138196 -223.549719) (xy 117.138704 -223.575626) (xy 117.138287 -223.600992)
			(xy 117.130534 -223.651127) (xy 117.115185 -223.69948) (xy 117.092603 -223.744908) (xy 117.063322 -223.786336)
			(xy 117.028034 -223.822783) (xy 116.987575 -223.853388) (xy 116.942901 -223.877427) (xy 116.895069 -223.894332)
			(xy 116.870226 -223.899476) (xy 116.847366 -223.903794) (xy 116.642642 -224.258632) (xy 116.650516 -224.280476)
			(xy 116.65909 -224.306896) (xy 116.66829 -224.36167) (xy 116.668804 -224.389442) (xy 116.949728 -224.389442)
			(xy 116.950236 -224.363555) (xy 116.958335 -224.312417) (xy 116.974334 -224.263177) (xy 116.99784 -224.217045)
			(xy 117.028272 -224.175158) (xy 117.064882 -224.138548) (xy 117.106769 -224.108116) (xy 117.152901 -224.08461)
			(xy 117.202141 -224.068611) (xy 117.253279 -224.060512) (xy 117.305053 -224.060512) (xy 117.356191 -224.068611)
			(xy 117.405431 -224.08461) (xy 117.451563 -224.108116) (xy 117.49345 -224.138548) (xy 117.53006 -224.175158)
			(xy 117.560492 -224.217045) (xy 117.583998 -224.263177) (xy 117.599997 -224.312417) (xy 117.608096 -224.363555)
			(xy 117.608604 -224.389442) (xy 117.889528 -224.389442) (xy 117.889935 -224.364105) (xy 117.897697 -224.314028)
			(xy 117.913029 -224.265728) (xy 117.93557 -224.220343) (xy 117.964789 -224.17894) (xy 117.999999 -224.142496)
			(xy 118.04037 -224.111867) (xy 118.084952 -224.087776) (xy 118.132695 -224.070789) (xy 118.157498 -224.065592)
			(xy 118.180358 -224.061274) (xy 118.385082 -223.706436) (xy 118.377462 -223.684338) (xy 118.368831 -223.657991)
			(xy 118.35951 -223.603344) (xy 118.35892 -223.575626) (xy 118.359428 -223.549719) (xy 118.367534 -223.498542)
			(xy 118.383546 -223.449263) (xy 118.407069 -223.403096) (xy 118.437525 -223.361177) (xy 118.474163 -223.324539)
			(xy 118.516082 -223.294083) (xy 118.562249 -223.27056) (xy 118.611528 -223.254548) (xy 118.662705 -223.246442)
			(xy 118.714519 -223.246442) (xy 118.765696 -223.254548) (xy 118.814975 -223.27056) (xy 118.861142 -223.294083)
			(xy 118.903061 -223.324539) (xy 118.939699 -223.361177) (xy 118.970155 -223.403096) (xy 118.993678 -223.449263)
			(xy 119.00969 -223.498542) (xy 119.017796 -223.549719) (xy 119.018304 -223.575626) (xy 119.017887 -223.600992)
			(xy 119.010134 -223.651127) (xy 118.994785 -223.69948) (xy 118.972203 -223.744908) (xy 118.942922 -223.786336)
			(xy 118.907634 -223.822783) (xy 118.867175 -223.853388) (xy 118.822501 -223.877427) (xy 118.774669 -223.894332)
			(xy 118.749826 -223.899476) (xy 118.726966 -223.903794) (xy 118.522242 -224.258632) (xy 118.530116 -224.280476)
			(xy 118.53869 -224.306896) (xy 118.54789 -224.36167) (xy 118.548404 -224.389442) (xy 118.829328 -224.389442)
			(xy 118.829836 -224.363555) (xy 118.837935 -224.312417) (xy 118.853934 -224.263177) (xy 118.87744 -224.217045)
			(xy 118.907872 -224.175158) (xy 118.944482 -224.138548) (xy 118.986369 -224.108116) (xy 119.032501 -224.08461)
			(xy 119.081741 -224.068611) (xy 119.132879 -224.060512) (xy 119.184653 -224.060512) (xy 119.235791 -224.068611)
			(xy 119.285031 -224.08461) (xy 119.331163 -224.108116) (xy 119.37305 -224.138548) (xy 119.40966 -224.175158)
			(xy 119.440092 -224.217045) (xy 119.463598 -224.263177) (xy 119.479597 -224.312417) (xy 119.487696 -224.363555)
			(xy 119.488204 -224.389442) (xy 119.769128 -224.389442) (xy 119.769535 -224.364105) (xy 119.777297 -224.314028)
			(xy 119.792629 -224.265728) (xy 119.81517 -224.220343) (xy 119.844389 -224.17894) (xy 119.879599 -224.142496)
			(xy 119.91997 -224.111867) (xy 119.964552 -224.087776) (xy 120.012295 -224.070789) (xy 120.037098 -224.065592)
			(xy 120.059958 -224.061274) (xy 120.264682 -223.706436) (xy 120.257062 -223.684338) (xy 120.248431 -223.657991)
			(xy 120.23911 -223.603344) (xy 120.23852 -223.575626) (xy 120.239028 -223.549719) (xy 120.247134 -223.498542)
			(xy 120.263146 -223.449263) (xy 120.286669 -223.403096) (xy 120.317125 -223.361177) (xy 120.353763 -223.324539)
			(xy 120.395682 -223.294083) (xy 120.441849 -223.27056) (xy 120.491128 -223.254548) (xy 120.542305 -223.246442)
			(xy 120.594119 -223.246442) (xy 120.645296 -223.254548) (xy 120.694575 -223.27056) (xy 120.740742 -223.294083)
			(xy 120.782661 -223.324539) (xy 120.819299 -223.361177) (xy 120.849755 -223.403096) (xy 120.873278 -223.449263)
			(xy 120.88929 -223.498542) (xy 120.897396 -223.549719) (xy 120.897904 -223.575626) (xy 120.897487 -223.600992)
			(xy 120.889734 -223.651127) (xy 120.874385 -223.69948) (xy 120.851803 -223.744908) (xy 120.822522 -223.786336)
			(xy 120.787234 -223.822783) (xy 120.746775 -223.853388) (xy 120.702101 -223.877427) (xy 120.654269 -223.894332)
			(xy 120.629426 -223.899476) (xy 120.606566 -223.903794) (xy 120.401842 -224.258632) (xy 120.409716 -224.280476)
			(xy 120.41829 -224.306896) (xy 120.42749 -224.36167) (xy 120.428004 -224.389442) (xy 120.708928 -224.389442)
			(xy 120.709436 -224.363555) (xy 120.717535 -224.312417) (xy 120.733534 -224.263177) (xy 120.75704 -224.217045)
			(xy 120.787472 -224.175158) (xy 120.824082 -224.138548) (xy 120.865969 -224.108116) (xy 120.912101 -224.08461)
			(xy 120.961341 -224.068611) (xy 121.012479 -224.060512) (xy 121.064253 -224.060512) (xy 121.115391 -224.068611)
			(xy 121.164631 -224.08461) (xy 121.210763 -224.108116) (xy 121.25265 -224.138548) (xy 121.28926 -224.175158)
			(xy 121.319692 -224.217045) (xy 121.343198 -224.263177) (xy 121.359197 -224.312417) (xy 121.367296 -224.363555)
			(xy 121.367804 -224.389442) (xy 121.648728 -224.389442) (xy 121.649135 -224.364105) (xy 121.656897 -224.314028)
			(xy 121.672229 -224.265728) (xy 121.69477 -224.220343) (xy 121.723989 -224.17894) (xy 121.759199 -224.142496)
			(xy 121.79957 -224.111867) (xy 121.844152 -224.087776) (xy 121.891895 -224.070789) (xy 121.916698 -224.065592)
			(xy 121.939558 -224.061274) (xy 122.144282 -223.706436) (xy 122.136662 -223.684338) (xy 122.128031 -223.657991)
			(xy 122.11871 -223.603344) (xy 122.11812 -223.575626) (xy 122.118628 -223.549719) (xy 122.126734 -223.498542)
			(xy 122.142746 -223.449263) (xy 122.166269 -223.403096) (xy 122.196725 -223.361177) (xy 122.233363 -223.324539)
			(xy 122.275282 -223.294083) (xy 122.321449 -223.27056) (xy 122.370728 -223.254548) (xy 122.421905 -223.246442)
			(xy 122.473719 -223.246442) (xy 122.524896 -223.254548) (xy 122.574175 -223.27056) (xy 122.620342 -223.294083)
			(xy 122.662261 -223.324539) (xy 122.698899 -223.361177) (xy 122.729355 -223.403096) (xy 122.752878 -223.449263)
			(xy 122.76889 -223.498542) (xy 122.776996 -223.549719) (xy 122.777504 -223.575626) (xy 122.777087 -223.600992)
			(xy 122.769334 -223.651127) (xy 122.753985 -223.69948) (xy 122.731403 -223.744908) (xy 122.702122 -223.786336)
			(xy 122.666834 -223.822783) (xy 122.626375 -223.853388) (xy 122.581701 -223.877427) (xy 122.533869 -223.894332)
			(xy 122.509026 -223.899476) (xy 122.486166 -223.903794) (xy 122.281442 -224.258632) (xy 122.289316 -224.280476)
			(xy 122.29789 -224.306896) (xy 122.30709 -224.36167) (xy 122.307604 -224.389442) (xy 122.588528 -224.389442)
			(xy 122.589036 -224.363555) (xy 122.597135 -224.312417) (xy 122.613134 -224.263177) (xy 122.63664 -224.217045)
			(xy 122.667072 -224.175158) (xy 122.703682 -224.138548) (xy 122.745569 -224.108116) (xy 122.791701 -224.08461)
			(xy 122.840941 -224.068611) (xy 122.892079 -224.060512) (xy 122.943853 -224.060512) (xy 122.994991 -224.068611)
			(xy 123.044231 -224.08461) (xy 123.090363 -224.108116) (xy 123.13225 -224.138548) (xy 123.16886 -224.175158)
			(xy 123.199292 -224.217045) (xy 123.222798 -224.263177) (xy 123.238797 -224.312417) (xy 123.246896 -224.363555)
			(xy 123.247404 -224.389442) (xy 123.528328 -224.389442) (xy 123.528735 -224.364105) (xy 123.536497 -224.314028)
			(xy 123.551829 -224.265728) (xy 123.57437 -224.220343) (xy 123.603589 -224.17894) (xy 123.638799 -224.142496)
			(xy 123.67917 -224.111867) (xy 123.723752 -224.087776) (xy 123.771495 -224.070789) (xy 123.796298 -224.065592)
			(xy 123.819158 -224.061274) (xy 124.023882 -223.706436) (xy 124.016262 -223.684338) (xy 124.007631 -223.657991)
			(xy 123.99831 -223.603344) (xy 123.99772 -223.575626) (xy 123.998228 -223.549719) (xy 124.006334 -223.498542)
			(xy 124.022346 -223.449263) (xy 124.045869 -223.403096) (xy 124.076325 -223.361177) (xy 124.112963 -223.324539)
			(xy 124.154882 -223.294083) (xy 124.201049 -223.27056) (xy 124.250328 -223.254548) (xy 124.301505 -223.246442)
			(xy 124.353319 -223.246442) (xy 124.404496 -223.254548) (xy 124.453775 -223.27056) (xy 124.499942 -223.294083)
			(xy 124.541861 -223.324539) (xy 124.578499 -223.361177) (xy 124.608955 -223.403096) (xy 124.632478 -223.449263)
			(xy 124.64849 -223.498542) (xy 124.656596 -223.549719) (xy 124.657104 -223.575626) (xy 124.656687 -223.600992)
			(xy 124.648934 -223.651127) (xy 124.633585 -223.69948) (xy 124.611003 -223.744908) (xy 124.581722 -223.786336)
			(xy 124.546434 -223.822783) (xy 124.505975 -223.853388) (xy 124.461301 -223.877427) (xy 124.413469 -223.894332)
			(xy 124.388626 -223.899476) (xy 124.365766 -223.903794) (xy 124.161042 -224.258632) (xy 124.168916 -224.280476)
			(xy 124.17749 -224.306896) (xy 124.18669 -224.36167) (xy 124.187204 -224.389442) (xy 124.468128 -224.389442)
			(xy 124.468636 -224.363555) (xy 124.476735 -224.312417) (xy 124.492734 -224.263177) (xy 124.51624 -224.217045)
			(xy 124.546672 -224.175158) (xy 124.583282 -224.138548) (xy 124.625169 -224.108116) (xy 124.671301 -224.08461)
			(xy 124.720541 -224.068611) (xy 124.771679 -224.060512) (xy 124.823453 -224.060512) (xy 124.874591 -224.068611)
			(xy 124.923831 -224.08461) (xy 124.969963 -224.108116) (xy 125.01185 -224.138548) (xy 125.04846 -224.175158)
			(xy 125.078892 -224.217045) (xy 125.102398 -224.263177) (xy 125.118397 -224.312417) (xy 125.126496 -224.363555)
			(xy 125.127004 -224.389442) (xy 125.407928 -224.389442) (xy 125.408335 -224.364105) (xy 125.416097 -224.314028)
			(xy 125.431429 -224.265728) (xy 125.45397 -224.220343) (xy 125.483189 -224.17894) (xy 125.518399 -224.142496)
			(xy 125.55877 -224.111867) (xy 125.603352 -224.087776) (xy 125.651095 -224.070789) (xy 125.675898 -224.065592)
			(xy 125.698758 -224.061274) (xy 125.903482 -223.706436) (xy 125.895862 -223.684338) (xy 125.887231 -223.657991)
			(xy 125.87791 -223.603344) (xy 125.87732 -223.575626) (xy 125.877828 -223.549719) (xy 125.885934 -223.498542)
			(xy 125.901946 -223.449263) (xy 125.925469 -223.403096) (xy 125.955925 -223.361177) (xy 125.992563 -223.324539)
			(xy 126.034482 -223.294083) (xy 126.080649 -223.27056) (xy 126.129928 -223.254548) (xy 126.181105 -223.246442)
			(xy 126.232919 -223.246442) (xy 126.284096 -223.254548) (xy 126.333375 -223.27056) (xy 126.379542 -223.294083)
			(xy 126.421461 -223.324539) (xy 126.458099 -223.361177) (xy 126.488555 -223.403096) (xy 126.512078 -223.449263)
			(xy 126.52809 -223.498542) (xy 126.536196 -223.549719) (xy 126.536704 -223.575626) (xy 126.536287 -223.600992)
			(xy 126.528534 -223.651127) (xy 126.513185 -223.69948) (xy 126.490603 -223.744908) (xy 126.461322 -223.786336)
			(xy 126.426034 -223.822783) (xy 126.385575 -223.853388) (xy 126.340901 -223.877427) (xy 126.293069 -223.894332)
			(xy 126.268226 -223.899476) (xy 126.245366 -223.903794) (xy 126.040642 -224.258632) (xy 126.048516 -224.280476)
			(xy 126.05709 -224.306896) (xy 126.06629 -224.36167) (xy 126.066804 -224.389442) (xy 126.347728 -224.389442)
			(xy 126.348236 -224.363555) (xy 126.356335 -224.312417) (xy 126.372334 -224.263177) (xy 126.39584 -224.217045)
			(xy 126.426272 -224.175158) (xy 126.462882 -224.138548) (xy 126.504769 -224.108116) (xy 126.550901 -224.08461)
			(xy 126.600141 -224.068611) (xy 126.651279 -224.060512) (xy 126.703053 -224.060512) (xy 126.754191 -224.068611)
			(xy 126.803431 -224.08461) (xy 126.849563 -224.108116) (xy 126.89145 -224.138548) (xy 126.92806 -224.175158)
			(xy 126.958492 -224.217045) (xy 126.981998 -224.263177) (xy 126.997997 -224.312417) (xy 127.006096 -224.363555)
			(xy 127.006604 -224.389442) (xy 127.287528 -224.389442) (xy 127.287935 -224.364105) (xy 127.295697 -224.314028)
			(xy 127.311029 -224.265728) (xy 127.33357 -224.220343) (xy 127.362789 -224.17894) (xy 127.397999 -224.142496)
			(xy 127.43837 -224.111867) (xy 127.482952 -224.087776) (xy 127.530695 -224.070789) (xy 127.555498 -224.065592)
			(xy 127.578358 -224.061274) (xy 127.783082 -223.706436) (xy 127.775462 -223.684338) (xy 127.766831 -223.657991)
			(xy 127.75751 -223.603344) (xy 127.75692 -223.575626) (xy 127.757428 -223.549719) (xy 127.765534 -223.498542)
			(xy 127.781546 -223.449263) (xy 127.805069 -223.403096) (xy 127.835525 -223.361177) (xy 127.872163 -223.324539)
			(xy 127.914082 -223.294083) (xy 127.960249 -223.27056) (xy 128.009528 -223.254548) (xy 128.060705 -223.246442)
			(xy 128.112519 -223.246442) (xy 128.163696 -223.254548) (xy 128.212975 -223.27056) (xy 128.259142 -223.294083)
			(xy 128.301061 -223.324539) (xy 128.337699 -223.361177) (xy 128.368155 -223.403096) (xy 128.391678 -223.449263)
			(xy 128.40769 -223.498542) (xy 128.415796 -223.549719) (xy 128.416304 -223.575626) (xy 128.415887 -223.600992)
			(xy 128.408134 -223.651127) (xy 128.392785 -223.69948) (xy 128.370203 -223.744908) (xy 128.340922 -223.786336)
			(xy 128.305634 -223.822783) (xy 128.265175 -223.853388) (xy 128.220501 -223.877427) (xy 128.172669 -223.894332)
			(xy 128.147826 -223.899476) (xy 128.124966 -223.903794) (xy 127.920242 -224.258632) (xy 127.928116 -224.280476)
			(xy 127.93669 -224.306896) (xy 127.94589 -224.36167) (xy 127.946404 -224.389442) (xy 128.227328 -224.389442)
			(xy 128.227836 -224.363555) (xy 128.235935 -224.312417) (xy 128.251934 -224.263177) (xy 128.27544 -224.217045)
			(xy 128.305872 -224.175158) (xy 128.342482 -224.138548) (xy 128.384369 -224.108116) (xy 128.430501 -224.08461)
			(xy 128.479741 -224.068611) (xy 128.530879 -224.060512) (xy 128.582653 -224.060512) (xy 128.633791 -224.068611)
			(xy 128.683031 -224.08461) (xy 128.729163 -224.108116) (xy 128.77105 -224.138548) (xy 128.80766 -224.175158)
			(xy 128.838092 -224.217045) (xy 128.861598 -224.263177) (xy 128.877597 -224.312417) (xy 128.885696 -224.363555)
			(xy 128.886204 -224.389442) (xy 129.167128 -224.389442) (xy 129.167535 -224.364105) (xy 129.175297 -224.314028)
			(xy 129.190629 -224.265728) (xy 129.21317 -224.220343) (xy 129.242389 -224.17894) (xy 129.277599 -224.142496)
			(xy 129.31797 -224.111867) (xy 129.362552 -224.087776) (xy 129.410295 -224.070789) (xy 129.435098 -224.065592)
			(xy 129.457958 -224.061274) (xy 129.662682 -223.706436) (xy 129.655062 -223.684338) (xy 129.646431 -223.657991)
			(xy 129.63711 -223.603344) (xy 129.63652 -223.575626) (xy 129.637028 -223.549719) (xy 129.645134 -223.498542)
			(xy 129.661146 -223.449263) (xy 129.684669 -223.403096) (xy 129.715125 -223.361177) (xy 129.751763 -223.324539)
			(xy 129.793682 -223.294083) (xy 129.839849 -223.27056) (xy 129.889128 -223.254548) (xy 129.940305 -223.246442)
			(xy 129.992119 -223.246442) (xy 130.043296 -223.254548) (xy 130.092575 -223.27056) (xy 130.138742 -223.294083)
			(xy 130.180661 -223.324539) (xy 130.217299 -223.361177) (xy 130.247755 -223.403096) (xy 130.271278 -223.449263)
			(xy 130.28729 -223.498542) (xy 130.295396 -223.549719) (xy 130.295904 -223.575626) (xy 130.295487 -223.600992)
			(xy 130.287734 -223.651127) (xy 130.272385 -223.69948) (xy 130.249803 -223.744908) (xy 130.220522 -223.786336)
			(xy 130.185234 -223.822783) (xy 130.144775 -223.853388) (xy 130.100101 -223.877427) (xy 130.052269 -223.894332)
			(xy 130.027426 -223.899476) (xy 130.004566 -223.903794) (xy 129.799842 -224.258632) (xy 129.807716 -224.280476)
			(xy 129.81629 -224.306896) (xy 129.82549 -224.36167) (xy 129.826004 -224.389442) (xy 130.106928 -224.389442)
			(xy 130.107436 -224.363555) (xy 130.115535 -224.312417) (xy 130.131534 -224.263177) (xy 130.15504 -224.217045)
			(xy 130.185472 -224.175158) (xy 130.222082 -224.138548) (xy 130.263969 -224.108116) (xy 130.310101 -224.08461)
			(xy 130.359341 -224.068611) (xy 130.410479 -224.060512) (xy 130.462253 -224.060512) (xy 130.513391 -224.068611)
			(xy 130.562631 -224.08461) (xy 130.608763 -224.108116) (xy 130.65065 -224.138548) (xy 130.68726 -224.175158)
			(xy 130.717692 -224.217045) (xy 130.741198 -224.263177) (xy 130.757197 -224.312417) (xy 130.765296 -224.363555)
			(xy 130.765804 -224.389442) (xy 131.046728 -224.389442) (xy 131.047135 -224.364105) (xy 131.054897 -224.314028)
			(xy 131.070229 -224.265728) (xy 131.09277 -224.220343) (xy 131.121989 -224.17894) (xy 131.157199 -224.142496)
			(xy 131.19757 -224.111867) (xy 131.242152 -224.087776) (xy 131.289895 -224.070789) (xy 131.314698 -224.065592)
			(xy 131.337558 -224.061274) (xy 131.542282 -223.706182) (xy 131.534662 -223.684338) (xy 131.526017 -223.657995)
			(xy 131.516704 -223.603345) (xy 131.51612 -223.575626) (xy 131.516628 -223.549719) (xy 131.524734 -223.498542)
			(xy 131.540746 -223.449263) (xy 131.564269 -223.403096) (xy 131.594725 -223.361177) (xy 131.631363 -223.324539)
			(xy 131.673282 -223.294083) (xy 131.719449 -223.27056) (xy 131.768728 -223.254548) (xy 131.819905 -223.246442)
			(xy 131.871719 -223.246442) (xy 131.922896 -223.254548) (xy 131.972175 -223.27056) (xy 132.018342 -223.294083)
			(xy 132.060261 -223.324539) (xy 132.096899 -223.361177) (xy 132.127355 -223.403096) (xy 132.150878 -223.449263)
			(xy 132.16689 -223.498542) (xy 132.174996 -223.549719) (xy 132.175504 -223.575626) (xy 132.175003 -223.60097)
			(xy 132.167228 -223.651059) (xy 132.151879 -223.699368) (xy 132.12932 -223.74476) (xy 132.10008 -223.786165)
			(xy 132.064849 -223.822609) (xy 132.024457 -223.853232) (xy 131.979854 -223.877314) (xy 131.932092 -223.894288)
			(xy 131.90728 -223.899476) (xy 131.88442 -223.903794) (xy 131.679696 -224.258632) (xy 131.687316 -224.280476)
			(xy 131.695872 -224.306769) (xy 131.705065 -224.361289) (xy 131.705604 -224.388934) (xy 131.705604 -224.389442)
			(xy 131.986528 -224.389442) (xy 131.987036 -224.363555) (xy 131.995135 -224.312417) (xy 132.011134 -224.263177)
			(xy 132.03464 -224.217045) (xy 132.065072 -224.175158) (xy 132.101682 -224.138548) (xy 132.143569 -224.108116)
			(xy 132.189701 -224.08461) (xy 132.238941 -224.068611) (xy 132.290079 -224.060512) (xy 132.341853 -224.060512)
			(xy 132.392991 -224.068611) (xy 132.442231 -224.08461) (xy 132.488363 -224.108116) (xy 132.53025 -224.138548)
			(xy 132.56686 -224.175158) (xy 132.597292 -224.217045) (xy 132.620798 -224.263177) (xy 132.636797 -224.312417)
			(xy 132.644896 -224.363555) (xy 132.645404 -224.389442) (xy 132.926328 -224.389442) (xy 132.926735 -224.364105)
			(xy 132.934497 -224.314028) (xy 132.949829 -224.265728) (xy 132.97237 -224.220343) (xy 133.001589 -224.17894)
			(xy 133.036799 -224.142496) (xy 133.07717 -224.111867) (xy 133.121752 -224.087776) (xy 133.169495 -224.070789)
			(xy 133.194298 -224.065592) (xy 133.217158 -224.061274) (xy 133.422136 -223.705928) (xy 133.414516 -223.684084)
			(xy 133.405997 -223.657912) (xy 133.396803 -223.603651) (xy 133.396228 -223.576134) (xy 133.396228 -223.575626)
			(xy 133.396736 -223.549739) (xy 133.404835 -223.498601) (xy 133.420834 -223.449361) (xy 133.44434 -223.403229)
			(xy 133.474772 -223.361342) (xy 133.511382 -223.324732) (xy 133.553269 -223.2943) (xy 133.599401 -223.270794)
			(xy 133.648641 -223.254795) (xy 133.699779 -223.246696) (xy 133.751553 -223.246696) (xy 133.802691 -223.254795)
			(xy 133.851931 -223.270794) (xy 133.898063 -223.2943) (xy 133.93995 -223.324732) (xy 133.97656 -223.361342)
			(xy 134.006992 -223.403229) (xy 134.030498 -223.449361) (xy 134.046497 -223.498601) (xy 134.054596 -223.549739)
			(xy 134.055104 -223.575626) (xy 134.054603 -223.60097) (xy 134.046828 -223.651059) (xy 134.031479 -223.699368)
			(xy 134.00892 -223.74476) (xy 133.97968 -223.786165) (xy 133.944449 -223.822609) (xy 133.904057 -223.853232)
			(xy 133.870156 -223.871536) (xy 162.162236 -223.871536) (xy 162.162236 -223.462596) (xy 162.162619 -223.452437)
			(xy 162.170423 -223.433678) (xy 162.184832 -223.419353) (xy 162.203637 -223.41166) (xy 162.213798 -223.411288)
			(xy 163.613338 -223.411288) (xy 163.623461 -223.411794) (xy 163.642173 -223.419525) (xy 163.656526 -223.433804)
			(xy 163.664353 -223.452476) (xy 163.6649 -223.462596) (xy 163.6649 -223.871536) (xy 169.706036 -223.871536)
			(xy 169.706036 -223.462596) (xy 169.706419 -223.452437) (xy 169.714223 -223.433678) (xy 169.728632 -223.419353)
			(xy 169.747437 -223.41166) (xy 169.757598 -223.411288) (xy 171.157138 -223.411288) (xy 171.167261 -223.411794)
			(xy 171.185973 -223.419525) (xy 171.200326 -223.433804) (xy 171.208153 -223.452476) (xy 171.2087 -223.462596)
			(xy 171.2087 -223.871536) (xy 177.249836 -223.871536) (xy 177.249836 -223.462596) (xy 177.250219 -223.452437)
			(xy 177.258023 -223.433678) (xy 177.272432 -223.419353) (xy 177.291237 -223.41166) (xy 177.301398 -223.411288)
			(xy 178.700938 -223.411288) (xy 178.711061 -223.411794) (xy 178.729773 -223.419525) (xy 178.744126 -223.433804)
			(xy 178.751953 -223.452476) (xy 178.7525 -223.462596) (xy 178.7525 -223.871536) (xy 184.793636 -223.871536)
			(xy 184.793636 -223.462596) (xy 184.794019 -223.452437) (xy 184.801823 -223.433678) (xy 184.816232 -223.419353)
			(xy 184.835037 -223.41166) (xy 184.845198 -223.411288) (xy 186.244738 -223.411288) (xy 186.254861 -223.411794)
			(xy 186.273573 -223.419525) (xy 186.287926 -223.433804) (xy 186.295753 -223.452476) (xy 186.2963 -223.462596)
			(xy 186.2963 -223.871536) (xy 192.337436 -223.871536) (xy 192.337436 -223.462596) (xy 192.337819 -223.452437)
			(xy 192.345623 -223.433678) (xy 192.360032 -223.419353) (xy 192.378837 -223.41166) (xy 192.388998 -223.411288)
			(xy 193.788538 -223.411288) (xy 193.798661 -223.411794) (xy 193.817373 -223.419525) (xy 193.831726 -223.433804)
			(xy 193.839553 -223.452476) (xy 193.8401 -223.462596) (xy 193.8401 -223.871536) (xy 199.881236 -223.871536)
			(xy 199.881236 -223.462596) (xy 199.881619 -223.452437) (xy 199.889423 -223.433678) (xy 199.903832 -223.419353)
			(xy 199.922637 -223.41166) (xy 199.932798 -223.411288) (xy 201.332338 -223.411288) (xy 201.342461 -223.411794)
			(xy 201.361173 -223.419525) (xy 201.375526 -223.433804) (xy 201.383353 -223.452476) (xy 201.3839 -223.462596)
			(xy 201.3839 -223.871536) (xy 207.425036 -223.871536) (xy 207.425036 -223.462596) (xy 207.425419 -223.452437)
			(xy 207.433223 -223.433678) (xy 207.447632 -223.419353) (xy 207.466437 -223.41166) (xy 207.476598 -223.411288)
			(xy 208.876138 -223.411288) (xy 208.886261 -223.411794) (xy 208.904973 -223.419525) (xy 208.919326 -223.433804)
			(xy 208.927153 -223.452476) (xy 208.9277 -223.462596) (xy 208.9277 -223.871536) (xy 214.968836 -223.871536)
			(xy 214.968836 -223.462596) (xy 214.969219 -223.452437) (xy 214.977023 -223.433678) (xy 214.991432 -223.419353)
			(xy 215.010237 -223.41166) (xy 215.020398 -223.411288) (xy 216.419938 -223.411288) (xy 216.430061 -223.411794)
			(xy 216.448773 -223.419525) (xy 216.463126 -223.433804) (xy 216.470953 -223.452476) (xy 216.4715 -223.462596)
			(xy 216.4715 -223.871536) (xy 259.429504 -223.871536) (xy 259.429504 -223.462596) (xy 259.429919 -223.452441)
			(xy 259.437716 -223.433688) (xy 259.452115 -223.419365) (xy 259.470909 -223.411666) (xy 259.481066 -223.411288)
			(xy 260.880606 -223.411288) (xy 260.890727 -223.41182) (xy 260.909438 -223.41954) (xy 260.923792 -223.433812)
			(xy 260.93162 -223.452478) (xy 260.932168 -223.462596) (xy 260.932168 -223.871536) (xy 266.973304 -223.871536)
			(xy 266.973304 -223.462596) (xy 266.973719 -223.452441) (xy 266.981516 -223.433688) (xy 266.995915 -223.419365)
			(xy 267.014709 -223.411666) (xy 267.024866 -223.411288) (xy 268.424406 -223.411288) (xy 268.434527 -223.41182)
			(xy 268.453238 -223.41954) (xy 268.467592 -223.433812) (xy 268.47542 -223.452478) (xy 268.475968 -223.462596)
			(xy 268.475968 -223.871536) (xy 274.517104 -223.871536) (xy 274.517104 -223.462596) (xy 274.517519 -223.452441)
			(xy 274.525316 -223.433688) (xy 274.539715 -223.419365) (xy 274.558509 -223.411666) (xy 274.568666 -223.411288)
			(xy 275.968206 -223.411288) (xy 275.978327 -223.41182) (xy 275.997038 -223.41954) (xy 276.011392 -223.433812)
			(xy 276.01922 -223.452478) (xy 276.019768 -223.462596) (xy 276.019768 -223.871536) (xy 282.060904 -223.871536)
			(xy 282.060904 -223.462596) (xy 282.061319 -223.452441) (xy 282.069116 -223.433688) (xy 282.083515 -223.419365)
			(xy 282.102309 -223.411666) (xy 282.112466 -223.411288) (xy 283.512006 -223.411288) (xy 283.522127 -223.41182)
			(xy 283.540838 -223.41954) (xy 283.555192 -223.433812) (xy 283.56302 -223.452478) (xy 283.563568 -223.462596)
			(xy 283.563568 -223.871536) (xy 289.604704 -223.871536) (xy 289.604704 -223.462596) (xy 289.605119 -223.452441)
			(xy 289.612916 -223.433688) (xy 289.627315 -223.419365) (xy 289.646109 -223.411666) (xy 289.656266 -223.411288)
			(xy 291.055806 -223.411288) (xy 291.065927 -223.41182) (xy 291.084638 -223.41954) (xy 291.098992 -223.433812)
			(xy 291.10682 -223.452478) (xy 291.107368 -223.462596) (xy 291.107368 -223.871536) (xy 297.148504 -223.871536)
			(xy 297.148504 -223.462596) (xy 297.148919 -223.452441) (xy 297.156716 -223.433688) (xy 297.171115 -223.419365)
			(xy 297.189909 -223.411666) (xy 297.200066 -223.411288) (xy 298.599606 -223.411288) (xy 298.609727 -223.41182)
			(xy 298.628438 -223.41954) (xy 298.642792 -223.433812) (xy 298.65062 -223.452478) (xy 298.651168 -223.462596)
			(xy 298.651168 -223.871536) (xy 304.692304 -223.871536) (xy 304.692304 -223.462596) (xy 304.692719 -223.452441)
			(xy 304.700516 -223.433688) (xy 304.714915 -223.419365) (xy 304.733709 -223.411666) (xy 304.743866 -223.411288)
			(xy 306.143406 -223.411288) (xy 306.153527 -223.41182) (xy 306.172238 -223.41954) (xy 306.186592 -223.433812)
			(xy 306.19442 -223.452478) (xy 306.194968 -223.462596) (xy 306.194968 -223.871536) (xy 312.236104 -223.871536)
			(xy 312.236104 -223.462596) (xy 312.236519 -223.452441) (xy 312.244316 -223.433688) (xy 312.258715 -223.419365)
			(xy 312.277509 -223.411666) (xy 312.287666 -223.411288) (xy 313.687206 -223.411288) (xy 313.697327 -223.41182)
			(xy 313.716038 -223.41954) (xy 313.730392 -223.433812) (xy 313.73822 -223.452478) (xy 313.738768 -223.462596)
			(xy 313.738768 -223.871536) (xy 313.738407 -223.881696) (xy 313.730594 -223.900456) (xy 313.716178 -223.914779)
			(xy 313.697369 -223.922472) (xy 313.687206 -223.922844) (xy 312.287666 -223.922844) (xy 312.277535 -223.922401)
			(xy 312.25881 -223.914659) (xy 312.244454 -223.900359) (xy 312.236639 -223.881665) (xy 312.236104 -223.871536)
			(xy 306.194968 -223.871536) (xy 306.194607 -223.881696) (xy 306.186794 -223.900456) (xy 306.172378 -223.914779)
			(xy 306.153569 -223.922472) (xy 306.143406 -223.922844) (xy 304.743866 -223.922844) (xy 304.733735 -223.922401)
			(xy 304.71501 -223.914659) (xy 304.700654 -223.900359) (xy 304.692839 -223.881665) (xy 304.692304 -223.871536)
			(xy 298.651168 -223.871536) (xy 298.650807 -223.881696) (xy 298.642994 -223.900456) (xy 298.628578 -223.914779)
			(xy 298.609769 -223.922472) (xy 298.599606 -223.922844) (xy 297.200066 -223.922844) (xy 297.189935 -223.922401)
			(xy 297.17121 -223.914659) (xy 297.156854 -223.900359) (xy 297.149039 -223.881665) (xy 297.148504 -223.871536)
			(xy 291.107368 -223.871536) (xy 291.107007 -223.881696) (xy 291.099194 -223.900456) (xy 291.084778 -223.914779)
			(xy 291.065969 -223.922472) (xy 291.055806 -223.922844) (xy 289.656266 -223.922844) (xy 289.646135 -223.922401)
			(xy 289.62741 -223.914659) (xy 289.613054 -223.900359) (xy 289.605239 -223.881665) (xy 289.604704 -223.871536)
			(xy 283.563568 -223.871536) (xy 283.563207 -223.881696) (xy 283.555394 -223.900456) (xy 283.540978 -223.914779)
			(xy 283.522169 -223.922472) (xy 283.512006 -223.922844) (xy 282.112466 -223.922844) (xy 282.102335 -223.922401)
			(xy 282.08361 -223.914659) (xy 282.069254 -223.900359) (xy 282.061439 -223.881665) (xy 282.060904 -223.871536)
			(xy 276.019768 -223.871536) (xy 276.019407 -223.881696) (xy 276.011594 -223.900456) (xy 275.997178 -223.914779)
			(xy 275.978369 -223.922472) (xy 275.968206 -223.922844) (xy 274.568666 -223.922844) (xy 274.558535 -223.922401)
			(xy 274.53981 -223.914659) (xy 274.525454 -223.900359) (xy 274.517639 -223.881665) (xy 274.517104 -223.871536)
			(xy 268.475968 -223.871536) (xy 268.475607 -223.881696) (xy 268.467794 -223.900456) (xy 268.453378 -223.914779)
			(xy 268.434569 -223.922472) (xy 268.424406 -223.922844) (xy 267.024866 -223.922844) (xy 267.014735 -223.922401)
			(xy 266.99601 -223.914659) (xy 266.981654 -223.900359) (xy 266.973839 -223.881665) (xy 266.973304 -223.871536)
			(xy 260.932168 -223.871536) (xy 260.931807 -223.881696) (xy 260.923994 -223.900456) (xy 260.909578 -223.914779)
			(xy 260.890769 -223.922472) (xy 260.880606 -223.922844) (xy 259.481066 -223.922844) (xy 259.470935 -223.922401)
			(xy 259.45221 -223.914659) (xy 259.437854 -223.900359) (xy 259.430039 -223.881665) (xy 259.429504 -223.871536)
			(xy 216.4715 -223.871536) (xy 216.471108 -223.881692) (xy 216.4633 -223.900446) (xy 216.448895 -223.914768)
			(xy 216.430097 -223.922466) (xy 216.419938 -223.922844) (xy 215.020398 -223.922844) (xy 215.010269 -223.922374)
			(xy 214.991545 -223.914643) (xy 214.977188 -223.900351) (xy 214.969372 -223.881662) (xy 214.968836 -223.871536)
			(xy 208.9277 -223.871536) (xy 208.927308 -223.881692) (xy 208.9195 -223.900446) (xy 208.905095 -223.914768)
			(xy 208.886297 -223.922466) (xy 208.876138 -223.922844) (xy 207.476598 -223.922844) (xy 207.466469 -223.922374)
			(xy 207.447745 -223.914643) (xy 207.433388 -223.900351) (xy 207.425572 -223.881662) (xy 207.425036 -223.871536)
			(xy 201.3839 -223.871536) (xy 201.383508 -223.881692) (xy 201.3757 -223.900446) (xy 201.361295 -223.914768)
			(xy 201.342497 -223.922466) (xy 201.332338 -223.922844) (xy 199.932798 -223.922844) (xy 199.922669 -223.922374)
			(xy 199.903945 -223.914643) (xy 199.889588 -223.900351) (xy 199.881772 -223.881662) (xy 199.881236 -223.871536)
			(xy 193.8401 -223.871536) (xy 193.839708 -223.881692) (xy 193.8319 -223.900446) (xy 193.817495 -223.914768)
			(xy 193.798697 -223.922466) (xy 193.788538 -223.922844) (xy 192.388998 -223.922844) (xy 192.378869 -223.922374)
			(xy 192.360145 -223.914643) (xy 192.345788 -223.900351) (xy 192.337972 -223.881662) (xy 192.337436 -223.871536)
			(xy 186.2963 -223.871536) (xy 186.295908 -223.881692) (xy 186.2881 -223.900446) (xy 186.273695 -223.914768)
			(xy 186.254897 -223.922466) (xy 186.244738 -223.922844) (xy 184.845198 -223.922844) (xy 184.835069 -223.922374)
			(xy 184.816345 -223.914643) (xy 184.801988 -223.900351) (xy 184.794172 -223.881662) (xy 184.793636 -223.871536)
			(xy 178.7525 -223.871536) (xy 178.752108 -223.881692) (xy 178.7443 -223.900446) (xy 178.729895 -223.914768)
			(xy 178.711097 -223.922466) (xy 178.700938 -223.922844) (xy 177.301398 -223.922844) (xy 177.291269 -223.922374)
			(xy 177.272545 -223.914643) (xy 177.258188 -223.900351) (xy 177.250372 -223.881662) (xy 177.249836 -223.871536)
			(xy 171.2087 -223.871536) (xy 171.208308 -223.881692) (xy 171.2005 -223.900446) (xy 171.186095 -223.914768)
			(xy 171.167297 -223.922466) (xy 171.157138 -223.922844) (xy 169.757598 -223.922844) (xy 169.747469 -223.922374)
			(xy 169.728745 -223.914643) (xy 169.714388 -223.900351) (xy 169.706572 -223.881662) (xy 169.706036 -223.871536)
			(xy 163.6649 -223.871536) (xy 163.664508 -223.881692) (xy 163.6567 -223.900446) (xy 163.642295 -223.914768)
			(xy 163.623497 -223.922466) (xy 163.613338 -223.922844) (xy 162.213798 -223.922844) (xy 162.203669 -223.922374)
			(xy 162.184945 -223.914643) (xy 162.170588 -223.900351) (xy 162.162772 -223.881662) (xy 162.162236 -223.871536)
			(xy 133.870156 -223.871536) (xy 133.859454 -223.877314) (xy 133.811692 -223.894288) (xy 133.78688 -223.899476)
			(xy 133.76402 -223.903794) (xy 133.559296 -224.258632) (xy 133.566916 -224.280476) (xy 133.575472 -224.306769)
			(xy 133.584665 -224.361289) (xy 133.585204 -224.388934) (xy 133.585204 -224.389442) (xy 133.866128 -224.389442)
			(xy 133.866636 -224.363555) (xy 133.874735 -224.312417) (xy 133.890734 -224.263177) (xy 133.91424 -224.217045)
			(xy 133.944672 -224.175158) (xy 133.981282 -224.138548) (xy 134.023169 -224.108116) (xy 134.069301 -224.08461)
			(xy 134.118541 -224.068611) (xy 134.169679 -224.060512) (xy 134.221453 -224.060512) (xy 134.272591 -224.068611)
			(xy 134.321831 -224.08461) (xy 134.367963 -224.108116) (xy 134.40985 -224.138548) (xy 134.44646 -224.175158)
			(xy 134.476892 -224.217045) (xy 134.500398 -224.263177) (xy 134.516397 -224.312417) (xy 134.524496 -224.363555)
			(xy 134.525004 -224.389442) (xy 134.524474 -224.41715) (xy 134.515275 -224.471796) (xy 134.506716 -224.498154)
			(xy 134.499096 -224.519998) (xy 134.615367 -224.72142) (xy 158.062168 -224.72142) (xy 158.062168 -224.31248)
			(xy 158.062604 -224.302329) (xy 158.070401 -224.283582) (xy 158.084792 -224.26926) (xy 158.103577 -224.261555)
			(xy 158.11373 -224.261172) (xy 159.51327 -224.261172) (xy 159.523399 -224.261652) (xy 159.542125 -224.269376)
			(xy 159.556484 -224.283665) (xy 159.564299 -224.302354) (xy 159.564832 -224.31248) (xy 159.564832 -224.72142)
			(xy 165.605968 -224.72142) (xy 165.605968 -224.31248) (xy 165.606404 -224.302329) (xy 165.614201 -224.283582)
			(xy 165.628592 -224.26926) (xy 165.647377 -224.261555) (xy 165.65753 -224.261172) (xy 167.05707 -224.261172)
			(xy 167.067199 -224.261652) (xy 167.085925 -224.269376) (xy 167.100284 -224.283665) (xy 167.108099 -224.302354)
			(xy 167.108632 -224.31248) (xy 167.108632 -224.72142) (xy 173.149768 -224.72142) (xy 173.149768 -224.31248)
			(xy 173.150204 -224.302329) (xy 173.158001 -224.283582) (xy 173.172392 -224.26926) (xy 173.191177 -224.261555)
			(xy 173.20133 -224.261172) (xy 174.60087 -224.261172) (xy 174.610999 -224.261652) (xy 174.629725 -224.269376)
			(xy 174.644084 -224.283665) (xy 174.651899 -224.302354) (xy 174.652432 -224.31248) (xy 174.652432 -224.72142)
			(xy 180.693568 -224.72142) (xy 180.693568 -224.31248) (xy 180.694004 -224.302329) (xy 180.701801 -224.283582)
			(xy 180.716192 -224.26926) (xy 180.734977 -224.261555) (xy 180.74513 -224.261172) (xy 182.14467 -224.261172)
			(xy 182.154799 -224.261652) (xy 182.173525 -224.269376) (xy 182.187884 -224.283665) (xy 182.195699 -224.302354)
			(xy 182.196232 -224.31248) (xy 182.196232 -224.72142) (xy 188.237368 -224.72142) (xy 188.237368 -224.31248)
			(xy 188.237804 -224.302329) (xy 188.245601 -224.283582) (xy 188.259992 -224.26926) (xy 188.278777 -224.261555)
			(xy 188.28893 -224.261172) (xy 189.68847 -224.261172) (xy 189.698599 -224.261652) (xy 189.717325 -224.269376)
			(xy 189.731684 -224.283665) (xy 189.739499 -224.302354) (xy 189.740032 -224.31248) (xy 189.740032 -224.72142)
			(xy 195.781168 -224.72142) (xy 195.781168 -224.31248) (xy 195.781604 -224.302329) (xy 195.789401 -224.283582)
			(xy 195.803792 -224.26926) (xy 195.822577 -224.261555) (xy 195.83273 -224.261172) (xy 197.23227 -224.261172)
			(xy 197.242399 -224.261652) (xy 197.261125 -224.269376) (xy 197.275484 -224.283665) (xy 197.283299 -224.302354)
			(xy 197.283832 -224.31248) (xy 197.283832 -224.72142) (xy 203.324968 -224.72142) (xy 203.324968 -224.31248)
			(xy 203.325404 -224.302329) (xy 203.333201 -224.283582) (xy 203.347592 -224.26926) (xy 203.366377 -224.261555)
			(xy 203.37653 -224.261172) (xy 204.77607 -224.261172) (xy 204.786199 -224.261652) (xy 204.804925 -224.269376)
			(xy 204.819284 -224.283665) (xy 204.827099 -224.302354) (xy 204.827632 -224.31248) (xy 204.827632 -224.72142)
			(xy 210.868768 -224.72142) (xy 210.868768 -224.31248) (xy 210.869204 -224.302329) (xy 210.877001 -224.283582)
			(xy 210.891392 -224.26926) (xy 210.910177 -224.261555) (xy 210.92033 -224.261172) (xy 212.31987 -224.261172)
			(xy 212.329999 -224.261652) (xy 212.348725 -224.269376) (xy 212.363084 -224.283665) (xy 212.370899 -224.302354)
			(xy 212.371432 -224.31248) (xy 212.371432 -224.72142) (xy 255.329436 -224.72142) (xy 255.329436 -224.31248)
			(xy 255.329806 -224.30232) (xy 255.337615 -224.28356) (xy 255.352028 -224.269236) (xy 255.370836 -224.261544)
			(xy 255.380998 -224.261172) (xy 256.780538 -224.261172) (xy 256.790671 -224.261596) (xy 256.809399 -224.269343)
			(xy 256.823755 -224.283648) (xy 256.831567 -224.302349) (xy 256.8321 -224.31248) (xy 256.8321 -224.72142)
			(xy 262.873236 -224.72142) (xy 262.873236 -224.31248) (xy 262.873606 -224.30232) (xy 262.881415 -224.28356)
			(xy 262.895828 -224.269236) (xy 262.914636 -224.261544) (xy 262.924798 -224.261172) (xy 264.324338 -224.261172)
			(xy 264.334471 -224.261596) (xy 264.353199 -224.269343) (xy 264.367555 -224.283648) (xy 264.375367 -224.302349)
			(xy 264.3759 -224.31248) (xy 264.3759 -224.72142) (xy 270.417036 -224.72142) (xy 270.417036 -224.31248)
			(xy 270.417406 -224.30232) (xy 270.425215 -224.28356) (xy 270.439628 -224.269236) (xy 270.458436 -224.261544)
			(xy 270.468598 -224.261172) (xy 271.868138 -224.261172) (xy 271.878271 -224.261596) (xy 271.896999 -224.269343)
			(xy 271.911355 -224.283648) (xy 271.919167 -224.302349) (xy 271.9197 -224.31248) (xy 271.9197 -224.72142)
			(xy 277.960836 -224.72142) (xy 277.960836 -224.31248) (xy 277.961206 -224.30232) (xy 277.969015 -224.28356)
			(xy 277.983428 -224.269236) (xy 278.002236 -224.261544) (xy 278.012398 -224.261172) (xy 279.411938 -224.261172)
			(xy 279.422071 -224.261596) (xy 279.440799 -224.269343) (xy 279.455155 -224.283648) (xy 279.462967 -224.302349)
			(xy 279.4635 -224.31248) (xy 279.4635 -224.72142) (xy 285.504636 -224.72142) (xy 285.504636 -224.31248)
			(xy 285.505006 -224.30232) (xy 285.512815 -224.28356) (xy 285.527228 -224.269236) (xy 285.546036 -224.261544)
			(xy 285.556198 -224.261172) (xy 286.955738 -224.261172) (xy 286.965871 -224.261596) (xy 286.984599 -224.269343)
			(xy 286.998955 -224.283648) (xy 287.006767 -224.302349) (xy 287.0073 -224.31248) (xy 287.0073 -224.72142)
			(xy 293.048436 -224.72142) (xy 293.048436 -224.31248) (xy 293.048806 -224.30232) (xy 293.056615 -224.28356)
			(xy 293.071028 -224.269236) (xy 293.089836 -224.261544) (xy 293.099998 -224.261172) (xy 294.499538 -224.261172)
			(xy 294.509671 -224.261596) (xy 294.528399 -224.269343) (xy 294.542755 -224.283648) (xy 294.550567 -224.302349)
			(xy 294.5511 -224.31248) (xy 294.5511 -224.72142) (xy 300.592236 -224.72142) (xy 300.592236 -224.31248)
			(xy 300.592606 -224.30232) (xy 300.600415 -224.28356) (xy 300.614828 -224.269236) (xy 300.633636 -224.261544)
			(xy 300.643798 -224.261172) (xy 302.043338 -224.261172) (xy 302.053471 -224.261596) (xy 302.072199 -224.269343)
			(xy 302.086555 -224.283648) (xy 302.094367 -224.302349) (xy 302.0949 -224.31248) (xy 302.0949 -224.72142)
			(xy 308.136036 -224.72142) (xy 308.136036 -224.31248) (xy 308.136406 -224.30232) (xy 308.144215 -224.28356)
			(xy 308.158628 -224.269236) (xy 308.177436 -224.261544) (xy 308.187598 -224.261172) (xy 309.587138 -224.261172)
			(xy 309.597271 -224.261596) (xy 309.615999 -224.269343) (xy 309.630355 -224.283648) (xy 309.638167 -224.302349)
			(xy 309.6387 -224.31248) (xy 309.6387 -224.389442) (xy 337.635596 -224.389442) (xy 337.636029 -224.364106)
			(xy 337.64379 -224.314032) (xy 337.65912 -224.265734) (xy 337.681659 -224.22035) (xy 337.710875 -224.178949)
			(xy 337.746081 -224.142504) (xy 337.786448 -224.111874) (xy 337.831026 -224.087781) (xy 337.878765 -224.070791)
			(xy 337.903566 -224.065592) (xy 337.926426 -224.061274) (xy 338.13115 -223.706182) (xy 338.12353 -223.684338)
			(xy 338.114887 -223.657995) (xy 338.105572 -223.603345) (xy 338.104988 -223.575626) (xy 338.105496 -223.549719)
			(xy 338.113602 -223.498542) (xy 338.129614 -223.449263) (xy 338.153137 -223.403096) (xy 338.183593 -223.361177)
			(xy 338.220231 -223.324539) (xy 338.26215 -223.294083) (xy 338.308317 -223.27056) (xy 338.357596 -223.254548)
			(xy 338.408773 -223.246442) (xy 338.460587 -223.246442) (xy 338.511764 -223.254548) (xy 338.561043 -223.27056)
			(xy 338.60721 -223.294083) (xy 338.649129 -223.324539) (xy 338.685767 -223.361177) (xy 338.716223 -223.403096)
			(xy 338.739746 -223.449263) (xy 338.755758 -223.498542) (xy 338.763864 -223.549719) (xy 338.764372 -223.575626)
			(xy 338.763897 -223.600971) (xy 338.756121 -223.651063) (xy 338.740771 -223.699374) (xy 338.718208 -223.744767)
			(xy 338.688966 -223.786173) (xy 338.653731 -223.822617) (xy 338.613335 -223.853239) (xy 338.568728 -223.877319)
			(xy 338.520962 -223.89429) (xy 338.496148 -223.899476) (xy 338.473288 -223.903794) (xy 338.268564 -224.258632)
			(xy 338.276184 -224.280476) (xy 338.284739 -224.306769) (xy 338.293932 -224.361289) (xy 338.294472 -224.388934)
			(xy 338.294472 -224.389442) (xy 338.575396 -224.389442) (xy 338.575904 -224.363555) (xy 338.584003 -224.312417)
			(xy 338.600002 -224.263177) (xy 338.623508 -224.217045) (xy 338.65394 -224.175158) (xy 338.69055 -224.138548)
			(xy 338.732437 -224.108116) (xy 338.778569 -224.08461) (xy 338.827809 -224.068611) (xy 338.878947 -224.060512)
			(xy 338.930721 -224.060512) (xy 338.981859 -224.068611) (xy 339.031099 -224.08461) (xy 339.077231 -224.108116)
			(xy 339.119118 -224.138548) (xy 339.155728 -224.175158) (xy 339.18616 -224.217045) (xy 339.209666 -224.263177)
			(xy 339.225665 -224.312417) (xy 339.233764 -224.363555) (xy 339.234272 -224.389442) (xy 340.454996 -224.389442)
			(xy 340.455504 -224.363555) (xy 340.463603 -224.312417) (xy 340.479602 -224.263177) (xy 340.503108 -224.217045)
			(xy 340.53354 -224.175158) (xy 340.57015 -224.138548) (xy 340.612037 -224.108116) (xy 340.658169 -224.08461)
			(xy 340.707409 -224.068611) (xy 340.758547 -224.060512) (xy 340.810321 -224.060512) (xy 340.861459 -224.068611)
			(xy 340.910699 -224.08461) (xy 340.956831 -224.108116) (xy 340.998718 -224.138548) (xy 341.035328 -224.175158)
			(xy 341.06576 -224.217045) (xy 341.089266 -224.263177) (xy 341.105265 -224.312417) (xy 341.113364 -224.363555)
			(xy 341.113872 -224.389442) (xy 341.394796 -224.389442) (xy 341.395229 -224.364106) (xy 341.40299 -224.314032)
			(xy 341.41832 -224.265734) (xy 341.440859 -224.22035) (xy 341.470075 -224.178949) (xy 341.505281 -224.142504)
			(xy 341.545648 -224.111874) (xy 341.590226 -224.087781) (xy 341.637965 -224.070791) (xy 341.662766 -224.065592)
			(xy 341.685626 -224.061274) (xy 341.89035 -223.706436) (xy 341.88273 -223.684338) (xy 341.874102 -223.657991)
			(xy 341.864779 -223.603344) (xy 341.864188 -223.575626) (xy 341.864696 -223.549719) (xy 341.872802 -223.498542)
			(xy 341.888814 -223.449263) (xy 341.912337 -223.403096) (xy 341.942793 -223.361177) (xy 341.979431 -223.324539)
			(xy 342.02135 -223.294083) (xy 342.067517 -223.27056) (xy 342.116796 -223.254548) (xy 342.167973 -223.246442)
			(xy 342.219787 -223.246442) (xy 342.270964 -223.254548) (xy 342.320243 -223.27056) (xy 342.36641 -223.294083)
			(xy 342.408329 -223.324539) (xy 342.444967 -223.361177) (xy 342.475423 -223.403096) (xy 342.498946 -223.449263)
			(xy 342.514958 -223.498542) (xy 342.523064 -223.549719) (xy 342.523572 -223.575626) (xy 342.523181 -223.600993)
			(xy 342.515428 -223.651131) (xy 342.500077 -223.699486) (xy 342.477492 -223.744915) (xy 342.448207 -223.786344)
			(xy 342.412916 -223.822791) (xy 342.372452 -223.853396) (xy 342.327774 -223.877433) (xy 342.279939 -223.894334)
			(xy 342.255094 -223.899476) (xy 342.232234 -223.903794) (xy 342.02751 -224.258632) (xy 342.035384 -224.280476)
			(xy 342.043957 -224.306897) (xy 342.053158 -224.36167) (xy 342.053672 -224.389442) (xy 342.334596 -224.389442)
			(xy 342.335104 -224.363555) (xy 342.343203 -224.312417) (xy 342.359202 -224.263177) (xy 342.382708 -224.217045)
			(xy 342.41314 -224.175158) (xy 342.44975 -224.138548) (xy 342.491637 -224.108116) (xy 342.537769 -224.08461)
			(xy 342.587009 -224.068611) (xy 342.638147 -224.060512) (xy 342.689921 -224.060512) (xy 342.741059 -224.068611)
			(xy 342.790299 -224.08461) (xy 342.836431 -224.108116) (xy 342.878318 -224.138548) (xy 342.914928 -224.175158)
			(xy 342.94536 -224.217045) (xy 342.968866 -224.263177) (xy 342.984865 -224.312417) (xy 342.992964 -224.363555)
			(xy 342.993472 -224.389442) (xy 343.274396 -224.389442) (xy 343.274829 -224.364106) (xy 343.28259 -224.314032)
			(xy 343.29792 -224.265734) (xy 343.320459 -224.22035) (xy 343.349675 -224.178949) (xy 343.384881 -224.142504)
			(xy 343.425248 -224.111874) (xy 343.469826 -224.087781) (xy 343.517565 -224.070791) (xy 343.542366 -224.065592)
			(xy 343.565226 -224.061274) (xy 343.76995 -223.706436) (xy 343.76233 -223.684338) (xy 343.753702 -223.657991)
			(xy 343.744379 -223.603344) (xy 343.743788 -223.575626) (xy 343.744296 -223.549719) (xy 343.752402 -223.498542)
			(xy 343.768414 -223.449263) (xy 343.791937 -223.403096) (xy 343.822393 -223.361177) (xy 343.859031 -223.324539)
			(xy 343.90095 -223.294083) (xy 343.947117 -223.27056) (xy 343.996396 -223.254548) (xy 344.047573 -223.246442)
			(xy 344.099387 -223.246442) (xy 344.150564 -223.254548) (xy 344.199843 -223.27056) (xy 344.24601 -223.294083)
			(xy 344.287929 -223.324539) (xy 344.324567 -223.361177) (xy 344.355023 -223.403096) (xy 344.378546 -223.449263)
			(xy 344.394558 -223.498542) (xy 344.402664 -223.549719) (xy 344.403172 -223.575626) (xy 344.402781 -223.600993)
			(xy 344.395028 -223.651131) (xy 344.379677 -223.699486) (xy 344.357092 -223.744915) (xy 344.327807 -223.786344)
			(xy 344.292516 -223.822791) (xy 344.252052 -223.853396) (xy 344.207374 -223.877433) (xy 344.159539 -223.894334)
			(xy 344.134694 -223.899476) (xy 344.111834 -223.903794) (xy 343.90711 -224.258632) (xy 343.914984 -224.280476)
			(xy 343.923557 -224.306897) (xy 343.932758 -224.36167) (xy 343.933272 -224.389442) (xy 344.214196 -224.389442)
			(xy 344.214704 -224.363555) (xy 344.222803 -224.312417) (xy 344.238802 -224.263177) (xy 344.262308 -224.217045)
			(xy 344.29274 -224.175158) (xy 344.32935 -224.138548) (xy 344.371237 -224.108116) (xy 344.417369 -224.08461)
			(xy 344.466609 -224.068611) (xy 344.517747 -224.060512) (xy 344.569521 -224.060512) (xy 344.620659 -224.068611)
			(xy 344.669899 -224.08461) (xy 344.716031 -224.108116) (xy 344.757918 -224.138548) (xy 344.794528 -224.175158)
			(xy 344.82496 -224.217045) (xy 344.848466 -224.263177) (xy 344.864465 -224.312417) (xy 344.872564 -224.363555)
			(xy 344.873072 -224.389442) (xy 345.153996 -224.389442) (xy 345.154429 -224.364106) (xy 345.16219 -224.314032)
			(xy 345.17752 -224.265734) (xy 345.200059 -224.22035) (xy 345.229275 -224.178949) (xy 345.264481 -224.142504)
			(xy 345.304848 -224.111874) (xy 345.349426 -224.087781) (xy 345.397165 -224.070791) (xy 345.421966 -224.065592)
			(xy 345.444826 -224.061274) (xy 345.64955 -223.706436) (xy 345.64193 -223.684338) (xy 345.633302 -223.657991)
			(xy 345.623979 -223.603344) (xy 345.623388 -223.575626) (xy 345.623896 -223.549719) (xy 345.632002 -223.498542)
			(xy 345.648014 -223.449263) (xy 345.671537 -223.403096) (xy 345.701993 -223.361177) (xy 345.738631 -223.324539)
			(xy 345.78055 -223.294083) (xy 345.826717 -223.27056) (xy 345.875996 -223.254548) (xy 345.927173 -223.246442)
			(xy 345.978987 -223.246442) (xy 346.030164 -223.254548) (xy 346.079443 -223.27056) (xy 346.12561 -223.294083)
			(xy 346.167529 -223.324539) (xy 346.204167 -223.361177) (xy 346.234623 -223.403096) (xy 346.258146 -223.449263)
			(xy 346.274158 -223.498542) (xy 346.282264 -223.549719) (xy 346.282772 -223.575626) (xy 346.282381 -223.600993)
			(xy 346.274628 -223.651131) (xy 346.259277 -223.699486) (xy 346.236692 -223.744915) (xy 346.207407 -223.786344)
			(xy 346.172116 -223.822791) (xy 346.131652 -223.853396) (xy 346.086974 -223.877433) (xy 346.039139 -223.894334)
			(xy 346.014294 -223.899476) (xy 345.991434 -223.903794) (xy 345.78671 -224.258632) (xy 345.794584 -224.280476)
			(xy 345.803157 -224.306897) (xy 345.812358 -224.36167) (xy 345.812872 -224.389442) (xy 346.093796 -224.389442)
			(xy 346.094304 -224.363555) (xy 346.102403 -224.312417) (xy 346.118402 -224.263177) (xy 346.141908 -224.217045)
			(xy 346.17234 -224.175158) (xy 346.20895 -224.138548) (xy 346.250837 -224.108116) (xy 346.296969 -224.08461)
			(xy 346.346209 -224.068611) (xy 346.397347 -224.060512) (xy 346.449121 -224.060512) (xy 346.500259 -224.068611)
			(xy 346.549499 -224.08461) (xy 346.595631 -224.108116) (xy 346.637518 -224.138548) (xy 346.674128 -224.175158)
			(xy 346.70456 -224.217045) (xy 346.728066 -224.263177) (xy 346.744065 -224.312417) (xy 346.752164 -224.363555)
			(xy 346.752672 -224.389442) (xy 347.033596 -224.389442) (xy 347.034029 -224.364106) (xy 347.04179 -224.314032)
			(xy 347.05712 -224.265734) (xy 347.079659 -224.22035) (xy 347.108875 -224.178949) (xy 347.144081 -224.142504)
			(xy 347.184448 -224.111874) (xy 347.229026 -224.087781) (xy 347.276765 -224.070791) (xy 347.301566 -224.065592)
			(xy 347.324426 -224.061274) (xy 347.52915 -223.706436) (xy 347.52153 -223.684338) (xy 347.512902 -223.657991)
			(xy 347.503579 -223.603344) (xy 347.502988 -223.575626) (xy 347.503496 -223.549719) (xy 347.511602 -223.498542)
			(xy 347.527614 -223.449263) (xy 347.551137 -223.403096) (xy 347.581593 -223.361177) (xy 347.618231 -223.324539)
			(xy 347.66015 -223.294083) (xy 347.706317 -223.27056) (xy 347.755596 -223.254548) (xy 347.806773 -223.246442)
			(xy 347.858587 -223.246442) (xy 347.909764 -223.254548) (xy 347.959043 -223.27056) (xy 348.00521 -223.294083)
			(xy 348.047129 -223.324539) (xy 348.083767 -223.361177) (xy 348.114223 -223.403096) (xy 348.137746 -223.449263)
			(xy 348.153758 -223.498542) (xy 348.161864 -223.549719) (xy 348.162372 -223.575626) (xy 348.161981 -223.600993)
			(xy 348.154228 -223.651131) (xy 348.138877 -223.699486) (xy 348.116292 -223.744915) (xy 348.087007 -223.786344)
			(xy 348.051716 -223.822791) (xy 348.011252 -223.853396) (xy 347.966574 -223.877433) (xy 347.918739 -223.894334)
			(xy 347.893894 -223.899476) (xy 347.871034 -223.903794) (xy 347.66631 -224.258632) (xy 347.674184 -224.280476)
			(xy 347.682757 -224.306897) (xy 347.691958 -224.36167) (xy 347.692472 -224.389442) (xy 347.973396 -224.389442)
			(xy 347.973904 -224.363555) (xy 347.982003 -224.312417) (xy 347.998002 -224.263177) (xy 348.021508 -224.217045)
			(xy 348.05194 -224.175158) (xy 348.08855 -224.138548) (xy 348.130437 -224.108116) (xy 348.176569 -224.08461)
			(xy 348.225809 -224.068611) (xy 348.276947 -224.060512) (xy 348.328721 -224.060512) (xy 348.379859 -224.068611)
			(xy 348.429099 -224.08461) (xy 348.475231 -224.108116) (xy 348.517118 -224.138548) (xy 348.553728 -224.175158)
			(xy 348.58416 -224.217045) (xy 348.607666 -224.263177) (xy 348.623665 -224.312417) (xy 348.631764 -224.363555)
			(xy 348.632272 -224.389442) (xy 348.913196 -224.389442) (xy 348.913629 -224.364106) (xy 348.92139 -224.314032)
			(xy 348.93672 -224.265734) (xy 348.959259 -224.22035) (xy 348.988475 -224.178949) (xy 349.023681 -224.142504)
			(xy 349.064048 -224.111874) (xy 349.108626 -224.087781) (xy 349.156365 -224.070791) (xy 349.181166 -224.065592)
			(xy 349.204026 -224.061274) (xy 349.40875 -223.706436) (xy 349.40113 -223.684338) (xy 349.392502 -223.657991)
			(xy 349.383179 -223.603344) (xy 349.382588 -223.575626) (xy 349.383096 -223.549719) (xy 349.391202 -223.498542)
			(xy 349.407214 -223.449263) (xy 349.430737 -223.403096) (xy 349.461193 -223.361177) (xy 349.497831 -223.324539)
			(xy 349.53975 -223.294083) (xy 349.585917 -223.27056) (xy 349.635196 -223.254548) (xy 349.686373 -223.246442)
			(xy 349.738187 -223.246442) (xy 349.789364 -223.254548) (xy 349.838643 -223.27056) (xy 349.88481 -223.294083)
			(xy 349.926729 -223.324539) (xy 349.963367 -223.361177) (xy 349.993823 -223.403096) (xy 350.017346 -223.449263)
			(xy 350.033358 -223.498542) (xy 350.041464 -223.549719) (xy 350.041972 -223.575626) (xy 350.041581 -223.600993)
			(xy 350.033828 -223.651131) (xy 350.018477 -223.699486) (xy 349.995892 -223.744915) (xy 349.966607 -223.786344)
			(xy 349.931316 -223.822791) (xy 349.890852 -223.853396) (xy 349.846174 -223.877433) (xy 349.798339 -223.894334)
			(xy 349.773494 -223.899476) (xy 349.750634 -223.903794) (xy 349.54591 -224.258632) (xy 349.553784 -224.280476)
			(xy 349.562357 -224.306897) (xy 349.571558 -224.36167) (xy 349.572072 -224.389442) (xy 349.852996 -224.389442)
			(xy 349.853504 -224.363555) (xy 349.861603 -224.312417) (xy 349.877602 -224.263177) (xy 349.901108 -224.217045)
			(xy 349.93154 -224.175158) (xy 349.96815 -224.138548) (xy 350.010037 -224.108116) (xy 350.056169 -224.08461)
			(xy 350.105409 -224.068611) (xy 350.156547 -224.060512) (xy 350.208321 -224.060512) (xy 350.259459 -224.068611)
			(xy 350.308699 -224.08461) (xy 350.354831 -224.108116) (xy 350.396718 -224.138548) (xy 350.433328 -224.175158)
			(xy 350.46376 -224.217045) (xy 350.487266 -224.263177) (xy 350.503265 -224.312417) (xy 350.511364 -224.363555)
			(xy 350.511872 -224.389442) (xy 350.792796 -224.389442) (xy 350.793229 -224.364106) (xy 350.80099 -224.314032)
			(xy 350.81632 -224.265734) (xy 350.838859 -224.22035) (xy 350.868075 -224.178949) (xy 350.903281 -224.142504)
			(xy 350.943648 -224.111874) (xy 350.988226 -224.087781) (xy 351.035965 -224.070791) (xy 351.060766 -224.065592)
			(xy 351.083626 -224.061274) (xy 351.28835 -223.706436) (xy 351.28073 -223.684338) (xy 351.272102 -223.657991)
			(xy 351.262779 -223.603344) (xy 351.262188 -223.575626) (xy 351.262696 -223.549719) (xy 351.270802 -223.498542)
			(xy 351.286814 -223.449263) (xy 351.310337 -223.403096) (xy 351.340793 -223.361177) (xy 351.377431 -223.324539)
			(xy 351.41935 -223.294083) (xy 351.465517 -223.27056) (xy 351.514796 -223.254548) (xy 351.565973 -223.246442)
			(xy 351.617787 -223.246442) (xy 351.668964 -223.254548) (xy 351.718243 -223.27056) (xy 351.76441 -223.294083)
			(xy 351.806329 -223.324539) (xy 351.842967 -223.361177) (xy 351.873423 -223.403096) (xy 351.896946 -223.449263)
			(xy 351.912958 -223.498542) (xy 351.921064 -223.549719) (xy 351.921572 -223.575626) (xy 351.921181 -223.600993)
			(xy 351.913428 -223.651131) (xy 351.898077 -223.699486) (xy 351.875492 -223.744915) (xy 351.846207 -223.786344)
			(xy 351.810916 -223.822791) (xy 351.770452 -223.853396) (xy 351.725774 -223.877433) (xy 351.677939 -223.894334)
			(xy 351.653094 -223.899476) (xy 351.630234 -223.903794) (xy 351.42551 -224.258632) (xy 351.433384 -224.280476)
			(xy 351.441957 -224.306897) (xy 351.451158 -224.36167) (xy 351.451672 -224.389442) (xy 351.732596 -224.389442)
			(xy 351.733104 -224.363555) (xy 351.741203 -224.312417) (xy 351.757202 -224.263177) (xy 351.780708 -224.217045)
			(xy 351.81114 -224.175158) (xy 351.84775 -224.138548) (xy 351.889637 -224.108116) (xy 351.935769 -224.08461)
			(xy 351.985009 -224.068611) (xy 352.036147 -224.060512) (xy 352.087921 -224.060512) (xy 352.139059 -224.068611)
			(xy 352.188299 -224.08461) (xy 352.234431 -224.108116) (xy 352.276318 -224.138548) (xy 352.312928 -224.175158)
			(xy 352.34336 -224.217045) (xy 352.366866 -224.263177) (xy 352.382865 -224.312417) (xy 352.390964 -224.363555)
			(xy 352.391472 -224.389442) (xy 352.672396 -224.389442) (xy 352.672829 -224.364106) (xy 352.68059 -224.314032)
			(xy 352.69592 -224.265734) (xy 352.718459 -224.22035) (xy 352.747675 -224.178949) (xy 352.782881 -224.142504)
			(xy 352.823248 -224.111874) (xy 352.867826 -224.087781) (xy 352.915565 -224.070791) (xy 352.940366 -224.065592)
			(xy 352.963226 -224.061274) (xy 353.16795 -223.706436) (xy 353.16033 -223.684338) (xy 353.151702 -223.657991)
			(xy 353.142379 -223.603344) (xy 353.141788 -223.575626) (xy 353.142296 -223.549719) (xy 353.150402 -223.498542)
			(xy 353.166414 -223.449263) (xy 353.189937 -223.403096) (xy 353.220393 -223.361177) (xy 353.257031 -223.324539)
			(xy 353.29895 -223.294083) (xy 353.345117 -223.27056) (xy 353.394396 -223.254548) (xy 353.445573 -223.246442)
			(xy 353.497387 -223.246442) (xy 353.548564 -223.254548) (xy 353.597843 -223.27056) (xy 353.64401 -223.294083)
			(xy 353.685929 -223.324539) (xy 353.722567 -223.361177) (xy 353.753023 -223.403096) (xy 353.776546 -223.449263)
			(xy 353.792558 -223.498542) (xy 353.800664 -223.549719) (xy 353.801172 -223.575626) (xy 353.800781 -223.600993)
			(xy 353.793028 -223.651131) (xy 353.777677 -223.699486) (xy 353.755092 -223.744915) (xy 353.725807 -223.786344)
			(xy 353.690516 -223.822791) (xy 353.650052 -223.853396) (xy 353.605374 -223.877433) (xy 353.557539 -223.894334)
			(xy 353.532694 -223.899476) (xy 353.509834 -223.903794) (xy 353.30511 -224.258632) (xy 353.312984 -224.280476)
			(xy 353.321557 -224.306897) (xy 353.330758 -224.36167) (xy 353.331272 -224.389442) (xy 353.612196 -224.389442)
			(xy 353.612704 -224.363555) (xy 353.620803 -224.312417) (xy 353.636802 -224.263177) (xy 353.660308 -224.217045)
			(xy 353.69074 -224.175158) (xy 353.72735 -224.138548) (xy 353.769237 -224.108116) (xy 353.815369 -224.08461)
			(xy 353.864609 -224.068611) (xy 353.915747 -224.060512) (xy 353.967521 -224.060512) (xy 354.018659 -224.068611)
			(xy 354.067899 -224.08461) (xy 354.114031 -224.108116) (xy 354.155918 -224.138548) (xy 354.192528 -224.175158)
			(xy 354.22296 -224.217045) (xy 354.246466 -224.263177) (xy 354.262465 -224.312417) (xy 354.270564 -224.363555)
			(xy 354.271072 -224.389442) (xy 354.551996 -224.389442) (xy 354.552429 -224.364106) (xy 354.56019 -224.314032)
			(xy 354.57552 -224.265734) (xy 354.598059 -224.22035) (xy 354.627275 -224.178949) (xy 354.662481 -224.142504)
			(xy 354.702848 -224.111874) (xy 354.747426 -224.087781) (xy 354.795165 -224.070791) (xy 354.819966 -224.065592)
			(xy 354.842826 -224.061274) (xy 355.04755 -223.706436) (xy 355.03993 -223.684338) (xy 355.031302 -223.657991)
			(xy 355.021979 -223.603344) (xy 355.021388 -223.575626) (xy 355.021896 -223.549719) (xy 355.030002 -223.498542)
			(xy 355.046014 -223.449263) (xy 355.069537 -223.403096) (xy 355.099993 -223.361177) (xy 355.136631 -223.324539)
			(xy 355.17855 -223.294083) (xy 355.224717 -223.27056) (xy 355.273996 -223.254548) (xy 355.325173 -223.246442)
			(xy 355.376987 -223.246442) (xy 355.428164 -223.254548) (xy 355.477443 -223.27056) (xy 355.52361 -223.294083)
			(xy 355.565529 -223.324539) (xy 355.602167 -223.361177) (xy 355.632623 -223.403096) (xy 355.656146 -223.449263)
			(xy 355.672158 -223.498542) (xy 355.680264 -223.549719) (xy 355.680772 -223.575626) (xy 355.680381 -223.600993)
			(xy 355.672628 -223.651131) (xy 355.657277 -223.699486) (xy 355.634692 -223.744915) (xy 355.605407 -223.786344)
			(xy 355.570116 -223.822791) (xy 355.529652 -223.853396) (xy 355.484974 -223.877433) (xy 355.437139 -223.894334)
			(xy 355.412294 -223.899476) (xy 355.389434 -223.903794) (xy 355.18471 -224.258632) (xy 355.192584 -224.280476)
			(xy 355.201157 -224.306897) (xy 355.210358 -224.36167) (xy 355.210872 -224.389442) (xy 355.491796 -224.389442)
			(xy 355.492304 -224.363555) (xy 355.500403 -224.312417) (xy 355.516402 -224.263177) (xy 355.539908 -224.217045)
			(xy 355.57034 -224.175158) (xy 355.60695 -224.138548) (xy 355.648837 -224.108116) (xy 355.694969 -224.08461)
			(xy 355.744209 -224.068611) (xy 355.795347 -224.060512) (xy 355.847121 -224.060512) (xy 355.898259 -224.068611)
			(xy 355.947499 -224.08461) (xy 355.993631 -224.108116) (xy 356.035518 -224.138548) (xy 356.072128 -224.175158)
			(xy 356.10256 -224.217045) (xy 356.126066 -224.263177) (xy 356.142065 -224.312417) (xy 356.150164 -224.363555)
			(xy 356.150672 -224.389442) (xy 356.431596 -224.389442) (xy 356.432029 -224.364106) (xy 356.43979 -224.314032)
			(xy 356.45512 -224.265734) (xy 356.477659 -224.22035) (xy 356.506875 -224.178949) (xy 356.542081 -224.142504)
			(xy 356.582448 -224.111874) (xy 356.627026 -224.087781) (xy 356.674765 -224.070791) (xy 356.699566 -224.065592)
			(xy 356.722426 -224.061274) (xy 356.92715 -223.706436) (xy 356.91953 -223.684338) (xy 356.910902 -223.657991)
			(xy 356.901579 -223.603344) (xy 356.900988 -223.575626) (xy 356.901496 -223.549719) (xy 356.909602 -223.498542)
			(xy 356.925614 -223.449263) (xy 356.949137 -223.403096) (xy 356.979593 -223.361177) (xy 357.016231 -223.324539)
			(xy 357.05815 -223.294083) (xy 357.104317 -223.27056) (xy 357.153596 -223.254548) (xy 357.204773 -223.246442)
			(xy 357.256587 -223.246442) (xy 357.307764 -223.254548) (xy 357.357043 -223.27056) (xy 357.40321 -223.294083)
			(xy 357.445129 -223.324539) (xy 357.481767 -223.361177) (xy 357.512223 -223.403096) (xy 357.535746 -223.449263)
			(xy 357.551758 -223.498542) (xy 357.559864 -223.549719) (xy 357.560372 -223.575626) (xy 357.559981 -223.600993)
			(xy 357.552228 -223.651131) (xy 357.536877 -223.699486) (xy 357.514292 -223.744915) (xy 357.485007 -223.786344)
			(xy 357.449716 -223.822791) (xy 357.409252 -223.853396) (xy 357.364574 -223.877433) (xy 357.316739 -223.894334)
			(xy 357.291894 -223.899476) (xy 357.269034 -223.903794) (xy 357.06431 -224.258632) (xy 357.072184 -224.280476)
			(xy 357.080757 -224.306897) (xy 357.089958 -224.36167) (xy 357.090472 -224.389442) (xy 357.371396 -224.389442)
			(xy 357.371904 -224.363555) (xy 357.380003 -224.312417) (xy 357.396002 -224.263177) (xy 357.419508 -224.217045)
			(xy 357.44994 -224.175158) (xy 357.48655 -224.138548) (xy 357.528437 -224.108116) (xy 357.574569 -224.08461)
			(xy 357.623809 -224.068611) (xy 357.674947 -224.060512) (xy 357.726721 -224.060512) (xy 357.777859 -224.068611)
			(xy 357.827099 -224.08461) (xy 357.873231 -224.108116) (xy 357.915118 -224.138548) (xy 357.951728 -224.175158)
			(xy 357.98216 -224.217045) (xy 358.005666 -224.263177) (xy 358.021665 -224.312417) (xy 358.029764 -224.363555)
			(xy 358.030272 -224.389442) (xy 358.311196 -224.389442) (xy 358.311629 -224.364106) (xy 358.31939 -224.314032)
			(xy 358.33472 -224.265734) (xy 358.357259 -224.22035) (xy 358.386475 -224.178949) (xy 358.421681 -224.142504)
			(xy 358.462048 -224.111874) (xy 358.506626 -224.087781) (xy 358.554365 -224.070791) (xy 358.579166 -224.065592)
			(xy 358.602026 -224.061274) (xy 358.80675 -223.706436) (xy 358.79913 -223.684338) (xy 358.790502 -223.657991)
			(xy 358.781179 -223.603344) (xy 358.780588 -223.575626) (xy 358.781096 -223.549719) (xy 358.789202 -223.498542)
			(xy 358.805214 -223.449263) (xy 358.828737 -223.403096) (xy 358.859193 -223.361177) (xy 358.895831 -223.324539)
			(xy 358.93775 -223.294083) (xy 358.983917 -223.27056) (xy 359.033196 -223.254548) (xy 359.084373 -223.246442)
			(xy 359.136187 -223.246442) (xy 359.187364 -223.254548) (xy 359.236643 -223.27056) (xy 359.28281 -223.294083)
			(xy 359.324729 -223.324539) (xy 359.361367 -223.361177) (xy 359.391823 -223.403096) (xy 359.415346 -223.449263)
			(xy 359.431358 -223.498542) (xy 359.439464 -223.549719) (xy 359.439972 -223.575626) (xy 359.439581 -223.600993)
			(xy 359.431828 -223.651131) (xy 359.416477 -223.699486) (xy 359.393892 -223.744915) (xy 359.364607 -223.786344)
			(xy 359.329316 -223.822791) (xy 359.288852 -223.853396) (xy 359.244174 -223.877433) (xy 359.196339 -223.894334)
			(xy 359.171494 -223.899476) (xy 359.148634 -223.903794) (xy 358.94391 -224.258632) (xy 358.951784 -224.280476)
			(xy 358.960357 -224.306897) (xy 358.969558 -224.36167) (xy 358.970072 -224.389442) (xy 359.250996 -224.389442)
			(xy 359.251504 -224.363555) (xy 359.259603 -224.312417) (xy 359.275602 -224.263177) (xy 359.299108 -224.217045)
			(xy 359.32954 -224.175158) (xy 359.36615 -224.138548) (xy 359.408037 -224.108116) (xy 359.454169 -224.08461)
			(xy 359.503409 -224.068611) (xy 359.554547 -224.060512) (xy 359.606321 -224.060512) (xy 359.657459 -224.068611)
			(xy 359.706699 -224.08461) (xy 359.752831 -224.108116) (xy 359.794718 -224.138548) (xy 359.831328 -224.175158)
			(xy 359.86176 -224.217045) (xy 359.885266 -224.263177) (xy 359.901265 -224.312417) (xy 359.909364 -224.363555)
			(xy 359.909872 -224.389442) (xy 360.190796 -224.389442) (xy 360.191229 -224.364106) (xy 360.19899 -224.314032)
			(xy 360.21432 -224.265734) (xy 360.236859 -224.22035) (xy 360.266075 -224.178949) (xy 360.301281 -224.142504)
			(xy 360.341648 -224.111874) (xy 360.386226 -224.087781) (xy 360.433965 -224.070791) (xy 360.458766 -224.065592)
			(xy 360.481626 -224.061274) (xy 360.68635 -223.706436) (xy 360.67873 -223.684338) (xy 360.670102 -223.657991)
			(xy 360.660779 -223.603344) (xy 360.660188 -223.575626) (xy 360.660696 -223.549719) (xy 360.668802 -223.498542)
			(xy 360.684814 -223.449263) (xy 360.708337 -223.403096) (xy 360.738793 -223.361177) (xy 360.775431 -223.324539)
			(xy 360.81735 -223.294083) (xy 360.863517 -223.27056) (xy 360.912796 -223.254548) (xy 360.963973 -223.246442)
			(xy 361.015787 -223.246442) (xy 361.066964 -223.254548) (xy 361.116243 -223.27056) (xy 361.16241 -223.294083)
			(xy 361.204329 -223.324539) (xy 361.240967 -223.361177) (xy 361.271423 -223.403096) (xy 361.294946 -223.449263)
			(xy 361.310958 -223.498542) (xy 361.319064 -223.549719) (xy 361.319572 -223.575626) (xy 361.319181 -223.600993)
			(xy 361.311428 -223.651131) (xy 361.296077 -223.699486) (xy 361.273492 -223.744915) (xy 361.244207 -223.786344)
			(xy 361.208916 -223.822791) (xy 361.168452 -223.853396) (xy 361.123774 -223.877433) (xy 361.075939 -223.894334)
			(xy 361.051094 -223.899476) (xy 361.028234 -223.903794) (xy 360.82351 -224.258632) (xy 360.831384 -224.280476)
			(xy 360.839957 -224.306897) (xy 360.849158 -224.36167) (xy 360.849672 -224.389442) (xy 361.130596 -224.389442)
			(xy 361.131104 -224.363555) (xy 361.139203 -224.312417) (xy 361.155202 -224.263177) (xy 361.178708 -224.217045)
			(xy 361.20914 -224.175158) (xy 361.24575 -224.138548) (xy 361.287637 -224.108116) (xy 361.333769 -224.08461)
			(xy 361.383009 -224.068611) (xy 361.434147 -224.060512) (xy 361.485921 -224.060512) (xy 361.537059 -224.068611)
			(xy 361.586299 -224.08461) (xy 361.632431 -224.108116) (xy 361.674318 -224.138548) (xy 361.710928 -224.175158)
			(xy 361.74136 -224.217045) (xy 361.764866 -224.263177) (xy 361.780865 -224.312417) (xy 361.788964 -224.363555)
			(xy 361.789472 -224.389442) (xy 362.070396 -224.389442) (xy 362.070829 -224.364106) (xy 362.07859 -224.314032)
			(xy 362.09392 -224.265734) (xy 362.116459 -224.22035) (xy 362.145675 -224.178949) (xy 362.180881 -224.142504)
			(xy 362.221248 -224.111874) (xy 362.265826 -224.087781) (xy 362.313565 -224.070791) (xy 362.338366 -224.065592)
			(xy 362.361226 -224.061274) (xy 362.566204 -223.706182) (xy 362.558584 -223.684084) (xy 362.550064 -223.657913)
			(xy 362.540871 -223.603651) (xy 362.540296 -223.576134) (xy 362.540296 -223.575626) (xy 362.540804 -223.549739)
			(xy 362.548903 -223.498601) (xy 362.564902 -223.449361) (xy 362.588408 -223.403229) (xy 362.61884 -223.361342)
			(xy 362.65545 -223.324732) (xy 362.697337 -223.2943) (xy 362.743469 -223.270794) (xy 362.792709 -223.254795)
			(xy 362.843847 -223.246696) (xy 362.895621 -223.246696) (xy 362.946759 -223.254795) (xy 362.995999 -223.270794)
			(xy 363.042131 -223.2943) (xy 363.084018 -223.324732) (xy 363.120628 -223.361342) (xy 363.15106 -223.403229)
			(xy 363.174566 -223.449361) (xy 363.190565 -223.498601) (xy 363.198664 -223.549739) (xy 363.199172 -223.575626)
			(xy 363.198781 -223.600993) (xy 363.191028 -223.651131) (xy 363.175677 -223.699486) (xy 363.153092 -223.744915)
			(xy 363.123807 -223.786344) (xy 363.088516 -223.822791) (xy 363.048052 -223.853396) (xy 363.003374 -223.877433)
			(xy 362.955539 -223.894334) (xy 362.930694 -223.899476) (xy 362.907834 -223.903794) (xy 362.70311 -224.258632)
			(xy 362.710984 -224.280476) (xy 362.719557 -224.306897) (xy 362.728758 -224.36167) (xy 362.729272 -224.389442)
			(xy 363.010196 -224.389442) (xy 363.010704 -224.363555) (xy 363.018803 -224.312417) (xy 363.034802 -224.263177)
			(xy 363.058308 -224.217045) (xy 363.08874 -224.175158) (xy 363.12535 -224.138548) (xy 363.167237 -224.108116)
			(xy 363.213369 -224.08461) (xy 363.262609 -224.068611) (xy 363.313747 -224.060512) (xy 363.365521 -224.060512)
			(xy 363.416659 -224.068611) (xy 363.465899 -224.08461) (xy 363.512031 -224.108116) (xy 363.553918 -224.138548)
			(xy 363.590528 -224.175158) (xy 363.62096 -224.217045) (xy 363.644466 -224.263177) (xy 363.660465 -224.312417)
			(xy 363.668564 -224.363555) (xy 363.669072 -224.389442) (xy 363.949996 -224.389442) (xy 363.950429 -224.364106)
			(xy 363.95819 -224.314032) (xy 363.97352 -224.265734) (xy 363.996059 -224.22035) (xy 364.025275 -224.178949)
			(xy 364.060481 -224.142504) (xy 364.100848 -224.111874) (xy 364.145426 -224.087781) (xy 364.193165 -224.070791)
			(xy 364.217966 -224.065592) (xy 364.240826 -224.061274) (xy 364.44555 -223.706436) (xy 364.43793 -223.684338)
			(xy 364.429302 -223.657991) (xy 364.419979 -223.603344) (xy 364.419388 -223.575626) (xy 364.419896 -223.549719)
			(xy 364.428002 -223.498542) (xy 364.444014 -223.449263) (xy 364.467537 -223.403096) (xy 364.497993 -223.361177)
			(xy 364.534631 -223.324539) (xy 364.57655 -223.294083) (xy 364.622717 -223.27056) (xy 364.671996 -223.254548)
			(xy 364.723173 -223.246442) (xy 364.774987 -223.246442) (xy 364.826164 -223.254548) (xy 364.875443 -223.27056)
			(xy 364.92161 -223.294083) (xy 364.963529 -223.324539) (xy 365.000167 -223.361177) (xy 365.030623 -223.403096)
			(xy 365.054146 -223.449263) (xy 365.070158 -223.498542) (xy 365.078264 -223.549719) (xy 365.078772 -223.575626)
			(xy 365.078381 -223.600993) (xy 365.070628 -223.651131) (xy 365.055277 -223.699486) (xy 365.032692 -223.744915)
			(xy 365.003407 -223.786344) (xy 364.968116 -223.822791) (xy 364.927652 -223.853396) (xy 364.882974 -223.877433)
			(xy 364.835139 -223.894334) (xy 364.810294 -223.899476) (xy 364.787434 -223.903794) (xy 364.58271 -224.258632)
			(xy 364.590584 -224.280476) (xy 364.599157 -224.306897) (xy 364.608358 -224.36167) (xy 364.608872 -224.389442)
			(xy 364.889796 -224.389442) (xy 364.890304 -224.363555) (xy 364.898403 -224.312417) (xy 364.914402 -224.263177)
			(xy 364.937908 -224.217045) (xy 364.96834 -224.175158) (xy 365.00495 -224.138548) (xy 365.046837 -224.108116)
			(xy 365.092969 -224.08461) (xy 365.142209 -224.068611) (xy 365.193347 -224.060512) (xy 365.245121 -224.060512)
			(xy 365.296259 -224.068611) (xy 365.345499 -224.08461) (xy 365.391631 -224.108116) (xy 365.433518 -224.138548)
			(xy 365.470128 -224.175158) (xy 365.50056 -224.217045) (xy 365.524066 -224.263177) (xy 365.540065 -224.312417)
			(xy 365.548164 -224.363555) (xy 365.548672 -224.389442) (xy 365.829596 -224.389442) (xy 365.830029 -224.364106)
			(xy 365.83779 -224.314032) (xy 365.85312 -224.265734) (xy 365.875659 -224.22035) (xy 365.904875 -224.178949)
			(xy 365.940081 -224.142504) (xy 365.980448 -224.111874) (xy 366.025026 -224.087781) (xy 366.072765 -224.070791)
			(xy 366.097566 -224.065592) (xy 366.120426 -224.061274) (xy 366.32515 -223.706436) (xy 366.31753 -223.684338)
			(xy 366.308902 -223.657991) (xy 366.299579 -223.603344) (xy 366.298988 -223.575626) (xy 366.299496 -223.549719)
			(xy 366.307602 -223.498542) (xy 366.323614 -223.449263) (xy 366.347137 -223.403096) (xy 366.377593 -223.361177)
			(xy 366.414231 -223.324539) (xy 366.45615 -223.294083) (xy 366.502317 -223.27056) (xy 366.551596 -223.254548)
			(xy 366.602773 -223.246442) (xy 366.654587 -223.246442) (xy 366.705764 -223.254548) (xy 366.755043 -223.27056)
			(xy 366.80121 -223.294083) (xy 366.843129 -223.324539) (xy 366.879767 -223.361177) (xy 366.910223 -223.403096)
			(xy 366.933746 -223.449263) (xy 366.949758 -223.498542) (xy 366.957864 -223.549719) (xy 366.958372 -223.575626)
			(xy 366.957981 -223.600993) (xy 366.950228 -223.651131) (xy 366.934877 -223.699486) (xy 366.912292 -223.744915)
			(xy 366.883007 -223.786344) (xy 366.847716 -223.822791) (xy 366.807252 -223.853396) (xy 366.762574 -223.877433)
			(xy 366.714739 -223.894334) (xy 366.689894 -223.899476) (xy 366.667034 -223.903794) (xy 366.46231 -224.258632)
			(xy 366.470184 -224.280476) (xy 366.478757 -224.306897) (xy 366.487958 -224.36167) (xy 366.488472 -224.389442)
			(xy 366.769396 -224.389442) (xy 366.769904 -224.363555) (xy 366.778003 -224.312417) (xy 366.794002 -224.263177)
			(xy 366.817508 -224.217045) (xy 366.84794 -224.175158) (xy 366.88455 -224.138548) (xy 366.926437 -224.108116)
			(xy 366.972569 -224.08461) (xy 367.021809 -224.068611) (xy 367.072947 -224.060512) (xy 367.124721 -224.060512)
			(xy 367.175859 -224.068611) (xy 367.225099 -224.08461) (xy 367.271231 -224.108116) (xy 367.313118 -224.138548)
			(xy 367.349728 -224.175158) (xy 367.38016 -224.217045) (xy 367.403666 -224.263177) (xy 367.419665 -224.312417)
			(xy 367.427764 -224.363555) (xy 367.428272 -224.389442) (xy 367.709196 -224.389442) (xy 367.709629 -224.364106)
			(xy 367.71739 -224.314032) (xy 367.73272 -224.265734) (xy 367.755259 -224.22035) (xy 367.784475 -224.178949)
			(xy 367.819681 -224.142504) (xy 367.860048 -224.111874) (xy 367.904626 -224.087781) (xy 367.952365 -224.070791)
			(xy 367.977166 -224.065592) (xy 368.000026 -224.061274) (xy 368.20475 -223.706436) (xy 368.19713 -223.684338)
			(xy 368.188502 -223.657991) (xy 368.179179 -223.603344) (xy 368.178588 -223.575626) (xy 368.179096 -223.549719)
			(xy 368.187202 -223.498542) (xy 368.203214 -223.449263) (xy 368.226737 -223.403096) (xy 368.257193 -223.361177)
			(xy 368.293831 -223.324539) (xy 368.33575 -223.294083) (xy 368.381917 -223.27056) (xy 368.431196 -223.254548)
			(xy 368.482373 -223.246442) (xy 368.534187 -223.246442) (xy 368.585364 -223.254548) (xy 368.634643 -223.27056)
			(xy 368.68081 -223.294083) (xy 368.722729 -223.324539) (xy 368.759367 -223.361177) (xy 368.789823 -223.403096)
			(xy 368.813346 -223.449263) (xy 368.829358 -223.498542) (xy 368.837464 -223.549719) (xy 368.837972 -223.575626)
			(xy 368.837581 -223.600993) (xy 368.829828 -223.651131) (xy 368.814477 -223.699486) (xy 368.791892 -223.744915)
			(xy 368.762607 -223.786344) (xy 368.727316 -223.822791) (xy 368.686852 -223.853396) (xy 368.642174 -223.877433)
			(xy 368.594339 -223.894334) (xy 368.569494 -223.899476) (xy 368.546634 -223.903794) (xy 368.34191 -224.258632)
			(xy 368.349784 -224.280476) (xy 368.358357 -224.306897) (xy 368.367558 -224.36167) (xy 368.368072 -224.389442)
			(xy 368.648996 -224.389442) (xy 368.649504 -224.363555) (xy 368.657603 -224.312417) (xy 368.673602 -224.263177)
			(xy 368.697108 -224.217045) (xy 368.72754 -224.175158) (xy 368.76415 -224.138548) (xy 368.806037 -224.108116)
			(xy 368.852169 -224.08461) (xy 368.901409 -224.068611) (xy 368.952547 -224.060512) (xy 369.004321 -224.060512)
			(xy 369.055459 -224.068611) (xy 369.104699 -224.08461) (xy 369.150831 -224.108116) (xy 369.192718 -224.138548)
			(xy 369.229328 -224.175158) (xy 369.25976 -224.217045) (xy 369.283266 -224.263177) (xy 369.299265 -224.312417)
			(xy 369.307364 -224.363555) (xy 369.307872 -224.389442) (xy 369.588796 -224.389442) (xy 369.589229 -224.364106)
			(xy 369.59699 -224.314032) (xy 369.61232 -224.265734) (xy 369.634859 -224.22035) (xy 369.664075 -224.178949)
			(xy 369.699281 -224.142504) (xy 369.739648 -224.111874) (xy 369.784226 -224.087781) (xy 369.831965 -224.070791)
			(xy 369.856766 -224.065592) (xy 369.879626 -224.061274) (xy 370.08435 -223.706436) (xy 370.07673 -223.684338)
			(xy 370.068102 -223.657991) (xy 370.058779 -223.603344) (xy 370.058188 -223.575626) (xy 370.058696 -223.549719)
			(xy 370.066802 -223.498542) (xy 370.082814 -223.449263) (xy 370.106337 -223.403096) (xy 370.136793 -223.361177)
			(xy 370.173431 -223.324539) (xy 370.21535 -223.294083) (xy 370.261517 -223.27056) (xy 370.310796 -223.254548)
			(xy 370.361973 -223.246442) (xy 370.413787 -223.246442) (xy 370.464964 -223.254548) (xy 370.514243 -223.27056)
			(xy 370.56041 -223.294083) (xy 370.602329 -223.324539) (xy 370.638967 -223.361177) (xy 370.669423 -223.403096)
			(xy 370.692946 -223.449263) (xy 370.708958 -223.498542) (xy 370.717064 -223.549719) (xy 370.717572 -223.575626)
			(xy 370.717181 -223.600993) (xy 370.709428 -223.651131) (xy 370.694077 -223.699486) (xy 370.671492 -223.744915)
			(xy 370.642207 -223.786344) (xy 370.606916 -223.822791) (xy 370.566452 -223.853396) (xy 370.521774 -223.877433)
			(xy 370.473939 -223.894334) (xy 370.449094 -223.899476) (xy 370.426234 -223.903794) (xy 370.22151 -224.258632)
			(xy 370.229384 -224.280476) (xy 370.237957 -224.306897) (xy 370.247158 -224.36167) (xy 370.247672 -224.389442)
			(xy 370.528596 -224.389442) (xy 370.529104 -224.363555) (xy 370.537203 -224.312417) (xy 370.553202 -224.263177)
			(xy 370.576708 -224.217045) (xy 370.60714 -224.175158) (xy 370.64375 -224.138548) (xy 370.685637 -224.108116)
			(xy 370.731769 -224.08461) (xy 370.781009 -224.068611) (xy 370.832147 -224.060512) (xy 370.883921 -224.060512)
			(xy 370.935059 -224.068611) (xy 370.984299 -224.08461) (xy 371.030431 -224.108116) (xy 371.072318 -224.138548)
			(xy 371.108928 -224.175158) (xy 371.13936 -224.217045) (xy 371.162866 -224.263177) (xy 371.178865 -224.312417)
			(xy 371.186964 -224.363555) (xy 371.187472 -224.389442) (xy 371.468396 -224.389442) (xy 371.468829 -224.364106)
			(xy 371.47659 -224.314032) (xy 371.49192 -224.265734) (xy 371.514459 -224.22035) (xy 371.543675 -224.178949)
			(xy 371.578881 -224.142504) (xy 371.619248 -224.111874) (xy 371.663826 -224.087781) (xy 371.711565 -224.070791)
			(xy 371.736366 -224.065592) (xy 371.759226 -224.061274) (xy 371.96395 -223.706436) (xy 371.95633 -223.684338)
			(xy 371.947702 -223.657991) (xy 371.938379 -223.603344) (xy 371.937788 -223.575626) (xy 371.938296 -223.549719)
			(xy 371.946402 -223.498542) (xy 371.962414 -223.449263) (xy 371.985937 -223.403096) (xy 372.016393 -223.361177)
			(xy 372.053031 -223.324539) (xy 372.09495 -223.294083) (xy 372.141117 -223.27056) (xy 372.190396 -223.254548)
			(xy 372.241573 -223.246442) (xy 372.293387 -223.246442) (xy 372.344564 -223.254548) (xy 372.393843 -223.27056)
			(xy 372.44001 -223.294083) (xy 372.481929 -223.324539) (xy 372.518567 -223.361177) (xy 372.549023 -223.403096)
			(xy 372.572546 -223.449263) (xy 372.588558 -223.498542) (xy 372.596664 -223.549719) (xy 372.597172 -223.575626)
			(xy 372.596781 -223.600993) (xy 372.589028 -223.651131) (xy 372.573677 -223.699486) (xy 372.551092 -223.744915)
			(xy 372.521807 -223.786344) (xy 372.486516 -223.822791) (xy 372.446052 -223.853396) (xy 372.401374 -223.877433)
			(xy 372.353539 -223.894334) (xy 372.328694 -223.899476) (xy 372.305834 -223.903794) (xy 372.10111 -224.258632)
			(xy 372.108984 -224.280476) (xy 372.117557 -224.306897) (xy 372.126758 -224.36167) (xy 372.127272 -224.389442)
			(xy 372.408196 -224.389442) (xy 372.408704 -224.363555) (xy 372.416803 -224.312417) (xy 372.432802 -224.263177)
			(xy 372.456308 -224.217045) (xy 372.48674 -224.175158) (xy 372.52335 -224.138548) (xy 372.565237 -224.108116)
			(xy 372.611369 -224.08461) (xy 372.660609 -224.068611) (xy 372.711747 -224.060512) (xy 372.763521 -224.060512)
			(xy 372.814659 -224.068611) (xy 372.863899 -224.08461) (xy 372.910031 -224.108116) (xy 372.951918 -224.138548)
			(xy 372.988528 -224.175158) (xy 373.01896 -224.217045) (xy 373.042466 -224.263177) (xy 373.058465 -224.312417)
			(xy 373.066564 -224.363555) (xy 373.067072 -224.389442) (xy 373.347996 -224.389442) (xy 373.348429 -224.364106)
			(xy 373.35619 -224.314032) (xy 373.37152 -224.265734) (xy 373.394059 -224.22035) (xy 373.423275 -224.178949)
			(xy 373.458481 -224.142504) (xy 373.498848 -224.111874) (xy 373.543426 -224.087781) (xy 373.591165 -224.070791)
			(xy 373.615966 -224.065592) (xy 373.638826 -224.061274) (xy 373.84355 -223.706436) (xy 373.83593 -223.684338)
			(xy 373.827302 -223.657991) (xy 373.817979 -223.603344) (xy 373.817388 -223.575626) (xy 373.817896 -223.549719)
			(xy 373.826002 -223.498542) (xy 373.842014 -223.449263) (xy 373.865537 -223.403096) (xy 373.895993 -223.361177)
			(xy 373.932631 -223.324539) (xy 373.97455 -223.294083) (xy 374.020717 -223.27056) (xy 374.069996 -223.254548)
			(xy 374.121173 -223.246442) (xy 374.172987 -223.246442) (xy 374.224164 -223.254548) (xy 374.273443 -223.27056)
			(xy 374.31961 -223.294083) (xy 374.361529 -223.324539) (xy 374.398167 -223.361177) (xy 374.428623 -223.403096)
			(xy 374.452146 -223.449263) (xy 374.468158 -223.498542) (xy 374.476264 -223.549719) (xy 374.476772 -223.575626)
			(xy 374.476381 -223.600993) (xy 374.468628 -223.651131) (xy 374.453277 -223.699486) (xy 374.430692 -223.744915)
			(xy 374.401407 -223.786344) (xy 374.366116 -223.822791) (xy 374.325652 -223.853396) (xy 374.280974 -223.877433)
			(xy 374.233139 -223.894334) (xy 374.208294 -223.899476) (xy 374.185434 -223.903794) (xy 373.98071 -224.258632)
			(xy 373.988584 -224.280476) (xy 373.997157 -224.306897) (xy 374.006358 -224.36167) (xy 374.006872 -224.389442)
			(xy 374.287796 -224.389442) (xy 374.288304 -224.363555) (xy 374.296403 -224.312417) (xy 374.312402 -224.263177)
			(xy 374.335908 -224.217045) (xy 374.36634 -224.175158) (xy 374.40295 -224.138548) (xy 374.444837 -224.108116)
			(xy 374.490969 -224.08461) (xy 374.540209 -224.068611) (xy 374.591347 -224.060512) (xy 374.643121 -224.060512)
			(xy 374.694259 -224.068611) (xy 374.743499 -224.08461) (xy 374.789631 -224.108116) (xy 374.831518 -224.138548)
			(xy 374.868128 -224.175158) (xy 374.89856 -224.217045) (xy 374.922066 -224.263177) (xy 374.938065 -224.312417)
			(xy 374.946164 -224.363555) (xy 374.946672 -224.389442) (xy 375.227596 -224.389442) (xy 375.228029 -224.364106)
			(xy 375.23579 -224.314032) (xy 375.25112 -224.265734) (xy 375.273659 -224.22035) (xy 375.302875 -224.178949)
			(xy 375.338081 -224.142504) (xy 375.378448 -224.111874) (xy 375.423026 -224.087781) (xy 375.470765 -224.070791)
			(xy 375.495566 -224.065592) (xy 375.518426 -224.061274) (xy 375.72315 -223.706436) (xy 375.71553 -223.684338)
			(xy 375.706902 -223.657991) (xy 375.697579 -223.603344) (xy 375.696988 -223.575626) (xy 375.697496 -223.549719)
			(xy 375.705602 -223.498542) (xy 375.721614 -223.449263) (xy 375.745137 -223.403096) (xy 375.775593 -223.361177)
			(xy 375.812231 -223.324539) (xy 375.85415 -223.294083) (xy 375.900317 -223.27056) (xy 375.949596 -223.254548)
			(xy 376.000773 -223.246442) (xy 376.052587 -223.246442) (xy 376.103764 -223.254548) (xy 376.153043 -223.27056)
			(xy 376.19921 -223.294083) (xy 376.241129 -223.324539) (xy 376.277767 -223.361177) (xy 376.308223 -223.403096)
			(xy 376.331746 -223.449263) (xy 376.347758 -223.498542) (xy 376.355864 -223.549719) (xy 376.356372 -223.575626)
			(xy 376.355981 -223.600993) (xy 376.348228 -223.651131) (xy 376.332877 -223.699486) (xy 376.310292 -223.744915)
			(xy 376.281007 -223.786344) (xy 376.245716 -223.822791) (xy 376.205252 -223.853396) (xy 376.160574 -223.877433)
			(xy 376.112739 -223.894334) (xy 376.087894 -223.899476) (xy 376.065034 -223.903794) (xy 375.86031 -224.258632)
			(xy 375.868184 -224.280476) (xy 375.876757 -224.306897) (xy 375.885958 -224.36167) (xy 375.886472 -224.389442)
			(xy 376.167396 -224.389442) (xy 376.167904 -224.363555) (xy 376.176003 -224.312417) (xy 376.192002 -224.263177)
			(xy 376.215508 -224.217045) (xy 376.24594 -224.175158) (xy 376.28255 -224.138548) (xy 376.324437 -224.108116)
			(xy 376.370569 -224.08461) (xy 376.419809 -224.068611) (xy 376.470947 -224.060512) (xy 376.522721 -224.060512)
			(xy 376.573859 -224.068611) (xy 376.623099 -224.08461) (xy 376.669231 -224.108116) (xy 376.711118 -224.138548)
			(xy 376.747728 -224.175158) (xy 376.77816 -224.217045) (xy 376.801666 -224.263177) (xy 376.817665 -224.312417)
			(xy 376.825764 -224.363555) (xy 376.826272 -224.389442) (xy 377.107196 -224.389442) (xy 377.107629 -224.364106)
			(xy 377.11539 -224.314032) (xy 377.13072 -224.265734) (xy 377.153259 -224.22035) (xy 377.182475 -224.178949)
			(xy 377.217681 -224.142504) (xy 377.258048 -224.111874) (xy 377.302626 -224.087781) (xy 377.350365 -224.070791)
			(xy 377.375166 -224.065592) (xy 377.398026 -224.061274) (xy 377.60275 -223.706436) (xy 377.59513 -223.684338)
			(xy 377.586502 -223.657991) (xy 377.577179 -223.603344) (xy 377.576588 -223.575626) (xy 377.577096 -223.549719)
			(xy 377.585202 -223.498542) (xy 377.601214 -223.449263) (xy 377.624737 -223.403096) (xy 377.655193 -223.361177)
			(xy 377.691831 -223.324539) (xy 377.73375 -223.294083) (xy 377.779917 -223.27056) (xy 377.829196 -223.254548)
			(xy 377.880373 -223.246442) (xy 377.932187 -223.246442) (xy 377.983364 -223.254548) (xy 378.032643 -223.27056)
			(xy 378.07881 -223.294083) (xy 378.120729 -223.324539) (xy 378.157367 -223.361177) (xy 378.187823 -223.403096)
			(xy 378.211346 -223.449263) (xy 378.227358 -223.498542) (xy 378.235464 -223.549719) (xy 378.235972 -223.575626)
			(xy 378.235581 -223.600993) (xy 378.227828 -223.651131) (xy 378.212477 -223.699486) (xy 378.189892 -223.744915)
			(xy 378.160607 -223.786344) (xy 378.125316 -223.822791) (xy 378.084852 -223.853396) (xy 378.040174 -223.877433)
			(xy 377.992339 -223.894334) (xy 377.967494 -223.899476) (xy 377.944634 -223.903794) (xy 377.73991 -224.258632)
			(xy 377.747784 -224.280476) (xy 377.756357 -224.306897) (xy 377.765558 -224.36167) (xy 377.766072 -224.389442)
			(xy 378.046996 -224.389442) (xy 378.047504 -224.363555) (xy 378.055603 -224.312417) (xy 378.071602 -224.263177)
			(xy 378.095108 -224.217045) (xy 378.12554 -224.175158) (xy 378.16215 -224.138548) (xy 378.204037 -224.108116)
			(xy 378.250169 -224.08461) (xy 378.299409 -224.068611) (xy 378.350547 -224.060512) (xy 378.402321 -224.060512)
			(xy 378.453459 -224.068611) (xy 378.502699 -224.08461) (xy 378.548831 -224.108116) (xy 378.590718 -224.138548)
			(xy 378.627328 -224.175158) (xy 378.65776 -224.217045) (xy 378.681266 -224.263177) (xy 378.697265 -224.312417)
			(xy 378.705364 -224.363555) (xy 378.705872 -224.389442) (xy 378.986796 -224.389442) (xy 378.987229 -224.364106)
			(xy 378.99499 -224.314032) (xy 379.01032 -224.265734) (xy 379.032859 -224.22035) (xy 379.062075 -224.178949)
			(xy 379.097281 -224.142504) (xy 379.137648 -224.111874) (xy 379.182226 -224.087781) (xy 379.229965 -224.070791)
			(xy 379.254766 -224.065592) (xy 379.277626 -224.061274) (xy 379.48235 -223.706182) (xy 379.47473 -223.684338)
			(xy 379.466087 -223.657995) (xy 379.456772 -223.603345) (xy 379.456188 -223.575626) (xy 379.456696 -223.549719)
			(xy 379.464802 -223.498542) (xy 379.480814 -223.449263) (xy 379.504337 -223.403096) (xy 379.534793 -223.361177)
			(xy 379.571431 -223.324539) (xy 379.61335 -223.294083) (xy 379.659517 -223.27056) (xy 379.708796 -223.254548)
			(xy 379.759973 -223.246442) (xy 379.811787 -223.246442) (xy 379.862964 -223.254548) (xy 379.912243 -223.27056)
			(xy 379.95841 -223.294083) (xy 380.000329 -223.324539) (xy 380.036967 -223.361177) (xy 380.067423 -223.403096)
			(xy 380.090946 -223.449263) (xy 380.106958 -223.498542) (xy 380.115064 -223.549719) (xy 380.115572 -223.575626)
			(xy 380.115097 -223.600971) (xy 380.107321 -223.651063) (xy 380.091971 -223.699374) (xy 380.069408 -223.744767)
			(xy 380.040166 -223.786173) (xy 380.004931 -223.822617) (xy 379.964535 -223.853239) (xy 379.919928 -223.877319)
			(xy 379.872162 -223.89429) (xy 379.847348 -223.899476) (xy 379.824488 -223.903794) (xy 379.619764 -224.258632)
			(xy 379.627384 -224.280476) (xy 379.635939 -224.306769) (xy 379.645132 -224.361289) (xy 379.645672 -224.388934)
			(xy 379.645672 -224.389442) (xy 379.926596 -224.389442) (xy 379.927104 -224.363555) (xy 379.935203 -224.312417)
			(xy 379.951202 -224.263177) (xy 379.974708 -224.217045) (xy 380.00514 -224.175158) (xy 380.04175 -224.138548)
			(xy 380.083637 -224.108116) (xy 380.129769 -224.08461) (xy 380.179009 -224.068611) (xy 380.230147 -224.060512)
			(xy 380.281921 -224.060512) (xy 380.333059 -224.068611) (xy 380.382299 -224.08461) (xy 380.428431 -224.108116)
			(xy 380.470318 -224.138548) (xy 380.506928 -224.175158) (xy 380.53736 -224.217045) (xy 380.560866 -224.263177)
			(xy 380.576865 -224.312417) (xy 380.584964 -224.363555) (xy 380.585472 -224.389442) (xy 380.866396 -224.389442)
			(xy 380.866829 -224.364106) (xy 380.87459 -224.314032) (xy 380.88992 -224.265734) (xy 380.912459 -224.22035)
			(xy 380.941675 -224.178949) (xy 380.976881 -224.142504) (xy 381.017248 -224.111874) (xy 381.061826 -224.087781)
			(xy 381.109565 -224.070791) (xy 381.134366 -224.065592) (xy 381.157226 -224.061274) (xy 381.362204 -223.705928)
			(xy 381.354584 -223.684084) (xy 381.346064 -223.657913) (xy 381.336871 -223.603651) (xy 381.336296 -223.576134)
			(xy 381.336296 -223.575626) (xy 381.336804 -223.549739) (xy 381.344903 -223.498601) (xy 381.360902 -223.449361)
			(xy 381.384408 -223.403229) (xy 381.41484 -223.361342) (xy 381.45145 -223.324732) (xy 381.493337 -223.2943)
			(xy 381.539469 -223.270794) (xy 381.588709 -223.254795) (xy 381.639847 -223.246696) (xy 381.691621 -223.246696)
			(xy 381.742759 -223.254795) (xy 381.791999 -223.270794) (xy 381.838131 -223.2943) (xy 381.880018 -223.324732)
			(xy 381.916628 -223.361342) (xy 381.94706 -223.403229) (xy 381.970566 -223.449361) (xy 381.986565 -223.498601)
			(xy 381.994664 -223.549739) (xy 381.995172 -223.575626) (xy 381.994697 -223.600971) (xy 381.986921 -223.651063)
			(xy 381.971571 -223.699374) (xy 381.949008 -223.744767) (xy 381.919766 -223.786173) (xy 381.884531 -223.822617)
			(xy 381.844135 -223.853239) (xy 381.810241 -223.871536) (xy 410.102304 -223.871536) (xy 410.102304 -223.462596)
			(xy 410.102719 -223.452441) (xy 410.110516 -223.433688) (xy 410.124915 -223.419365) (xy 410.143709 -223.411666)
			(xy 410.153866 -223.411288) (xy 411.553406 -223.411288) (xy 411.563527 -223.41182) (xy 411.582238 -223.41954)
			(xy 411.596592 -223.433812) (xy 411.60442 -223.452478) (xy 411.604968 -223.462596) (xy 411.604968 -223.871536)
			(xy 417.646104 -223.871536) (xy 417.646104 -223.462596) (xy 417.646519 -223.452441) (xy 417.654316 -223.433688)
			(xy 417.668715 -223.419365) (xy 417.687509 -223.411666) (xy 417.697666 -223.411288) (xy 419.097206 -223.411288)
			(xy 419.107327 -223.41182) (xy 419.126038 -223.41954) (xy 419.140392 -223.433812) (xy 419.14822 -223.452478)
			(xy 419.148768 -223.462596) (xy 419.148768 -223.871536) (xy 425.189904 -223.871536) (xy 425.189904 -223.462596)
			(xy 425.190319 -223.452441) (xy 425.198116 -223.433688) (xy 425.212515 -223.419365) (xy 425.231309 -223.411666)
			(xy 425.241466 -223.411288) (xy 426.641006 -223.411288) (xy 426.651127 -223.41182) (xy 426.669838 -223.41954)
			(xy 426.684192 -223.433812) (xy 426.69202 -223.452478) (xy 426.692568 -223.462596) (xy 426.692568 -223.871536)
			(xy 432.733704 -223.871536) (xy 432.733704 -223.462596) (xy 432.734119 -223.452441) (xy 432.741916 -223.433688)
			(xy 432.756315 -223.419365) (xy 432.775109 -223.411666) (xy 432.785266 -223.411288) (xy 434.184806 -223.411288)
			(xy 434.194927 -223.41182) (xy 434.213638 -223.41954) (xy 434.227992 -223.433812) (xy 434.23582 -223.452478)
			(xy 434.236368 -223.462596) (xy 434.236368 -223.871536) (xy 440.277504 -223.871536) (xy 440.277504 -223.462596)
			(xy 440.277919 -223.452441) (xy 440.285716 -223.433688) (xy 440.300115 -223.419365) (xy 440.318909 -223.411666)
			(xy 440.329066 -223.411288) (xy 441.728606 -223.411288) (xy 441.738727 -223.41182) (xy 441.757438 -223.41954)
			(xy 441.771792 -223.433812) (xy 441.77962 -223.452478) (xy 441.780168 -223.462596) (xy 441.780168 -223.871536)
			(xy 447.821304 -223.871536) (xy 447.821304 -223.462596) (xy 447.821719 -223.452441) (xy 447.829516 -223.433688)
			(xy 447.843915 -223.419365) (xy 447.862709 -223.411666) (xy 447.872866 -223.411288) (xy 449.272406 -223.411288)
			(xy 449.282527 -223.41182) (xy 449.301238 -223.41954) (xy 449.315592 -223.433812) (xy 449.32342 -223.452478)
			(xy 449.323968 -223.462596) (xy 449.323968 -223.871536) (xy 455.365104 -223.871536) (xy 455.365104 -223.462596)
			(xy 455.365519 -223.452441) (xy 455.373316 -223.433688) (xy 455.387715 -223.419365) (xy 455.406509 -223.411666)
			(xy 455.416666 -223.411288) (xy 456.816206 -223.411288) (xy 456.826327 -223.41182) (xy 456.845038 -223.41954)
			(xy 456.859392 -223.433812) (xy 456.86722 -223.452478) (xy 456.867768 -223.462596) (xy 456.867768 -223.871536)
			(xy 462.908904 -223.871536) (xy 462.908904 -223.462596) (xy 462.909319 -223.452441) (xy 462.917116 -223.433688)
			(xy 462.931515 -223.419365) (xy 462.950309 -223.411666) (xy 462.960466 -223.411288) (xy 464.360006 -223.411288)
			(xy 464.370127 -223.41182) (xy 464.388838 -223.41954) (xy 464.403192 -223.433812) (xy 464.41102 -223.452478)
			(xy 464.411568 -223.462596) (xy 464.411568 -223.871536) (xy 464.411207 -223.881696) (xy 464.403394 -223.900456)
			(xy 464.388978 -223.914779) (xy 464.370169 -223.922472) (xy 464.360006 -223.922844) (xy 462.960466 -223.922844)
			(xy 462.950335 -223.922401) (xy 462.93161 -223.914659) (xy 462.917254 -223.900359) (xy 462.909439 -223.881665)
			(xy 462.908904 -223.871536) (xy 456.867768 -223.871536) (xy 456.867407 -223.881696) (xy 456.859594 -223.900456)
			(xy 456.845178 -223.914779) (xy 456.826369 -223.922472) (xy 456.816206 -223.922844) (xy 455.416666 -223.922844)
			(xy 455.406535 -223.922401) (xy 455.38781 -223.914659) (xy 455.373454 -223.900359) (xy 455.365639 -223.881665)
			(xy 455.365104 -223.871536) (xy 449.323968 -223.871536) (xy 449.323607 -223.881696) (xy 449.315794 -223.900456)
			(xy 449.301378 -223.914779) (xy 449.282569 -223.922472) (xy 449.272406 -223.922844) (xy 447.872866 -223.922844)
			(xy 447.862735 -223.922401) (xy 447.84401 -223.914659) (xy 447.829654 -223.900359) (xy 447.821839 -223.881665)
			(xy 447.821304 -223.871536) (xy 441.780168 -223.871536) (xy 441.779807 -223.881696) (xy 441.771994 -223.900456)
			(xy 441.757578 -223.914779) (xy 441.738769 -223.922472) (xy 441.728606 -223.922844) (xy 440.329066 -223.922844)
			(xy 440.318935 -223.922401) (xy 440.30021 -223.914659) (xy 440.285854 -223.900359) (xy 440.278039 -223.881665)
			(xy 440.277504 -223.871536) (xy 434.236368 -223.871536) (xy 434.236007 -223.881696) (xy 434.228194 -223.900456)
			(xy 434.213778 -223.914779) (xy 434.194969 -223.922472) (xy 434.184806 -223.922844) (xy 432.785266 -223.922844)
			(xy 432.775135 -223.922401) (xy 432.75641 -223.914659) (xy 432.742054 -223.900359) (xy 432.734239 -223.881665)
			(xy 432.733704 -223.871536) (xy 426.692568 -223.871536) (xy 426.692207 -223.881696) (xy 426.684394 -223.900456)
			(xy 426.669978 -223.914779) (xy 426.651169 -223.922472) (xy 426.641006 -223.922844) (xy 425.241466 -223.922844)
			(xy 425.231335 -223.922401) (xy 425.21261 -223.914659) (xy 425.198254 -223.900359) (xy 425.190439 -223.881665)
			(xy 425.189904 -223.871536) (xy 419.148768 -223.871536) (xy 419.148407 -223.881696) (xy 419.140594 -223.900456)
			(xy 419.126178 -223.914779) (xy 419.107369 -223.922472) (xy 419.097206 -223.922844) (xy 417.697666 -223.922844)
			(xy 417.687535 -223.922401) (xy 417.66881 -223.914659) (xy 417.654454 -223.900359) (xy 417.646639 -223.881665)
			(xy 417.646104 -223.871536) (xy 411.604968 -223.871536) (xy 411.604607 -223.881696) (xy 411.596794 -223.900456)
			(xy 411.582378 -223.914779) (xy 411.563569 -223.922472) (xy 411.553406 -223.922844) (xy 410.153866 -223.922844)
			(xy 410.143735 -223.922401) (xy 410.12501 -223.914659) (xy 410.110654 -223.900359) (xy 410.102839 -223.881665)
			(xy 410.102304 -223.871536) (xy 381.810241 -223.871536) (xy 381.799528 -223.877319) (xy 381.751762 -223.89429)
			(xy 381.726948 -223.899476) (xy 381.704088 -223.903794) (xy 381.499364 -224.258632) (xy 381.506984 -224.280476)
			(xy 381.515539 -224.306769) (xy 381.524732 -224.361289) (xy 381.525272 -224.388934) (xy 381.525272 -224.389442)
			(xy 381.806196 -224.389442) (xy 381.806704 -224.363555) (xy 381.814803 -224.312417) (xy 381.830802 -224.263177)
			(xy 381.854308 -224.217045) (xy 381.88474 -224.175158) (xy 381.92135 -224.138548) (xy 381.963237 -224.108116)
			(xy 382.009369 -224.08461) (xy 382.058609 -224.068611) (xy 382.109747 -224.060512) (xy 382.161521 -224.060512)
			(xy 382.212659 -224.068611) (xy 382.261899 -224.08461) (xy 382.308031 -224.108116) (xy 382.349918 -224.138548)
			(xy 382.386528 -224.175158) (xy 382.41696 -224.217045) (xy 382.440466 -224.263177) (xy 382.456465 -224.312417)
			(xy 382.464564 -224.363555) (xy 382.465072 -224.389442) (xy 382.464539 -224.41715) (xy 382.455342 -224.471795)
			(xy 382.446784 -224.498154) (xy 382.439164 -224.519998) (xy 382.555435 -224.72142) (xy 406.002236 -224.72142)
			(xy 406.002236 -224.31248) (xy 406.002606 -224.30232) (xy 406.010415 -224.28356) (xy 406.024828 -224.269236)
			(xy 406.043636 -224.261544) (xy 406.053798 -224.261172) (xy 407.453338 -224.261172) (xy 407.463471 -224.261596)
			(xy 407.482199 -224.269343) (xy 407.496555 -224.283648) (xy 407.504367 -224.302349) (xy 407.5049 -224.31248)
			(xy 407.5049 -224.72142) (xy 413.546036 -224.72142) (xy 413.546036 -224.31248) (xy 413.546406 -224.30232)
			(xy 413.554215 -224.28356) (xy 413.568628 -224.269236) (xy 413.587436 -224.261544) (xy 413.597598 -224.261172)
			(xy 414.997138 -224.261172) (xy 415.007271 -224.261596) (xy 415.025999 -224.269343) (xy 415.040355 -224.283648)
			(xy 415.048167 -224.302349) (xy 415.0487 -224.31248) (xy 415.0487 -224.72142) (xy 421.089836 -224.72142)
			(xy 421.089836 -224.31248) (xy 421.090206 -224.30232) (xy 421.098015 -224.28356) (xy 421.112428 -224.269236)
			(xy 421.131236 -224.261544) (xy 421.141398 -224.261172) (xy 422.540938 -224.261172) (xy 422.551071 -224.261596)
			(xy 422.569799 -224.269343) (xy 422.584155 -224.283648) (xy 422.591967 -224.302349) (xy 422.5925 -224.31248)
			(xy 422.5925 -224.72142) (xy 428.633636 -224.72142) (xy 428.633636 -224.31248) (xy 428.634006 -224.30232)
			(xy 428.641815 -224.28356) (xy 428.656228 -224.269236) (xy 428.675036 -224.261544) (xy 428.685198 -224.261172)
			(xy 430.084738 -224.261172) (xy 430.094871 -224.261596) (xy 430.113599 -224.269343) (xy 430.127955 -224.283648)
			(xy 430.135767 -224.302349) (xy 430.1363 -224.31248) (xy 430.1363 -224.72142) (xy 436.177436 -224.72142)
			(xy 436.177436 -224.31248) (xy 436.177806 -224.30232) (xy 436.185615 -224.28356) (xy 436.200028 -224.269236)
			(xy 436.218836 -224.261544) (xy 436.228998 -224.261172) (xy 437.628538 -224.261172) (xy 437.638671 -224.261596)
			(xy 437.657399 -224.269343) (xy 437.671755 -224.283648) (xy 437.679567 -224.302349) (xy 437.6801 -224.31248)
			(xy 437.6801 -224.72142) (xy 443.721236 -224.72142) (xy 443.721236 -224.31248) (xy 443.721606 -224.30232)
			(xy 443.729415 -224.28356) (xy 443.743828 -224.269236) (xy 443.762636 -224.261544) (xy 443.772798 -224.261172)
			(xy 445.172338 -224.261172) (xy 445.182471 -224.261596) (xy 445.201199 -224.269343) (xy 445.215555 -224.283648)
			(xy 445.223367 -224.302349) (xy 445.2239 -224.31248) (xy 445.2239 -224.72142) (xy 451.265036 -224.72142)
			(xy 451.265036 -224.31248) (xy 451.265406 -224.30232) (xy 451.273215 -224.28356) (xy 451.287628 -224.269236)
			(xy 451.306436 -224.261544) (xy 451.316598 -224.261172) (xy 452.716138 -224.261172) (xy 452.726271 -224.261596)
			(xy 452.744999 -224.269343) (xy 452.759355 -224.283648) (xy 452.767167 -224.302349) (xy 452.7677 -224.31248)
			(xy 452.7677 -224.72142) (xy 458.808836 -224.72142) (xy 458.808836 -224.31248) (xy 458.809206 -224.30232)
			(xy 458.817015 -224.28356) (xy 458.831428 -224.269236) (xy 458.850236 -224.261544) (xy 458.860398 -224.261172)
			(xy 460.259938 -224.261172) (xy 460.270071 -224.261596) (xy 460.288799 -224.269343) (xy 460.303155 -224.283648)
			(xy 460.310967 -224.302349) (xy 460.3115 -224.31248) (xy 460.3115 -224.72142) (xy 460.311095 -224.731575)
			(xy 460.303293 -224.750328) (xy 460.288891 -224.764651) (xy 460.270096 -224.77235) (xy 460.259938 -224.772728)
			(xy 458.860398 -224.772728) (xy 458.850267 -224.772274) (xy 458.83154 -224.76454) (xy 458.817183 -224.750243)
			(xy 458.809369 -224.731549) (xy 458.808836 -224.72142) (xy 452.7677 -224.72142) (xy 452.767295 -224.731575)
			(xy 452.759493 -224.750328) (xy 452.745091 -224.764651) (xy 452.726296 -224.77235) (xy 452.716138 -224.772728)
			(xy 451.316598 -224.772728) (xy 451.306467 -224.772274) (xy 451.28774 -224.76454) (xy 451.273383 -224.750243)
			(xy 451.265569 -224.731549) (xy 451.265036 -224.72142) (xy 445.2239 -224.72142) (xy 445.223495 -224.731575)
			(xy 445.215693 -224.750328) (xy 445.201291 -224.764651) (xy 445.182496 -224.77235) (xy 445.172338 -224.772728)
			(xy 443.772798 -224.772728) (xy 443.762667 -224.772274) (xy 443.74394 -224.76454) (xy 443.729583 -224.750243)
			(xy 443.721769 -224.731549) (xy 443.721236 -224.72142) (xy 437.6801 -224.72142) (xy 437.679695 -224.731575)
			(xy 437.671893 -224.750328) (xy 437.657491 -224.764651) (xy 437.638696 -224.77235) (xy 437.628538 -224.772728)
			(xy 436.228998 -224.772728) (xy 436.218867 -224.772274) (xy 436.20014 -224.76454) (xy 436.185783 -224.750243)
			(xy 436.177969 -224.731549) (xy 436.177436 -224.72142) (xy 430.1363 -224.72142) (xy 430.135895 -224.731575)
			(xy 430.128093 -224.750328) (xy 430.113691 -224.764651) (xy 430.094896 -224.77235) (xy 430.084738 -224.772728)
			(xy 428.685198 -224.772728) (xy 428.675067 -224.772274) (xy 428.65634 -224.76454) (xy 428.641983 -224.750243)
			(xy 428.634169 -224.731549) (xy 428.633636 -224.72142) (xy 422.5925 -224.72142) (xy 422.592095 -224.731575)
			(xy 422.584293 -224.750328) (xy 422.569891 -224.764651) (xy 422.551096 -224.77235) (xy 422.540938 -224.772728)
			(xy 421.141398 -224.772728) (xy 421.131267 -224.772274) (xy 421.11254 -224.76454) (xy 421.098183 -224.750243)
			(xy 421.090369 -224.731549) (xy 421.089836 -224.72142) (xy 415.0487 -224.72142) (xy 415.048295 -224.731575)
			(xy 415.040493 -224.750328) (xy 415.026091 -224.764651) (xy 415.007296 -224.77235) (xy 414.997138 -224.772728)
			(xy 413.597598 -224.772728) (xy 413.587467 -224.772274) (xy 413.56874 -224.76454) (xy 413.554383 -224.750243)
			(xy 413.546569 -224.731549) (xy 413.546036 -224.72142) (xy 407.5049 -224.72142) (xy 407.504495 -224.731575)
			(xy 407.496693 -224.750328) (xy 407.482291 -224.764651) (xy 407.463496 -224.77235) (xy 407.453338 -224.772728)
			(xy 406.053798 -224.772728) (xy 406.043667 -224.772274) (xy 406.02494 -224.76454) (xy 406.010583 -224.750243)
			(xy 406.002769 -224.731549) (xy 406.002236 -224.72142) (xy 382.555435 -224.72142) (xy 382.644142 -224.87509)
			(xy 382.667002 -224.879408) (xy 382.691815 -224.884555) (xy 382.739557 -224.901547) (xy 382.784137 -224.925644)
			(xy 382.824504 -224.95628) (xy 382.859707 -224.992732) (xy 382.888918 -225.034142) (xy 382.911448 -225.079534)
			(xy 382.926766 -225.12784) (xy 382.934512 -225.17792) (xy 382.934972 -225.203258) (xy 382.934464 -225.229145)
			(xy 382.926365 -225.280283) (xy 382.910366 -225.329523) (xy 382.88686 -225.375655) (xy 382.856428 -225.417542)
			(xy 382.819818 -225.454152) (xy 382.777931 -225.484584) (xy 382.731799 -225.50809) (xy 382.682559 -225.524089)
			(xy 382.631421 -225.532188) (xy 382.579647 -225.532188) (xy 382.528509 -225.524089) (xy 382.479269 -225.50809)
			(xy 382.433137 -225.484584) (xy 382.39125 -225.454152) (xy 382.35464 -225.417542) (xy 382.324208 -225.375655)
			(xy 382.300702 -225.329523) (xy 382.284703 -225.280283) (xy 382.276604 -225.229145) (xy 382.276096 -225.203258)
			(xy 382.276096 -225.20275) (xy 382.276653 -225.175107) (xy 382.285844 -225.120589) (xy 382.294384 -225.094292)
			(xy 382.302004 -225.072448) (xy 382.09728 -224.71761) (xy 382.07442 -224.713292) (xy 382.049591 -224.708158)
			(xy 382.001812 -224.691199) (xy 381.957192 -224.667122) (xy 381.916786 -224.636498) (xy 381.881546 -224.600046)
			(xy 381.852303 -224.558629) (xy 381.829748 -224.513222) (xy 381.814412 -224.464896) (xy 381.806657 -224.414792)
			(xy 381.806196 -224.389442) (xy 381.525272 -224.389442) (xy 381.524764 -224.415329) (xy 381.516665 -224.466467)
			(xy 381.500666 -224.515707) (xy 381.47716 -224.561839) (xy 381.446728 -224.603726) (xy 381.410118 -224.640336)
			(xy 381.368231 -224.670768) (xy 381.322099 -224.694274) (xy 381.272859 -224.710273) (xy 381.221721 -224.718372)
			(xy 381.169947 -224.718372) (xy 381.118809 -224.710273) (xy 381.069569 -224.694274) (xy 381.023437 -224.670768)
			(xy 380.98155 -224.640336) (xy 380.94494 -224.603726) (xy 380.914508 -224.561839) (xy 380.891002 -224.515707)
			(xy 380.875003 -224.466467) (xy 380.866904 -224.415329) (xy 380.866396 -224.389442) (xy 380.585472 -224.389442)
			(xy 380.584925 -224.417149) (xy 380.575741 -224.471796) (xy 380.567184 -224.498154) (xy 380.55931 -224.520252)
			(xy 380.764288 -224.87509) (xy 380.787148 -224.879408) (xy 380.811971 -224.884565) (xy 380.859751 -224.90152)
			(xy 380.904371 -224.925592) (xy 380.944778 -224.956214) (xy 380.980019 -224.992662) (xy 381.009263 -225.034077)
			(xy 381.031819 -225.079482) (xy 381.047156 -225.127806) (xy 381.054911 -225.177908) (xy 381.055372 -225.203258)
			(xy 381.054864 -225.229165) (xy 381.046758 -225.280342) (xy 381.030746 -225.329621) (xy 381.007223 -225.375788)
			(xy 380.976767 -225.417707) (xy 380.940129 -225.454345) (xy 380.89821 -225.484801) (xy 380.852043 -225.508324)
			(xy 380.802764 -225.524336) (xy 380.751587 -225.532442) (xy 380.699773 -225.532442) (xy 380.648596 -225.524336)
			(xy 380.599317 -225.508324) (xy 380.55315 -225.484801) (xy 380.511231 -225.454345) (xy 380.474593 -225.417707)
			(xy 380.444137 -225.375788) (xy 380.420614 -225.329621) (xy 380.404602 -225.280342) (xy 380.396496 -225.229165)
			(xy 380.395988 -225.203258) (xy 380.396597 -225.175541) (xy 380.40591 -225.120895) (xy 380.41453 -225.094546)
			(xy 380.422404 -225.072448) (xy 380.217426 -224.71761) (xy 380.194566 -224.713292) (xy 380.169748 -224.708169)
			(xy 380.122005 -224.691172) (xy 380.077426 -224.667071) (xy 380.03706 -224.636431) (xy 380.001857 -224.599976)
			(xy 379.972648 -224.558564) (xy 379.950119 -224.51317) (xy 379.934801 -224.464863) (xy 379.927055 -224.414781)
			(xy 379.926596 -224.389442) (xy 379.645672 -224.389442) (xy 379.645164 -224.415329) (xy 379.637065 -224.466467)
			(xy 379.621066 -224.515707) (xy 379.59756 -224.561839) (xy 379.567128 -224.603726) (xy 379.530518 -224.640336)
			(xy 379.488631 -224.670768) (xy 379.442499 -224.694274) (xy 379.393259 -224.710273) (xy 379.342121 -224.718372)
			(xy 379.290347 -224.718372) (xy 379.239209 -224.710273) (xy 379.189969 -224.694274) (xy 379.143837 -224.670768)
			(xy 379.10195 -224.640336) (xy 379.06534 -224.603726) (xy 379.034908 -224.561839) (xy 379.011402 -224.515707)
			(xy 378.995403 -224.466467) (xy 378.987304 -224.415329) (xy 378.986796 -224.389442) (xy 378.705872 -224.389442)
			(xy 378.705325 -224.417149) (xy 378.696141 -224.471796) (xy 378.687584 -224.498154) (xy 378.67971 -224.520252)
			(xy 378.884688 -224.87509) (xy 378.907548 -224.879408) (xy 378.932371 -224.884565) (xy 378.980151 -224.90152)
			(xy 379.024771 -224.925592) (xy 379.065178 -224.956214) (xy 379.100419 -224.992662) (xy 379.129663 -225.034077)
			(xy 379.152219 -225.079482) (xy 379.167556 -225.127806) (xy 379.175311 -225.177908) (xy 379.175772 -225.203258)
			(xy 379.175264 -225.229165) (xy 379.167158 -225.280342) (xy 379.151146 -225.329621) (xy 379.127623 -225.375788)
			(xy 379.097167 -225.417707) (xy 379.060529 -225.454345) (xy 379.01861 -225.484801) (xy 378.972443 -225.508324)
			(xy 378.923164 -225.524336) (xy 378.871987 -225.532442) (xy 378.820173 -225.532442) (xy 378.768996 -225.524336)
			(xy 378.719717 -225.508324) (xy 378.67355 -225.484801) (xy 378.631631 -225.454345) (xy 378.594993 -225.417707)
			(xy 378.564537 -225.375788) (xy 378.541014 -225.329621) (xy 378.525002 -225.280342) (xy 378.516896 -225.229165)
			(xy 378.516388 -225.203258) (xy 378.516997 -225.175541) (xy 378.52631 -225.120895) (xy 378.53493 -225.094546)
			(xy 378.542804 -225.072448) (xy 378.337826 -224.71761) (xy 378.314966 -224.713292) (xy 378.290148 -224.708169)
			(xy 378.242405 -224.691172) (xy 378.197826 -224.667071) (xy 378.15746 -224.636431) (xy 378.122257 -224.599976)
			(xy 378.093048 -224.558564) (xy 378.070519 -224.51317) (xy 378.055201 -224.464863) (xy 378.047455 -224.414781)
			(xy 378.046996 -224.389442) (xy 377.766072 -224.389442) (xy 377.765564 -224.415329) (xy 377.757465 -224.466467)
			(xy 377.741466 -224.515707) (xy 377.71796 -224.561839) (xy 377.687528 -224.603726) (xy 377.650918 -224.640336)
			(xy 377.609031 -224.670768) (xy 377.562899 -224.694274) (xy 377.513659 -224.710273) (xy 377.462521 -224.718372)
			(xy 377.410747 -224.718372) (xy 377.359609 -224.710273) (xy 377.310369 -224.694274) (xy 377.264237 -224.670768)
			(xy 377.22235 -224.640336) (xy 377.18574 -224.603726) (xy 377.155308 -224.561839) (xy 377.131802 -224.515707)
			(xy 377.115803 -224.466467) (xy 377.107704 -224.415329) (xy 377.107196 -224.389442) (xy 376.826272 -224.389442)
			(xy 376.825725 -224.417149) (xy 376.816541 -224.471796) (xy 376.807984 -224.498154) (xy 376.80011 -224.520252)
			(xy 377.005088 -224.87509) (xy 377.027948 -224.879408) (xy 377.052771 -224.884565) (xy 377.100551 -224.90152)
			(xy 377.145171 -224.925592) (xy 377.185578 -224.956214) (xy 377.220819 -224.992662) (xy 377.250063 -225.034077)
			(xy 377.272619 -225.079482) (xy 377.287956 -225.127806) (xy 377.295711 -225.177908) (xy 377.296172 -225.203258)
			(xy 377.295664 -225.229165) (xy 377.287558 -225.280342) (xy 377.271546 -225.329621) (xy 377.248023 -225.375788)
			(xy 377.217567 -225.417707) (xy 377.180929 -225.454345) (xy 377.13901 -225.484801) (xy 377.092843 -225.508324)
			(xy 377.043564 -225.524336) (xy 376.992387 -225.532442) (xy 376.940573 -225.532442) (xy 376.889396 -225.524336)
			(xy 376.840117 -225.508324) (xy 376.79395 -225.484801) (xy 376.752031 -225.454345) (xy 376.715393 -225.417707)
			(xy 376.684937 -225.375788) (xy 376.661414 -225.329621) (xy 376.645402 -225.280342) (xy 376.637296 -225.229165)
			(xy 376.636788 -225.203258) (xy 376.637397 -225.175541) (xy 376.64671 -225.120895) (xy 376.65533 -225.094546)
			(xy 376.663204 -225.072448) (xy 376.458226 -224.71761) (xy 376.435366 -224.713292) (xy 376.410548 -224.708169)
			(xy 376.362805 -224.691172) (xy 376.318226 -224.667071) (xy 376.27786 -224.636431) (xy 376.242657 -224.599976)
			(xy 376.213448 -224.558564) (xy 376.190919 -224.51317) (xy 376.175601 -224.464863) (xy 376.167855 -224.414781)
			(xy 376.167396 -224.389442) (xy 375.886472 -224.389442) (xy 375.885964 -224.415329) (xy 375.877865 -224.466467)
			(xy 375.861866 -224.515707) (xy 375.83836 -224.561839) (xy 375.807928 -224.603726) (xy 375.771318 -224.640336)
			(xy 375.729431 -224.670768) (xy 375.683299 -224.694274) (xy 375.634059 -224.710273) (xy 375.582921 -224.718372)
			(xy 375.531147 -224.718372) (xy 375.480009 -224.710273) (xy 375.430769 -224.694274) (xy 375.384637 -224.670768)
			(xy 375.34275 -224.640336) (xy 375.30614 -224.603726) (xy 375.275708 -224.561839) (xy 375.252202 -224.515707)
			(xy 375.236203 -224.466467) (xy 375.228104 -224.415329) (xy 375.227596 -224.389442) (xy 374.946672 -224.389442)
			(xy 374.946125 -224.417149) (xy 374.936941 -224.471796) (xy 374.928384 -224.498154) (xy 374.92051 -224.520252)
			(xy 375.125488 -224.87509) (xy 375.148348 -224.879408) (xy 375.173171 -224.884565) (xy 375.220951 -224.90152)
			(xy 375.265571 -224.925592) (xy 375.305978 -224.956214) (xy 375.341219 -224.992662) (xy 375.370463 -225.034077)
			(xy 375.393019 -225.079482) (xy 375.408356 -225.127806) (xy 375.416111 -225.177908) (xy 375.416572 -225.203258)
			(xy 375.416064 -225.229165) (xy 375.407958 -225.280342) (xy 375.391946 -225.329621) (xy 375.368423 -225.375788)
			(xy 375.337967 -225.417707) (xy 375.301329 -225.454345) (xy 375.25941 -225.484801) (xy 375.213243 -225.508324)
			(xy 375.163964 -225.524336) (xy 375.112787 -225.532442) (xy 375.060973 -225.532442) (xy 375.009796 -225.524336)
			(xy 374.960517 -225.508324) (xy 374.91435 -225.484801) (xy 374.872431 -225.454345) (xy 374.835793 -225.417707)
			(xy 374.805337 -225.375788) (xy 374.781814 -225.329621) (xy 374.765802 -225.280342) (xy 374.757696 -225.229165)
			(xy 374.757188 -225.203258) (xy 374.757797 -225.175541) (xy 374.76711 -225.120895) (xy 374.77573 -225.094546)
			(xy 374.783604 -225.072448) (xy 374.578626 -224.71761) (xy 374.555766 -224.713292) (xy 374.530948 -224.708169)
			(xy 374.483205 -224.691172) (xy 374.438626 -224.667071) (xy 374.39826 -224.636431) (xy 374.363057 -224.599976)
			(xy 374.333848 -224.558564) (xy 374.311319 -224.51317) (xy 374.296001 -224.464863) (xy 374.288255 -224.414781)
			(xy 374.287796 -224.389442) (xy 374.006872 -224.389442) (xy 374.006364 -224.415329) (xy 373.998265 -224.466467)
			(xy 373.982266 -224.515707) (xy 373.95876 -224.561839) (xy 373.928328 -224.603726) (xy 373.891718 -224.640336)
			(xy 373.849831 -224.670768) (xy 373.803699 -224.694274) (xy 373.754459 -224.710273) (xy 373.703321 -224.718372)
			(xy 373.651547 -224.718372) (xy 373.600409 -224.710273) (xy 373.551169 -224.694274) (xy 373.505037 -224.670768)
			(xy 373.46315 -224.640336) (xy 373.42654 -224.603726) (xy 373.396108 -224.561839) (xy 373.372602 -224.515707)
			(xy 373.356603 -224.466467) (xy 373.348504 -224.415329) (xy 373.347996 -224.389442) (xy 373.067072 -224.389442)
			(xy 373.066525 -224.417149) (xy 373.057341 -224.471796) (xy 373.048784 -224.498154) (xy 373.04091 -224.520252)
			(xy 373.245888 -224.87509) (xy 373.268748 -224.879408) (xy 373.293571 -224.884565) (xy 373.341351 -224.90152)
			(xy 373.385971 -224.925592) (xy 373.426378 -224.956214) (xy 373.461619 -224.992662) (xy 373.490863 -225.034077)
			(xy 373.513419 -225.079482) (xy 373.528756 -225.127806) (xy 373.536511 -225.177908) (xy 373.536972 -225.203258)
			(xy 373.536464 -225.229165) (xy 373.528358 -225.280342) (xy 373.512346 -225.329621) (xy 373.488823 -225.375788)
			(xy 373.458367 -225.417707) (xy 373.421729 -225.454345) (xy 373.37981 -225.484801) (xy 373.333643 -225.508324)
			(xy 373.284364 -225.524336) (xy 373.233187 -225.532442) (xy 373.181373 -225.532442) (xy 373.130196 -225.524336)
			(xy 373.080917 -225.508324) (xy 373.03475 -225.484801) (xy 372.992831 -225.454345) (xy 372.956193 -225.417707)
			(xy 372.925737 -225.375788) (xy 372.902214 -225.329621) (xy 372.886202 -225.280342) (xy 372.878096 -225.229165)
			(xy 372.877588 -225.203258) (xy 372.878197 -225.175541) (xy 372.88751 -225.120895) (xy 372.89613 -225.094546)
			(xy 372.904004 -225.072448) (xy 372.699026 -224.71761) (xy 372.676166 -224.713292) (xy 372.651348 -224.708169)
			(xy 372.603605 -224.691172) (xy 372.559026 -224.667071) (xy 372.51866 -224.636431) (xy 372.483457 -224.599976)
			(xy 372.454248 -224.558564) (xy 372.431719 -224.51317) (xy 372.416401 -224.464863) (xy 372.408655 -224.414781)
			(xy 372.408196 -224.389442) (xy 372.127272 -224.389442) (xy 372.126764 -224.415329) (xy 372.118665 -224.466467)
			(xy 372.102666 -224.515707) (xy 372.07916 -224.561839) (xy 372.048728 -224.603726) (xy 372.012118 -224.640336)
			(xy 371.970231 -224.670768) (xy 371.924099 -224.694274) (xy 371.874859 -224.710273) (xy 371.823721 -224.718372)
			(xy 371.771947 -224.718372) (xy 371.720809 -224.710273) (xy 371.671569 -224.694274) (xy 371.625437 -224.670768)
			(xy 371.58355 -224.640336) (xy 371.54694 -224.603726) (xy 371.516508 -224.561839) (xy 371.493002 -224.515707)
			(xy 371.477003 -224.466467) (xy 371.468904 -224.415329) (xy 371.468396 -224.389442) (xy 371.187472 -224.389442)
			(xy 371.186925 -224.417149) (xy 371.177741 -224.471796) (xy 371.169184 -224.498154) (xy 371.16131 -224.520252)
			(xy 371.366288 -224.87509) (xy 371.389148 -224.879408) (xy 371.413971 -224.884565) (xy 371.461751 -224.90152)
			(xy 371.506371 -224.925592) (xy 371.546778 -224.956214) (xy 371.582019 -224.992662) (xy 371.611263 -225.034077)
			(xy 371.633819 -225.079482) (xy 371.649156 -225.127806) (xy 371.656911 -225.177908) (xy 371.657372 -225.203258)
			(xy 371.656864 -225.229165) (xy 371.648758 -225.280342) (xy 371.632746 -225.329621) (xy 371.609223 -225.375788)
			(xy 371.578767 -225.417707) (xy 371.542129 -225.454345) (xy 371.50021 -225.484801) (xy 371.454043 -225.508324)
			(xy 371.404764 -225.524336) (xy 371.353587 -225.532442) (xy 371.301773 -225.532442) (xy 371.250596 -225.524336)
			(xy 371.201317 -225.508324) (xy 371.15515 -225.484801) (xy 371.113231 -225.454345) (xy 371.076593 -225.417707)
			(xy 371.046137 -225.375788) (xy 371.022614 -225.329621) (xy 371.006602 -225.280342) (xy 370.998496 -225.229165)
			(xy 370.997988 -225.203258) (xy 370.998597 -225.175541) (xy 371.00791 -225.120895) (xy 371.01653 -225.094546)
			(xy 371.024404 -225.072448) (xy 370.819426 -224.71761) (xy 370.796566 -224.713292) (xy 370.771748 -224.708169)
			(xy 370.724005 -224.691172) (xy 370.679426 -224.667071) (xy 370.63906 -224.636431) (xy 370.603857 -224.599976)
			(xy 370.574648 -224.558564) (xy 370.552119 -224.51317) (xy 370.536801 -224.464863) (xy 370.529055 -224.414781)
			(xy 370.528596 -224.389442) (xy 370.247672 -224.389442) (xy 370.247164 -224.415329) (xy 370.239065 -224.466467)
			(xy 370.223066 -224.515707) (xy 370.19956 -224.561839) (xy 370.169128 -224.603726) (xy 370.132518 -224.640336)
			(xy 370.090631 -224.670768) (xy 370.044499 -224.694274) (xy 369.995259 -224.710273) (xy 369.944121 -224.718372)
			(xy 369.892347 -224.718372) (xy 369.841209 -224.710273) (xy 369.791969 -224.694274) (xy 369.745837 -224.670768)
			(xy 369.70395 -224.640336) (xy 369.66734 -224.603726) (xy 369.636908 -224.561839) (xy 369.613402 -224.515707)
			(xy 369.597403 -224.466467) (xy 369.589304 -224.415329) (xy 369.588796 -224.389442) (xy 369.307872 -224.389442)
			(xy 369.307325 -224.417149) (xy 369.298141 -224.471796) (xy 369.289584 -224.498154) (xy 369.28171 -224.520252)
			(xy 369.486688 -224.87509) (xy 369.509548 -224.879408) (xy 369.534371 -224.884565) (xy 369.582151 -224.90152)
			(xy 369.626771 -224.925592) (xy 369.667178 -224.956214) (xy 369.702419 -224.992662) (xy 369.731663 -225.034077)
			(xy 369.754219 -225.079482) (xy 369.769556 -225.127806) (xy 369.777311 -225.177908) (xy 369.777772 -225.203258)
			(xy 369.777264 -225.229165) (xy 369.769158 -225.280342) (xy 369.753146 -225.329621) (xy 369.729623 -225.375788)
			(xy 369.699167 -225.417707) (xy 369.662529 -225.454345) (xy 369.62061 -225.484801) (xy 369.574443 -225.508324)
			(xy 369.525164 -225.524336) (xy 369.473987 -225.532442) (xy 369.422173 -225.532442) (xy 369.370996 -225.524336)
			(xy 369.321717 -225.508324) (xy 369.27555 -225.484801) (xy 369.233631 -225.454345) (xy 369.196993 -225.417707)
			(xy 369.166537 -225.375788) (xy 369.143014 -225.329621) (xy 369.127002 -225.280342) (xy 369.118896 -225.229165)
			(xy 369.118388 -225.203258) (xy 369.118997 -225.175541) (xy 369.12831 -225.120895) (xy 369.13693 -225.094546)
			(xy 369.144804 -225.072448) (xy 368.939826 -224.71761) (xy 368.916966 -224.713292) (xy 368.892148 -224.708169)
			(xy 368.844405 -224.691172) (xy 368.799826 -224.667071) (xy 368.75946 -224.636431) (xy 368.724257 -224.599976)
			(xy 368.695048 -224.558564) (xy 368.672519 -224.51317) (xy 368.657201 -224.464863) (xy 368.649455 -224.414781)
			(xy 368.648996 -224.389442) (xy 368.368072 -224.389442) (xy 368.367564 -224.415329) (xy 368.359465 -224.466467)
			(xy 368.343466 -224.515707) (xy 368.31996 -224.561839) (xy 368.289528 -224.603726) (xy 368.252918 -224.640336)
			(xy 368.211031 -224.670768) (xy 368.164899 -224.694274) (xy 368.115659 -224.710273) (xy 368.064521 -224.718372)
			(xy 368.012747 -224.718372) (xy 367.961609 -224.710273) (xy 367.912369 -224.694274) (xy 367.866237 -224.670768)
			(xy 367.82435 -224.640336) (xy 367.78774 -224.603726) (xy 367.757308 -224.561839) (xy 367.733802 -224.515707)
			(xy 367.717803 -224.466467) (xy 367.709704 -224.415329) (xy 367.709196 -224.389442) (xy 367.428272 -224.389442)
			(xy 367.427725 -224.417149) (xy 367.418541 -224.471796) (xy 367.409984 -224.498154) (xy 367.40211 -224.520252)
			(xy 367.607088 -224.87509) (xy 367.629948 -224.879408) (xy 367.654771 -224.884565) (xy 367.702551 -224.90152)
			(xy 367.747171 -224.925592) (xy 367.787578 -224.956214) (xy 367.822819 -224.992662) (xy 367.852063 -225.034077)
			(xy 367.874619 -225.079482) (xy 367.889956 -225.127806) (xy 367.897711 -225.177908) (xy 367.898172 -225.203258)
			(xy 367.897664 -225.229165) (xy 367.889558 -225.280342) (xy 367.873546 -225.329621) (xy 367.850023 -225.375788)
			(xy 367.819567 -225.417707) (xy 367.782929 -225.454345) (xy 367.74101 -225.484801) (xy 367.694843 -225.508324)
			(xy 367.645564 -225.524336) (xy 367.594387 -225.532442) (xy 367.542573 -225.532442) (xy 367.491396 -225.524336)
			(xy 367.442117 -225.508324) (xy 367.39595 -225.484801) (xy 367.354031 -225.454345) (xy 367.317393 -225.417707)
			(xy 367.286937 -225.375788) (xy 367.263414 -225.329621) (xy 367.247402 -225.280342) (xy 367.239296 -225.229165)
			(xy 367.238788 -225.203258) (xy 367.239397 -225.175541) (xy 367.24871 -225.120895) (xy 367.25733 -225.094546)
			(xy 367.265204 -225.072448) (xy 367.060226 -224.71761) (xy 367.037366 -224.713292) (xy 367.012548 -224.708169)
			(xy 366.964805 -224.691172) (xy 366.920226 -224.667071) (xy 366.87986 -224.636431) (xy 366.844657 -224.599976)
			(xy 366.815448 -224.558564) (xy 366.792919 -224.51317) (xy 366.777601 -224.464863) (xy 366.769855 -224.414781)
			(xy 366.769396 -224.389442) (xy 366.488472 -224.389442) (xy 366.487964 -224.415329) (xy 366.479865 -224.466467)
			(xy 366.463866 -224.515707) (xy 366.44036 -224.561839) (xy 366.409928 -224.603726) (xy 366.373318 -224.640336)
			(xy 366.331431 -224.670768) (xy 366.285299 -224.694274) (xy 366.236059 -224.710273) (xy 366.184921 -224.718372)
			(xy 366.133147 -224.718372) (xy 366.082009 -224.710273) (xy 366.032769 -224.694274) (xy 365.986637 -224.670768)
			(xy 365.94475 -224.640336) (xy 365.90814 -224.603726) (xy 365.877708 -224.561839) (xy 365.854202 -224.515707)
			(xy 365.838203 -224.466467) (xy 365.830104 -224.415329) (xy 365.829596 -224.389442) (xy 365.548672 -224.389442)
			(xy 365.548125 -224.417149) (xy 365.538941 -224.471796) (xy 365.530384 -224.498154) (xy 365.52251 -224.520252)
			(xy 365.727488 -224.87509) (xy 365.750348 -224.879408) (xy 365.775171 -224.884565) (xy 365.822951 -224.90152)
			(xy 365.867571 -224.925592) (xy 365.907978 -224.956214) (xy 365.943219 -224.992662) (xy 365.972463 -225.034077)
			(xy 365.995019 -225.079482) (xy 366.010356 -225.127806) (xy 366.018111 -225.177908) (xy 366.018572 -225.203258)
			(xy 366.018064 -225.229165) (xy 366.009958 -225.280342) (xy 365.993946 -225.329621) (xy 365.970423 -225.375788)
			(xy 365.939967 -225.417707) (xy 365.903329 -225.454345) (xy 365.86141 -225.484801) (xy 365.815243 -225.508324)
			(xy 365.765964 -225.524336) (xy 365.714787 -225.532442) (xy 365.662973 -225.532442) (xy 365.611796 -225.524336)
			(xy 365.562517 -225.508324) (xy 365.51635 -225.484801) (xy 365.474431 -225.454345) (xy 365.437793 -225.417707)
			(xy 365.407337 -225.375788) (xy 365.383814 -225.329621) (xy 365.367802 -225.280342) (xy 365.359696 -225.229165)
			(xy 365.359188 -225.203258) (xy 365.359797 -225.175541) (xy 365.36911 -225.120895) (xy 365.37773 -225.094546)
			(xy 365.385604 -225.072448) (xy 365.180626 -224.71761) (xy 365.157766 -224.713292) (xy 365.132948 -224.708169)
			(xy 365.085205 -224.691172) (xy 365.040626 -224.667071) (xy 365.00026 -224.636431) (xy 364.965057 -224.599976)
			(xy 364.935848 -224.558564) (xy 364.913319 -224.51317) (xy 364.898001 -224.464863) (xy 364.890255 -224.414781)
			(xy 364.889796 -224.389442) (xy 364.608872 -224.389442) (xy 364.608364 -224.415329) (xy 364.600265 -224.466467)
			(xy 364.584266 -224.515707) (xy 364.56076 -224.561839) (xy 364.530328 -224.603726) (xy 364.493718 -224.640336)
			(xy 364.451831 -224.670768) (xy 364.405699 -224.694274) (xy 364.356459 -224.710273) (xy 364.305321 -224.718372)
			(xy 364.253547 -224.718372) (xy 364.202409 -224.710273) (xy 364.153169 -224.694274) (xy 364.107037 -224.670768)
			(xy 364.06515 -224.640336) (xy 364.02854 -224.603726) (xy 363.998108 -224.561839) (xy 363.974602 -224.515707)
			(xy 363.958603 -224.466467) (xy 363.950504 -224.415329) (xy 363.949996 -224.389442) (xy 363.669072 -224.389442)
			(xy 363.668525 -224.417149) (xy 363.659341 -224.471796) (xy 363.650784 -224.498154) (xy 363.64291 -224.520252)
			(xy 363.847888 -224.87509) (xy 363.870748 -224.879408) (xy 363.895571 -224.884565) (xy 363.943351 -224.90152)
			(xy 363.987971 -224.925592) (xy 364.028378 -224.956214) (xy 364.063619 -224.992662) (xy 364.092863 -225.034077)
			(xy 364.115419 -225.079482) (xy 364.130756 -225.127806) (xy 364.138511 -225.177908) (xy 364.138972 -225.203258)
			(xy 364.138464 -225.229165) (xy 364.130358 -225.280342) (xy 364.114346 -225.329621) (xy 364.090823 -225.375788)
			(xy 364.060367 -225.417707) (xy 364.023729 -225.454345) (xy 363.98181 -225.484801) (xy 363.935643 -225.508324)
			(xy 363.886364 -225.524336) (xy 363.835187 -225.532442) (xy 363.783373 -225.532442) (xy 363.732196 -225.524336)
			(xy 363.682917 -225.508324) (xy 363.63675 -225.484801) (xy 363.594831 -225.454345) (xy 363.558193 -225.417707)
			(xy 363.527737 -225.375788) (xy 363.504214 -225.329621) (xy 363.488202 -225.280342) (xy 363.480096 -225.229165)
			(xy 363.479588 -225.203258) (xy 363.480197 -225.175541) (xy 363.48951 -225.120895) (xy 363.49813 -225.094546)
			(xy 363.506004 -225.072448) (xy 363.301026 -224.71761) (xy 363.278166 -224.713292) (xy 363.253348 -224.708169)
			(xy 363.205605 -224.691172) (xy 363.161026 -224.667071) (xy 363.12066 -224.636431) (xy 363.085457 -224.599976)
			(xy 363.056248 -224.558564) (xy 363.033719 -224.51317) (xy 363.018401 -224.464863) (xy 363.010655 -224.414781)
			(xy 363.010196 -224.389442) (xy 362.729272 -224.389442) (xy 362.728764 -224.415329) (xy 362.720665 -224.466467)
			(xy 362.704666 -224.515707) (xy 362.68116 -224.561839) (xy 362.650728 -224.603726) (xy 362.614118 -224.640336)
			(xy 362.572231 -224.670768) (xy 362.526099 -224.694274) (xy 362.476859 -224.710273) (xy 362.425721 -224.718372)
			(xy 362.373947 -224.718372) (xy 362.322809 -224.710273) (xy 362.273569 -224.694274) (xy 362.227437 -224.670768)
			(xy 362.18555 -224.640336) (xy 362.14894 -224.603726) (xy 362.118508 -224.561839) (xy 362.095002 -224.515707)
			(xy 362.079003 -224.466467) (xy 362.070904 -224.415329) (xy 362.070396 -224.389442) (xy 361.789472 -224.389442)
			(xy 361.788925 -224.417149) (xy 361.779741 -224.471796) (xy 361.771184 -224.498154) (xy 361.76331 -224.520252)
			(xy 361.968288 -224.87509) (xy 361.991148 -224.879408) (xy 362.015971 -224.884565) (xy 362.063751 -224.90152)
			(xy 362.108371 -224.925592) (xy 362.148778 -224.956214) (xy 362.184019 -224.992662) (xy 362.213263 -225.034077)
			(xy 362.235819 -225.079482) (xy 362.251156 -225.127806) (xy 362.258911 -225.177908) (xy 362.259372 -225.203258)
			(xy 362.258864 -225.229165) (xy 362.250758 -225.280342) (xy 362.234746 -225.329621) (xy 362.211223 -225.375788)
			(xy 362.180767 -225.417707) (xy 362.144129 -225.454345) (xy 362.10221 -225.484801) (xy 362.056043 -225.508324)
			(xy 362.006764 -225.524336) (xy 361.955587 -225.532442) (xy 361.903773 -225.532442) (xy 361.852596 -225.524336)
			(xy 361.803317 -225.508324) (xy 361.75715 -225.484801) (xy 361.715231 -225.454345) (xy 361.678593 -225.417707)
			(xy 361.648137 -225.375788) (xy 361.624614 -225.329621) (xy 361.608602 -225.280342) (xy 361.600496 -225.229165)
			(xy 361.599988 -225.203258) (xy 361.600597 -225.175541) (xy 361.60991 -225.120895) (xy 361.61853 -225.094546)
			(xy 361.626404 -225.072448) (xy 361.421426 -224.71761) (xy 361.398566 -224.713292) (xy 361.373748 -224.708169)
			(xy 361.326005 -224.691172) (xy 361.281426 -224.667071) (xy 361.24106 -224.636431) (xy 361.205857 -224.599976)
			(xy 361.176648 -224.558564) (xy 361.154119 -224.51317) (xy 361.138801 -224.464863) (xy 361.131055 -224.414781)
			(xy 361.130596 -224.389442) (xy 360.849672 -224.389442) (xy 360.849164 -224.415329) (xy 360.841065 -224.466467)
			(xy 360.825066 -224.515707) (xy 360.80156 -224.561839) (xy 360.771128 -224.603726) (xy 360.734518 -224.640336)
			(xy 360.692631 -224.670768) (xy 360.646499 -224.694274) (xy 360.597259 -224.710273) (xy 360.546121 -224.718372)
			(xy 360.494347 -224.718372) (xy 360.443209 -224.710273) (xy 360.393969 -224.694274) (xy 360.347837 -224.670768)
			(xy 360.30595 -224.640336) (xy 360.26934 -224.603726) (xy 360.238908 -224.561839) (xy 360.215402 -224.515707)
			(xy 360.199403 -224.466467) (xy 360.191304 -224.415329) (xy 360.190796 -224.389442) (xy 359.909872 -224.389442)
			(xy 359.909325 -224.417149) (xy 359.900141 -224.471796) (xy 359.891584 -224.498154) (xy 359.88371 -224.520252)
			(xy 360.088688 -224.87509) (xy 360.111548 -224.879408) (xy 360.136371 -224.884565) (xy 360.184151 -224.90152)
			(xy 360.228771 -224.925592) (xy 360.269178 -224.956214) (xy 360.304419 -224.992662) (xy 360.333663 -225.034077)
			(xy 360.356219 -225.079482) (xy 360.371556 -225.127806) (xy 360.379311 -225.177908) (xy 360.379772 -225.203258)
			(xy 360.379264 -225.229165) (xy 360.371158 -225.280342) (xy 360.355146 -225.329621) (xy 360.331623 -225.375788)
			(xy 360.301167 -225.417707) (xy 360.264529 -225.454345) (xy 360.22261 -225.484801) (xy 360.176443 -225.508324)
			(xy 360.127164 -225.524336) (xy 360.075987 -225.532442) (xy 360.024173 -225.532442) (xy 359.972996 -225.524336)
			(xy 359.923717 -225.508324) (xy 359.87755 -225.484801) (xy 359.835631 -225.454345) (xy 359.798993 -225.417707)
			(xy 359.768537 -225.375788) (xy 359.745014 -225.329621) (xy 359.729002 -225.280342) (xy 359.720896 -225.229165)
			(xy 359.720388 -225.203258) (xy 359.720997 -225.175541) (xy 359.73031 -225.120895) (xy 359.73893 -225.094546)
			(xy 359.746804 -225.072448) (xy 359.541826 -224.71761) (xy 359.518966 -224.713292) (xy 359.494148 -224.708169)
			(xy 359.446405 -224.691172) (xy 359.401826 -224.667071) (xy 359.36146 -224.636431) (xy 359.326257 -224.599976)
			(xy 359.297048 -224.558564) (xy 359.274519 -224.51317) (xy 359.259201 -224.464863) (xy 359.251455 -224.414781)
			(xy 359.250996 -224.389442) (xy 358.970072 -224.389442) (xy 358.969564 -224.415329) (xy 358.961465 -224.466467)
			(xy 358.945466 -224.515707) (xy 358.92196 -224.561839) (xy 358.891528 -224.603726) (xy 358.854918 -224.640336)
			(xy 358.813031 -224.670768) (xy 358.766899 -224.694274) (xy 358.717659 -224.710273) (xy 358.666521 -224.718372)
			(xy 358.614747 -224.718372) (xy 358.563609 -224.710273) (xy 358.514369 -224.694274) (xy 358.468237 -224.670768)
			(xy 358.42635 -224.640336) (xy 358.38974 -224.603726) (xy 358.359308 -224.561839) (xy 358.335802 -224.515707)
			(xy 358.319803 -224.466467) (xy 358.311704 -224.415329) (xy 358.311196 -224.389442) (xy 358.030272 -224.389442)
			(xy 358.029725 -224.417149) (xy 358.020541 -224.471796) (xy 358.011984 -224.498154) (xy 358.00411 -224.520252)
			(xy 358.209088 -224.87509) (xy 358.231948 -224.879408) (xy 358.256771 -224.884565) (xy 358.304551 -224.90152)
			(xy 358.349171 -224.925592) (xy 358.389578 -224.956214) (xy 358.424819 -224.992662) (xy 358.454063 -225.034077)
			(xy 358.476619 -225.079482) (xy 358.491956 -225.127806) (xy 358.499711 -225.177908) (xy 358.500172 -225.203258)
			(xy 358.499664 -225.229165) (xy 358.491558 -225.280342) (xy 358.475546 -225.329621) (xy 358.452023 -225.375788)
			(xy 358.421567 -225.417707) (xy 358.384929 -225.454345) (xy 358.34301 -225.484801) (xy 358.296843 -225.508324)
			(xy 358.247564 -225.524336) (xy 358.196387 -225.532442) (xy 358.144573 -225.532442) (xy 358.093396 -225.524336)
			(xy 358.044117 -225.508324) (xy 357.99795 -225.484801) (xy 357.956031 -225.454345) (xy 357.919393 -225.417707)
			(xy 357.888937 -225.375788) (xy 357.865414 -225.329621) (xy 357.849402 -225.280342) (xy 357.841296 -225.229165)
			(xy 357.840788 -225.203258) (xy 357.841397 -225.175541) (xy 357.85071 -225.120895) (xy 357.85933 -225.094546)
			(xy 357.867204 -225.072448) (xy 357.662226 -224.71761) (xy 357.639366 -224.713292) (xy 357.614548 -224.708169)
			(xy 357.566805 -224.691172) (xy 357.522226 -224.667071) (xy 357.48186 -224.636431) (xy 357.446657 -224.599976)
			(xy 357.417448 -224.558564) (xy 357.394919 -224.51317) (xy 357.379601 -224.464863) (xy 357.371855 -224.414781)
			(xy 357.371396 -224.389442) (xy 357.090472 -224.389442) (xy 357.089964 -224.415329) (xy 357.081865 -224.466467)
			(xy 357.065866 -224.515707) (xy 357.04236 -224.561839) (xy 357.011928 -224.603726) (xy 356.975318 -224.640336)
			(xy 356.933431 -224.670768) (xy 356.887299 -224.694274) (xy 356.838059 -224.710273) (xy 356.786921 -224.718372)
			(xy 356.735147 -224.718372) (xy 356.684009 -224.710273) (xy 356.634769 -224.694274) (xy 356.588637 -224.670768)
			(xy 356.54675 -224.640336) (xy 356.51014 -224.603726) (xy 356.479708 -224.561839) (xy 356.456202 -224.515707)
			(xy 356.440203 -224.466467) (xy 356.432104 -224.415329) (xy 356.431596 -224.389442) (xy 356.150672 -224.389442)
			(xy 356.150125 -224.417149) (xy 356.140941 -224.471796) (xy 356.132384 -224.498154) (xy 356.12451 -224.520252)
			(xy 356.329488 -224.87509) (xy 356.352348 -224.879408) (xy 356.377171 -224.884565) (xy 356.424951 -224.90152)
			(xy 356.469571 -224.925592) (xy 356.509978 -224.956214) (xy 356.545219 -224.992662) (xy 356.574463 -225.034077)
			(xy 356.597019 -225.079482) (xy 356.612356 -225.127806) (xy 356.620111 -225.177908) (xy 356.620572 -225.203258)
			(xy 356.620064 -225.229165) (xy 356.611958 -225.280342) (xy 356.595946 -225.329621) (xy 356.572423 -225.375788)
			(xy 356.541967 -225.417707) (xy 356.505329 -225.454345) (xy 356.46341 -225.484801) (xy 356.417243 -225.508324)
			(xy 356.367964 -225.524336) (xy 356.316787 -225.532442) (xy 356.264973 -225.532442) (xy 356.213796 -225.524336)
			(xy 356.164517 -225.508324) (xy 356.11835 -225.484801) (xy 356.076431 -225.454345) (xy 356.039793 -225.417707)
			(xy 356.009337 -225.375788) (xy 355.985814 -225.329621) (xy 355.969802 -225.280342) (xy 355.961696 -225.229165)
			(xy 355.961188 -225.203258) (xy 355.961797 -225.175541) (xy 355.97111 -225.120895) (xy 355.97973 -225.094546)
			(xy 355.987604 -225.072448) (xy 355.782626 -224.71761) (xy 355.759766 -224.713292) (xy 355.734948 -224.708169)
			(xy 355.687205 -224.691172) (xy 355.642626 -224.667071) (xy 355.60226 -224.636431) (xy 355.567057 -224.599976)
			(xy 355.537848 -224.558564) (xy 355.515319 -224.51317) (xy 355.500001 -224.464863) (xy 355.492255 -224.414781)
			(xy 355.491796 -224.389442) (xy 355.210872 -224.389442) (xy 355.210364 -224.415329) (xy 355.202265 -224.466467)
			(xy 355.186266 -224.515707) (xy 355.16276 -224.561839) (xy 355.132328 -224.603726) (xy 355.095718 -224.640336)
			(xy 355.053831 -224.670768) (xy 355.007699 -224.694274) (xy 354.958459 -224.710273) (xy 354.907321 -224.718372)
			(xy 354.855547 -224.718372) (xy 354.804409 -224.710273) (xy 354.755169 -224.694274) (xy 354.709037 -224.670768)
			(xy 354.66715 -224.640336) (xy 354.63054 -224.603726) (xy 354.600108 -224.561839) (xy 354.576602 -224.515707)
			(xy 354.560603 -224.466467) (xy 354.552504 -224.415329) (xy 354.551996 -224.389442) (xy 354.271072 -224.389442)
			(xy 354.270525 -224.417149) (xy 354.261341 -224.471796) (xy 354.252784 -224.498154) (xy 354.24491 -224.520252)
			(xy 354.449888 -224.87509) (xy 354.472748 -224.879408) (xy 354.497571 -224.884565) (xy 354.545351 -224.90152)
			(xy 354.589971 -224.925592) (xy 354.630378 -224.956214) (xy 354.665619 -224.992662) (xy 354.694863 -225.034077)
			(xy 354.717419 -225.079482) (xy 354.732756 -225.127806) (xy 354.740511 -225.177908) (xy 354.740972 -225.203258)
			(xy 354.740464 -225.229165) (xy 354.732358 -225.280342) (xy 354.716346 -225.329621) (xy 354.692823 -225.375788)
			(xy 354.662367 -225.417707) (xy 354.625729 -225.454345) (xy 354.58381 -225.484801) (xy 354.537643 -225.508324)
			(xy 354.488364 -225.524336) (xy 354.437187 -225.532442) (xy 354.385373 -225.532442) (xy 354.334196 -225.524336)
			(xy 354.284917 -225.508324) (xy 354.23875 -225.484801) (xy 354.196831 -225.454345) (xy 354.160193 -225.417707)
			(xy 354.129737 -225.375788) (xy 354.106214 -225.329621) (xy 354.090202 -225.280342) (xy 354.082096 -225.229165)
			(xy 354.081588 -225.203258) (xy 354.082197 -225.175541) (xy 354.09151 -225.120895) (xy 354.10013 -225.094546)
			(xy 354.108004 -225.072448) (xy 353.903026 -224.71761) (xy 353.880166 -224.713292) (xy 353.855348 -224.708169)
			(xy 353.807605 -224.691172) (xy 353.763026 -224.667071) (xy 353.72266 -224.636431) (xy 353.687457 -224.599976)
			(xy 353.658248 -224.558564) (xy 353.635719 -224.51317) (xy 353.620401 -224.464863) (xy 353.612655 -224.414781)
			(xy 353.612196 -224.389442) (xy 353.331272 -224.389442) (xy 353.330764 -224.415329) (xy 353.322665 -224.466467)
			(xy 353.306666 -224.515707) (xy 353.28316 -224.561839) (xy 353.252728 -224.603726) (xy 353.216118 -224.640336)
			(xy 353.174231 -224.670768) (xy 353.128099 -224.694274) (xy 353.078859 -224.710273) (xy 353.027721 -224.718372)
			(xy 352.975947 -224.718372) (xy 352.924809 -224.710273) (xy 352.875569 -224.694274) (xy 352.829437 -224.670768)
			(xy 352.78755 -224.640336) (xy 352.75094 -224.603726) (xy 352.720508 -224.561839) (xy 352.697002 -224.515707)
			(xy 352.681003 -224.466467) (xy 352.672904 -224.415329) (xy 352.672396 -224.389442) (xy 352.391472 -224.389442)
			(xy 352.390925 -224.417149) (xy 352.381741 -224.471796) (xy 352.373184 -224.498154) (xy 352.36531 -224.520252)
			(xy 352.570288 -224.87509) (xy 352.593148 -224.879408) (xy 352.617971 -224.884565) (xy 352.665751 -224.90152)
			(xy 352.710371 -224.925592) (xy 352.750778 -224.956214) (xy 352.786019 -224.992662) (xy 352.815263 -225.034077)
			(xy 352.837819 -225.079482) (xy 352.853156 -225.127806) (xy 352.860911 -225.177908) (xy 352.861372 -225.203258)
			(xy 352.860864 -225.229165) (xy 352.852758 -225.280342) (xy 352.836746 -225.329621) (xy 352.813223 -225.375788)
			(xy 352.782767 -225.417707) (xy 352.746129 -225.454345) (xy 352.70421 -225.484801) (xy 352.658043 -225.508324)
			(xy 352.608764 -225.524336) (xy 352.557587 -225.532442) (xy 352.505773 -225.532442) (xy 352.454596 -225.524336)
			(xy 352.405317 -225.508324) (xy 352.35915 -225.484801) (xy 352.317231 -225.454345) (xy 352.280593 -225.417707)
			(xy 352.250137 -225.375788) (xy 352.226614 -225.329621) (xy 352.210602 -225.280342) (xy 352.202496 -225.229165)
			(xy 352.201988 -225.203258) (xy 352.202597 -225.175541) (xy 352.21191 -225.120895) (xy 352.22053 -225.094546)
			(xy 352.228404 -225.072448) (xy 352.023426 -224.71761) (xy 352.000566 -224.713292) (xy 351.975748 -224.708169)
			(xy 351.928005 -224.691172) (xy 351.883426 -224.667071) (xy 351.84306 -224.636431) (xy 351.807857 -224.599976)
			(xy 351.778648 -224.558564) (xy 351.756119 -224.51317) (xy 351.740801 -224.464863) (xy 351.733055 -224.414781)
			(xy 351.732596 -224.389442) (xy 351.451672 -224.389442) (xy 351.451164 -224.415329) (xy 351.443065 -224.466467)
			(xy 351.427066 -224.515707) (xy 351.40356 -224.561839) (xy 351.373128 -224.603726) (xy 351.336518 -224.640336)
			(xy 351.294631 -224.670768) (xy 351.248499 -224.694274) (xy 351.199259 -224.710273) (xy 351.148121 -224.718372)
			(xy 351.096347 -224.718372) (xy 351.045209 -224.710273) (xy 350.995969 -224.694274) (xy 350.949837 -224.670768)
			(xy 350.90795 -224.640336) (xy 350.87134 -224.603726) (xy 350.840908 -224.561839) (xy 350.817402 -224.515707)
			(xy 350.801403 -224.466467) (xy 350.793304 -224.415329) (xy 350.792796 -224.389442) (xy 350.511872 -224.389442)
			(xy 350.511325 -224.417149) (xy 350.502141 -224.471796) (xy 350.493584 -224.498154) (xy 350.48571 -224.520252)
			(xy 350.690688 -224.87509) (xy 350.713548 -224.879408) (xy 350.738371 -224.884565) (xy 350.786151 -224.90152)
			(xy 350.830771 -224.925592) (xy 350.871178 -224.956214) (xy 350.906419 -224.992662) (xy 350.935663 -225.034077)
			(xy 350.958219 -225.079482) (xy 350.973556 -225.127806) (xy 350.981311 -225.177908) (xy 350.981772 -225.203258)
			(xy 350.981264 -225.229165) (xy 350.973158 -225.280342) (xy 350.957146 -225.329621) (xy 350.933623 -225.375788)
			(xy 350.903167 -225.417707) (xy 350.866529 -225.454345) (xy 350.82461 -225.484801) (xy 350.778443 -225.508324)
			(xy 350.729164 -225.524336) (xy 350.677987 -225.532442) (xy 350.626173 -225.532442) (xy 350.574996 -225.524336)
			(xy 350.525717 -225.508324) (xy 350.47955 -225.484801) (xy 350.437631 -225.454345) (xy 350.400993 -225.417707)
			(xy 350.370537 -225.375788) (xy 350.347014 -225.329621) (xy 350.331002 -225.280342) (xy 350.322896 -225.229165)
			(xy 350.322388 -225.203258) (xy 350.322997 -225.175541) (xy 350.33231 -225.120895) (xy 350.34093 -225.094546)
			(xy 350.348804 -225.072448) (xy 350.143826 -224.71761) (xy 350.120966 -224.713292) (xy 350.096148 -224.708169)
			(xy 350.048405 -224.691172) (xy 350.003826 -224.667071) (xy 349.96346 -224.636431) (xy 349.928257 -224.599976)
			(xy 349.899048 -224.558564) (xy 349.876519 -224.51317) (xy 349.861201 -224.464863) (xy 349.853455 -224.414781)
			(xy 349.852996 -224.389442) (xy 349.572072 -224.389442) (xy 349.571564 -224.415329) (xy 349.563465 -224.466467)
			(xy 349.547466 -224.515707) (xy 349.52396 -224.561839) (xy 349.493528 -224.603726) (xy 349.456918 -224.640336)
			(xy 349.415031 -224.670768) (xy 349.368899 -224.694274) (xy 349.319659 -224.710273) (xy 349.268521 -224.718372)
			(xy 349.216747 -224.718372) (xy 349.165609 -224.710273) (xy 349.116369 -224.694274) (xy 349.070237 -224.670768)
			(xy 349.02835 -224.640336) (xy 348.99174 -224.603726) (xy 348.961308 -224.561839) (xy 348.937802 -224.515707)
			(xy 348.921803 -224.466467) (xy 348.913704 -224.415329) (xy 348.913196 -224.389442) (xy 348.632272 -224.389442)
			(xy 348.631725 -224.417149) (xy 348.622541 -224.471796) (xy 348.613984 -224.498154) (xy 348.60611 -224.520252)
			(xy 348.811088 -224.87509) (xy 348.833948 -224.879408) (xy 348.858771 -224.884565) (xy 348.906551 -224.90152)
			(xy 348.951171 -224.925592) (xy 348.991578 -224.956214) (xy 349.026819 -224.992662) (xy 349.056063 -225.034077)
			(xy 349.078619 -225.079482) (xy 349.093956 -225.127806) (xy 349.101711 -225.177908) (xy 349.102172 -225.203258)
			(xy 349.101664 -225.229165) (xy 349.093558 -225.280342) (xy 349.077546 -225.329621) (xy 349.054023 -225.375788)
			(xy 349.023567 -225.417707) (xy 348.986929 -225.454345) (xy 348.94501 -225.484801) (xy 348.898843 -225.508324)
			(xy 348.849564 -225.524336) (xy 348.798387 -225.532442) (xy 348.746573 -225.532442) (xy 348.695396 -225.524336)
			(xy 348.646117 -225.508324) (xy 348.59995 -225.484801) (xy 348.558031 -225.454345) (xy 348.521393 -225.417707)
			(xy 348.490937 -225.375788) (xy 348.467414 -225.329621) (xy 348.451402 -225.280342) (xy 348.443296 -225.229165)
			(xy 348.442788 -225.203258) (xy 348.443397 -225.175541) (xy 348.45271 -225.120895) (xy 348.46133 -225.094546)
			(xy 348.469204 -225.072448) (xy 348.264226 -224.71761) (xy 348.241366 -224.713292) (xy 348.216548 -224.708169)
			(xy 348.168805 -224.691172) (xy 348.124226 -224.667071) (xy 348.08386 -224.636431) (xy 348.048657 -224.599976)
			(xy 348.019448 -224.558564) (xy 347.996919 -224.51317) (xy 347.981601 -224.464863) (xy 347.973855 -224.414781)
			(xy 347.973396 -224.389442) (xy 347.692472 -224.389442) (xy 347.691964 -224.415329) (xy 347.683865 -224.466467)
			(xy 347.667866 -224.515707) (xy 347.64436 -224.561839) (xy 347.613928 -224.603726) (xy 347.577318 -224.640336)
			(xy 347.535431 -224.670768) (xy 347.489299 -224.694274) (xy 347.440059 -224.710273) (xy 347.388921 -224.718372)
			(xy 347.337147 -224.718372) (xy 347.286009 -224.710273) (xy 347.236769 -224.694274) (xy 347.190637 -224.670768)
			(xy 347.14875 -224.640336) (xy 347.11214 -224.603726) (xy 347.081708 -224.561839) (xy 347.058202 -224.515707)
			(xy 347.042203 -224.466467) (xy 347.034104 -224.415329) (xy 347.033596 -224.389442) (xy 346.752672 -224.389442)
			(xy 346.752125 -224.417149) (xy 346.742941 -224.471796) (xy 346.734384 -224.498154) (xy 346.72651 -224.520252)
			(xy 346.931488 -224.87509) (xy 346.954348 -224.879408) (xy 346.979171 -224.884565) (xy 347.026951 -224.90152)
			(xy 347.071571 -224.925592) (xy 347.111978 -224.956214) (xy 347.147219 -224.992662) (xy 347.176463 -225.034077)
			(xy 347.199019 -225.079482) (xy 347.214356 -225.127806) (xy 347.222111 -225.177908) (xy 347.222572 -225.203258)
			(xy 347.222064 -225.229165) (xy 347.213958 -225.280342) (xy 347.197946 -225.329621) (xy 347.174423 -225.375788)
			(xy 347.143967 -225.417707) (xy 347.107329 -225.454345) (xy 347.06541 -225.484801) (xy 347.019243 -225.508324)
			(xy 346.969964 -225.524336) (xy 346.918787 -225.532442) (xy 346.866973 -225.532442) (xy 346.815796 -225.524336)
			(xy 346.766517 -225.508324) (xy 346.72035 -225.484801) (xy 346.678431 -225.454345) (xy 346.641793 -225.417707)
			(xy 346.611337 -225.375788) (xy 346.587814 -225.329621) (xy 346.571802 -225.280342) (xy 346.563696 -225.229165)
			(xy 346.563188 -225.203258) (xy 346.563797 -225.175541) (xy 346.57311 -225.120895) (xy 346.58173 -225.094546)
			(xy 346.589604 -225.072448) (xy 346.384626 -224.71761) (xy 346.361766 -224.713292) (xy 346.336948 -224.708169)
			(xy 346.289205 -224.691172) (xy 346.244626 -224.667071) (xy 346.20426 -224.636431) (xy 346.169057 -224.599976)
			(xy 346.139848 -224.558564) (xy 346.117319 -224.51317) (xy 346.102001 -224.464863) (xy 346.094255 -224.414781)
			(xy 346.093796 -224.389442) (xy 345.812872 -224.389442) (xy 345.812364 -224.415329) (xy 345.804265 -224.466467)
			(xy 345.788266 -224.515707) (xy 345.76476 -224.561839) (xy 345.734328 -224.603726) (xy 345.697718 -224.640336)
			(xy 345.655831 -224.670768) (xy 345.609699 -224.694274) (xy 345.560459 -224.710273) (xy 345.509321 -224.718372)
			(xy 345.457547 -224.718372) (xy 345.406409 -224.710273) (xy 345.357169 -224.694274) (xy 345.311037 -224.670768)
			(xy 345.26915 -224.640336) (xy 345.23254 -224.603726) (xy 345.202108 -224.561839) (xy 345.178602 -224.515707)
			(xy 345.162603 -224.466467) (xy 345.154504 -224.415329) (xy 345.153996 -224.389442) (xy 344.873072 -224.389442)
			(xy 344.872525 -224.417149) (xy 344.863341 -224.471796) (xy 344.854784 -224.498154) (xy 344.84691 -224.520252)
			(xy 345.051888 -224.87509) (xy 345.074748 -224.879408) (xy 345.099571 -224.884565) (xy 345.147351 -224.90152)
			(xy 345.191971 -224.925592) (xy 345.232378 -224.956214) (xy 345.267619 -224.992662) (xy 345.296863 -225.034077)
			(xy 345.319419 -225.079482) (xy 345.334756 -225.127806) (xy 345.342511 -225.177908) (xy 345.342972 -225.203258)
			(xy 345.342464 -225.229165) (xy 345.334358 -225.280342) (xy 345.318346 -225.329621) (xy 345.294823 -225.375788)
			(xy 345.264367 -225.417707) (xy 345.227729 -225.454345) (xy 345.18581 -225.484801) (xy 345.139643 -225.508324)
			(xy 345.090364 -225.524336) (xy 345.039187 -225.532442) (xy 344.987373 -225.532442) (xy 344.936196 -225.524336)
			(xy 344.886917 -225.508324) (xy 344.84075 -225.484801) (xy 344.798831 -225.454345) (xy 344.762193 -225.417707)
			(xy 344.731737 -225.375788) (xy 344.708214 -225.329621) (xy 344.692202 -225.280342) (xy 344.684096 -225.229165)
			(xy 344.683588 -225.203258) (xy 344.684197 -225.175541) (xy 344.69351 -225.120895) (xy 344.70213 -225.094546)
			(xy 344.710004 -225.072448) (xy 344.505026 -224.71761) (xy 344.482166 -224.713292) (xy 344.457348 -224.708169)
			(xy 344.409605 -224.691172) (xy 344.365026 -224.667071) (xy 344.32466 -224.636431) (xy 344.289457 -224.599976)
			(xy 344.260248 -224.558564) (xy 344.237719 -224.51317) (xy 344.222401 -224.464863) (xy 344.214655 -224.414781)
			(xy 344.214196 -224.389442) (xy 343.933272 -224.389442) (xy 343.932764 -224.415329) (xy 343.924665 -224.466467)
			(xy 343.908666 -224.515707) (xy 343.88516 -224.561839) (xy 343.854728 -224.603726) (xy 343.818118 -224.640336)
			(xy 343.776231 -224.670768) (xy 343.730099 -224.694274) (xy 343.680859 -224.710273) (xy 343.629721 -224.718372)
			(xy 343.577947 -224.718372) (xy 343.526809 -224.710273) (xy 343.477569 -224.694274) (xy 343.431437 -224.670768)
			(xy 343.38955 -224.640336) (xy 343.35294 -224.603726) (xy 343.322508 -224.561839) (xy 343.299002 -224.515707)
			(xy 343.283003 -224.466467) (xy 343.274904 -224.415329) (xy 343.274396 -224.389442) (xy 342.993472 -224.389442)
			(xy 342.992925 -224.417149) (xy 342.983741 -224.471796) (xy 342.975184 -224.498154) (xy 342.96731 -224.520252)
			(xy 343.172288 -224.87509) (xy 343.195148 -224.879408) (xy 343.219971 -224.884565) (xy 343.267751 -224.90152)
			(xy 343.312371 -224.925592) (xy 343.352778 -224.956214) (xy 343.388019 -224.992662) (xy 343.417263 -225.034077)
			(xy 343.439819 -225.079482) (xy 343.455156 -225.127806) (xy 343.462911 -225.177908) (xy 343.463372 -225.203258)
			(xy 343.462864 -225.229165) (xy 343.454758 -225.280342) (xy 343.438746 -225.329621) (xy 343.415223 -225.375788)
			(xy 343.384767 -225.417707) (xy 343.348129 -225.454345) (xy 343.30621 -225.484801) (xy 343.260043 -225.508324)
			(xy 343.210764 -225.524336) (xy 343.159587 -225.532442) (xy 343.107773 -225.532442) (xy 343.056596 -225.524336)
			(xy 343.007317 -225.508324) (xy 342.96115 -225.484801) (xy 342.919231 -225.454345) (xy 342.882593 -225.417707)
			(xy 342.852137 -225.375788) (xy 342.828614 -225.329621) (xy 342.812602 -225.280342) (xy 342.804496 -225.229165)
			(xy 342.803988 -225.203258) (xy 342.804597 -225.175541) (xy 342.81391 -225.120895) (xy 342.82253 -225.094546)
			(xy 342.830404 -225.072448) (xy 342.625426 -224.71761) (xy 342.602566 -224.713292) (xy 342.577748 -224.708169)
			(xy 342.530005 -224.691172) (xy 342.485426 -224.667071) (xy 342.44506 -224.636431) (xy 342.409857 -224.599976)
			(xy 342.380648 -224.558564) (xy 342.358119 -224.51317) (xy 342.342801 -224.464863) (xy 342.335055 -224.414781)
			(xy 342.334596 -224.389442) (xy 342.053672 -224.389442) (xy 342.053164 -224.415329) (xy 342.045065 -224.466467)
			(xy 342.029066 -224.515707) (xy 342.00556 -224.561839) (xy 341.975128 -224.603726) (xy 341.938518 -224.640336)
			(xy 341.896631 -224.670768) (xy 341.850499 -224.694274) (xy 341.801259 -224.710273) (xy 341.750121 -224.718372)
			(xy 341.698347 -224.718372) (xy 341.647209 -224.710273) (xy 341.597969 -224.694274) (xy 341.551837 -224.670768)
			(xy 341.50995 -224.640336) (xy 341.47334 -224.603726) (xy 341.442908 -224.561839) (xy 341.419402 -224.515707)
			(xy 341.403403 -224.466467) (xy 341.395304 -224.415329) (xy 341.394796 -224.389442) (xy 341.113872 -224.389442)
			(xy 341.113872 -224.38995) (xy 341.113311 -224.417593) (xy 341.104122 -224.472111) (xy 341.095584 -224.498408)
			(xy 341.087964 -224.520252) (xy 341.292688 -224.87509) (xy 341.315548 -224.879408) (xy 341.340371 -224.884565)
			(xy 341.388151 -224.90152) (xy 341.432771 -224.925592) (xy 341.473178 -224.956214) (xy 341.508419 -224.992662)
			(xy 341.537663 -225.034077) (xy 341.560219 -225.079482) (xy 341.575556 -225.127806) (xy 341.583311 -225.177908)
			(xy 341.583772 -225.203258) (xy 341.583264 -225.229165) (xy 341.575158 -225.280342) (xy 341.559146 -225.329621)
			(xy 341.535623 -225.375788) (xy 341.505167 -225.417707) (xy 341.468529 -225.454345) (xy 341.42661 -225.484801)
			(xy 341.380443 -225.508324) (xy 341.331164 -225.524336) (xy 341.279987 -225.532442) (xy 341.228173 -225.532442)
			(xy 341.176996 -225.524336) (xy 341.127717 -225.508324) (xy 341.08155 -225.484801) (xy 341.039631 -225.454345)
			(xy 341.002993 -225.417707) (xy 340.972537 -225.375788) (xy 340.949014 -225.329621) (xy 340.933002 -225.280342)
			(xy 340.924896 -225.229165) (xy 340.924388 -225.203258) (xy 340.924388 -225.20275) (xy 340.924995 -225.175096)
			(xy 340.93432 -225.120578) (xy 340.94293 -225.094292) (xy 340.95055 -225.072448) (xy 340.745826 -224.71761)
			(xy 340.722966 -224.713292) (xy 340.698148 -224.708169) (xy 340.650405 -224.691172) (xy 340.605826 -224.667071)
			(xy 340.56546 -224.636431) (xy 340.530257 -224.599976) (xy 340.501048 -224.558564) (xy 340.478519 -224.51317)
			(xy 340.463201 -224.464863) (xy 340.455455 -224.414781) (xy 340.454996 -224.389442) (xy 339.234272 -224.389442)
			(xy 339.234272 -224.38995) (xy 339.233711 -224.417593) (xy 339.224522 -224.472111) (xy 339.215984 -224.498408)
			(xy 339.208364 -224.520252) (xy 339.413088 -224.87509) (xy 339.435948 -224.879408) (xy 339.460771 -224.884565)
			(xy 339.508551 -224.90152) (xy 339.553171 -224.925592) (xy 339.593578 -224.956214) (xy 339.628819 -224.992662)
			(xy 339.658063 -225.034077) (xy 339.680619 -225.079482) (xy 339.695956 -225.127806) (xy 339.703711 -225.177908)
			(xy 339.704172 -225.203258) (xy 339.703664 -225.229165) (xy 339.695558 -225.280342) (xy 339.679546 -225.329621)
			(xy 339.656023 -225.375788) (xy 339.625567 -225.417707) (xy 339.588929 -225.454345) (xy 339.54701 -225.484801)
			(xy 339.500843 -225.508324) (xy 339.451564 -225.524336) (xy 339.400387 -225.532442) (xy 339.348573 -225.532442)
			(xy 339.297396 -225.524336) (xy 339.248117 -225.508324) (xy 339.20195 -225.484801) (xy 339.160031 -225.454345)
			(xy 339.123393 -225.417707) (xy 339.092937 -225.375788) (xy 339.069414 -225.329621) (xy 339.053402 -225.280342)
			(xy 339.045296 -225.229165) (xy 339.044788 -225.203258) (xy 339.044788 -225.20275) (xy 339.045395 -225.175096)
			(xy 339.05472 -225.120578) (xy 339.06333 -225.094292) (xy 339.07095 -225.072448) (xy 338.866226 -224.71761)
			(xy 338.843366 -224.713292) (xy 338.818548 -224.708169) (xy 338.770805 -224.691172) (xy 338.726226 -224.667071)
			(xy 338.68586 -224.636431) (xy 338.650657 -224.599976) (xy 338.621448 -224.558564) (xy 338.598919 -224.51317)
			(xy 338.583601 -224.464863) (xy 338.575855 -224.414781) (xy 338.575396 -224.389442) (xy 338.294472 -224.389442)
			(xy 338.293964 -224.415329) (xy 338.285865 -224.466467) (xy 338.269866 -224.515707) (xy 338.24636 -224.561839)
			(xy 338.215928 -224.603726) (xy 338.179318 -224.640336) (xy 338.137431 -224.670768) (xy 338.091299 -224.694274)
			(xy 338.042059 -224.710273) (xy 337.990921 -224.718372) (xy 337.939147 -224.718372) (xy 337.888009 -224.710273)
			(xy 337.838769 -224.694274) (xy 337.792637 -224.670768) (xy 337.75075 -224.640336) (xy 337.71414 -224.603726)
			(xy 337.683708 -224.561839) (xy 337.660202 -224.515707) (xy 337.644203 -224.466467) (xy 337.636104 -224.415329)
			(xy 337.635596 -224.389442) (xy 309.6387 -224.389442) (xy 309.6387 -224.72142) (xy 309.638295 -224.731575)
			(xy 309.630493 -224.750328) (xy 309.616091 -224.764651) (xy 309.597296 -224.77235) (xy 309.587138 -224.772728)
			(xy 308.187598 -224.772728) (xy 308.177467 -224.772274) (xy 308.15874 -224.76454) (xy 308.144383 -224.750243)
			(xy 308.136569 -224.731549) (xy 308.136036 -224.72142) (xy 302.0949 -224.72142) (xy 302.094495 -224.731575)
			(xy 302.086693 -224.750328) (xy 302.072291 -224.764651) (xy 302.053496 -224.77235) (xy 302.043338 -224.772728)
			(xy 300.643798 -224.772728) (xy 300.633667 -224.772274) (xy 300.61494 -224.76454) (xy 300.600583 -224.750243)
			(xy 300.592769 -224.731549) (xy 300.592236 -224.72142) (xy 294.5511 -224.72142) (xy 294.550695 -224.731575)
			(xy 294.542893 -224.750328) (xy 294.528491 -224.764651) (xy 294.509696 -224.77235) (xy 294.499538 -224.772728)
			(xy 293.099998 -224.772728) (xy 293.089867 -224.772274) (xy 293.07114 -224.76454) (xy 293.056783 -224.750243)
			(xy 293.048969 -224.731549) (xy 293.048436 -224.72142) (xy 287.0073 -224.72142) (xy 287.006895 -224.731575)
			(xy 286.999093 -224.750328) (xy 286.984691 -224.764651) (xy 286.965896 -224.77235) (xy 286.955738 -224.772728)
			(xy 285.556198 -224.772728) (xy 285.546067 -224.772274) (xy 285.52734 -224.76454) (xy 285.512983 -224.750243)
			(xy 285.505169 -224.731549) (xy 285.504636 -224.72142) (xy 279.4635 -224.72142) (xy 279.463095 -224.731575)
			(xy 279.455293 -224.750328) (xy 279.440891 -224.764651) (xy 279.422096 -224.77235) (xy 279.411938 -224.772728)
			(xy 278.012398 -224.772728) (xy 278.002267 -224.772274) (xy 277.98354 -224.76454) (xy 277.969183 -224.750243)
			(xy 277.961369 -224.731549) (xy 277.960836 -224.72142) (xy 271.9197 -224.72142) (xy 271.919295 -224.731575)
			(xy 271.911493 -224.750328) (xy 271.897091 -224.764651) (xy 271.878296 -224.77235) (xy 271.868138 -224.772728)
			(xy 270.468598 -224.772728) (xy 270.458467 -224.772274) (xy 270.43974 -224.76454) (xy 270.425383 -224.750243)
			(xy 270.417569 -224.731549) (xy 270.417036 -224.72142) (xy 264.3759 -224.72142) (xy 264.375495 -224.731575)
			(xy 264.367693 -224.750328) (xy 264.353291 -224.764651) (xy 264.334496 -224.77235) (xy 264.324338 -224.772728)
			(xy 262.924798 -224.772728) (xy 262.914667 -224.772274) (xy 262.89594 -224.76454) (xy 262.881583 -224.750243)
			(xy 262.873769 -224.731549) (xy 262.873236 -224.72142) (xy 256.8321 -224.72142) (xy 256.831695 -224.731575)
			(xy 256.823893 -224.750328) (xy 256.809491 -224.764651) (xy 256.790696 -224.77235) (xy 256.780538 -224.772728)
			(xy 255.380998 -224.772728) (xy 255.370867 -224.772274) (xy 255.35214 -224.76454) (xy 255.337783 -224.750243)
			(xy 255.329969 -224.731549) (xy 255.329436 -224.72142) (xy 212.371432 -224.72142) (xy 212.370996 -224.731571)
			(xy 212.363199 -224.750318) (xy 212.348808 -224.76464) (xy 212.330023 -224.772345) (xy 212.31987 -224.772728)
			(xy 210.92033 -224.772728) (xy 210.910201 -224.772248) (xy 210.891475 -224.764524) (xy 210.877116 -224.750235)
			(xy 210.869301 -224.731546) (xy 210.868768 -224.72142) (xy 204.827632 -224.72142) (xy 204.827196 -224.731571)
			(xy 204.819399 -224.750318) (xy 204.805008 -224.76464) (xy 204.786223 -224.772345) (xy 204.77607 -224.772728)
			(xy 203.37653 -224.772728) (xy 203.366401 -224.772248) (xy 203.347675 -224.764524) (xy 203.333316 -224.750235)
			(xy 203.325501 -224.731546) (xy 203.324968 -224.72142) (xy 197.283832 -224.72142) (xy 197.283396 -224.731571)
			(xy 197.275599 -224.750318) (xy 197.261208 -224.76464) (xy 197.242423 -224.772345) (xy 197.23227 -224.772728)
			(xy 195.83273 -224.772728) (xy 195.822601 -224.772248) (xy 195.803875 -224.764524) (xy 195.789516 -224.750235)
			(xy 195.781701 -224.731546) (xy 195.781168 -224.72142) (xy 189.740032 -224.72142) (xy 189.739596 -224.731571)
			(xy 189.731799 -224.750318) (xy 189.717408 -224.76464) (xy 189.698623 -224.772345) (xy 189.68847 -224.772728)
			(xy 188.28893 -224.772728) (xy 188.278801 -224.772248) (xy 188.260075 -224.764524) (xy 188.245716 -224.750235)
			(xy 188.237901 -224.731546) (xy 188.237368 -224.72142) (xy 182.196232 -224.72142) (xy 182.195796 -224.731571)
			(xy 182.187999 -224.750318) (xy 182.173608 -224.76464) (xy 182.154823 -224.772345) (xy 182.14467 -224.772728)
			(xy 180.74513 -224.772728) (xy 180.735001 -224.772248) (xy 180.716275 -224.764524) (xy 180.701916 -224.750235)
			(xy 180.694101 -224.731546) (xy 180.693568 -224.72142) (xy 174.652432 -224.72142) (xy 174.651996 -224.731571)
			(xy 174.644199 -224.750318) (xy 174.629808 -224.76464) (xy 174.611023 -224.772345) (xy 174.60087 -224.772728)
			(xy 173.20133 -224.772728) (xy 173.191201 -224.772248) (xy 173.172475 -224.764524) (xy 173.158116 -224.750235)
			(xy 173.150301 -224.731546) (xy 173.149768 -224.72142) (xy 167.108632 -224.72142) (xy 167.108196 -224.731571)
			(xy 167.100399 -224.750318) (xy 167.086008 -224.76464) (xy 167.067223 -224.772345) (xy 167.05707 -224.772728)
			(xy 165.65753 -224.772728) (xy 165.647401 -224.772248) (xy 165.628675 -224.764524) (xy 165.614316 -224.750235)
			(xy 165.606501 -224.731546) (xy 165.605968 -224.72142) (xy 159.564832 -224.72142) (xy 159.564396 -224.731571)
			(xy 159.556599 -224.750318) (xy 159.542208 -224.76464) (xy 159.523423 -224.772345) (xy 159.51327 -224.772728)
			(xy 158.11373 -224.772728) (xy 158.103601 -224.772248) (xy 158.084875 -224.764524) (xy 158.070516 -224.750235)
			(xy 158.062701 -224.731546) (xy 158.062168 -224.72142) (xy 134.615367 -224.72142) (xy 134.704074 -224.87509)
			(xy 134.726934 -224.879408) (xy 134.751752 -224.884531) (xy 134.799495 -224.901528) (xy 134.844074 -224.925629)
			(xy 134.88444 -224.956269) (xy 134.919643 -224.992724) (xy 134.948852 -225.034136) (xy 134.971381 -225.07953)
			(xy 134.986699 -225.127837) (xy 134.994445 -225.177919) (xy 134.994904 -225.203258) (xy 134.994396 -225.229145)
			(xy 134.986297 -225.280283) (xy 134.970298 -225.329523) (xy 134.946792 -225.375655) (xy 134.91636 -225.417542)
			(xy 134.87975 -225.454152) (xy 134.837863 -225.484584) (xy 134.791731 -225.50809) (xy 134.742491 -225.524089)
			(xy 134.691353 -225.532188) (xy 134.639579 -225.532188) (xy 134.588441 -225.524089) (xy 134.539201 -225.50809)
			(xy 134.493069 -225.484584) (xy 134.451182 -225.454152) (xy 134.414572 -225.417542) (xy 134.38414 -225.375655)
			(xy 134.360634 -225.329523) (xy 134.344635 -225.280283) (xy 134.336536 -225.229145) (xy 134.336028 -225.203258)
			(xy 134.336028 -225.20275) (xy 134.336589 -225.175107) (xy 134.345778 -225.120589) (xy 134.354316 -225.094292)
			(xy 134.361936 -225.072448) (xy 134.157212 -224.71761) (xy 134.134352 -224.713292) (xy 134.109529 -224.708135)
			(xy 134.061749 -224.69118) (xy 134.017129 -224.667108) (xy 133.976722 -224.636486) (xy 133.941481 -224.600038)
			(xy 133.912237 -224.558623) (xy 133.889681 -224.513218) (xy 133.874344 -224.464894) (xy 133.866589 -224.414792)
			(xy 133.866128 -224.389442) (xy 133.585204 -224.389442) (xy 133.584696 -224.415329) (xy 133.576597 -224.466467)
			(xy 133.560598 -224.515707) (xy 133.537092 -224.561839) (xy 133.50666 -224.603726) (xy 133.47005 -224.640336)
			(xy 133.428163 -224.670768) (xy 133.382031 -224.694274) (xy 133.332791 -224.710273) (xy 133.281653 -224.718372)
			(xy 133.229879 -224.718372) (xy 133.178741 -224.710273) (xy 133.129501 -224.694274) (xy 133.083369 -224.670768)
			(xy 133.041482 -224.640336) (xy 133.004872 -224.603726) (xy 132.97444 -224.561839) (xy 132.950934 -224.515707)
			(xy 132.934935 -224.466467) (xy 132.926836 -224.415329) (xy 132.926328 -224.389442) (xy 132.645404 -224.389442)
			(xy 132.64486 -224.417149) (xy 132.635674 -224.471796) (xy 132.627116 -224.498154) (xy 132.619242 -224.520252)
			(xy 132.82422 -224.87509) (xy 132.84708 -224.879408) (xy 132.871909 -224.884542) (xy 132.919688 -224.901501)
			(xy 132.964308 -224.925578) (xy 133.004714 -224.956202) (xy 133.039954 -224.992654) (xy 133.069197 -225.034071)
			(xy 133.091752 -225.079478) (xy 133.107088 -225.127804) (xy 133.114843 -225.177908) (xy 133.115304 -225.203258)
			(xy 133.114796 -225.229165) (xy 133.10669 -225.280342) (xy 133.090678 -225.329621) (xy 133.067155 -225.375788)
			(xy 133.036699 -225.417707) (xy 133.000061 -225.454345) (xy 132.958142 -225.484801) (xy 132.911975 -225.508324)
			(xy 132.862696 -225.524336) (xy 132.811519 -225.532442) (xy 132.759705 -225.532442) (xy 132.708528 -225.524336)
			(xy 132.659249 -225.508324) (xy 132.613082 -225.484801) (xy 132.571163 -225.454345) (xy 132.534525 -225.417707)
			(xy 132.504069 -225.375788) (xy 132.480546 -225.329621) (xy 132.464534 -225.280342) (xy 132.456428 -225.229165)
			(xy 132.45592 -225.203258) (xy 132.456527 -225.175541) (xy 132.465842 -225.120895) (xy 132.474462 -225.094546)
			(xy 132.482336 -225.072448) (xy 132.277358 -224.71761) (xy 132.254498 -224.713292) (xy 132.229685 -224.708145)
			(xy 132.181943 -224.691153) (xy 132.137363 -224.667056) (xy 132.096996 -224.63642) (xy 132.061793 -224.599968)
			(xy 132.032582 -224.558558) (xy 132.010052 -224.513166) (xy 131.994734 -224.46486) (xy 131.986988 -224.41478)
			(xy 131.986528 -224.389442) (xy 131.705604 -224.389442) (xy 131.705096 -224.415329) (xy 131.696997 -224.466467)
			(xy 131.680998 -224.515707) (xy 131.657492 -224.561839) (xy 131.62706 -224.603726) (xy 131.59045 -224.640336)
			(xy 131.548563 -224.670768) (xy 131.502431 -224.694274) (xy 131.453191 -224.710273) (xy 131.402053 -224.718372)
			(xy 131.350279 -224.718372) (xy 131.299141 -224.710273) (xy 131.249901 -224.694274) (xy 131.203769 -224.670768)
			(xy 131.161882 -224.640336) (xy 131.125272 -224.603726) (xy 131.09484 -224.561839) (xy 131.071334 -224.515707)
			(xy 131.055335 -224.466467) (xy 131.047236 -224.415329) (xy 131.046728 -224.389442) (xy 130.765804 -224.389442)
			(xy 130.76526 -224.417149) (xy 130.756074 -224.471796) (xy 130.747516 -224.498154) (xy 130.739642 -224.520252)
			(xy 130.94462 -224.87509) (xy 130.96748 -224.879408) (xy 130.992309 -224.884542) (xy 131.040088 -224.901501)
			(xy 131.084708 -224.925578) (xy 131.125114 -224.956202) (xy 131.160354 -224.992654) (xy 131.189597 -225.034071)
			(xy 131.212152 -225.079478) (xy 131.227488 -225.127804) (xy 131.235243 -225.177908) (xy 131.235704 -225.203258)
			(xy 131.235196 -225.229165) (xy 131.22709 -225.280342) (xy 131.211078 -225.329621) (xy 131.187555 -225.375788)
			(xy 131.157099 -225.417707) (xy 131.120461 -225.454345) (xy 131.078542 -225.484801) (xy 131.032375 -225.508324)
			(xy 130.983096 -225.524336) (xy 130.931919 -225.532442) (xy 130.880105 -225.532442) (xy 130.828928 -225.524336)
			(xy 130.779649 -225.508324) (xy 130.733482 -225.484801) (xy 130.691563 -225.454345) (xy 130.654925 -225.417707)
			(xy 130.624469 -225.375788) (xy 130.600946 -225.329621) (xy 130.584934 -225.280342) (xy 130.576828 -225.229165)
			(xy 130.57632 -225.203258) (xy 130.576927 -225.175541) (xy 130.586242 -225.120895) (xy 130.594862 -225.094546)
			(xy 130.602736 -225.072448) (xy 130.397758 -224.71761) (xy 130.374898 -224.713292) (xy 130.350085 -224.708145)
			(xy 130.302343 -224.691153) (xy 130.257763 -224.667056) (xy 130.217396 -224.63642) (xy 130.182193 -224.599968)
			(xy 130.152982 -224.558558) (xy 130.130452 -224.513166) (xy 130.115134 -224.46486) (xy 130.107388 -224.41478)
			(xy 130.106928 -224.389442) (xy 129.826004 -224.389442) (xy 129.825496 -224.415329) (xy 129.817397 -224.466467)
			(xy 129.801398 -224.515707) (xy 129.777892 -224.561839) (xy 129.74746 -224.603726) (xy 129.71085 -224.640336)
			(xy 129.668963 -224.670768) (xy 129.622831 -224.694274) (xy 129.573591 -224.710273) (xy 129.522453 -224.718372)
			(xy 129.470679 -224.718372) (xy 129.419541 -224.710273) (xy 129.370301 -224.694274) (xy 129.324169 -224.670768)
			(xy 129.282282 -224.640336) (xy 129.245672 -224.603726) (xy 129.21524 -224.561839) (xy 129.191734 -224.515707)
			(xy 129.175735 -224.466467) (xy 129.167636 -224.415329) (xy 129.167128 -224.389442) (xy 128.886204 -224.389442)
			(xy 128.88566 -224.417149) (xy 128.876474 -224.471796) (xy 128.867916 -224.498154) (xy 128.860042 -224.520252)
			(xy 129.06502 -224.87509) (xy 129.08788 -224.879408) (xy 129.112709 -224.884542) (xy 129.160488 -224.901501)
			(xy 129.205108 -224.925578) (xy 129.245514 -224.956202) (xy 129.280754 -224.992654) (xy 129.309997 -225.034071)
			(xy 129.332552 -225.079478) (xy 129.347888 -225.127804) (xy 129.355643 -225.177908) (xy 129.356104 -225.203258)
			(xy 129.355596 -225.229165) (xy 129.34749 -225.280342) (xy 129.331478 -225.329621) (xy 129.307955 -225.375788)
			(xy 129.277499 -225.417707) (xy 129.240861 -225.454345) (xy 129.198942 -225.484801) (xy 129.152775 -225.508324)
			(xy 129.103496 -225.524336) (xy 129.052319 -225.532442) (xy 129.000505 -225.532442) (xy 128.949328 -225.524336)
			(xy 128.900049 -225.508324) (xy 128.853882 -225.484801) (xy 128.811963 -225.454345) (xy 128.775325 -225.417707)
			(xy 128.744869 -225.375788) (xy 128.721346 -225.329621) (xy 128.705334 -225.280342) (xy 128.697228 -225.229165)
			(xy 128.69672 -225.203258) (xy 128.697327 -225.175541) (xy 128.706642 -225.120895) (xy 128.715262 -225.094546)
			(xy 128.723136 -225.072448) (xy 128.518158 -224.71761) (xy 128.495298 -224.713292) (xy 128.470485 -224.708145)
			(xy 128.422743 -224.691153) (xy 128.378163 -224.667056) (xy 128.337796 -224.63642) (xy 128.302593 -224.599968)
			(xy 128.273382 -224.558558) (xy 128.250852 -224.513166) (xy 128.235534 -224.46486) (xy 128.227788 -224.41478)
			(xy 128.227328 -224.389442) (xy 127.946404 -224.389442) (xy 127.945896 -224.415329) (xy 127.937797 -224.466467)
			(xy 127.921798 -224.515707) (xy 127.898292 -224.561839) (xy 127.86786 -224.603726) (xy 127.83125 -224.640336)
			(xy 127.789363 -224.670768) (xy 127.743231 -224.694274) (xy 127.693991 -224.710273) (xy 127.642853 -224.718372)
			(xy 127.591079 -224.718372) (xy 127.539941 -224.710273) (xy 127.490701 -224.694274) (xy 127.444569 -224.670768)
			(xy 127.402682 -224.640336) (xy 127.366072 -224.603726) (xy 127.33564 -224.561839) (xy 127.312134 -224.515707)
			(xy 127.296135 -224.466467) (xy 127.288036 -224.415329) (xy 127.287528 -224.389442) (xy 127.006604 -224.389442)
			(xy 127.00606 -224.417149) (xy 126.996874 -224.471796) (xy 126.988316 -224.498154) (xy 126.980442 -224.520252)
			(xy 127.18542 -224.87509) (xy 127.20828 -224.879408) (xy 127.233109 -224.884542) (xy 127.280888 -224.901501)
			(xy 127.325508 -224.925578) (xy 127.365914 -224.956202) (xy 127.401154 -224.992654) (xy 127.430397 -225.034071)
			(xy 127.452952 -225.079478) (xy 127.468288 -225.127804) (xy 127.476043 -225.177908) (xy 127.476504 -225.203258)
			(xy 127.475996 -225.229165) (xy 127.46789 -225.280342) (xy 127.451878 -225.329621) (xy 127.428355 -225.375788)
			(xy 127.397899 -225.417707) (xy 127.361261 -225.454345) (xy 127.319342 -225.484801) (xy 127.273175 -225.508324)
			(xy 127.223896 -225.524336) (xy 127.172719 -225.532442) (xy 127.120905 -225.532442) (xy 127.069728 -225.524336)
			(xy 127.020449 -225.508324) (xy 126.974282 -225.484801) (xy 126.932363 -225.454345) (xy 126.895725 -225.417707)
			(xy 126.865269 -225.375788) (xy 126.841746 -225.329621) (xy 126.825734 -225.280342) (xy 126.817628 -225.229165)
			(xy 126.81712 -225.203258) (xy 126.817727 -225.175541) (xy 126.827042 -225.120895) (xy 126.835662 -225.094546)
			(xy 126.843536 -225.072448) (xy 126.638558 -224.71761) (xy 126.615698 -224.713292) (xy 126.590885 -224.708145)
			(xy 126.543143 -224.691153) (xy 126.498563 -224.667056) (xy 126.458196 -224.63642) (xy 126.422993 -224.599968)
			(xy 126.393782 -224.558558) (xy 126.371252 -224.513166) (xy 126.355934 -224.46486) (xy 126.348188 -224.41478)
			(xy 126.347728 -224.389442) (xy 126.066804 -224.389442) (xy 126.066296 -224.415329) (xy 126.058197 -224.466467)
			(xy 126.042198 -224.515707) (xy 126.018692 -224.561839) (xy 125.98826 -224.603726) (xy 125.95165 -224.640336)
			(xy 125.909763 -224.670768) (xy 125.863631 -224.694274) (xy 125.814391 -224.710273) (xy 125.763253 -224.718372)
			(xy 125.711479 -224.718372) (xy 125.660341 -224.710273) (xy 125.611101 -224.694274) (xy 125.564969 -224.670768)
			(xy 125.523082 -224.640336) (xy 125.486472 -224.603726) (xy 125.45604 -224.561839) (xy 125.432534 -224.515707)
			(xy 125.416535 -224.466467) (xy 125.408436 -224.415329) (xy 125.407928 -224.389442) (xy 125.127004 -224.389442)
			(xy 125.12646 -224.417149) (xy 125.117274 -224.471796) (xy 125.108716 -224.498154) (xy 125.100842 -224.520252)
			(xy 125.30582 -224.87509) (xy 125.32868 -224.879408) (xy 125.353509 -224.884542) (xy 125.401288 -224.901501)
			(xy 125.445908 -224.925578) (xy 125.486314 -224.956202) (xy 125.521554 -224.992654) (xy 125.550797 -225.034071)
			(xy 125.573352 -225.079478) (xy 125.588688 -225.127804) (xy 125.596443 -225.177908) (xy 125.596904 -225.203258)
			(xy 125.596396 -225.229165) (xy 125.58829 -225.280342) (xy 125.572278 -225.329621) (xy 125.548755 -225.375788)
			(xy 125.518299 -225.417707) (xy 125.481661 -225.454345) (xy 125.439742 -225.484801) (xy 125.393575 -225.508324)
			(xy 125.344296 -225.524336) (xy 125.293119 -225.532442) (xy 125.241305 -225.532442) (xy 125.190128 -225.524336)
			(xy 125.140849 -225.508324) (xy 125.094682 -225.484801) (xy 125.052763 -225.454345) (xy 125.016125 -225.417707)
			(xy 124.985669 -225.375788) (xy 124.962146 -225.329621) (xy 124.946134 -225.280342) (xy 124.938028 -225.229165)
			(xy 124.93752 -225.203258) (xy 124.938127 -225.175541) (xy 124.947442 -225.120895) (xy 124.956062 -225.094546)
			(xy 124.963936 -225.072448) (xy 124.758958 -224.71761) (xy 124.736098 -224.713292) (xy 124.711285 -224.708145)
			(xy 124.663543 -224.691153) (xy 124.618963 -224.667056) (xy 124.578596 -224.63642) (xy 124.543393 -224.599968)
			(xy 124.514182 -224.558558) (xy 124.491652 -224.513166) (xy 124.476334 -224.46486) (xy 124.468588 -224.41478)
			(xy 124.468128 -224.389442) (xy 124.187204 -224.389442) (xy 124.186696 -224.415329) (xy 124.178597 -224.466467)
			(xy 124.162598 -224.515707) (xy 124.139092 -224.561839) (xy 124.10866 -224.603726) (xy 124.07205 -224.640336)
			(xy 124.030163 -224.670768) (xy 123.984031 -224.694274) (xy 123.934791 -224.710273) (xy 123.883653 -224.718372)
			(xy 123.831879 -224.718372) (xy 123.780741 -224.710273) (xy 123.731501 -224.694274) (xy 123.685369 -224.670768)
			(xy 123.643482 -224.640336) (xy 123.606872 -224.603726) (xy 123.57644 -224.561839) (xy 123.552934 -224.515707)
			(xy 123.536935 -224.466467) (xy 123.528836 -224.415329) (xy 123.528328 -224.389442) (xy 123.247404 -224.389442)
			(xy 123.24686 -224.417149) (xy 123.237674 -224.471796) (xy 123.229116 -224.498154) (xy 123.221242 -224.520252)
			(xy 123.42622 -224.87509) (xy 123.44908 -224.879408) (xy 123.473909 -224.884542) (xy 123.521688 -224.901501)
			(xy 123.566308 -224.925578) (xy 123.606714 -224.956202) (xy 123.641954 -224.992654) (xy 123.671197 -225.034071)
			(xy 123.693752 -225.079478) (xy 123.709088 -225.127804) (xy 123.716843 -225.177908) (xy 123.717304 -225.203258)
			(xy 123.716796 -225.229165) (xy 123.70869 -225.280342) (xy 123.692678 -225.329621) (xy 123.669155 -225.375788)
			(xy 123.638699 -225.417707) (xy 123.602061 -225.454345) (xy 123.560142 -225.484801) (xy 123.513975 -225.508324)
			(xy 123.464696 -225.524336) (xy 123.413519 -225.532442) (xy 123.361705 -225.532442) (xy 123.310528 -225.524336)
			(xy 123.261249 -225.508324) (xy 123.215082 -225.484801) (xy 123.173163 -225.454345) (xy 123.136525 -225.417707)
			(xy 123.106069 -225.375788) (xy 123.082546 -225.329621) (xy 123.066534 -225.280342) (xy 123.058428 -225.229165)
			(xy 123.05792 -225.203258) (xy 123.058527 -225.175541) (xy 123.067842 -225.120895) (xy 123.076462 -225.094546)
			(xy 123.084336 -225.072448) (xy 122.879358 -224.71761) (xy 122.856498 -224.713292) (xy 122.831685 -224.708145)
			(xy 122.783943 -224.691153) (xy 122.739363 -224.667056) (xy 122.698996 -224.63642) (xy 122.663793 -224.599968)
			(xy 122.634582 -224.558558) (xy 122.612052 -224.513166) (xy 122.596734 -224.46486) (xy 122.588988 -224.41478)
			(xy 122.588528 -224.389442) (xy 122.307604 -224.389442) (xy 122.307096 -224.415329) (xy 122.298997 -224.466467)
			(xy 122.282998 -224.515707) (xy 122.259492 -224.561839) (xy 122.22906 -224.603726) (xy 122.19245 -224.640336)
			(xy 122.150563 -224.670768) (xy 122.104431 -224.694274) (xy 122.055191 -224.710273) (xy 122.004053 -224.718372)
			(xy 121.952279 -224.718372) (xy 121.901141 -224.710273) (xy 121.851901 -224.694274) (xy 121.805769 -224.670768)
			(xy 121.763882 -224.640336) (xy 121.727272 -224.603726) (xy 121.69684 -224.561839) (xy 121.673334 -224.515707)
			(xy 121.657335 -224.466467) (xy 121.649236 -224.415329) (xy 121.648728 -224.389442) (xy 121.367804 -224.389442)
			(xy 121.36726 -224.417149) (xy 121.358074 -224.471796) (xy 121.349516 -224.498154) (xy 121.341642 -224.520252)
			(xy 121.54662 -224.87509) (xy 121.56948 -224.879408) (xy 121.594309 -224.884542) (xy 121.642088 -224.901501)
			(xy 121.686708 -224.925578) (xy 121.727114 -224.956202) (xy 121.762354 -224.992654) (xy 121.791597 -225.034071)
			(xy 121.814152 -225.079478) (xy 121.829488 -225.127804) (xy 121.837243 -225.177908) (xy 121.837704 -225.203258)
			(xy 121.837196 -225.229165) (xy 121.82909 -225.280342) (xy 121.813078 -225.329621) (xy 121.789555 -225.375788)
			(xy 121.759099 -225.417707) (xy 121.722461 -225.454345) (xy 121.680542 -225.484801) (xy 121.634375 -225.508324)
			(xy 121.585096 -225.524336) (xy 121.533919 -225.532442) (xy 121.482105 -225.532442) (xy 121.430928 -225.524336)
			(xy 121.381649 -225.508324) (xy 121.335482 -225.484801) (xy 121.293563 -225.454345) (xy 121.256925 -225.417707)
			(xy 121.226469 -225.375788) (xy 121.202946 -225.329621) (xy 121.186934 -225.280342) (xy 121.178828 -225.229165)
			(xy 121.17832 -225.203258) (xy 121.178927 -225.175541) (xy 121.188242 -225.120895) (xy 121.196862 -225.094546)
			(xy 121.204736 -225.072448) (xy 120.999758 -224.71761) (xy 120.976898 -224.713292) (xy 120.952085 -224.708145)
			(xy 120.904343 -224.691153) (xy 120.859763 -224.667056) (xy 120.819396 -224.63642) (xy 120.784193 -224.599968)
			(xy 120.754982 -224.558558) (xy 120.732452 -224.513166) (xy 120.717134 -224.46486) (xy 120.709388 -224.41478)
			(xy 120.708928 -224.389442) (xy 120.428004 -224.389442) (xy 120.427496 -224.415329) (xy 120.419397 -224.466467)
			(xy 120.403398 -224.515707) (xy 120.379892 -224.561839) (xy 120.34946 -224.603726) (xy 120.31285 -224.640336)
			(xy 120.270963 -224.670768) (xy 120.224831 -224.694274) (xy 120.175591 -224.710273) (xy 120.124453 -224.718372)
			(xy 120.072679 -224.718372) (xy 120.021541 -224.710273) (xy 119.972301 -224.694274) (xy 119.926169 -224.670768)
			(xy 119.884282 -224.640336) (xy 119.847672 -224.603726) (xy 119.81724 -224.561839) (xy 119.793734 -224.515707)
			(xy 119.777735 -224.466467) (xy 119.769636 -224.415329) (xy 119.769128 -224.389442) (xy 119.488204 -224.389442)
			(xy 119.48766 -224.417149) (xy 119.478474 -224.471796) (xy 119.469916 -224.498154) (xy 119.462042 -224.520252)
			(xy 119.66702 -224.87509) (xy 119.68988 -224.879408) (xy 119.714709 -224.884542) (xy 119.762488 -224.901501)
			(xy 119.807108 -224.925578) (xy 119.847514 -224.956202) (xy 119.882754 -224.992654) (xy 119.911997 -225.034071)
			(xy 119.934552 -225.079478) (xy 119.949888 -225.127804) (xy 119.957643 -225.177908) (xy 119.958104 -225.203258)
			(xy 119.957596 -225.229165) (xy 119.94949 -225.280342) (xy 119.933478 -225.329621) (xy 119.909955 -225.375788)
			(xy 119.879499 -225.417707) (xy 119.842861 -225.454345) (xy 119.800942 -225.484801) (xy 119.754775 -225.508324)
			(xy 119.705496 -225.524336) (xy 119.654319 -225.532442) (xy 119.602505 -225.532442) (xy 119.551328 -225.524336)
			(xy 119.502049 -225.508324) (xy 119.455882 -225.484801) (xy 119.413963 -225.454345) (xy 119.377325 -225.417707)
			(xy 119.346869 -225.375788) (xy 119.323346 -225.329621) (xy 119.307334 -225.280342) (xy 119.299228 -225.229165)
			(xy 119.29872 -225.203258) (xy 119.299327 -225.175541) (xy 119.308642 -225.120895) (xy 119.317262 -225.094546)
			(xy 119.325136 -225.072448) (xy 119.120158 -224.71761) (xy 119.097298 -224.713292) (xy 119.072485 -224.708145)
			(xy 119.024743 -224.691153) (xy 118.980163 -224.667056) (xy 118.939796 -224.63642) (xy 118.904593 -224.599968)
			(xy 118.875382 -224.558558) (xy 118.852852 -224.513166) (xy 118.837534 -224.46486) (xy 118.829788 -224.41478)
			(xy 118.829328 -224.389442) (xy 118.548404 -224.389442) (xy 118.547896 -224.415329) (xy 118.539797 -224.466467)
			(xy 118.523798 -224.515707) (xy 118.500292 -224.561839) (xy 118.46986 -224.603726) (xy 118.43325 -224.640336)
			(xy 118.391363 -224.670768) (xy 118.345231 -224.694274) (xy 118.295991 -224.710273) (xy 118.244853 -224.718372)
			(xy 118.193079 -224.718372) (xy 118.141941 -224.710273) (xy 118.092701 -224.694274) (xy 118.046569 -224.670768)
			(xy 118.004682 -224.640336) (xy 117.968072 -224.603726) (xy 117.93764 -224.561839) (xy 117.914134 -224.515707)
			(xy 117.898135 -224.466467) (xy 117.890036 -224.415329) (xy 117.889528 -224.389442) (xy 117.608604 -224.389442)
			(xy 117.60806 -224.417149) (xy 117.598874 -224.471796) (xy 117.590316 -224.498154) (xy 117.582442 -224.520252)
			(xy 117.78742 -224.87509) (xy 117.81028 -224.879408) (xy 117.835109 -224.884542) (xy 117.882888 -224.901501)
			(xy 117.927508 -224.925578) (xy 117.967914 -224.956202) (xy 118.003154 -224.992654) (xy 118.032397 -225.034071)
			(xy 118.054952 -225.079478) (xy 118.070288 -225.127804) (xy 118.078043 -225.177908) (xy 118.078504 -225.203258)
			(xy 118.077996 -225.229165) (xy 118.06989 -225.280342) (xy 118.053878 -225.329621) (xy 118.030355 -225.375788)
			(xy 117.999899 -225.417707) (xy 117.963261 -225.454345) (xy 117.921342 -225.484801) (xy 117.875175 -225.508324)
			(xy 117.825896 -225.524336) (xy 117.774719 -225.532442) (xy 117.722905 -225.532442) (xy 117.671728 -225.524336)
			(xy 117.622449 -225.508324) (xy 117.576282 -225.484801) (xy 117.534363 -225.454345) (xy 117.497725 -225.417707)
			(xy 117.467269 -225.375788) (xy 117.443746 -225.329621) (xy 117.427734 -225.280342) (xy 117.419628 -225.229165)
			(xy 117.41912 -225.203258) (xy 117.419727 -225.175541) (xy 117.429042 -225.120895) (xy 117.437662 -225.094546)
			(xy 117.445536 -225.072448) (xy 117.240558 -224.71761) (xy 117.217698 -224.713292) (xy 117.192885 -224.708145)
			(xy 117.145143 -224.691153) (xy 117.100563 -224.667056) (xy 117.060196 -224.63642) (xy 117.024993 -224.599968)
			(xy 116.995782 -224.558558) (xy 116.973252 -224.513166) (xy 116.957934 -224.46486) (xy 116.950188 -224.41478)
			(xy 116.949728 -224.389442) (xy 116.668804 -224.389442) (xy 116.668296 -224.415329) (xy 116.660197 -224.466467)
			(xy 116.644198 -224.515707) (xy 116.620692 -224.561839) (xy 116.59026 -224.603726) (xy 116.55365 -224.640336)
			(xy 116.511763 -224.670768) (xy 116.465631 -224.694274) (xy 116.416391 -224.710273) (xy 116.365253 -224.718372)
			(xy 116.313479 -224.718372) (xy 116.262341 -224.710273) (xy 116.213101 -224.694274) (xy 116.166969 -224.670768)
			(xy 116.125082 -224.640336) (xy 116.088472 -224.603726) (xy 116.05804 -224.561839) (xy 116.034534 -224.515707)
			(xy 116.018535 -224.466467) (xy 116.010436 -224.415329) (xy 116.009928 -224.389442) (xy 115.729004 -224.389442)
			(xy 115.72846 -224.417149) (xy 115.719274 -224.471796) (xy 115.710716 -224.498154) (xy 115.702842 -224.520252)
			(xy 115.90782 -224.87509) (xy 115.93068 -224.879408) (xy 115.955509 -224.884542) (xy 116.003288 -224.901501)
			(xy 116.047908 -224.925578) (xy 116.088314 -224.956202) (xy 116.123554 -224.992654) (xy 116.152797 -225.034071)
			(xy 116.175352 -225.079478) (xy 116.190688 -225.127804) (xy 116.198443 -225.177908) (xy 116.198904 -225.203258)
			(xy 116.198396 -225.229165) (xy 116.19029 -225.280342) (xy 116.174278 -225.329621) (xy 116.150755 -225.375788)
			(xy 116.120299 -225.417707) (xy 116.083661 -225.454345) (xy 116.041742 -225.484801) (xy 115.995575 -225.508324)
			(xy 115.946296 -225.524336) (xy 115.895119 -225.532442) (xy 115.843305 -225.532442) (xy 115.792128 -225.524336)
			(xy 115.742849 -225.508324) (xy 115.696682 -225.484801) (xy 115.654763 -225.454345) (xy 115.618125 -225.417707)
			(xy 115.587669 -225.375788) (xy 115.564146 -225.329621) (xy 115.548134 -225.280342) (xy 115.540028 -225.229165)
			(xy 115.53952 -225.203258) (xy 115.540127 -225.175541) (xy 115.549442 -225.120895) (xy 115.558062 -225.094546)
			(xy 115.565936 -225.072448) (xy 115.360958 -224.71761) (xy 115.338098 -224.713292) (xy 115.313285 -224.708145)
			(xy 115.265543 -224.691153) (xy 115.220963 -224.667056) (xy 115.180596 -224.63642) (xy 115.145393 -224.599968)
			(xy 115.116182 -224.558558) (xy 115.093652 -224.513166) (xy 115.078334 -224.46486) (xy 115.070588 -224.41478)
			(xy 115.070128 -224.389442) (xy 114.789204 -224.389442) (xy 114.788696 -224.415329) (xy 114.780597 -224.466467)
			(xy 114.764598 -224.515707) (xy 114.741092 -224.561839) (xy 114.71066 -224.603726) (xy 114.67405 -224.640336)
			(xy 114.632163 -224.670768) (xy 114.586031 -224.694274) (xy 114.536791 -224.710273) (xy 114.485653 -224.718372)
			(xy 114.433879 -224.718372) (xy 114.382741 -224.710273) (xy 114.333501 -224.694274) (xy 114.287369 -224.670768)
			(xy 114.245482 -224.640336) (xy 114.208872 -224.603726) (xy 114.17844 -224.561839) (xy 114.154934 -224.515707)
			(xy 114.138935 -224.466467) (xy 114.130836 -224.415329) (xy 114.130328 -224.389442) (xy 113.849404 -224.389442)
			(xy 113.84886 -224.417149) (xy 113.839674 -224.471796) (xy 113.831116 -224.498154) (xy 113.823242 -224.520252)
			(xy 114.02822 -224.87509) (xy 114.05108 -224.879408) (xy 114.075909 -224.884542) (xy 114.123688 -224.901501)
			(xy 114.168308 -224.925578) (xy 114.208714 -224.956202) (xy 114.243954 -224.992654) (xy 114.273197 -225.034071)
			(xy 114.295752 -225.079478) (xy 114.311088 -225.127804) (xy 114.318843 -225.177908) (xy 114.319304 -225.203258)
			(xy 114.318796 -225.229165) (xy 114.31069 -225.280342) (xy 114.294678 -225.329621) (xy 114.271155 -225.375788)
			(xy 114.240699 -225.417707) (xy 114.204061 -225.454345) (xy 114.162142 -225.484801) (xy 114.115975 -225.508324)
			(xy 114.066696 -225.524336) (xy 114.015519 -225.532442) (xy 113.963705 -225.532442) (xy 113.912528 -225.524336)
			(xy 113.863249 -225.508324) (xy 113.817082 -225.484801) (xy 113.775163 -225.454345) (xy 113.738525 -225.417707)
			(xy 113.708069 -225.375788) (xy 113.684546 -225.329621) (xy 113.668534 -225.280342) (xy 113.660428 -225.229165)
			(xy 113.65992 -225.203258) (xy 113.660527 -225.175541) (xy 113.669842 -225.120895) (xy 113.678462 -225.094546)
			(xy 113.686336 -225.072448) (xy 113.481358 -224.71761) (xy 113.458498 -224.713292) (xy 113.433685 -224.708145)
			(xy 113.385943 -224.691153) (xy 113.341363 -224.667056) (xy 113.300996 -224.63642) (xy 113.265793 -224.599968)
			(xy 113.236582 -224.558558) (xy 113.214052 -224.513166) (xy 113.198734 -224.46486) (xy 113.190988 -224.41478)
			(xy 113.190528 -224.389442) (xy 112.909604 -224.389442) (xy 112.909096 -224.415329) (xy 112.900997 -224.466467)
			(xy 112.884998 -224.515707) (xy 112.861492 -224.561839) (xy 112.83106 -224.603726) (xy 112.79445 -224.640336)
			(xy 112.752563 -224.670768) (xy 112.706431 -224.694274) (xy 112.657191 -224.710273) (xy 112.606053 -224.718372)
			(xy 112.554279 -224.718372) (xy 112.503141 -224.710273) (xy 112.453901 -224.694274) (xy 112.407769 -224.670768)
			(xy 112.365882 -224.640336) (xy 112.329272 -224.603726) (xy 112.29884 -224.561839) (xy 112.275334 -224.515707)
			(xy 112.259335 -224.466467) (xy 112.251236 -224.415329) (xy 112.250728 -224.389442) (xy 111.969804 -224.389442)
			(xy 111.96926 -224.417149) (xy 111.960074 -224.471796) (xy 111.951516 -224.498154) (xy 111.943642 -224.520252)
			(xy 112.14862 -224.87509) (xy 112.17148 -224.879408) (xy 112.196309 -224.884542) (xy 112.244088 -224.901501)
			(xy 112.288708 -224.925578) (xy 112.329114 -224.956202) (xy 112.364354 -224.992654) (xy 112.393597 -225.034071)
			(xy 112.416152 -225.079478) (xy 112.431488 -225.127804) (xy 112.439243 -225.177908) (xy 112.439704 -225.203258)
			(xy 112.439196 -225.229165) (xy 112.43109 -225.280342) (xy 112.415078 -225.329621) (xy 112.391555 -225.375788)
			(xy 112.361099 -225.417707) (xy 112.324461 -225.454345) (xy 112.282542 -225.484801) (xy 112.236375 -225.508324)
			(xy 112.187096 -225.524336) (xy 112.135919 -225.532442) (xy 112.084105 -225.532442) (xy 112.032928 -225.524336)
			(xy 111.983649 -225.508324) (xy 111.937482 -225.484801) (xy 111.895563 -225.454345) (xy 111.858925 -225.417707)
			(xy 111.828469 -225.375788) (xy 111.804946 -225.329621) (xy 111.788934 -225.280342) (xy 111.780828 -225.229165)
			(xy 111.78032 -225.203258) (xy 111.780927 -225.175541) (xy 111.790242 -225.120895) (xy 111.798862 -225.094546)
			(xy 111.806736 -225.072448) (xy 111.601758 -224.71761) (xy 111.578898 -224.713292) (xy 111.554085 -224.708145)
			(xy 111.506343 -224.691153) (xy 111.461763 -224.667056) (xy 111.421396 -224.63642) (xy 111.386193 -224.599968)
			(xy 111.356982 -224.558558) (xy 111.334452 -224.513166) (xy 111.319134 -224.46486) (xy 111.311388 -224.41478)
			(xy 111.310928 -224.389442) (xy 111.030004 -224.389442) (xy 111.029496 -224.415329) (xy 111.021397 -224.466467)
			(xy 111.005398 -224.515707) (xy 110.981892 -224.561839) (xy 110.95146 -224.603726) (xy 110.91485 -224.640336)
			(xy 110.872963 -224.670768) (xy 110.826831 -224.694274) (xy 110.777591 -224.710273) (xy 110.726453 -224.718372)
			(xy 110.674679 -224.718372) (xy 110.623541 -224.710273) (xy 110.574301 -224.694274) (xy 110.528169 -224.670768)
			(xy 110.486282 -224.640336) (xy 110.449672 -224.603726) (xy 110.41924 -224.561839) (xy 110.395734 -224.515707)
			(xy 110.379735 -224.466467) (xy 110.371636 -224.415329) (xy 110.371128 -224.389442) (xy 110.090204 -224.389442)
			(xy 110.08966 -224.417149) (xy 110.080474 -224.471796) (xy 110.071916 -224.498154) (xy 110.064042 -224.520252)
			(xy 110.26902 -224.87509) (xy 110.29188 -224.879408) (xy 110.316709 -224.884542) (xy 110.364488 -224.901501)
			(xy 110.409108 -224.925578) (xy 110.449514 -224.956202) (xy 110.484754 -224.992654) (xy 110.513997 -225.034071)
			(xy 110.536552 -225.079478) (xy 110.551888 -225.127804) (xy 110.559643 -225.177908) (xy 110.560104 -225.203258)
			(xy 110.559596 -225.229165) (xy 110.55149 -225.280342) (xy 110.535478 -225.329621) (xy 110.511955 -225.375788)
			(xy 110.481499 -225.417707) (xy 110.444861 -225.454345) (xy 110.402942 -225.484801) (xy 110.356775 -225.508324)
			(xy 110.307496 -225.524336) (xy 110.256319 -225.532442) (xy 110.204505 -225.532442) (xy 110.153328 -225.524336)
			(xy 110.104049 -225.508324) (xy 110.057882 -225.484801) (xy 110.015963 -225.454345) (xy 109.979325 -225.417707)
			(xy 109.948869 -225.375788) (xy 109.925346 -225.329621) (xy 109.909334 -225.280342) (xy 109.901228 -225.229165)
			(xy 109.90072 -225.203258) (xy 109.901327 -225.175541) (xy 109.910642 -225.120895) (xy 109.919262 -225.094546)
			(xy 109.927136 -225.072448) (xy 109.722158 -224.71761) (xy 109.699298 -224.713292) (xy 109.674485 -224.708145)
			(xy 109.626743 -224.691153) (xy 109.582163 -224.667056) (xy 109.541796 -224.63642) (xy 109.506593 -224.599968)
			(xy 109.477382 -224.558558) (xy 109.454852 -224.513166) (xy 109.439534 -224.46486) (xy 109.431788 -224.41478)
			(xy 109.431328 -224.389442) (xy 109.150404 -224.389442) (xy 109.149896 -224.415329) (xy 109.141797 -224.466467)
			(xy 109.125798 -224.515707) (xy 109.102292 -224.561839) (xy 109.07186 -224.603726) (xy 109.03525 -224.640336)
			(xy 108.993363 -224.670768) (xy 108.947231 -224.694274) (xy 108.897991 -224.710273) (xy 108.846853 -224.718372)
			(xy 108.795079 -224.718372) (xy 108.743941 -224.710273) (xy 108.694701 -224.694274) (xy 108.648569 -224.670768)
			(xy 108.606682 -224.640336) (xy 108.570072 -224.603726) (xy 108.53964 -224.561839) (xy 108.516134 -224.515707)
			(xy 108.500135 -224.466467) (xy 108.492036 -224.415329) (xy 108.491528 -224.389442) (xy 108.210604 -224.389442)
			(xy 108.21006 -224.417149) (xy 108.200874 -224.471796) (xy 108.192316 -224.498154) (xy 108.184442 -224.520252)
			(xy 108.38942 -224.87509) (xy 108.41228 -224.879408) (xy 108.437109 -224.884542) (xy 108.484888 -224.901501)
			(xy 108.529508 -224.925578) (xy 108.569914 -224.956202) (xy 108.605154 -224.992654) (xy 108.634397 -225.034071)
			(xy 108.656952 -225.079478) (xy 108.672288 -225.127804) (xy 108.680043 -225.177908) (xy 108.680504 -225.203258)
			(xy 108.679996 -225.229165) (xy 108.67189 -225.280342) (xy 108.655878 -225.329621) (xy 108.632355 -225.375788)
			(xy 108.601899 -225.417707) (xy 108.565261 -225.454345) (xy 108.523342 -225.484801) (xy 108.477175 -225.508324)
			(xy 108.427896 -225.524336) (xy 108.376719 -225.532442) (xy 108.324905 -225.532442) (xy 108.273728 -225.524336)
			(xy 108.224449 -225.508324) (xy 108.178282 -225.484801) (xy 108.136363 -225.454345) (xy 108.099725 -225.417707)
			(xy 108.069269 -225.375788) (xy 108.045746 -225.329621) (xy 108.029734 -225.280342) (xy 108.021628 -225.229165)
			(xy 108.02112 -225.203258) (xy 108.021727 -225.175541) (xy 108.031042 -225.120895) (xy 108.039662 -225.094546)
			(xy 108.047536 -225.072448) (xy 107.842558 -224.71761) (xy 107.819698 -224.713292) (xy 107.794885 -224.708145)
			(xy 107.747143 -224.691153) (xy 107.702563 -224.667056) (xy 107.662196 -224.63642) (xy 107.626993 -224.599968)
			(xy 107.597782 -224.558558) (xy 107.575252 -224.513166) (xy 107.559934 -224.46486) (xy 107.552188 -224.41478)
			(xy 107.551728 -224.389442) (xy 107.270804 -224.389442) (xy 107.270296 -224.415329) (xy 107.262197 -224.466467)
			(xy 107.246198 -224.515707) (xy 107.222692 -224.561839) (xy 107.19226 -224.603726) (xy 107.15565 -224.640336)
			(xy 107.113763 -224.670768) (xy 107.067631 -224.694274) (xy 107.018391 -224.710273) (xy 106.967253 -224.718372)
			(xy 106.915479 -224.718372) (xy 106.864341 -224.710273) (xy 106.815101 -224.694274) (xy 106.768969 -224.670768)
			(xy 106.727082 -224.640336) (xy 106.690472 -224.603726) (xy 106.66004 -224.561839) (xy 106.636534 -224.515707)
			(xy 106.620535 -224.466467) (xy 106.612436 -224.415329) (xy 106.611928 -224.389442) (xy 106.331004 -224.389442)
			(xy 106.33046 -224.417149) (xy 106.321274 -224.471796) (xy 106.312716 -224.498154) (xy 106.304842 -224.520252)
			(xy 106.50982 -224.87509) (xy 106.53268 -224.879408) (xy 106.557509 -224.884542) (xy 106.605288 -224.901501)
			(xy 106.649908 -224.925578) (xy 106.690314 -224.956202) (xy 106.725554 -224.992654) (xy 106.754797 -225.034071)
			(xy 106.777352 -225.079478) (xy 106.792688 -225.127804) (xy 106.800443 -225.177908) (xy 106.800904 -225.203258)
			(xy 106.800396 -225.229165) (xy 106.79229 -225.280342) (xy 106.776278 -225.329621) (xy 106.752755 -225.375788)
			(xy 106.722299 -225.417707) (xy 106.685661 -225.454345) (xy 106.643742 -225.484801) (xy 106.597575 -225.508324)
			(xy 106.548296 -225.524336) (xy 106.497119 -225.532442) (xy 106.445305 -225.532442) (xy 106.394128 -225.524336)
			(xy 106.344849 -225.508324) (xy 106.298682 -225.484801) (xy 106.256763 -225.454345) (xy 106.220125 -225.417707)
			(xy 106.189669 -225.375788) (xy 106.166146 -225.329621) (xy 106.150134 -225.280342) (xy 106.142028 -225.229165)
			(xy 106.14152 -225.203258) (xy 106.142127 -225.175541) (xy 106.151442 -225.120895) (xy 106.160062 -225.094546)
			(xy 106.167936 -225.072448) (xy 105.962958 -224.71761) (xy 105.940098 -224.713292) (xy 105.915285 -224.708145)
			(xy 105.867543 -224.691153) (xy 105.822963 -224.667056) (xy 105.782596 -224.63642) (xy 105.747393 -224.599968)
			(xy 105.718182 -224.558558) (xy 105.695652 -224.513166) (xy 105.680334 -224.46486) (xy 105.672588 -224.41478)
			(xy 105.672128 -224.389442) (xy 105.391204 -224.389442) (xy 105.390696 -224.415329) (xy 105.382597 -224.466467)
			(xy 105.366598 -224.515707) (xy 105.343092 -224.561839) (xy 105.31266 -224.603726) (xy 105.27605 -224.640336)
			(xy 105.234163 -224.670768) (xy 105.188031 -224.694274) (xy 105.138791 -224.710273) (xy 105.087653 -224.718372)
			(xy 105.035879 -224.718372) (xy 104.984741 -224.710273) (xy 104.935501 -224.694274) (xy 104.889369 -224.670768)
			(xy 104.847482 -224.640336) (xy 104.810872 -224.603726) (xy 104.78044 -224.561839) (xy 104.756934 -224.515707)
			(xy 104.740935 -224.466467) (xy 104.732836 -224.415329) (xy 104.732328 -224.389442) (xy 104.451404 -224.389442)
			(xy 104.45086 -224.417149) (xy 104.441674 -224.471796) (xy 104.433116 -224.498154) (xy 104.425242 -224.520252)
			(xy 104.63022 -224.87509) (xy 104.65308 -224.879408) (xy 104.677909 -224.884542) (xy 104.725688 -224.901501)
			(xy 104.770308 -224.925578) (xy 104.810714 -224.956202) (xy 104.845954 -224.992654) (xy 104.875197 -225.034071)
			(xy 104.897752 -225.079478) (xy 104.913088 -225.127804) (xy 104.920843 -225.177908) (xy 104.921304 -225.203258)
			(xy 104.920796 -225.229165) (xy 104.91269 -225.280342) (xy 104.896678 -225.329621) (xy 104.873155 -225.375788)
			(xy 104.842699 -225.417707) (xy 104.806061 -225.454345) (xy 104.764142 -225.484801) (xy 104.717975 -225.508324)
			(xy 104.668696 -225.524336) (xy 104.617519 -225.532442) (xy 104.565705 -225.532442) (xy 104.514528 -225.524336)
			(xy 104.465249 -225.508324) (xy 104.419082 -225.484801) (xy 104.377163 -225.454345) (xy 104.340525 -225.417707)
			(xy 104.310069 -225.375788) (xy 104.286546 -225.329621) (xy 104.270534 -225.280342) (xy 104.262428 -225.229165)
			(xy 104.26192 -225.203258) (xy 104.262527 -225.175541) (xy 104.271842 -225.120895) (xy 104.280462 -225.094546)
			(xy 104.288336 -225.072448) (xy 104.083358 -224.71761) (xy 104.060498 -224.713292) (xy 104.035685 -224.708145)
			(xy 103.987943 -224.691153) (xy 103.943363 -224.667056) (xy 103.902996 -224.63642) (xy 103.867793 -224.599968)
			(xy 103.838582 -224.558558) (xy 103.816052 -224.513166) (xy 103.800734 -224.46486) (xy 103.792988 -224.41478)
			(xy 103.792528 -224.389442) (xy 103.511604 -224.389442) (xy 103.511096 -224.415329) (xy 103.502997 -224.466467)
			(xy 103.486998 -224.515707) (xy 103.463492 -224.561839) (xy 103.43306 -224.603726) (xy 103.39645 -224.640336)
			(xy 103.354563 -224.670768) (xy 103.308431 -224.694274) (xy 103.259191 -224.710273) (xy 103.208053 -224.718372)
			(xy 103.156279 -224.718372) (xy 103.105141 -224.710273) (xy 103.055901 -224.694274) (xy 103.009769 -224.670768)
			(xy 102.967882 -224.640336) (xy 102.931272 -224.603726) (xy 102.90084 -224.561839) (xy 102.877334 -224.515707)
			(xy 102.861335 -224.466467) (xy 102.853236 -224.415329) (xy 102.852728 -224.389442) (xy 102.571804 -224.389442)
			(xy 102.57126 -224.417149) (xy 102.562074 -224.471796) (xy 102.553516 -224.498154) (xy 102.545642 -224.520252)
			(xy 102.75062 -224.87509) (xy 102.77348 -224.879408) (xy 102.798309 -224.884542) (xy 102.846088 -224.901501)
			(xy 102.890708 -224.925578) (xy 102.931114 -224.956202) (xy 102.966354 -224.992654) (xy 102.995597 -225.034071)
			(xy 103.018152 -225.079478) (xy 103.033488 -225.127804) (xy 103.041243 -225.177908) (xy 103.041704 -225.203258)
			(xy 103.041196 -225.229165) (xy 103.03309 -225.280342) (xy 103.017078 -225.329621) (xy 102.993555 -225.375788)
			(xy 102.963099 -225.417707) (xy 102.926461 -225.454345) (xy 102.884542 -225.484801) (xy 102.838375 -225.508324)
			(xy 102.789096 -225.524336) (xy 102.737919 -225.532442) (xy 102.686105 -225.532442) (xy 102.634928 -225.524336)
			(xy 102.585649 -225.508324) (xy 102.539482 -225.484801) (xy 102.497563 -225.454345) (xy 102.460925 -225.417707)
			(xy 102.430469 -225.375788) (xy 102.406946 -225.329621) (xy 102.390934 -225.280342) (xy 102.382828 -225.229165)
			(xy 102.38232 -225.203258) (xy 102.382927 -225.175541) (xy 102.392242 -225.120895) (xy 102.400862 -225.094546)
			(xy 102.408736 -225.072448) (xy 102.203758 -224.71761) (xy 102.180898 -224.713292) (xy 102.156085 -224.708145)
			(xy 102.108343 -224.691153) (xy 102.063763 -224.667056) (xy 102.023396 -224.63642) (xy 101.988193 -224.599968)
			(xy 101.958982 -224.558558) (xy 101.936452 -224.513166) (xy 101.921134 -224.46486) (xy 101.913388 -224.41478)
			(xy 101.912928 -224.389442) (xy 101.632004 -224.389442) (xy 101.631496 -224.415329) (xy 101.623397 -224.466467)
			(xy 101.607398 -224.515707) (xy 101.583892 -224.561839) (xy 101.55346 -224.603726) (xy 101.51685 -224.640336)
			(xy 101.474963 -224.670768) (xy 101.428831 -224.694274) (xy 101.379591 -224.710273) (xy 101.328453 -224.718372)
			(xy 101.276679 -224.718372) (xy 101.225541 -224.710273) (xy 101.176301 -224.694274) (xy 101.130169 -224.670768)
			(xy 101.088282 -224.640336) (xy 101.051672 -224.603726) (xy 101.02124 -224.561839) (xy 100.997734 -224.515707)
			(xy 100.981735 -224.466467) (xy 100.973636 -224.415329) (xy 100.973128 -224.389442) (xy 100.692204 -224.389442)
			(xy 100.69166 -224.417149) (xy 100.682474 -224.471796) (xy 100.673916 -224.498154) (xy 100.666042 -224.520252)
			(xy 100.87102 -224.87509) (xy 100.89388 -224.879408) (xy 100.918709 -224.884542) (xy 100.966488 -224.901501)
			(xy 101.011108 -224.925578) (xy 101.051514 -224.956202) (xy 101.086754 -224.992654) (xy 101.115997 -225.034071)
			(xy 101.138552 -225.079478) (xy 101.153888 -225.127804) (xy 101.161643 -225.177908) (xy 101.162104 -225.203258)
			(xy 101.161596 -225.229165) (xy 101.15349 -225.280342) (xy 101.137478 -225.329621) (xy 101.113955 -225.375788)
			(xy 101.083499 -225.417707) (xy 101.046861 -225.454345) (xy 101.004942 -225.484801) (xy 100.958775 -225.508324)
			(xy 100.909496 -225.524336) (xy 100.858319 -225.532442) (xy 100.806505 -225.532442) (xy 100.755328 -225.524336)
			(xy 100.706049 -225.508324) (xy 100.659882 -225.484801) (xy 100.617963 -225.454345) (xy 100.581325 -225.417707)
			(xy 100.550869 -225.375788) (xy 100.527346 -225.329621) (xy 100.511334 -225.280342) (xy 100.503228 -225.229165)
			(xy 100.50272 -225.203258) (xy 100.503327 -225.175541) (xy 100.512642 -225.120895) (xy 100.521262 -225.094546)
			(xy 100.529136 -225.072448) (xy 100.324158 -224.71761) (xy 100.301298 -224.713292) (xy 100.276485 -224.708145)
			(xy 100.228743 -224.691153) (xy 100.184163 -224.667056) (xy 100.143796 -224.63642) (xy 100.108593 -224.599968)
			(xy 100.079382 -224.558558) (xy 100.056852 -224.513166) (xy 100.041534 -224.46486) (xy 100.033788 -224.41478)
			(xy 100.033328 -224.389442) (xy 99.752404 -224.389442) (xy 99.751896 -224.415329) (xy 99.743797 -224.466467)
			(xy 99.727798 -224.515707) (xy 99.704292 -224.561839) (xy 99.67386 -224.603726) (xy 99.63725 -224.640336)
			(xy 99.595363 -224.670768) (xy 99.549231 -224.694274) (xy 99.499991 -224.710273) (xy 99.448853 -224.718372)
			(xy 99.397079 -224.718372) (xy 99.345941 -224.710273) (xy 99.296701 -224.694274) (xy 99.250569 -224.670768)
			(xy 99.208682 -224.640336) (xy 99.172072 -224.603726) (xy 99.14164 -224.561839) (xy 99.118134 -224.515707)
			(xy 99.102135 -224.466467) (xy 99.094036 -224.415329) (xy 99.093528 -224.389442) (xy 98.812604 -224.389442)
			(xy 98.81206 -224.417149) (xy 98.802874 -224.471796) (xy 98.794316 -224.498154) (xy 98.786442 -224.520252)
			(xy 98.99142 -224.87509) (xy 99.01428 -224.879408) (xy 99.039109 -224.884542) (xy 99.086888 -224.901501)
			(xy 99.131508 -224.925578) (xy 99.171914 -224.956202) (xy 99.207154 -224.992654) (xy 99.236397 -225.034071)
			(xy 99.258952 -225.079478) (xy 99.274288 -225.127804) (xy 99.282043 -225.177908) (xy 99.282504 -225.203258)
			(xy 99.281996 -225.229165) (xy 99.27389 -225.280342) (xy 99.257878 -225.329621) (xy 99.234355 -225.375788)
			(xy 99.203899 -225.417707) (xy 99.167261 -225.454345) (xy 99.125342 -225.484801) (xy 99.079175 -225.508324)
			(xy 99.029896 -225.524336) (xy 98.978719 -225.532442) (xy 98.926905 -225.532442) (xy 98.875728 -225.524336)
			(xy 98.826449 -225.508324) (xy 98.780282 -225.484801) (xy 98.738363 -225.454345) (xy 98.701725 -225.417707)
			(xy 98.671269 -225.375788) (xy 98.647746 -225.329621) (xy 98.631734 -225.280342) (xy 98.623628 -225.229165)
			(xy 98.62312 -225.203258) (xy 98.623727 -225.175541) (xy 98.633042 -225.120895) (xy 98.641662 -225.094546)
			(xy 98.649536 -225.072448) (xy 98.444558 -224.71761) (xy 98.421698 -224.713292) (xy 98.396885 -224.708145)
			(xy 98.349143 -224.691153) (xy 98.304563 -224.667056) (xy 98.264196 -224.63642) (xy 98.228993 -224.599968)
			(xy 98.199782 -224.558558) (xy 98.177252 -224.513166) (xy 98.161934 -224.46486) (xy 98.154188 -224.41478)
			(xy 98.153728 -224.389442) (xy 97.872804 -224.389442) (xy 97.872296 -224.415329) (xy 97.864197 -224.466467)
			(xy 97.848198 -224.515707) (xy 97.824692 -224.561839) (xy 97.79426 -224.603726) (xy 97.75765 -224.640336)
			(xy 97.715763 -224.670768) (xy 97.669631 -224.694274) (xy 97.620391 -224.710273) (xy 97.569253 -224.718372)
			(xy 97.517479 -224.718372) (xy 97.466341 -224.710273) (xy 97.417101 -224.694274) (xy 97.370969 -224.670768)
			(xy 97.329082 -224.640336) (xy 97.292472 -224.603726) (xy 97.26204 -224.561839) (xy 97.238534 -224.515707)
			(xy 97.222535 -224.466467) (xy 97.214436 -224.415329) (xy 97.213928 -224.389442) (xy 96.933004 -224.389442)
			(xy 96.93246 -224.417149) (xy 96.923274 -224.471796) (xy 96.914716 -224.498154) (xy 96.906842 -224.520252)
			(xy 97.11182 -224.87509) (xy 97.13468 -224.879408) (xy 97.159509 -224.884542) (xy 97.207288 -224.901501)
			(xy 97.251908 -224.925578) (xy 97.292314 -224.956202) (xy 97.327554 -224.992654) (xy 97.356797 -225.034071)
			(xy 97.379352 -225.079478) (xy 97.394688 -225.127804) (xy 97.402443 -225.177908) (xy 97.402904 -225.203258)
			(xy 97.402396 -225.229165) (xy 97.39429 -225.280342) (xy 97.378278 -225.329621) (xy 97.354755 -225.375788)
			(xy 97.324299 -225.417707) (xy 97.287661 -225.454345) (xy 97.245742 -225.484801) (xy 97.199575 -225.508324)
			(xy 97.150296 -225.524336) (xy 97.099119 -225.532442) (xy 97.047305 -225.532442) (xy 96.996128 -225.524336)
			(xy 96.946849 -225.508324) (xy 96.900682 -225.484801) (xy 96.858763 -225.454345) (xy 96.822125 -225.417707)
			(xy 96.791669 -225.375788) (xy 96.768146 -225.329621) (xy 96.752134 -225.280342) (xy 96.744028 -225.229165)
			(xy 96.74352 -225.203258) (xy 96.744127 -225.175541) (xy 96.753442 -225.120895) (xy 96.762062 -225.094546)
			(xy 96.769936 -225.072448) (xy 96.564958 -224.71761) (xy 96.542098 -224.713292) (xy 96.517285 -224.708145)
			(xy 96.469543 -224.691153) (xy 96.424963 -224.667056) (xy 96.384596 -224.63642) (xy 96.349393 -224.599968)
			(xy 96.320182 -224.558558) (xy 96.297652 -224.513166) (xy 96.282334 -224.46486) (xy 96.274588 -224.41478)
			(xy 96.274128 -224.389442) (xy 95.993204 -224.389442) (xy 95.992696 -224.415329) (xy 95.984597 -224.466467)
			(xy 95.968598 -224.515707) (xy 95.945092 -224.561839) (xy 95.91466 -224.603726) (xy 95.87805 -224.640336)
			(xy 95.836163 -224.670768) (xy 95.790031 -224.694274) (xy 95.740791 -224.710273) (xy 95.689653 -224.718372)
			(xy 95.637879 -224.718372) (xy 95.586741 -224.710273) (xy 95.537501 -224.694274) (xy 95.491369 -224.670768)
			(xy 95.449482 -224.640336) (xy 95.412872 -224.603726) (xy 95.38244 -224.561839) (xy 95.358934 -224.515707)
			(xy 95.342935 -224.466467) (xy 95.334836 -224.415329) (xy 95.334328 -224.389442) (xy 95.053404 -224.389442)
			(xy 95.05286 -224.417149) (xy 95.043674 -224.471796) (xy 95.035116 -224.498154) (xy 95.027242 -224.520252)
			(xy 95.23222 -224.87509) (xy 95.25508 -224.879408) (xy 95.279909 -224.884542) (xy 95.327688 -224.901501)
			(xy 95.372308 -224.925578) (xy 95.412714 -224.956202) (xy 95.447954 -224.992654) (xy 95.477197 -225.034071)
			(xy 95.499752 -225.079478) (xy 95.515088 -225.127804) (xy 95.522843 -225.177908) (xy 95.523304 -225.203258)
			(xy 95.522796 -225.229165) (xy 95.51469 -225.280342) (xy 95.498678 -225.329621) (xy 95.475155 -225.375788)
			(xy 95.444699 -225.417707) (xy 95.408061 -225.454345) (xy 95.366142 -225.484801) (xy 95.319975 -225.508324)
			(xy 95.270696 -225.524336) (xy 95.219519 -225.532442) (xy 95.167705 -225.532442) (xy 95.116528 -225.524336)
			(xy 95.067249 -225.508324) (xy 95.021082 -225.484801) (xy 94.979163 -225.454345) (xy 94.942525 -225.417707)
			(xy 94.912069 -225.375788) (xy 94.888546 -225.329621) (xy 94.872534 -225.280342) (xy 94.864428 -225.229165)
			(xy 94.86392 -225.203258) (xy 94.864527 -225.175541) (xy 94.873842 -225.120895) (xy 94.882462 -225.094546)
			(xy 94.890336 -225.072448) (xy 94.685358 -224.71761) (xy 94.662498 -224.713292) (xy 94.637685 -224.708145)
			(xy 94.589943 -224.691153) (xy 94.545363 -224.667056) (xy 94.504996 -224.63642) (xy 94.469793 -224.599968)
			(xy 94.440582 -224.558558) (xy 94.418052 -224.513166) (xy 94.402734 -224.46486) (xy 94.394988 -224.41478)
			(xy 94.394528 -224.389442) (xy 94.113604 -224.389442) (xy 94.113096 -224.415329) (xy 94.104997 -224.466467)
			(xy 94.088998 -224.515707) (xy 94.065492 -224.561839) (xy 94.03506 -224.603726) (xy 93.99845 -224.640336)
			(xy 93.956563 -224.670768) (xy 93.910431 -224.694274) (xy 93.861191 -224.710273) (xy 93.810053 -224.718372)
			(xy 93.758279 -224.718372) (xy 93.707141 -224.710273) (xy 93.657901 -224.694274) (xy 93.611769 -224.670768)
			(xy 93.569882 -224.640336) (xy 93.533272 -224.603726) (xy 93.50284 -224.561839) (xy 93.479334 -224.515707)
			(xy 93.463335 -224.466467) (xy 93.455236 -224.415329) (xy 93.454728 -224.389442) (xy 93.173804 -224.389442)
			(xy 93.173804 -224.38995) (xy 93.173247 -224.417593) (xy 93.164056 -224.472111) (xy 93.155516 -224.498408)
			(xy 93.147896 -224.520252) (xy 93.35262 -224.87509) (xy 93.37548 -224.879408) (xy 93.400309 -224.884542)
			(xy 93.448088 -224.901501) (xy 93.492708 -224.925578) (xy 93.533114 -224.956202) (xy 93.568354 -224.992654)
			(xy 93.597597 -225.034071) (xy 93.620152 -225.079478) (xy 93.635488 -225.127804) (xy 93.643243 -225.177908)
			(xy 93.643704 -225.203258) (xy 93.643196 -225.229165) (xy 93.63509 -225.280342) (xy 93.619078 -225.329621)
			(xy 93.595555 -225.375788) (xy 93.565099 -225.417707) (xy 93.528461 -225.454345) (xy 93.486542 -225.484801)
			(xy 93.440375 -225.508324) (xy 93.391096 -225.524336) (xy 93.339919 -225.532442) (xy 93.288105 -225.532442)
			(xy 93.236928 -225.524336) (xy 93.187649 -225.508324) (xy 93.141482 -225.484801) (xy 93.099563 -225.454345)
			(xy 93.062925 -225.417707) (xy 93.032469 -225.375788) (xy 93.008946 -225.329621) (xy 92.992934 -225.280342)
			(xy 92.984828 -225.229165) (xy 92.98432 -225.203258) (xy 92.98432 -225.20275) (xy 92.98493 -225.175096)
			(xy 92.994253 -225.120579) (xy 93.002862 -225.094292) (xy 93.010482 -225.072448) (xy 92.805758 -224.71761)
			(xy 92.782898 -224.713292) (xy 92.758085 -224.708145) (xy 92.710343 -224.691153) (xy 92.665763 -224.667056)
			(xy 92.625396 -224.63642) (xy 92.590193 -224.599968) (xy 92.560982 -224.558558) (xy 92.538452 -224.513166)
			(xy 92.523134 -224.46486) (xy 92.515388 -224.41478) (xy 92.514928 -224.389442) (xy 91.294204 -224.389442)
			(xy 91.294204 -224.38995) (xy 91.293647 -224.417593) (xy 91.284456 -224.472111) (xy 91.275916 -224.498408)
			(xy 91.268296 -224.520252) (xy 91.47302 -224.87509) (xy 91.49588 -224.879408) (xy 91.520709 -224.884542)
			(xy 91.568488 -224.901501) (xy 91.613108 -224.925578) (xy 91.653514 -224.956202) (xy 91.688754 -224.992654)
			(xy 91.717997 -225.034071) (xy 91.740552 -225.079478) (xy 91.755888 -225.127804) (xy 91.763643 -225.177908)
			(xy 91.764104 -225.203258) (xy 91.763596 -225.229165) (xy 91.75549 -225.280342) (xy 91.739478 -225.329621)
			(xy 91.715955 -225.375788) (xy 91.685499 -225.417707) (xy 91.648861 -225.454345) (xy 91.606942 -225.484801)
			(xy 91.560775 -225.508324) (xy 91.511496 -225.524336) (xy 91.460319 -225.532442) (xy 91.408505 -225.532442)
			(xy 91.357328 -225.524336) (xy 91.308049 -225.508324) (xy 91.261882 -225.484801) (xy 91.219963 -225.454345)
			(xy 91.183325 -225.417707) (xy 91.152869 -225.375788) (xy 91.129346 -225.329621) (xy 91.113334 -225.280342)
			(xy 91.105228 -225.229165) (xy 91.10472 -225.203258) (xy 91.10472 -225.20275) (xy 91.10533 -225.175096)
			(xy 91.114653 -225.120579) (xy 91.123262 -225.094292) (xy 91.130882 -225.072448) (xy 90.926158 -224.71761)
			(xy 90.903298 -224.713292) (xy 90.878485 -224.708145) (xy 90.830743 -224.691153) (xy 90.786163 -224.667056)
			(xy 90.745796 -224.63642) (xy 90.710593 -224.599968) (xy 90.681382 -224.558558) (xy 90.658852 -224.513166)
			(xy 90.643534 -224.46486) (xy 90.635788 -224.41478) (xy 90.635328 -224.389442) (xy 90.354404 -224.389442)
			(xy 90.353896 -224.415329) (xy 90.345797 -224.466467) (xy 90.329798 -224.515707) (xy 90.306292 -224.561839)
			(xy 90.27586 -224.603726) (xy 90.23925 -224.640336) (xy 90.197363 -224.670768) (xy 90.151231 -224.694274)
			(xy 90.101991 -224.710273) (xy 90.050853 -224.718372) (xy 89.999079 -224.718372) (xy 89.947941 -224.710273)
			(xy 89.898701 -224.694274) (xy 89.852569 -224.670768) (xy 89.810682 -224.640336) (xy 89.774072 -224.603726)
			(xy 89.74364 -224.561839) (xy 89.720134 -224.515707) (xy 89.704135 -224.466467) (xy 89.696036 -224.415329)
			(xy 89.695528 -224.389442) (xy 61.698632 -224.389442) (xy 61.698632 -224.72142) (xy 61.698196 -224.731571)
			(xy 61.690399 -224.750318) (xy 61.676008 -224.76464) (xy 61.657223 -224.772345) (xy 61.64707 -224.772728)
			(xy 60.24753 -224.772728) (xy 60.237401 -224.772248) (xy 60.218675 -224.764524) (xy 60.204316 -224.750235)
			(xy 60.196501 -224.731546) (xy 60.195968 -224.72142) (xy 54.154832 -224.72142) (xy 54.154396 -224.731571)
			(xy 54.146599 -224.750318) (xy 54.132208 -224.76464) (xy 54.113423 -224.772345) (xy 54.10327 -224.772728)
			(xy 52.70373 -224.772728) (xy 52.693601 -224.772248) (xy 52.674875 -224.764524) (xy 52.660516 -224.750235)
			(xy 52.652701 -224.731546) (xy 52.652168 -224.72142) (xy 46.611032 -224.72142) (xy 46.610596 -224.731571)
			(xy 46.602799 -224.750318) (xy 46.588408 -224.76464) (xy 46.569623 -224.772345) (xy 46.55947 -224.772728)
			(xy 45.15993 -224.772728) (xy 45.149801 -224.772248) (xy 45.131075 -224.764524) (xy 45.116716 -224.750235)
			(xy 45.108901 -224.731546) (xy 45.108368 -224.72142) (xy 39.067232 -224.72142) (xy 39.066796 -224.731571)
			(xy 39.058999 -224.750318) (xy 39.044608 -224.76464) (xy 39.025823 -224.772345) (xy 39.01567 -224.772728)
			(xy 37.61613 -224.772728) (xy 37.606001 -224.772248) (xy 37.587275 -224.764524) (xy 37.572916 -224.750235)
			(xy 37.565101 -224.731546) (xy 37.564568 -224.72142) (xy 31.523432 -224.72142) (xy 31.522996 -224.731571)
			(xy 31.515199 -224.750318) (xy 31.500808 -224.76464) (xy 31.482023 -224.772345) (xy 31.47187 -224.772728)
			(xy 30.07233 -224.772728) (xy 30.062201 -224.772248) (xy 30.043475 -224.764524) (xy 30.029116 -224.750235)
			(xy 30.021301 -224.731546) (xy 30.020768 -224.72142) (xy 23.979632 -224.72142) (xy 23.979196 -224.731571)
			(xy 23.971399 -224.750318) (xy 23.957008 -224.76464) (xy 23.938223 -224.772345) (xy 23.92807 -224.772728)
			(xy 22.52853 -224.772728) (xy 22.518401 -224.772248) (xy 22.499675 -224.764524) (xy 22.485316 -224.750235)
			(xy 22.477501 -224.731546) (xy 22.476968 -224.72142) (xy 16.435832 -224.72142) (xy 16.435396 -224.731571)
			(xy 16.427599 -224.750318) (xy 16.413208 -224.76464) (xy 16.394423 -224.772345) (xy 16.38427 -224.772728)
			(xy 14.98473 -224.772728) (xy 14.974601 -224.772248) (xy 14.955875 -224.764524) (xy 14.941516 -224.750235)
			(xy 14.933701 -224.731546) (xy 14.933168 -224.72142) (xy 8.892032 -224.72142) (xy 8.891596 -224.731571)
			(xy 8.883799 -224.750318) (xy 8.869408 -224.76464) (xy 8.850623 -224.772345) (xy 8.84047 -224.772728)
			(xy 7.44093 -224.772728) (xy 7.430801 -224.772248) (xy 7.412075 -224.764524) (xy 7.397716 -224.750235)
			(xy 7.389901 -224.731546) (xy 7.389368 -224.72142) (xy 2.509012 -224.72142) (xy 2.509012 -225.571304)
			(xy 11.489436 -225.571304) (xy 11.489436 -225.162364) (xy 11.489793 -225.152203) (xy 11.497607 -225.133443)
			(xy 11.512024 -225.11912) (xy 11.530834 -225.111428) (xy 11.540998 -225.111056) (xy 12.940538 -225.111056)
			(xy 12.950669 -225.111496) (xy 12.969394 -225.119239) (xy 12.98375 -225.13354) (xy 12.991565 -225.152235)
			(xy 12.9921 -225.162364) (xy 12.9921 -225.571304) (xy 19.033236 -225.571304) (xy 19.033236 -225.162364)
			(xy 19.033593 -225.152203) (xy 19.041407 -225.133443) (xy 19.055824 -225.11912) (xy 19.074634 -225.111428)
			(xy 19.084798 -225.111056) (xy 20.484338 -225.111056) (xy 20.494469 -225.111496) (xy 20.513194 -225.119239)
			(xy 20.52755 -225.13354) (xy 20.535365 -225.152235) (xy 20.5359 -225.162364) (xy 20.5359 -225.571304)
			(xy 26.577036 -225.571304) (xy 26.577036 -225.162364) (xy 26.577393 -225.152203) (xy 26.585207 -225.133443)
			(xy 26.599624 -225.11912) (xy 26.618434 -225.111428) (xy 26.628598 -225.111056) (xy 28.028138 -225.111056)
			(xy 28.038269 -225.111496) (xy 28.056994 -225.119239) (xy 28.07135 -225.13354) (xy 28.079165 -225.152235)
			(xy 28.0797 -225.162364) (xy 28.0797 -225.571304) (xy 34.120836 -225.571304) (xy 34.120836 -225.162364)
			(xy 34.121193 -225.152203) (xy 34.129007 -225.133443) (xy 34.143424 -225.11912) (xy 34.162234 -225.111428)
			(xy 34.172398 -225.111056) (xy 35.571938 -225.111056) (xy 35.582069 -225.111496) (xy 35.600794 -225.119239)
			(xy 35.61515 -225.13354) (xy 35.622965 -225.152235) (xy 35.6235 -225.162364) (xy 35.6235 -225.571304)
			(xy 41.664636 -225.571304) (xy 41.664636 -225.162364) (xy 41.664993 -225.152203) (xy 41.672807 -225.133443)
			(xy 41.687224 -225.11912) (xy 41.706034 -225.111428) (xy 41.716198 -225.111056) (xy 43.115738 -225.111056)
			(xy 43.125869 -225.111496) (xy 43.144594 -225.119239) (xy 43.15895 -225.13354) (xy 43.166765 -225.152235)
			(xy 43.1673 -225.162364) (xy 43.1673 -225.571304) (xy 49.208436 -225.571304) (xy 49.208436 -225.162364)
			(xy 49.208793 -225.152203) (xy 49.216607 -225.133443) (xy 49.231024 -225.11912) (xy 49.249834 -225.111428)
			(xy 49.259998 -225.111056) (xy 50.659538 -225.111056) (xy 50.669669 -225.111496) (xy 50.688394 -225.119239)
			(xy 50.70275 -225.13354) (xy 50.710565 -225.152235) (xy 50.7111 -225.162364) (xy 50.7111 -225.571304)
			(xy 56.752236 -225.571304) (xy 56.752236 -225.162364) (xy 56.752593 -225.152203) (xy 56.760407 -225.133443)
			(xy 56.774824 -225.11912) (xy 56.793634 -225.111428) (xy 56.803798 -225.111056) (xy 58.203338 -225.111056)
			(xy 58.213469 -225.111496) (xy 58.232194 -225.119239) (xy 58.24655 -225.13354) (xy 58.254365 -225.152235)
			(xy 58.2549 -225.162364) (xy 58.2549 -225.571304) (xy 64.296036 -225.571304) (xy 64.296036 -225.162364)
			(xy 64.296393 -225.152203) (xy 64.304207 -225.133443) (xy 64.318624 -225.11912) (xy 64.337434 -225.111428)
			(xy 64.347598 -225.111056) (xy 65.747138 -225.111056) (xy 65.757269 -225.111496) (xy 65.775994 -225.119239)
			(xy 65.79035 -225.13354) (xy 65.798165 -225.152235) (xy 65.7987 -225.162364) (xy 65.7987 -225.571304)
			(xy 162.162236 -225.571304) (xy 162.162236 -225.162364) (xy 162.162593 -225.152203) (xy 162.170407 -225.133443)
			(xy 162.184824 -225.11912) (xy 162.203634 -225.111428) (xy 162.213798 -225.111056) (xy 163.613338 -225.111056)
			(xy 163.623469 -225.111496) (xy 163.642194 -225.119239) (xy 163.65655 -225.13354) (xy 163.664365 -225.152235)
			(xy 163.6649 -225.162364) (xy 163.6649 -225.571304) (xy 169.706036 -225.571304) (xy 169.706036 -225.162364)
			(xy 169.706393 -225.152203) (xy 169.714207 -225.133443) (xy 169.728624 -225.11912) (xy 169.747434 -225.111428)
			(xy 169.757598 -225.111056) (xy 171.157138 -225.111056) (xy 171.167269 -225.111496) (xy 171.185994 -225.119239)
			(xy 171.20035 -225.13354) (xy 171.208165 -225.152235) (xy 171.2087 -225.162364) (xy 171.2087 -225.571304)
			(xy 177.249836 -225.571304) (xy 177.249836 -225.162364) (xy 177.250193 -225.152203) (xy 177.258007 -225.133443)
			(xy 177.272424 -225.11912) (xy 177.291234 -225.111428) (xy 177.301398 -225.111056) (xy 178.700938 -225.111056)
			(xy 178.711069 -225.111496) (xy 178.729794 -225.119239) (xy 178.74415 -225.13354) (xy 178.751965 -225.152235)
			(xy 178.7525 -225.162364) (xy 178.7525 -225.571304) (xy 184.793636 -225.571304) (xy 184.793636 -225.162364)
			(xy 184.793993 -225.152203) (xy 184.801807 -225.133443) (xy 184.816224 -225.11912) (xy 184.835034 -225.111428)
			(xy 184.845198 -225.111056) (xy 186.244738 -225.111056) (xy 186.254869 -225.111496) (xy 186.273594 -225.119239)
			(xy 186.28795 -225.13354) (xy 186.295765 -225.152235) (xy 186.2963 -225.162364) (xy 186.2963 -225.571304)
			(xy 192.337436 -225.571304) (xy 192.337436 -225.162364) (xy 192.337793 -225.152203) (xy 192.345607 -225.133443)
			(xy 192.360024 -225.11912) (xy 192.378834 -225.111428) (xy 192.388998 -225.111056) (xy 193.788538 -225.111056)
			(xy 193.798669 -225.111496) (xy 193.817394 -225.119239) (xy 193.83175 -225.13354) (xy 193.839565 -225.152235)
			(xy 193.8401 -225.162364) (xy 193.8401 -225.571304) (xy 199.881236 -225.571304) (xy 199.881236 -225.162364)
			(xy 199.881593 -225.152203) (xy 199.889407 -225.133443) (xy 199.903824 -225.11912) (xy 199.922634 -225.111428)
			(xy 199.932798 -225.111056) (xy 201.332338 -225.111056) (xy 201.342469 -225.111496) (xy 201.361194 -225.119239)
			(xy 201.37555 -225.13354) (xy 201.383365 -225.152235) (xy 201.3839 -225.162364) (xy 201.3839 -225.571304)
			(xy 207.425036 -225.571304) (xy 207.425036 -225.162364) (xy 207.425393 -225.152203) (xy 207.433207 -225.133443)
			(xy 207.447624 -225.11912) (xy 207.466434 -225.111428) (xy 207.476598 -225.111056) (xy 208.876138 -225.111056)
			(xy 208.886269 -225.111496) (xy 208.904994 -225.119239) (xy 208.91935 -225.13354) (xy 208.927165 -225.152235)
			(xy 208.9277 -225.162364) (xy 208.9277 -225.571304) (xy 214.968836 -225.571304) (xy 214.968836 -225.162364)
			(xy 214.969193 -225.152203) (xy 214.977007 -225.133443) (xy 214.991424 -225.11912) (xy 215.010234 -225.111428)
			(xy 215.020398 -225.111056) (xy 216.419938 -225.111056) (xy 216.430069 -225.111496) (xy 216.448794 -225.119239)
			(xy 216.46315 -225.13354) (xy 216.470965 -225.152235) (xy 216.4715 -225.162364) (xy 216.4715 -225.571304)
			(xy 259.429504 -225.571304) (xy 259.429504 -225.162364) (xy 259.429892 -225.152207) (xy 259.4377 -225.133453)
			(xy 259.452107 -225.119131) (xy 259.470907 -225.111433) (xy 259.481066 -225.111056) (xy 260.880606 -225.111056)
			(xy 260.890735 -225.111522) (xy 260.909459 -225.119255) (xy 260.923816 -225.133548) (xy 260.931632 -225.152237)
			(xy 260.932168 -225.162364) (xy 260.932168 -225.571304) (xy 266.973304 -225.571304) (xy 266.973304 -225.162364)
			(xy 266.973692 -225.152207) (xy 266.9815 -225.133453) (xy 266.995907 -225.119131) (xy 267.014707 -225.111433)
			(xy 267.024866 -225.111056) (xy 268.424406 -225.111056) (xy 268.434535 -225.111522) (xy 268.453259 -225.119255)
			(xy 268.467616 -225.133548) (xy 268.475432 -225.152237) (xy 268.475968 -225.162364) (xy 268.475968 -225.571304)
			(xy 274.517104 -225.571304) (xy 274.517104 -225.162364) (xy 274.517492 -225.152207) (xy 274.5253 -225.133453)
			(xy 274.539707 -225.119131) (xy 274.558507 -225.111433) (xy 274.568666 -225.111056) (xy 275.968206 -225.111056)
			(xy 275.978335 -225.111522) (xy 275.997059 -225.119255) (xy 276.011416 -225.133548) (xy 276.019232 -225.152237)
			(xy 276.019768 -225.162364) (xy 276.019768 -225.571304) (xy 282.060904 -225.571304) (xy 282.060904 -225.162364)
			(xy 282.061292 -225.152207) (xy 282.0691 -225.133453) (xy 282.083507 -225.119131) (xy 282.102307 -225.111433)
			(xy 282.112466 -225.111056) (xy 283.512006 -225.111056) (xy 283.522135 -225.111522) (xy 283.540859 -225.119255)
			(xy 283.555216 -225.133548) (xy 283.563032 -225.152237) (xy 283.563568 -225.162364) (xy 283.563568 -225.571304)
			(xy 289.604704 -225.571304) (xy 289.604704 -225.162364) (xy 289.605092 -225.152207) (xy 289.6129 -225.133453)
			(xy 289.627307 -225.119131) (xy 289.646107 -225.111433) (xy 289.656266 -225.111056) (xy 291.055806 -225.111056)
			(xy 291.065935 -225.111522) (xy 291.084659 -225.119255) (xy 291.099016 -225.133548) (xy 291.106832 -225.152237)
			(xy 291.107368 -225.162364) (xy 291.107368 -225.571304) (xy 297.148504 -225.571304) (xy 297.148504 -225.162364)
			(xy 297.148892 -225.152207) (xy 297.1567 -225.133453) (xy 297.171107 -225.119131) (xy 297.189907 -225.111433)
			(xy 297.200066 -225.111056) (xy 298.599606 -225.111056) (xy 298.609735 -225.111522) (xy 298.628459 -225.119255)
			(xy 298.642816 -225.133548) (xy 298.650632 -225.152237) (xy 298.651168 -225.162364) (xy 298.651168 -225.571304)
			(xy 304.692304 -225.571304) (xy 304.692304 -225.162364) (xy 304.692692 -225.152207) (xy 304.7005 -225.133453)
			(xy 304.714907 -225.119131) (xy 304.733707 -225.111433) (xy 304.743866 -225.111056) (xy 306.143406 -225.111056)
			(xy 306.153535 -225.111522) (xy 306.172259 -225.119255) (xy 306.186616 -225.133548) (xy 306.194432 -225.152237)
			(xy 306.194968 -225.162364) (xy 306.194968 -225.571304) (xy 312.236104 -225.571304) (xy 312.236104 -225.162364)
			(xy 312.236492 -225.152207) (xy 312.2443 -225.133453) (xy 312.258707 -225.119131) (xy 312.277507 -225.111433)
			(xy 312.287666 -225.111056) (xy 313.687206 -225.111056) (xy 313.697335 -225.111522) (xy 313.716059 -225.119255)
			(xy 313.730416 -225.133548) (xy 313.738232 -225.152237) (xy 313.738768 -225.162364) (xy 313.738768 -225.571304)
			(xy 410.102304 -225.571304) (xy 410.102304 -225.162364) (xy 410.102692 -225.152207) (xy 410.1105 -225.133453)
			(xy 410.124907 -225.119131) (xy 410.143707 -225.111433) (xy 410.153866 -225.111056) (xy 411.553406 -225.111056)
			(xy 411.563535 -225.111522) (xy 411.582259 -225.119255) (xy 411.596616 -225.133548) (xy 411.604432 -225.152237)
			(xy 411.604968 -225.162364) (xy 411.604968 -225.571304) (xy 417.646104 -225.571304) (xy 417.646104 -225.162364)
			(xy 417.646492 -225.152207) (xy 417.6543 -225.133453) (xy 417.668707 -225.119131) (xy 417.687507 -225.111433)
			(xy 417.697666 -225.111056) (xy 419.097206 -225.111056) (xy 419.107335 -225.111522) (xy 419.126059 -225.119255)
			(xy 419.140416 -225.133548) (xy 419.148232 -225.152237) (xy 419.148768 -225.162364) (xy 419.148768 -225.571304)
			(xy 425.189904 -225.571304) (xy 425.189904 -225.162364) (xy 425.190292 -225.152207) (xy 425.1981 -225.133453)
			(xy 425.212507 -225.119131) (xy 425.231307 -225.111433) (xy 425.241466 -225.111056) (xy 426.641006 -225.111056)
			(xy 426.651135 -225.111522) (xy 426.669859 -225.119255) (xy 426.684216 -225.133548) (xy 426.692032 -225.152237)
			(xy 426.692568 -225.162364) (xy 426.692568 -225.571304) (xy 432.733704 -225.571304) (xy 432.733704 -225.162364)
			(xy 432.734092 -225.152207) (xy 432.7419 -225.133453) (xy 432.756307 -225.119131) (xy 432.775107 -225.111433)
			(xy 432.785266 -225.111056) (xy 434.184806 -225.111056) (xy 434.194935 -225.111522) (xy 434.213659 -225.119255)
			(xy 434.228016 -225.133548) (xy 434.235832 -225.152237) (xy 434.236368 -225.162364) (xy 434.236368 -225.571304)
			(xy 440.277504 -225.571304) (xy 440.277504 -225.162364) (xy 440.277892 -225.152207) (xy 440.2857 -225.133453)
			(xy 440.300107 -225.119131) (xy 440.318907 -225.111433) (xy 440.329066 -225.111056) (xy 441.728606 -225.111056)
			(xy 441.738735 -225.111522) (xy 441.757459 -225.119255) (xy 441.771816 -225.133548) (xy 441.779632 -225.152237)
			(xy 441.780168 -225.162364) (xy 441.780168 -225.571304) (xy 447.821304 -225.571304) (xy 447.821304 -225.162364)
			(xy 447.821692 -225.152207) (xy 447.8295 -225.133453) (xy 447.843907 -225.119131) (xy 447.862707 -225.111433)
			(xy 447.872866 -225.111056) (xy 449.272406 -225.111056) (xy 449.282535 -225.111522) (xy 449.301259 -225.119255)
			(xy 449.315616 -225.133548) (xy 449.323432 -225.152237) (xy 449.323968 -225.162364) (xy 449.323968 -225.571304)
			(xy 455.365104 -225.571304) (xy 455.365104 -225.162364) (xy 455.365492 -225.152207) (xy 455.3733 -225.133453)
			(xy 455.387707 -225.119131) (xy 455.406507 -225.111433) (xy 455.416666 -225.111056) (xy 456.816206 -225.111056)
			(xy 456.826335 -225.111522) (xy 456.845059 -225.119255) (xy 456.859416 -225.133548) (xy 456.867232 -225.152237)
			(xy 456.867768 -225.162364) (xy 456.867768 -225.571304) (xy 462.908904 -225.571304) (xy 462.908904 -225.162364)
			(xy 462.909292 -225.152207) (xy 462.9171 -225.133453) (xy 462.931507 -225.119131) (xy 462.950307 -225.111433)
			(xy 462.960466 -225.111056) (xy 464.360006 -225.111056) (xy 464.370135 -225.111522) (xy 464.388859 -225.119255)
			(xy 464.403216 -225.133548) (xy 464.411032 -225.152237) (xy 464.411568 -225.162364) (xy 464.411568 -225.571304)
			(xy 464.411181 -225.581462) (xy 464.403378 -225.600221) (xy 464.38897 -225.614545) (xy 464.370167 -225.622239)
			(xy 464.360006 -225.622612) (xy 462.960466 -225.622612) (xy 462.950344 -225.622103) (xy 462.931631 -225.614374)
			(xy 462.917278 -225.600095) (xy 462.909451 -225.581424) (xy 462.908904 -225.571304) (xy 456.867768 -225.571304)
			(xy 456.867381 -225.581462) (xy 456.859578 -225.600221) (xy 456.84517 -225.614545) (xy 456.826367 -225.622239)
			(xy 456.816206 -225.622612) (xy 455.416666 -225.622612) (xy 455.406544 -225.622103) (xy 455.387831 -225.614374)
			(xy 455.373478 -225.600095) (xy 455.365651 -225.581424) (xy 455.365104 -225.571304) (xy 449.323968 -225.571304)
			(xy 449.323581 -225.581462) (xy 449.315778 -225.600221) (xy 449.30137 -225.614545) (xy 449.282567 -225.622239)
			(xy 449.272406 -225.622612) (xy 447.872866 -225.622612) (xy 447.862744 -225.622103) (xy 447.844031 -225.614374)
			(xy 447.829678 -225.600095) (xy 447.821851 -225.581424) (xy 447.821304 -225.571304) (xy 441.780168 -225.571304)
			(xy 441.779781 -225.581462) (xy 441.771978 -225.600221) (xy 441.75757 -225.614545) (xy 441.738767 -225.622239)
			(xy 441.728606 -225.622612) (xy 440.329066 -225.622612) (xy 440.318944 -225.622103) (xy 440.300231 -225.614374)
			(xy 440.285878 -225.600095) (xy 440.278051 -225.581424) (xy 440.277504 -225.571304) (xy 434.236368 -225.571304)
			(xy 434.235981 -225.581462) (xy 434.228178 -225.600221) (xy 434.21377 -225.614545) (xy 434.194967 -225.622239)
			(xy 434.184806 -225.622612) (xy 432.785266 -225.622612) (xy 432.775144 -225.622103) (xy 432.756431 -225.614374)
			(xy 432.742078 -225.600095) (xy 432.734251 -225.581424) (xy 432.733704 -225.571304) (xy 426.692568 -225.571304)
			(xy 426.692181 -225.581462) (xy 426.684378 -225.600221) (xy 426.66997 -225.614545) (xy 426.651167 -225.622239)
			(xy 426.641006 -225.622612) (xy 425.241466 -225.622612) (xy 425.231344 -225.622103) (xy 425.212631 -225.614374)
			(xy 425.198278 -225.600095) (xy 425.190451 -225.581424) (xy 425.189904 -225.571304) (xy 419.148768 -225.571304)
			(xy 419.148381 -225.581462) (xy 419.140578 -225.600221) (xy 419.12617 -225.614545) (xy 419.107367 -225.622239)
			(xy 419.097206 -225.622612) (xy 417.697666 -225.622612) (xy 417.687544 -225.622103) (xy 417.668831 -225.614374)
			(xy 417.654478 -225.600095) (xy 417.646651 -225.581424) (xy 417.646104 -225.571304) (xy 411.604968 -225.571304)
			(xy 411.604581 -225.581462) (xy 411.596778 -225.600221) (xy 411.58237 -225.614545) (xy 411.563567 -225.622239)
			(xy 411.553406 -225.622612) (xy 410.153866 -225.622612) (xy 410.143744 -225.622103) (xy 410.125031 -225.614374)
			(xy 410.110678 -225.600095) (xy 410.102851 -225.581424) (xy 410.102304 -225.571304) (xy 313.738768 -225.571304)
			(xy 313.738381 -225.581462) (xy 313.730578 -225.600221) (xy 313.71617 -225.614545) (xy 313.697367 -225.622239)
			(xy 313.687206 -225.622612) (xy 312.287666 -225.622612) (xy 312.277544 -225.622103) (xy 312.258831 -225.614374)
			(xy 312.244478 -225.600095) (xy 312.236651 -225.581424) (xy 312.236104 -225.571304) (xy 306.194968 -225.571304)
			(xy 306.194581 -225.581462) (xy 306.186778 -225.600221) (xy 306.17237 -225.614545) (xy 306.153567 -225.622239)
			(xy 306.143406 -225.622612) (xy 304.743866 -225.622612) (xy 304.733744 -225.622103) (xy 304.715031 -225.614374)
			(xy 304.700678 -225.600095) (xy 304.692851 -225.581424) (xy 304.692304 -225.571304) (xy 298.651168 -225.571304)
			(xy 298.650781 -225.581462) (xy 298.642978 -225.600221) (xy 298.62857 -225.614545) (xy 298.609767 -225.622239)
			(xy 298.599606 -225.622612) (xy 297.200066 -225.622612) (xy 297.189944 -225.622103) (xy 297.171231 -225.614374)
			(xy 297.156878 -225.600095) (xy 297.149051 -225.581424) (xy 297.148504 -225.571304) (xy 291.107368 -225.571304)
			(xy 291.106981 -225.581462) (xy 291.099178 -225.600221) (xy 291.08477 -225.614545) (xy 291.065967 -225.622239)
			(xy 291.055806 -225.622612) (xy 289.656266 -225.622612) (xy 289.646144 -225.622103) (xy 289.627431 -225.614374)
			(xy 289.613078 -225.600095) (xy 289.605251 -225.581424) (xy 289.604704 -225.571304) (xy 283.563568 -225.571304)
			(xy 283.563181 -225.581462) (xy 283.555378 -225.600221) (xy 283.54097 -225.614545) (xy 283.522167 -225.622239)
			(xy 283.512006 -225.622612) (xy 282.112466 -225.622612) (xy 282.102344 -225.622103) (xy 282.083631 -225.614374)
			(xy 282.069278 -225.600095) (xy 282.061451 -225.581424) (xy 282.060904 -225.571304) (xy 276.019768 -225.571304)
			(xy 276.019381 -225.581462) (xy 276.011578 -225.600221) (xy 275.99717 -225.614545) (xy 275.978367 -225.622239)
			(xy 275.968206 -225.622612) (xy 274.568666 -225.622612) (xy 274.558544 -225.622103) (xy 274.539831 -225.614374)
			(xy 274.525478 -225.600095) (xy 274.517651 -225.581424) (xy 274.517104 -225.571304) (xy 268.475968 -225.571304)
			(xy 268.475581 -225.581462) (xy 268.467778 -225.600221) (xy 268.45337 -225.614545) (xy 268.434567 -225.622239)
			(xy 268.424406 -225.622612) (xy 267.024866 -225.622612) (xy 267.014744 -225.622103) (xy 266.996031 -225.614374)
			(xy 266.981678 -225.600095) (xy 266.973851 -225.581424) (xy 266.973304 -225.571304) (xy 260.932168 -225.571304)
			(xy 260.931781 -225.581462) (xy 260.923978 -225.600221) (xy 260.90957 -225.614545) (xy 260.890767 -225.622239)
			(xy 260.880606 -225.622612) (xy 259.481066 -225.622612) (xy 259.470944 -225.622103) (xy 259.452231 -225.614374)
			(xy 259.437878 -225.600095) (xy 259.430051 -225.581424) (xy 259.429504 -225.571304) (xy 216.4715 -225.571304)
			(xy 216.471082 -225.581458) (xy 216.463285 -225.600211) (xy 216.448887 -225.614534) (xy 216.430094 -225.622234)
			(xy 216.419938 -225.622612) (xy 215.020398 -225.622612) (xy 215.010278 -225.622077) (xy 214.991566 -225.614358)
			(xy 214.977212 -225.600087) (xy 214.969384 -225.581421) (xy 214.968836 -225.571304) (xy 208.9277 -225.571304)
			(xy 208.927282 -225.581458) (xy 208.919485 -225.600211) (xy 208.905087 -225.614534) (xy 208.886294 -225.622234)
			(xy 208.876138 -225.622612) (xy 207.476598 -225.622612) (xy 207.466478 -225.622077) (xy 207.447766 -225.614358)
			(xy 207.433412 -225.600087) (xy 207.425584 -225.581421) (xy 207.425036 -225.571304) (xy 201.3839 -225.571304)
			(xy 201.383482 -225.581458) (xy 201.375685 -225.600211) (xy 201.361287 -225.614534) (xy 201.342494 -225.622234)
			(xy 201.332338 -225.622612) (xy 199.932798 -225.622612) (xy 199.922678 -225.622077) (xy 199.903966 -225.614358)
			(xy 199.889612 -225.600087) (xy 199.881784 -225.581421) (xy 199.881236 -225.571304) (xy 193.8401 -225.571304)
			(xy 193.839682 -225.581458) (xy 193.831885 -225.600211) (xy 193.817487 -225.614534) (xy 193.798694 -225.622234)
			(xy 193.788538 -225.622612) (xy 192.388998 -225.622612) (xy 192.378878 -225.622077) (xy 192.360166 -225.614358)
			(xy 192.345812 -225.600087) (xy 192.337984 -225.581421) (xy 192.337436 -225.571304) (xy 186.2963 -225.571304)
			(xy 186.295882 -225.581458) (xy 186.288085 -225.600211) (xy 186.273687 -225.614534) (xy 186.254894 -225.622234)
			(xy 186.244738 -225.622612) (xy 184.845198 -225.622612) (xy 184.835078 -225.622077) (xy 184.816366 -225.614358)
			(xy 184.802012 -225.600087) (xy 184.794184 -225.581421) (xy 184.793636 -225.571304) (xy 178.7525 -225.571304)
			(xy 178.752082 -225.581458) (xy 178.744285 -225.600211) (xy 178.729887 -225.614534) (xy 178.711094 -225.622234)
			(xy 178.700938 -225.622612) (xy 177.301398 -225.622612) (xy 177.291278 -225.622077) (xy 177.272566 -225.614358)
			(xy 177.258212 -225.600087) (xy 177.250384 -225.581421) (xy 177.249836 -225.571304) (xy 171.2087 -225.571304)
			(xy 171.208282 -225.581458) (xy 171.200485 -225.600211) (xy 171.186087 -225.614534) (xy 171.167294 -225.622234)
			(xy 171.157138 -225.622612) (xy 169.757598 -225.622612) (xy 169.747478 -225.622077) (xy 169.728766 -225.614358)
			(xy 169.714412 -225.600087) (xy 169.706584 -225.581421) (xy 169.706036 -225.571304) (xy 163.6649 -225.571304)
			(xy 163.664482 -225.581458) (xy 163.656685 -225.600211) (xy 163.642287 -225.614534) (xy 163.623494 -225.622234)
			(xy 163.613338 -225.622612) (xy 162.213798 -225.622612) (xy 162.203678 -225.622077) (xy 162.184966 -225.614358)
			(xy 162.170612 -225.600087) (xy 162.162784 -225.581421) (xy 162.162236 -225.571304) (xy 65.7987 -225.571304)
			(xy 65.798282 -225.581458) (xy 65.790485 -225.600211) (xy 65.776087 -225.614534) (xy 65.757294 -225.622234)
			(xy 65.747138 -225.622612) (xy 64.347598 -225.622612) (xy 64.337478 -225.622077) (xy 64.318766 -225.614358)
			(xy 64.304412 -225.600087) (xy 64.296584 -225.581421) (xy 64.296036 -225.571304) (xy 58.2549 -225.571304)
			(xy 58.254482 -225.581458) (xy 58.246685 -225.600211) (xy 58.232287 -225.614534) (xy 58.213494 -225.622234)
			(xy 58.203338 -225.622612) (xy 56.803798 -225.622612) (xy 56.793678 -225.622077) (xy 56.774966 -225.614358)
			(xy 56.760612 -225.600087) (xy 56.752784 -225.581421) (xy 56.752236 -225.571304) (xy 50.7111 -225.571304)
			(xy 50.710682 -225.581458) (xy 50.702885 -225.600211) (xy 50.688487 -225.614534) (xy 50.669694 -225.622234)
			(xy 50.659538 -225.622612) (xy 49.259998 -225.622612) (xy 49.249878 -225.622077) (xy 49.231166 -225.614358)
			(xy 49.216812 -225.600087) (xy 49.208984 -225.581421) (xy 49.208436 -225.571304) (xy 43.1673 -225.571304)
			(xy 43.166882 -225.581458) (xy 43.159085 -225.600211) (xy 43.144687 -225.614534) (xy 43.125894 -225.622234)
			(xy 43.115738 -225.622612) (xy 41.716198 -225.622612) (xy 41.706078 -225.622077) (xy 41.687366 -225.614358)
			(xy 41.673012 -225.600087) (xy 41.665184 -225.581421) (xy 41.664636 -225.571304) (xy 35.6235 -225.571304)
			(xy 35.623082 -225.581458) (xy 35.615285 -225.600211) (xy 35.600887 -225.614534) (xy 35.582094 -225.622234)
			(xy 35.571938 -225.622612) (xy 34.172398 -225.622612) (xy 34.162278 -225.622077) (xy 34.143566 -225.614358)
			(xy 34.129212 -225.600087) (xy 34.121384 -225.581421) (xy 34.120836 -225.571304) (xy 28.0797 -225.571304)
			(xy 28.079282 -225.581458) (xy 28.071485 -225.600211) (xy 28.057087 -225.614534) (xy 28.038294 -225.622234)
			(xy 28.028138 -225.622612) (xy 26.628598 -225.622612) (xy 26.618478 -225.622077) (xy 26.599766 -225.614358)
			(xy 26.585412 -225.600087) (xy 26.577584 -225.581421) (xy 26.577036 -225.571304) (xy 20.5359 -225.571304)
			(xy 20.535482 -225.581458) (xy 20.527685 -225.600211) (xy 20.513287 -225.614534) (xy 20.494494 -225.622234)
			(xy 20.484338 -225.622612) (xy 19.084798 -225.622612) (xy 19.074678 -225.622077) (xy 19.055966 -225.614358)
			(xy 19.041612 -225.600087) (xy 19.033784 -225.581421) (xy 19.033236 -225.571304) (xy 12.9921 -225.571304)
			(xy 12.991682 -225.581458) (xy 12.983885 -225.600211) (xy 12.969487 -225.614534) (xy 12.950694 -225.622234)
			(xy 12.940538 -225.622612) (xy 11.540998 -225.622612) (xy 11.530878 -225.622077) (xy 11.512166 -225.614358)
			(xy 11.497812 -225.600087) (xy 11.489984 -225.581421) (xy 11.489436 -225.571304) (xy 2.509012 -225.571304)
			(xy 2.509012 -226.421442) (xy 7.389368 -226.421442) (xy 7.389368 -226.012502) (xy 7.389766 -226.002327)
			(xy 7.397556 -225.983526) (xy 7.41195 -225.96914) (xy 7.430755 -225.961361) (xy 7.44093 -225.96094)
			(xy 8.84047 -225.96094) (xy 8.85064 -225.961389) (xy 8.869434 -225.969164) (xy 8.88382 -225.983542)
			(xy 8.891606 -226.002332) (xy 8.892032 -226.012502) (xy 8.892032 -226.421442) (xy 14.933168 -226.421442)
			(xy 14.933168 -226.012502) (xy 14.933566 -226.002327) (xy 14.941356 -225.983526) (xy 14.95575 -225.96914)
			(xy 14.974555 -225.961361) (xy 14.98473 -225.96094) (xy 16.38427 -225.96094) (xy 16.39444 -225.961389)
			(xy 16.413234 -225.969164) (xy 16.42762 -225.983542) (xy 16.435406 -226.002332) (xy 16.435832 -226.012502)
			(xy 16.435832 -226.421442) (xy 22.476968 -226.421442) (xy 22.476968 -226.012502) (xy 22.477366 -226.002327)
			(xy 22.485156 -225.983526) (xy 22.49955 -225.96914) (xy 22.518355 -225.961361) (xy 22.52853 -225.96094)
			(xy 23.92807 -225.96094) (xy 23.93824 -225.961389) (xy 23.957034 -225.969164) (xy 23.97142 -225.983542)
			(xy 23.979206 -226.002332) (xy 23.979632 -226.012502) (xy 23.979632 -226.421442) (xy 30.020768 -226.421442)
			(xy 30.020768 -226.012502) (xy 30.021166 -226.002327) (xy 30.028956 -225.983526) (xy 30.04335 -225.96914)
			(xy 30.062155 -225.961361) (xy 30.07233 -225.96094) (xy 31.47187 -225.96094) (xy 31.48204 -225.961389)
			(xy 31.500834 -225.969164) (xy 31.51522 -225.983542) (xy 31.523006 -226.002332) (xy 31.523432 -226.012502)
			(xy 31.523432 -226.421442) (xy 37.564568 -226.421442) (xy 37.564568 -226.012502) (xy 37.564966 -226.002327)
			(xy 37.572756 -225.983526) (xy 37.58715 -225.96914) (xy 37.605955 -225.961361) (xy 37.61613 -225.96094)
			(xy 39.01567 -225.96094) (xy 39.02584 -225.961389) (xy 39.044634 -225.969164) (xy 39.05902 -225.983542)
			(xy 39.066806 -226.002332) (xy 39.067232 -226.012502) (xy 39.067232 -226.421442) (xy 45.108368 -226.421442)
			(xy 45.108368 -226.012502) (xy 45.108766 -226.002327) (xy 45.116556 -225.983526) (xy 45.13095 -225.96914)
			(xy 45.149755 -225.961361) (xy 45.15993 -225.96094) (xy 46.55947 -225.96094) (xy 46.56964 -225.961389)
			(xy 46.588434 -225.969164) (xy 46.60282 -225.983542) (xy 46.610606 -226.002332) (xy 46.611032 -226.012502)
			(xy 46.611032 -226.421442) (xy 52.652168 -226.421442) (xy 52.652168 -226.012502) (xy 52.652566 -226.002327)
			(xy 52.660356 -225.983526) (xy 52.67475 -225.96914) (xy 52.693555 -225.961361) (xy 52.70373 -225.96094)
			(xy 54.10327 -225.96094) (xy 54.11344 -225.961389) (xy 54.132234 -225.969164) (xy 54.14662 -225.983542)
			(xy 54.154406 -226.002332) (xy 54.154832 -226.012502) (xy 54.154832 -226.421442) (xy 60.195968 -226.421442)
			(xy 60.195968 -226.012502) (xy 60.196366 -226.002327) (xy 60.204156 -225.983526) (xy 60.21855 -225.96914)
			(xy 60.237355 -225.961361) (xy 60.24753 -225.96094) (xy 61.64707 -225.96094) (xy 61.65724 -225.961389)
			(xy 61.676034 -225.969164) (xy 61.69042 -225.983542) (xy 61.698206 -226.002332) (xy 61.698632 -226.012502)
			(xy 61.698632 -226.421442) (xy 158.062168 -226.421442) (xy 158.062168 -226.012502) (xy 158.062566 -226.002327)
			(xy 158.070356 -225.983526) (xy 158.08475 -225.96914) (xy 158.103555 -225.961361) (xy 158.11373 -225.96094)
			(xy 159.51327 -225.96094) (xy 159.52344 -225.961389) (xy 159.542234 -225.969164) (xy 159.55662 -225.983542)
			(xy 159.564406 -226.002332) (xy 159.564832 -226.012502) (xy 159.564832 -226.421442) (xy 165.605968 -226.421442)
			(xy 165.605968 -226.012502) (xy 165.606366 -226.002327) (xy 165.614156 -225.983526) (xy 165.62855 -225.96914)
			(xy 165.647355 -225.961361) (xy 165.65753 -225.96094) (xy 167.05707 -225.96094) (xy 167.06724 -225.961389)
			(xy 167.086034 -225.969164) (xy 167.10042 -225.983542) (xy 167.108206 -226.002332) (xy 167.108632 -226.012502)
			(xy 167.108632 -226.421442) (xy 173.149768 -226.421442) (xy 173.149768 -226.012502) (xy 173.150166 -226.002327)
			(xy 173.157956 -225.983526) (xy 173.17235 -225.96914) (xy 173.191155 -225.961361) (xy 173.20133 -225.96094)
			(xy 174.60087 -225.96094) (xy 174.61104 -225.961389) (xy 174.629834 -225.969164) (xy 174.64422 -225.983542)
			(xy 174.652006 -226.002332) (xy 174.652432 -226.012502) (xy 174.652432 -226.421442) (xy 180.693568 -226.421442)
			(xy 180.693568 -226.012502) (xy 180.693966 -226.002327) (xy 180.701756 -225.983526) (xy 180.71615 -225.96914)
			(xy 180.734955 -225.961361) (xy 180.74513 -225.96094) (xy 182.14467 -225.96094) (xy 182.15484 -225.961389)
			(xy 182.173634 -225.969164) (xy 182.18802 -225.983542) (xy 182.195806 -226.002332) (xy 182.196232 -226.012502)
			(xy 182.196232 -226.421442) (xy 188.237368 -226.421442) (xy 188.237368 -226.012502) (xy 188.237766 -226.002327)
			(xy 188.245556 -225.983526) (xy 188.25995 -225.96914) (xy 188.278755 -225.961361) (xy 188.28893 -225.96094)
			(xy 189.68847 -225.96094) (xy 189.69864 -225.961389) (xy 189.717434 -225.969164) (xy 189.73182 -225.983542)
			(xy 189.739606 -226.002332) (xy 189.740032 -226.012502) (xy 189.740032 -226.421442) (xy 195.781168 -226.421442)
			(xy 195.781168 -226.012502) (xy 195.781566 -226.002327) (xy 195.789356 -225.983526) (xy 195.80375 -225.96914)
			(xy 195.822555 -225.961361) (xy 195.83273 -225.96094) (xy 197.23227 -225.96094) (xy 197.24244 -225.961389)
			(xy 197.261234 -225.969164) (xy 197.27562 -225.983542) (xy 197.283406 -226.002332) (xy 197.283832 -226.012502)
			(xy 197.283832 -226.421442) (xy 203.324968 -226.421442) (xy 203.324968 -226.012502) (xy 203.325366 -226.002327)
			(xy 203.333156 -225.983526) (xy 203.34755 -225.96914) (xy 203.366355 -225.961361) (xy 203.37653 -225.96094)
			(xy 204.77607 -225.96094) (xy 204.78624 -225.961389) (xy 204.805034 -225.969164) (xy 204.81942 -225.983542)
			(xy 204.827206 -226.002332) (xy 204.827632 -226.012502) (xy 204.827632 -226.421442) (xy 210.868768 -226.421442)
			(xy 210.868768 -226.012502) (xy 210.869166 -226.002327) (xy 210.876956 -225.983526) (xy 210.89135 -225.96914)
			(xy 210.910155 -225.961361) (xy 210.92033 -225.96094) (xy 212.31987 -225.96094) (xy 212.33004 -225.961389)
			(xy 212.348834 -225.969164) (xy 212.36322 -225.983542) (xy 212.371006 -226.002332) (xy 212.371432 -226.012502)
			(xy 212.371432 -226.421442) (xy 255.329436 -226.421442) (xy 255.329436 -226.012502) (xy 255.329935 -226.002345)
			(xy 255.337708 -225.983576) (xy 255.352073 -225.969211) (xy 255.370841 -225.961436) (xy 255.380998 -225.96094)
			(xy 256.780538 -225.96094) (xy 256.790698 -225.961402) (xy 256.809469 -225.96919) (xy 256.823833 -225.983565)
			(xy 256.831606 -226.002341) (xy 256.8321 -226.012502) (xy 256.8321 -226.421442) (xy 262.873236 -226.421442)
			(xy 262.873236 -226.012502) (xy 262.873735 -226.002345) (xy 262.881508 -225.983576) (xy 262.895873 -225.969211)
			(xy 262.914641 -225.961436) (xy 262.924798 -225.96094) (xy 264.324338 -225.96094) (xy 264.334498 -225.961402)
			(xy 264.353269 -225.96919) (xy 264.367633 -225.983565) (xy 264.375406 -226.002341) (xy 264.3759 -226.012502)
			(xy 264.3759 -226.421442) (xy 270.417036 -226.421442) (xy 270.417036 -226.012502) (xy 270.417535 -226.002345)
			(xy 270.425308 -225.983576) (xy 270.439673 -225.969211) (xy 270.458441 -225.961436) (xy 270.468598 -225.96094)
			(xy 271.868138 -225.96094) (xy 271.878298 -225.961402) (xy 271.897069 -225.96919) (xy 271.911433 -225.983565)
			(xy 271.919206 -226.002341) (xy 271.9197 -226.012502) (xy 271.9197 -226.421442) (xy 277.960836 -226.421442)
			(xy 277.960836 -226.012502) (xy 277.961335 -226.002345) (xy 277.969108 -225.983576) (xy 277.983473 -225.969211)
			(xy 278.002241 -225.961436) (xy 278.012398 -225.96094) (xy 279.411938 -225.96094) (xy 279.422098 -225.961402)
			(xy 279.440869 -225.96919) (xy 279.455233 -225.983565) (xy 279.463006 -226.002341) (xy 279.4635 -226.012502)
			(xy 279.4635 -226.421442) (xy 285.504636 -226.421442) (xy 285.504636 -226.012502) (xy 285.505135 -226.002345)
			(xy 285.512908 -225.983576) (xy 285.527273 -225.969211) (xy 285.546041 -225.961436) (xy 285.556198 -225.96094)
			(xy 286.955738 -225.96094) (xy 286.965898 -225.961402) (xy 286.984669 -225.96919) (xy 286.999033 -225.983565)
			(xy 287.006806 -226.002341) (xy 287.0073 -226.012502) (xy 287.0073 -226.421442) (xy 293.048436 -226.421442)
			(xy 293.048436 -226.012502) (xy 293.048935 -226.002345) (xy 293.056708 -225.983576) (xy 293.071073 -225.969211)
			(xy 293.089841 -225.961436) (xy 293.099998 -225.96094) (xy 294.499538 -225.96094) (xy 294.509698 -225.961402)
			(xy 294.528469 -225.96919) (xy 294.542833 -225.983565) (xy 294.550606 -226.002341) (xy 294.5511 -226.012502)
			(xy 294.5511 -226.421442) (xy 300.592236 -226.421442) (xy 300.592236 -226.012502) (xy 300.592735 -226.002345)
			(xy 300.600508 -225.983576) (xy 300.614873 -225.969211) (xy 300.633641 -225.961436) (xy 300.643798 -225.96094)
			(xy 302.043338 -225.96094) (xy 302.053498 -225.961402) (xy 302.072269 -225.96919) (xy 302.086633 -225.983565)
			(xy 302.094406 -226.002341) (xy 302.0949 -226.012502) (xy 302.0949 -226.421442) (xy 308.136036 -226.421442)
			(xy 308.136036 -226.012502) (xy 308.136535 -226.002345) (xy 308.144308 -225.983576) (xy 308.158673 -225.969211)
			(xy 308.177441 -225.961436) (xy 308.187598 -225.96094) (xy 309.587138 -225.96094) (xy 309.597298 -225.961402)
			(xy 309.616069 -225.96919) (xy 309.630433 -225.983565) (xy 309.638206 -226.002341) (xy 309.6387 -226.012502)
			(xy 309.6387 -226.421442) (xy 406.002236 -226.421442) (xy 406.002236 -226.012502) (xy 406.002735 -226.002345)
			(xy 406.010508 -225.983576) (xy 406.024873 -225.969211) (xy 406.043641 -225.961436) (xy 406.053798 -225.96094)
			(xy 407.453338 -225.96094) (xy 407.463498 -225.961402) (xy 407.482269 -225.96919) (xy 407.496633 -225.983565)
			(xy 407.504406 -226.002341) (xy 407.5049 -226.012502) (xy 407.5049 -226.421442) (xy 413.546036 -226.421442)
			(xy 413.546036 -226.012502) (xy 413.546535 -226.002345) (xy 413.554308 -225.983576) (xy 413.568673 -225.969211)
			(xy 413.587441 -225.961436) (xy 413.597598 -225.96094) (xy 414.997138 -225.96094) (xy 415.007298 -225.961402)
			(xy 415.026069 -225.96919) (xy 415.040433 -225.983565) (xy 415.048206 -226.002341) (xy 415.0487 -226.012502)
			(xy 415.0487 -226.421442) (xy 421.089836 -226.421442) (xy 421.089836 -226.012502) (xy 421.090335 -226.002345)
			(xy 421.098108 -225.983576) (xy 421.112473 -225.969211) (xy 421.131241 -225.961436) (xy 421.141398 -225.96094)
			(xy 422.540938 -225.96094) (xy 422.551098 -225.961402) (xy 422.569869 -225.96919) (xy 422.584233 -225.983565)
			(xy 422.592006 -226.002341) (xy 422.5925 -226.012502) (xy 422.5925 -226.421442) (xy 428.633636 -226.421442)
			(xy 428.633636 -226.012502) (xy 428.634135 -226.002345) (xy 428.641908 -225.983576) (xy 428.656273 -225.969211)
			(xy 428.675041 -225.961436) (xy 428.685198 -225.96094) (xy 430.084738 -225.96094) (xy 430.094898 -225.961402)
			(xy 430.113669 -225.96919) (xy 430.128033 -225.983565) (xy 430.135806 -226.002341) (xy 430.1363 -226.012502)
			(xy 430.1363 -226.421442) (xy 436.177436 -226.421442) (xy 436.177436 -226.012502) (xy 436.177935 -226.002345)
			(xy 436.185708 -225.983576) (xy 436.200073 -225.969211) (xy 436.218841 -225.961436) (xy 436.228998 -225.96094)
			(xy 437.628538 -225.96094) (xy 437.638698 -225.961402) (xy 437.657469 -225.96919) (xy 437.671833 -225.983565)
			(xy 437.679606 -226.002341) (xy 437.6801 -226.012502) (xy 437.6801 -226.421442) (xy 443.721236 -226.421442)
			(xy 443.721236 -226.012502) (xy 443.721735 -226.002345) (xy 443.729508 -225.983576) (xy 443.743873 -225.969211)
			(xy 443.762641 -225.961436) (xy 443.772798 -225.96094) (xy 445.172338 -225.96094) (xy 445.182498 -225.961402)
			(xy 445.201269 -225.96919) (xy 445.215633 -225.983565) (xy 445.223406 -226.002341) (xy 445.2239 -226.012502)
			(xy 445.2239 -226.421442) (xy 451.265036 -226.421442) (xy 451.265036 -226.012502) (xy 451.265535 -226.002345)
			(xy 451.273308 -225.983576) (xy 451.287673 -225.969211) (xy 451.306441 -225.961436) (xy 451.316598 -225.96094)
			(xy 452.716138 -225.96094) (xy 452.726298 -225.961402) (xy 452.745069 -225.96919) (xy 452.759433 -225.983565)
			(xy 452.767206 -226.002341) (xy 452.7677 -226.012502) (xy 452.7677 -226.421442) (xy 458.808836 -226.421442)
			(xy 458.808836 -226.012502) (xy 458.809335 -226.002345) (xy 458.817108 -225.983576) (xy 458.831473 -225.969211)
			(xy 458.850241 -225.961436) (xy 458.860398 -225.96094) (xy 460.259938 -225.96094) (xy 460.270098 -225.961402)
			(xy 460.288869 -225.96919) (xy 460.303233 -225.983565) (xy 460.311006 -226.002341) (xy 460.3115 -226.012502)
			(xy 460.3115 -226.421442) (xy 460.311002 -226.431598) (xy 460.303221 -226.450361) (xy 460.288857 -226.464723)
			(xy 460.270094 -226.472503) (xy 460.259938 -226.473004) (xy 458.860398 -226.473004) (xy 458.850245 -226.472469)
			(xy 458.831484 -226.464702) (xy 458.817121 -226.450349) (xy 458.809339 -226.431594) (xy 458.808836 -226.421442)
			(xy 452.7677 -226.421442) (xy 452.767202 -226.431598) (xy 452.759421 -226.450361) (xy 452.745057 -226.464723)
			(xy 452.726294 -226.472503) (xy 452.716138 -226.473004) (xy 451.316598 -226.473004) (xy 451.306445 -226.472469)
			(xy 451.287684 -226.464702) (xy 451.273321 -226.450349) (xy 451.265539 -226.431594) (xy 451.265036 -226.421442)
			(xy 445.2239 -226.421442) (xy 445.223402 -226.431598) (xy 445.215621 -226.450361) (xy 445.201257 -226.464723)
			(xy 445.182494 -226.472503) (xy 445.172338 -226.473004) (xy 443.772798 -226.473004) (xy 443.762645 -226.472469)
			(xy 443.743884 -226.464702) (xy 443.729521 -226.450349) (xy 443.721739 -226.431594) (xy 443.721236 -226.421442)
			(xy 437.6801 -226.421442) (xy 437.679602 -226.431598) (xy 437.671821 -226.450361) (xy 437.657457 -226.464723)
			(xy 437.638694 -226.472503) (xy 437.628538 -226.473004) (xy 436.228998 -226.473004) (xy 436.218845 -226.472469)
			(xy 436.200084 -226.464702) (xy 436.185721 -226.450349) (xy 436.177939 -226.431594) (xy 436.177436 -226.421442)
			(xy 430.1363 -226.421442) (xy 430.135802 -226.431598) (xy 430.128021 -226.450361) (xy 430.113657 -226.464723)
			(xy 430.094894 -226.472503) (xy 430.084738 -226.473004) (xy 428.685198 -226.473004) (xy 428.675045 -226.472469)
			(xy 428.656284 -226.464702) (xy 428.641921 -226.450349) (xy 428.634139 -226.431594) (xy 428.633636 -226.421442)
			(xy 422.5925 -226.421442) (xy 422.592002 -226.431598) (xy 422.584221 -226.450361) (xy 422.569857 -226.464723)
			(xy 422.551094 -226.472503) (xy 422.540938 -226.473004) (xy 421.141398 -226.473004) (xy 421.131245 -226.472469)
			(xy 421.112484 -226.464702) (xy 421.098121 -226.450349) (xy 421.090339 -226.431594) (xy 421.089836 -226.421442)
			(xy 415.0487 -226.421442) (xy 415.048202 -226.431598) (xy 415.040421 -226.450361) (xy 415.026057 -226.464723)
			(xy 415.007294 -226.472503) (xy 414.997138 -226.473004) (xy 413.597598 -226.473004) (xy 413.587445 -226.472469)
			(xy 413.568684 -226.464702) (xy 413.554321 -226.450349) (xy 413.546539 -226.431594) (xy 413.546036 -226.421442)
			(xy 407.5049 -226.421442) (xy 407.504402 -226.431598) (xy 407.496621 -226.450361) (xy 407.482257 -226.464723)
			(xy 407.463494 -226.472503) (xy 407.453338 -226.473004) (xy 406.053798 -226.473004) (xy 406.043645 -226.472469)
			(xy 406.024884 -226.464702) (xy 406.010521 -226.450349) (xy 406.002739 -226.431594) (xy 406.002236 -226.421442)
			(xy 309.6387 -226.421442) (xy 309.638202 -226.431598) (xy 309.630421 -226.450361) (xy 309.616057 -226.464723)
			(xy 309.597294 -226.472503) (xy 309.587138 -226.473004) (xy 308.187598 -226.473004) (xy 308.177445 -226.472469)
			(xy 308.158684 -226.464702) (xy 308.144321 -226.450349) (xy 308.136539 -226.431594) (xy 308.136036 -226.421442)
			(xy 302.0949 -226.421442) (xy 302.094402 -226.431598) (xy 302.086621 -226.450361) (xy 302.072257 -226.464723)
			(xy 302.053494 -226.472503) (xy 302.043338 -226.473004) (xy 300.643798 -226.473004) (xy 300.633645 -226.472469)
			(xy 300.614884 -226.464702) (xy 300.600521 -226.450349) (xy 300.592739 -226.431594) (xy 300.592236 -226.421442)
			(xy 294.5511 -226.421442) (xy 294.550602 -226.431598) (xy 294.542821 -226.450361) (xy 294.528457 -226.464723)
			(xy 294.509694 -226.472503) (xy 294.499538 -226.473004) (xy 293.099998 -226.473004) (xy 293.089845 -226.472469)
			(xy 293.071084 -226.464702) (xy 293.056721 -226.450349) (xy 293.048939 -226.431594) (xy 293.048436 -226.421442)
			(xy 287.0073 -226.421442) (xy 287.006802 -226.431598) (xy 286.999021 -226.450361) (xy 286.984657 -226.464723)
			(xy 286.965894 -226.472503) (xy 286.955738 -226.473004) (xy 285.556198 -226.473004) (xy 285.546045 -226.472469)
			(xy 285.527284 -226.464702) (xy 285.512921 -226.450349) (xy 285.505139 -226.431594) (xy 285.504636 -226.421442)
			(xy 279.4635 -226.421442) (xy 279.463002 -226.431598) (xy 279.455221 -226.450361) (xy 279.440857 -226.464723)
			(xy 279.422094 -226.472503) (xy 279.411938 -226.473004) (xy 278.012398 -226.473004) (xy 278.002245 -226.472469)
			(xy 277.983484 -226.464702) (xy 277.969121 -226.450349) (xy 277.961339 -226.431594) (xy 277.960836 -226.421442)
			(xy 271.9197 -226.421442) (xy 271.919202 -226.431598) (xy 271.911421 -226.450361) (xy 271.897057 -226.464723)
			(xy 271.878294 -226.472503) (xy 271.868138 -226.473004) (xy 270.468598 -226.473004) (xy 270.458445 -226.472469)
			(xy 270.439684 -226.464702) (xy 270.425321 -226.450349) (xy 270.417539 -226.431594) (xy 270.417036 -226.421442)
			(xy 264.3759 -226.421442) (xy 264.375402 -226.431598) (xy 264.367621 -226.450361) (xy 264.353257 -226.464723)
			(xy 264.334494 -226.472503) (xy 264.324338 -226.473004) (xy 262.924798 -226.473004) (xy 262.914645 -226.472469)
			(xy 262.895884 -226.464702) (xy 262.881521 -226.450349) (xy 262.873739 -226.431594) (xy 262.873236 -226.421442)
			(xy 256.8321 -226.421442) (xy 256.831602 -226.431598) (xy 256.823821 -226.450361) (xy 256.809457 -226.464723)
			(xy 256.790694 -226.472503) (xy 256.780538 -226.473004) (xy 255.380998 -226.473004) (xy 255.370845 -226.472469)
			(xy 255.352084 -226.464702) (xy 255.337721 -226.450349) (xy 255.329939 -226.431594) (xy 255.329436 -226.421442)
			(xy 212.371432 -226.421442) (xy 212.371 -226.431606) (xy 212.363206 -226.450382) (xy 212.348822 -226.464747)
			(xy 212.330035 -226.472514) (xy 212.31987 -226.473004) (xy 210.92033 -226.473004) (xy 210.910179 -226.472443)
			(xy 210.891419 -226.464687) (xy 210.877054 -226.450342) (xy 210.869271 -226.431592) (xy 210.868768 -226.421442)
			(xy 204.827632 -226.421442) (xy 204.8272 -226.431606) (xy 204.819406 -226.450382) (xy 204.805022 -226.464747)
			(xy 204.786235 -226.472514) (xy 204.77607 -226.473004) (xy 203.37653 -226.473004) (xy 203.366379 -226.472443)
			(xy 203.347619 -226.464687) (xy 203.333254 -226.450342) (xy 203.325471 -226.431592) (xy 203.324968 -226.421442)
			(xy 197.283832 -226.421442) (xy 197.2834 -226.431606) (xy 197.275606 -226.450382) (xy 197.261222 -226.464747)
			(xy 197.242435 -226.472514) (xy 197.23227 -226.473004) (xy 195.83273 -226.473004) (xy 195.822579 -226.472443)
			(xy 195.803819 -226.464687) (xy 195.789454 -226.450342) (xy 195.781671 -226.431592) (xy 195.781168 -226.421442)
			(xy 189.740032 -226.421442) (xy 189.7396 -226.431606) (xy 189.731806 -226.450382) (xy 189.717422 -226.464747)
			(xy 189.698635 -226.472514) (xy 189.68847 -226.473004) (xy 188.28893 -226.473004) (xy 188.278779 -226.472443)
			(xy 188.260019 -226.464687) (xy 188.245654 -226.450342) (xy 188.237871 -226.431592) (xy 188.237368 -226.421442)
			(xy 182.196232 -226.421442) (xy 182.1958 -226.431606) (xy 182.188006 -226.450382) (xy 182.173622 -226.464747)
			(xy 182.154835 -226.472514) (xy 182.14467 -226.473004) (xy 180.74513 -226.473004) (xy 180.734979 -226.472443)
			(xy 180.716219 -226.464687) (xy 180.701854 -226.450342) (xy 180.694071 -226.431592) (xy 180.693568 -226.421442)
			(xy 174.652432 -226.421442) (xy 174.652 -226.431606) (xy 174.644206 -226.450382) (xy 174.629822 -226.464747)
			(xy 174.611035 -226.472514) (xy 174.60087 -226.473004) (xy 173.20133 -226.473004) (xy 173.191179 -226.472443)
			(xy 173.172419 -226.464687) (xy 173.158054 -226.450342) (xy 173.150271 -226.431592) (xy 173.149768 -226.421442)
			(xy 167.108632 -226.421442) (xy 167.1082 -226.431606) (xy 167.100406 -226.450382) (xy 167.086022 -226.464747)
			(xy 167.067235 -226.472514) (xy 167.05707 -226.473004) (xy 165.65753 -226.473004) (xy 165.647379 -226.472443)
			(xy 165.628619 -226.464687) (xy 165.614254 -226.450342) (xy 165.606471 -226.431592) (xy 165.605968 -226.421442)
			(xy 159.564832 -226.421442) (xy 159.5644 -226.431606) (xy 159.556606 -226.450382) (xy 159.542222 -226.464747)
			(xy 159.523435 -226.472514) (xy 159.51327 -226.473004) (xy 158.11373 -226.473004) (xy 158.103579 -226.472443)
			(xy 158.084819 -226.464687) (xy 158.070454 -226.450342) (xy 158.062671 -226.431592) (xy 158.062168 -226.421442)
			(xy 61.698632 -226.421442) (xy 61.6982 -226.431606) (xy 61.690406 -226.450382) (xy 61.676022 -226.464747)
			(xy 61.657235 -226.472514) (xy 61.64707 -226.473004) (xy 60.24753 -226.473004) (xy 60.237379 -226.472443)
			(xy 60.218619 -226.464687) (xy 60.204254 -226.450342) (xy 60.196471 -226.431592) (xy 60.195968 -226.421442)
			(xy 54.154832 -226.421442) (xy 54.1544 -226.431606) (xy 54.146606 -226.450382) (xy 54.132222 -226.464747)
			(xy 54.113435 -226.472514) (xy 54.10327 -226.473004) (xy 52.70373 -226.473004) (xy 52.693579 -226.472443)
			(xy 52.674819 -226.464687) (xy 52.660454 -226.450342) (xy 52.652671 -226.431592) (xy 52.652168 -226.421442)
			(xy 46.611032 -226.421442) (xy 46.6106 -226.431606) (xy 46.602806 -226.450382) (xy 46.588422 -226.464747)
			(xy 46.569635 -226.472514) (xy 46.55947 -226.473004) (xy 45.15993 -226.473004) (xy 45.149779 -226.472443)
			(xy 45.131019 -226.464687) (xy 45.116654 -226.450342) (xy 45.108871 -226.431592) (xy 45.108368 -226.421442)
			(xy 39.067232 -226.421442) (xy 39.0668 -226.431606) (xy 39.059006 -226.450382) (xy 39.044622 -226.464747)
			(xy 39.025835 -226.472514) (xy 39.01567 -226.473004) (xy 37.61613 -226.473004) (xy 37.605979 -226.472443)
			(xy 37.587219 -226.464687) (xy 37.572854 -226.450342) (xy 37.565071 -226.431592) (xy 37.564568 -226.421442)
			(xy 31.523432 -226.421442) (xy 31.523 -226.431606) (xy 31.515206 -226.450382) (xy 31.500822 -226.464747)
			(xy 31.482035 -226.472514) (xy 31.47187 -226.473004) (xy 30.07233 -226.473004) (xy 30.062179 -226.472443)
			(xy 30.043419 -226.464687) (xy 30.029054 -226.450342) (xy 30.021271 -226.431592) (xy 30.020768 -226.421442)
			(xy 23.979632 -226.421442) (xy 23.9792 -226.431606) (xy 23.971406 -226.450382) (xy 23.957022 -226.464747)
			(xy 23.938235 -226.472514) (xy 23.92807 -226.473004) (xy 22.52853 -226.473004) (xy 22.518379 -226.472443)
			(xy 22.499619 -226.464687) (xy 22.485254 -226.450342) (xy 22.477471 -226.431592) (xy 22.476968 -226.421442)
			(xy 16.435832 -226.421442) (xy 16.4354 -226.431606) (xy 16.427606 -226.450382) (xy 16.413222 -226.464747)
			(xy 16.394435 -226.472514) (xy 16.38427 -226.473004) (xy 14.98473 -226.473004) (xy 14.974579 -226.472443)
			(xy 14.955819 -226.464687) (xy 14.941454 -226.450342) (xy 14.933671 -226.431592) (xy 14.933168 -226.421442)
			(xy 8.892032 -226.421442) (xy 8.8916 -226.431606) (xy 8.883806 -226.450382) (xy 8.869422 -226.464747)
			(xy 8.850635 -226.472514) (xy 8.84047 -226.473004) (xy 7.44093 -226.473004) (xy 7.430779 -226.472443)
			(xy 7.412019 -226.464687) (xy 7.397654 -226.450342) (xy 7.389871 -226.431592) (xy 7.389368 -226.421442)
			(xy 2.509012 -226.421442) (xy 2.509012 -227.271326) (xy 11.489436 -227.271326) (xy 11.489436 -226.862386)
			(xy 11.489922 -226.852228) (xy 11.497701 -226.833459) (xy 11.512069 -226.819094) (xy 11.53084 -226.81132)
			(xy 11.540998 -226.810824) (xy 12.940538 -226.810824) (xy 12.950696 -226.811302) (xy 12.969464 -226.819086)
			(xy 12.983827 -226.833456) (xy 12.991603 -226.852227) (xy 12.9921 -226.862386) (xy 12.9921 -227.271326)
			(xy 19.033236 -227.271326) (xy 19.033236 -226.862386) (xy 19.033722 -226.852228) (xy 19.041501 -226.833459)
			(xy 19.055869 -226.819094) (xy 19.07464 -226.81132) (xy 19.084798 -226.810824) (xy 20.484338 -226.810824)
			(xy 20.494496 -226.811302) (xy 20.513264 -226.819086) (xy 20.527627 -226.833456) (xy 20.535403 -226.852227)
			(xy 20.5359 -226.862386) (xy 20.5359 -227.271326) (xy 26.577036 -227.271326) (xy 26.577036 -226.862386)
			(xy 26.577522 -226.852228) (xy 26.585301 -226.833459) (xy 26.599669 -226.819094) (xy 26.61844 -226.81132)
			(xy 26.628598 -226.810824) (xy 28.028138 -226.810824) (xy 28.038296 -226.811302) (xy 28.057064 -226.819086)
			(xy 28.071427 -226.833456) (xy 28.079203 -226.852227) (xy 28.0797 -226.862386) (xy 28.0797 -227.271326)
			(xy 34.120836 -227.271326) (xy 34.120836 -226.862386) (xy 34.121322 -226.852228) (xy 34.129101 -226.833459)
			(xy 34.143469 -226.819094) (xy 34.16224 -226.81132) (xy 34.172398 -226.810824) (xy 35.571938 -226.810824)
			(xy 35.582096 -226.811302) (xy 35.600864 -226.819086) (xy 35.615227 -226.833456) (xy 35.623003 -226.852227)
			(xy 35.6235 -226.862386) (xy 35.6235 -227.271326) (xy 41.664636 -227.271326) (xy 41.664636 -226.862386)
			(xy 41.665122 -226.852228) (xy 41.672901 -226.833459) (xy 41.687269 -226.819094) (xy 41.70604 -226.81132)
			(xy 41.716198 -226.810824) (xy 43.115738 -226.810824) (xy 43.125896 -226.811302) (xy 43.144664 -226.819086)
			(xy 43.159027 -226.833456) (xy 43.166803 -226.852227) (xy 43.1673 -226.862386) (xy 43.1673 -227.271326)
			(xy 49.208436 -227.271326) (xy 49.208436 -226.862386) (xy 49.208922 -226.852228) (xy 49.216701 -226.833459)
			(xy 49.231069 -226.819094) (xy 49.24984 -226.81132) (xy 49.259998 -226.810824) (xy 50.659538 -226.810824)
			(xy 50.669696 -226.811302) (xy 50.688464 -226.819086) (xy 50.702827 -226.833456) (xy 50.710603 -226.852227)
			(xy 50.7111 -226.862386) (xy 50.7111 -227.271326) (xy 56.752236 -227.271326) (xy 56.752236 -226.862386)
			(xy 56.752722 -226.852228) (xy 56.760501 -226.833459) (xy 56.774869 -226.819094) (xy 56.79364 -226.81132)
			(xy 56.803798 -226.810824) (xy 58.203338 -226.810824) (xy 58.213496 -226.811302) (xy 58.232264 -226.819086)
			(xy 58.246627 -226.833456) (xy 58.254403 -226.852227) (xy 58.2549 -226.862386) (xy 58.2549 -227.271326)
			(xy 64.296036 -227.271326) (xy 64.296036 -226.862386) (xy 64.296522 -226.852228) (xy 64.304301 -226.833459)
			(xy 64.318669 -226.819094) (xy 64.33744 -226.81132) (xy 64.347598 -226.810824) (xy 65.747138 -226.810824)
			(xy 65.757296 -226.811302) (xy 65.776064 -226.819086) (xy 65.790427 -226.833456) (xy 65.798203 -226.852227)
			(xy 65.7987 -226.862386) (xy 65.7987 -227.271326) (xy 162.162236 -227.271326) (xy 162.162236 -226.862386)
			(xy 162.162722 -226.852228) (xy 162.170501 -226.833459) (xy 162.184869 -226.819094) (xy 162.20364 -226.81132)
			(xy 162.213798 -226.810824) (xy 163.613338 -226.810824) (xy 163.623496 -226.811302) (xy 163.642264 -226.819086)
			(xy 163.656627 -226.833456) (xy 163.664403 -226.852227) (xy 163.6649 -226.862386) (xy 163.6649 -227.271326)
			(xy 169.706036 -227.271326) (xy 169.706036 -226.862386) (xy 169.706522 -226.852228) (xy 169.714301 -226.833459)
			(xy 169.728669 -226.819094) (xy 169.74744 -226.81132) (xy 169.757598 -226.810824) (xy 171.157138 -226.810824)
			(xy 171.167296 -226.811302) (xy 171.186064 -226.819086) (xy 171.200427 -226.833456) (xy 171.208203 -226.852227)
			(xy 171.2087 -226.862386) (xy 171.2087 -227.271326) (xy 177.249836 -227.271326) (xy 177.249836 -226.862386)
			(xy 177.250322 -226.852228) (xy 177.258101 -226.833459) (xy 177.272469 -226.819094) (xy 177.29124 -226.81132)
			(xy 177.301398 -226.810824) (xy 178.700938 -226.810824) (xy 178.711096 -226.811302) (xy 178.729864 -226.819086)
			(xy 178.744227 -226.833456) (xy 178.752003 -226.852227) (xy 178.7525 -226.862386) (xy 178.7525 -227.271326)
			(xy 184.793636 -227.271326) (xy 184.793636 -226.862386) (xy 184.794122 -226.852228) (xy 184.801901 -226.833459)
			(xy 184.816269 -226.819094) (xy 184.83504 -226.81132) (xy 184.845198 -226.810824) (xy 186.244738 -226.810824)
			(xy 186.254896 -226.811302) (xy 186.273664 -226.819086) (xy 186.288027 -226.833456) (xy 186.295803 -226.852227)
			(xy 186.2963 -226.862386) (xy 186.2963 -227.271326) (xy 192.337436 -227.271326) (xy 192.337436 -226.862386)
			(xy 192.337922 -226.852228) (xy 192.345701 -226.833459) (xy 192.360069 -226.819094) (xy 192.37884 -226.81132)
			(xy 192.388998 -226.810824) (xy 193.788538 -226.810824) (xy 193.798696 -226.811302) (xy 193.817464 -226.819086)
			(xy 193.831827 -226.833456) (xy 193.839603 -226.852227) (xy 193.8401 -226.862386) (xy 193.8401 -227.271326)
			(xy 199.881236 -227.271326) (xy 199.881236 -226.862386) (xy 199.881722 -226.852228) (xy 199.889501 -226.833459)
			(xy 199.903869 -226.819094) (xy 199.92264 -226.81132) (xy 199.932798 -226.810824) (xy 201.332338 -226.810824)
			(xy 201.342496 -226.811302) (xy 201.361264 -226.819086) (xy 201.375627 -226.833456) (xy 201.383403 -226.852227)
			(xy 201.3839 -226.862386) (xy 201.3839 -227.271326) (xy 207.425036 -227.271326) (xy 207.425036 -226.862386)
			(xy 207.425522 -226.852228) (xy 207.433301 -226.833459) (xy 207.447669 -226.819094) (xy 207.46644 -226.81132)
			(xy 207.476598 -226.810824) (xy 208.876138 -226.810824) (xy 208.886296 -226.811302) (xy 208.905064 -226.819086)
			(xy 208.919427 -226.833456) (xy 208.927203 -226.852227) (xy 208.9277 -226.862386) (xy 208.9277 -227.271326)
			(xy 214.968836 -227.271326) (xy 214.968836 -226.862386) (xy 214.969322 -226.852228) (xy 214.977101 -226.833459)
			(xy 214.991469 -226.819094) (xy 215.01024 -226.81132) (xy 215.020398 -226.810824) (xy 216.419938 -226.810824)
			(xy 216.430096 -226.811302) (xy 216.448864 -226.819086) (xy 216.463227 -226.833456) (xy 216.471003 -226.852227)
			(xy 216.4715 -226.862386) (xy 216.4715 -227.271326) (xy 259.429504 -227.271326) (xy 259.429504 -226.862386)
			(xy 259.430021 -226.852232) (xy 259.437794 -226.833469) (xy 259.452152 -226.819105) (xy 259.470912 -226.811325)
			(xy 259.481066 -226.810824) (xy 260.880606 -226.810824) (xy 260.890762 -226.811328) (xy 260.909529 -226.819102)
			(xy 260.923893 -226.833464) (xy 260.93167 -226.85223) (xy 260.932168 -226.862386) (xy 260.932168 -227.271326)
			(xy 266.973304 -227.271326) (xy 266.973304 -226.862386) (xy 266.973821 -226.852232) (xy 266.981594 -226.833469)
			(xy 266.995952 -226.819105) (xy 267.014712 -226.811325) (xy 267.024866 -226.810824) (xy 268.424406 -226.810824)
			(xy 268.434562 -226.811328) (xy 268.453329 -226.819102) (xy 268.467693 -226.833464) (xy 268.47547 -226.85223)
			(xy 268.475968 -226.862386) (xy 268.475968 -227.271326) (xy 274.517104 -227.271326) (xy 274.517104 -226.862386)
			(xy 274.517621 -226.852232) (xy 274.525394 -226.833469) (xy 274.539752 -226.819105) (xy 274.558512 -226.811325)
			(xy 274.568666 -226.810824) (xy 275.968206 -226.810824) (xy 275.978362 -226.811328) (xy 275.997129 -226.819102)
			(xy 276.011493 -226.833464) (xy 276.01927 -226.85223) (xy 276.019768 -226.862386) (xy 276.019768 -227.271326)
			(xy 282.060904 -227.271326) (xy 282.060904 -226.862386) (xy 282.061421 -226.852232) (xy 282.069194 -226.833469)
			(xy 282.083552 -226.819105) (xy 282.102312 -226.811325) (xy 282.112466 -226.810824) (xy 283.512006 -226.810824)
			(xy 283.522162 -226.811328) (xy 283.540929 -226.819102) (xy 283.555293 -226.833464) (xy 283.56307 -226.85223)
			(xy 283.563568 -226.862386) (xy 283.563568 -227.271326) (xy 289.604704 -227.271326) (xy 289.604704 -226.862386)
			(xy 289.605221 -226.852232) (xy 289.612994 -226.833469) (xy 289.627352 -226.819105) (xy 289.646112 -226.811325)
			(xy 289.656266 -226.810824) (xy 291.055806 -226.810824) (xy 291.065962 -226.811328) (xy 291.084729 -226.819102)
			(xy 291.099093 -226.833464) (xy 291.10687 -226.85223) (xy 291.107368 -226.862386) (xy 291.107368 -227.271326)
			(xy 297.148504 -227.271326) (xy 297.148504 -226.862386) (xy 297.149021 -226.852232) (xy 297.156794 -226.833469)
			(xy 297.171152 -226.819105) (xy 297.189912 -226.811325) (xy 297.200066 -226.810824) (xy 298.599606 -226.810824)
			(xy 298.609762 -226.811328) (xy 298.628529 -226.819102) (xy 298.642893 -226.833464) (xy 298.65067 -226.85223)
			(xy 298.651168 -226.862386) (xy 298.651168 -227.271326) (xy 304.692304 -227.271326) (xy 304.692304 -226.862386)
			(xy 304.692821 -226.852232) (xy 304.700594 -226.833469) (xy 304.714952 -226.819105) (xy 304.733712 -226.811325)
			(xy 304.743866 -226.810824) (xy 306.143406 -226.810824) (xy 306.153562 -226.811328) (xy 306.172329 -226.819102)
			(xy 306.186693 -226.833464) (xy 306.19447 -226.85223) (xy 306.194968 -226.862386) (xy 306.194968 -227.271326)
			(xy 312.236104 -227.271326) (xy 312.236104 -226.862386) (xy 312.236621 -226.852232) (xy 312.244394 -226.833469)
			(xy 312.258752 -226.819105) (xy 312.277512 -226.811325) (xy 312.287666 -226.810824) (xy 313.687206 -226.810824)
			(xy 313.697362 -226.811328) (xy 313.716129 -226.819102) (xy 313.730493 -226.833464) (xy 313.73827 -226.85223)
			(xy 313.738768 -226.862386) (xy 313.738768 -227.271326) (xy 410.102304 -227.271326) (xy 410.102304 -226.862386)
			(xy 410.102821 -226.852232) (xy 410.110594 -226.833469) (xy 410.124952 -226.819105) (xy 410.143712 -226.811325)
			(xy 410.153866 -226.810824) (xy 411.553406 -226.810824) (xy 411.563562 -226.811328) (xy 411.582329 -226.819102)
			(xy 411.596693 -226.833464) (xy 411.60447 -226.85223) (xy 411.604968 -226.862386) (xy 411.604968 -227.271326)
			(xy 417.646104 -227.271326) (xy 417.646104 -226.862386) (xy 417.646621 -226.852232) (xy 417.654394 -226.833469)
			(xy 417.668752 -226.819105) (xy 417.687512 -226.811325) (xy 417.697666 -226.810824) (xy 419.097206 -226.810824)
			(xy 419.107362 -226.811328) (xy 419.126129 -226.819102) (xy 419.140493 -226.833464) (xy 419.14827 -226.85223)
			(xy 419.148768 -226.862386) (xy 419.148768 -227.271326) (xy 425.189904 -227.271326) (xy 425.189904 -226.862386)
			(xy 425.190421 -226.852232) (xy 425.198194 -226.833469) (xy 425.212552 -226.819105) (xy 425.231312 -226.811325)
			(xy 425.241466 -226.810824) (xy 426.641006 -226.810824) (xy 426.651162 -226.811328) (xy 426.669929 -226.819102)
			(xy 426.684293 -226.833464) (xy 426.69207 -226.85223) (xy 426.692568 -226.862386) (xy 426.692568 -227.271326)
			(xy 432.733704 -227.271326) (xy 432.733704 -226.862386) (xy 432.734221 -226.852232) (xy 432.741994 -226.833469)
			(xy 432.756352 -226.819105) (xy 432.775112 -226.811325) (xy 432.785266 -226.810824) (xy 434.184806 -226.810824)
			(xy 434.194962 -226.811328) (xy 434.213729 -226.819102) (xy 434.228093 -226.833464) (xy 434.23587 -226.85223)
			(xy 434.236368 -226.862386) (xy 434.236368 -227.271326) (xy 440.277504 -227.271326) (xy 440.277504 -226.862386)
			(xy 440.278021 -226.852232) (xy 440.285794 -226.833469) (xy 440.300152 -226.819105) (xy 440.318912 -226.811325)
			(xy 440.329066 -226.810824) (xy 441.728606 -226.810824) (xy 441.738762 -226.811328) (xy 441.757529 -226.819102)
			(xy 441.771893 -226.833464) (xy 441.77967 -226.85223) (xy 441.780168 -226.862386) (xy 441.780168 -227.271326)
			(xy 447.821304 -227.271326) (xy 447.821304 -226.862386) (xy 447.821821 -226.852232) (xy 447.829594 -226.833469)
			(xy 447.843952 -226.819105) (xy 447.862712 -226.811325) (xy 447.872866 -226.810824) (xy 449.272406 -226.810824)
			(xy 449.282562 -226.811328) (xy 449.301329 -226.819102) (xy 449.315693 -226.833464) (xy 449.32347 -226.85223)
			(xy 449.323968 -226.862386) (xy 449.323968 -227.271326) (xy 455.365104 -227.271326) (xy 455.365104 -226.862386)
			(xy 455.365621 -226.852232) (xy 455.373394 -226.833469) (xy 455.387752 -226.819105) (xy 455.406512 -226.811325)
			(xy 455.416666 -226.810824) (xy 456.816206 -226.810824) (xy 456.826362 -226.811328) (xy 456.845129 -226.819102)
			(xy 456.859493 -226.833464) (xy 456.86727 -226.85223) (xy 456.867768 -226.862386) (xy 456.867768 -227.271326)
			(xy 462.908904 -227.271326) (xy 462.908904 -226.862386) (xy 462.909421 -226.852232) (xy 462.917194 -226.833469)
			(xy 462.931552 -226.819105) (xy 462.950312 -226.811325) (xy 462.960466 -226.810824) (xy 464.360006 -226.810824)
			(xy 464.370162 -226.811328) (xy 464.388929 -226.819102) (xy 464.403293 -226.833464) (xy 464.41107 -226.85223)
			(xy 464.411568 -226.862386) (xy 464.411568 -227.271326) (xy 464.411088 -227.281485) (xy 464.403306 -227.300253)
			(xy 464.388937 -227.314618) (xy 464.370165 -227.322392) (xy 464.360006 -227.322888) (xy 462.960466 -227.322888)
			(xy 462.950309 -227.322395) (xy 462.931544 -227.314614) (xy 462.917181 -227.300249) (xy 462.909403 -227.281483)
			(xy 462.908904 -227.271326) (xy 456.867768 -227.271326) (xy 456.867288 -227.281485) (xy 456.859506 -227.300253)
			(xy 456.845137 -227.314618) (xy 456.826365 -227.322392) (xy 456.816206 -227.322888) (xy 455.416666 -227.322888)
			(xy 455.406509 -227.322395) (xy 455.387744 -227.314614) (xy 455.373381 -227.300249) (xy 455.365603 -227.281483)
			(xy 455.365104 -227.271326) (xy 449.323968 -227.271326) (xy 449.323488 -227.281485) (xy 449.315706 -227.300253)
			(xy 449.301337 -227.314618) (xy 449.282565 -227.322392) (xy 449.272406 -227.322888) (xy 447.872866 -227.322888)
			(xy 447.862709 -227.322395) (xy 447.843944 -227.314614) (xy 447.829581 -227.300249) (xy 447.821803 -227.281483)
			(xy 447.821304 -227.271326) (xy 441.780168 -227.271326) (xy 441.779688 -227.281485) (xy 441.771906 -227.300253)
			(xy 441.757537 -227.314618) (xy 441.738765 -227.322392) (xy 441.728606 -227.322888) (xy 440.329066 -227.322888)
			(xy 440.318909 -227.322395) (xy 440.300144 -227.314614) (xy 440.285781 -227.300249) (xy 440.278003 -227.281483)
			(xy 440.277504 -227.271326) (xy 434.236368 -227.271326) (xy 434.235888 -227.281485) (xy 434.228106 -227.300253)
			(xy 434.213737 -227.314618) (xy 434.194965 -227.322392) (xy 434.184806 -227.322888) (xy 432.785266 -227.322888)
			(xy 432.775109 -227.322395) (xy 432.756344 -227.314614) (xy 432.741981 -227.300249) (xy 432.734203 -227.281483)
			(xy 432.733704 -227.271326) (xy 426.692568 -227.271326) (xy 426.692088 -227.281485) (xy 426.684306 -227.300253)
			(xy 426.669937 -227.314618) (xy 426.651165 -227.322392) (xy 426.641006 -227.322888) (xy 425.241466 -227.322888)
			(xy 425.231309 -227.322395) (xy 425.212544 -227.314614) (xy 425.198181 -227.300249) (xy 425.190403 -227.281483)
			(xy 425.189904 -227.271326) (xy 419.148768 -227.271326) (xy 419.148288 -227.281485) (xy 419.140506 -227.300253)
			(xy 419.126137 -227.314618) (xy 419.107365 -227.322392) (xy 419.097206 -227.322888) (xy 417.697666 -227.322888)
			(xy 417.687509 -227.322395) (xy 417.668744 -227.314614) (xy 417.654381 -227.300249) (xy 417.646603 -227.281483)
			(xy 417.646104 -227.271326) (xy 411.604968 -227.271326) (xy 411.604488 -227.281485) (xy 411.596706 -227.300253)
			(xy 411.582337 -227.314618) (xy 411.563565 -227.322392) (xy 411.553406 -227.322888) (xy 410.153866 -227.322888)
			(xy 410.143709 -227.322395) (xy 410.124944 -227.314614) (xy 410.110581 -227.300249) (xy 410.102803 -227.281483)
			(xy 410.102304 -227.271326) (xy 313.738768 -227.271326) (xy 313.738288 -227.281485) (xy 313.730506 -227.300253)
			(xy 313.716137 -227.314618) (xy 313.697365 -227.322392) (xy 313.687206 -227.322888) (xy 312.287666 -227.322888)
			(xy 312.277509 -227.322395) (xy 312.258744 -227.314614) (xy 312.244381 -227.300249) (xy 312.236603 -227.281483)
			(xy 312.236104 -227.271326) (xy 306.194968 -227.271326) (xy 306.194488 -227.281485) (xy 306.186706 -227.300253)
			(xy 306.172337 -227.314618) (xy 306.153565 -227.322392) (xy 306.143406 -227.322888) (xy 304.743866 -227.322888)
			(xy 304.733709 -227.322395) (xy 304.714944 -227.314614) (xy 304.700581 -227.300249) (xy 304.692803 -227.281483)
			(xy 304.692304 -227.271326) (xy 298.651168 -227.271326) (xy 298.650688 -227.281485) (xy 298.642906 -227.300253)
			(xy 298.628537 -227.314618) (xy 298.609765 -227.322392) (xy 298.599606 -227.322888) (xy 297.200066 -227.322888)
			(xy 297.189909 -227.322395) (xy 297.171144 -227.314614) (xy 297.156781 -227.300249) (xy 297.149003 -227.281483)
			(xy 297.148504 -227.271326) (xy 291.107368 -227.271326) (xy 291.106888 -227.281485) (xy 291.099106 -227.300253)
			(xy 291.084737 -227.314618) (xy 291.065965 -227.322392) (xy 291.055806 -227.322888) (xy 289.656266 -227.322888)
			(xy 289.646109 -227.322395) (xy 289.627344 -227.314614) (xy 289.612981 -227.300249) (xy 289.605203 -227.281483)
			(xy 289.604704 -227.271326) (xy 283.563568 -227.271326) (xy 283.563088 -227.281485) (xy 283.555306 -227.300253)
			(xy 283.540937 -227.314618) (xy 283.522165 -227.322392) (xy 283.512006 -227.322888) (xy 282.112466 -227.322888)
			(xy 282.102309 -227.322395) (xy 282.083544 -227.314614) (xy 282.069181 -227.300249) (xy 282.061403 -227.281483)
			(xy 282.060904 -227.271326) (xy 276.019768 -227.271326) (xy 276.019288 -227.281485) (xy 276.011506 -227.300253)
			(xy 275.997137 -227.314618) (xy 275.978365 -227.322392) (xy 275.968206 -227.322888) (xy 274.568666 -227.322888)
			(xy 274.558509 -227.322395) (xy 274.539744 -227.314614) (xy 274.525381 -227.300249) (xy 274.517603 -227.281483)
			(xy 274.517104 -227.271326) (xy 268.475968 -227.271326) (xy 268.475488 -227.281485) (xy 268.467706 -227.300253)
			(xy 268.453337 -227.314618) (xy 268.434565 -227.322392) (xy 268.424406 -227.322888) (xy 267.024866 -227.322888)
			(xy 267.014709 -227.322395) (xy 266.995944 -227.314614) (xy 266.981581 -227.300249) (xy 266.973803 -227.281483)
			(xy 266.973304 -227.271326) (xy 260.932168 -227.271326) (xy 260.931688 -227.281485) (xy 260.923906 -227.300253)
			(xy 260.909537 -227.314618) (xy 260.890765 -227.322392) (xy 260.880606 -227.322888) (xy 259.481066 -227.322888)
			(xy 259.470909 -227.322395) (xy 259.452144 -227.314614) (xy 259.437781 -227.300249) (xy 259.430003 -227.281483)
			(xy 259.429504 -227.271326) (xy 216.4715 -227.271326) (xy 216.470989 -227.281481) (xy 216.463213 -227.300243)
			(xy 216.448853 -227.314606) (xy 216.430093 -227.322387) (xy 216.419938 -227.322888) (xy 215.020398 -227.322888)
			(xy 215.010243 -227.322369) (xy 214.991479 -227.314599) (xy 214.977115 -227.300241) (xy 214.969336 -227.28148)
			(xy 214.968836 -227.271326) (xy 208.9277 -227.271326) (xy 208.927189 -227.281481) (xy 208.919413 -227.300243)
			(xy 208.905053 -227.314606) (xy 208.886293 -227.322387) (xy 208.876138 -227.322888) (xy 207.476598 -227.322888)
			(xy 207.466443 -227.322369) (xy 207.447679 -227.314599) (xy 207.433315 -227.300241) (xy 207.425536 -227.28148)
			(xy 207.425036 -227.271326) (xy 201.3839 -227.271326) (xy 201.383389 -227.281481) (xy 201.375613 -227.300243)
			(xy 201.361253 -227.314606) (xy 201.342493 -227.322387) (xy 201.332338 -227.322888) (xy 199.932798 -227.322888)
			(xy 199.922643 -227.322369) (xy 199.903879 -227.314599) (xy 199.889515 -227.300241) (xy 199.881736 -227.28148)
			(xy 199.881236 -227.271326) (xy 193.8401 -227.271326) (xy 193.839589 -227.281481) (xy 193.831813 -227.300243)
			(xy 193.817453 -227.314606) (xy 193.798693 -227.322387) (xy 193.788538 -227.322888) (xy 192.388998 -227.322888)
			(xy 192.378843 -227.322369) (xy 192.360079 -227.314599) (xy 192.345715 -227.300241) (xy 192.337936 -227.28148)
			(xy 192.337436 -227.271326) (xy 186.2963 -227.271326) (xy 186.295789 -227.281481) (xy 186.288013 -227.300243)
			(xy 186.273653 -227.314606) (xy 186.254893 -227.322387) (xy 186.244738 -227.322888) (xy 184.845198 -227.322888)
			(xy 184.835043 -227.322369) (xy 184.816279 -227.314599) (xy 184.801915 -227.300241) (xy 184.794136 -227.28148)
			(xy 184.793636 -227.271326) (xy 178.7525 -227.271326) (xy 178.751989 -227.281481) (xy 178.744213 -227.300243)
			(xy 178.729853 -227.314606) (xy 178.711093 -227.322387) (xy 178.700938 -227.322888) (xy 177.301398 -227.322888)
			(xy 177.291243 -227.322369) (xy 177.272479 -227.314599) (xy 177.258115 -227.300241) (xy 177.250336 -227.28148)
			(xy 177.249836 -227.271326) (xy 171.2087 -227.271326) (xy 171.208189 -227.281481) (xy 171.200413 -227.300243)
			(xy 171.186053 -227.314606) (xy 171.167293 -227.322387) (xy 171.157138 -227.322888) (xy 169.757598 -227.322888)
			(xy 169.747443 -227.322369) (xy 169.728679 -227.314599) (xy 169.714315 -227.300241) (xy 169.706536 -227.28148)
			(xy 169.706036 -227.271326) (xy 163.6649 -227.271326) (xy 163.664389 -227.281481) (xy 163.656613 -227.300243)
			(xy 163.642253 -227.314606) (xy 163.623493 -227.322387) (xy 163.613338 -227.322888) (xy 162.213798 -227.322888)
			(xy 162.203643 -227.322369) (xy 162.184879 -227.314599) (xy 162.170515 -227.300241) (xy 162.162736 -227.28148)
			(xy 162.162236 -227.271326) (xy 65.7987 -227.271326) (xy 65.798189 -227.281481) (xy 65.790413 -227.300243)
			(xy 65.776053 -227.314606) (xy 65.757293 -227.322387) (xy 65.747138 -227.322888) (xy 64.347598 -227.322888)
			(xy 64.337443 -227.322369) (xy 64.318679 -227.314599) (xy 64.304315 -227.300241) (xy 64.296536 -227.28148)
			(xy 64.296036 -227.271326) (xy 58.2549 -227.271326) (xy 58.254389 -227.281481) (xy 58.246613 -227.300243)
			(xy 58.232253 -227.314606) (xy 58.213493 -227.322387) (xy 58.203338 -227.322888) (xy 56.803798 -227.322888)
			(xy 56.793643 -227.322369) (xy 56.774879 -227.314599) (xy 56.760515 -227.300241) (xy 56.752736 -227.28148)
			(xy 56.752236 -227.271326) (xy 50.7111 -227.271326) (xy 50.710589 -227.281481) (xy 50.702813 -227.300243)
			(xy 50.688453 -227.314606) (xy 50.669693 -227.322387) (xy 50.659538 -227.322888) (xy 49.259998 -227.322888)
			(xy 49.249843 -227.322369) (xy 49.231079 -227.314599) (xy 49.216715 -227.300241) (xy 49.208936 -227.28148)
			(xy 49.208436 -227.271326) (xy 43.1673 -227.271326) (xy 43.166789 -227.281481) (xy 43.159013 -227.300243)
			(xy 43.144653 -227.314606) (xy 43.125893 -227.322387) (xy 43.115738 -227.322888) (xy 41.716198 -227.322888)
			(xy 41.706043 -227.322369) (xy 41.687279 -227.314599) (xy 41.672915 -227.300241) (xy 41.665136 -227.28148)
			(xy 41.664636 -227.271326) (xy 35.6235 -227.271326) (xy 35.622989 -227.281481) (xy 35.615213 -227.300243)
			(xy 35.600853 -227.314606) (xy 35.582093 -227.322387) (xy 35.571938 -227.322888) (xy 34.172398 -227.322888)
			(xy 34.162243 -227.322369) (xy 34.143479 -227.314599) (xy 34.129115 -227.300241) (xy 34.121336 -227.28148)
			(xy 34.120836 -227.271326) (xy 28.0797 -227.271326) (xy 28.079189 -227.281481) (xy 28.071413 -227.300243)
			(xy 28.057053 -227.314606) (xy 28.038293 -227.322387) (xy 28.028138 -227.322888) (xy 26.628598 -227.322888)
			(xy 26.618443 -227.322369) (xy 26.599679 -227.314599) (xy 26.585315 -227.300241) (xy 26.577536 -227.28148)
			(xy 26.577036 -227.271326) (xy 20.5359 -227.271326) (xy 20.535389 -227.281481) (xy 20.527613 -227.300243)
			(xy 20.513253 -227.314606) (xy 20.494493 -227.322387) (xy 20.484338 -227.322888) (xy 19.084798 -227.322888)
			(xy 19.074643 -227.322369) (xy 19.055879 -227.314599) (xy 19.041515 -227.300241) (xy 19.033736 -227.28148)
			(xy 19.033236 -227.271326) (xy 12.9921 -227.271326) (xy 12.991589 -227.281481) (xy 12.983813 -227.300243)
			(xy 12.969453 -227.314606) (xy 12.950693 -227.322387) (xy 12.940538 -227.322888) (xy 11.540998 -227.322888)
			(xy 11.530843 -227.322369) (xy 11.512079 -227.314599) (xy 11.497715 -227.300241) (xy 11.489936 -227.28148)
			(xy 11.489436 -227.271326) (xy 2.509012 -227.271326) (xy 2.509012 -228.121464) (xy 7.389368 -228.121464)
			(xy 7.389368 -227.712524) (xy 7.38984 -227.702375) (xy 7.397622 -227.68363) (xy 7.412003 -227.669306)
			(xy 7.43078 -227.6616) (xy 7.44093 -227.661216) (xy 8.84047 -227.661216) (xy 8.850592 -227.66175)
			(xy 8.869308 -227.669464) (xy 8.883664 -227.683735) (xy 8.891489 -227.702405) (xy 8.892032 -227.712524)
			(xy 8.892032 -228.121464) (xy 11.489436 -228.121464) (xy 11.489436 -227.712524) (xy 11.489842 -227.702367)
			(xy 11.497636 -227.683608) (xy 11.512039 -227.669282) (xy 11.530839 -227.661588) (xy 11.540998 -227.661216)
			(xy 12.940538 -227.661216) (xy 12.950664 -227.661695) (xy 12.969382 -227.669431) (xy 12.983736 -227.683719)
			(xy 12.991558 -227.7024) (xy 12.9921 -227.712524) (xy 12.9921 -228.121464) (xy 14.933168 -228.121464)
			(xy 14.933168 -227.712524) (xy 14.93364 -227.702375) (xy 14.941422 -227.68363) (xy 14.955803 -227.669306)
			(xy 14.97458 -227.6616) (xy 14.98473 -227.661216) (xy 16.38427 -227.661216) (xy 16.394392 -227.66175)
			(xy 16.413108 -227.669464) (xy 16.427464 -227.683735) (xy 16.435289 -227.702405) (xy 16.435832 -227.712524)
			(xy 16.435832 -228.121464) (xy 19.033236 -228.121464) (xy 19.033236 -227.712524) (xy 19.033642 -227.702367)
			(xy 19.041436 -227.683608) (xy 19.055839 -227.669282) (xy 19.074639 -227.661588) (xy 19.084798 -227.661216)
			(xy 20.484338 -227.661216) (xy 20.494464 -227.661695) (xy 20.513182 -227.669431) (xy 20.527536 -227.683719)
			(xy 20.535358 -227.7024) (xy 20.5359 -227.712524) (xy 20.5359 -228.121464) (xy 22.476968 -228.121464)
			(xy 22.476968 -227.712524) (xy 22.47744 -227.702375) (xy 22.485222 -227.68363) (xy 22.499603 -227.669306)
			(xy 22.51838 -227.6616) (xy 22.52853 -227.661216) (xy 23.92807 -227.661216) (xy 23.938192 -227.66175)
			(xy 23.956908 -227.669464) (xy 23.971264 -227.683735) (xy 23.979089 -227.702405) (xy 23.979632 -227.712524)
			(xy 23.979632 -228.121464) (xy 26.577036 -228.121464) (xy 26.577036 -227.712524) (xy 26.577442 -227.702367)
			(xy 26.585236 -227.683608) (xy 26.599639 -227.669282) (xy 26.618439 -227.661588) (xy 26.628598 -227.661216)
			(xy 28.028138 -227.661216) (xy 28.038264 -227.661695) (xy 28.056982 -227.669431) (xy 28.071336 -227.683719)
			(xy 28.079158 -227.7024) (xy 28.0797 -227.712524) (xy 28.0797 -228.121464) (xy 30.020768 -228.121464)
			(xy 30.020768 -227.712524) (xy 30.02124 -227.702375) (xy 30.029022 -227.68363) (xy 30.043403 -227.669306)
			(xy 30.06218 -227.6616) (xy 30.07233 -227.661216) (xy 31.47187 -227.661216) (xy 31.481992 -227.66175)
			(xy 31.500708 -227.669464) (xy 31.515064 -227.683735) (xy 31.522889 -227.702405) (xy 31.523432 -227.712524)
			(xy 31.523432 -228.121464) (xy 34.120836 -228.121464) (xy 34.120836 -227.712524) (xy 34.121242 -227.702367)
			(xy 34.129036 -227.683608) (xy 34.143439 -227.669282) (xy 34.162239 -227.661588) (xy 34.172398 -227.661216)
			(xy 35.571938 -227.661216) (xy 35.582064 -227.661695) (xy 35.600782 -227.669431) (xy 35.615136 -227.683719)
			(xy 35.622958 -227.7024) (xy 35.6235 -227.712524) (xy 35.6235 -228.121464) (xy 37.564568 -228.121464)
			(xy 37.564568 -227.712524) (xy 37.56504 -227.702375) (xy 37.572822 -227.68363) (xy 37.587203 -227.669306)
			(xy 37.60598 -227.6616) (xy 37.61613 -227.661216) (xy 39.01567 -227.661216) (xy 39.025792 -227.66175)
			(xy 39.044508 -227.669464) (xy 39.058864 -227.683735) (xy 39.066689 -227.702405) (xy 39.067232 -227.712524)
			(xy 39.067232 -228.121464) (xy 41.664636 -228.121464) (xy 41.664636 -227.712524) (xy 41.665042 -227.702367)
			(xy 41.672836 -227.683608) (xy 41.687239 -227.669282) (xy 41.706039 -227.661588) (xy 41.716198 -227.661216)
			(xy 43.115738 -227.661216) (xy 43.125864 -227.661695) (xy 43.144582 -227.669431) (xy 43.158936 -227.683719)
			(xy 43.166758 -227.7024) (xy 43.1673 -227.712524) (xy 43.1673 -228.121464) (xy 45.108368 -228.121464)
			(xy 45.108368 -227.712524) (xy 45.10884 -227.702375) (xy 45.116622 -227.68363) (xy 45.131003 -227.669306)
			(xy 45.14978 -227.6616) (xy 45.15993 -227.661216) (xy 46.55947 -227.661216) (xy 46.569592 -227.66175)
			(xy 46.588308 -227.669464) (xy 46.602664 -227.683735) (xy 46.610489 -227.702405) (xy 46.611032 -227.712524)
			(xy 46.611032 -228.121464) (xy 49.208436 -228.121464) (xy 49.208436 -227.712524) (xy 49.208842 -227.702367)
			(xy 49.216636 -227.683608) (xy 49.231039 -227.669282) (xy 49.249839 -227.661588) (xy 49.259998 -227.661216)
			(xy 50.659538 -227.661216) (xy 50.669664 -227.661695) (xy 50.688382 -227.669431) (xy 50.702736 -227.683719)
			(xy 50.710558 -227.7024) (xy 50.7111 -227.712524) (xy 50.7111 -228.121464) (xy 52.652168 -228.121464)
			(xy 52.652168 -227.712524) (xy 52.65264 -227.702375) (xy 52.660422 -227.68363) (xy 52.674803 -227.669306)
			(xy 52.69358 -227.6616) (xy 52.70373 -227.661216) (xy 54.10327 -227.661216) (xy 54.113392 -227.66175)
			(xy 54.132108 -227.669464) (xy 54.146464 -227.683735) (xy 54.154289 -227.702405) (xy 54.154832 -227.712524)
			(xy 54.154832 -228.121464) (xy 56.752236 -228.121464) (xy 56.752236 -227.712524) (xy 56.752642 -227.702367)
			(xy 56.760436 -227.683608) (xy 56.774839 -227.669282) (xy 56.793639 -227.661588) (xy 56.803798 -227.661216)
			(xy 58.203338 -227.661216) (xy 58.213464 -227.661695) (xy 58.232182 -227.669431) (xy 58.246536 -227.683719)
			(xy 58.254358 -227.7024) (xy 58.2549 -227.712524) (xy 58.2549 -228.121464) (xy 60.195968 -228.121464)
			(xy 60.195968 -227.712524) (xy 60.19644 -227.702375) (xy 60.204222 -227.68363) (xy 60.218603 -227.669306)
			(xy 60.23738 -227.6616) (xy 60.24753 -227.661216) (xy 61.64707 -227.661216) (xy 61.657192 -227.66175)
			(xy 61.675908 -227.669464) (xy 61.690264 -227.683735) (xy 61.698089 -227.702405) (xy 61.698632 -227.712524)
			(xy 61.698632 -228.121464) (xy 64.296036 -228.121464) (xy 64.296036 -227.712524) (xy 64.296442 -227.702367)
			(xy 64.304236 -227.683608) (xy 64.318639 -227.669282) (xy 64.337439 -227.661588) (xy 64.347598 -227.661216)
			(xy 65.747138 -227.661216) (xy 65.757264 -227.661695) (xy 65.775982 -227.669431) (xy 65.790336 -227.683719)
			(xy 65.798158 -227.7024) (xy 65.7987 -227.712524) (xy 65.7987 -228.121464) (xy 158.062168 -228.121464)
			(xy 158.062168 -227.712524) (xy 158.06264 -227.702375) (xy 158.070422 -227.68363) (xy 158.084803 -227.669306)
			(xy 158.10358 -227.6616) (xy 158.11373 -227.661216) (xy 159.51327 -227.661216) (xy 159.523392 -227.66175)
			(xy 159.542108 -227.669464) (xy 159.556464 -227.683735) (xy 159.564289 -227.702405) (xy 159.564832 -227.712524)
			(xy 159.564832 -228.121464) (xy 162.162236 -228.121464) (xy 162.162236 -227.712524) (xy 162.162642 -227.702367)
			(xy 162.170436 -227.683608) (xy 162.184839 -227.669282) (xy 162.203639 -227.661588) (xy 162.213798 -227.661216)
			(xy 163.613338 -227.661216) (xy 163.623464 -227.661695) (xy 163.642182 -227.669431) (xy 163.656536 -227.683719)
			(xy 163.664358 -227.7024) (xy 163.6649 -227.712524) (xy 163.6649 -228.121464) (xy 165.605968 -228.121464)
			(xy 165.605968 -227.712524) (xy 165.60644 -227.702375) (xy 165.614222 -227.68363) (xy 165.628603 -227.669306)
			(xy 165.64738 -227.6616) (xy 165.65753 -227.661216) (xy 167.05707 -227.661216) (xy 167.067192 -227.66175)
			(xy 167.085908 -227.669464) (xy 167.100264 -227.683735) (xy 167.108089 -227.702405) (xy 167.108632 -227.712524)
			(xy 167.108632 -228.121464) (xy 169.706036 -228.121464) (xy 169.706036 -227.712524) (xy 169.706442 -227.702367)
			(xy 169.714236 -227.683608) (xy 169.728639 -227.669282) (xy 169.747439 -227.661588) (xy 169.757598 -227.661216)
			(xy 171.157138 -227.661216) (xy 171.167264 -227.661695) (xy 171.185982 -227.669431) (xy 171.200336 -227.683719)
			(xy 171.208158 -227.7024) (xy 171.2087 -227.712524) (xy 171.2087 -228.121464) (xy 173.149768 -228.121464)
			(xy 173.149768 -227.712524) (xy 173.15024 -227.702375) (xy 173.158022 -227.68363) (xy 173.172403 -227.669306)
			(xy 173.19118 -227.6616) (xy 173.20133 -227.661216) (xy 174.60087 -227.661216) (xy 174.610992 -227.66175)
			(xy 174.629708 -227.669464) (xy 174.644064 -227.683735) (xy 174.651889 -227.702405) (xy 174.652432 -227.712524)
			(xy 174.652432 -228.121464) (xy 177.249836 -228.121464) (xy 177.249836 -227.712524) (xy 177.250242 -227.702367)
			(xy 177.258036 -227.683608) (xy 177.272439 -227.669282) (xy 177.291239 -227.661588) (xy 177.301398 -227.661216)
			(xy 178.700938 -227.661216) (xy 178.711064 -227.661695) (xy 178.729782 -227.669431) (xy 178.744136 -227.683719)
			(xy 178.751958 -227.7024) (xy 178.7525 -227.712524) (xy 178.7525 -228.121464) (xy 180.693568 -228.121464)
			(xy 180.693568 -227.712524) (xy 180.69404 -227.702375) (xy 180.701822 -227.68363) (xy 180.716203 -227.669306)
			(xy 180.73498 -227.6616) (xy 180.74513 -227.661216) (xy 182.14467 -227.661216) (xy 182.154792 -227.66175)
			(xy 182.173508 -227.669464) (xy 182.187864 -227.683735) (xy 182.195689 -227.702405) (xy 182.196232 -227.712524)
			(xy 182.196232 -228.121464) (xy 184.793636 -228.121464) (xy 184.793636 -227.712524) (xy 184.794042 -227.702367)
			(xy 184.801836 -227.683608) (xy 184.816239 -227.669282) (xy 184.835039 -227.661588) (xy 184.845198 -227.661216)
			(xy 186.244738 -227.661216) (xy 186.254864 -227.661695) (xy 186.273582 -227.669431) (xy 186.287936 -227.683719)
			(xy 186.295758 -227.7024) (xy 186.2963 -227.712524) (xy 186.2963 -228.121464) (xy 188.237368 -228.121464)
			(xy 188.237368 -227.712524) (xy 188.23784 -227.702375) (xy 188.245622 -227.68363) (xy 188.260003 -227.669306)
			(xy 188.27878 -227.6616) (xy 188.28893 -227.661216) (xy 189.68847 -227.661216) (xy 189.698592 -227.66175)
			(xy 189.717308 -227.669464) (xy 189.731664 -227.683735) (xy 189.739489 -227.702405) (xy 189.740032 -227.712524)
			(xy 189.740032 -228.121464) (xy 192.337436 -228.121464) (xy 192.337436 -227.712524) (xy 192.337842 -227.702367)
			(xy 192.345636 -227.683608) (xy 192.360039 -227.669282) (xy 192.378839 -227.661588) (xy 192.388998 -227.661216)
			(xy 193.788538 -227.661216) (xy 193.798664 -227.661695) (xy 193.817382 -227.669431) (xy 193.831736 -227.683719)
			(xy 193.839558 -227.7024) (xy 193.8401 -227.712524) (xy 193.8401 -228.121464) (xy 195.781168 -228.121464)
			(xy 195.781168 -227.712524) (xy 195.78164 -227.702375) (xy 195.789422 -227.68363) (xy 195.803803 -227.669306)
			(xy 195.82258 -227.6616) (xy 195.83273 -227.661216) (xy 197.23227 -227.661216) (xy 197.242392 -227.66175)
			(xy 197.261108 -227.669464) (xy 197.275464 -227.683735) (xy 197.283289 -227.702405) (xy 197.283832 -227.712524)
			(xy 197.283832 -228.121464) (xy 199.881236 -228.121464) (xy 199.881236 -227.712524) (xy 199.881642 -227.702367)
			(xy 199.889436 -227.683608) (xy 199.903839 -227.669282) (xy 199.922639 -227.661588) (xy 199.932798 -227.661216)
			(xy 201.332338 -227.661216) (xy 201.342464 -227.661695) (xy 201.361182 -227.669431) (xy 201.375536 -227.683719)
			(xy 201.383358 -227.7024) (xy 201.3839 -227.712524) (xy 201.3839 -228.121464) (xy 203.324968 -228.121464)
			(xy 203.324968 -227.712524) (xy 203.32544 -227.702375) (xy 203.333222 -227.68363) (xy 203.347603 -227.669306)
			(xy 203.36638 -227.6616) (xy 203.37653 -227.661216) (xy 204.77607 -227.661216) (xy 204.786192 -227.66175)
			(xy 204.804908 -227.669464) (xy 204.819264 -227.683735) (xy 204.827089 -227.702405) (xy 204.827632 -227.712524)
			(xy 204.827632 -228.121464) (xy 207.425036 -228.121464) (xy 207.425036 -227.712524) (xy 207.425442 -227.702367)
			(xy 207.433236 -227.683608) (xy 207.447639 -227.669282) (xy 207.466439 -227.661588) (xy 207.476598 -227.661216)
			(xy 208.876138 -227.661216) (xy 208.886264 -227.661695) (xy 208.904982 -227.669431) (xy 208.919336 -227.683719)
			(xy 208.927158 -227.7024) (xy 208.9277 -227.712524) (xy 208.9277 -228.121464) (xy 210.868768 -228.121464)
			(xy 210.868768 -227.712524) (xy 210.86924 -227.702375) (xy 210.877022 -227.68363) (xy 210.891403 -227.669306)
			(xy 210.91018 -227.6616) (xy 210.92033 -227.661216) (xy 212.31987 -227.661216) (xy 212.329992 -227.66175)
			(xy 212.348708 -227.669464) (xy 212.363064 -227.683735) (xy 212.370889 -227.702405) (xy 212.371432 -227.712524)
			(xy 212.371432 -228.121464) (xy 214.968836 -228.121464) (xy 214.968836 -227.712524) (xy 214.969242 -227.702367)
			(xy 214.977036 -227.683608) (xy 214.991439 -227.669282) (xy 215.010239 -227.661588) (xy 215.020398 -227.661216)
			(xy 216.419938 -227.661216) (xy 216.430064 -227.661695) (xy 216.448782 -227.669431) (xy 216.463136 -227.683719)
			(xy 216.470958 -227.7024) (xy 216.4715 -227.712524) (xy 216.4715 -228.121464) (xy 255.329436 -228.121464)
			(xy 255.329436 -227.712524) (xy 255.329842 -227.702367) (xy 255.337636 -227.683608) (xy 255.352039 -227.669282)
			(xy 255.370839 -227.661588) (xy 255.380998 -227.661216) (xy 256.780538 -227.661216) (xy 256.790664 -227.661695)
			(xy 256.809382 -227.669431) (xy 256.823736 -227.683719) (xy 256.831558 -227.7024) (xy 256.8321 -227.712524)
			(xy 256.8321 -228.121464) (xy 259.429504 -228.121464) (xy 259.429504 -227.712524) (xy 259.429941 -227.702371)
			(xy 259.43773 -227.683618) (xy 259.452122 -227.669294) (xy 259.470911 -227.661594) (xy 259.481066 -227.661216)
			(xy 260.880606 -227.661216) (xy 260.89073 -227.661721) (xy 260.909447 -227.669446) (xy 260.923802 -227.683727)
			(xy 260.931625 -227.702403) (xy 260.932168 -227.712524) (xy 260.932168 -228.121464) (xy 262.873236 -228.121464)
			(xy 262.873236 -227.712524) (xy 262.873642 -227.702367) (xy 262.881436 -227.683608) (xy 262.895839 -227.669282)
			(xy 262.914639 -227.661588) (xy 262.924798 -227.661216) (xy 264.324338 -227.661216) (xy 264.334464 -227.661695)
			(xy 264.353182 -227.669431) (xy 264.367536 -227.683719) (xy 264.375358 -227.7024) (xy 264.3759 -227.712524)
			(xy 264.3759 -228.121464) (xy 266.973304 -228.121464) (xy 266.973304 -227.712524) (xy 266.973741 -227.702371)
			(xy 266.98153 -227.683618) (xy 266.995922 -227.669294) (xy 267.014711 -227.661594) (xy 267.024866 -227.661216)
			(xy 268.424406 -227.661216) (xy 268.43453 -227.661721) (xy 268.453247 -227.669446) (xy 268.467602 -227.683727)
			(xy 268.475425 -227.702403) (xy 268.475968 -227.712524) (xy 268.475968 -228.121464) (xy 270.417036 -228.121464)
			(xy 270.417036 -227.712524) (xy 270.417442 -227.702367) (xy 270.425236 -227.683608) (xy 270.439639 -227.669282)
			(xy 270.458439 -227.661588) (xy 270.468598 -227.661216) (xy 271.868138 -227.661216) (xy 271.878264 -227.661695)
			(xy 271.896982 -227.669431) (xy 271.911336 -227.683719) (xy 271.919158 -227.7024) (xy 271.9197 -227.712524)
			(xy 271.9197 -228.121464) (xy 274.517104 -228.121464) (xy 274.517104 -227.712524) (xy 274.517541 -227.702371)
			(xy 274.52533 -227.683618) (xy 274.539722 -227.669294) (xy 274.558511 -227.661594) (xy 274.568666 -227.661216)
			(xy 275.968206 -227.661216) (xy 275.97833 -227.661721) (xy 275.997047 -227.669446) (xy 276.011402 -227.683727)
			(xy 276.019225 -227.702403) (xy 276.019768 -227.712524) (xy 276.019768 -228.121464) (xy 277.960836 -228.121464)
			(xy 277.960836 -227.712524) (xy 277.961242 -227.702367) (xy 277.969036 -227.683608) (xy 277.983439 -227.669282)
			(xy 278.002239 -227.661588) (xy 278.012398 -227.661216) (xy 279.411938 -227.661216) (xy 279.422064 -227.661695)
			(xy 279.440782 -227.669431) (xy 279.455136 -227.683719) (xy 279.462958 -227.7024) (xy 279.4635 -227.712524)
			(xy 279.4635 -228.121464) (xy 282.060904 -228.121464) (xy 282.060904 -227.712524) (xy 282.061341 -227.702371)
			(xy 282.06913 -227.683618) (xy 282.083522 -227.669294) (xy 282.102311 -227.661594) (xy 282.112466 -227.661216)
			(xy 283.512006 -227.661216) (xy 283.52213 -227.661721) (xy 283.540847 -227.669446) (xy 283.555202 -227.683727)
			(xy 283.563025 -227.702403) (xy 283.563568 -227.712524) (xy 283.563568 -228.121464) (xy 285.504636 -228.121464)
			(xy 285.504636 -227.712524) (xy 285.505042 -227.702367) (xy 285.512836 -227.683608) (xy 285.527239 -227.669282)
			(xy 285.546039 -227.661588) (xy 285.556198 -227.661216) (xy 286.955738 -227.661216) (xy 286.965864 -227.661695)
			(xy 286.984582 -227.669431) (xy 286.998936 -227.683719) (xy 287.006758 -227.7024) (xy 287.0073 -227.712524)
			(xy 287.0073 -228.121464) (xy 289.604704 -228.121464) (xy 289.604704 -227.712524) (xy 289.605141 -227.702371)
			(xy 289.61293 -227.683618) (xy 289.627322 -227.669294) (xy 289.646111 -227.661594) (xy 289.656266 -227.661216)
			(xy 291.055806 -227.661216) (xy 291.06593 -227.661721) (xy 291.084647 -227.669446) (xy 291.099002 -227.683727)
			(xy 291.106825 -227.702403) (xy 291.107368 -227.712524) (xy 291.107368 -228.121464) (xy 293.048436 -228.121464)
			(xy 293.048436 -227.712524) (xy 293.048842 -227.702367) (xy 293.056636 -227.683608) (xy 293.071039 -227.669282)
			(xy 293.089839 -227.661588) (xy 293.099998 -227.661216) (xy 294.499538 -227.661216) (xy 294.509664 -227.661695)
			(xy 294.528382 -227.669431) (xy 294.542736 -227.683719) (xy 294.550558 -227.7024) (xy 294.5511 -227.712524)
			(xy 294.5511 -228.121464) (xy 297.148504 -228.121464) (xy 297.148504 -227.712524) (xy 297.148941 -227.702371)
			(xy 297.15673 -227.683618) (xy 297.171122 -227.669294) (xy 297.189911 -227.661594) (xy 297.200066 -227.661216)
			(xy 298.599606 -227.661216) (xy 298.60973 -227.661721) (xy 298.628447 -227.669446) (xy 298.642802 -227.683727)
			(xy 298.650625 -227.702403) (xy 298.651168 -227.712524) (xy 298.651168 -228.121464) (xy 300.592236 -228.121464)
			(xy 300.592236 -227.712524) (xy 300.592642 -227.702367) (xy 300.600436 -227.683608) (xy 300.614839 -227.669282)
			(xy 300.633639 -227.661588) (xy 300.643798 -227.661216) (xy 302.043338 -227.661216) (xy 302.053464 -227.661695)
			(xy 302.072182 -227.669431) (xy 302.086536 -227.683719) (xy 302.094358 -227.7024) (xy 302.0949 -227.712524)
			(xy 302.0949 -228.121464) (xy 304.692304 -228.121464) (xy 304.692304 -227.712524) (xy 304.692741 -227.702371)
			(xy 304.70053 -227.683618) (xy 304.714922 -227.669294) (xy 304.733711 -227.661594) (xy 304.743866 -227.661216)
			(xy 306.143406 -227.661216) (xy 306.15353 -227.661721) (xy 306.172247 -227.669446) (xy 306.186602 -227.683727)
			(xy 306.194425 -227.702403) (xy 306.194968 -227.712524) (xy 306.194968 -228.121464) (xy 308.136036 -228.121464)
			(xy 308.136036 -227.712524) (xy 308.136442 -227.702367) (xy 308.144236 -227.683608) (xy 308.158639 -227.669282)
			(xy 308.177439 -227.661588) (xy 308.187598 -227.661216) (xy 309.587138 -227.661216) (xy 309.597264 -227.661695)
			(xy 309.615982 -227.669431) (xy 309.630336 -227.683719) (xy 309.638158 -227.7024) (xy 309.6387 -227.712524)
			(xy 309.6387 -228.121464) (xy 312.236104 -228.121464) (xy 312.236104 -227.712524) (xy 312.236541 -227.702371)
			(xy 312.24433 -227.683618) (xy 312.258722 -227.669294) (xy 312.277511 -227.661594) (xy 312.287666 -227.661216)
			(xy 313.687206 -227.661216) (xy 313.69733 -227.661721) (xy 313.716047 -227.669446) (xy 313.730402 -227.683727)
			(xy 313.738225 -227.702403) (xy 313.738768 -227.712524) (xy 313.738768 -228.121464) (xy 406.002236 -228.121464)
			(xy 406.002236 -227.712524) (xy 406.002642 -227.702367) (xy 406.010436 -227.683608) (xy 406.024839 -227.669282)
			(xy 406.043639 -227.661588) (xy 406.053798 -227.661216) (xy 407.453338 -227.661216) (xy 407.463464 -227.661695)
			(xy 407.482182 -227.669431) (xy 407.496536 -227.683719) (xy 407.504358 -227.7024) (xy 407.5049 -227.712524)
			(xy 407.5049 -228.121464) (xy 410.102304 -228.121464) (xy 410.102304 -227.712524) (xy 410.102741 -227.702371)
			(xy 410.11053 -227.683618) (xy 410.124922 -227.669294) (xy 410.143711 -227.661594) (xy 410.153866 -227.661216)
			(xy 411.553406 -227.661216) (xy 411.56353 -227.661721) (xy 411.582247 -227.669446) (xy 411.596602 -227.683727)
			(xy 411.604425 -227.702403) (xy 411.604968 -227.712524) (xy 411.604968 -228.121464) (xy 413.546036 -228.121464)
			(xy 413.546036 -227.712524) (xy 413.546442 -227.702367) (xy 413.554236 -227.683608) (xy 413.568639 -227.669282)
			(xy 413.587439 -227.661588) (xy 413.597598 -227.661216) (xy 414.997138 -227.661216) (xy 415.007264 -227.661695)
			(xy 415.025982 -227.669431) (xy 415.040336 -227.683719) (xy 415.048158 -227.7024) (xy 415.0487 -227.712524)
			(xy 415.0487 -228.121464) (xy 417.646104 -228.121464) (xy 417.646104 -227.712524) (xy 417.646541 -227.702371)
			(xy 417.65433 -227.683618) (xy 417.668722 -227.669294) (xy 417.687511 -227.661594) (xy 417.697666 -227.661216)
			(xy 419.097206 -227.661216) (xy 419.10733 -227.661721) (xy 419.126047 -227.669446) (xy 419.140402 -227.683727)
			(xy 419.148225 -227.702403) (xy 419.148768 -227.712524) (xy 419.148768 -228.121464) (xy 421.089836 -228.121464)
			(xy 421.089836 -227.712524) (xy 421.090242 -227.702367) (xy 421.098036 -227.683608) (xy 421.112439 -227.669282)
			(xy 421.131239 -227.661588) (xy 421.141398 -227.661216) (xy 422.540938 -227.661216) (xy 422.551064 -227.661695)
			(xy 422.569782 -227.669431) (xy 422.584136 -227.683719) (xy 422.591958 -227.7024) (xy 422.5925 -227.712524)
			(xy 422.5925 -228.121464) (xy 425.189904 -228.121464) (xy 425.189904 -227.712524) (xy 425.190341 -227.702371)
			(xy 425.19813 -227.683618) (xy 425.212522 -227.669294) (xy 425.231311 -227.661594) (xy 425.241466 -227.661216)
			(xy 426.641006 -227.661216) (xy 426.65113 -227.661721) (xy 426.669847 -227.669446) (xy 426.684202 -227.683727)
			(xy 426.692025 -227.702403) (xy 426.692568 -227.712524) (xy 426.692568 -228.121464) (xy 428.633636 -228.121464)
			(xy 428.633636 -227.712524) (xy 428.634042 -227.702367) (xy 428.641836 -227.683608) (xy 428.656239 -227.669282)
			(xy 428.675039 -227.661588) (xy 428.685198 -227.661216) (xy 430.084738 -227.661216) (xy 430.094864 -227.661695)
			(xy 430.113582 -227.669431) (xy 430.127936 -227.683719) (xy 430.135758 -227.7024) (xy 430.1363 -227.712524)
			(xy 430.1363 -228.121464) (xy 432.733704 -228.121464) (xy 432.733704 -227.712524) (xy 432.734141 -227.702371)
			(xy 432.74193 -227.683618) (xy 432.756322 -227.669294) (xy 432.775111 -227.661594) (xy 432.785266 -227.661216)
			(xy 434.184806 -227.661216) (xy 434.19493 -227.661721) (xy 434.213647 -227.669446) (xy 434.228002 -227.683727)
			(xy 434.235825 -227.702403) (xy 434.236368 -227.712524) (xy 434.236368 -228.121464) (xy 436.177436 -228.121464)
			(xy 436.177436 -227.712524) (xy 436.177842 -227.702367) (xy 436.185636 -227.683608) (xy 436.200039 -227.669282)
			(xy 436.218839 -227.661588) (xy 436.228998 -227.661216) (xy 437.628538 -227.661216) (xy 437.638664 -227.661695)
			(xy 437.657382 -227.669431) (xy 437.671736 -227.683719) (xy 437.679558 -227.7024) (xy 437.6801 -227.712524)
			(xy 437.6801 -228.121464) (xy 440.277504 -228.121464) (xy 440.277504 -227.712524) (xy 440.277941 -227.702371)
			(xy 440.28573 -227.683618) (xy 440.300122 -227.669294) (xy 440.318911 -227.661594) (xy 440.329066 -227.661216)
			(xy 441.728606 -227.661216) (xy 441.73873 -227.661721) (xy 441.757447 -227.669446) (xy 441.771802 -227.683727)
			(xy 441.779625 -227.702403) (xy 441.780168 -227.712524) (xy 441.780168 -228.121464) (xy 443.721236 -228.121464)
			(xy 443.721236 -227.712524) (xy 443.721642 -227.702367) (xy 443.729436 -227.683608) (xy 443.743839 -227.669282)
			(xy 443.762639 -227.661588) (xy 443.772798 -227.661216) (xy 445.172338 -227.661216) (xy 445.182464 -227.661695)
			(xy 445.201182 -227.669431) (xy 445.215536 -227.683719) (xy 445.223358 -227.7024) (xy 445.2239 -227.712524)
			(xy 445.2239 -228.121464) (xy 447.821304 -228.121464) (xy 447.821304 -227.712524) (xy 447.821741 -227.702371)
			(xy 447.82953 -227.683618) (xy 447.843922 -227.669294) (xy 447.862711 -227.661594) (xy 447.872866 -227.661216)
			(xy 449.272406 -227.661216) (xy 449.28253 -227.661721) (xy 449.301247 -227.669446) (xy 449.315602 -227.683727)
			(xy 449.323425 -227.702403) (xy 449.323968 -227.712524) (xy 449.323968 -228.121464) (xy 451.265036 -228.121464)
			(xy 451.265036 -227.712524) (xy 451.265442 -227.702367) (xy 451.273236 -227.683608) (xy 451.287639 -227.669282)
			(xy 451.306439 -227.661588) (xy 451.316598 -227.661216) (xy 452.716138 -227.661216) (xy 452.726264 -227.661695)
			(xy 452.744982 -227.669431) (xy 452.759336 -227.683719) (xy 452.767158 -227.7024) (xy 452.7677 -227.712524)
			(xy 452.7677 -228.121464) (xy 455.365104 -228.121464) (xy 455.365104 -227.712524) (xy 455.365541 -227.702371)
			(xy 455.37333 -227.683618) (xy 455.387722 -227.669294) (xy 455.406511 -227.661594) (xy 455.416666 -227.661216)
			(xy 456.816206 -227.661216) (xy 456.82633 -227.661721) (xy 456.845047 -227.669446) (xy 456.859402 -227.683727)
			(xy 456.867225 -227.702403) (xy 456.867768 -227.712524) (xy 456.867768 -228.121464) (xy 458.808836 -228.121464)
			(xy 458.808836 -227.712524) (xy 458.809242 -227.702367) (xy 458.817036 -227.683608) (xy 458.831439 -227.669282)
			(xy 458.850239 -227.661588) (xy 458.860398 -227.661216) (xy 460.259938 -227.661216) (xy 460.270064 -227.661695)
			(xy 460.288782 -227.669431) (xy 460.303136 -227.683719) (xy 460.310958 -227.7024) (xy 460.3115 -227.712524)
			(xy 460.3115 -228.121464) (xy 462.908904 -228.121464) (xy 462.908904 -227.712524) (xy 462.909341 -227.702371)
			(xy 462.91713 -227.683618) (xy 462.931522 -227.669294) (xy 462.950311 -227.661594) (xy 462.960466 -227.661216)
			(xy 464.360006 -227.661216) (xy 464.37013 -227.661721) (xy 464.388847 -227.669446) (xy 464.403202 -227.683727)
			(xy 464.411025 -227.702403) (xy 464.411568 -227.712524) (xy 464.411568 -228.121464) (xy 464.411148 -228.13162)
			(xy 464.403358 -228.150377) (xy 464.38896 -228.164703) (xy 464.370164 -228.172398) (xy 464.360006 -228.172772)
			(xy 462.960466 -228.172772) (xy 462.950339 -228.172302) (xy 462.931619 -228.164565) (xy 462.917264 -228.150274)
			(xy 462.909444 -228.131589) (xy 462.908904 -228.121464) (xy 460.3115 -228.121464) (xy 460.311049 -228.131616)
			(xy 460.303265 -228.150367) (xy 460.288877 -228.164692) (xy 460.270091 -228.172393) (xy 460.259938 -228.172772)
			(xy 458.860398 -228.172772) (xy 458.850273 -228.172275) (xy 458.831554 -228.164549) (xy 458.817198 -228.150266)
			(xy 458.809377 -228.131587) (xy 458.808836 -228.121464) (xy 456.867768 -228.121464) (xy 456.867348 -228.13162)
			(xy 456.859558 -228.150377) (xy 456.84516 -228.164703) (xy 456.826364 -228.172398) (xy 456.816206 -228.172772)
			(xy 455.416666 -228.172772) (xy 455.406539 -228.172302) (xy 455.387819 -228.164565) (xy 455.373464 -228.150274)
			(xy 455.365644 -228.131589) (xy 455.365104 -228.121464) (xy 452.7677 -228.121464) (xy 452.767249 -228.131616)
			(xy 452.759465 -228.150367) (xy 452.745077 -228.164692) (xy 452.726291 -228.172393) (xy 452.716138 -228.172772)
			(xy 451.316598 -228.172772) (xy 451.306473 -228.172275) (xy 451.287754 -228.164549) (xy 451.273398 -228.150266)
			(xy 451.265577 -228.131587) (xy 451.265036 -228.121464) (xy 449.323968 -228.121464) (xy 449.323548 -228.13162)
			(xy 449.315758 -228.150377) (xy 449.30136 -228.164703) (xy 449.282564 -228.172398) (xy 449.272406 -228.172772)
			(xy 447.872866 -228.172772) (xy 447.862739 -228.172302) (xy 447.844019 -228.164565) (xy 447.829664 -228.150274)
			(xy 447.821844 -228.131589) (xy 447.821304 -228.121464) (xy 445.2239 -228.121464) (xy 445.223449 -228.131616)
			(xy 445.215665 -228.150367) (xy 445.201277 -228.164692) (xy 445.182491 -228.172393) (xy 445.172338 -228.172772)
			(xy 443.772798 -228.172772) (xy 443.762673 -228.172275) (xy 443.743954 -228.164549) (xy 443.729598 -228.150266)
			(xy 443.721777 -228.131587) (xy 443.721236 -228.121464) (xy 441.780168 -228.121464) (xy 441.779748 -228.13162)
			(xy 441.771958 -228.150377) (xy 441.75756 -228.164703) (xy 441.738764 -228.172398) (xy 441.728606 -228.172772)
			(xy 440.329066 -228.172772) (xy 440.318939 -228.172302) (xy 440.300219 -228.164565) (xy 440.285864 -228.150274)
			(xy 440.278044 -228.131589) (xy 440.277504 -228.121464) (xy 437.6801 -228.121464) (xy 437.679649 -228.131616)
			(xy 437.671865 -228.150367) (xy 437.657477 -228.164692) (xy 437.638691 -228.172393) (xy 437.628538 -228.172772)
			(xy 436.228998 -228.172772) (xy 436.218873 -228.172275) (xy 436.200154 -228.164549) (xy 436.185798 -228.150266)
			(xy 436.177977 -228.131587) (xy 436.177436 -228.121464) (xy 434.236368 -228.121464) (xy 434.235948 -228.13162)
			(xy 434.228158 -228.150377) (xy 434.21376 -228.164703) (xy 434.194964 -228.172398) (xy 434.184806 -228.172772)
			(xy 432.785266 -228.172772) (xy 432.775139 -228.172302) (xy 432.756419 -228.164565) (xy 432.742064 -228.150274)
			(xy 432.734244 -228.131589) (xy 432.733704 -228.121464) (xy 430.1363 -228.121464) (xy 430.135849 -228.131616)
			(xy 430.128065 -228.150367) (xy 430.113677 -228.164692) (xy 430.094891 -228.172393) (xy 430.084738 -228.172772)
			(xy 428.685198 -228.172772) (xy 428.675073 -228.172275) (xy 428.656354 -228.164549) (xy 428.641998 -228.150266)
			(xy 428.634177 -228.131587) (xy 428.633636 -228.121464) (xy 426.692568 -228.121464) (xy 426.692148 -228.13162)
			(xy 426.684358 -228.150377) (xy 426.66996 -228.164703) (xy 426.651164 -228.172398) (xy 426.641006 -228.172772)
			(xy 425.241466 -228.172772) (xy 425.231339 -228.172302) (xy 425.212619 -228.164565) (xy 425.198264 -228.150274)
			(xy 425.190444 -228.131589) (xy 425.189904 -228.121464) (xy 422.5925 -228.121464) (xy 422.592049 -228.131616)
			(xy 422.584265 -228.150367) (xy 422.569877 -228.164692) (xy 422.551091 -228.172393) (xy 422.540938 -228.172772)
			(xy 421.141398 -228.172772) (xy 421.131273 -228.172275) (xy 421.112554 -228.164549) (xy 421.098198 -228.150266)
			(xy 421.090377 -228.131587) (xy 421.089836 -228.121464) (xy 419.148768 -228.121464) (xy 419.148348 -228.13162)
			(xy 419.140558 -228.150377) (xy 419.12616 -228.164703) (xy 419.107364 -228.172398) (xy 419.097206 -228.172772)
			(xy 417.697666 -228.172772) (xy 417.687539 -228.172302) (xy 417.668819 -228.164565) (xy 417.654464 -228.150274)
			(xy 417.646644 -228.131589) (xy 417.646104 -228.121464) (xy 415.0487 -228.121464) (xy 415.048249 -228.131616)
			(xy 415.040465 -228.150367) (xy 415.026077 -228.164692) (xy 415.007291 -228.172393) (xy 414.997138 -228.172772)
			(xy 413.597598 -228.172772) (xy 413.587473 -228.172275) (xy 413.568754 -228.164549) (xy 413.554398 -228.150266)
			(xy 413.546577 -228.131587) (xy 413.546036 -228.121464) (xy 411.604968 -228.121464) (xy 411.604548 -228.13162)
			(xy 411.596758 -228.150377) (xy 411.58236 -228.164703) (xy 411.563564 -228.172398) (xy 411.553406 -228.172772)
			(xy 410.153866 -228.172772) (xy 410.143739 -228.172302) (xy 410.125019 -228.164565) (xy 410.110664 -228.150274)
			(xy 410.102844 -228.131589) (xy 410.102304 -228.121464) (xy 407.5049 -228.121464) (xy 407.504449 -228.131616)
			(xy 407.496665 -228.150367) (xy 407.482277 -228.164692) (xy 407.463491 -228.172393) (xy 407.453338 -228.172772)
			(xy 406.053798 -228.172772) (xy 406.043673 -228.172275) (xy 406.024954 -228.164549) (xy 406.010598 -228.150266)
			(xy 406.002777 -228.131587) (xy 406.002236 -228.121464) (xy 313.738768 -228.121464) (xy 313.738348 -228.13162)
			(xy 313.730558 -228.150377) (xy 313.71616 -228.164703) (xy 313.697364 -228.172398) (xy 313.687206 -228.172772)
			(xy 312.287666 -228.172772) (xy 312.277539 -228.172302) (xy 312.258819 -228.164565) (xy 312.244464 -228.150274)
			(xy 312.236644 -228.131589) (xy 312.236104 -228.121464) (xy 309.6387 -228.121464) (xy 309.638249 -228.131616)
			(xy 309.630465 -228.150367) (xy 309.616077 -228.164692) (xy 309.597291 -228.172393) (xy 309.587138 -228.172772)
			(xy 308.187598 -228.172772) (xy 308.177473 -228.172275) (xy 308.158754 -228.164549) (xy 308.144398 -228.150266)
			(xy 308.136577 -228.131587) (xy 308.136036 -228.121464) (xy 306.194968 -228.121464) (xy 306.194548 -228.13162)
			(xy 306.186758 -228.150377) (xy 306.17236 -228.164703) (xy 306.153564 -228.172398) (xy 306.143406 -228.172772)
			(xy 304.743866 -228.172772) (xy 304.733739 -228.172302) (xy 304.715019 -228.164565) (xy 304.700664 -228.150274)
			(xy 304.692844 -228.131589) (xy 304.692304 -228.121464) (xy 302.0949 -228.121464) (xy 302.094449 -228.131616)
			(xy 302.086665 -228.150367) (xy 302.072277 -228.164692) (xy 302.053491 -228.172393) (xy 302.043338 -228.172772)
			(xy 300.643798 -228.172772) (xy 300.633673 -228.172275) (xy 300.614954 -228.164549) (xy 300.600598 -228.150266)
			(xy 300.592777 -228.131587) (xy 300.592236 -228.121464) (xy 298.651168 -228.121464) (xy 298.650748 -228.13162)
			(xy 298.642958 -228.150377) (xy 298.62856 -228.164703) (xy 298.609764 -228.172398) (xy 298.599606 -228.172772)
			(xy 297.200066 -228.172772) (xy 297.189939 -228.172302) (xy 297.171219 -228.164565) (xy 297.156864 -228.150274)
			(xy 297.149044 -228.131589) (xy 297.148504 -228.121464) (xy 294.5511 -228.121464) (xy 294.550649 -228.131616)
			(xy 294.542865 -228.150367) (xy 294.528477 -228.164692) (xy 294.509691 -228.172393) (xy 294.499538 -228.172772)
			(xy 293.099998 -228.172772) (xy 293.089873 -228.172275) (xy 293.071154 -228.164549) (xy 293.056798 -228.150266)
			(xy 293.048977 -228.131587) (xy 293.048436 -228.121464) (xy 291.107368 -228.121464) (xy 291.106948 -228.13162)
			(xy 291.099158 -228.150377) (xy 291.08476 -228.164703) (xy 291.065964 -228.172398) (xy 291.055806 -228.172772)
			(xy 289.656266 -228.172772) (xy 289.646139 -228.172302) (xy 289.627419 -228.164565) (xy 289.613064 -228.150274)
			(xy 289.605244 -228.131589) (xy 289.604704 -228.121464) (xy 287.0073 -228.121464) (xy 287.006849 -228.131616)
			(xy 286.999065 -228.150367) (xy 286.984677 -228.164692) (xy 286.965891 -228.172393) (xy 286.955738 -228.172772)
			(xy 285.556198 -228.172772) (xy 285.546073 -228.172275) (xy 285.527354 -228.164549) (xy 285.512998 -228.150266)
			(xy 285.505177 -228.131587) (xy 285.504636 -228.121464) (xy 283.563568 -228.121464) (xy 283.563148 -228.13162)
			(xy 283.555358 -228.150377) (xy 283.54096 -228.164703) (xy 283.522164 -228.172398) (xy 283.512006 -228.172772)
			(xy 282.112466 -228.172772) (xy 282.102339 -228.172302) (xy 282.083619 -228.164565) (xy 282.069264 -228.150274)
			(xy 282.061444 -228.131589) (xy 282.060904 -228.121464) (xy 279.4635 -228.121464) (xy 279.463049 -228.131616)
			(xy 279.455265 -228.150367) (xy 279.440877 -228.164692) (xy 279.422091 -228.172393) (xy 279.411938 -228.172772)
			(xy 278.012398 -228.172772) (xy 278.002273 -228.172275) (xy 277.983554 -228.164549) (xy 277.969198 -228.150266)
			(xy 277.961377 -228.131587) (xy 277.960836 -228.121464) (xy 276.019768 -228.121464) (xy 276.019348 -228.13162)
			(xy 276.011558 -228.150377) (xy 275.99716 -228.164703) (xy 275.978364 -228.172398) (xy 275.968206 -228.172772)
			(xy 274.568666 -228.172772) (xy 274.558539 -228.172302) (xy 274.539819 -228.164565) (xy 274.525464 -228.150274)
			(xy 274.517644 -228.131589) (xy 274.517104 -228.121464) (xy 271.9197 -228.121464) (xy 271.919249 -228.131616)
			(xy 271.911465 -228.150367) (xy 271.897077 -228.164692) (xy 271.878291 -228.172393) (xy 271.868138 -228.172772)
			(xy 270.468598 -228.172772) (xy 270.458473 -228.172275) (xy 270.439754 -228.164549) (xy 270.425398 -228.150266)
			(xy 270.417577 -228.131587) (xy 270.417036 -228.121464) (xy 268.475968 -228.121464) (xy 268.475548 -228.13162)
			(xy 268.467758 -228.150377) (xy 268.45336 -228.164703) (xy 268.434564 -228.172398) (xy 268.424406 -228.172772)
			(xy 267.024866 -228.172772) (xy 267.014739 -228.172302) (xy 266.996019 -228.164565) (xy 266.981664 -228.150274)
			(xy 266.973844 -228.131589) (xy 266.973304 -228.121464) (xy 264.3759 -228.121464) (xy 264.375449 -228.131616)
			(xy 264.367665 -228.150367) (xy 264.353277 -228.164692) (xy 264.334491 -228.172393) (xy 264.324338 -228.172772)
			(xy 262.924798 -228.172772) (xy 262.914673 -228.172275) (xy 262.895954 -228.164549) (xy 262.881598 -228.150266)
			(xy 262.873777 -228.131587) (xy 262.873236 -228.121464) (xy 260.932168 -228.121464) (xy 260.931748 -228.13162)
			(xy 260.923958 -228.150377) (xy 260.90956 -228.164703) (xy 260.890764 -228.172398) (xy 260.880606 -228.172772)
			(xy 259.481066 -228.172772) (xy 259.470939 -228.172302) (xy 259.452219 -228.164565) (xy 259.437864 -228.150274)
			(xy 259.430044 -228.131589) (xy 259.429504 -228.121464) (xy 256.8321 -228.121464) (xy 256.831649 -228.131616)
			(xy 256.823865 -228.150367) (xy 256.809477 -228.164692) (xy 256.790691 -228.172393) (xy 256.780538 -228.172772)
			(xy 255.380998 -228.172772) (xy 255.370873 -228.172275) (xy 255.352154 -228.164549) (xy 255.337798 -228.150266)
			(xy 255.329977 -228.131587) (xy 255.329436 -228.121464) (xy 216.4715 -228.121464) (xy 216.471049 -228.131616)
			(xy 216.463265 -228.150367) (xy 216.448877 -228.164692) (xy 216.430091 -228.172393) (xy 216.419938 -228.172772)
			(xy 215.020398 -228.172772) (xy 215.010273 -228.172275) (xy 214.991554 -228.164549) (xy 214.977198 -228.150266)
			(xy 214.969377 -228.131587) (xy 214.968836 -228.121464) (xy 212.371432 -228.121464) (xy 212.370949 -228.131612)
			(xy 212.363172 -228.150357) (xy 212.348794 -228.164681) (xy 212.330019 -228.172387) (xy 212.31987 -228.172772)
			(xy 210.92033 -228.172772) (xy 210.910207 -228.172249) (xy 210.891488 -228.164534) (xy 210.877131 -228.150258)
			(xy 210.869309 -228.131584) (xy 210.868768 -228.121464) (xy 208.9277 -228.121464) (xy 208.927249 -228.131616)
			(xy 208.919465 -228.150367) (xy 208.905077 -228.164692) (xy 208.886291 -228.172393) (xy 208.876138 -228.172772)
			(xy 207.476598 -228.172772) (xy 207.466473 -228.172275) (xy 207.447754 -228.164549) (xy 207.433398 -228.150266)
			(xy 207.425577 -228.131587) (xy 207.425036 -228.121464) (xy 204.827632 -228.121464) (xy 204.827149 -228.131612)
			(xy 204.819372 -228.150357) (xy 204.804994 -228.164681) (xy 204.786219 -228.172387) (xy 204.77607 -228.172772)
			(xy 203.37653 -228.172772) (xy 203.366407 -228.172249) (xy 203.347688 -228.164534) (xy 203.333331 -228.150258)
			(xy 203.325509 -228.131584) (xy 203.324968 -228.121464) (xy 201.3839 -228.121464) (xy 201.383449 -228.131616)
			(xy 201.375665 -228.150367) (xy 201.361277 -228.164692) (xy 201.342491 -228.172393) (xy 201.332338 -228.172772)
			(xy 199.932798 -228.172772) (xy 199.922673 -228.172275) (xy 199.903954 -228.164549) (xy 199.889598 -228.150266)
			(xy 199.881777 -228.131587) (xy 199.881236 -228.121464) (xy 197.283832 -228.121464) (xy 197.283349 -228.131612)
			(xy 197.275572 -228.150357) (xy 197.261194 -228.164681) (xy 197.242419 -228.172387) (xy 197.23227 -228.172772)
			(xy 195.83273 -228.172772) (xy 195.822607 -228.172249) (xy 195.803888 -228.164534) (xy 195.789531 -228.150258)
			(xy 195.781709 -228.131584) (xy 195.781168 -228.121464) (xy 193.8401 -228.121464) (xy 193.839649 -228.131616)
			(xy 193.831865 -228.150367) (xy 193.817477 -228.164692) (xy 193.798691 -228.172393) (xy 193.788538 -228.172772)
			(xy 192.388998 -228.172772) (xy 192.378873 -228.172275) (xy 192.360154 -228.164549) (xy 192.345798 -228.150266)
			(xy 192.337977 -228.131587) (xy 192.337436 -228.121464) (xy 189.740032 -228.121464) (xy 189.739549 -228.131612)
			(xy 189.731772 -228.150357) (xy 189.717394 -228.164681) (xy 189.698619 -228.172387) (xy 189.68847 -228.172772)
			(xy 188.28893 -228.172772) (xy 188.278807 -228.172249) (xy 188.260088 -228.164534) (xy 188.245731 -228.150258)
			(xy 188.237909 -228.131584) (xy 188.237368 -228.121464) (xy 186.2963 -228.121464) (xy 186.295849 -228.131616)
			(xy 186.288065 -228.150367) (xy 186.273677 -228.164692) (xy 186.254891 -228.172393) (xy 186.244738 -228.172772)
			(xy 184.845198 -228.172772) (xy 184.835073 -228.172275) (xy 184.816354 -228.164549) (xy 184.801998 -228.150266)
			(xy 184.794177 -228.131587) (xy 184.793636 -228.121464) (xy 182.196232 -228.121464) (xy 182.195749 -228.131612)
			(xy 182.187972 -228.150357) (xy 182.173594 -228.164681) (xy 182.154819 -228.172387) (xy 182.14467 -228.172772)
			(xy 180.74513 -228.172772) (xy 180.735007 -228.172249) (xy 180.716288 -228.164534) (xy 180.701931 -228.150258)
			(xy 180.694109 -228.131584) (xy 180.693568 -228.121464) (xy 178.7525 -228.121464) (xy 178.752049 -228.131616)
			(xy 178.744265 -228.150367) (xy 178.729877 -228.164692) (xy 178.711091 -228.172393) (xy 178.700938 -228.172772)
			(xy 177.301398 -228.172772) (xy 177.291273 -228.172275) (xy 177.272554 -228.164549) (xy 177.258198 -228.150266)
			(xy 177.250377 -228.131587) (xy 177.249836 -228.121464) (xy 174.652432 -228.121464) (xy 174.651949 -228.131612)
			(xy 174.644172 -228.150357) (xy 174.629794 -228.164681) (xy 174.611019 -228.172387) (xy 174.60087 -228.172772)
			(xy 173.20133 -228.172772) (xy 173.191207 -228.172249) (xy 173.172488 -228.164534) (xy 173.158131 -228.150258)
			(xy 173.150309 -228.131584) (xy 173.149768 -228.121464) (xy 171.2087 -228.121464) (xy 171.208249 -228.131616)
			(xy 171.200465 -228.150367) (xy 171.186077 -228.164692) (xy 171.167291 -228.172393) (xy 171.157138 -228.172772)
			(xy 169.757598 -228.172772) (xy 169.747473 -228.172275) (xy 169.728754 -228.164549) (xy 169.714398 -228.150266)
			(xy 169.706577 -228.131587) (xy 169.706036 -228.121464) (xy 167.108632 -228.121464) (xy 167.108149 -228.131612)
			(xy 167.100372 -228.150357) (xy 167.085994 -228.164681) (xy 167.067219 -228.172387) (xy 167.05707 -228.172772)
			(xy 165.65753 -228.172772) (xy 165.647407 -228.172249) (xy 165.628688 -228.164534) (xy 165.614331 -228.150258)
			(xy 165.606509 -228.131584) (xy 165.605968 -228.121464) (xy 163.6649 -228.121464) (xy 163.664449 -228.131616)
			(xy 163.656665 -228.150367) (xy 163.642277 -228.164692) (xy 163.623491 -228.172393) (xy 163.613338 -228.172772)
			(xy 162.213798 -228.172772) (xy 162.203673 -228.172275) (xy 162.184954 -228.164549) (xy 162.170598 -228.150266)
			(xy 162.162777 -228.131587) (xy 162.162236 -228.121464) (xy 159.564832 -228.121464) (xy 159.564349 -228.131612)
			(xy 159.556572 -228.150357) (xy 159.542194 -228.164681) (xy 159.523419 -228.172387) (xy 159.51327 -228.172772)
			(xy 158.11373 -228.172772) (xy 158.103607 -228.172249) (xy 158.084888 -228.164534) (xy 158.070531 -228.150258)
			(xy 158.062709 -228.131584) (xy 158.062168 -228.121464) (xy 65.7987 -228.121464) (xy 65.798249 -228.131616)
			(xy 65.790465 -228.150367) (xy 65.776077 -228.164692) (xy 65.757291 -228.172393) (xy 65.747138 -228.172772)
			(xy 64.347598 -228.172772) (xy 64.337473 -228.172275) (xy 64.318754 -228.164549) (xy 64.304398 -228.150266)
			(xy 64.296577 -228.131587) (xy 64.296036 -228.121464) (xy 61.698632 -228.121464) (xy 61.698149 -228.131612)
			(xy 61.690372 -228.150357) (xy 61.675994 -228.164681) (xy 61.657219 -228.172387) (xy 61.64707 -228.172772)
			(xy 60.24753 -228.172772) (xy 60.237407 -228.172249) (xy 60.218688 -228.164534) (xy 60.204331 -228.150258)
			(xy 60.196509 -228.131584) (xy 60.195968 -228.121464) (xy 58.2549 -228.121464) (xy 58.254449 -228.131616)
			(xy 58.246665 -228.150367) (xy 58.232277 -228.164692) (xy 58.213491 -228.172393) (xy 58.203338 -228.172772)
			(xy 56.803798 -228.172772) (xy 56.793673 -228.172275) (xy 56.774954 -228.164549) (xy 56.760598 -228.150266)
			(xy 56.752777 -228.131587) (xy 56.752236 -228.121464) (xy 54.154832 -228.121464) (xy 54.154349 -228.131612)
			(xy 54.146572 -228.150357) (xy 54.132194 -228.164681) (xy 54.113419 -228.172387) (xy 54.10327 -228.172772)
			(xy 52.70373 -228.172772) (xy 52.693607 -228.172249) (xy 52.674888 -228.164534) (xy 52.660531 -228.150258)
			(xy 52.652709 -228.131584) (xy 52.652168 -228.121464) (xy 50.7111 -228.121464) (xy 50.710649 -228.131616)
			(xy 50.702865 -228.150367) (xy 50.688477 -228.164692) (xy 50.669691 -228.172393) (xy 50.659538 -228.172772)
			(xy 49.259998 -228.172772) (xy 49.249873 -228.172275) (xy 49.231154 -228.164549) (xy 49.216798 -228.150266)
			(xy 49.208977 -228.131587) (xy 49.208436 -228.121464) (xy 46.611032 -228.121464) (xy 46.610549 -228.131612)
			(xy 46.602772 -228.150357) (xy 46.588394 -228.164681) (xy 46.569619 -228.172387) (xy 46.55947 -228.172772)
			(xy 45.15993 -228.172772) (xy 45.149807 -228.172249) (xy 45.131088 -228.164534) (xy 45.116731 -228.150258)
			(xy 45.108909 -228.131584) (xy 45.108368 -228.121464) (xy 43.1673 -228.121464) (xy 43.166849 -228.131616)
			(xy 43.159065 -228.150367) (xy 43.144677 -228.164692) (xy 43.125891 -228.172393) (xy 43.115738 -228.172772)
			(xy 41.716198 -228.172772) (xy 41.706073 -228.172275) (xy 41.687354 -228.164549) (xy 41.672998 -228.150266)
			(xy 41.665177 -228.131587) (xy 41.664636 -228.121464) (xy 39.067232 -228.121464) (xy 39.066749 -228.131612)
			(xy 39.058972 -228.150357) (xy 39.044594 -228.164681) (xy 39.025819 -228.172387) (xy 39.01567 -228.172772)
			(xy 37.61613 -228.172772) (xy 37.606007 -228.172249) (xy 37.587288 -228.164534) (xy 37.572931 -228.150258)
			(xy 37.565109 -228.131584) (xy 37.564568 -228.121464) (xy 35.6235 -228.121464) (xy 35.623049 -228.131616)
			(xy 35.615265 -228.150367) (xy 35.600877 -228.164692) (xy 35.582091 -228.172393) (xy 35.571938 -228.172772)
			(xy 34.172398 -228.172772) (xy 34.162273 -228.172275) (xy 34.143554 -228.164549) (xy 34.129198 -228.150266)
			(xy 34.121377 -228.131587) (xy 34.120836 -228.121464) (xy 31.523432 -228.121464) (xy 31.522949 -228.131612)
			(xy 31.515172 -228.150357) (xy 31.500794 -228.164681) (xy 31.482019 -228.172387) (xy 31.47187 -228.172772)
			(xy 30.07233 -228.172772) (xy 30.062207 -228.172249) (xy 30.043488 -228.164534) (xy 30.029131 -228.150258)
			(xy 30.021309 -228.131584) (xy 30.020768 -228.121464) (xy 28.0797 -228.121464) (xy 28.079249 -228.131616)
			(xy 28.071465 -228.150367) (xy 28.057077 -228.164692) (xy 28.038291 -228.172393) (xy 28.028138 -228.172772)
			(xy 26.628598 -228.172772) (xy 26.618473 -228.172275) (xy 26.599754 -228.164549) (xy 26.585398 -228.150266)
			(xy 26.577577 -228.131587) (xy 26.577036 -228.121464) (xy 23.979632 -228.121464) (xy 23.979149 -228.131612)
			(xy 23.971372 -228.150357) (xy 23.956994 -228.164681) (xy 23.938219 -228.172387) (xy 23.92807 -228.172772)
			(xy 22.52853 -228.172772) (xy 22.518407 -228.172249) (xy 22.499688 -228.164534) (xy 22.485331 -228.150258)
			(xy 22.477509 -228.131584) (xy 22.476968 -228.121464) (xy 20.5359 -228.121464) (xy 20.535449 -228.131616)
			(xy 20.527665 -228.150367) (xy 20.513277 -228.164692) (xy 20.494491 -228.172393) (xy 20.484338 -228.172772)
			(xy 19.084798 -228.172772) (xy 19.074673 -228.172275) (xy 19.055954 -228.164549) (xy 19.041598 -228.150266)
			(xy 19.033777 -228.131587) (xy 19.033236 -228.121464) (xy 16.435832 -228.121464) (xy 16.435349 -228.131612)
			(xy 16.427572 -228.150357) (xy 16.413194 -228.164681) (xy 16.394419 -228.172387) (xy 16.38427 -228.172772)
			(xy 14.98473 -228.172772) (xy 14.974607 -228.172249) (xy 14.955888 -228.164534) (xy 14.941531 -228.150258)
			(xy 14.933709 -228.131584) (xy 14.933168 -228.121464) (xy 12.9921 -228.121464) (xy 12.991649 -228.131616)
			(xy 12.983865 -228.150367) (xy 12.969477 -228.164692) (xy 12.950691 -228.172393) (xy 12.940538 -228.172772)
			(xy 11.540998 -228.172772) (xy 11.530873 -228.172275) (xy 11.512154 -228.164549) (xy 11.497798 -228.150266)
			(xy 11.489977 -228.131587) (xy 11.489436 -228.121464) (xy 8.892032 -228.121464) (xy 8.891549 -228.131612)
			(xy 8.883772 -228.150357) (xy 8.869394 -228.164681) (xy 8.850619 -228.172387) (xy 8.84047 -228.172772)
			(xy 7.44093 -228.172772) (xy 7.430807 -228.172249) (xy 7.412088 -228.164534) (xy 7.397731 -228.150258)
			(xy 7.389909 -228.131584) (xy 7.389368 -228.121464) (xy 2.509012 -228.121464) (xy 2.509012 -228.971348)
			(xy 7.389368 -228.971348) (xy 7.389368 -228.562408) (xy 7.389828 -228.552258) (xy 7.397614 -228.533512)
			(xy 7.411999 -228.51919) (xy 7.430779 -228.511484) (xy 7.44093 -228.5111) (xy 8.84047 -228.5111)
			(xy 8.85059 -228.51165) (xy 8.869303 -228.51936) (xy 8.883659 -228.533627) (xy 8.891486 -228.552291)
			(xy 8.892032 -228.562408) (xy 8.892032 -228.971348) (xy 14.933168 -228.971348) (xy 14.933168 -228.562408)
			(xy 14.933628 -228.552258) (xy 14.941414 -228.533512) (xy 14.955799 -228.51919) (xy 14.974579 -228.511484)
			(xy 14.98473 -228.5111) (xy 16.38427 -228.5111) (xy 16.39439 -228.51165) (xy 16.413103 -228.51936)
			(xy 16.427459 -228.533627) (xy 16.435286 -228.552291) (xy 16.435832 -228.562408) (xy 16.435832 -228.971348)
			(xy 22.476968 -228.971348) (xy 22.476968 -228.562408) (xy 22.477428 -228.552258) (xy 22.485214 -228.533512)
			(xy 22.499599 -228.51919) (xy 22.518379 -228.511484) (xy 22.52853 -228.5111) (xy 23.92807 -228.5111)
			(xy 23.93819 -228.51165) (xy 23.956903 -228.51936) (xy 23.971259 -228.533627) (xy 23.979086 -228.552291)
			(xy 23.979632 -228.562408) (xy 23.979632 -228.971348) (xy 30.020768 -228.971348) (xy 30.020768 -228.562408)
			(xy 30.021228 -228.552258) (xy 30.029014 -228.533512) (xy 30.043399 -228.51919) (xy 30.062179 -228.511484)
			(xy 30.07233 -228.5111) (xy 31.47187 -228.5111) (xy 31.48199 -228.51165) (xy 31.500703 -228.51936)
			(xy 31.515059 -228.533627) (xy 31.522886 -228.552291) (xy 31.523432 -228.562408) (xy 31.523432 -228.971348)
			(xy 37.564568 -228.971348) (xy 37.564568 -228.562408) (xy 37.565028 -228.552258) (xy 37.572814 -228.533512)
			(xy 37.587199 -228.51919) (xy 37.605979 -228.511484) (xy 37.61613 -228.5111) (xy 39.01567 -228.5111)
			(xy 39.02579 -228.51165) (xy 39.044503 -228.51936) (xy 39.058859 -228.533627) (xy 39.066686 -228.552291)
			(xy 39.067232 -228.562408) (xy 39.067232 -228.971348) (xy 45.108368 -228.971348) (xy 45.108368 -228.562408)
			(xy 45.108828 -228.552258) (xy 45.116614 -228.533512) (xy 45.130999 -228.51919) (xy 45.149779 -228.511484)
			(xy 45.15993 -228.5111) (xy 46.55947 -228.5111) (xy 46.56959 -228.51165) (xy 46.588303 -228.51936)
			(xy 46.602659 -228.533627) (xy 46.610486 -228.552291) (xy 46.611032 -228.562408) (xy 46.611032 -228.971348)
			(xy 52.652168 -228.971348) (xy 52.652168 -228.562408) (xy 52.652628 -228.552258) (xy 52.660414 -228.533512)
			(xy 52.674799 -228.51919) (xy 52.693579 -228.511484) (xy 52.70373 -228.5111) (xy 54.10327 -228.5111)
			(xy 54.11339 -228.51165) (xy 54.132103 -228.51936) (xy 54.146459 -228.533627) (xy 54.154286 -228.552291)
			(xy 54.154832 -228.562408) (xy 54.154832 -228.971348) (xy 60.195968 -228.971348) (xy 60.195968 -228.562408)
			(xy 60.196428 -228.552258) (xy 60.204214 -228.533512) (xy 60.218599 -228.51919) (xy 60.237379 -228.511484)
			(xy 60.24753 -228.5111) (xy 61.64707 -228.5111) (xy 61.65719 -228.51165) (xy 61.675903 -228.51936)
			(xy 61.690259 -228.533627) (xy 61.698086 -228.552291) (xy 61.698632 -228.562408) (xy 61.698632 -228.971348)
			(xy 158.062168 -228.971348) (xy 158.062168 -228.562408) (xy 158.062628 -228.552258) (xy 158.070414 -228.533512)
			(xy 158.084799 -228.51919) (xy 158.103579 -228.511484) (xy 158.11373 -228.5111) (xy 159.51327 -228.5111)
			(xy 159.52339 -228.51165) (xy 159.542103 -228.51936) (xy 159.556459 -228.533627) (xy 159.564286 -228.552291)
			(xy 159.564832 -228.562408) (xy 159.564832 -228.971348) (xy 165.605968 -228.971348) (xy 165.605968 -228.562408)
			(xy 165.606428 -228.552258) (xy 165.614214 -228.533512) (xy 165.628599 -228.51919) (xy 165.647379 -228.511484)
			(xy 165.65753 -228.5111) (xy 167.05707 -228.5111) (xy 167.06719 -228.51165) (xy 167.085903 -228.51936)
			(xy 167.100259 -228.533627) (xy 167.108086 -228.552291) (xy 167.108632 -228.562408) (xy 167.108632 -228.971348)
			(xy 173.149768 -228.971348) (xy 173.149768 -228.562408) (xy 173.150228 -228.552258) (xy 173.158014 -228.533512)
			(xy 173.172399 -228.51919) (xy 173.191179 -228.511484) (xy 173.20133 -228.5111) (xy 174.60087 -228.5111)
			(xy 174.61099 -228.51165) (xy 174.629703 -228.51936) (xy 174.644059 -228.533627) (xy 174.651886 -228.552291)
			(xy 174.652432 -228.562408) (xy 174.652432 -228.971348) (xy 180.693568 -228.971348) (xy 180.693568 -228.562408)
			(xy 180.694028 -228.552258) (xy 180.701814 -228.533512) (xy 180.716199 -228.51919) (xy 180.734979 -228.511484)
			(xy 180.74513 -228.5111) (xy 182.14467 -228.5111) (xy 182.15479 -228.51165) (xy 182.173503 -228.51936)
			(xy 182.187859 -228.533627) (xy 182.195686 -228.552291) (xy 182.196232 -228.562408) (xy 182.196232 -228.971348)
			(xy 188.237368 -228.971348) (xy 188.237368 -228.562408) (xy 188.237828 -228.552258) (xy 188.245614 -228.533512)
			(xy 188.259999 -228.51919) (xy 188.278779 -228.511484) (xy 188.28893 -228.5111) (xy 189.68847 -228.5111)
			(xy 189.69859 -228.51165) (xy 189.717303 -228.51936) (xy 189.731659 -228.533627) (xy 189.739486 -228.552291)
			(xy 189.740032 -228.562408) (xy 189.740032 -228.971348) (xy 195.781168 -228.971348) (xy 195.781168 -228.562408)
			(xy 195.781628 -228.552258) (xy 195.789414 -228.533512) (xy 195.803799 -228.51919) (xy 195.822579 -228.511484)
			(xy 195.83273 -228.5111) (xy 197.23227 -228.5111) (xy 197.24239 -228.51165) (xy 197.261103 -228.51936)
			(xy 197.275459 -228.533627) (xy 197.283286 -228.552291) (xy 197.283832 -228.562408) (xy 197.283832 -228.971348)
			(xy 203.324968 -228.971348) (xy 203.324968 -228.562408) (xy 203.325428 -228.552258) (xy 203.333214 -228.533512)
			(xy 203.347599 -228.51919) (xy 203.366379 -228.511484) (xy 203.37653 -228.5111) (xy 204.77607 -228.5111)
			(xy 204.78619 -228.51165) (xy 204.804903 -228.51936) (xy 204.819259 -228.533627) (xy 204.827086 -228.552291)
			(xy 204.827632 -228.562408) (xy 204.827632 -228.971348) (xy 210.868768 -228.971348) (xy 210.868768 -228.562408)
			(xy 210.869228 -228.552258) (xy 210.877014 -228.533512) (xy 210.891399 -228.51919) (xy 210.910179 -228.511484)
			(xy 210.92033 -228.5111) (xy 212.31987 -228.5111) (xy 212.32999 -228.51165) (xy 212.348703 -228.51936)
			(xy 212.363059 -228.533627) (xy 212.370886 -228.552291) (xy 212.371432 -228.562408) (xy 212.371432 -228.971348)
			(xy 255.329436 -228.971348) (xy 255.329436 -228.562408) (xy 255.329829 -228.55225) (xy 255.337629 -228.533491)
			(xy 255.352035 -228.519166) (xy 255.370838 -228.511472) (xy 255.380998 -228.5111) (xy 256.780538 -228.5111)
			(xy 256.790662 -228.511594) (xy 256.809377 -228.519327) (xy 256.82373 -228.53361) (xy 256.831555 -228.552286)
			(xy 256.8321 -228.562408) (xy 256.8321 -228.971348) (xy 262.873236 -228.971348) (xy 262.873236 -228.562408)
			(xy 262.873629 -228.55225) (xy 262.881429 -228.533491) (xy 262.895835 -228.519166) (xy 262.914638 -228.511472)
			(xy 262.924798 -228.5111) (xy 264.324338 -228.5111) (xy 264.334462 -228.511594) (xy 264.353177 -228.519327)
			(xy 264.36753 -228.53361) (xy 264.375355 -228.552286) (xy 264.3759 -228.562408) (xy 264.3759 -228.971348)
			(xy 270.417036 -228.971348) (xy 270.417036 -228.562408) (xy 270.417429 -228.55225) (xy 270.425229 -228.533491)
			(xy 270.439635 -228.519166) (xy 270.458438 -228.511472) (xy 270.468598 -228.5111) (xy 271.868138 -228.5111)
			(xy 271.878262 -228.511594) (xy 271.896977 -228.519327) (xy 271.91133 -228.53361) (xy 271.919155 -228.552286)
			(xy 271.9197 -228.562408) (xy 271.9197 -228.971348) (xy 277.960836 -228.971348) (xy 277.960836 -228.562408)
			(xy 277.961229 -228.55225) (xy 277.969029 -228.533491) (xy 277.983435 -228.519166) (xy 278.002238 -228.511472)
			(xy 278.012398 -228.5111) (xy 279.411938 -228.5111) (xy 279.422062 -228.511594) (xy 279.440777 -228.519327)
			(xy 279.45513 -228.53361) (xy 279.462955 -228.552286) (xy 279.4635 -228.562408) (xy 279.4635 -228.971348)
			(xy 285.504636 -228.971348) (xy 285.504636 -228.562408) (xy 285.505029 -228.55225) (xy 285.512829 -228.533491)
			(xy 285.527235 -228.519166) (xy 285.546038 -228.511472) (xy 285.556198 -228.5111) (xy 286.955738 -228.5111)
			(xy 286.965862 -228.511594) (xy 286.984577 -228.519327) (xy 286.99893 -228.53361) (xy 287.006755 -228.552286)
			(xy 287.0073 -228.562408) (xy 287.0073 -228.971348) (xy 293.048436 -228.971348) (xy 293.048436 -228.562408)
			(xy 293.048829 -228.55225) (xy 293.056629 -228.533491) (xy 293.071035 -228.519166) (xy 293.089838 -228.511472)
			(xy 293.099998 -228.5111) (xy 294.499538 -228.5111) (xy 294.509662 -228.511594) (xy 294.528377 -228.519327)
			(xy 294.54273 -228.53361) (xy 294.550555 -228.552286) (xy 294.5511 -228.562408) (xy 294.5511 -228.971348)
			(xy 300.592236 -228.971348) (xy 300.592236 -228.562408) (xy 300.592629 -228.55225) (xy 300.600429 -228.533491)
			(xy 300.614835 -228.519166) (xy 300.633638 -228.511472) (xy 300.643798 -228.5111) (xy 302.043338 -228.5111)
			(xy 302.053462 -228.511594) (xy 302.072177 -228.519327) (xy 302.08653 -228.53361) (xy 302.094355 -228.552286)
			(xy 302.0949 -228.562408) (xy 302.0949 -228.971348) (xy 308.136036 -228.971348) (xy 308.136036 -228.562408)
			(xy 308.136429 -228.55225) (xy 308.144229 -228.533491) (xy 308.158635 -228.519166) (xy 308.177438 -228.511472)
			(xy 308.187598 -228.5111) (xy 309.587138 -228.5111) (xy 309.597262 -228.511594) (xy 309.615977 -228.519327)
			(xy 309.63033 -228.53361) (xy 309.638155 -228.552286) (xy 309.6387 -228.562408) (xy 309.6387 -228.971348)
			(xy 406.002236 -228.971348) (xy 406.002236 -228.562408) (xy 406.002629 -228.55225) (xy 406.010429 -228.533491)
			(xy 406.024835 -228.519166) (xy 406.043638 -228.511472) (xy 406.053798 -228.5111) (xy 407.453338 -228.5111)
			(xy 407.463462 -228.511594) (xy 407.482177 -228.519327) (xy 407.49653 -228.53361) (xy 407.504355 -228.552286)
			(xy 407.5049 -228.562408) (xy 407.5049 -228.971348) (xy 413.546036 -228.971348) (xy 413.546036 -228.562408)
			(xy 413.546429 -228.55225) (xy 413.554229 -228.533491) (xy 413.568635 -228.519166) (xy 413.587438 -228.511472)
			(xy 413.597598 -228.5111) (xy 414.997138 -228.5111) (xy 415.007262 -228.511594) (xy 415.025977 -228.519327)
			(xy 415.04033 -228.53361) (xy 415.048155 -228.552286) (xy 415.0487 -228.562408) (xy 415.0487 -228.971348)
			(xy 421.089836 -228.971348) (xy 421.089836 -228.562408) (xy 421.090229 -228.55225) (xy 421.098029 -228.533491)
			(xy 421.112435 -228.519166) (xy 421.131238 -228.511472) (xy 421.141398 -228.5111) (xy 422.540938 -228.5111)
			(xy 422.551062 -228.511594) (xy 422.569777 -228.519327) (xy 422.58413 -228.53361) (xy 422.591955 -228.552286)
			(xy 422.5925 -228.562408) (xy 422.5925 -228.971348) (xy 428.633636 -228.971348) (xy 428.633636 -228.562408)
			(xy 428.634029 -228.55225) (xy 428.641829 -228.533491) (xy 428.656235 -228.519166) (xy 428.675038 -228.511472)
			(xy 428.685198 -228.5111) (xy 430.084738 -228.5111) (xy 430.094862 -228.511594) (xy 430.113577 -228.519327)
			(xy 430.12793 -228.53361) (xy 430.135755 -228.552286) (xy 430.1363 -228.562408) (xy 430.1363 -228.971348)
			(xy 436.177436 -228.971348) (xy 436.177436 -228.562408) (xy 436.177829 -228.55225) (xy 436.185629 -228.533491)
			(xy 436.200035 -228.519166) (xy 436.218838 -228.511472) (xy 436.228998 -228.5111) (xy 437.628538 -228.5111)
			(xy 437.638662 -228.511594) (xy 437.657377 -228.519327) (xy 437.67173 -228.53361) (xy 437.679555 -228.552286)
			(xy 437.6801 -228.562408) (xy 437.6801 -228.971348) (xy 443.721236 -228.971348) (xy 443.721236 -228.562408)
			(xy 443.721629 -228.55225) (xy 443.729429 -228.533491) (xy 443.743835 -228.519166) (xy 443.762638 -228.511472)
			(xy 443.772798 -228.5111) (xy 445.172338 -228.5111) (xy 445.182462 -228.511594) (xy 445.201177 -228.519327)
			(xy 445.21553 -228.53361) (xy 445.223355 -228.552286) (xy 445.2239 -228.562408) (xy 445.2239 -228.971348)
			(xy 451.265036 -228.971348) (xy 451.265036 -228.562408) (xy 451.265429 -228.55225) (xy 451.273229 -228.533491)
			(xy 451.287635 -228.519166) (xy 451.306438 -228.511472) (xy 451.316598 -228.5111) (xy 452.716138 -228.5111)
			(xy 452.726262 -228.511594) (xy 452.744977 -228.519327) (xy 452.75933 -228.53361) (xy 452.767155 -228.552286)
			(xy 452.7677 -228.562408) (xy 452.7677 -228.971348) (xy 458.808836 -228.971348) (xy 458.808836 -228.562408)
			(xy 458.809229 -228.55225) (xy 458.817029 -228.533491) (xy 458.831435 -228.519166) (xy 458.850238 -228.511472)
			(xy 458.860398 -228.5111) (xy 460.259938 -228.5111) (xy 460.270062 -228.511594) (xy 460.288777 -228.519327)
			(xy 460.30313 -228.53361) (xy 460.310955 -228.552286) (xy 460.3115 -228.562408) (xy 460.3115 -228.971348)
			(xy 460.311118 -228.981505) (xy 460.303306 -229.000259) (xy 460.288898 -229.01458) (xy 460.270098 -229.022278)
			(xy 460.259938 -229.022656) (xy 458.860398 -229.022656) (xy 458.850271 -229.022175) (xy 458.831549 -229.014446)
			(xy 458.817192 -229.000158) (xy 458.809374 -228.981473) (xy 458.808836 -228.971348) (xy 452.7677 -228.971348)
			(xy 452.767318 -228.981505) (xy 452.759506 -229.000259) (xy 452.745098 -229.01458) (xy 452.726298 -229.022278)
			(xy 452.716138 -229.022656) (xy 451.316598 -229.022656) (xy 451.306471 -229.022175) (xy 451.287749 -229.014446)
			(xy 451.273392 -229.000158) (xy 451.265574 -228.981473) (xy 451.265036 -228.971348) (xy 445.2239 -228.971348)
			(xy 445.223518 -228.981505) (xy 445.215706 -229.000259) (xy 445.201298 -229.01458) (xy 445.182498 -229.022278)
			(xy 445.172338 -229.022656) (xy 443.772798 -229.022656) (xy 443.762671 -229.022175) (xy 443.743949 -229.014446)
			(xy 443.729592 -229.000158) (xy 443.721774 -228.981473) (xy 443.721236 -228.971348) (xy 437.6801 -228.971348)
			(xy 437.679718 -228.981505) (xy 437.671906 -229.000259) (xy 437.657498 -229.01458) (xy 437.638698 -229.022278)
			(xy 437.628538 -229.022656) (xy 436.228998 -229.022656) (xy 436.218871 -229.022175) (xy 436.200149 -229.014446)
			(xy 436.185792 -229.000158) (xy 436.177974 -228.981473) (xy 436.177436 -228.971348) (xy 430.1363 -228.971348)
			(xy 430.135918 -228.981505) (xy 430.128106 -229.000259) (xy 430.113698 -229.01458) (xy 430.094898 -229.022278)
			(xy 430.084738 -229.022656) (xy 428.685198 -229.022656) (xy 428.675071 -229.022175) (xy 428.656349 -229.014446)
			(xy 428.641992 -229.000158) (xy 428.634174 -228.981473) (xy 428.633636 -228.971348) (xy 422.5925 -228.971348)
			(xy 422.592118 -228.981505) (xy 422.584306 -229.000259) (xy 422.569898 -229.01458) (xy 422.551098 -229.022278)
			(xy 422.540938 -229.022656) (xy 421.141398 -229.022656) (xy 421.131271 -229.022175) (xy 421.112549 -229.014446)
			(xy 421.098192 -229.000158) (xy 421.090374 -228.981473) (xy 421.089836 -228.971348) (xy 415.0487 -228.971348)
			(xy 415.048318 -228.981505) (xy 415.040506 -229.000259) (xy 415.026098 -229.01458) (xy 415.007298 -229.022278)
			(xy 414.997138 -229.022656) (xy 413.597598 -229.022656) (xy 413.587471 -229.022175) (xy 413.568749 -229.014446)
			(xy 413.554392 -229.000158) (xy 413.546574 -228.981473) (xy 413.546036 -228.971348) (xy 407.5049 -228.971348)
			(xy 407.504518 -228.981505) (xy 407.496706 -229.000259) (xy 407.482298 -229.01458) (xy 407.463498 -229.022278)
			(xy 407.453338 -229.022656) (xy 406.053798 -229.022656) (xy 406.043671 -229.022175) (xy 406.024949 -229.014446)
			(xy 406.010592 -229.000158) (xy 406.002774 -228.981473) (xy 406.002236 -228.971348) (xy 309.6387 -228.971348)
			(xy 309.638318 -228.981505) (xy 309.630506 -229.000259) (xy 309.616098 -229.01458) (xy 309.597298 -229.022278)
			(xy 309.587138 -229.022656) (xy 308.187598 -229.022656) (xy 308.177471 -229.022175) (xy 308.158749 -229.014446)
			(xy 308.144392 -229.000158) (xy 308.136574 -228.981473) (xy 308.136036 -228.971348) (xy 302.0949 -228.971348)
			(xy 302.094518 -228.981505) (xy 302.086706 -229.000259) (xy 302.072298 -229.01458) (xy 302.053498 -229.022278)
			(xy 302.043338 -229.022656) (xy 300.643798 -229.022656) (xy 300.633671 -229.022175) (xy 300.614949 -229.014446)
			(xy 300.600592 -229.000158) (xy 300.592774 -228.981473) (xy 300.592236 -228.971348) (xy 294.5511 -228.971348)
			(xy 294.550718 -228.981505) (xy 294.542906 -229.000259) (xy 294.528498 -229.01458) (xy 294.509698 -229.022278)
			(xy 294.499538 -229.022656) (xy 293.099998 -229.022656) (xy 293.089871 -229.022175) (xy 293.071149 -229.014446)
			(xy 293.056792 -229.000158) (xy 293.048974 -228.981473) (xy 293.048436 -228.971348) (xy 287.0073 -228.971348)
			(xy 287.006918 -228.981505) (xy 286.999106 -229.000259) (xy 286.984698 -229.01458) (xy 286.965898 -229.022278)
			(xy 286.955738 -229.022656) (xy 285.556198 -229.022656) (xy 285.546071 -229.022175) (xy 285.527349 -229.014446)
			(xy 285.512992 -229.000158) (xy 285.505174 -228.981473) (xy 285.504636 -228.971348) (xy 279.4635 -228.971348)
			(xy 279.463118 -228.981505) (xy 279.455306 -229.000259) (xy 279.440898 -229.01458) (xy 279.422098 -229.022278)
			(xy 279.411938 -229.022656) (xy 278.012398 -229.022656) (xy 278.002271 -229.022175) (xy 277.983549 -229.014446)
			(xy 277.969192 -229.000158) (xy 277.961374 -228.981473) (xy 277.960836 -228.971348) (xy 271.9197 -228.971348)
			(xy 271.919318 -228.981505) (xy 271.911506 -229.000259) (xy 271.897098 -229.01458) (xy 271.878298 -229.022278)
			(xy 271.868138 -229.022656) (xy 270.468598 -229.022656) (xy 270.458471 -229.022175) (xy 270.439749 -229.014446)
			(xy 270.425392 -229.000158) (xy 270.417574 -228.981473) (xy 270.417036 -228.971348) (xy 264.3759 -228.971348)
			(xy 264.375518 -228.981505) (xy 264.367706 -229.000259) (xy 264.353298 -229.01458) (xy 264.334498 -229.022278)
			(xy 264.324338 -229.022656) (xy 262.924798 -229.022656) (xy 262.914671 -229.022175) (xy 262.895949 -229.014446)
			(xy 262.881592 -229.000158) (xy 262.873774 -228.981473) (xy 262.873236 -228.971348) (xy 256.8321 -228.971348)
			(xy 256.831718 -228.981505) (xy 256.823906 -229.000259) (xy 256.809498 -229.01458) (xy 256.790698 -229.022278)
			(xy 256.780538 -229.022656) (xy 255.380998 -229.022656) (xy 255.370871 -229.022175) (xy 255.352149 -229.014446)
			(xy 255.337792 -229.000158) (xy 255.329974 -228.981473) (xy 255.329436 -228.971348) (xy 212.371432 -228.971348)
			(xy 212.371018 -228.981501) (xy 212.363213 -229.000248) (xy 212.348815 -229.014569) (xy 212.330025 -229.022273)
			(xy 212.31987 -229.022656) (xy 210.92033 -229.022656) (xy 210.910205 -229.022149) (xy 210.891483 -229.01443)
			(xy 210.877126 -229.00015) (xy 210.869306 -228.981471) (xy 210.868768 -228.971348) (xy 204.827632 -228.971348)
			(xy 204.827218 -228.981501) (xy 204.819413 -229.000248) (xy 204.805015 -229.014569) (xy 204.786225 -229.022273)
			(xy 204.77607 -229.022656) (xy 203.37653 -229.022656) (xy 203.366405 -229.022149) (xy 203.347683 -229.01443)
			(xy 203.333326 -229.00015) (xy 203.325506 -228.981471) (xy 203.324968 -228.971348) (xy 197.283832 -228.971348)
			(xy 197.283418 -228.981501) (xy 197.275613 -229.000248) (xy 197.261215 -229.014569) (xy 197.242425 -229.022273)
			(xy 197.23227 -229.022656) (xy 195.83273 -229.022656) (xy 195.822605 -229.022149) (xy 195.803883 -229.01443)
			(xy 195.789526 -229.00015) (xy 195.781706 -228.981471) (xy 195.781168 -228.971348) (xy 189.740032 -228.971348)
			(xy 189.739618 -228.981501) (xy 189.731813 -229.000248) (xy 189.717415 -229.014569) (xy 189.698625 -229.022273)
			(xy 189.68847 -229.022656) (xy 188.28893 -229.022656) (xy 188.278805 -229.022149) (xy 188.260083 -229.01443)
			(xy 188.245726 -229.00015) (xy 188.237906 -228.981471) (xy 188.237368 -228.971348) (xy 182.196232 -228.971348)
			(xy 182.195818 -228.981501) (xy 182.188013 -229.000248) (xy 182.173615 -229.014569) (xy 182.154825 -229.022273)
			(xy 182.14467 -229.022656) (xy 180.74513 -229.022656) (xy 180.735005 -229.022149) (xy 180.716283 -229.01443)
			(xy 180.701926 -229.00015) (xy 180.694106 -228.981471) (xy 180.693568 -228.971348) (xy 174.652432 -228.971348)
			(xy 174.652018 -228.981501) (xy 174.644213 -229.000248) (xy 174.629815 -229.014569) (xy 174.611025 -229.022273)
			(xy 174.60087 -229.022656) (xy 173.20133 -229.022656) (xy 173.191205 -229.022149) (xy 173.172483 -229.01443)
			(xy 173.158126 -229.00015) (xy 173.150306 -228.981471) (xy 173.149768 -228.971348) (xy 167.108632 -228.971348)
			(xy 167.108218 -228.981501) (xy 167.100413 -229.000248) (xy 167.086015 -229.014569) (xy 167.067225 -229.022273)
			(xy 167.05707 -229.022656) (xy 165.65753 -229.022656) (xy 165.647405 -229.022149) (xy 165.628683 -229.01443)
			(xy 165.614326 -229.00015) (xy 165.606506 -228.981471) (xy 165.605968 -228.971348) (xy 159.564832 -228.971348)
			(xy 159.564418 -228.981501) (xy 159.556613 -229.000248) (xy 159.542215 -229.014569) (xy 159.523425 -229.022273)
			(xy 159.51327 -229.022656) (xy 158.11373 -229.022656) (xy 158.103605 -229.022149) (xy 158.084883 -229.01443)
			(xy 158.070526 -229.00015) (xy 158.062706 -228.981471) (xy 158.062168 -228.971348) (xy 61.698632 -228.971348)
			(xy 61.698218 -228.981501) (xy 61.690413 -229.000248) (xy 61.676015 -229.014569) (xy 61.657225 -229.022273)
			(xy 61.64707 -229.022656) (xy 60.24753 -229.022656) (xy 60.237405 -229.022149) (xy 60.218683 -229.01443)
			(xy 60.204326 -229.00015) (xy 60.196506 -228.981471) (xy 60.195968 -228.971348) (xy 54.154832 -228.971348)
			(xy 54.154418 -228.981501) (xy 54.146613 -229.000248) (xy 54.132215 -229.014569) (xy 54.113425 -229.022273)
			(xy 54.10327 -229.022656) (xy 52.70373 -229.022656) (xy 52.693605 -229.022149) (xy 52.674883 -229.01443)
			(xy 52.660526 -229.00015) (xy 52.652706 -228.981471) (xy 52.652168 -228.971348) (xy 46.611032 -228.971348)
			(xy 46.610618 -228.981501) (xy 46.602813 -229.000248) (xy 46.588415 -229.014569) (xy 46.569625 -229.022273)
			(xy 46.55947 -229.022656) (xy 45.15993 -229.022656) (xy 45.149805 -229.022149) (xy 45.131083 -229.01443)
			(xy 45.116726 -229.00015) (xy 45.108906 -228.981471) (xy 45.108368 -228.971348) (xy 39.067232 -228.971348)
			(xy 39.066818 -228.981501) (xy 39.059013 -229.000248) (xy 39.044615 -229.014569) (xy 39.025825 -229.022273)
			(xy 39.01567 -229.022656) (xy 37.61613 -229.022656) (xy 37.606005 -229.022149) (xy 37.587283 -229.01443)
			(xy 37.572926 -229.00015) (xy 37.565106 -228.981471) (xy 37.564568 -228.971348) (xy 31.523432 -228.971348)
			(xy 31.523018 -228.981501) (xy 31.515213 -229.000248) (xy 31.500815 -229.014569) (xy 31.482025 -229.022273)
			(xy 31.47187 -229.022656) (xy 30.07233 -229.022656) (xy 30.062205 -229.022149) (xy 30.043483 -229.01443)
			(xy 30.029126 -229.00015) (xy 30.021306 -228.981471) (xy 30.020768 -228.971348) (xy 23.979632 -228.971348)
			(xy 23.979218 -228.981501) (xy 23.971413 -229.000248) (xy 23.957015 -229.014569) (xy 23.938225 -229.022273)
			(xy 23.92807 -229.022656) (xy 22.52853 -229.022656) (xy 22.518405 -229.022149) (xy 22.499683 -229.01443)
			(xy 22.485326 -229.00015) (xy 22.477506 -228.981471) (xy 22.476968 -228.971348) (xy 16.435832 -228.971348)
			(xy 16.435418 -228.981501) (xy 16.427613 -229.000248) (xy 16.413215 -229.014569) (xy 16.394425 -229.022273)
			(xy 16.38427 -229.022656) (xy 14.98473 -229.022656) (xy 14.974605 -229.022149) (xy 14.955883 -229.01443)
			(xy 14.941526 -229.00015) (xy 14.933706 -228.981471) (xy 14.933168 -228.971348) (xy 8.892032 -228.971348)
			(xy 8.891618 -228.981501) (xy 8.883813 -229.000248) (xy 8.869415 -229.014569) (xy 8.850625 -229.022273)
			(xy 8.84047 -229.022656) (xy 7.44093 -229.022656) (xy 7.430805 -229.022149) (xy 7.412083 -229.01443)
			(xy 7.397726 -229.00015) (xy 7.389906 -228.981471) (xy 7.389368 -228.971348) (xy 2.509012 -228.971348)
			(xy 2.509012 -229.821486) (xy 11.489436 -229.821486) (xy 11.489436 -229.412546) (xy 11.489901 -229.402378)
			(xy 11.497671 -229.383584) (xy 11.512044 -229.369198) (xy 11.53083 -229.361411) (xy 11.540998 -229.360984)
			(xy 12.940538 -229.360984) (xy 12.950718 -229.361334) (xy 12.969522 -229.36914) (xy 12.983907 -229.383548)
			(xy 12.991683 -229.402366) (xy 12.9921 -229.412546) (xy 12.9921 -229.821486) (xy 19.033236 -229.821486)
			(xy 19.033236 -229.412546) (xy 19.033701 -229.402378) (xy 19.041471 -229.383584) (xy 19.055844 -229.369198)
			(xy 19.07463 -229.361411) (xy 19.084798 -229.360984) (xy 20.484338 -229.360984) (xy 20.494518 -229.361334)
			(xy 20.513322 -229.36914) (xy 20.527707 -229.383548) (xy 20.535483 -229.402366) (xy 20.5359 -229.412546)
			(xy 20.5359 -229.821486) (xy 26.577036 -229.821486) (xy 26.577036 -229.412546) (xy 26.577501 -229.402378)
			(xy 26.585271 -229.383584) (xy 26.599644 -229.369198) (xy 26.61843 -229.361411) (xy 26.628598 -229.360984)
			(xy 28.028138 -229.360984) (xy 28.038318 -229.361334) (xy 28.057122 -229.36914) (xy 28.071507 -229.383548)
			(xy 28.079283 -229.402366) (xy 28.0797 -229.412546) (xy 28.0797 -229.821486) (xy 34.120836 -229.821486)
			(xy 34.120836 -229.412546) (xy 34.121301 -229.402378) (xy 34.129071 -229.383584) (xy 34.143444 -229.369198)
			(xy 34.16223 -229.361411) (xy 34.172398 -229.360984) (xy 35.571938 -229.360984) (xy 35.582118 -229.361334)
			(xy 35.600922 -229.36914) (xy 35.615307 -229.383548) (xy 35.623083 -229.402366) (xy 35.6235 -229.412546)
			(xy 35.6235 -229.821486) (xy 41.664636 -229.821486) (xy 41.664636 -229.412546) (xy 41.665101 -229.402378)
			(xy 41.672871 -229.383584) (xy 41.687244 -229.369198) (xy 41.70603 -229.361411) (xy 41.716198 -229.360984)
			(xy 43.115738 -229.360984) (xy 43.125918 -229.361334) (xy 43.144722 -229.36914) (xy 43.159107 -229.383548)
			(xy 43.166883 -229.402366) (xy 43.1673 -229.412546) (xy 43.1673 -229.821486) (xy 49.208436 -229.821486)
			(xy 49.208436 -229.412546) (xy 49.208901 -229.402378) (xy 49.216671 -229.383584) (xy 49.231044 -229.369198)
			(xy 49.24983 -229.361411) (xy 49.259998 -229.360984) (xy 50.659538 -229.360984) (xy 50.669718 -229.361334)
			(xy 50.688522 -229.36914) (xy 50.702907 -229.383548) (xy 50.710683 -229.402366) (xy 50.7111 -229.412546)
			(xy 50.7111 -229.821486) (xy 56.752236 -229.821486) (xy 56.752236 -229.412546) (xy 56.752701 -229.402378)
			(xy 56.760471 -229.383584) (xy 56.774844 -229.369198) (xy 56.79363 -229.361411) (xy 56.803798 -229.360984)
			(xy 58.203338 -229.360984) (xy 58.213518 -229.361334) (xy 58.232322 -229.36914) (xy 58.246707 -229.383548)
			(xy 58.254483 -229.402366) (xy 58.2549 -229.412546) (xy 58.2549 -229.821486) (xy 64.296036 -229.821486)
			(xy 64.296036 -229.412546) (xy 64.296501 -229.402378) (xy 64.304271 -229.383584) (xy 64.318644 -229.369198)
			(xy 64.33743 -229.361411) (xy 64.347598 -229.360984) (xy 65.747138 -229.360984) (xy 65.757318 -229.361334)
			(xy 65.776122 -229.36914) (xy 65.790507 -229.383548) (xy 65.798283 -229.402366) (xy 65.7987 -229.412546)
			(xy 65.7987 -229.821486) (xy 162.162236 -229.821486) (xy 162.162236 -229.412546) (xy 162.162701 -229.402378)
			(xy 162.170471 -229.383584) (xy 162.184844 -229.369198) (xy 162.20363 -229.361411) (xy 162.213798 -229.360984)
			(xy 163.613338 -229.360984) (xy 163.623518 -229.361334) (xy 163.642322 -229.36914) (xy 163.656707 -229.383548)
			(xy 163.664483 -229.402366) (xy 163.6649 -229.412546) (xy 163.6649 -229.821486) (xy 169.706036 -229.821486)
			(xy 169.706036 -229.412546) (xy 169.706501 -229.402378) (xy 169.714271 -229.383584) (xy 169.728644 -229.369198)
			(xy 169.74743 -229.361411) (xy 169.757598 -229.360984) (xy 171.157138 -229.360984) (xy 171.167318 -229.361334)
			(xy 171.186122 -229.36914) (xy 171.200507 -229.383548) (xy 171.208283 -229.402366) (xy 171.2087 -229.412546)
			(xy 171.2087 -229.821486) (xy 177.249836 -229.821486) (xy 177.249836 -229.412546) (xy 177.250301 -229.402378)
			(xy 177.258071 -229.383584) (xy 177.272444 -229.369198) (xy 177.29123 -229.361411) (xy 177.301398 -229.360984)
			(xy 178.700938 -229.360984) (xy 178.711118 -229.361334) (xy 178.729922 -229.36914) (xy 178.744307 -229.383548)
			(xy 178.752083 -229.402366) (xy 178.7525 -229.412546) (xy 178.7525 -229.821486) (xy 184.793636 -229.821486)
			(xy 184.793636 -229.412546) (xy 184.794101 -229.402378) (xy 184.801871 -229.383584) (xy 184.816244 -229.369198)
			(xy 184.83503 -229.361411) (xy 184.845198 -229.360984) (xy 186.244738 -229.360984) (xy 186.254918 -229.361334)
			(xy 186.273722 -229.36914) (xy 186.288107 -229.383548) (xy 186.295883 -229.402366) (xy 186.2963 -229.412546)
			(xy 186.2963 -229.821486) (xy 192.337436 -229.821486) (xy 192.337436 -229.412546) (xy 192.337901 -229.402378)
			(xy 192.345671 -229.383584) (xy 192.360044 -229.369198) (xy 192.37883 -229.361411) (xy 192.388998 -229.360984)
			(xy 193.788538 -229.360984) (xy 193.798718 -229.361334) (xy 193.817522 -229.36914) (xy 193.831907 -229.383548)
			(xy 193.839683 -229.402366) (xy 193.8401 -229.412546) (xy 193.8401 -229.821486) (xy 199.881236 -229.821486)
			(xy 199.881236 -229.412546) (xy 199.881701 -229.402378) (xy 199.889471 -229.383584) (xy 199.903844 -229.369198)
			(xy 199.92263 -229.361411) (xy 199.932798 -229.360984) (xy 201.332338 -229.360984) (xy 201.342518 -229.361334)
			(xy 201.361322 -229.36914) (xy 201.375707 -229.383548) (xy 201.383483 -229.402366) (xy 201.3839 -229.412546)
			(xy 201.3839 -229.821486) (xy 207.425036 -229.821486) (xy 207.425036 -229.412546) (xy 207.425501 -229.402378)
			(xy 207.433271 -229.383584) (xy 207.447644 -229.369198) (xy 207.46643 -229.361411) (xy 207.476598 -229.360984)
			(xy 208.876138 -229.360984) (xy 208.886318 -229.361334) (xy 208.905122 -229.36914) (xy 208.919507 -229.383548)
			(xy 208.927283 -229.402366) (xy 208.9277 -229.412546) (xy 208.9277 -229.821486) (xy 214.968836 -229.821486)
			(xy 214.968836 -229.412546) (xy 214.969301 -229.402378) (xy 214.977071 -229.383584) (xy 214.991444 -229.369198)
			(xy 215.01023 -229.361411) (xy 215.020398 -229.360984) (xy 216.419938 -229.360984) (xy 216.430118 -229.361334)
			(xy 216.448922 -229.36914) (xy 216.463307 -229.383548) (xy 216.471083 -229.402366) (xy 216.4715 -229.412546)
			(xy 216.4715 -229.821486) (xy 259.429504 -229.821486) (xy 259.429504 -229.412546) (xy 259.430001 -229.402382)
			(xy 259.437764 -229.383594) (xy 259.452127 -229.369209) (xy 259.470902 -229.361416) (xy 259.481066 -229.360984)
			(xy 260.880606 -229.360984) (xy 260.890784 -229.36136) (xy 260.909587 -229.369156) (xy 260.923974 -229.383556)
			(xy 260.93175 -229.402368) (xy 260.932168 -229.412546) (xy 260.932168 -229.821486) (xy 266.973304 -229.821486)
			(xy 266.973304 -229.412546) (xy 266.973801 -229.402382) (xy 266.981564 -229.383594) (xy 266.995927 -229.369209)
			(xy 267.014702 -229.361416) (xy 267.024866 -229.360984) (xy 268.424406 -229.360984) (xy 268.434584 -229.36136)
			(xy 268.453387 -229.369156) (xy 268.467774 -229.383556) (xy 268.47555 -229.402368) (xy 268.475968 -229.412546)
			(xy 268.475968 -229.821486) (xy 274.517104 -229.821486) (xy 274.517104 -229.412546) (xy 274.517601 -229.402382)
			(xy 274.525364 -229.383594) (xy 274.539727 -229.369209) (xy 274.558502 -229.361416) (xy 274.568666 -229.360984)
			(xy 275.968206 -229.360984) (xy 275.978384 -229.36136) (xy 275.997187 -229.369156) (xy 276.011574 -229.383556)
			(xy 276.01935 -229.402368) (xy 276.019768 -229.412546) (xy 276.019768 -229.821486) (xy 282.060904 -229.821486)
			(xy 282.060904 -229.412546) (xy 282.061401 -229.402382) (xy 282.069164 -229.383594) (xy 282.083527 -229.369209)
			(xy 282.102302 -229.361416) (xy 282.112466 -229.360984) (xy 283.512006 -229.360984) (xy 283.522184 -229.36136)
			(xy 283.540987 -229.369156) (xy 283.555374 -229.383556) (xy 283.56315 -229.402368) (xy 283.563568 -229.412546)
			(xy 283.563568 -229.821486) (xy 289.604704 -229.821486) (xy 289.604704 -229.412546) (xy 289.605201 -229.402382)
			(xy 289.612964 -229.383594) (xy 289.627327 -229.369209) (xy 289.646102 -229.361416) (xy 289.656266 -229.360984)
			(xy 291.055806 -229.360984) (xy 291.065984 -229.36136) (xy 291.084787 -229.369156) (xy 291.099174 -229.383556)
			(xy 291.10695 -229.402368) (xy 291.107368 -229.412546) (xy 291.107368 -229.821486) (xy 297.148504 -229.821486)
			(xy 297.148504 -229.412546) (xy 297.149001 -229.402382) (xy 297.156764 -229.383594) (xy 297.171127 -229.369209)
			(xy 297.189902 -229.361416) (xy 297.200066 -229.360984) (xy 298.599606 -229.360984) (xy 298.609784 -229.36136)
			(xy 298.628587 -229.369156) (xy 298.642974 -229.383556) (xy 298.65075 -229.402368) (xy 298.651168 -229.412546)
			(xy 298.651168 -229.821486) (xy 304.692304 -229.821486) (xy 304.692304 -229.412546) (xy 304.692801 -229.402382)
			(xy 304.700564 -229.383594) (xy 304.714927 -229.369209) (xy 304.733702 -229.361416) (xy 304.743866 -229.360984)
			(xy 306.143406 -229.360984) (xy 306.153584 -229.36136) (xy 306.172387 -229.369156) (xy 306.186774 -229.383556)
			(xy 306.19455 -229.402368) (xy 306.194968 -229.412546) (xy 306.194968 -229.821486) (xy 312.236104 -229.821486)
			(xy 312.236104 -229.412546) (xy 312.236601 -229.402382) (xy 312.244364 -229.383594) (xy 312.258727 -229.369209)
			(xy 312.277502 -229.361416) (xy 312.287666 -229.360984) (xy 313.687206 -229.360984) (xy 313.697384 -229.36136)
			(xy 313.716187 -229.369156) (xy 313.730574 -229.383556) (xy 313.73835 -229.402368) (xy 313.738768 -229.412546)
			(xy 313.738768 -229.821486) (xy 410.102304 -229.821486) (xy 410.102304 -229.412546) (xy 410.102801 -229.402382)
			(xy 410.110564 -229.383594) (xy 410.124927 -229.369209) (xy 410.143702 -229.361416) (xy 410.153866 -229.360984)
			(xy 411.553406 -229.360984) (xy 411.563584 -229.36136) (xy 411.582387 -229.369156) (xy 411.596774 -229.383556)
			(xy 411.60455 -229.402368) (xy 411.604968 -229.412546) (xy 411.604968 -229.821486) (xy 417.646104 -229.821486)
			(xy 417.646104 -229.412546) (xy 417.646601 -229.402382) (xy 417.654364 -229.383594) (xy 417.668727 -229.369209)
			(xy 417.687502 -229.361416) (xy 417.697666 -229.360984) (xy 419.097206 -229.360984) (xy 419.107384 -229.36136)
			(xy 419.126187 -229.369156) (xy 419.140574 -229.383556) (xy 419.14835 -229.402368) (xy 419.148768 -229.412546)
			(xy 419.148768 -229.821486) (xy 425.189904 -229.821486) (xy 425.189904 -229.412546) (xy 425.190401 -229.402382)
			(xy 425.198164 -229.383594) (xy 425.212527 -229.369209) (xy 425.231302 -229.361416) (xy 425.241466 -229.360984)
			(xy 426.641006 -229.360984) (xy 426.651184 -229.36136) (xy 426.669987 -229.369156) (xy 426.684374 -229.383556)
			(xy 426.69215 -229.402368) (xy 426.692568 -229.412546) (xy 426.692568 -229.821486) (xy 432.733704 -229.821486)
			(xy 432.733704 -229.412546) (xy 432.734201 -229.402382) (xy 432.741964 -229.383594) (xy 432.756327 -229.369209)
			(xy 432.775102 -229.361416) (xy 432.785266 -229.360984) (xy 434.184806 -229.360984) (xy 434.194984 -229.36136)
			(xy 434.213787 -229.369156) (xy 434.228174 -229.383556) (xy 434.23595 -229.402368) (xy 434.236368 -229.412546)
			(xy 434.236368 -229.821486) (xy 440.277504 -229.821486) (xy 440.277504 -229.412546) (xy 440.278001 -229.402382)
			(xy 440.285764 -229.383594) (xy 440.300127 -229.369209) (xy 440.318902 -229.361416) (xy 440.329066 -229.360984)
			(xy 441.728606 -229.360984) (xy 441.738784 -229.36136) (xy 441.757587 -229.369156) (xy 441.771974 -229.383556)
			(xy 441.77975 -229.402368) (xy 441.780168 -229.412546) (xy 441.780168 -229.821486) (xy 447.821304 -229.821486)
			(xy 447.821304 -229.412546) (xy 447.821801 -229.402382) (xy 447.829564 -229.383594) (xy 447.843927 -229.369209)
			(xy 447.862702 -229.361416) (xy 447.872866 -229.360984) (xy 449.272406 -229.360984) (xy 449.282584 -229.36136)
			(xy 449.301387 -229.369156) (xy 449.315774 -229.383556) (xy 449.32355 -229.402368) (xy 449.323968 -229.412546)
			(xy 449.323968 -229.821486) (xy 455.365104 -229.821486) (xy 455.365104 -229.412546) (xy 455.365601 -229.402382)
			(xy 455.373364 -229.383594) (xy 455.387727 -229.369209) (xy 455.406502 -229.361416) (xy 455.416666 -229.360984)
			(xy 456.816206 -229.360984) (xy 456.826384 -229.36136) (xy 456.845187 -229.369156) (xy 456.859574 -229.383556)
			(xy 456.86735 -229.402368) (xy 456.867768 -229.412546) (xy 456.867768 -229.821486) (xy 462.908904 -229.821486)
			(xy 462.908904 -229.412546) (xy 462.909401 -229.402382) (xy 462.917164 -229.383594) (xy 462.931527 -229.369209)
			(xy 462.950302 -229.361416) (xy 462.960466 -229.360984) (xy 464.360006 -229.360984) (xy 464.370184 -229.36136)
			(xy 464.388987 -229.369156) (xy 464.403374 -229.383556) (xy 464.41115 -229.402368) (xy 464.411568 -229.412546)
			(xy 464.411568 -229.821486) (xy 464.411125 -229.831656) (xy 464.403346 -229.850449) (xy 464.388966 -229.864834)
			(xy 464.370176 -229.872621) (xy 464.360006 -229.873048) (xy 462.960466 -229.873048) (xy 462.950304 -229.872594)
			(xy 462.931532 -229.864806) (xy 462.917167 -229.850428) (xy 462.909396 -229.831648) (xy 462.908904 -229.821486)
			(xy 456.867768 -229.821486) (xy 456.867325 -229.831656) (xy 456.859546 -229.850449) (xy 456.845166 -229.864834)
			(xy 456.826376 -229.872621) (xy 456.816206 -229.873048) (xy 455.416666 -229.873048) (xy 455.406504 -229.872594)
			(xy 455.387732 -229.864806) (xy 455.373367 -229.850428) (xy 455.365596 -229.831648) (xy 455.365104 -229.821486)
			(xy 449.323968 -229.821486) (xy 449.323525 -229.831656) (xy 449.315746 -229.850449) (xy 449.301366 -229.864834)
			(xy 449.282576 -229.872621) (xy 449.272406 -229.873048) (xy 447.872866 -229.873048) (xy 447.862704 -229.872594)
			(xy 447.843932 -229.864806) (xy 447.829567 -229.850428) (xy 447.821796 -229.831648) (xy 447.821304 -229.821486)
			(xy 441.780168 -229.821486) (xy 441.779725 -229.831656) (xy 441.771946 -229.850449) (xy 441.757566 -229.864834)
			(xy 441.738776 -229.872621) (xy 441.728606 -229.873048) (xy 440.329066 -229.873048) (xy 440.318904 -229.872594)
			(xy 440.300132 -229.864806) (xy 440.285767 -229.850428) (xy 440.277996 -229.831648) (xy 440.277504 -229.821486)
			(xy 434.236368 -229.821486) (xy 434.235925 -229.831656) (xy 434.228146 -229.850449) (xy 434.213766 -229.864834)
			(xy 434.194976 -229.872621) (xy 434.184806 -229.873048) (xy 432.785266 -229.873048) (xy 432.775104 -229.872594)
			(xy 432.756332 -229.864806) (xy 432.741967 -229.850428) (xy 432.734196 -229.831648) (xy 432.733704 -229.821486)
			(xy 426.692568 -229.821486) (xy 426.692125 -229.831656) (xy 426.684346 -229.850449) (xy 426.669966 -229.864834)
			(xy 426.651176 -229.872621) (xy 426.641006 -229.873048) (xy 425.241466 -229.873048) (xy 425.231304 -229.872594)
			(xy 425.212532 -229.864806) (xy 425.198167 -229.850428) (xy 425.190396 -229.831648) (xy 425.189904 -229.821486)
			(xy 419.148768 -229.821486) (xy 419.148325 -229.831656) (xy 419.140546 -229.850449) (xy 419.126166 -229.864834)
			(xy 419.107376 -229.872621) (xy 419.097206 -229.873048) (xy 417.697666 -229.873048) (xy 417.687504 -229.872594)
			(xy 417.668732 -229.864806) (xy 417.654367 -229.850428) (xy 417.646596 -229.831648) (xy 417.646104 -229.821486)
			(xy 411.604968 -229.821486) (xy 411.604525 -229.831656) (xy 411.596746 -229.850449) (xy 411.582366 -229.864834)
			(xy 411.563576 -229.872621) (xy 411.553406 -229.873048) (xy 410.153866 -229.873048) (xy 410.143704 -229.872594)
			(xy 410.124932 -229.864806) (xy 410.110567 -229.850428) (xy 410.102796 -229.831648) (xy 410.102304 -229.821486)
			(xy 313.738768 -229.821486) (xy 313.738325 -229.831656) (xy 313.730546 -229.850449) (xy 313.716166 -229.864834)
			(xy 313.697376 -229.872621) (xy 313.687206 -229.873048) (xy 312.287666 -229.873048) (xy 312.277504 -229.872594)
			(xy 312.258732 -229.864806) (xy 312.244367 -229.850428) (xy 312.236596 -229.831648) (xy 312.236104 -229.821486)
			(xy 306.194968 -229.821486) (xy 306.194525 -229.831656) (xy 306.186746 -229.850449) (xy 306.172366 -229.864834)
			(xy 306.153576 -229.872621) (xy 306.143406 -229.873048) (xy 304.743866 -229.873048) (xy 304.733704 -229.872594)
			(xy 304.714932 -229.864806) (xy 304.700567 -229.850428) (xy 304.692796 -229.831648) (xy 304.692304 -229.821486)
			(xy 298.651168 -229.821486) (xy 298.650725 -229.831656) (xy 298.642946 -229.850449) (xy 298.628566 -229.864834)
			(xy 298.609776 -229.872621) (xy 298.599606 -229.873048) (xy 297.200066 -229.873048) (xy 297.189904 -229.872594)
			(xy 297.171132 -229.864806) (xy 297.156767 -229.850428) (xy 297.148996 -229.831648) (xy 297.148504 -229.821486)
			(xy 291.107368 -229.821486) (xy 291.106925 -229.831656) (xy 291.099146 -229.850449) (xy 291.084766 -229.864834)
			(xy 291.065976 -229.872621) (xy 291.055806 -229.873048) (xy 289.656266 -229.873048) (xy 289.646104 -229.872594)
			(xy 289.627332 -229.864806) (xy 289.612967 -229.850428) (xy 289.605196 -229.831648) (xy 289.604704 -229.821486)
			(xy 283.563568 -229.821486) (xy 283.563125 -229.831656) (xy 283.555346 -229.850449) (xy 283.540966 -229.864834)
			(xy 283.522176 -229.872621) (xy 283.512006 -229.873048) (xy 282.112466 -229.873048) (xy 282.102304 -229.872594)
			(xy 282.083532 -229.864806) (xy 282.069167 -229.850428) (xy 282.061396 -229.831648) (xy 282.060904 -229.821486)
			(xy 276.019768 -229.821486) (xy 276.019325 -229.831656) (xy 276.011546 -229.850449) (xy 275.997166 -229.864834)
			(xy 275.978376 -229.872621) (xy 275.968206 -229.873048) (xy 274.568666 -229.873048) (xy 274.558504 -229.872594)
			(xy 274.539732 -229.864806) (xy 274.525367 -229.850428) (xy 274.517596 -229.831648) (xy 274.517104 -229.821486)
			(xy 268.475968 -229.821486) (xy 268.475525 -229.831656) (xy 268.467746 -229.850449) (xy 268.453366 -229.864834)
			(xy 268.434576 -229.872621) (xy 268.424406 -229.873048) (xy 267.024866 -229.873048) (xy 267.014704 -229.872594)
			(xy 266.995932 -229.864806) (xy 266.981567 -229.850428) (xy 266.973796 -229.831648) (xy 266.973304 -229.821486)
			(xy 260.932168 -229.821486) (xy 260.931725 -229.831656) (xy 260.923946 -229.850449) (xy 260.909566 -229.864834)
			(xy 260.890776 -229.872621) (xy 260.880606 -229.873048) (xy 259.481066 -229.873048) (xy 259.470904 -229.872594)
			(xy 259.452132 -229.864806) (xy 259.437767 -229.850428) (xy 259.429996 -229.831648) (xy 259.429504 -229.821486)
			(xy 216.4715 -229.821486) (xy 216.470956 -229.831638) (xy 216.463193 -229.8504) (xy 216.448843 -229.864764)
			(xy 216.43009 -229.872546) (xy 216.419938 -229.873048) (xy 215.020398 -229.873048) (xy 215.010225 -229.872637)
			(xy 214.991427 -229.864849) (xy 214.977042 -229.850459) (xy 214.969259 -229.83166) (xy 214.968836 -229.821486)
			(xy 208.9277 -229.821486) (xy 208.927156 -229.831638) (xy 208.919393 -229.8504) (xy 208.905043 -229.864764)
			(xy 208.88629 -229.872546) (xy 208.876138 -229.873048) (xy 207.476598 -229.873048) (xy 207.466425 -229.872637)
			(xy 207.447627 -229.864849) (xy 207.433242 -229.850459) (xy 207.425459 -229.83166) (xy 207.425036 -229.821486)
			(xy 201.3839 -229.821486) (xy 201.383356 -229.831638) (xy 201.375593 -229.8504) (xy 201.361243 -229.864764)
			(xy 201.34249 -229.872546) (xy 201.332338 -229.873048) (xy 199.932798 -229.873048) (xy 199.922625 -229.872637)
			(xy 199.903827 -229.864849) (xy 199.889442 -229.850459) (xy 199.881659 -229.83166) (xy 199.881236 -229.821486)
			(xy 193.8401 -229.821486) (xy 193.839556 -229.831638) (xy 193.831793 -229.8504) (xy 193.817443 -229.864764)
			(xy 193.79869 -229.872546) (xy 193.788538 -229.873048) (xy 192.388998 -229.873048) (xy 192.378825 -229.872637)
			(xy 192.360027 -229.864849) (xy 192.345642 -229.850459) (xy 192.337859 -229.83166) (xy 192.337436 -229.821486)
			(xy 186.2963 -229.821486) (xy 186.295756 -229.831638) (xy 186.287993 -229.8504) (xy 186.273643 -229.864764)
			(xy 186.25489 -229.872546) (xy 186.244738 -229.873048) (xy 184.845198 -229.873048) (xy 184.835025 -229.872637)
			(xy 184.816227 -229.864849) (xy 184.801842 -229.850459) (xy 184.794059 -229.83166) (xy 184.793636 -229.821486)
			(xy 178.7525 -229.821486) (xy 178.751956 -229.831638) (xy 178.744193 -229.8504) (xy 178.729843 -229.864764)
			(xy 178.71109 -229.872546) (xy 178.700938 -229.873048) (xy 177.301398 -229.873048) (xy 177.291225 -229.872637)
			(xy 177.272427 -229.864849) (xy 177.258042 -229.850459) (xy 177.250259 -229.83166) (xy 177.249836 -229.821486)
			(xy 171.2087 -229.821486) (xy 171.208156 -229.831638) (xy 171.200393 -229.8504) (xy 171.186043 -229.864764)
			(xy 171.16729 -229.872546) (xy 171.157138 -229.873048) (xy 169.757598 -229.873048) (xy 169.747425 -229.872637)
			(xy 169.728627 -229.864849) (xy 169.714242 -229.850459) (xy 169.706459 -229.83166) (xy 169.706036 -229.821486)
			(xy 163.6649 -229.821486) (xy 163.664356 -229.831638) (xy 163.656593 -229.8504) (xy 163.642243 -229.864764)
			(xy 163.62349 -229.872546) (xy 163.613338 -229.873048) (xy 162.213798 -229.873048) (xy 162.203625 -229.872637)
			(xy 162.184827 -229.864849) (xy 162.170442 -229.850459) (xy 162.162659 -229.83166) (xy 162.162236 -229.821486)
			(xy 65.7987 -229.821486) (xy 65.798156 -229.831638) (xy 65.790393 -229.8504) (xy 65.776043 -229.864764)
			(xy 65.75729 -229.872546) (xy 65.747138 -229.873048) (xy 64.347598 -229.873048) (xy 64.337425 -229.872637)
			(xy 64.318627 -229.864849) (xy 64.304242 -229.850459) (xy 64.296459 -229.83166) (xy 64.296036 -229.821486)
			(xy 58.2549 -229.821486) (xy 58.254356 -229.831638) (xy 58.246593 -229.8504) (xy 58.232243 -229.864764)
			(xy 58.21349 -229.872546) (xy 58.203338 -229.873048) (xy 56.803798 -229.873048) (xy 56.793625 -229.872637)
			(xy 56.774827 -229.864849) (xy 56.760442 -229.850459) (xy 56.752659 -229.83166) (xy 56.752236 -229.821486)
			(xy 50.7111 -229.821486) (xy 50.710556 -229.831638) (xy 50.702793 -229.8504) (xy 50.688443 -229.864764)
			(xy 50.66969 -229.872546) (xy 50.659538 -229.873048) (xy 49.259998 -229.873048) (xy 49.249825 -229.872637)
			(xy 49.231027 -229.864849) (xy 49.216642 -229.850459) (xy 49.208859 -229.83166) (xy 49.208436 -229.821486)
			(xy 43.1673 -229.821486) (xy 43.166756 -229.831638) (xy 43.158993 -229.8504) (xy 43.144643 -229.864764)
			(xy 43.12589 -229.872546) (xy 43.115738 -229.873048) (xy 41.716198 -229.873048) (xy 41.706025 -229.872637)
			(xy 41.687227 -229.864849) (xy 41.672842 -229.850459) (xy 41.665059 -229.83166) (xy 41.664636 -229.821486)
			(xy 35.6235 -229.821486) (xy 35.622956 -229.831638) (xy 35.615193 -229.8504) (xy 35.600843 -229.864764)
			(xy 35.58209 -229.872546) (xy 35.571938 -229.873048) (xy 34.172398 -229.873048) (xy 34.162225 -229.872637)
			(xy 34.143427 -229.864849) (xy 34.129042 -229.850459) (xy 34.121259 -229.83166) (xy 34.120836 -229.821486)
			(xy 28.0797 -229.821486) (xy 28.079156 -229.831638) (xy 28.071393 -229.8504) (xy 28.057043 -229.864764)
			(xy 28.03829 -229.872546) (xy 28.028138 -229.873048) (xy 26.628598 -229.873048) (xy 26.618425 -229.872637)
			(xy 26.599627 -229.864849) (xy 26.585242 -229.850459) (xy 26.577459 -229.83166) (xy 26.577036 -229.821486)
			(xy 20.5359 -229.821486) (xy 20.535356 -229.831638) (xy 20.527593 -229.8504) (xy 20.513243 -229.864764)
			(xy 20.49449 -229.872546) (xy 20.484338 -229.873048) (xy 19.084798 -229.873048) (xy 19.074625 -229.872637)
			(xy 19.055827 -229.864849) (xy 19.041442 -229.850459) (xy 19.033659 -229.83166) (xy 19.033236 -229.821486)
			(xy 12.9921 -229.821486) (xy 12.991556 -229.831638) (xy 12.983793 -229.8504) (xy 12.969443 -229.864764)
			(xy 12.95069 -229.872546) (xy 12.940538 -229.873048) (xy 11.540998 -229.873048) (xy 11.530825 -229.872637)
			(xy 11.512027 -229.864849) (xy 11.497642 -229.850459) (xy 11.489859 -229.83166) (xy 11.489436 -229.821486)
			(xy 2.509012 -229.821486) (xy 2.509012 -230.67137) (xy 7.389368 -230.67137) (xy 7.389368 -230.26243)
			(xy 7.389789 -230.252257) (xy 7.39757 -230.233457) (xy 7.411957 -230.21907) (xy 7.430757 -230.211289)
			(xy 7.44093 -230.210868) (xy 8.84047 -230.210868) (xy 8.850643 -230.211289) (xy 8.869443 -230.21907)
			(xy 8.88383 -230.233457) (xy 8.891611 -230.252257) (xy 8.892032 -230.26243) (xy 8.892032 -230.67137)
			(xy 14.933168 -230.67137) (xy 14.933168 -230.26243) (xy 14.933589 -230.252257) (xy 14.94137 -230.233457)
			(xy 14.955757 -230.21907) (xy 14.974557 -230.211289) (xy 14.98473 -230.210868) (xy 16.38427 -230.210868)
			(xy 16.394443 -230.211289) (xy 16.413243 -230.21907) (xy 16.42763 -230.233457) (xy 16.435411 -230.252257)
			(xy 16.435832 -230.26243) (xy 16.435832 -230.67137) (xy 22.476968 -230.67137) (xy 22.476968 -230.26243)
			(xy 22.477389 -230.252257) (xy 22.48517 -230.233457) (xy 22.499557 -230.21907) (xy 22.518357 -230.211289)
			(xy 22.52853 -230.210868) (xy 23.92807 -230.210868) (xy 23.938243 -230.211289) (xy 23.957043 -230.21907)
			(xy 23.97143 -230.233457) (xy 23.979211 -230.252257) (xy 23.979632 -230.26243) (xy 23.979632 -230.67137)
			(xy 30.020768 -230.67137) (xy 30.020768 -230.26243) (xy 30.021189 -230.252257) (xy 30.02897 -230.233457)
			(xy 30.043357 -230.21907) (xy 30.062157 -230.211289) (xy 30.07233 -230.210868) (xy 31.47187 -230.210868)
			(xy 31.482043 -230.211289) (xy 31.500843 -230.21907) (xy 31.51523 -230.233457) (xy 31.523011 -230.252257)
			(xy 31.523432 -230.26243) (xy 31.523432 -230.67137) (xy 37.564568 -230.67137) (xy 37.564568 -230.26243)
			(xy 37.564989 -230.252257) (xy 37.57277 -230.233457) (xy 37.587157 -230.21907) (xy 37.605957 -230.211289)
			(xy 37.61613 -230.210868) (xy 39.01567 -230.210868) (xy 39.025843 -230.211289) (xy 39.044643 -230.21907)
			(xy 39.05903 -230.233457) (xy 39.066811 -230.252257) (xy 39.067232 -230.26243) (xy 39.067232 -230.67137)
			(xy 45.108368 -230.67137) (xy 45.108368 -230.26243) (xy 45.108789 -230.252257) (xy 45.11657 -230.233457)
			(xy 45.130957 -230.21907) (xy 45.149757 -230.211289) (xy 45.15993 -230.210868) (xy 46.55947 -230.210868)
			(xy 46.569643 -230.211289) (xy 46.588443 -230.21907) (xy 46.60283 -230.233457) (xy 46.610611 -230.252257)
			(xy 46.611032 -230.26243) (xy 46.611032 -230.67137) (xy 52.652168 -230.67137) (xy 52.652168 -230.26243)
			(xy 52.652589 -230.252257) (xy 52.66037 -230.233457) (xy 52.674757 -230.21907) (xy 52.693557 -230.211289)
			(xy 52.70373 -230.210868) (xy 54.10327 -230.210868) (xy 54.113443 -230.211289) (xy 54.132243 -230.21907)
			(xy 54.14663 -230.233457) (xy 54.154411 -230.252257) (xy 54.154832 -230.26243) (xy 54.154832 -230.67137)
			(xy 60.195968 -230.67137) (xy 60.195968 -230.26243) (xy 60.196389 -230.252257) (xy 60.20417 -230.233457)
			(xy 60.218557 -230.21907) (xy 60.237357 -230.211289) (xy 60.24753 -230.210868) (xy 61.64707 -230.210868)
			(xy 61.657243 -230.211289) (xy 61.676043 -230.21907) (xy 61.69043 -230.233457) (xy 61.698211 -230.252257)
			(xy 61.698632 -230.26243) (xy 61.698632 -230.67137) (xy 158.062168 -230.67137) (xy 158.062168 -230.26243)
			(xy 158.062589 -230.252257) (xy 158.07037 -230.233457) (xy 158.084757 -230.21907) (xy 158.103557 -230.211289)
			(xy 158.11373 -230.210868) (xy 159.51327 -230.210868) (xy 159.523443 -230.211289) (xy 159.542243 -230.21907)
			(xy 159.55663 -230.233457) (xy 159.564411 -230.252257) (xy 159.564832 -230.26243) (xy 159.564832 -230.67137)
			(xy 165.605968 -230.67137) (xy 165.605968 -230.26243) (xy 165.606389 -230.252257) (xy 165.61417 -230.233457)
			(xy 165.628557 -230.21907) (xy 165.647357 -230.211289) (xy 165.65753 -230.210868) (xy 167.05707 -230.210868)
			(xy 167.067243 -230.211289) (xy 167.086043 -230.21907) (xy 167.10043 -230.233457) (xy 167.108211 -230.252257)
			(xy 167.108632 -230.26243) (xy 167.108632 -230.67137) (xy 173.149768 -230.67137) (xy 173.149768 -230.26243)
			(xy 173.150189 -230.252257) (xy 173.15797 -230.233457) (xy 173.172357 -230.21907) (xy 173.191157 -230.211289)
			(xy 173.20133 -230.210868) (xy 174.60087 -230.210868) (xy 174.611043 -230.211289) (xy 174.629843 -230.21907)
			(xy 174.64423 -230.233457) (xy 174.652011 -230.252257) (xy 174.652432 -230.26243) (xy 174.652432 -230.67137)
			(xy 180.693568 -230.67137) (xy 180.693568 -230.26243) (xy 180.693989 -230.252257) (xy 180.70177 -230.233457)
			(xy 180.716157 -230.21907) (xy 180.734957 -230.211289) (xy 180.74513 -230.210868) (xy 182.14467 -230.210868)
			(xy 182.154843 -230.211289) (xy 182.173643 -230.21907) (xy 182.18803 -230.233457) (xy 182.195811 -230.252257)
			(xy 182.196232 -230.26243) (xy 182.196232 -230.67137) (xy 188.237368 -230.67137) (xy 188.237368 -230.26243)
			(xy 188.237789 -230.252257) (xy 188.24557 -230.233457) (xy 188.259957 -230.21907) (xy 188.278757 -230.211289)
			(xy 188.28893 -230.210868) (xy 189.68847 -230.210868) (xy 189.698643 -230.211289) (xy 189.717443 -230.21907)
			(xy 189.73183 -230.233457) (xy 189.739611 -230.252257) (xy 189.740032 -230.26243) (xy 189.740032 -230.67137)
			(xy 195.781168 -230.67137) (xy 195.781168 -230.26243) (xy 195.781589 -230.252257) (xy 195.78937 -230.233457)
			(xy 195.803757 -230.21907) (xy 195.822557 -230.211289) (xy 195.83273 -230.210868) (xy 197.23227 -230.210868)
			(xy 197.242443 -230.211289) (xy 197.261243 -230.21907) (xy 197.27563 -230.233457) (xy 197.283411 -230.252257)
			(xy 197.283832 -230.26243) (xy 197.283832 -230.67137) (xy 203.324968 -230.67137) (xy 203.324968 -230.26243)
			(xy 203.325389 -230.252257) (xy 203.33317 -230.233457) (xy 203.347557 -230.21907) (xy 203.366357 -230.211289)
			(xy 203.37653 -230.210868) (xy 204.77607 -230.210868) (xy 204.786243 -230.211289) (xy 204.805043 -230.21907)
			(xy 204.81943 -230.233457) (xy 204.827211 -230.252257) (xy 204.827632 -230.26243) (xy 204.827632 -230.67137)
			(xy 210.868768 -230.67137) (xy 210.868768 -230.26243) (xy 210.869189 -230.252257) (xy 210.87697 -230.233457)
			(xy 210.891357 -230.21907) (xy 210.910157 -230.211289) (xy 210.92033 -230.210868) (xy 212.31987 -230.210868)
			(xy 212.330043 -230.211289) (xy 212.348843 -230.21907) (xy 212.36323 -230.233457) (xy 212.371011 -230.252257)
			(xy 212.371432 -230.26243) (xy 212.371432 -230.67137) (xy 255.329436 -230.67137) (xy 255.329436 -230.26243)
			(xy 255.329889 -230.252261) (xy 255.337663 -230.233467) (xy 255.35204 -230.219081) (xy 255.370829 -230.211295)
			(xy 255.380998 -230.210868) (xy 256.780538 -230.210868) (xy 256.790702 -230.211303) (xy 256.809478 -230.219096)
			(xy 256.823843 -230.233479) (xy 256.83161 -230.252265) (xy 256.8321 -230.26243) (xy 256.8321 -230.67137)
			(xy 262.873236 -230.67137) (xy 262.873236 -230.26243) (xy 262.873689 -230.252261) (xy 262.881463 -230.233467)
			(xy 262.89584 -230.219081) (xy 262.914629 -230.211295) (xy 262.924798 -230.210868) (xy 264.324338 -230.210868)
			(xy 264.334502 -230.211303) (xy 264.353278 -230.219096) (xy 264.367643 -230.233479) (xy 264.37541 -230.252265)
			(xy 264.3759 -230.26243) (xy 264.3759 -230.67137) (xy 270.417036 -230.67137) (xy 270.417036 -230.26243)
			(xy 270.417489 -230.252261) (xy 270.425263 -230.233467) (xy 270.43964 -230.219081) (xy 270.458429 -230.211295)
			(xy 270.468598 -230.210868) (xy 271.868138 -230.210868) (xy 271.878302 -230.211303) (xy 271.897078 -230.219096)
			(xy 271.911443 -230.233479) (xy 271.91921 -230.252265) (xy 271.9197 -230.26243) (xy 271.9197 -230.67137)
			(xy 277.960836 -230.67137) (xy 277.960836 -230.26243) (xy 277.961289 -230.252261) (xy 277.969063 -230.233467)
			(xy 277.98344 -230.219081) (xy 278.002229 -230.211295) (xy 278.012398 -230.210868) (xy 279.411938 -230.210868)
			(xy 279.422102 -230.211303) (xy 279.440878 -230.219096) (xy 279.455243 -230.233479) (xy 279.46301 -230.252265)
			(xy 279.4635 -230.26243) (xy 279.4635 -230.67137) (xy 285.504636 -230.67137) (xy 285.504636 -230.26243)
			(xy 285.505089 -230.252261) (xy 285.512863 -230.233467) (xy 285.52724 -230.219081) (xy 285.546029 -230.211295)
			(xy 285.556198 -230.210868) (xy 286.955738 -230.210868) (xy 286.965902 -230.211303) (xy 286.984678 -230.219096)
			(xy 286.999043 -230.233479) (xy 287.00681 -230.252265) (xy 287.0073 -230.26243) (xy 287.0073 -230.67137)
			(xy 293.048436 -230.67137) (xy 293.048436 -230.26243) (xy 293.048889 -230.252261) (xy 293.056663 -230.233467)
			(xy 293.07104 -230.219081) (xy 293.089829 -230.211295) (xy 293.099998 -230.210868) (xy 294.499538 -230.210868)
			(xy 294.509702 -230.211303) (xy 294.528478 -230.219096) (xy 294.542843 -230.233479) (xy 294.55061 -230.252265)
			(xy 294.5511 -230.26243) (xy 294.5511 -230.67137) (xy 300.592236 -230.67137) (xy 300.592236 -230.26243)
			(xy 300.592689 -230.252261) (xy 300.600463 -230.233467) (xy 300.61484 -230.219081) (xy 300.633629 -230.211295)
			(xy 300.643798 -230.210868) (xy 302.043338 -230.210868) (xy 302.053502 -230.211303) (xy 302.072278 -230.219096)
			(xy 302.086643 -230.233479) (xy 302.09441 -230.252265) (xy 302.0949 -230.26243) (xy 302.0949 -230.67137)
			(xy 308.136036 -230.67137) (xy 308.136036 -230.26243) (xy 308.136489 -230.252261) (xy 308.144263 -230.233467)
			(xy 308.15864 -230.219081) (xy 308.177429 -230.211295) (xy 308.187598 -230.210868) (xy 309.587138 -230.210868)
			(xy 309.597302 -230.211303) (xy 309.616078 -230.219096) (xy 309.630443 -230.233479) (xy 309.63821 -230.252265)
			(xy 309.6387 -230.26243) (xy 309.6387 -230.67137) (xy 406.002236 -230.67137) (xy 406.002236 -230.26243)
			(xy 406.002689 -230.252261) (xy 406.010463 -230.233467) (xy 406.02484 -230.219081) (xy 406.043629 -230.211295)
			(xy 406.053798 -230.210868) (xy 407.453338 -230.210868) (xy 407.463502 -230.211303) (xy 407.482278 -230.219096)
			(xy 407.496643 -230.233479) (xy 407.50441 -230.252265) (xy 407.5049 -230.26243) (xy 407.5049 -230.67137)
			(xy 413.546036 -230.67137) (xy 413.546036 -230.26243) (xy 413.546489 -230.252261) (xy 413.554263 -230.233467)
			(xy 413.56864 -230.219081) (xy 413.587429 -230.211295) (xy 413.597598 -230.210868) (xy 414.997138 -230.210868)
			(xy 415.007302 -230.211303) (xy 415.026078 -230.219096) (xy 415.040443 -230.233479) (xy 415.04821 -230.252265)
			(xy 415.0487 -230.26243) (xy 415.0487 -230.67137) (xy 421.089836 -230.67137) (xy 421.089836 -230.26243)
			(xy 421.090289 -230.252261) (xy 421.098063 -230.233467) (xy 421.11244 -230.219081) (xy 421.131229 -230.211295)
			(xy 421.141398 -230.210868) (xy 422.540938 -230.210868) (xy 422.551102 -230.211303) (xy 422.569878 -230.219096)
			(xy 422.584243 -230.233479) (xy 422.59201 -230.252265) (xy 422.5925 -230.26243) (xy 422.5925 -230.67137)
			(xy 428.633636 -230.67137) (xy 428.633636 -230.26243) (xy 428.634089 -230.252261) (xy 428.641863 -230.233467)
			(xy 428.65624 -230.219081) (xy 428.675029 -230.211295) (xy 428.685198 -230.210868) (xy 430.084738 -230.210868)
			(xy 430.094902 -230.211303) (xy 430.113678 -230.219096) (xy 430.128043 -230.233479) (xy 430.13581 -230.252265)
			(xy 430.1363 -230.26243) (xy 430.1363 -230.67137) (xy 436.177436 -230.67137) (xy 436.177436 -230.26243)
			(xy 436.177889 -230.252261) (xy 436.185663 -230.233467) (xy 436.20004 -230.219081) (xy 436.218829 -230.211295)
			(xy 436.228998 -230.210868) (xy 437.628538 -230.210868) (xy 437.638702 -230.211303) (xy 437.657478 -230.219096)
			(xy 437.671843 -230.233479) (xy 437.67961 -230.252265) (xy 437.6801 -230.26243) (xy 437.6801 -230.67137)
			(xy 443.721236 -230.67137) (xy 443.721236 -230.26243) (xy 443.721689 -230.252261) (xy 443.729463 -230.233467)
			(xy 443.74384 -230.219081) (xy 443.762629 -230.211295) (xy 443.772798 -230.210868) (xy 445.172338 -230.210868)
			(xy 445.182502 -230.211303) (xy 445.201278 -230.219096) (xy 445.215643 -230.233479) (xy 445.22341 -230.252265)
			(xy 445.2239 -230.26243) (xy 445.2239 -230.67137) (xy 451.265036 -230.67137) (xy 451.265036 -230.26243)
			(xy 451.265489 -230.252261) (xy 451.273263 -230.233467) (xy 451.28764 -230.219081) (xy 451.306429 -230.211295)
			(xy 451.316598 -230.210868) (xy 452.716138 -230.210868) (xy 452.726302 -230.211303) (xy 452.745078 -230.219096)
			(xy 452.759443 -230.233479) (xy 452.76721 -230.252265) (xy 452.7677 -230.26243) (xy 452.7677 -230.67137)
			(xy 458.808836 -230.67137) (xy 458.808836 -230.26243) (xy 458.809289 -230.252261) (xy 458.817063 -230.233467)
			(xy 458.83144 -230.219081) (xy 458.850229 -230.211295) (xy 458.860398 -230.210868) (xy 460.259938 -230.210868)
			(xy 460.270102 -230.211303) (xy 460.288878 -230.219096) (xy 460.303243 -230.233479) (xy 460.31101 -230.252265)
			(xy 460.3115 -230.26243) (xy 460.3115 -230.67137) (xy 460.310943 -230.681521) (xy 460.303186 -230.700283)
			(xy 460.28884 -230.714648) (xy 460.270089 -230.72243) (xy 460.259938 -230.722932) (xy 458.860398 -230.722932)
			(xy 458.850223 -230.722537) (xy 458.831422 -230.714746) (xy 458.817036 -230.700351) (xy 458.809257 -230.681546)
			(xy 458.808836 -230.67137) (xy 452.7677 -230.67137) (xy 452.767143 -230.681521) (xy 452.759386 -230.700283)
			(xy 452.74504 -230.714648) (xy 452.726289 -230.72243) (xy 452.716138 -230.722932) (xy 451.316598 -230.722932)
			(xy 451.306423 -230.722537) (xy 451.287622 -230.714746) (xy 451.273236 -230.700351) (xy 451.265457 -230.681546)
			(xy 451.265036 -230.67137) (xy 445.2239 -230.67137) (xy 445.223343 -230.681521) (xy 445.215586 -230.700283)
			(xy 445.20124 -230.714648) (xy 445.182489 -230.72243) (xy 445.172338 -230.722932) (xy 443.772798 -230.722932)
			(xy 443.762623 -230.722537) (xy 443.743822 -230.714746) (xy 443.729436 -230.700351) (xy 443.721657 -230.681546)
			(xy 443.721236 -230.67137) (xy 437.6801 -230.67137) (xy 437.679543 -230.681521) (xy 437.671786 -230.700283)
			(xy 437.65744 -230.714648) (xy 437.638689 -230.72243) (xy 437.628538 -230.722932) (xy 436.228998 -230.722932)
			(xy 436.218823 -230.722537) (xy 436.200022 -230.714746) (xy 436.185636 -230.700351) (xy 436.177857 -230.681546)
			(xy 436.177436 -230.67137) (xy 430.1363 -230.67137) (xy 430.135743 -230.681521) (xy 430.127986 -230.700283)
			(xy 430.11364 -230.714648) (xy 430.094889 -230.72243) (xy 430.084738 -230.722932) (xy 428.685198 -230.722932)
			(xy 428.675023 -230.722537) (xy 428.656222 -230.714746) (xy 428.641836 -230.700351) (xy 428.634057 -230.681546)
			(xy 428.633636 -230.67137) (xy 422.5925 -230.67137) (xy 422.591943 -230.681521) (xy 422.584186 -230.700283)
			(xy 422.56984 -230.714648) (xy 422.551089 -230.72243) (xy 422.540938 -230.722932) (xy 421.141398 -230.722932)
			(xy 421.131223 -230.722537) (xy 421.112422 -230.714746) (xy 421.098036 -230.700351) (xy 421.090257 -230.681546)
			(xy 421.089836 -230.67137) (xy 415.0487 -230.67137) (xy 415.048143 -230.681521) (xy 415.040386 -230.700283)
			(xy 415.02604 -230.714648) (xy 415.007289 -230.72243) (xy 414.997138 -230.722932) (xy 413.597598 -230.722932)
			(xy 413.587423 -230.722537) (xy 413.568622 -230.714746) (xy 413.554236 -230.700351) (xy 413.546457 -230.681546)
			(xy 413.546036 -230.67137) (xy 407.5049 -230.67137) (xy 407.504343 -230.681521) (xy 407.496586 -230.700283)
			(xy 407.48224 -230.714648) (xy 407.463489 -230.72243) (xy 407.453338 -230.722932) (xy 406.053798 -230.722932)
			(xy 406.043623 -230.722537) (xy 406.024822 -230.714746) (xy 406.010436 -230.700351) (xy 406.002657 -230.681546)
			(xy 406.002236 -230.67137) (xy 309.6387 -230.67137) (xy 309.638143 -230.681521) (xy 309.630386 -230.700283)
			(xy 309.61604 -230.714648) (xy 309.597289 -230.72243) (xy 309.587138 -230.722932) (xy 308.187598 -230.722932)
			(xy 308.177423 -230.722537) (xy 308.158622 -230.714746) (xy 308.144236 -230.700351) (xy 308.136457 -230.681546)
			(xy 308.136036 -230.67137) (xy 302.0949 -230.67137) (xy 302.094343 -230.681521) (xy 302.086586 -230.700283)
			(xy 302.07224 -230.714648) (xy 302.053489 -230.72243) (xy 302.043338 -230.722932) (xy 300.643798 -230.722932)
			(xy 300.633623 -230.722537) (xy 300.614822 -230.714746) (xy 300.600436 -230.700351) (xy 300.592657 -230.681546)
			(xy 300.592236 -230.67137) (xy 294.5511 -230.67137) (xy 294.550543 -230.681521) (xy 294.542786 -230.700283)
			(xy 294.52844 -230.714648) (xy 294.509689 -230.72243) (xy 294.499538 -230.722932) (xy 293.099998 -230.722932)
			(xy 293.089823 -230.722537) (xy 293.071022 -230.714746) (xy 293.056636 -230.700351) (xy 293.048857 -230.681546)
			(xy 293.048436 -230.67137) (xy 287.0073 -230.67137) (xy 287.006743 -230.681521) (xy 286.998986 -230.700283)
			(xy 286.98464 -230.714648) (xy 286.965889 -230.72243) (xy 286.955738 -230.722932) (xy 285.556198 -230.722932)
			(xy 285.546023 -230.722537) (xy 285.527222 -230.714746) (xy 285.512836 -230.700351) (xy 285.505057 -230.681546)
			(xy 285.504636 -230.67137) (xy 279.4635 -230.67137) (xy 279.462943 -230.681521) (xy 279.455186 -230.700283)
			(xy 279.44084 -230.714648) (xy 279.422089 -230.72243) (xy 279.411938 -230.722932) (xy 278.012398 -230.722932)
			(xy 278.002223 -230.722537) (xy 277.983422 -230.714746) (xy 277.969036 -230.700351) (xy 277.961257 -230.681546)
			(xy 277.960836 -230.67137) (xy 271.9197 -230.67137) (xy 271.919143 -230.681521) (xy 271.911386 -230.700283)
			(xy 271.89704 -230.714648) (xy 271.878289 -230.72243) (xy 271.868138 -230.722932) (xy 270.468598 -230.722932)
			(xy 270.458423 -230.722537) (xy 270.439622 -230.714746) (xy 270.425236 -230.700351) (xy 270.417457 -230.681546)
			(xy 270.417036 -230.67137) (xy 264.3759 -230.67137) (xy 264.375343 -230.681521) (xy 264.367586 -230.700283)
			(xy 264.35324 -230.714648) (xy 264.334489 -230.72243) (xy 264.324338 -230.722932) (xy 262.924798 -230.722932)
			(xy 262.914623 -230.722537) (xy 262.895822 -230.714746) (xy 262.881436 -230.700351) (xy 262.873657 -230.681546)
			(xy 262.873236 -230.67137) (xy 256.8321 -230.67137) (xy 256.831543 -230.681521) (xy 256.823786 -230.700283)
			(xy 256.80944 -230.714648) (xy 256.790689 -230.72243) (xy 256.780538 -230.722932) (xy 255.380998 -230.722932)
			(xy 255.370823 -230.722537) (xy 255.352022 -230.714746) (xy 255.337636 -230.700351) (xy 255.329857 -230.681546)
			(xy 255.329436 -230.67137) (xy 212.371432 -230.67137) (xy 212.371011 -230.681543) (xy 212.36323 -230.700343)
			(xy 212.348843 -230.71473) (xy 212.330043 -230.722511) (xy 212.31987 -230.722932) (xy 210.92033 -230.722932)
			(xy 210.910157 -230.722511) (xy 210.891357 -230.71473) (xy 210.87697 -230.700343) (xy 210.869189 -230.681543)
			(xy 210.868768 -230.67137) (xy 204.827632 -230.67137) (xy 204.827211 -230.681543) (xy 204.81943 -230.700343)
			(xy 204.805043 -230.71473) (xy 204.786243 -230.722511) (xy 204.77607 -230.722932) (xy 203.37653 -230.722932)
			(xy 203.366357 -230.722511) (xy 203.347557 -230.71473) (xy 203.33317 -230.700343) (xy 203.325389 -230.681543)
			(xy 203.324968 -230.67137) (xy 197.283832 -230.67137) (xy 197.283411 -230.681543) (xy 197.27563 -230.700343)
			(xy 197.261243 -230.71473) (xy 197.242443 -230.722511) (xy 197.23227 -230.722932) (xy 195.83273 -230.722932)
			(xy 195.822557 -230.722511) (xy 195.803757 -230.71473) (xy 195.78937 -230.700343) (xy 195.781589 -230.681543)
			(xy 195.781168 -230.67137) (xy 189.740032 -230.67137) (xy 189.739611 -230.681543) (xy 189.73183 -230.700343)
			(xy 189.717443 -230.71473) (xy 189.698643 -230.722511) (xy 189.68847 -230.722932) (xy 188.28893 -230.722932)
			(xy 188.278757 -230.722511) (xy 188.259957 -230.71473) (xy 188.24557 -230.700343) (xy 188.237789 -230.681543)
			(xy 188.237368 -230.67137) (xy 182.196232 -230.67137) (xy 182.195811 -230.681543) (xy 182.18803 -230.700343)
			(xy 182.173643 -230.71473) (xy 182.154843 -230.722511) (xy 182.14467 -230.722932) (xy 180.74513 -230.722932)
			(xy 180.734957 -230.722511) (xy 180.716157 -230.71473) (xy 180.70177 -230.700343) (xy 180.693989 -230.681543)
			(xy 180.693568 -230.67137) (xy 174.652432 -230.67137) (xy 174.652011 -230.681543) (xy 174.64423 -230.700343)
			(xy 174.629843 -230.71473) (xy 174.611043 -230.722511) (xy 174.60087 -230.722932) (xy 173.20133 -230.722932)
			(xy 173.191157 -230.722511) (xy 173.172357 -230.71473) (xy 173.15797 -230.700343) (xy 173.150189 -230.681543)
			(xy 173.149768 -230.67137) (xy 167.108632 -230.67137) (xy 167.108211 -230.681543) (xy 167.10043 -230.700343)
			(xy 167.086043 -230.71473) (xy 167.067243 -230.722511) (xy 167.05707 -230.722932) (xy 165.65753 -230.722932)
			(xy 165.647357 -230.722511) (xy 165.628557 -230.71473) (xy 165.61417 -230.700343) (xy 165.606389 -230.681543)
			(xy 165.605968 -230.67137) (xy 159.564832 -230.67137) (xy 159.564411 -230.681543) (xy 159.55663 -230.700343)
			(xy 159.542243 -230.71473) (xy 159.523443 -230.722511) (xy 159.51327 -230.722932) (xy 158.11373 -230.722932)
			(xy 158.103557 -230.722511) (xy 158.084757 -230.71473) (xy 158.07037 -230.700343) (xy 158.062589 -230.681543)
			(xy 158.062168 -230.67137) (xy 61.698632 -230.67137) (xy 61.698211 -230.681543) (xy 61.69043 -230.700343)
			(xy 61.676043 -230.71473) (xy 61.657243 -230.722511) (xy 61.64707 -230.722932) (xy 60.24753 -230.722932)
			(xy 60.237357 -230.722511) (xy 60.218557 -230.71473) (xy 60.20417 -230.700343) (xy 60.196389 -230.681543)
			(xy 60.195968 -230.67137) (xy 54.154832 -230.67137) (xy 54.154411 -230.681543) (xy 54.14663 -230.700343)
			(xy 54.132243 -230.71473) (xy 54.113443 -230.722511) (xy 54.10327 -230.722932) (xy 52.70373 -230.722932)
			(xy 52.693557 -230.722511) (xy 52.674757 -230.71473) (xy 52.66037 -230.700343) (xy 52.652589 -230.681543)
			(xy 52.652168 -230.67137) (xy 46.611032 -230.67137) (xy 46.610611 -230.681543) (xy 46.60283 -230.700343)
			(xy 46.588443 -230.71473) (xy 46.569643 -230.722511) (xy 46.55947 -230.722932) (xy 45.15993 -230.722932)
			(xy 45.149757 -230.722511) (xy 45.130957 -230.71473) (xy 45.11657 -230.700343) (xy 45.108789 -230.681543)
			(xy 45.108368 -230.67137) (xy 39.067232 -230.67137) (xy 39.066811 -230.681543) (xy 39.05903 -230.700343)
			(xy 39.044643 -230.71473) (xy 39.025843 -230.722511) (xy 39.01567 -230.722932) (xy 37.61613 -230.722932)
			(xy 37.605957 -230.722511) (xy 37.587157 -230.71473) (xy 37.57277 -230.700343) (xy 37.564989 -230.681543)
			(xy 37.564568 -230.67137) (xy 31.523432 -230.67137) (xy 31.523011 -230.681543) (xy 31.51523 -230.700343)
			(xy 31.500843 -230.71473) (xy 31.482043 -230.722511) (xy 31.47187 -230.722932) (xy 30.07233 -230.722932)
			(xy 30.062157 -230.722511) (xy 30.043357 -230.71473) (xy 30.02897 -230.700343) (xy 30.021189 -230.681543)
			(xy 30.020768 -230.67137) (xy 23.979632 -230.67137) (xy 23.979211 -230.681543) (xy 23.97143 -230.700343)
			(xy 23.957043 -230.71473) (xy 23.938243 -230.722511) (xy 23.92807 -230.722932) (xy 22.52853 -230.722932)
			(xy 22.518357 -230.722511) (xy 22.499557 -230.71473) (xy 22.48517 -230.700343) (xy 22.477389 -230.681543)
			(xy 22.476968 -230.67137) (xy 16.435832 -230.67137) (xy 16.435411 -230.681543) (xy 16.42763 -230.700343)
			(xy 16.413243 -230.71473) (xy 16.394443 -230.722511) (xy 16.38427 -230.722932) (xy 14.98473 -230.722932)
			(xy 14.974557 -230.722511) (xy 14.955757 -230.71473) (xy 14.94137 -230.700343) (xy 14.933589 -230.681543)
			(xy 14.933168 -230.67137) (xy 8.892032 -230.67137) (xy 8.891611 -230.681543) (xy 8.88383 -230.700343)
			(xy 8.869443 -230.71473) (xy 8.850643 -230.722511) (xy 8.84047 -230.722932) (xy 7.44093 -230.722932)
			(xy 7.430757 -230.722511) (xy 7.411957 -230.71473) (xy 7.39757 -230.700343) (xy 7.389789 -230.681543)
			(xy 7.389368 -230.67137) (xy 2.509012 -230.67137) (xy 2.509012 -231.521508) (xy 11.489436 -231.521508)
			(xy 11.489436 -231.112568) (xy 11.489796 -231.102407) (xy 11.497609 -231.083647) (xy 11.512025 -231.069324)
			(xy 11.530835 -231.061632) (xy 11.540998 -231.06126) (xy 12.940538 -231.06126) (xy 12.95067 -231.061696)
			(xy 12.969395 -231.06944) (xy 12.983751 -231.083742) (xy 12.991565 -231.102438) (xy 12.9921 -231.112568)
			(xy 12.9921 -231.521508) (xy 19.033236 -231.521508) (xy 19.033236 -231.112568) (xy 19.033596 -231.102407)
			(xy 19.041409 -231.083647) (xy 19.055825 -231.069324) (xy 19.074635 -231.061632) (xy 19.084798 -231.06126)
			(xy 20.484338 -231.06126) (xy 20.49447 -231.061696) (xy 20.513195 -231.06944) (xy 20.527551 -231.083742)
			(xy 20.535365 -231.102438) (xy 20.5359 -231.112568) (xy 20.5359 -231.521508) (xy 26.577036 -231.521508)
			(xy 26.577036 -231.112568) (xy 26.577396 -231.102407) (xy 26.585209 -231.083647) (xy 26.599625 -231.069324)
			(xy 26.618435 -231.061632) (xy 26.628598 -231.06126) (xy 28.028138 -231.06126) (xy 28.03827 -231.061696)
			(xy 28.056995 -231.06944) (xy 28.071351 -231.083742) (xy 28.079165 -231.102438) (xy 28.0797 -231.112568)
			(xy 28.0797 -231.521508) (xy 34.120836 -231.521508) (xy 34.120836 -231.112568) (xy 34.121196 -231.102407)
			(xy 34.129009 -231.083647) (xy 34.143425 -231.069324) (xy 34.162235 -231.061632) (xy 34.172398 -231.06126)
			(xy 35.571938 -231.06126) (xy 35.58207 -231.061696) (xy 35.600795 -231.06944) (xy 35.615151 -231.083742)
			(xy 35.622965 -231.102438) (xy 35.6235 -231.112568) (xy 35.6235 -231.521508) (xy 41.664636 -231.521508)
			(xy 41.664636 -231.112568) (xy 41.664996 -231.102407) (xy 41.672809 -231.083647) (xy 41.687225 -231.069324)
			(xy 41.706035 -231.061632) (xy 41.716198 -231.06126) (xy 43.115738 -231.06126) (xy 43.12587 -231.061696)
			(xy 43.144595 -231.06944) (xy 43.158951 -231.083742) (xy 43.166765 -231.102438) (xy 43.1673 -231.112568)
			(xy 43.1673 -231.521508) (xy 49.208436 -231.521508) (xy 49.208436 -231.112568) (xy 49.208796 -231.102407)
			(xy 49.216609 -231.083647) (xy 49.231025 -231.069324) (xy 49.249835 -231.061632) (xy 49.259998 -231.06126)
			(xy 50.659538 -231.06126) (xy 50.66967 -231.061696) (xy 50.688395 -231.06944) (xy 50.702751 -231.083742)
			(xy 50.710565 -231.102438) (xy 50.7111 -231.112568) (xy 50.7111 -231.521508) (xy 56.752236 -231.521508)
			(xy 56.752236 -231.112568) (xy 56.752596 -231.102407) (xy 56.760409 -231.083647) (xy 56.774825 -231.069324)
			(xy 56.793635 -231.061632) (xy 56.803798 -231.06126) (xy 58.203338 -231.06126) (xy 58.21347 -231.061696)
			(xy 58.232195 -231.06944) (xy 58.246551 -231.083742) (xy 58.254365 -231.102438) (xy 58.2549 -231.112568)
			(xy 58.2549 -231.521508) (xy 64.296036 -231.521508) (xy 64.296036 -231.112568) (xy 64.296396 -231.102407)
			(xy 64.304209 -231.083647) (xy 64.318625 -231.069324) (xy 64.337435 -231.061632) (xy 64.347598 -231.06126)
			(xy 65.747138 -231.06126) (xy 65.75727 -231.061696) (xy 65.775995 -231.06944) (xy 65.790351 -231.083742)
			(xy 65.798165 -231.102438) (xy 65.7987 -231.112568) (xy 65.7987 -231.521508) (xy 162.162236 -231.521508)
			(xy 162.162236 -231.112568) (xy 162.162596 -231.102407) (xy 162.170409 -231.083647) (xy 162.184825 -231.069324)
			(xy 162.203635 -231.061632) (xy 162.213798 -231.06126) (xy 163.613338 -231.06126) (xy 163.62347 -231.061696)
			(xy 163.642195 -231.06944) (xy 163.656551 -231.083742) (xy 163.664365 -231.102438) (xy 163.6649 -231.112568)
			(xy 163.6649 -231.521508) (xy 169.706036 -231.521508) (xy 169.706036 -231.112568) (xy 169.706396 -231.102407)
			(xy 169.714209 -231.083647) (xy 169.728625 -231.069324) (xy 169.747435 -231.061632) (xy 169.757598 -231.06126)
			(xy 171.157138 -231.06126) (xy 171.16727 -231.061696) (xy 171.185995 -231.06944) (xy 171.200351 -231.083742)
			(xy 171.208165 -231.102438) (xy 171.2087 -231.112568) (xy 171.2087 -231.521508) (xy 177.249836 -231.521508)
			(xy 177.249836 -231.112568) (xy 177.250196 -231.102407) (xy 177.258009 -231.083647) (xy 177.272425 -231.069324)
			(xy 177.291235 -231.061632) (xy 177.301398 -231.06126) (xy 178.700938 -231.06126) (xy 178.71107 -231.061696)
			(xy 178.729795 -231.06944) (xy 178.744151 -231.083742) (xy 178.751965 -231.102438) (xy 178.7525 -231.112568)
			(xy 178.7525 -231.521508) (xy 184.793636 -231.521508) (xy 184.793636 -231.112568) (xy 184.793996 -231.102407)
			(xy 184.801809 -231.083647) (xy 184.816225 -231.069324) (xy 184.835035 -231.061632) (xy 184.845198 -231.06126)
			(xy 186.244738 -231.06126) (xy 186.25487 -231.061696) (xy 186.273595 -231.06944) (xy 186.287951 -231.083742)
			(xy 186.295765 -231.102438) (xy 186.2963 -231.112568) (xy 186.2963 -231.521508) (xy 192.337436 -231.521508)
			(xy 192.337436 -231.112568) (xy 192.337796 -231.102407) (xy 192.345609 -231.083647) (xy 192.360025 -231.069324)
			(xy 192.378835 -231.061632) (xy 192.388998 -231.06126) (xy 193.788538 -231.06126) (xy 193.79867 -231.061696)
			(xy 193.817395 -231.06944) (xy 193.831751 -231.083742) (xy 193.839565 -231.102438) (xy 193.8401 -231.112568)
			(xy 193.8401 -231.521508) (xy 199.881236 -231.521508) (xy 199.881236 -231.112568) (xy 199.881596 -231.102407)
			(xy 199.889409 -231.083647) (xy 199.903825 -231.069324) (xy 199.922635 -231.061632) (xy 199.932798 -231.06126)
			(xy 201.332338 -231.06126) (xy 201.34247 -231.061696) (xy 201.361195 -231.06944) (xy 201.375551 -231.083742)
			(xy 201.383365 -231.102438) (xy 201.3839 -231.112568) (xy 201.3839 -231.521508) (xy 207.425036 -231.521508)
			(xy 207.425036 -231.112568) (xy 207.425396 -231.102407) (xy 207.433209 -231.083647) (xy 207.447625 -231.069324)
			(xy 207.466435 -231.061632) (xy 207.476598 -231.06126) (xy 208.876138 -231.06126) (xy 208.88627 -231.061696)
			(xy 208.904995 -231.06944) (xy 208.919351 -231.083742) (xy 208.927165 -231.102438) (xy 208.9277 -231.112568)
			(xy 208.9277 -231.521508) (xy 214.968836 -231.521508) (xy 214.968836 -231.112568) (xy 214.969196 -231.102407)
			(xy 214.977009 -231.083647) (xy 214.991425 -231.069324) (xy 215.010235 -231.061632) (xy 215.020398 -231.06126)
			(xy 216.419938 -231.06126) (xy 216.43007 -231.061696) (xy 216.448795 -231.06944) (xy 216.463151 -231.083742)
			(xy 216.470965 -231.102438) (xy 216.4715 -231.112568) (xy 216.4715 -231.521508) (xy 259.429504 -231.521508)
			(xy 259.429504 -231.112568) (xy 259.429895 -231.102411) (xy 259.437702 -231.083657) (xy 259.452108 -231.069335)
			(xy 259.470907 -231.061637) (xy 259.481066 -231.06126) (xy 260.880606 -231.06126) (xy 260.890736 -231.061722)
			(xy 260.909461 -231.069456) (xy 260.923817 -231.08375) (xy 260.931633 -231.102441) (xy 260.932168 -231.112568)
			(xy 260.932168 -231.521508) (xy 266.973304 -231.521508) (xy 266.973304 -231.112568) (xy 266.973695 -231.102411)
			(xy 266.981502 -231.083657) (xy 266.995908 -231.069335) (xy 267.014707 -231.061637) (xy 267.024866 -231.06126)
			(xy 268.424406 -231.06126) (xy 268.434536 -231.061722) (xy 268.453261 -231.069456) (xy 268.467617 -231.08375)
			(xy 268.475433 -231.102441) (xy 268.475968 -231.112568) (xy 268.475968 -231.521508) (xy 274.517104 -231.521508)
			(xy 274.517104 -231.112568) (xy 274.517495 -231.102411) (xy 274.525302 -231.083657) (xy 274.539708 -231.069335)
			(xy 274.558507 -231.061637) (xy 274.568666 -231.06126) (xy 275.968206 -231.06126) (xy 275.978336 -231.061722)
			(xy 275.997061 -231.069456) (xy 276.011417 -231.08375) (xy 276.019233 -231.102441) (xy 276.019768 -231.112568)
			(xy 276.019768 -231.521508) (xy 282.060904 -231.521508) (xy 282.060904 -231.112568) (xy 282.061295 -231.102411)
			(xy 282.069102 -231.083657) (xy 282.083508 -231.069335) (xy 282.102307 -231.061637) (xy 282.112466 -231.06126)
			(xy 283.512006 -231.06126) (xy 283.522136 -231.061722) (xy 283.540861 -231.069456) (xy 283.555217 -231.08375)
			(xy 283.563033 -231.102441) (xy 283.563568 -231.112568) (xy 283.563568 -231.521508) (xy 289.604704 -231.521508)
			(xy 289.604704 -231.112568) (xy 289.605095 -231.102411) (xy 289.612902 -231.083657) (xy 289.627308 -231.069335)
			(xy 289.646107 -231.061637) (xy 289.656266 -231.06126) (xy 291.055806 -231.06126) (xy 291.065936 -231.061722)
			(xy 291.084661 -231.069456) (xy 291.099017 -231.08375) (xy 291.106833 -231.102441) (xy 291.107368 -231.112568)
			(xy 291.107368 -231.521508) (xy 297.148504 -231.521508) (xy 297.148504 -231.112568) (xy 297.148895 -231.102411)
			(xy 297.156702 -231.083657) (xy 297.171108 -231.069335) (xy 297.189907 -231.061637) (xy 297.200066 -231.06126)
			(xy 298.599606 -231.06126) (xy 298.609736 -231.061722) (xy 298.628461 -231.069456) (xy 298.642817 -231.08375)
			(xy 298.650633 -231.102441) (xy 298.651168 -231.112568) (xy 298.651168 -231.521508) (xy 304.692304 -231.521508)
			(xy 304.692304 -231.112568) (xy 304.692695 -231.102411) (xy 304.700502 -231.083657) (xy 304.714908 -231.069335)
			(xy 304.733707 -231.061637) (xy 304.743866 -231.06126) (xy 306.143406 -231.06126) (xy 306.153536 -231.061722)
			(xy 306.172261 -231.069456) (xy 306.186617 -231.08375) (xy 306.194433 -231.102441) (xy 306.194968 -231.112568)
			(xy 306.194968 -231.521508) (xy 312.236104 -231.521508) (xy 312.236104 -231.112568) (xy 312.236495 -231.102411)
			(xy 312.244302 -231.083657) (xy 312.258708 -231.069335) (xy 312.277507 -231.061637) (xy 312.287666 -231.06126)
			(xy 313.687206 -231.06126) (xy 313.697336 -231.061722) (xy 313.716061 -231.069456) (xy 313.730417 -231.08375)
			(xy 313.738233 -231.102441) (xy 313.738768 -231.112568) (xy 313.738768 -231.521508) (xy 410.102304 -231.521508)
			(xy 410.102304 -231.112568) (xy 410.102695 -231.102411) (xy 410.110502 -231.083657) (xy 410.124908 -231.069335)
			(xy 410.143707 -231.061637) (xy 410.153866 -231.06126) (xy 411.553406 -231.06126) (xy 411.563536 -231.061722)
			(xy 411.582261 -231.069456) (xy 411.596617 -231.08375) (xy 411.604433 -231.102441) (xy 411.604968 -231.112568)
			(xy 411.604968 -231.521508) (xy 417.646104 -231.521508) (xy 417.646104 -231.112568) (xy 417.646495 -231.102411)
			(xy 417.654302 -231.083657) (xy 417.668708 -231.069335) (xy 417.687507 -231.061637) (xy 417.697666 -231.06126)
			(xy 419.097206 -231.06126) (xy 419.107336 -231.061722) (xy 419.126061 -231.069456) (xy 419.140417 -231.08375)
			(xy 419.148233 -231.102441) (xy 419.148768 -231.112568) (xy 419.148768 -231.521508) (xy 425.189904 -231.521508)
			(xy 425.189904 -231.112568) (xy 425.190295 -231.102411) (xy 425.198102 -231.083657) (xy 425.212508 -231.069335)
			(xy 425.231307 -231.061637) (xy 425.241466 -231.06126) (xy 426.641006 -231.06126) (xy 426.651136 -231.061722)
			(xy 426.669861 -231.069456) (xy 426.684217 -231.08375) (xy 426.692033 -231.102441) (xy 426.692568 -231.112568)
			(xy 426.692568 -231.521508) (xy 432.733704 -231.521508) (xy 432.733704 -231.112568) (xy 432.734095 -231.102411)
			(xy 432.741902 -231.083657) (xy 432.756308 -231.069335) (xy 432.775107 -231.061637) (xy 432.785266 -231.06126)
			(xy 434.184806 -231.06126) (xy 434.194936 -231.061722) (xy 434.213661 -231.069456) (xy 434.228017 -231.08375)
			(xy 434.235833 -231.102441) (xy 434.236368 -231.112568) (xy 434.236368 -231.521508) (xy 440.277504 -231.521508)
			(xy 440.277504 -231.112568) (xy 440.277895 -231.102411) (xy 440.285702 -231.083657) (xy 440.300108 -231.069335)
			(xy 440.318907 -231.061637) (xy 440.329066 -231.06126) (xy 441.728606 -231.06126) (xy 441.738736 -231.061722)
			(xy 441.757461 -231.069456) (xy 441.771817 -231.08375) (xy 441.779633 -231.102441) (xy 441.780168 -231.112568)
			(xy 441.780168 -231.521508) (xy 447.821304 -231.521508) (xy 447.821304 -231.112568) (xy 447.821695 -231.102411)
			(xy 447.829502 -231.083657) (xy 447.843908 -231.069335) (xy 447.862707 -231.061637) (xy 447.872866 -231.06126)
			(xy 449.272406 -231.06126) (xy 449.282536 -231.061722) (xy 449.301261 -231.069456) (xy 449.315617 -231.08375)
			(xy 449.323433 -231.102441) (xy 449.323968 -231.112568) (xy 449.323968 -231.521508) (xy 455.365104 -231.521508)
			(xy 455.365104 -231.112568) (xy 455.365495 -231.102411) (xy 455.373302 -231.083657) (xy 455.387708 -231.069335)
			(xy 455.406507 -231.061637) (xy 455.416666 -231.06126) (xy 456.816206 -231.06126) (xy 456.826336 -231.061722)
			(xy 456.845061 -231.069456) (xy 456.859417 -231.08375) (xy 456.867233 -231.102441) (xy 456.867768 -231.112568)
			(xy 456.867768 -231.521508) (xy 462.908904 -231.521508) (xy 462.908904 -231.112568) (xy 462.909295 -231.102411)
			(xy 462.917102 -231.083657) (xy 462.931508 -231.069335) (xy 462.950307 -231.061637) (xy 462.960466 -231.06126)
			(xy 464.360006 -231.06126) (xy 464.370136 -231.061722) (xy 464.388861 -231.069456) (xy 464.403217 -231.08375)
			(xy 464.411033 -231.102441) (xy 464.411568 -231.112568) (xy 464.411568 -231.521508) (xy 464.411184 -231.531667)
			(xy 464.40338 -231.550425) (xy 464.388971 -231.564749) (xy 464.370167 -231.572443) (xy 464.360006 -231.572816)
			(xy 462.960466 -231.572816) (xy 462.950332 -231.5724) (xy 462.931601 -231.564653) (xy 462.917245 -231.550345)
			(xy 462.909435 -231.531641) (xy 462.908904 -231.521508) (xy 456.867768 -231.521508) (xy 456.867384 -231.531667)
			(xy 456.85958 -231.550425) (xy 456.845171 -231.564749) (xy 456.826367 -231.572443) (xy 456.816206 -231.572816)
			(xy 455.416666 -231.572816) (xy 455.406532 -231.5724) (xy 455.387801 -231.564653) (xy 455.373445 -231.550345)
			(xy 455.365635 -231.531641) (xy 455.365104 -231.521508) (xy 449.323968 -231.521508) (xy 449.323584 -231.531667)
			(xy 449.31578 -231.550425) (xy 449.301371 -231.564749) (xy 449.282567 -231.572443) (xy 449.272406 -231.572816)
			(xy 447.872866 -231.572816) (xy 447.862732 -231.5724) (xy 447.844001 -231.564653) (xy 447.829645 -231.550345)
			(xy 447.821835 -231.531641) (xy 447.821304 -231.521508) (xy 441.780168 -231.521508) (xy 441.779784 -231.531667)
			(xy 441.77198 -231.550425) (xy 441.757571 -231.564749) (xy 441.738767 -231.572443) (xy 441.728606 -231.572816)
			(xy 440.329066 -231.572816) (xy 440.318932 -231.5724) (xy 440.300201 -231.564653) (xy 440.285845 -231.550345)
			(xy 440.278035 -231.531641) (xy 440.277504 -231.521508) (xy 434.236368 -231.521508) (xy 434.235984 -231.531667)
			(xy 434.22818 -231.550425) (xy 434.213771 -231.564749) (xy 434.194967 -231.572443) (xy 434.184806 -231.572816)
			(xy 432.785266 -231.572816) (xy 432.775132 -231.5724) (xy 432.756401 -231.564653) (xy 432.742045 -231.550345)
			(xy 432.734235 -231.531641) (xy 432.733704 -231.521508) (xy 426.692568 -231.521508) (xy 426.692184 -231.531667)
			(xy 426.68438 -231.550425) (xy 426.669971 -231.564749) (xy 426.651167 -231.572443) (xy 426.641006 -231.572816)
			(xy 425.241466 -231.572816) (xy 425.231332 -231.5724) (xy 425.212601 -231.564653) (xy 425.198245 -231.550345)
			(xy 425.190435 -231.531641) (xy 425.189904 -231.521508) (xy 419.148768 -231.521508) (xy 419.148384 -231.531667)
			(xy 419.14058 -231.550425) (xy 419.126171 -231.564749) (xy 419.107367 -231.572443) (xy 419.097206 -231.572816)
			(xy 417.697666 -231.572816) (xy 417.687532 -231.5724) (xy 417.668801 -231.564653) (xy 417.654445 -231.550345)
			(xy 417.646635 -231.531641) (xy 417.646104 -231.521508) (xy 411.604968 -231.521508) (xy 411.604584 -231.531667)
			(xy 411.59678 -231.550425) (xy 411.582371 -231.564749) (xy 411.563567 -231.572443) (xy 411.553406 -231.572816)
			(xy 410.153866 -231.572816) (xy 410.143732 -231.5724) (xy 410.125001 -231.564653) (xy 410.110645 -231.550345)
			(xy 410.102835 -231.531641) (xy 410.102304 -231.521508) (xy 313.738768 -231.521508) (xy 313.738384 -231.531667)
			(xy 313.73058 -231.550425) (xy 313.716171 -231.564749) (xy 313.697367 -231.572443) (xy 313.687206 -231.572816)
			(xy 312.287666 -231.572816) (xy 312.277532 -231.5724) (xy 312.258801 -231.564653) (xy 312.244445 -231.550345)
			(xy 312.236635 -231.531641) (xy 312.236104 -231.521508) (xy 306.194968 -231.521508) (xy 306.194584 -231.531667)
			(xy 306.18678 -231.550425) (xy 306.172371 -231.564749) (xy 306.153567 -231.572443) (xy 306.143406 -231.572816)
			(xy 304.743866 -231.572816) (xy 304.733732 -231.5724) (xy 304.715001 -231.564653) (xy 304.700645 -231.550345)
			(xy 304.692835 -231.531641) (xy 304.692304 -231.521508) (xy 298.651168 -231.521508) (xy 298.650784 -231.531667)
			(xy 298.64298 -231.550425) (xy 298.628571 -231.564749) (xy 298.609767 -231.572443) (xy 298.599606 -231.572816)
			(xy 297.200066 -231.572816) (xy 297.189932 -231.5724) (xy 297.171201 -231.564653) (xy 297.156845 -231.550345)
			(xy 297.149035 -231.531641) (xy 297.148504 -231.521508) (xy 291.107368 -231.521508) (xy 291.106984 -231.531667)
			(xy 291.09918 -231.550425) (xy 291.084771 -231.564749) (xy 291.065967 -231.572443) (xy 291.055806 -231.572816)
			(xy 289.656266 -231.572816) (xy 289.646132 -231.5724) (xy 289.627401 -231.564653) (xy 289.613045 -231.550345)
			(xy 289.605235 -231.531641) (xy 289.604704 -231.521508) (xy 283.563568 -231.521508) (xy 283.563184 -231.531667)
			(xy 283.55538 -231.550425) (xy 283.540971 -231.564749) (xy 283.522167 -231.572443) (xy 283.512006 -231.572816)
			(xy 282.112466 -231.572816) (xy 282.102332 -231.5724) (xy 282.083601 -231.564653) (xy 282.069245 -231.550345)
			(xy 282.061435 -231.531641) (xy 282.060904 -231.521508) (xy 276.019768 -231.521508) (xy 276.019384 -231.531667)
			(xy 276.01158 -231.550425) (xy 275.997171 -231.564749) (xy 275.978367 -231.572443) (xy 275.968206 -231.572816)
			(xy 274.568666 -231.572816) (xy 274.558532 -231.5724) (xy 274.539801 -231.564653) (xy 274.525445 -231.550345)
			(xy 274.517635 -231.531641) (xy 274.517104 -231.521508) (xy 268.475968 -231.521508) (xy 268.475584 -231.531667)
			(xy 268.46778 -231.550425) (xy 268.453371 -231.564749) (xy 268.434567 -231.572443) (xy 268.424406 -231.572816)
			(xy 267.024866 -231.572816) (xy 267.014732 -231.5724) (xy 266.996001 -231.564653) (xy 266.981645 -231.550345)
			(xy 266.973835 -231.531641) (xy 266.973304 -231.521508) (xy 260.932168 -231.521508) (xy 260.931784 -231.531667)
			(xy 260.92398 -231.550425) (xy 260.909571 -231.564749) (xy 260.890767 -231.572443) (xy 260.880606 -231.572816)
			(xy 259.481066 -231.572816) (xy 259.470932 -231.5724) (xy 259.452201 -231.564653) (xy 259.437845 -231.550345)
			(xy 259.430035 -231.531641) (xy 259.429504 -231.521508) (xy 216.4715 -231.521508) (xy 216.471085 -231.531663)
			(xy 216.463287 -231.550415) (xy 216.448888 -231.564738) (xy 216.430095 -231.572438) (xy 216.419938 -231.572816)
			(xy 215.020398 -231.572816) (xy 215.010266 -231.572374) (xy 214.991536 -231.564637) (xy 214.977179 -231.550337)
			(xy 214.969367 -231.531638) (xy 214.968836 -231.521508) (xy 208.9277 -231.521508) (xy 208.927285 -231.531663)
			(xy 208.919487 -231.550415) (xy 208.905088 -231.564738) (xy 208.886295 -231.572438) (xy 208.876138 -231.572816)
			(xy 207.476598 -231.572816) (xy 207.466466 -231.572374) (xy 207.447736 -231.564637) (xy 207.433379 -231.550337)
			(xy 207.425567 -231.531638) (xy 207.425036 -231.521508) (xy 201.3839 -231.521508) (xy 201.383485 -231.531663)
			(xy 201.375687 -231.550415) (xy 201.361288 -231.564738) (xy 201.342495 -231.572438) (xy 201.332338 -231.572816)
			(xy 199.932798 -231.572816) (xy 199.922666 -231.572374) (xy 199.903936 -231.564637) (xy 199.889579 -231.550337)
			(xy 199.881767 -231.531638) (xy 199.881236 -231.521508) (xy 193.8401 -231.521508) (xy 193.839685 -231.531663)
			(xy 193.831887 -231.550415) (xy 193.817488 -231.564738) (xy 193.798695 -231.572438) (xy 193.788538 -231.572816)
			(xy 192.388998 -231.572816) (xy 192.378866 -231.572374) (xy 192.360136 -231.564637) (xy 192.345779 -231.550337)
			(xy 192.337967 -231.531638) (xy 192.337436 -231.521508) (xy 186.2963 -231.521508) (xy 186.295885 -231.531663)
			(xy 186.288087 -231.550415) (xy 186.273688 -231.564738) (xy 186.254895 -231.572438) (xy 186.244738 -231.572816)
			(xy 184.845198 -231.572816) (xy 184.835066 -231.572374) (xy 184.816336 -231.564637) (xy 184.801979 -231.550337)
			(xy 184.794167 -231.531638) (xy 184.793636 -231.521508) (xy 178.7525 -231.521508) (xy 178.752085 -231.531663)
			(xy 178.744287 -231.550415) (xy 178.729888 -231.564738) (xy 178.711095 -231.572438) (xy 178.700938 -231.572816)
			(xy 177.301398 -231.572816) (xy 177.291266 -231.572374) (xy 177.272536 -231.564637) (xy 177.258179 -231.550337)
			(xy 177.250367 -231.531638) (xy 177.249836 -231.521508) (xy 171.2087 -231.521508) (xy 171.208285 -231.531663)
			(xy 171.200487 -231.550415) (xy 171.186088 -231.564738) (xy 171.167295 -231.572438) (xy 171.157138 -231.572816)
			(xy 169.757598 -231.572816) (xy 169.747466 -231.572374) (xy 169.728736 -231.564637) (xy 169.714379 -231.550337)
			(xy 169.706567 -231.531638) (xy 169.706036 -231.521508) (xy 163.6649 -231.521508) (xy 163.664485 -231.531663)
			(xy 163.656687 -231.550415) (xy 163.642288 -231.564738) (xy 163.623495 -231.572438) (xy 163.613338 -231.572816)
			(xy 162.213798 -231.572816) (xy 162.203666 -231.572374) (xy 162.184936 -231.564637) (xy 162.170579 -231.550337)
			(xy 162.162767 -231.531638) (xy 162.162236 -231.521508) (xy 65.7987 -231.521508) (xy 65.798285 -231.531663)
			(xy 65.790487 -231.550415) (xy 65.776088 -231.564738) (xy 65.757295 -231.572438) (xy 65.747138 -231.572816)
			(xy 64.347598 -231.572816) (xy 64.337466 -231.572374) (xy 64.318736 -231.564637) (xy 64.304379 -231.550337)
			(xy 64.296567 -231.531638) (xy 64.296036 -231.521508) (xy 58.2549 -231.521508) (xy 58.254485 -231.531663)
			(xy 58.246687 -231.550415) (xy 58.232288 -231.564738) (xy 58.213495 -231.572438) (xy 58.203338 -231.572816)
			(xy 56.803798 -231.572816) (xy 56.793666 -231.572374) (xy 56.774936 -231.564637) (xy 56.760579 -231.550337)
			(xy 56.752767 -231.531638) (xy 56.752236 -231.521508) (xy 50.7111 -231.521508) (xy 50.710685 -231.531663)
			(xy 50.702887 -231.550415) (xy 50.688488 -231.564738) (xy 50.669695 -231.572438) (xy 50.659538 -231.572816)
			(xy 49.259998 -231.572816) (xy 49.249866 -231.572374) (xy 49.231136 -231.564637) (xy 49.216779 -231.550337)
			(xy 49.208967 -231.531638) (xy 49.208436 -231.521508) (xy 43.1673 -231.521508) (xy 43.166885 -231.531663)
			(xy 43.159087 -231.550415) (xy 43.144688 -231.564738) (xy 43.125895 -231.572438) (xy 43.115738 -231.572816)
			(xy 41.716198 -231.572816) (xy 41.706066 -231.572374) (xy 41.687336 -231.564637) (xy 41.672979 -231.550337)
			(xy 41.665167 -231.531638) (xy 41.664636 -231.521508) (xy 35.6235 -231.521508) (xy 35.623085 -231.531663)
			(xy 35.615287 -231.550415) (xy 35.600888 -231.564738) (xy 35.582095 -231.572438) (xy 35.571938 -231.572816)
			(xy 34.172398 -231.572816) (xy 34.162266 -231.572374) (xy 34.143536 -231.564637) (xy 34.129179 -231.550337)
			(xy 34.121367 -231.531638) (xy 34.120836 -231.521508) (xy 28.0797 -231.521508) (xy 28.079285 -231.531663)
			(xy 28.071487 -231.550415) (xy 28.057088 -231.564738) (xy 28.038295 -231.572438) (xy 28.028138 -231.572816)
			(xy 26.628598 -231.572816) (xy 26.618466 -231.572374) (xy 26.599736 -231.564637) (xy 26.585379 -231.550337)
			(xy 26.577567 -231.531638) (xy 26.577036 -231.521508) (xy 20.5359 -231.521508) (xy 20.535485 -231.531663)
			(xy 20.527687 -231.550415) (xy 20.513288 -231.564738) (xy 20.494495 -231.572438) (xy 20.484338 -231.572816)
			(xy 19.084798 -231.572816) (xy 19.074666 -231.572374) (xy 19.055936 -231.564637) (xy 19.041579 -231.550337)
			(xy 19.033767 -231.531638) (xy 19.033236 -231.521508) (xy 12.9921 -231.521508) (xy 12.991685 -231.531663)
			(xy 12.983887 -231.550415) (xy 12.969488 -231.564738) (xy 12.950695 -231.572438) (xy 12.940538 -231.572816)
			(xy 11.540998 -231.572816) (xy 11.530866 -231.572374) (xy 11.512136 -231.564637) (xy 11.497779 -231.550337)
			(xy 11.489967 -231.531638) (xy 11.489436 -231.521508) (xy 2.509012 -231.521508) (xy 2.509012 -232.371392)
			(xy 7.389368 -232.371392) (xy 7.389368 -231.962452) (xy 7.389782 -231.952299) (xy 7.397587 -231.933552)
			(xy 7.411985 -231.919231) (xy 7.430775 -231.911527) (xy 7.44093 -231.911144) (xy 8.84047 -231.911144)
			(xy 8.850595 -231.911651) (xy 8.869317 -231.91937) (xy 8.883674 -231.93365) (xy 8.891494 -231.952329)
			(xy 8.892032 -231.962452) (xy 8.892032 -232.371392) (xy 14.933168 -232.371392) (xy 14.933168 -231.962452)
			(xy 14.933582 -231.952299) (xy 14.941387 -231.933552) (xy 14.955785 -231.919231) (xy 14.974575 -231.911527)
			(xy 14.98473 -231.911144) (xy 16.38427 -231.911144) (xy 16.394395 -231.911651) (xy 16.413117 -231.91937)
			(xy 16.427474 -231.93365) (xy 16.435294 -231.952329) (xy 16.435832 -231.962452) (xy 16.435832 -232.371392)
			(xy 22.476968 -232.371392) (xy 22.476968 -231.962452) (xy 22.477382 -231.952299) (xy 22.485187 -231.933552)
			(xy 22.499585 -231.919231) (xy 22.518375 -231.911527) (xy 22.52853 -231.911144) (xy 23.92807 -231.911144)
			(xy 23.938195 -231.911651) (xy 23.956917 -231.91937) (xy 23.971274 -231.93365) (xy 23.979094 -231.952329)
			(xy 23.979632 -231.962452) (xy 23.979632 -232.371392) (xy 30.020768 -232.371392) (xy 30.020768 -231.962452)
			(xy 30.021182 -231.952299) (xy 30.028987 -231.933552) (xy 30.043385 -231.919231) (xy 30.062175 -231.911527)
			(xy 30.07233 -231.911144) (xy 31.47187 -231.911144) (xy 31.481995 -231.911651) (xy 31.500717 -231.91937)
			(xy 31.515074 -231.93365) (xy 31.522894 -231.952329) (xy 31.523432 -231.962452) (xy 31.523432 -232.371392)
			(xy 37.564568 -232.371392) (xy 37.564568 -231.962452) (xy 37.564982 -231.952299) (xy 37.572787 -231.933552)
			(xy 37.587185 -231.919231) (xy 37.605975 -231.911527) (xy 37.61613 -231.911144) (xy 39.01567 -231.911144)
			(xy 39.025795 -231.911651) (xy 39.044517 -231.91937) (xy 39.058874 -231.93365) (xy 39.066694 -231.952329)
			(xy 39.067232 -231.962452) (xy 39.067232 -232.371392) (xy 45.108368 -232.371392) (xy 45.108368 -231.962452)
			(xy 45.108782 -231.952299) (xy 45.116587 -231.933552) (xy 45.130985 -231.919231) (xy 45.149775 -231.911527)
			(xy 45.15993 -231.911144) (xy 46.55947 -231.911144) (xy 46.569595 -231.911651) (xy 46.588317 -231.91937)
			(xy 46.602674 -231.93365) (xy 46.610494 -231.952329) (xy 46.611032 -231.962452) (xy 46.611032 -232.371392)
			(xy 52.652168 -232.371392) (xy 52.652168 -231.962452) (xy 52.652582 -231.952299) (xy 52.660387 -231.933552)
			(xy 52.674785 -231.919231) (xy 52.693575 -231.911527) (xy 52.70373 -231.911144) (xy 54.10327 -231.911144)
			(xy 54.113395 -231.911651) (xy 54.132117 -231.91937) (xy 54.146474 -231.93365) (xy 54.154294 -231.952329)
			(xy 54.154832 -231.962452) (xy 54.154832 -232.371392) (xy 60.195968 -232.371392) (xy 60.195968 -231.962452)
			(xy 60.196382 -231.952299) (xy 60.204187 -231.933552) (xy 60.218585 -231.919231) (xy 60.237375 -231.911527)
			(xy 60.24753 -231.911144) (xy 61.64707 -231.911144) (xy 61.657195 -231.911651) (xy 61.675917 -231.91937)
			(xy 61.690274 -231.93365) (xy 61.698094 -231.952329) (xy 61.698632 -231.962452) (xy 61.698632 -232.371392)
			(xy 158.062168 -232.371392) (xy 158.062168 -231.962452) (xy 158.062582 -231.952299) (xy 158.070387 -231.933552)
			(xy 158.084785 -231.919231) (xy 158.103575 -231.911527) (xy 158.11373 -231.911144) (xy 159.51327 -231.911144)
			(xy 159.523395 -231.911651) (xy 159.542117 -231.91937) (xy 159.556474 -231.93365) (xy 159.564294 -231.952329)
			(xy 159.564832 -231.962452) (xy 159.564832 -232.371392) (xy 165.605968 -232.371392) (xy 165.605968 -231.962452)
			(xy 165.606382 -231.952299) (xy 165.614187 -231.933552) (xy 165.628585 -231.919231) (xy 165.647375 -231.911527)
			(xy 165.65753 -231.911144) (xy 167.05707 -231.911144) (xy 167.067195 -231.911651) (xy 167.085917 -231.91937)
			(xy 167.100274 -231.93365) (xy 167.108094 -231.952329) (xy 167.108632 -231.962452) (xy 167.108632 -232.371392)
			(xy 173.149768 -232.371392) (xy 173.149768 -231.962452) (xy 173.150182 -231.952299) (xy 173.157987 -231.933552)
			(xy 173.172385 -231.919231) (xy 173.191175 -231.911527) (xy 173.20133 -231.911144) (xy 174.60087 -231.911144)
			(xy 174.610995 -231.911651) (xy 174.629717 -231.91937) (xy 174.644074 -231.93365) (xy 174.651894 -231.952329)
			(xy 174.652432 -231.962452) (xy 174.652432 -232.371392) (xy 180.693568 -232.371392) (xy 180.693568 -231.962452)
			(xy 180.693982 -231.952299) (xy 180.701787 -231.933552) (xy 180.716185 -231.919231) (xy 180.734975 -231.911527)
			(xy 180.74513 -231.911144) (xy 182.14467 -231.911144) (xy 182.154795 -231.911651) (xy 182.173517 -231.91937)
			(xy 182.187874 -231.93365) (xy 182.195694 -231.952329) (xy 182.196232 -231.962452) (xy 182.196232 -232.371392)
			(xy 188.237368 -232.371392) (xy 188.237368 -231.962452) (xy 188.237782 -231.952299) (xy 188.245587 -231.933552)
			(xy 188.259985 -231.919231) (xy 188.278775 -231.911527) (xy 188.28893 -231.911144) (xy 189.68847 -231.911144)
			(xy 189.698595 -231.911651) (xy 189.717317 -231.91937) (xy 189.731674 -231.93365) (xy 189.739494 -231.952329)
			(xy 189.740032 -231.962452) (xy 189.740032 -232.371392) (xy 195.781168 -232.371392) (xy 195.781168 -231.962452)
			(xy 195.781582 -231.952299) (xy 195.789387 -231.933552) (xy 195.803785 -231.919231) (xy 195.822575 -231.911527)
			(xy 195.83273 -231.911144) (xy 197.23227 -231.911144) (xy 197.242395 -231.911651) (xy 197.261117 -231.91937)
			(xy 197.275474 -231.93365) (xy 197.283294 -231.952329) (xy 197.283832 -231.962452) (xy 197.283832 -232.371392)
			(xy 203.324968 -232.371392) (xy 203.324968 -231.962452) (xy 203.325382 -231.952299) (xy 203.333187 -231.933552)
			(xy 203.347585 -231.919231) (xy 203.366375 -231.911527) (xy 203.37653 -231.911144) (xy 204.77607 -231.911144)
			(xy 204.786195 -231.911651) (xy 204.804917 -231.91937) (xy 204.819274 -231.93365) (xy 204.827094 -231.952329)
			(xy 204.827632 -231.962452) (xy 204.827632 -232.371392) (xy 210.868768 -232.371392) (xy 210.868768 -231.962452)
			(xy 210.869182 -231.952299) (xy 210.876987 -231.933552) (xy 210.891385 -231.919231) (xy 210.910175 -231.911527)
			(xy 210.92033 -231.911144) (xy 212.31987 -231.911144) (xy 212.329995 -231.911651) (xy 212.348717 -231.91937)
			(xy 212.363074 -231.93365) (xy 212.370894 -231.952329) (xy 212.371432 -231.962452) (xy 212.371432 -232.371392)
			(xy 255.329436 -232.371392) (xy 255.329436 -231.962452) (xy 255.329783 -231.95229) (xy 255.337601 -231.93353)
			(xy 255.352021 -231.919207) (xy 255.370834 -231.911516) (xy 255.380998 -231.911144) (xy 256.780538 -231.911144)
			(xy 256.790668 -231.911596) (xy 256.80939 -231.919337) (xy 256.823746 -231.933633) (xy 256.831563 -231.952324)
			(xy 256.8321 -231.962452) (xy 256.8321 -232.371392) (xy 262.873236 -232.371392) (xy 262.873236 -231.962452)
			(xy 262.873583 -231.95229) (xy 262.881401 -231.93353) (xy 262.895821 -231.919207) (xy 262.914634 -231.911516)
			(xy 262.924798 -231.911144) (xy 264.324338 -231.911144) (xy 264.334468 -231.911596) (xy 264.35319 -231.919337)
			(xy 264.367546 -231.933633) (xy 264.375363 -231.952324) (xy 264.3759 -231.962452) (xy 264.3759 -232.371392)
			(xy 270.417036 -232.371392) (xy 270.417036 -231.962452) (xy 270.417383 -231.95229) (xy 270.425201 -231.93353)
			(xy 270.439621 -231.919207) (xy 270.458434 -231.911516) (xy 270.468598 -231.911144) (xy 271.868138 -231.911144)
			(xy 271.878268 -231.911596) (xy 271.89699 -231.919337) (xy 271.911346 -231.933633) (xy 271.919163 -231.952324)
			(xy 271.9197 -231.962452) (xy 271.9197 -232.371392) (xy 277.960836 -232.371392) (xy 277.960836 -231.962452)
			(xy 277.961183 -231.95229) (xy 277.969001 -231.93353) (xy 277.983421 -231.919207) (xy 278.002234 -231.911516)
			(xy 278.012398 -231.911144) (xy 279.411938 -231.911144) (xy 279.422068 -231.911596) (xy 279.44079 -231.919337)
			(xy 279.455146 -231.933633) (xy 279.462963 -231.952324) (xy 279.4635 -231.962452) (xy 279.4635 -232.371392)
			(xy 285.504636 -232.371392) (xy 285.504636 -231.962452) (xy 285.504983 -231.95229) (xy 285.512801 -231.93353)
			(xy 285.527221 -231.919207) (xy 285.546034 -231.911516) (xy 285.556198 -231.911144) (xy 286.955738 -231.911144)
			(xy 286.965868 -231.911596) (xy 286.98459 -231.919337) (xy 286.998946 -231.933633) (xy 287.006763 -231.952324)
			(xy 287.0073 -231.962452) (xy 287.0073 -232.371392) (xy 293.048436 -232.371392) (xy 293.048436 -231.962452)
			(xy 293.048783 -231.95229) (xy 293.056601 -231.93353) (xy 293.071021 -231.919207) (xy 293.089834 -231.911516)
			(xy 293.099998 -231.911144) (xy 294.499538 -231.911144) (xy 294.509668 -231.911596) (xy 294.52839 -231.919337)
			(xy 294.542746 -231.933633) (xy 294.550563 -231.952324) (xy 294.5511 -231.962452) (xy 294.5511 -232.371392)
			(xy 300.592236 -232.371392) (xy 300.592236 -231.962452) (xy 300.592583 -231.95229) (xy 300.600401 -231.93353)
			(xy 300.614821 -231.919207) (xy 300.633634 -231.911516) (xy 300.643798 -231.911144) (xy 302.043338 -231.911144)
			(xy 302.053468 -231.911596) (xy 302.07219 -231.919337) (xy 302.086546 -231.933633) (xy 302.094363 -231.952324)
			(xy 302.0949 -231.962452) (xy 302.0949 -232.371392) (xy 308.136036 -232.371392) (xy 308.136036 -231.962452)
			(xy 308.136383 -231.95229) (xy 308.144201 -231.93353) (xy 308.158621 -231.919207) (xy 308.177434 -231.911516)
			(xy 308.187598 -231.911144) (xy 309.587138 -231.911144) (xy 309.597268 -231.911596) (xy 309.61599 -231.919337)
			(xy 309.630346 -231.933633) (xy 309.638163 -231.952324) (xy 309.6387 -231.962452) (xy 309.6387 -232.371392)
			(xy 406.002236 -232.371392) (xy 406.002236 -231.962452) (xy 406.002583 -231.95229) (xy 406.010401 -231.93353)
			(xy 406.024821 -231.919207) (xy 406.043634 -231.911516) (xy 406.053798 -231.911144) (xy 407.453338 -231.911144)
			(xy 407.463468 -231.911596) (xy 407.48219 -231.919337) (xy 407.496546 -231.933633) (xy 407.504363 -231.952324)
			(xy 407.5049 -231.962452) (xy 407.5049 -232.371392) (xy 413.546036 -232.371392) (xy 413.546036 -231.962452)
			(xy 413.546383 -231.95229) (xy 413.554201 -231.93353) (xy 413.568621 -231.919207) (xy 413.587434 -231.911516)
			(xy 413.597598 -231.911144) (xy 414.997138 -231.911144) (xy 415.007268 -231.911596) (xy 415.02599 -231.919337)
			(xy 415.040346 -231.933633) (xy 415.048163 -231.952324) (xy 415.0487 -231.962452) (xy 415.0487 -232.371392)
			(xy 421.089836 -232.371392) (xy 421.089836 -231.962452) (xy 421.090183 -231.95229) (xy 421.098001 -231.93353)
			(xy 421.112421 -231.919207) (xy 421.131234 -231.911516) (xy 421.141398 -231.911144) (xy 422.540938 -231.911144)
			(xy 422.551068 -231.911596) (xy 422.56979 -231.919337) (xy 422.584146 -231.933633) (xy 422.591963 -231.952324)
			(xy 422.5925 -231.962452) (xy 422.5925 -232.371392) (xy 428.633636 -232.371392) (xy 428.633636 -231.962452)
			(xy 428.633983 -231.95229) (xy 428.641801 -231.93353) (xy 428.656221 -231.919207) (xy 428.675034 -231.911516)
			(xy 428.685198 -231.911144) (xy 430.084738 -231.911144) (xy 430.094868 -231.911596) (xy 430.11359 -231.919337)
			(xy 430.127946 -231.933633) (xy 430.135763 -231.952324) (xy 430.1363 -231.962452) (xy 430.1363 -232.371392)
			(xy 436.177436 -232.371392) (xy 436.177436 -231.962452) (xy 436.177783 -231.95229) (xy 436.185601 -231.93353)
			(xy 436.200021 -231.919207) (xy 436.218834 -231.911516) (xy 436.228998 -231.911144) (xy 437.628538 -231.911144)
			(xy 437.638668 -231.911596) (xy 437.65739 -231.919337) (xy 437.671746 -231.933633) (xy 437.679563 -231.952324)
			(xy 437.6801 -231.962452) (xy 437.6801 -232.371392) (xy 443.721236 -232.371392) (xy 443.721236 -231.962452)
			(xy 443.721583 -231.95229) (xy 443.729401 -231.93353) (xy 443.743821 -231.919207) (xy 443.762634 -231.911516)
			(xy 443.772798 -231.911144) (xy 445.172338 -231.911144) (xy 445.182468 -231.911596) (xy 445.20119 -231.919337)
			(xy 445.215546 -231.933633) (xy 445.223363 -231.952324) (xy 445.2239 -231.962452) (xy 445.2239 -232.371392)
			(xy 451.265036 -232.371392) (xy 451.265036 -231.962452) (xy 451.265383 -231.95229) (xy 451.273201 -231.93353)
			(xy 451.287621 -231.919207) (xy 451.306434 -231.911516) (xy 451.316598 -231.911144) (xy 452.716138 -231.911144)
			(xy 452.726268 -231.911596) (xy 452.74499 -231.919337) (xy 452.759346 -231.933633) (xy 452.767163 -231.952324)
			(xy 452.7677 -231.962452) (xy 452.7677 -232.371392) (xy 458.808836 -232.371392) (xy 458.808836 -231.962452)
			(xy 458.809183 -231.95229) (xy 458.817001 -231.93353) (xy 458.831421 -231.919207) (xy 458.850234 -231.911516)
			(xy 458.860398 -231.911144) (xy 460.259938 -231.911144) (xy 460.270068 -231.911596) (xy 460.28879 -231.919337)
			(xy 460.303146 -231.933633) (xy 460.310963 -231.952324) (xy 460.3115 -231.962452) (xy 460.3115 -232.371392)
			(xy 460.311072 -232.381546) (xy 460.303279 -232.400298) (xy 460.288884 -232.414621) (xy 460.270094 -232.422321)
			(xy 460.259938 -232.4227) (xy 458.860398 -232.4227) (xy 458.850276 -232.422176) (xy 458.831563 -232.414455)
			(xy 458.817208 -232.400181) (xy 458.809382 -232.381511) (xy 458.808836 -232.371392) (xy 452.7677 -232.371392)
			(xy 452.767272 -232.381546) (xy 452.759479 -232.400298) (xy 452.745084 -232.414621) (xy 452.726294 -232.422321)
			(xy 452.716138 -232.4227) (xy 451.316598 -232.4227) (xy 451.306476 -232.422176) (xy 451.287763 -232.414455)
			(xy 451.273408 -232.400181) (xy 451.265582 -232.381511) (xy 451.265036 -232.371392) (xy 445.2239 -232.371392)
			(xy 445.223472 -232.381546) (xy 445.215679 -232.400298) (xy 445.201284 -232.414621) (xy 445.182494 -232.422321)
			(xy 445.172338 -232.4227) (xy 443.772798 -232.4227) (xy 443.762676 -232.422176) (xy 443.743963 -232.414455)
			(xy 443.729608 -232.400181) (xy 443.721782 -232.381511) (xy 443.721236 -232.371392) (xy 437.6801 -232.371392)
			(xy 437.679672 -232.381546) (xy 437.671879 -232.400298) (xy 437.657484 -232.414621) (xy 437.638694 -232.422321)
			(xy 437.628538 -232.4227) (xy 436.228998 -232.4227) (xy 436.218876 -232.422176) (xy 436.200163 -232.414455)
			(xy 436.185808 -232.400181) (xy 436.177982 -232.381511) (xy 436.177436 -232.371392) (xy 430.1363 -232.371392)
			(xy 430.135872 -232.381546) (xy 430.128079 -232.400298) (xy 430.113684 -232.414621) (xy 430.094894 -232.422321)
			(xy 430.084738 -232.4227) (xy 428.685198 -232.4227) (xy 428.675076 -232.422176) (xy 428.656363 -232.414455)
			(xy 428.642008 -232.400181) (xy 428.634182 -232.381511) (xy 428.633636 -232.371392) (xy 422.5925 -232.371392)
			(xy 422.592072 -232.381546) (xy 422.584279 -232.400298) (xy 422.569884 -232.414621) (xy 422.551094 -232.422321)
			(xy 422.540938 -232.4227) (xy 421.141398 -232.4227) (xy 421.131276 -232.422176) (xy 421.112563 -232.414455)
			(xy 421.098208 -232.400181) (xy 421.090382 -232.381511) (xy 421.089836 -232.371392) (xy 415.0487 -232.371392)
			(xy 415.048272 -232.381546) (xy 415.040479 -232.400298) (xy 415.026084 -232.414621) (xy 415.007294 -232.422321)
			(xy 414.997138 -232.4227) (xy 413.597598 -232.4227) (xy 413.587476 -232.422176) (xy 413.568763 -232.414455)
			(xy 413.554408 -232.400181) (xy 413.546582 -232.381511) (xy 413.546036 -232.371392) (xy 407.5049 -232.371392)
			(xy 407.504472 -232.381546) (xy 407.496679 -232.400298) (xy 407.482284 -232.414621) (xy 407.463494 -232.422321)
			(xy 407.453338 -232.4227) (xy 406.053798 -232.4227) (xy 406.043676 -232.422176) (xy 406.024963 -232.414455)
			(xy 406.010608 -232.400181) (xy 406.002782 -232.381511) (xy 406.002236 -232.371392) (xy 309.6387 -232.371392)
			(xy 309.638272 -232.381546) (xy 309.630479 -232.400298) (xy 309.616084 -232.414621) (xy 309.597294 -232.422321)
			(xy 309.587138 -232.4227) (xy 308.187598 -232.4227) (xy 308.177476 -232.422176) (xy 308.158763 -232.414455)
			(xy 308.144408 -232.400181) (xy 308.136582 -232.381511) (xy 308.136036 -232.371392) (xy 302.0949 -232.371392)
			(xy 302.094472 -232.381546) (xy 302.086679 -232.400298) (xy 302.072284 -232.414621) (xy 302.053494 -232.422321)
			(xy 302.043338 -232.4227) (xy 300.643798 -232.4227) (xy 300.633676 -232.422176) (xy 300.614963 -232.414455)
			(xy 300.600608 -232.400181) (xy 300.592782 -232.381511) (xy 300.592236 -232.371392) (xy 294.5511 -232.371392)
			(xy 294.550672 -232.381546) (xy 294.542879 -232.400298) (xy 294.528484 -232.414621) (xy 294.509694 -232.422321)
			(xy 294.499538 -232.4227) (xy 293.099998 -232.4227) (xy 293.089876 -232.422176) (xy 293.071163 -232.414455)
			(xy 293.056808 -232.400181) (xy 293.048982 -232.381511) (xy 293.048436 -232.371392) (xy 287.0073 -232.371392)
			(xy 287.006872 -232.381546) (xy 286.999079 -232.400298) (xy 286.984684 -232.414621) (xy 286.965894 -232.422321)
			(xy 286.955738 -232.4227) (xy 285.556198 -232.4227) (xy 285.546076 -232.422176) (xy 285.527363 -232.414455)
			(xy 285.513008 -232.400181) (xy 285.505182 -232.381511) (xy 285.504636 -232.371392) (xy 279.4635 -232.371392)
			(xy 279.463072 -232.381546) (xy 279.455279 -232.400298) (xy 279.440884 -232.414621) (xy 279.422094 -232.422321)
			(xy 279.411938 -232.4227) (xy 278.012398 -232.4227) (xy 278.002276 -232.422176) (xy 277.983563 -232.414455)
			(xy 277.969208 -232.400181) (xy 277.961382 -232.381511) (xy 277.960836 -232.371392) (xy 271.9197 -232.371392)
			(xy 271.919272 -232.381546) (xy 271.911479 -232.400298) (xy 271.897084 -232.414621) (xy 271.878294 -232.422321)
			(xy 271.868138 -232.4227) (xy 270.468598 -232.4227) (xy 270.458476 -232.422176) (xy 270.439763 -232.414455)
			(xy 270.425408 -232.400181) (xy 270.417582 -232.381511) (xy 270.417036 -232.371392) (xy 264.3759 -232.371392)
			(xy 264.375472 -232.381546) (xy 264.367679 -232.400298) (xy 264.353284 -232.414621) (xy 264.334494 -232.422321)
			(xy 264.324338 -232.4227) (xy 262.924798 -232.4227) (xy 262.914676 -232.422176) (xy 262.895963 -232.414455)
			(xy 262.881608 -232.400181) (xy 262.873782 -232.381511) (xy 262.873236 -232.371392) (xy 256.8321 -232.371392)
			(xy 256.831672 -232.381546) (xy 256.823879 -232.400298) (xy 256.809484 -232.414621) (xy 256.790694 -232.422321)
			(xy 256.780538 -232.4227) (xy 255.380998 -232.4227) (xy 255.370876 -232.422176) (xy 255.352163 -232.414455)
			(xy 255.337808 -232.400181) (xy 255.329982 -232.381511) (xy 255.329436 -232.371392) (xy 212.371432 -232.371392)
			(xy 212.370972 -232.381542) (xy 212.363186 -232.400288) (xy 212.348801 -232.41461) (xy 212.330021 -232.422316)
			(xy 212.31987 -232.4227) (xy 210.92033 -232.4227) (xy 210.91021 -232.42215) (xy 210.891497 -232.41444)
			(xy 210.877141 -232.400173) (xy 210.869314 -232.381509) (xy 210.868768 -232.371392) (xy 204.827632 -232.371392)
			(xy 204.827172 -232.381542) (xy 204.819386 -232.400288) (xy 204.805001 -232.41461) (xy 204.786221 -232.422316)
			(xy 204.77607 -232.4227) (xy 203.37653 -232.4227) (xy 203.36641 -232.42215) (xy 203.347697 -232.41444)
			(xy 203.333341 -232.400173) (xy 203.325514 -232.381509) (xy 203.324968 -232.371392) (xy 197.283832 -232.371392)
			(xy 197.283372 -232.381542) (xy 197.275586 -232.400288) (xy 197.261201 -232.41461) (xy 197.242421 -232.422316)
			(xy 197.23227 -232.4227) (xy 195.83273 -232.4227) (xy 195.82261 -232.42215) (xy 195.803897 -232.41444)
			(xy 195.789541 -232.400173) (xy 195.781714 -232.381509) (xy 195.781168 -232.371392) (xy 189.740032 -232.371392)
			(xy 189.739572 -232.381542) (xy 189.731786 -232.400288) (xy 189.717401 -232.41461) (xy 189.698621 -232.422316)
			(xy 189.68847 -232.4227) (xy 188.28893 -232.4227) (xy 188.27881 -232.42215) (xy 188.260097 -232.41444)
			(xy 188.245741 -232.400173) (xy 188.237914 -232.381509) (xy 188.237368 -232.371392) (xy 182.196232 -232.371392)
			(xy 182.195772 -232.381542) (xy 182.187986 -232.400288) (xy 182.173601 -232.41461) (xy 182.154821 -232.422316)
			(xy 182.14467 -232.4227) (xy 180.74513 -232.4227) (xy 180.73501 -232.42215) (xy 180.716297 -232.41444)
			(xy 180.701941 -232.400173) (xy 180.694114 -232.381509) (xy 180.693568 -232.371392) (xy 174.652432 -232.371392)
			(xy 174.651972 -232.381542) (xy 174.644186 -232.400288) (xy 174.629801 -232.41461) (xy 174.611021 -232.422316)
			(xy 174.60087 -232.4227) (xy 173.20133 -232.4227) (xy 173.19121 -232.42215) (xy 173.172497 -232.41444)
			(xy 173.158141 -232.400173) (xy 173.150314 -232.381509) (xy 173.149768 -232.371392) (xy 167.108632 -232.371392)
			(xy 167.108172 -232.381542) (xy 167.100386 -232.400288) (xy 167.086001 -232.41461) (xy 167.067221 -232.422316)
			(xy 167.05707 -232.4227) (xy 165.65753 -232.4227) (xy 165.64741 -232.42215) (xy 165.628697 -232.41444)
			(xy 165.614341 -232.400173) (xy 165.606514 -232.381509) (xy 165.605968 -232.371392) (xy 159.564832 -232.371392)
			(xy 159.564372 -232.381542) (xy 159.556586 -232.400288) (xy 159.542201 -232.41461) (xy 159.523421 -232.422316)
			(xy 159.51327 -232.4227) (xy 158.11373 -232.4227) (xy 158.10361 -232.42215) (xy 158.084897 -232.41444)
			(xy 158.070541 -232.400173) (xy 158.062714 -232.381509) (xy 158.062168 -232.371392) (xy 61.698632 -232.371392)
			(xy 61.698172 -232.381542) (xy 61.690386 -232.400288) (xy 61.676001 -232.41461) (xy 61.657221 -232.422316)
			(xy 61.64707 -232.4227) (xy 60.24753 -232.4227) (xy 60.23741 -232.42215) (xy 60.218697 -232.41444)
			(xy 60.204341 -232.400173) (xy 60.196514 -232.381509) (xy 60.195968 -232.371392) (xy 54.154832 -232.371392)
			(xy 54.154372 -232.381542) (xy 54.146586 -232.400288) (xy 54.132201 -232.41461) (xy 54.113421 -232.422316)
			(xy 54.10327 -232.4227) (xy 52.70373 -232.4227) (xy 52.69361 -232.42215) (xy 52.674897 -232.41444)
			(xy 52.660541 -232.400173) (xy 52.652714 -232.381509) (xy 52.652168 -232.371392) (xy 46.611032 -232.371392)
			(xy 46.610572 -232.381542) (xy 46.602786 -232.400288) (xy 46.588401 -232.41461) (xy 46.569621 -232.422316)
			(xy 46.55947 -232.4227) (xy 45.15993 -232.4227) (xy 45.14981 -232.42215) (xy 45.131097 -232.41444)
			(xy 45.116741 -232.400173) (xy 45.108914 -232.381509) (xy 45.108368 -232.371392) (xy 39.067232 -232.371392)
			(xy 39.066772 -232.381542) (xy 39.058986 -232.400288) (xy 39.044601 -232.41461) (xy 39.025821 -232.422316)
			(xy 39.01567 -232.4227) (xy 37.61613 -232.4227) (xy 37.60601 -232.42215) (xy 37.587297 -232.41444)
			(xy 37.572941 -232.400173) (xy 37.565114 -232.381509) (xy 37.564568 -232.371392) (xy 31.523432 -232.371392)
			(xy 31.522972 -232.381542) (xy 31.515186 -232.400288) (xy 31.500801 -232.41461) (xy 31.482021 -232.422316)
			(xy 31.47187 -232.4227) (xy 30.07233 -232.4227) (xy 30.06221 -232.42215) (xy 30.043497 -232.41444)
			(xy 30.029141 -232.400173) (xy 30.021314 -232.381509) (xy 30.020768 -232.371392) (xy 23.979632 -232.371392)
			(xy 23.979172 -232.381542) (xy 23.971386 -232.400288) (xy 23.957001 -232.41461) (xy 23.938221 -232.422316)
			(xy 23.92807 -232.4227) (xy 22.52853 -232.4227) (xy 22.51841 -232.42215) (xy 22.499697 -232.41444)
			(xy 22.485341 -232.400173) (xy 22.477514 -232.381509) (xy 22.476968 -232.371392) (xy 16.435832 -232.371392)
			(xy 16.435372 -232.381542) (xy 16.427586 -232.400288) (xy 16.413201 -232.41461) (xy 16.394421 -232.422316)
			(xy 16.38427 -232.4227) (xy 14.98473 -232.4227) (xy 14.97461 -232.42215) (xy 14.955897 -232.41444)
			(xy 14.941541 -232.400173) (xy 14.933714 -232.381509) (xy 14.933168 -232.371392) (xy 8.892032 -232.371392)
			(xy 8.891572 -232.381542) (xy 8.883786 -232.400288) (xy 8.869401 -232.41461) (xy 8.850621 -232.422316)
			(xy 8.84047 -232.4227) (xy 7.44093 -232.4227) (xy 7.43081 -232.42215) (xy 7.412097 -232.41444) (xy 7.397741 -232.400173)
			(xy 7.389914 -232.381509) (xy 7.389368 -232.371392) (xy 2.509012 -232.371392) (xy 2.509012 -233.22153)
			(xy 11.489436 -233.22153) (xy 11.489436 -232.81259) (xy 11.489925 -232.802432) (xy 11.497703 -232.783663)
			(xy 11.51207 -232.769298) (xy 11.53084 -232.761524) (xy 11.540998 -232.761028) (xy 12.940538 -232.761028)
			(xy 12.950697 -232.761502) (xy 12.969465 -232.769287) (xy 12.983829 -232.783658) (xy 12.991604 -232.802431)
			(xy 12.9921 -232.81259) (xy 12.9921 -233.22153) (xy 19.033236 -233.22153) (xy 19.033236 -232.81259)
			(xy 19.033725 -232.802432) (xy 19.041503 -232.783663) (xy 19.05587 -232.769298) (xy 19.07464 -232.761524)
			(xy 19.084798 -232.761028) (xy 20.484338 -232.761028) (xy 20.494497 -232.761502) (xy 20.513265 -232.769287)
			(xy 20.527629 -232.783658) (xy 20.535404 -232.802431) (xy 20.5359 -232.81259) (xy 20.5359 -233.22153)
			(xy 26.577036 -233.22153) (xy 26.577036 -232.81259) (xy 26.577525 -232.802432) (xy 26.585303 -232.783663)
			(xy 26.59967 -232.769298) (xy 26.61844 -232.761524) (xy 26.628598 -232.761028) (xy 28.028138 -232.761028)
			(xy 28.038297 -232.761502) (xy 28.057065 -232.769287) (xy 28.071429 -232.783658) (xy 28.079204 -232.802431)
			(xy 28.0797 -232.81259) (xy 28.0797 -233.22153) (xy 34.120836 -233.22153) (xy 34.120836 -232.81259)
			(xy 34.121325 -232.802432) (xy 34.129103 -232.783663) (xy 34.14347 -232.769298) (xy 34.16224 -232.761524)
			(xy 34.172398 -232.761028) (xy 35.571938 -232.761028) (xy 35.582097 -232.761502) (xy 35.600865 -232.769287)
			(xy 35.615229 -232.783658) (xy 35.623004 -232.802431) (xy 35.6235 -232.81259) (xy 35.6235 -233.22153)
			(xy 41.664636 -233.22153) (xy 41.664636 -232.81259) (xy 41.665125 -232.802432) (xy 41.672903 -232.783663)
			(xy 41.68727 -232.769298) (xy 41.70604 -232.761524) (xy 41.716198 -232.761028) (xy 43.115738 -232.761028)
			(xy 43.125897 -232.761502) (xy 43.144665 -232.769287) (xy 43.159029 -232.783658) (xy 43.166804 -232.802431)
			(xy 43.1673 -232.81259) (xy 43.1673 -233.22153) (xy 49.208436 -233.22153) (xy 49.208436 -232.81259)
			(xy 49.208925 -232.802432) (xy 49.216703 -232.783663) (xy 49.23107 -232.769298) (xy 49.24984 -232.761524)
			(xy 49.259998 -232.761028) (xy 50.659538 -232.761028) (xy 50.669697 -232.761502) (xy 50.688465 -232.769287)
			(xy 50.702829 -232.783658) (xy 50.710604 -232.802431) (xy 50.7111 -232.81259) (xy 50.7111 -233.22153)
			(xy 56.752236 -233.22153) (xy 56.752236 -232.81259) (xy 56.752725 -232.802432) (xy 56.760503 -232.783663)
			(xy 56.77487 -232.769298) (xy 56.79364 -232.761524) (xy 56.803798 -232.761028) (xy 58.203338 -232.761028)
			(xy 58.213497 -232.761502) (xy 58.232265 -232.769287) (xy 58.246629 -232.783658) (xy 58.254404 -232.802431)
			(xy 58.2549 -232.81259) (xy 58.2549 -233.22153) (xy 64.296036 -233.22153) (xy 64.296036 -232.81259)
			(xy 64.296525 -232.802432) (xy 64.304303 -232.783663) (xy 64.31867 -232.769298) (xy 64.33744 -232.761524)
			(xy 64.347598 -232.761028) (xy 65.747138 -232.761028) (xy 65.757297 -232.761502) (xy 65.776065 -232.769287)
			(xy 65.790429 -232.783658) (xy 65.798204 -232.802431) (xy 65.7987 -232.81259) (xy 65.7987 -233.22153)
			(xy 162.162236 -233.22153) (xy 162.162236 -232.81259) (xy 162.162725 -232.802432) (xy 162.170503 -232.783663)
			(xy 162.18487 -232.769298) (xy 162.20364 -232.761524) (xy 162.213798 -232.761028) (xy 163.613338 -232.761028)
			(xy 163.623497 -232.761502) (xy 163.642265 -232.769287) (xy 163.656629 -232.783658) (xy 163.664404 -232.802431)
			(xy 163.6649 -232.81259) (xy 163.6649 -233.22153) (xy 169.706036 -233.22153) (xy 169.706036 -232.81259)
			(xy 169.706525 -232.802432) (xy 169.714303 -232.783663) (xy 169.72867 -232.769298) (xy 169.74744 -232.761524)
			(xy 169.757598 -232.761028) (xy 171.157138 -232.761028) (xy 171.167297 -232.761502) (xy 171.186065 -232.769287)
			(xy 171.200429 -232.783658) (xy 171.208204 -232.802431) (xy 171.2087 -232.81259) (xy 171.2087 -233.22153)
			(xy 177.249836 -233.22153) (xy 177.249836 -232.81259) (xy 177.250325 -232.802432) (xy 177.258103 -232.783663)
			(xy 177.27247 -232.769298) (xy 177.29124 -232.761524) (xy 177.301398 -232.761028) (xy 178.700938 -232.761028)
			(xy 178.711097 -232.761502) (xy 178.729865 -232.769287) (xy 178.744229 -232.783658) (xy 178.752004 -232.802431)
			(xy 178.7525 -232.81259) (xy 178.7525 -233.22153) (xy 184.793636 -233.22153) (xy 184.793636 -232.81259)
			(xy 184.794125 -232.802432) (xy 184.801903 -232.783663) (xy 184.81627 -232.769298) (xy 184.83504 -232.761524)
			(xy 184.845198 -232.761028) (xy 186.244738 -232.761028) (xy 186.254897 -232.761502) (xy 186.273665 -232.769287)
			(xy 186.288029 -232.783658) (xy 186.295804 -232.802431) (xy 186.2963 -232.81259) (xy 186.2963 -233.22153)
			(xy 192.337436 -233.22153) (xy 192.337436 -232.81259) (xy 192.337925 -232.802432) (xy 192.345703 -232.783663)
			(xy 192.36007 -232.769298) (xy 192.37884 -232.761524) (xy 192.388998 -232.761028) (xy 193.788538 -232.761028)
			(xy 193.798697 -232.761502) (xy 193.817465 -232.769287) (xy 193.831829 -232.783658) (xy 193.839604 -232.802431)
			(xy 193.8401 -232.81259) (xy 193.8401 -233.22153) (xy 199.881236 -233.22153) (xy 199.881236 -232.81259)
			(xy 199.881725 -232.802432) (xy 199.889503 -232.783663) (xy 199.90387 -232.769298) (xy 199.92264 -232.761524)
			(xy 199.932798 -232.761028) (xy 201.332338 -232.761028) (xy 201.342497 -232.761502) (xy 201.361265 -232.769287)
			(xy 201.375629 -232.783658) (xy 201.383404 -232.802431) (xy 201.3839 -232.81259) (xy 201.3839 -233.22153)
			(xy 207.425036 -233.22153) (xy 207.425036 -232.81259) (xy 207.425525 -232.802432) (xy 207.433303 -232.783663)
			(xy 207.44767 -232.769298) (xy 207.46644 -232.761524) (xy 207.476598 -232.761028) (xy 208.876138 -232.761028)
			(xy 208.886297 -232.761502) (xy 208.905065 -232.769287) (xy 208.919429 -232.783658) (xy 208.927204 -232.802431)
			(xy 208.9277 -232.81259) (xy 208.9277 -233.22153) (xy 214.968836 -233.22153) (xy 214.968836 -232.81259)
			(xy 214.969325 -232.802432) (xy 214.977103 -232.783663) (xy 214.99147 -232.769298) (xy 215.01024 -232.761524)
			(xy 215.020398 -232.761028) (xy 216.419938 -232.761028) (xy 216.430097 -232.761502) (xy 216.448865 -232.769287)
			(xy 216.463229 -232.783658) (xy 216.471004 -232.802431) (xy 216.4715 -232.81259) (xy 216.4715 -233.22153)
			(xy 259.429504 -233.22153) (xy 259.429504 -232.81259) (xy 259.430025 -232.802436) (xy 259.437796 -232.783673)
			(xy 259.452153 -232.769309) (xy 259.470912 -232.761529) (xy 259.481066 -232.761028) (xy 260.880606 -232.761028)
			(xy 260.890763 -232.761528) (xy 260.90953 -232.769303) (xy 260.923895 -232.783666) (xy 260.931671 -232.802433)
			(xy 260.932168 -232.81259) (xy 260.932168 -233.22153) (xy 266.973304 -233.22153) (xy 266.973304 -232.81259)
			(xy 266.973825 -232.802436) (xy 266.981596 -232.783673) (xy 266.995953 -232.769309) (xy 267.014712 -232.761529)
			(xy 267.024866 -232.761028) (xy 268.424406 -232.761028) (xy 268.434563 -232.761528) (xy 268.45333 -232.769303)
			(xy 268.467695 -232.783666) (xy 268.475471 -232.802433) (xy 268.475968 -232.81259) (xy 268.475968 -233.22153)
			(xy 274.517104 -233.22153) (xy 274.517104 -232.81259) (xy 274.517625 -232.802436) (xy 274.525396 -232.783673)
			(xy 274.539753 -232.769309) (xy 274.558512 -232.761529) (xy 274.568666 -232.761028) (xy 275.968206 -232.761028)
			(xy 275.978363 -232.761528) (xy 275.99713 -232.769303) (xy 276.011495 -232.783666) (xy 276.019271 -232.802433)
			(xy 276.019768 -232.81259) (xy 276.019768 -233.22153) (xy 282.060904 -233.22153) (xy 282.060904 -232.81259)
			(xy 282.061425 -232.802436) (xy 282.069196 -232.783673) (xy 282.083553 -232.769309) (xy 282.102312 -232.761529)
			(xy 282.112466 -232.761028) (xy 283.512006 -232.761028) (xy 283.522163 -232.761528) (xy 283.54093 -232.769303)
			(xy 283.555295 -232.783666) (xy 283.563071 -232.802433) (xy 283.563568 -232.81259) (xy 283.563568 -233.22153)
			(xy 289.604704 -233.22153) (xy 289.604704 -232.81259) (xy 289.605225 -232.802436) (xy 289.612996 -232.783673)
			(xy 289.627353 -232.769309) (xy 289.646112 -232.761529) (xy 289.656266 -232.761028) (xy 291.055806 -232.761028)
			(xy 291.065963 -232.761528) (xy 291.08473 -232.769303) (xy 291.099095 -232.783666) (xy 291.106871 -232.802433)
			(xy 291.107368 -232.81259) (xy 291.107368 -233.22153) (xy 297.148504 -233.22153) (xy 297.148504 -232.81259)
			(xy 297.149025 -232.802436) (xy 297.156796 -232.783673) (xy 297.171153 -232.769309) (xy 297.189912 -232.761529)
			(xy 297.200066 -232.761028) (xy 298.599606 -232.761028) (xy 298.609763 -232.761528) (xy 298.62853 -232.769303)
			(xy 298.642895 -232.783666) (xy 298.650671 -232.802433) (xy 298.651168 -232.81259) (xy 298.651168 -233.22153)
			(xy 304.692304 -233.22153) (xy 304.692304 -232.81259) (xy 304.692825 -232.802436) (xy 304.700596 -232.783673)
			(xy 304.714953 -232.769309) (xy 304.733712 -232.761529) (xy 304.743866 -232.761028) (xy 306.143406 -232.761028)
			(xy 306.153563 -232.761528) (xy 306.17233 -232.769303) (xy 306.186695 -232.783666) (xy 306.194471 -232.802433)
			(xy 306.194968 -232.81259) (xy 306.194968 -233.22153) (xy 312.236104 -233.22153) (xy 312.236104 -232.81259)
			(xy 312.236625 -232.802436) (xy 312.244396 -232.783673) (xy 312.258753 -232.769309) (xy 312.277512 -232.761529)
			(xy 312.287666 -232.761028) (xy 313.687206 -232.761028) (xy 313.697363 -232.761528) (xy 313.71613 -232.769303)
			(xy 313.730495 -232.783666) (xy 313.738271 -232.802433) (xy 313.738768 -232.81259) (xy 313.738768 -233.22153)
			(xy 410.102304 -233.22153) (xy 410.102304 -232.81259) (xy 410.102825 -232.802436) (xy 410.110596 -232.783673)
			(xy 410.124953 -232.769309) (xy 410.143712 -232.761529) (xy 410.153866 -232.761028) (xy 411.553406 -232.761028)
			(xy 411.563563 -232.761528) (xy 411.58233 -232.769303) (xy 411.596695 -232.783666) (xy 411.604471 -232.802433)
			(xy 411.604968 -232.81259) (xy 411.604968 -233.22153) (xy 417.646104 -233.22153) (xy 417.646104 -232.81259)
			(xy 417.646625 -232.802436) (xy 417.654396 -232.783673) (xy 417.668753 -232.769309) (xy 417.687512 -232.761529)
			(xy 417.697666 -232.761028) (xy 419.097206 -232.761028) (xy 419.107363 -232.761528) (xy 419.12613 -232.769303)
			(xy 419.140495 -232.783666) (xy 419.148271 -232.802433) (xy 419.148768 -232.81259) (xy 419.148768 -233.22153)
			(xy 425.189904 -233.22153) (xy 425.189904 -232.81259) (xy 425.190425 -232.802436) (xy 425.198196 -232.783673)
			(xy 425.212553 -232.769309) (xy 425.231312 -232.761529) (xy 425.241466 -232.761028) (xy 426.641006 -232.761028)
			(xy 426.651163 -232.761528) (xy 426.66993 -232.769303) (xy 426.684295 -232.783666) (xy 426.692071 -232.802433)
			(xy 426.692568 -232.81259) (xy 426.692568 -233.22153) (xy 432.733704 -233.22153) (xy 432.733704 -232.81259)
			(xy 432.734225 -232.802436) (xy 432.741996 -232.783673) (xy 432.756353 -232.769309) (xy 432.775112 -232.761529)
			(xy 432.785266 -232.761028) (xy 434.184806 -232.761028) (xy 434.194963 -232.761528) (xy 434.21373 -232.769303)
			(xy 434.228095 -232.783666) (xy 434.235871 -232.802433) (xy 434.236368 -232.81259) (xy 434.236368 -233.22153)
			(xy 440.277504 -233.22153) (xy 440.277504 -232.81259) (xy 440.278025 -232.802436) (xy 440.285796 -232.783673)
			(xy 440.300153 -232.769309) (xy 440.318912 -232.761529) (xy 440.329066 -232.761028) (xy 441.728606 -232.761028)
			(xy 441.738763 -232.761528) (xy 441.75753 -232.769303) (xy 441.771895 -232.783666) (xy 441.779671 -232.802433)
			(xy 441.780168 -232.81259) (xy 441.780168 -233.22153) (xy 447.821304 -233.22153) (xy 447.821304 -232.81259)
			(xy 447.821825 -232.802436) (xy 447.829596 -232.783673) (xy 447.843953 -232.769309) (xy 447.862712 -232.761529)
			(xy 447.872866 -232.761028) (xy 449.272406 -232.761028) (xy 449.282563 -232.761528) (xy 449.30133 -232.769303)
			(xy 449.315695 -232.783666) (xy 449.323471 -232.802433) (xy 449.323968 -232.81259) (xy 449.323968 -233.22153)
			(xy 455.365104 -233.22153) (xy 455.365104 -232.81259) (xy 455.365625 -232.802436) (xy 455.373396 -232.783673)
			(xy 455.387753 -232.769309) (xy 455.406512 -232.761529) (xy 455.416666 -232.761028) (xy 456.816206 -232.761028)
			(xy 456.826363 -232.761528) (xy 456.84513 -232.769303) (xy 456.859495 -232.783666) (xy 456.867271 -232.802433)
			(xy 456.867768 -232.81259) (xy 456.867768 -233.22153) (xy 462.908904 -233.22153) (xy 462.908904 -232.81259)
			(xy 462.909425 -232.802436) (xy 462.917196 -232.783673) (xy 462.931553 -232.769309) (xy 462.950312 -232.761529)
			(xy 462.960466 -232.761028) (xy 464.360006 -232.761028) (xy 464.370163 -232.761528) (xy 464.38893 -232.769303)
			(xy 464.403295 -232.783666) (xy 464.411071 -232.802433) (xy 464.411568 -232.81259) (xy 464.411568 -233.22153)
			(xy 464.411091 -233.231689) (xy 464.403308 -233.250458) (xy 464.388938 -233.264822) (xy 464.370165 -233.272596)
			(xy 464.360006 -233.273092) (xy 462.960466 -233.273092) (xy 462.95031 -233.272595) (xy 462.931546 -233.264815)
			(xy 462.917183 -233.250451) (xy 462.909404 -233.231686) (xy 462.908904 -233.22153) (xy 456.867768 -233.22153)
			(xy 456.867291 -233.231689) (xy 456.859508 -233.250458) (xy 456.845138 -233.264822) (xy 456.826365 -233.272596)
			(xy 456.816206 -233.273092) (xy 455.416666 -233.273092) (xy 455.40651 -233.272595) (xy 455.387746 -233.264815)
			(xy 455.373383 -233.250451) (xy 455.365604 -233.231686) (xy 455.365104 -233.22153) (xy 449.323968 -233.22153)
			(xy 449.323491 -233.231689) (xy 449.315708 -233.250458) (xy 449.301338 -233.264822) (xy 449.282565 -233.272596)
			(xy 449.272406 -233.273092) (xy 447.872866 -233.273092) (xy 447.86271 -233.272595) (xy 447.843946 -233.264815)
			(xy 447.829583 -233.250451) (xy 447.821804 -233.231686) (xy 447.821304 -233.22153) (xy 441.780168 -233.22153)
			(xy 441.779691 -233.231689) (xy 441.771908 -233.250458) (xy 441.757538 -233.264822) (xy 441.738765 -233.272596)
			(xy 441.728606 -233.273092) (xy 440.329066 -233.273092) (xy 440.31891 -233.272595) (xy 440.300146 -233.264815)
			(xy 440.285783 -233.250451) (xy 440.278004 -233.231686) (xy 440.277504 -233.22153) (xy 434.236368 -233.22153)
			(xy 434.235891 -233.231689) (xy 434.228108 -233.250458) (xy 434.213738 -233.264822) (xy 434.194965 -233.272596)
			(xy 434.184806 -233.273092) (xy 432.785266 -233.273092) (xy 432.77511 -233.272595) (xy 432.756346 -233.264815)
			(xy 432.741983 -233.250451) (xy 432.734204 -233.231686) (xy 432.733704 -233.22153) (xy 426.692568 -233.22153)
			(xy 426.692091 -233.231689) (xy 426.684308 -233.250458) (xy 426.669938 -233.264822) (xy 426.651165 -233.272596)
			(xy 426.641006 -233.273092) (xy 425.241466 -233.273092) (xy 425.23131 -233.272595) (xy 425.212546 -233.264815)
			(xy 425.198183 -233.250451) (xy 425.190404 -233.231686) (xy 425.189904 -233.22153) (xy 419.148768 -233.22153)
			(xy 419.148291 -233.231689) (xy 419.140508 -233.250458) (xy 419.126138 -233.264822) (xy 419.107365 -233.272596)
			(xy 419.097206 -233.273092) (xy 417.697666 -233.273092) (xy 417.68751 -233.272595) (xy 417.668746 -233.264815)
			(xy 417.654383 -233.250451) (xy 417.646604 -233.231686) (xy 417.646104 -233.22153) (xy 411.604968 -233.22153)
			(xy 411.604491 -233.231689) (xy 411.596708 -233.250458) (xy 411.582338 -233.264822) (xy 411.563565 -233.272596)
			(xy 411.553406 -233.273092) (xy 410.153866 -233.273092) (xy 410.14371 -233.272595) (xy 410.124946 -233.264815)
			(xy 410.110583 -233.250451) (xy 410.102804 -233.231686) (xy 410.102304 -233.22153) (xy 313.738768 -233.22153)
			(xy 313.738291 -233.231689) (xy 313.730508 -233.250458) (xy 313.716138 -233.264822) (xy 313.697365 -233.272596)
			(xy 313.687206 -233.273092) (xy 312.287666 -233.273092) (xy 312.27751 -233.272595) (xy 312.258746 -233.264815)
			(xy 312.244383 -233.250451) (xy 312.236604 -233.231686) (xy 312.236104 -233.22153) (xy 306.194968 -233.22153)
			(xy 306.194491 -233.231689) (xy 306.186708 -233.250458) (xy 306.172338 -233.264822) (xy 306.153565 -233.272596)
			(xy 306.143406 -233.273092) (xy 304.743866 -233.273092) (xy 304.73371 -233.272595) (xy 304.714946 -233.264815)
			(xy 304.700583 -233.250451) (xy 304.692804 -233.231686) (xy 304.692304 -233.22153) (xy 298.651168 -233.22153)
			(xy 298.650691 -233.231689) (xy 298.642908 -233.250458) (xy 298.628538 -233.264822) (xy 298.609765 -233.272596)
			(xy 298.599606 -233.273092) (xy 297.200066 -233.273092) (xy 297.18991 -233.272595) (xy 297.171146 -233.264815)
			(xy 297.156783 -233.250451) (xy 297.149004 -233.231686) (xy 297.148504 -233.22153) (xy 291.107368 -233.22153)
			(xy 291.106891 -233.231689) (xy 291.099108 -233.250458) (xy 291.084738 -233.264822) (xy 291.065965 -233.272596)
			(xy 291.055806 -233.273092) (xy 289.656266 -233.273092) (xy 289.64611 -233.272595) (xy 289.627346 -233.264815)
			(xy 289.612983 -233.250451) (xy 289.605204 -233.231686) (xy 289.604704 -233.22153) (xy 283.563568 -233.22153)
			(xy 283.563091 -233.231689) (xy 283.555308 -233.250458) (xy 283.540938 -233.264822) (xy 283.522165 -233.272596)
			(xy 283.512006 -233.273092) (xy 282.112466 -233.273092) (xy 282.10231 -233.272595) (xy 282.083546 -233.264815)
			(xy 282.069183 -233.250451) (xy 282.061404 -233.231686) (xy 282.060904 -233.22153) (xy 276.019768 -233.22153)
			(xy 276.019291 -233.231689) (xy 276.011508 -233.250458) (xy 275.997138 -233.264822) (xy 275.978365 -233.272596)
			(xy 275.968206 -233.273092) (xy 274.568666 -233.273092) (xy 274.55851 -233.272595) (xy 274.539746 -233.264815)
			(xy 274.525383 -233.250451) (xy 274.517604 -233.231686) (xy 274.517104 -233.22153) (xy 268.475968 -233.22153)
			(xy 268.475491 -233.231689) (xy 268.467708 -233.250458) (xy 268.453338 -233.264822) (xy 268.434565 -233.272596)
			(xy 268.424406 -233.273092) (xy 267.024866 -233.273092) (xy 267.01471 -233.272595) (xy 266.995946 -233.264815)
			(xy 266.981583 -233.250451) (xy 266.973804 -233.231686) (xy 266.973304 -233.22153) (xy 260.932168 -233.22153)
			(xy 260.931691 -233.231689) (xy 260.923908 -233.250458) (xy 260.909538 -233.264822) (xy 260.890765 -233.272596)
			(xy 260.880606 -233.273092) (xy 259.481066 -233.273092) (xy 259.47091 -233.272595) (xy 259.452146 -233.264815)
			(xy 259.437783 -233.250451) (xy 259.430004 -233.231686) (xy 259.429504 -233.22153) (xy 216.4715 -233.22153)
			(xy 216.470992 -233.231685) (xy 216.463215 -233.250448) (xy 216.448854 -233.26481) (xy 216.430093 -233.272591)
			(xy 216.419938 -233.273092) (xy 215.020398 -233.273092) (xy 215.010244 -233.272569) (xy 214.99148 -233.264799)
			(xy 214.977116 -233.250443) (xy 214.969337 -233.231684) (xy 214.968836 -233.22153) (xy 208.9277 -233.22153)
			(xy 208.927192 -233.231685) (xy 208.919415 -233.250448) (xy 208.905054 -233.26481) (xy 208.886293 -233.272591)
			(xy 208.876138 -233.273092) (xy 207.476598 -233.273092) (xy 207.466444 -233.272569) (xy 207.44768 -233.264799)
			(xy 207.433316 -233.250443) (xy 207.425537 -233.231684) (xy 207.425036 -233.22153) (xy 201.3839 -233.22153)
			(xy 201.383392 -233.231685) (xy 201.375615 -233.250448) (xy 201.361254 -233.26481) (xy 201.342493 -233.272591)
			(xy 201.332338 -233.273092) (xy 199.932798 -233.273092) (xy 199.922644 -233.272569) (xy 199.90388 -233.264799)
			(xy 199.889516 -233.250443) (xy 199.881737 -233.231684) (xy 199.881236 -233.22153) (xy 193.8401 -233.22153)
			(xy 193.839592 -233.231685) (xy 193.831815 -233.250448) (xy 193.817454 -233.26481) (xy 193.798693 -233.272591)
			(xy 193.788538 -233.273092) (xy 192.388998 -233.273092) (xy 192.378844 -233.272569) (xy 192.36008 -233.264799)
			(xy 192.345716 -233.250443) (xy 192.337937 -233.231684) (xy 192.337436 -233.22153) (xy 186.2963 -233.22153)
			(xy 186.295792 -233.231685) (xy 186.288015 -233.250448) (xy 186.273654 -233.26481) (xy 186.254893 -233.272591)
			(xy 186.244738 -233.273092) (xy 184.845198 -233.273092) (xy 184.835044 -233.272569) (xy 184.81628 -233.264799)
			(xy 184.801916 -233.250443) (xy 184.794137 -233.231684) (xy 184.793636 -233.22153) (xy 178.7525 -233.22153)
			(xy 178.751992 -233.231685) (xy 178.744215 -233.250448) (xy 178.729854 -233.26481) (xy 178.711093 -233.272591)
			(xy 178.700938 -233.273092) (xy 177.301398 -233.273092) (xy 177.291244 -233.272569) (xy 177.27248 -233.264799)
			(xy 177.258116 -233.250443) (xy 177.250337 -233.231684) (xy 177.249836 -233.22153) (xy 171.2087 -233.22153)
			(xy 171.208192 -233.231685) (xy 171.200415 -233.250448) (xy 171.186054 -233.26481) (xy 171.167293 -233.272591)
			(xy 171.157138 -233.273092) (xy 169.757598 -233.273092) (xy 169.747444 -233.272569) (xy 169.72868 -233.264799)
			(xy 169.714316 -233.250443) (xy 169.706537 -233.231684) (xy 169.706036 -233.22153) (xy 163.6649 -233.22153)
			(xy 163.664392 -233.231685) (xy 163.656615 -233.250448) (xy 163.642254 -233.26481) (xy 163.623493 -233.272591)
			(xy 163.613338 -233.273092) (xy 162.213798 -233.273092) (xy 162.203644 -233.272569) (xy 162.18488 -233.264799)
			(xy 162.170516 -233.250443) (xy 162.162737 -233.231684) (xy 162.162236 -233.22153) (xy 65.7987 -233.22153)
			(xy 65.798192 -233.231685) (xy 65.790415 -233.250448) (xy 65.776054 -233.26481) (xy 65.757293 -233.272591)
			(xy 65.747138 -233.273092) (xy 64.347598 -233.273092) (xy 64.337444 -233.272569) (xy 64.31868 -233.264799)
			(xy 64.304316 -233.250443) (xy 64.296537 -233.231684) (xy 64.296036 -233.22153) (xy 58.2549 -233.22153)
			(xy 58.254392 -233.231685) (xy 58.246615 -233.250448) (xy 58.232254 -233.26481) (xy 58.213493 -233.272591)
			(xy 58.203338 -233.273092) (xy 56.803798 -233.273092) (xy 56.793644 -233.272569) (xy 56.77488 -233.264799)
			(xy 56.760516 -233.250443) (xy 56.752737 -233.231684) (xy 56.752236 -233.22153) (xy 50.7111 -233.22153)
			(xy 50.710592 -233.231685) (xy 50.702815 -233.250448) (xy 50.688454 -233.26481) (xy 50.669693 -233.272591)
			(xy 50.659538 -233.273092) (xy 49.259998 -233.273092) (xy 49.249844 -233.272569) (xy 49.23108 -233.264799)
			(xy 49.216716 -233.250443) (xy 49.208937 -233.231684) (xy 49.208436 -233.22153) (xy 43.1673 -233.22153)
			(xy 43.166792 -233.231685) (xy 43.159015 -233.250448) (xy 43.144654 -233.26481) (xy 43.125893 -233.272591)
			(xy 43.115738 -233.273092) (xy 41.716198 -233.273092) (xy 41.706044 -233.272569) (xy 41.68728 -233.264799)
			(xy 41.672916 -233.250443) (xy 41.665137 -233.231684) (xy 41.664636 -233.22153) (xy 35.6235 -233.22153)
			(xy 35.622992 -233.231685) (xy 35.615215 -233.250448) (xy 35.600854 -233.26481) (xy 35.582093 -233.272591)
			(xy 35.571938 -233.273092) (xy 34.172398 -233.273092) (xy 34.162244 -233.272569) (xy 34.14348 -233.264799)
			(xy 34.129116 -233.250443) (xy 34.121337 -233.231684) (xy 34.120836 -233.22153) (xy 28.0797 -233.22153)
			(xy 28.079192 -233.231685) (xy 28.071415 -233.250448) (xy 28.057054 -233.26481) (xy 28.038293 -233.272591)
			(xy 28.028138 -233.273092) (xy 26.628598 -233.273092) (xy 26.618444 -233.272569) (xy 26.59968 -233.264799)
			(xy 26.585316 -233.250443) (xy 26.577537 -233.231684) (xy 26.577036 -233.22153) (xy 20.5359 -233.22153)
			(xy 20.535392 -233.231685) (xy 20.527615 -233.250448) (xy 20.513254 -233.26481) (xy 20.494493 -233.272591)
			(xy 20.484338 -233.273092) (xy 19.084798 -233.273092) (xy 19.074644 -233.272569) (xy 19.05588 -233.264799)
			(xy 19.041516 -233.250443) (xy 19.033737 -233.231684) (xy 19.033236 -233.22153) (xy 12.9921 -233.22153)
			(xy 12.991592 -233.231685) (xy 12.983815 -233.250448) (xy 12.969454 -233.26481) (xy 12.950693 -233.272591)
			(xy 12.940538 -233.273092) (xy 11.540998 -233.273092) (xy 11.530844 -233.272569) (xy 11.51208 -233.264799)
			(xy 11.497716 -233.250443) (xy 11.489937 -233.231684) (xy 11.489436 -233.22153) (xy 2.509012 -233.22153)
			(xy 2.509012 -234.071414) (xy 7.389368 -234.071414) (xy 7.389368 -233.662474) (xy 7.389743 -233.652297)
			(xy 7.397542 -233.633496) (xy 7.411943 -233.619111) (xy 7.430752 -233.611332) (xy 7.44093 -233.610912)
			(xy 8.84047 -233.610912) (xy 8.850636 -233.611388) (xy 8.869425 -233.619158) (xy 8.88381 -233.633528)
			(xy 8.891601 -233.652308) (xy 8.892032 -233.662474) (xy 8.892032 -234.071414) (xy 14.933168 -234.071414)
			(xy 14.933168 -233.662474) (xy 14.933543 -233.652297) (xy 14.941342 -233.633496) (xy 14.955743 -233.619111)
			(xy 14.974552 -233.611332) (xy 14.98473 -233.610912) (xy 16.38427 -233.610912) (xy 16.394436 -233.611388)
			(xy 16.413225 -233.619158) (xy 16.42761 -233.633528) (xy 16.435401 -233.652308) (xy 16.435832 -233.662474)
			(xy 16.435832 -234.071414) (xy 22.476968 -234.071414) (xy 22.476968 -233.662474) (xy 22.477343 -233.652297)
			(xy 22.485142 -233.633496) (xy 22.499543 -233.619111) (xy 22.518352 -233.611332) (xy 22.52853 -233.610912)
			(xy 23.92807 -233.610912) (xy 23.938236 -233.611388) (xy 23.957025 -233.619158) (xy 23.97141 -233.633528)
			(xy 23.979201 -233.652308) (xy 23.979632 -233.662474) (xy 23.979632 -234.071414) (xy 30.020768 -234.071414)
			(xy 30.020768 -233.662474) (xy 30.021143 -233.652297) (xy 30.028942 -233.633496) (xy 30.043343 -233.619111)
			(xy 30.062152 -233.611332) (xy 30.07233 -233.610912) (xy 31.47187 -233.610912) (xy 31.482036 -233.611388)
			(xy 31.500825 -233.619158) (xy 31.51521 -233.633528) (xy 31.523001 -233.652308) (xy 31.523432 -233.662474)
			(xy 31.523432 -234.071414) (xy 37.564568 -234.071414) (xy 37.564568 -233.662474) (xy 37.564943 -233.652297)
			(xy 37.572742 -233.633496) (xy 37.587143 -233.619111) (xy 37.605952 -233.611332) (xy 37.61613 -233.610912)
			(xy 39.01567 -233.610912) (xy 39.025836 -233.611388) (xy 39.044625 -233.619158) (xy 39.05901 -233.633528)
			(xy 39.066801 -233.652308) (xy 39.067232 -233.662474) (xy 39.067232 -234.071414) (xy 45.108368 -234.071414)
			(xy 45.108368 -233.662474) (xy 45.108743 -233.652297) (xy 45.116542 -233.633496) (xy 45.130943 -233.619111)
			(xy 45.149752 -233.611332) (xy 45.15993 -233.610912) (xy 46.55947 -233.610912) (xy 46.569636 -233.611388)
			(xy 46.588425 -233.619158) (xy 46.60281 -233.633528) (xy 46.610601 -233.652308) (xy 46.611032 -233.662474)
			(xy 46.611032 -234.071414) (xy 52.652168 -234.071414) (xy 52.652168 -233.662474) (xy 52.652543 -233.652297)
			(xy 52.660342 -233.633496) (xy 52.674743 -233.619111) (xy 52.693552 -233.611332) (xy 52.70373 -233.610912)
			(xy 54.10327 -233.610912) (xy 54.113436 -233.611388) (xy 54.132225 -233.619158) (xy 54.14661 -233.633528)
			(xy 54.154401 -233.652308) (xy 54.154832 -233.662474) (xy 54.154832 -234.071414) (xy 60.195968 -234.071414)
			(xy 60.195968 -233.662474) (xy 60.196343 -233.652297) (xy 60.204142 -233.633496) (xy 60.218543 -233.619111)
			(xy 60.237352 -233.611332) (xy 60.24753 -233.610912) (xy 61.64707 -233.610912) (xy 61.657236 -233.611388)
			(xy 61.676025 -233.619158) (xy 61.69041 -233.633528) (xy 61.698201 -233.652308) (xy 61.698632 -233.662474)
			(xy 61.698632 -234.071414) (xy 158.062168 -234.071414) (xy 158.062168 -233.662474) (xy 158.062543 -233.652297)
			(xy 158.070342 -233.633496) (xy 158.084743 -233.619111) (xy 158.103552 -233.611332) (xy 158.11373 -233.610912)
			(xy 159.51327 -233.610912) (xy 159.523436 -233.611388) (xy 159.542225 -233.619158) (xy 159.55661 -233.633528)
			(xy 159.564401 -233.652308) (xy 159.564832 -233.662474) (xy 159.564832 -234.071414) (xy 165.605968 -234.071414)
			(xy 165.605968 -233.662474) (xy 165.606343 -233.652297) (xy 165.614142 -233.633496) (xy 165.628543 -233.619111)
			(xy 165.647352 -233.611332) (xy 165.65753 -233.610912) (xy 167.05707 -233.610912) (xy 167.067236 -233.611388)
			(xy 167.086025 -233.619158) (xy 167.10041 -233.633528) (xy 167.108201 -233.652308) (xy 167.108632 -233.662474)
			(xy 167.108632 -234.071414) (xy 173.149768 -234.071414) (xy 173.149768 -233.662474) (xy 173.150143 -233.652297)
			(xy 173.157942 -233.633496) (xy 173.172343 -233.619111) (xy 173.191152 -233.611332) (xy 173.20133 -233.610912)
			(xy 174.60087 -233.610912) (xy 174.611036 -233.611388) (xy 174.629825 -233.619158) (xy 174.64421 -233.633528)
			(xy 174.652001 -233.652308) (xy 174.652432 -233.662474) (xy 174.652432 -234.071414) (xy 180.693568 -234.071414)
			(xy 180.693568 -233.662474) (xy 180.693943 -233.652297) (xy 180.701742 -233.633496) (xy 180.716143 -233.619111)
			(xy 180.734952 -233.611332) (xy 180.74513 -233.610912) (xy 182.14467 -233.610912) (xy 182.154836 -233.611388)
			(xy 182.173625 -233.619158) (xy 182.18801 -233.633528) (xy 182.195801 -233.652308) (xy 182.196232 -233.662474)
			(xy 182.196232 -234.071414) (xy 188.237368 -234.071414) (xy 188.237368 -233.662474) (xy 188.237743 -233.652297)
			(xy 188.245542 -233.633496) (xy 188.259943 -233.619111) (xy 188.278752 -233.611332) (xy 188.28893 -233.610912)
			(xy 189.68847 -233.610912) (xy 189.698636 -233.611388) (xy 189.717425 -233.619158) (xy 189.73181 -233.633528)
			(xy 189.739601 -233.652308) (xy 189.740032 -233.662474) (xy 189.740032 -234.071414) (xy 195.781168 -234.071414)
			(xy 195.781168 -233.662474) (xy 195.781543 -233.652297) (xy 195.789342 -233.633496) (xy 195.803743 -233.619111)
			(xy 195.822552 -233.611332) (xy 195.83273 -233.610912) (xy 197.23227 -233.610912) (xy 197.242436 -233.611388)
			(xy 197.261225 -233.619158) (xy 197.27561 -233.633528) (xy 197.283401 -233.652308) (xy 197.283832 -233.662474)
			(xy 197.283832 -234.071414) (xy 203.324968 -234.071414) (xy 203.324968 -233.662474) (xy 203.325343 -233.652297)
			(xy 203.333142 -233.633496) (xy 203.347543 -233.619111) (xy 203.366352 -233.611332) (xy 203.37653 -233.610912)
			(xy 204.77607 -233.610912) (xy 204.786236 -233.611388) (xy 204.805025 -233.619158) (xy 204.81941 -233.633528)
			(xy 204.827201 -233.652308) (xy 204.827632 -233.662474) (xy 204.827632 -234.071414) (xy 210.868768 -234.071414)
			(xy 210.868768 -233.662474) (xy 210.869143 -233.652297) (xy 210.876942 -233.633496) (xy 210.891343 -233.619111)
			(xy 210.910152 -233.611332) (xy 210.92033 -233.610912) (xy 212.31987 -233.610912) (xy 212.330036 -233.611388)
			(xy 212.348825 -233.619158) (xy 212.36321 -233.633528) (xy 212.371001 -233.652308) (xy 212.371432 -233.662474)
			(xy 212.371432 -234.071414) (xy 255.329436 -234.071414) (xy 255.329436 -233.662474) (xy 255.329912 -233.652315)
			(xy 255.337695 -233.633545) (xy 255.352066 -233.619181) (xy 255.370839 -233.611407) (xy 255.380998 -233.610912)
			(xy 256.780538 -233.610912) (xy 256.790695 -233.611402) (xy 256.80946 -233.619184) (xy 256.823823 -233.63355)
			(xy 256.831601 -233.652317) (xy 256.8321 -233.662474) (xy 256.8321 -234.071414) (xy 262.873236 -234.071414)
			(xy 262.873236 -233.662474) (xy 262.873712 -233.652315) (xy 262.881495 -233.633545) (xy 262.895866 -233.619181)
			(xy 262.914639 -233.611407) (xy 262.924798 -233.610912) (xy 264.324338 -233.610912) (xy 264.334495 -233.611402)
			(xy 264.35326 -233.619184) (xy 264.367623 -233.63355) (xy 264.375401 -233.652317) (xy 264.3759 -233.662474)
			(xy 264.3759 -234.071414) (xy 270.417036 -234.071414) (xy 270.417036 -233.662474) (xy 270.417512 -233.652315)
			(xy 270.425295 -233.633545) (xy 270.439666 -233.619181) (xy 270.458439 -233.611407) (xy 270.468598 -233.610912)
			(xy 271.868138 -233.610912) (xy 271.878295 -233.611402) (xy 271.89706 -233.619184) (xy 271.911423 -233.63355)
			(xy 271.919201 -233.652317) (xy 271.9197 -233.662474) (xy 271.9197 -234.071414) (xy 277.960836 -234.071414)
			(xy 277.960836 -233.662474) (xy 277.961312 -233.652315) (xy 277.969095 -233.633545) (xy 277.983466 -233.619181)
			(xy 278.002239 -233.611407) (xy 278.012398 -233.610912) (xy 279.411938 -233.610912) (xy 279.422095 -233.611402)
			(xy 279.44086 -233.619184) (xy 279.455223 -233.63355) (xy 279.463001 -233.652317) (xy 279.4635 -233.662474)
			(xy 279.4635 -234.071414) (xy 285.504636 -234.071414) (xy 285.504636 -233.662474) (xy 285.505112 -233.652315)
			(xy 285.512895 -233.633545) (xy 285.527266 -233.619181) (xy 285.546039 -233.611407) (xy 285.556198 -233.610912)
			(xy 286.955738 -233.610912) (xy 286.965895 -233.611402) (xy 286.98466 -233.619184) (xy 286.999023 -233.63355)
			(xy 287.006801 -233.652317) (xy 287.0073 -233.662474) (xy 287.0073 -234.071414) (xy 293.048436 -234.071414)
			(xy 293.048436 -233.662474) (xy 293.048912 -233.652315) (xy 293.056695 -233.633545) (xy 293.071066 -233.619181)
			(xy 293.089839 -233.611407) (xy 293.099998 -233.610912) (xy 294.499538 -233.610912) (xy 294.509695 -233.611402)
			(xy 294.52846 -233.619184) (xy 294.542823 -233.63355) (xy 294.550601 -233.652317) (xy 294.5511 -233.662474)
			(xy 294.5511 -234.071414) (xy 300.592236 -234.071414) (xy 300.592236 -233.662474) (xy 300.592712 -233.652315)
			(xy 300.600495 -233.633545) (xy 300.614866 -233.619181) (xy 300.633639 -233.611407) (xy 300.643798 -233.610912)
			(xy 302.043338 -233.610912) (xy 302.053495 -233.611402) (xy 302.07226 -233.619184) (xy 302.086623 -233.63355)
			(xy 302.094401 -233.652317) (xy 302.0949 -233.662474) (xy 302.0949 -234.071414) (xy 308.136036 -234.071414)
			(xy 308.136036 -233.662474) (xy 308.136512 -233.652315) (xy 308.144295 -233.633545) (xy 308.158666 -233.619181)
			(xy 308.177439 -233.611407) (xy 308.187598 -233.610912) (xy 309.587138 -233.610912) (xy 309.597295 -233.611402)
			(xy 309.61606 -233.619184) (xy 309.630423 -233.63355) (xy 309.638201 -233.652317) (xy 309.6387 -233.662474)
			(xy 309.6387 -234.071414) (xy 406.002236 -234.071414) (xy 406.002236 -233.662474) (xy 406.002712 -233.652315)
			(xy 406.010495 -233.633545) (xy 406.024866 -233.619181) (xy 406.043639 -233.611407) (xy 406.053798 -233.610912)
			(xy 407.453338 -233.610912) (xy 407.463495 -233.611402) (xy 407.48226 -233.619184) (xy 407.496623 -233.63355)
			(xy 407.504401 -233.652317) (xy 407.5049 -233.662474) (xy 407.5049 -234.071414) (xy 413.546036 -234.071414)
			(xy 413.546036 -233.662474) (xy 413.546512 -233.652315) (xy 413.554295 -233.633545) (xy 413.568666 -233.619181)
			(xy 413.587439 -233.611407) (xy 413.597598 -233.610912) (xy 414.997138 -233.610912) (xy 415.007295 -233.611402)
			(xy 415.02606 -233.619184) (xy 415.040423 -233.63355) (xy 415.048201 -233.652317) (xy 415.0487 -233.662474)
			(xy 415.0487 -234.071414) (xy 421.089836 -234.071414) (xy 421.089836 -233.662474) (xy 421.090312 -233.652315)
			(xy 421.098095 -233.633545) (xy 421.112466 -233.619181) (xy 421.131239 -233.611407) (xy 421.141398 -233.610912)
			(xy 422.540938 -233.610912) (xy 422.551095 -233.611402) (xy 422.56986 -233.619184) (xy 422.584223 -233.63355)
			(xy 422.592001 -233.652317) (xy 422.5925 -233.662474) (xy 422.5925 -234.071414) (xy 428.633636 -234.071414)
			(xy 428.633636 -233.662474) (xy 428.634112 -233.652315) (xy 428.641895 -233.633545) (xy 428.656266 -233.619181)
			(xy 428.675039 -233.611407) (xy 428.685198 -233.610912) (xy 430.084738 -233.610912) (xy 430.094895 -233.611402)
			(xy 430.11366 -233.619184) (xy 430.128023 -233.63355) (xy 430.135801 -233.652317) (xy 430.1363 -233.662474)
			(xy 430.1363 -234.071414) (xy 436.177436 -234.071414) (xy 436.177436 -233.662474) (xy 436.177912 -233.652315)
			(xy 436.185695 -233.633545) (xy 436.200066 -233.619181) (xy 436.218839 -233.611407) (xy 436.228998 -233.610912)
			(xy 437.628538 -233.610912) (xy 437.638695 -233.611402) (xy 437.65746 -233.619184) (xy 437.671823 -233.63355)
			(xy 437.679601 -233.652317) (xy 437.6801 -233.662474) (xy 437.6801 -234.071414) (xy 443.721236 -234.071414)
			(xy 443.721236 -233.662474) (xy 443.721712 -233.652315) (xy 443.729495 -233.633545) (xy 443.743866 -233.619181)
			(xy 443.762639 -233.611407) (xy 443.772798 -233.610912) (xy 445.172338 -233.610912) (xy 445.182495 -233.611402)
			(xy 445.20126 -233.619184) (xy 445.215623 -233.63355) (xy 445.223401 -233.652317) (xy 445.2239 -233.662474)
			(xy 445.2239 -234.071414) (xy 451.265036 -234.071414) (xy 451.265036 -233.662474) (xy 451.265512 -233.652315)
			(xy 451.273295 -233.633545) (xy 451.287666 -233.619181) (xy 451.306439 -233.611407) (xy 451.316598 -233.610912)
			(xy 452.716138 -233.610912) (xy 452.726295 -233.611402) (xy 452.74506 -233.619184) (xy 452.759423 -233.63355)
			(xy 452.767201 -233.652317) (xy 452.7677 -233.662474) (xy 452.7677 -234.071414) (xy 458.808836 -234.071414)
			(xy 458.808836 -233.662474) (xy 458.809312 -233.652315) (xy 458.817095 -233.633545) (xy 458.831466 -233.619181)
			(xy 458.850239 -233.611407) (xy 458.860398 -233.610912) (xy 460.259938 -233.610912) (xy 460.270095 -233.611402)
			(xy 460.28886 -233.619184) (xy 460.303223 -233.63355) (xy 460.311001 -233.652317) (xy 460.3115 -233.662474)
			(xy 460.3115 -234.071414) (xy 460.310979 -234.081568) (xy 460.303207 -234.10033) (xy 460.28885 -234.114693)
			(xy 460.270092 -234.122474) (xy 460.259938 -234.122976) (xy 458.860398 -234.122976) (xy 458.850242 -234.122469)
			(xy 458.831475 -234.114696) (xy 458.817111 -234.100335) (xy 458.809334 -234.08157) (xy 458.808836 -234.071414)
			(xy 452.7677 -234.071414) (xy 452.767179 -234.081568) (xy 452.759407 -234.10033) (xy 452.74505 -234.114693)
			(xy 452.726292 -234.122474) (xy 452.716138 -234.122976) (xy 451.316598 -234.122976) (xy 451.306442 -234.122469)
			(xy 451.287675 -234.114696) (xy 451.273311 -234.100335) (xy 451.265534 -234.08157) (xy 451.265036 -234.071414)
			(xy 445.2239 -234.071414) (xy 445.223379 -234.081568) (xy 445.215607 -234.10033) (xy 445.20125 -234.114693)
			(xy 445.182492 -234.122474) (xy 445.172338 -234.122976) (xy 443.772798 -234.122976) (xy 443.762642 -234.122469)
			(xy 443.743875 -234.114696) (xy 443.729511 -234.100335) (xy 443.721734 -234.08157) (xy 443.721236 -234.071414)
			(xy 437.6801 -234.071414) (xy 437.679579 -234.081568) (xy 437.671807 -234.10033) (xy 437.65745 -234.114693)
			(xy 437.638692 -234.122474) (xy 437.628538 -234.122976) (xy 436.228998 -234.122976) (xy 436.218842 -234.122469)
			(xy 436.200075 -234.114696) (xy 436.185711 -234.100335) (xy 436.177934 -234.08157) (xy 436.177436 -234.071414)
			(xy 430.1363 -234.071414) (xy 430.135779 -234.081568) (xy 430.128007 -234.10033) (xy 430.11365 -234.114693)
			(xy 430.094892 -234.122474) (xy 430.084738 -234.122976) (xy 428.685198 -234.122976) (xy 428.675042 -234.122469)
			(xy 428.656275 -234.114696) (xy 428.641911 -234.100335) (xy 428.634134 -234.08157) (xy 428.633636 -234.071414)
			(xy 422.5925 -234.071414) (xy 422.591979 -234.081568) (xy 422.584207 -234.10033) (xy 422.56985 -234.114693)
			(xy 422.551092 -234.122474) (xy 422.540938 -234.122976) (xy 421.141398 -234.122976) (xy 421.131242 -234.122469)
			(xy 421.112475 -234.114696) (xy 421.098111 -234.100335) (xy 421.090334 -234.08157) (xy 421.089836 -234.071414)
			(xy 415.0487 -234.071414) (xy 415.048179 -234.081568) (xy 415.040407 -234.10033) (xy 415.02605 -234.114693)
			(xy 415.007292 -234.122474) (xy 414.997138 -234.122976) (xy 413.597598 -234.122976) (xy 413.587442 -234.122469)
			(xy 413.568675 -234.114696) (xy 413.554311 -234.100335) (xy 413.546534 -234.08157) (xy 413.546036 -234.071414)
			(xy 407.5049 -234.071414) (xy 407.504379 -234.081568) (xy 407.496607 -234.10033) (xy 407.48225 -234.114693)
			(xy 407.463492 -234.122474) (xy 407.453338 -234.122976) (xy 406.053798 -234.122976) (xy 406.043642 -234.122469)
			(xy 406.024875 -234.114696) (xy 406.010511 -234.100335) (xy 406.002734 -234.08157) (xy 406.002236 -234.071414)
			(xy 309.6387 -234.071414) (xy 309.638179 -234.081568) (xy 309.630407 -234.10033) (xy 309.61605 -234.114693)
			(xy 309.597292 -234.122474) (xy 309.587138 -234.122976) (xy 308.187598 -234.122976) (xy 308.177442 -234.122469)
			(xy 308.158675 -234.114696) (xy 308.144311 -234.100335) (xy 308.136534 -234.08157) (xy 308.136036 -234.071414)
			(xy 302.0949 -234.071414) (xy 302.094379 -234.081568) (xy 302.086607 -234.10033) (xy 302.07225 -234.114693)
			(xy 302.053492 -234.122474) (xy 302.043338 -234.122976) (xy 300.643798 -234.122976) (xy 300.633642 -234.122469)
			(xy 300.614875 -234.114696) (xy 300.600511 -234.100335) (xy 300.592734 -234.08157) (xy 300.592236 -234.071414)
			(xy 294.5511 -234.071414) (xy 294.550579 -234.081568) (xy 294.542807 -234.10033) (xy 294.52845 -234.114693)
			(xy 294.509692 -234.122474) (xy 294.499538 -234.122976) (xy 293.099998 -234.122976) (xy 293.089842 -234.122469)
			(xy 293.071075 -234.114696) (xy 293.056711 -234.100335) (xy 293.048934 -234.08157) (xy 293.048436 -234.071414)
			(xy 287.0073 -234.071414) (xy 287.006779 -234.081568) (xy 286.999007 -234.10033) (xy 286.98465 -234.114693)
			(xy 286.965892 -234.122474) (xy 286.955738 -234.122976) (xy 285.556198 -234.122976) (xy 285.546042 -234.122469)
			(xy 285.527275 -234.114696) (xy 285.512911 -234.100335) (xy 285.505134 -234.08157) (xy 285.504636 -234.071414)
			(xy 279.4635 -234.071414) (xy 279.462979 -234.081568) (xy 279.455207 -234.10033) (xy 279.44085 -234.114693)
			(xy 279.422092 -234.122474) (xy 279.411938 -234.122976) (xy 278.012398 -234.122976) (xy 278.002242 -234.122469)
			(xy 277.983475 -234.114696) (xy 277.969111 -234.100335) (xy 277.961334 -234.08157) (xy 277.960836 -234.071414)
			(xy 271.9197 -234.071414) (xy 271.919179 -234.081568) (xy 271.911407 -234.10033) (xy 271.89705 -234.114693)
			(xy 271.878292 -234.122474) (xy 271.868138 -234.122976) (xy 270.468598 -234.122976) (xy 270.458442 -234.122469)
			(xy 270.439675 -234.114696) (xy 270.425311 -234.100335) (xy 270.417534 -234.08157) (xy 270.417036 -234.071414)
			(xy 264.3759 -234.071414) (xy 264.375379 -234.081568) (xy 264.367607 -234.10033) (xy 264.35325 -234.114693)
			(xy 264.334492 -234.122474) (xy 264.324338 -234.122976) (xy 262.924798 -234.122976) (xy 262.914642 -234.122469)
			(xy 262.895875 -234.114696) (xy 262.881511 -234.100335) (xy 262.873734 -234.08157) (xy 262.873236 -234.071414)
			(xy 256.8321 -234.071414) (xy 256.831579 -234.081568) (xy 256.823807 -234.10033) (xy 256.80945 -234.114693)
			(xy 256.790692 -234.122474) (xy 256.780538 -234.122976) (xy 255.380998 -234.122976) (xy 255.370842 -234.122469)
			(xy 255.352075 -234.114696) (xy 255.337711 -234.100335) (xy 255.329934 -234.08157) (xy 255.329436 -234.071414)
			(xy 212.371432 -234.071414) (xy 212.371047 -234.08159) (xy 212.363252 -234.100391) (xy 212.348854 -234.114776)
			(xy 212.330047 -234.122555) (xy 212.31987 -234.122976) (xy 210.92033 -234.122976) (xy 210.910162 -234.122512)
			(xy 210.891371 -234.114739) (xy 210.876985 -234.100366) (xy 210.869197 -234.081582) (xy 210.868768 -234.071414)
			(xy 204.827632 -234.071414) (xy 204.827247 -234.08159) (xy 204.819452 -234.100391) (xy 204.805054 -234.114776)
			(xy 204.786247 -234.122555) (xy 204.77607 -234.122976) (xy 203.37653 -234.122976) (xy 203.366362 -234.122512)
			(xy 203.347571 -234.114739) (xy 203.333185 -234.100366) (xy 203.325397 -234.081582) (xy 203.324968 -234.071414)
			(xy 197.283832 -234.071414) (xy 197.283447 -234.08159) (xy 197.275652 -234.100391) (xy 197.261254 -234.114776)
			(xy 197.242447 -234.122555) (xy 197.23227 -234.122976) (xy 195.83273 -234.122976) (xy 195.822562 -234.122512)
			(xy 195.803771 -234.114739) (xy 195.789385 -234.100366) (xy 195.781597 -234.081582) (xy 195.781168 -234.071414)
			(xy 189.740032 -234.071414) (xy 189.739647 -234.08159) (xy 189.731852 -234.100391) (xy 189.717454 -234.114776)
			(xy 189.698647 -234.122555) (xy 189.68847 -234.122976) (xy 188.28893 -234.122976) (xy 188.278762 -234.122512)
			(xy 188.259971 -234.114739) (xy 188.245585 -234.100366) (xy 188.237797 -234.081582) (xy 188.237368 -234.071414)
			(xy 182.196232 -234.071414) (xy 182.195847 -234.08159) (xy 182.188052 -234.100391) (xy 182.173654 -234.114776)
			(xy 182.154847 -234.122555) (xy 182.14467 -234.122976) (xy 180.74513 -234.122976) (xy 180.734962 -234.122512)
			(xy 180.716171 -234.114739) (xy 180.701785 -234.100366) (xy 180.693997 -234.081582) (xy 180.693568 -234.071414)
			(xy 174.652432 -234.071414) (xy 174.652047 -234.08159) (xy 174.644252 -234.100391) (xy 174.629854 -234.114776)
			(xy 174.611047 -234.122555) (xy 174.60087 -234.122976) (xy 173.20133 -234.122976) (xy 173.191162 -234.122512)
			(xy 173.172371 -234.114739) (xy 173.157985 -234.100366) (xy 173.150197 -234.081582) (xy 173.149768 -234.071414)
			(xy 167.108632 -234.071414) (xy 167.108247 -234.08159) (xy 167.100452 -234.100391) (xy 167.086054 -234.114776)
			(xy 167.067247 -234.122555) (xy 167.05707 -234.122976) (xy 165.65753 -234.122976) (xy 165.647362 -234.122512)
			(xy 165.628571 -234.114739) (xy 165.614185 -234.100366) (xy 165.606397 -234.081582) (xy 165.605968 -234.071414)
			(xy 159.564832 -234.071414) (xy 159.564447 -234.08159) (xy 159.556652 -234.100391) (xy 159.542254 -234.114776)
			(xy 159.523447 -234.122555) (xy 159.51327 -234.122976) (xy 158.11373 -234.122976) (xy 158.103562 -234.122512)
			(xy 158.084771 -234.114739) (xy 158.070385 -234.100366) (xy 158.062597 -234.081582) (xy 158.062168 -234.071414)
			(xy 61.698632 -234.071414) (xy 61.698247 -234.08159) (xy 61.690452 -234.100391) (xy 61.676054 -234.114776)
			(xy 61.657247 -234.122555) (xy 61.64707 -234.122976) (xy 60.24753 -234.122976) (xy 60.237362 -234.122512)
			(xy 60.218571 -234.114739) (xy 60.204185 -234.100366) (xy 60.196397 -234.081582) (xy 60.195968 -234.071414)
			(xy 54.154832 -234.071414) (xy 54.154447 -234.08159) (xy 54.146652 -234.100391) (xy 54.132254 -234.114776)
			(xy 54.113447 -234.122555) (xy 54.10327 -234.122976) (xy 52.70373 -234.122976) (xy 52.693562 -234.122512)
			(xy 52.674771 -234.114739) (xy 52.660385 -234.100366) (xy 52.652597 -234.081582) (xy 52.652168 -234.071414)
			(xy 46.611032 -234.071414) (xy 46.610647 -234.08159) (xy 46.602852 -234.100391) (xy 46.588454 -234.114776)
			(xy 46.569647 -234.122555) (xy 46.55947 -234.122976) (xy 45.15993 -234.122976) (xy 45.149762 -234.122512)
			(xy 45.130971 -234.114739) (xy 45.116585 -234.100366) (xy 45.108797 -234.081582) (xy 45.108368 -234.071414)
			(xy 39.067232 -234.071414) (xy 39.066847 -234.08159) (xy 39.059052 -234.100391) (xy 39.044654 -234.114776)
			(xy 39.025847 -234.122555) (xy 39.01567 -234.122976) (xy 37.61613 -234.122976) (xy 37.605962 -234.122512)
			(xy 37.587171 -234.114739) (xy 37.572785 -234.100366) (xy 37.564997 -234.081582) (xy 37.564568 -234.071414)
			(xy 31.523432 -234.071414) (xy 31.523047 -234.08159) (xy 31.515252 -234.100391) (xy 31.500854 -234.114776)
			(xy 31.482047 -234.122555) (xy 31.47187 -234.122976) (xy 30.07233 -234.122976) (xy 30.062162 -234.122512)
			(xy 30.043371 -234.114739) (xy 30.028985 -234.100366) (xy 30.021197 -234.081582) (xy 30.020768 -234.071414)
			(xy 23.979632 -234.071414) (xy 23.979247 -234.08159) (xy 23.971452 -234.100391) (xy 23.957054 -234.114776)
			(xy 23.938247 -234.122555) (xy 23.92807 -234.122976) (xy 22.52853 -234.122976) (xy 22.518362 -234.122512)
			(xy 22.499571 -234.114739) (xy 22.485185 -234.100366) (xy 22.477397 -234.081582) (xy 22.476968 -234.071414)
			(xy 16.435832 -234.071414) (xy 16.435447 -234.08159) (xy 16.427652 -234.100391) (xy 16.413254 -234.114776)
			(xy 16.394447 -234.122555) (xy 16.38427 -234.122976) (xy 14.98473 -234.122976) (xy 14.974562 -234.122512)
			(xy 14.955771 -234.114739) (xy 14.941385 -234.100366) (xy 14.933597 -234.081582) (xy 14.933168 -234.071414)
			(xy 8.892032 -234.071414) (xy 8.891647 -234.08159) (xy 8.883852 -234.100391) (xy 8.869454 -234.114776)
			(xy 8.850647 -234.122555) (xy 8.84047 -234.122976) (xy 7.44093 -234.122976) (xy 7.430762 -234.122512)
			(xy 7.411971 -234.114739) (xy 7.397585 -234.100366) (xy 7.389797 -234.081582) (xy 7.389368 -234.071414)
			(xy 2.509012 -234.071414) (xy 2.509012 -234.921298) (xy 11.489436 -234.921298) (xy 11.489436 -234.512358)
			(xy 11.489899 -234.502198) (xy 11.497687 -234.483428) (xy 11.512062 -234.469064) (xy 11.530837 -234.461291)
			(xy 11.540998 -234.460796) (xy 12.940538 -234.460796) (xy 12.950693 -234.461301) (xy 12.969455 -234.46908)
			(xy 12.983817 -234.483442) (xy 12.991598 -234.502203) (xy 12.9921 -234.512358) (xy 12.9921 -234.921298)
			(xy 19.033236 -234.921298) (xy 19.033236 -234.512358) (xy 19.033699 -234.502198) (xy 19.041487 -234.483428)
			(xy 19.055862 -234.469064) (xy 19.074637 -234.461291) (xy 19.084798 -234.460796) (xy 20.484338 -234.460796)
			(xy 20.494493 -234.461301) (xy 20.513255 -234.46908) (xy 20.527617 -234.483442) (xy 20.535398 -234.502203)
			(xy 20.5359 -234.512358) (xy 20.5359 -234.921298) (xy 26.577036 -234.921298) (xy 26.577036 -234.512358)
			(xy 26.577499 -234.502198) (xy 26.585287 -234.483428) (xy 26.599662 -234.469064) (xy 26.618437 -234.461291)
			(xy 26.628598 -234.460796) (xy 28.028138 -234.460796) (xy 28.038293 -234.461301) (xy 28.057055 -234.46908)
			(xy 28.071417 -234.483442) (xy 28.079198 -234.502203) (xy 28.0797 -234.512358) (xy 28.0797 -234.921298)
			(xy 34.120836 -234.921298) (xy 34.120836 -234.512358) (xy 34.121299 -234.502198) (xy 34.129087 -234.483428)
			(xy 34.143462 -234.469064) (xy 34.162237 -234.461291) (xy 34.172398 -234.460796) (xy 35.571938 -234.460796)
			(xy 35.582093 -234.461301) (xy 35.600855 -234.46908) (xy 35.615217 -234.483442) (xy 35.622998 -234.502203)
			(xy 35.6235 -234.512358) (xy 35.6235 -234.921298) (xy 41.664636 -234.921298) (xy 41.664636 -234.512358)
			(xy 41.665099 -234.502198) (xy 41.672887 -234.483428) (xy 41.687262 -234.469064) (xy 41.706037 -234.461291)
			(xy 41.716198 -234.460796) (xy 43.115738 -234.460796) (xy 43.125893 -234.461301) (xy 43.144655 -234.46908)
			(xy 43.159017 -234.483442) (xy 43.166798 -234.502203) (xy 43.1673 -234.512358) (xy 43.1673 -234.921298)
			(xy 49.208436 -234.921298) (xy 49.208436 -234.512358) (xy 49.208899 -234.502198) (xy 49.216687 -234.483428)
			(xy 49.231062 -234.469064) (xy 49.249837 -234.461291) (xy 49.259998 -234.460796) (xy 50.659538 -234.460796)
			(xy 50.669693 -234.461301) (xy 50.688455 -234.46908) (xy 50.702817 -234.483442) (xy 50.710598 -234.502203)
			(xy 50.7111 -234.512358) (xy 50.7111 -234.921298) (xy 56.752236 -234.921298) (xy 56.752236 -234.512358)
			(xy 56.752699 -234.502198) (xy 56.760487 -234.483428) (xy 56.774862 -234.469064) (xy 56.793637 -234.461291)
			(xy 56.803798 -234.460796) (xy 58.203338 -234.460796) (xy 58.213493 -234.461301) (xy 58.232255 -234.46908)
			(xy 58.246617 -234.483442) (xy 58.254398 -234.502203) (xy 58.2549 -234.512358) (xy 58.2549 -234.921298)
			(xy 64.296036 -234.921298) (xy 64.296036 -234.512358) (xy 64.296499 -234.502198) (xy 64.304287 -234.483428)
			(xy 64.318662 -234.469064) (xy 64.337437 -234.461291) (xy 64.347598 -234.460796) (xy 65.747138 -234.460796)
			(xy 65.757293 -234.461301) (xy 65.776055 -234.46908) (xy 65.790417 -234.483442) (xy 65.798198 -234.502203)
			(xy 65.7987 -234.512358) (xy 65.7987 -234.921298) (xy 162.162236 -234.921298) (xy 162.162236 -234.512358)
			(xy 162.162699 -234.502198) (xy 162.170487 -234.483428) (xy 162.184862 -234.469064) (xy 162.203637 -234.461291)
			(xy 162.213798 -234.460796) (xy 163.613338 -234.460796) (xy 163.623493 -234.461301) (xy 163.642255 -234.46908)
			(xy 163.656617 -234.483442) (xy 163.664398 -234.502203) (xy 163.6649 -234.512358) (xy 163.6649 -234.921298)
			(xy 169.706036 -234.921298) (xy 169.706036 -234.512358) (xy 169.706499 -234.502198) (xy 169.714287 -234.483428)
			(xy 169.728662 -234.469064) (xy 169.747437 -234.461291) (xy 169.757598 -234.460796) (xy 171.157138 -234.460796)
			(xy 171.167293 -234.461301) (xy 171.186055 -234.46908) (xy 171.200417 -234.483442) (xy 171.208198 -234.502203)
			(xy 171.2087 -234.512358) (xy 171.2087 -234.921298) (xy 177.249836 -234.921298) (xy 177.249836 -234.512358)
			(xy 177.250299 -234.502198) (xy 177.258087 -234.483428) (xy 177.272462 -234.469064) (xy 177.291237 -234.461291)
			(xy 177.301398 -234.460796) (xy 178.700938 -234.460796) (xy 178.711093 -234.461301) (xy 178.729855 -234.46908)
			(xy 178.744217 -234.483442) (xy 178.751998 -234.502203) (xy 178.7525 -234.512358) (xy 178.7525 -234.921298)
			(xy 184.793636 -234.921298) (xy 184.793636 -234.512358) (xy 184.794099 -234.502198) (xy 184.801887 -234.483428)
			(xy 184.816262 -234.469064) (xy 184.835037 -234.461291) (xy 184.845198 -234.460796) (xy 186.244738 -234.460796)
			(xy 186.254893 -234.461301) (xy 186.273655 -234.46908) (xy 186.288017 -234.483442) (xy 186.295798 -234.502203)
			(xy 186.2963 -234.512358) (xy 186.2963 -234.921298) (xy 192.337436 -234.921298) (xy 192.337436 -234.512358)
			(xy 192.337899 -234.502198) (xy 192.345687 -234.483428) (xy 192.360062 -234.469064) (xy 192.378837 -234.461291)
			(xy 192.388998 -234.460796) (xy 193.788538 -234.460796) (xy 193.798693 -234.461301) (xy 193.817455 -234.46908)
			(xy 193.831817 -234.483442) (xy 193.839598 -234.502203) (xy 193.8401 -234.512358) (xy 193.8401 -234.921298)
			(xy 199.881236 -234.921298) (xy 199.881236 -234.512358) (xy 199.881699 -234.502198) (xy 199.889487 -234.483428)
			(xy 199.903862 -234.469064) (xy 199.922637 -234.461291) (xy 199.932798 -234.460796) (xy 201.332338 -234.460796)
			(xy 201.342493 -234.461301) (xy 201.361255 -234.46908) (xy 201.375617 -234.483442) (xy 201.383398 -234.502203)
			(xy 201.3839 -234.512358) (xy 201.3839 -234.921298) (xy 207.425036 -234.921298) (xy 207.425036 -234.512358)
			(xy 207.425499 -234.502198) (xy 207.433287 -234.483428) (xy 207.447662 -234.469064) (xy 207.466437 -234.461291)
			(xy 207.476598 -234.460796) (xy 208.876138 -234.460796) (xy 208.886293 -234.461301) (xy 208.905055 -234.46908)
			(xy 208.919417 -234.483442) (xy 208.927198 -234.502203) (xy 208.9277 -234.512358) (xy 208.9277 -234.921298)
			(xy 214.968836 -234.921298) (xy 214.968836 -234.512358) (xy 214.969299 -234.502198) (xy 214.977087 -234.483428)
			(xy 214.991462 -234.469064) (xy 215.010237 -234.461291) (xy 215.020398 -234.460796) (xy 216.419938 -234.460796)
			(xy 216.430093 -234.461301) (xy 216.448855 -234.46908) (xy 216.463217 -234.483442) (xy 216.470998 -234.502203)
			(xy 216.4715 -234.512358) (xy 216.4715 -234.921298) (xy 259.429504 -234.921298) (xy 259.429504 -234.512358)
			(xy 259.429998 -234.502202) (xy 259.43778 -234.483438) (xy 259.452145 -234.469076) (xy 259.47091 -234.461297)
			(xy 259.481066 -234.460796) (xy 260.880606 -234.460796) (xy 260.890759 -234.461328) (xy 260.90952 -234.469096)
			(xy 260.923884 -234.48345) (xy 260.931665 -234.502205) (xy 260.932168 -234.512358) (xy 260.932168 -234.921298)
			(xy 266.973304 -234.921298) (xy 266.973304 -234.512358) (xy 266.973798 -234.502202) (xy 266.98158 -234.483438)
			(xy 266.995945 -234.469076) (xy 267.01471 -234.461297) (xy 267.024866 -234.460796) (xy 268.424406 -234.460796)
			(xy 268.434559 -234.461328) (xy 268.45332 -234.469096) (xy 268.467684 -234.48345) (xy 268.475465 -234.502205)
			(xy 268.475968 -234.512358) (xy 268.475968 -234.921298) (xy 274.517104 -234.921298) (xy 274.517104 -234.512358)
			(xy 274.517598 -234.502202) (xy 274.52538 -234.483438) (xy 274.539745 -234.469076) (xy 274.55851 -234.461297)
			(xy 274.568666 -234.460796) (xy 275.968206 -234.460796) (xy 275.978359 -234.461328) (xy 275.99712 -234.469096)
			(xy 276.011484 -234.48345) (xy 276.019265 -234.502205) (xy 276.019768 -234.512358) (xy 276.019768 -234.921298)
			(xy 282.060904 -234.921298) (xy 282.060904 -234.512358) (xy 282.061398 -234.502202) (xy 282.06918 -234.483438)
			(xy 282.083545 -234.469076) (xy 282.10231 -234.461297) (xy 282.112466 -234.460796) (xy 283.512006 -234.460796)
			(xy 283.522159 -234.461328) (xy 283.54092 -234.469096) (xy 283.555284 -234.48345) (xy 283.563065 -234.502205)
			(xy 283.563568 -234.512358) (xy 283.563568 -234.921298) (xy 289.604704 -234.921298) (xy 289.604704 -234.512358)
			(xy 289.605198 -234.502202) (xy 289.61298 -234.483438) (xy 289.627345 -234.469076) (xy 289.64611 -234.461297)
			(xy 289.656266 -234.460796) (xy 291.055806 -234.460796) (xy 291.065959 -234.461328) (xy 291.08472 -234.469096)
			(xy 291.099084 -234.48345) (xy 291.106865 -234.502205) (xy 291.107368 -234.512358) (xy 291.107368 -234.921298)
			(xy 297.148504 -234.921298) (xy 297.148504 -234.512358) (xy 297.148998 -234.502202) (xy 297.15678 -234.483438)
			(xy 297.171145 -234.469076) (xy 297.18991 -234.461297) (xy 297.200066 -234.460796) (xy 298.599606 -234.460796)
			(xy 298.609759 -234.461328) (xy 298.62852 -234.469096) (xy 298.642884 -234.48345) (xy 298.650665 -234.502205)
			(xy 298.651168 -234.512358) (xy 298.651168 -234.921298) (xy 304.692304 -234.921298) (xy 304.692304 -234.512358)
			(xy 304.692798 -234.502202) (xy 304.70058 -234.483438) (xy 304.714945 -234.469076) (xy 304.73371 -234.461297)
			(xy 304.743866 -234.460796) (xy 306.143406 -234.460796) (xy 306.153559 -234.461328) (xy 306.17232 -234.469096)
			(xy 306.186684 -234.48345) (xy 306.194465 -234.502205) (xy 306.194968 -234.512358) (xy 306.194968 -234.921298)
			(xy 312.236104 -234.921298) (xy 312.236104 -234.512358) (xy 312.236598 -234.502202) (xy 312.24438 -234.483438)
			(xy 312.258745 -234.469076) (xy 312.27751 -234.461297) (xy 312.287666 -234.460796) (xy 313.687206 -234.460796)
			(xy 313.697359 -234.461328) (xy 313.71612 -234.469096) (xy 313.730484 -234.48345) (xy 313.738265 -234.502205)
			(xy 313.738768 -234.512358) (xy 313.738768 -234.921298) (xy 410.102304 -234.921298) (xy 410.102304 -234.512358)
			(xy 410.102798 -234.502202) (xy 410.11058 -234.483438) (xy 410.124945 -234.469076) (xy 410.14371 -234.461297)
			(xy 410.153866 -234.460796) (xy 411.553406 -234.460796) (xy 411.563559 -234.461328) (xy 411.58232 -234.469096)
			(xy 411.596684 -234.48345) (xy 411.604465 -234.502205) (xy 411.604968 -234.512358) (xy 411.604968 -234.921298)
			(xy 417.646104 -234.921298) (xy 417.646104 -234.512358) (xy 417.646598 -234.502202) (xy 417.65438 -234.483438)
			(xy 417.668745 -234.469076) (xy 417.68751 -234.461297) (xy 417.697666 -234.460796) (xy 419.097206 -234.460796)
			(xy 419.107359 -234.461328) (xy 419.12612 -234.469096) (xy 419.140484 -234.48345) (xy 419.148265 -234.502205)
			(xy 419.148768 -234.512358) (xy 419.148768 -234.921298) (xy 425.189904 -234.921298) (xy 425.189904 -234.512358)
			(xy 425.190398 -234.502202) (xy 425.19818 -234.483438) (xy 425.212545 -234.469076) (xy 425.23131 -234.461297)
			(xy 425.241466 -234.460796) (xy 426.641006 -234.460796) (xy 426.651159 -234.461328) (xy 426.66992 -234.469096)
			(xy 426.684284 -234.48345) (xy 426.692065 -234.502205) (xy 426.692568 -234.512358) (xy 426.692568 -234.921298)
			(xy 432.733704 -234.921298) (xy 432.733704 -234.512358) (xy 432.734198 -234.502202) (xy 432.74198 -234.483438)
			(xy 432.756345 -234.469076) (xy 432.77511 -234.461297) (xy 432.785266 -234.460796) (xy 434.184806 -234.460796)
			(xy 434.194959 -234.461328) (xy 434.21372 -234.469096) (xy 434.228084 -234.48345) (xy 434.235865 -234.502205)
			(xy 434.236368 -234.512358) (xy 434.236368 -234.921298) (xy 440.277504 -234.921298) (xy 440.277504 -234.512358)
			(xy 440.277998 -234.502202) (xy 440.28578 -234.483438) (xy 440.300145 -234.469076) (xy 440.31891 -234.461297)
			(xy 440.329066 -234.460796) (xy 441.728606 -234.460796) (xy 441.738759 -234.461328) (xy 441.75752 -234.469096)
			(xy 441.771884 -234.48345) (xy 441.779665 -234.502205) (xy 441.780168 -234.512358) (xy 441.780168 -234.921298)
			(xy 447.821304 -234.921298) (xy 447.821304 -234.512358) (xy 447.821798 -234.502202) (xy 447.82958 -234.483438)
			(xy 447.843945 -234.469076) (xy 447.86271 -234.461297) (xy 447.872866 -234.460796) (xy 449.272406 -234.460796)
			(xy 449.282559 -234.461328) (xy 449.30132 -234.469096) (xy 449.315684 -234.48345) (xy 449.323465 -234.502205)
			(xy 449.323968 -234.512358) (xy 449.323968 -234.921298) (xy 455.365104 -234.921298) (xy 455.365104 -234.512358)
			(xy 455.365598 -234.502202) (xy 455.37338 -234.483438) (xy 455.387745 -234.469076) (xy 455.40651 -234.461297)
			(xy 455.416666 -234.460796) (xy 456.816206 -234.460796) (xy 456.826359 -234.461328) (xy 456.84512 -234.469096)
			(xy 456.859484 -234.48345) (xy 456.867265 -234.502205) (xy 456.867768 -234.512358) (xy 456.867768 -234.921298)
			(xy 462.908904 -234.921298) (xy 462.908904 -234.512358) (xy 462.909398 -234.502202) (xy 462.91718 -234.483438)
			(xy 462.931545 -234.469076) (xy 462.95031 -234.461297) (xy 462.960466 -234.460796) (xy 464.360006 -234.460796)
			(xy 464.370159 -234.461328) (xy 464.38892 -234.469096) (xy 464.403284 -234.48345) (xy 464.411065 -234.502205)
			(xy 464.411568 -234.512358) (xy 464.411568 -234.921298) (xy 464.411065 -234.931455) (xy 464.403292 -234.950223)
			(xy 464.38893 -234.964588) (xy 464.370163 -234.972364) (xy 464.360006 -234.97286) (xy 462.960466 -234.97286)
			(xy 462.950306 -234.972394) (xy 462.931535 -234.964608) (xy 462.917171 -234.950234) (xy 462.909398 -234.931459)
			(xy 462.908904 -234.921298) (xy 456.867768 -234.921298) (xy 456.867265 -234.931455) (xy 456.859492 -234.950223)
			(xy 456.84513 -234.964588) (xy 456.826363 -234.972364) (xy 456.816206 -234.97286) (xy 455.416666 -234.97286)
			(xy 455.406506 -234.972394) (xy 455.387735 -234.964608) (xy 455.373371 -234.950234) (xy 455.365598 -234.931459)
			(xy 455.365104 -234.921298) (xy 449.323968 -234.921298) (xy 449.323465 -234.931455) (xy 449.315692 -234.950223)
			(xy 449.30133 -234.964588) (xy 449.282563 -234.972364) (xy 449.272406 -234.97286) (xy 447.872866 -234.97286)
			(xy 447.862706 -234.972394) (xy 447.843935 -234.964608) (xy 447.829571 -234.950234) (xy 447.821798 -234.931459)
			(xy 447.821304 -234.921298) (xy 441.780168 -234.921298) (xy 441.779665 -234.931455) (xy 441.771892 -234.950223)
			(xy 441.75753 -234.964588) (xy 441.738763 -234.972364) (xy 441.728606 -234.97286) (xy 440.329066 -234.97286)
			(xy 440.318906 -234.972394) (xy 440.300135 -234.964608) (xy 440.285771 -234.950234) (xy 440.277998 -234.931459)
			(xy 440.277504 -234.921298) (xy 434.236368 -234.921298) (xy 434.235865 -234.931455) (xy 434.228092 -234.950223)
			(xy 434.21373 -234.964588) (xy 434.194963 -234.972364) (xy 434.184806 -234.97286) (xy 432.785266 -234.97286)
			(xy 432.775106 -234.972394) (xy 432.756335 -234.964608) (xy 432.741971 -234.950234) (xy 432.734198 -234.931459)
			(xy 432.733704 -234.921298) (xy 426.692568 -234.921298) (xy 426.692065 -234.931455) (xy 426.684292 -234.950223)
			(xy 426.66993 -234.964588) (xy 426.651163 -234.972364) (xy 426.641006 -234.97286) (xy 425.241466 -234.97286)
			(xy 425.231306 -234.972394) (xy 425.212535 -234.964608) (xy 425.198171 -234.950234) (xy 425.190398 -234.931459)
			(xy 425.189904 -234.921298) (xy 419.148768 -234.921298) (xy 419.148265 -234.931455) (xy 419.140492 -234.950223)
			(xy 419.12613 -234.964588) (xy 419.107363 -234.972364) (xy 419.097206 -234.97286) (xy 417.697666 -234.97286)
			(xy 417.687506 -234.972394) (xy 417.668735 -234.964608) (xy 417.654371 -234.950234) (xy 417.646598 -234.931459)
			(xy 417.646104 -234.921298) (xy 411.604968 -234.921298) (xy 411.604465 -234.931455) (xy 411.596692 -234.950223)
			(xy 411.58233 -234.964588) (xy 411.563563 -234.972364) (xy 411.553406 -234.97286) (xy 410.153866 -234.97286)
			(xy 410.143706 -234.972394) (xy 410.124935 -234.964608) (xy 410.110571 -234.950234) (xy 410.102798 -234.931459)
			(xy 410.102304 -234.921298) (xy 313.738768 -234.921298) (xy 313.738265 -234.931455) (xy 313.730492 -234.950223)
			(xy 313.71613 -234.964588) (xy 313.697363 -234.972364) (xy 313.687206 -234.97286) (xy 312.287666 -234.97286)
			(xy 312.277506 -234.972394) (xy 312.258735 -234.964608) (xy 312.244371 -234.950234) (xy 312.236598 -234.931459)
			(xy 312.236104 -234.921298) (xy 306.194968 -234.921298) (xy 306.194465 -234.931455) (xy 306.186692 -234.950223)
			(xy 306.17233 -234.964588) (xy 306.153563 -234.972364) (xy 306.143406 -234.97286) (xy 304.743866 -234.97286)
			(xy 304.733706 -234.972394) (xy 304.714935 -234.964608) (xy 304.700571 -234.950234) (xy 304.692798 -234.931459)
			(xy 304.692304 -234.921298) (xy 298.651168 -234.921298) (xy 298.650665 -234.931455) (xy 298.642892 -234.950223)
			(xy 298.62853 -234.964588) (xy 298.609763 -234.972364) (xy 298.599606 -234.97286) (xy 297.200066 -234.97286)
			(xy 297.189906 -234.972394) (xy 297.171135 -234.964608) (xy 297.156771 -234.950234) (xy 297.148998 -234.931459)
			(xy 297.148504 -234.921298) (xy 291.107368 -234.921298) (xy 291.106865 -234.931455) (xy 291.099092 -234.950223)
			(xy 291.08473 -234.964588) (xy 291.065963 -234.972364) (xy 291.055806 -234.97286) (xy 289.656266 -234.97286)
			(xy 289.646106 -234.972394) (xy 289.627335 -234.964608) (xy 289.612971 -234.950234) (xy 289.605198 -234.931459)
			(xy 289.604704 -234.921298) (xy 283.563568 -234.921298) (xy 283.563065 -234.931455) (xy 283.555292 -234.950223)
			(xy 283.54093 -234.964588) (xy 283.522163 -234.972364) (xy 283.512006 -234.97286) (xy 282.112466 -234.97286)
			(xy 282.102306 -234.972394) (xy 282.083535 -234.964608) (xy 282.069171 -234.950234) (xy 282.061398 -234.931459)
			(xy 282.060904 -234.921298) (xy 276.019768 -234.921298) (xy 276.019265 -234.931455) (xy 276.011492 -234.950223)
			(xy 275.99713 -234.964588) (xy 275.978363 -234.972364) (xy 275.968206 -234.97286) (xy 274.568666 -234.97286)
			(xy 274.558506 -234.972394) (xy 274.539735 -234.964608) (xy 274.525371 -234.950234) (xy 274.517598 -234.931459)
			(xy 274.517104 -234.921298) (xy 268.475968 -234.921298) (xy 268.475465 -234.931455) (xy 268.467692 -234.950223)
			(xy 268.45333 -234.964588) (xy 268.434563 -234.972364) (xy 268.424406 -234.97286) (xy 267.024866 -234.97286)
			(xy 267.014706 -234.972394) (xy 266.995935 -234.964608) (xy 266.981571 -234.950234) (xy 266.973798 -234.931459)
			(xy 266.973304 -234.921298) (xy 260.932168 -234.921298) (xy 260.931665 -234.931455) (xy 260.923892 -234.950223)
			(xy 260.90953 -234.964588) (xy 260.890763 -234.972364) (xy 260.880606 -234.97286) (xy 259.481066 -234.97286)
			(xy 259.470906 -234.972394) (xy 259.452135 -234.964608) (xy 259.437771 -234.950234) (xy 259.429998 -234.931459)
			(xy 259.429504 -234.921298) (xy 216.4715 -234.921298) (xy 216.470966 -234.931451) (xy 216.463199 -234.950213)
			(xy 216.448846 -234.964577) (xy 216.430091 -234.972358) (xy 216.419938 -234.97286) (xy 215.020398 -234.97286)
			(xy 215.01024 -234.972368) (xy 214.99147 -234.964593) (xy 214.977105 -234.950226) (xy 214.969331 -234.931456)
			(xy 214.968836 -234.921298) (xy 208.9277 -234.921298) (xy 208.927166 -234.931451) (xy 208.919399 -234.950213)
			(xy 208.905046 -234.964577) (xy 208.886291 -234.972358) (xy 208.876138 -234.97286) (xy 207.476598 -234.97286)
			(xy 207.46644 -234.972368) (xy 207.44767 -234.964593) (xy 207.433305 -234.950226) (xy 207.425531 -234.931456)
			(xy 207.425036 -234.921298) (xy 201.3839 -234.921298) (xy 201.383366 -234.931451) (xy 201.375599 -234.950213)
			(xy 201.361246 -234.964577) (xy 201.342491 -234.972358) (xy 201.332338 -234.97286) (xy 199.932798 -234.97286)
			(xy 199.92264 -234.972368) (xy 199.90387 -234.964593) (xy 199.889505 -234.950226) (xy 199.881731 -234.931456)
			(xy 199.881236 -234.921298) (xy 193.8401 -234.921298) (xy 193.839566 -234.931451) (xy 193.831799 -234.950213)
			(xy 193.817446 -234.964577) (xy 193.798691 -234.972358) (xy 193.788538 -234.97286) (xy 192.388998 -234.97286)
			(xy 192.37884 -234.972368) (xy 192.36007 -234.964593) (xy 192.345705 -234.950226) (xy 192.337931 -234.931456)
			(xy 192.337436 -234.921298) (xy 186.2963 -234.921298) (xy 186.295766 -234.931451) (xy 186.287999 -234.950213)
			(xy 186.273646 -234.964577) (xy 186.254891 -234.972358) (xy 186.244738 -234.97286) (xy 184.845198 -234.97286)
			(xy 184.83504 -234.972368) (xy 184.81627 -234.964593) (xy 184.801905 -234.950226) (xy 184.794131 -234.931456)
			(xy 184.793636 -234.921298) (xy 178.7525 -234.921298) (xy 178.751966 -234.931451) (xy 178.744199 -234.950213)
			(xy 178.729846 -234.964577) (xy 178.711091 -234.972358) (xy 178.700938 -234.97286) (xy 177.301398 -234.97286)
			(xy 177.29124 -234.972368) (xy 177.27247 -234.964593) (xy 177.258105 -234.950226) (xy 177.250331 -234.931456)
			(xy 177.249836 -234.921298) (xy 171.2087 -234.921298) (xy 171.208166 -234.931451) (xy 171.200399 -234.950213)
			(xy 171.186046 -234.964577) (xy 171.167291 -234.972358) (xy 171.157138 -234.97286) (xy 169.757598 -234.97286)
			(xy 169.74744 -234.972368) (xy 169.72867 -234.964593) (xy 169.714305 -234.950226) (xy 169.706531 -234.931456)
			(xy 169.706036 -234.921298) (xy 163.6649 -234.921298) (xy 163.664366 -234.931451) (xy 163.656599 -234.950213)
			(xy 163.642246 -234.964577) (xy 163.623491 -234.972358) (xy 163.613338 -234.97286) (xy 162.213798 -234.97286)
			(xy 162.20364 -234.972368) (xy 162.18487 -234.964593) (xy 162.170505 -234.950226) (xy 162.162731 -234.931456)
			(xy 162.162236 -234.921298) (xy 65.7987 -234.921298) (xy 65.798166 -234.931451) (xy 65.790399 -234.950213)
			(xy 65.776046 -234.964577) (xy 65.757291 -234.972358) (xy 65.747138 -234.97286) (xy 64.347598 -234.97286)
			(xy 64.33744 -234.972368) (xy 64.31867 -234.964593) (xy 64.304305 -234.950226) (xy 64.296531 -234.931456)
			(xy 64.296036 -234.921298) (xy 58.2549 -234.921298) (xy 58.254366 -234.931451) (xy 58.246599 -234.950213)
			(xy 58.232246 -234.964577) (xy 58.213491 -234.972358) (xy 58.203338 -234.97286) (xy 56.803798 -234.97286)
			(xy 56.79364 -234.972368) (xy 56.77487 -234.964593) (xy 56.760505 -234.950226) (xy 56.752731 -234.931456)
			(xy 56.752236 -234.921298) (xy 50.7111 -234.921298) (xy 50.710566 -234.931451) (xy 50.702799 -234.950213)
			(xy 50.688446 -234.964577) (xy 50.669691 -234.972358) (xy 50.659538 -234.97286) (xy 49.259998 -234.97286)
			(xy 49.24984 -234.972368) (xy 49.23107 -234.964593) (xy 49.216705 -234.950226) (xy 49.208931 -234.931456)
			(xy 49.208436 -234.921298) (xy 43.1673 -234.921298) (xy 43.166766 -234.931451) (xy 43.158999 -234.950213)
			(xy 43.144646 -234.964577) (xy 43.125891 -234.972358) (xy 43.115738 -234.97286) (xy 41.716198 -234.97286)
			(xy 41.70604 -234.972368) (xy 41.68727 -234.964593) (xy 41.672905 -234.950226) (xy 41.665131 -234.931456)
			(xy 41.664636 -234.921298) (xy 35.6235 -234.921298) (xy 35.622966 -234.931451) (xy 35.615199 -234.950213)
			(xy 35.600846 -234.964577) (xy 35.582091 -234.972358) (xy 35.571938 -234.97286) (xy 34.172398 -234.97286)
			(xy 34.16224 -234.972368) (xy 34.14347 -234.964593) (xy 34.129105 -234.950226) (xy 34.121331 -234.931456)
			(xy 34.120836 -234.921298) (xy 28.0797 -234.921298) (xy 28.079166 -234.931451) (xy 28.071399 -234.950213)
			(xy 28.057046 -234.964577) (xy 28.038291 -234.972358) (xy 28.028138 -234.97286) (xy 26.628598 -234.97286)
			(xy 26.61844 -234.972368) (xy 26.59967 -234.964593) (xy 26.585305 -234.950226) (xy 26.577531 -234.931456)
			(xy 26.577036 -234.921298) (xy 20.5359 -234.921298) (xy 20.535366 -234.931451) (xy 20.527599 -234.950213)
			(xy 20.513246 -234.964577) (xy 20.494491 -234.972358) (xy 20.484338 -234.97286) (xy 19.084798 -234.97286)
			(xy 19.07464 -234.972368) (xy 19.05587 -234.964593) (xy 19.041505 -234.950226) (xy 19.033731 -234.931456)
			(xy 19.033236 -234.921298) (xy 12.9921 -234.921298) (xy 12.991566 -234.931451) (xy 12.983799 -234.950213)
			(xy 12.969446 -234.964577) (xy 12.950691 -234.972358) (xy 12.940538 -234.97286) (xy 11.540998 -234.97286)
			(xy 11.53084 -234.972368) (xy 11.51207 -234.964593) (xy 11.497705 -234.950226) (xy 11.489931 -234.931456)
			(xy 11.489436 -234.921298) (xy 2.509012 -234.921298) (xy 2.509012 -235.771436) (xy 7.389368 -235.771436)
			(xy 7.389368 -235.362496) (xy 7.389818 -235.352346) (xy 7.397609 -235.333599) (xy 7.411996 -235.319277)
			(xy 7.430778 -235.311572) (xy 7.44093 -235.311188) (xy 8.84047 -235.311188) (xy 8.850588 -235.311749)
			(xy 8.869299 -235.319458) (xy 8.883655 -235.333721) (xy 8.891484 -235.352381) (xy 8.892032 -235.362496)
			(xy 8.892032 -235.771436) (xy 14.933168 -235.771436) (xy 14.933168 -235.362496) (xy 14.933618 -235.352346)
			(xy 14.941409 -235.333599) (xy 14.955796 -235.319277) (xy 14.974578 -235.311572) (xy 14.98473 -235.311188)
			(xy 16.38427 -235.311188) (xy 16.394388 -235.311749) (xy 16.413099 -235.319458) (xy 16.427455 -235.333721)
			(xy 16.435284 -235.352381) (xy 16.435832 -235.362496) (xy 16.435832 -235.771436) (xy 22.476968 -235.771436)
			(xy 22.476968 -235.362496) (xy 22.477418 -235.352346) (xy 22.485209 -235.333599) (xy 22.499596 -235.319277)
			(xy 22.518378 -235.311572) (xy 22.52853 -235.311188) (xy 23.92807 -235.311188) (xy 23.938188 -235.311749)
			(xy 23.956899 -235.319458) (xy 23.971255 -235.333721) (xy 23.979084 -235.352381) (xy 23.979632 -235.362496)
			(xy 23.979632 -235.771436) (xy 30.020768 -235.771436) (xy 30.020768 -235.362496) (xy 30.021218 -235.352346)
			(xy 30.029009 -235.333599) (xy 30.043396 -235.319277) (xy 30.062178 -235.311572) (xy 30.07233 -235.311188)
			(xy 31.47187 -235.311188) (xy 31.481988 -235.311749) (xy 31.500699 -235.319458) (xy 31.515055 -235.333721)
			(xy 31.522884 -235.352381) (xy 31.523432 -235.362496) (xy 31.523432 -235.771436) (xy 37.564568 -235.771436)
			(xy 37.564568 -235.362496) (xy 37.565018 -235.352346) (xy 37.572809 -235.333599) (xy 37.587196 -235.319277)
			(xy 37.605978 -235.311572) (xy 37.61613 -235.311188) (xy 39.01567 -235.311188) (xy 39.025788 -235.311749)
			(xy 39.044499 -235.319458) (xy 39.058855 -235.333721) (xy 39.066684 -235.352381) (xy 39.067232 -235.362496)
			(xy 39.067232 -235.771436) (xy 45.108368 -235.771436) (xy 45.108368 -235.362496) (xy 45.108818 -235.352346)
			(xy 45.116609 -235.333599) (xy 45.130996 -235.319277) (xy 45.149778 -235.311572) (xy 45.15993 -235.311188)
			(xy 46.55947 -235.311188) (xy 46.569588 -235.311749) (xy 46.588299 -235.319458) (xy 46.602655 -235.333721)
			(xy 46.610484 -235.352381) (xy 46.611032 -235.362496) (xy 46.611032 -235.771436) (xy 52.652168 -235.771436)
			(xy 52.652168 -235.362496) (xy 52.652618 -235.352346) (xy 52.660409 -235.333599) (xy 52.674796 -235.319277)
			(xy 52.693578 -235.311572) (xy 52.70373 -235.311188) (xy 54.10327 -235.311188) (xy 54.113388 -235.311749)
			(xy 54.132099 -235.319458) (xy 54.146455 -235.333721) (xy 54.154284 -235.352381) (xy 54.154832 -235.362496)
			(xy 54.154832 -235.771436) (xy 60.195968 -235.771436) (xy 60.195968 -235.362496) (xy 60.196418 -235.352346)
			(xy 60.204209 -235.333599) (xy 60.218596 -235.319277) (xy 60.237378 -235.311572) (xy 60.24753 -235.311188)
			(xy 61.64707 -235.311188) (xy 61.657188 -235.311749) (xy 61.675899 -235.319458) (xy 61.690255 -235.333721)
			(xy 61.698084 -235.352381) (xy 61.698632 -235.362496) (xy 61.698632 -235.771436) (xy 158.062168 -235.771436)
			(xy 158.062168 -235.362496) (xy 158.062618 -235.352346) (xy 158.070409 -235.333599) (xy 158.084796 -235.319277)
			(xy 158.103578 -235.311572) (xy 158.11373 -235.311188) (xy 159.51327 -235.311188) (xy 159.523388 -235.311749)
			(xy 159.542099 -235.319458) (xy 159.556455 -235.333721) (xy 159.564284 -235.352381) (xy 159.564832 -235.362496)
			(xy 159.564832 -235.771436) (xy 165.605968 -235.771436) (xy 165.605968 -235.362496) (xy 165.606418 -235.352346)
			(xy 165.614209 -235.333599) (xy 165.628596 -235.319277) (xy 165.647378 -235.311572) (xy 165.65753 -235.311188)
			(xy 167.05707 -235.311188) (xy 167.067188 -235.311749) (xy 167.085899 -235.319458) (xy 167.100255 -235.333721)
			(xy 167.108084 -235.352381) (xy 167.108632 -235.362496) (xy 167.108632 -235.771436) (xy 173.149768 -235.771436)
			(xy 173.149768 -235.362496) (xy 173.150218 -235.352346) (xy 173.158009 -235.333599) (xy 173.172396 -235.319277)
			(xy 173.191178 -235.311572) (xy 173.20133 -235.311188) (xy 174.60087 -235.311188) (xy 174.610988 -235.311749)
			(xy 174.629699 -235.319458) (xy 174.644055 -235.333721) (xy 174.651884 -235.352381) (xy 174.652432 -235.362496)
			(xy 174.652432 -235.771436) (xy 180.693568 -235.771436) (xy 180.693568 -235.362496) (xy 180.694018 -235.352346)
			(xy 180.701809 -235.333599) (xy 180.716196 -235.319277) (xy 180.734978 -235.311572) (xy 180.74513 -235.311188)
			(xy 182.14467 -235.311188) (xy 182.154788 -235.311749) (xy 182.173499 -235.319458) (xy 182.187855 -235.333721)
			(xy 182.195684 -235.352381) (xy 182.196232 -235.362496) (xy 182.196232 -235.771436) (xy 188.237368 -235.771436)
			(xy 188.237368 -235.362496) (xy 188.237818 -235.352346) (xy 188.245609 -235.333599) (xy 188.259996 -235.319277)
			(xy 188.278778 -235.311572) (xy 188.28893 -235.311188) (xy 189.68847 -235.311188) (xy 189.698588 -235.311749)
			(xy 189.717299 -235.319458) (xy 189.731655 -235.333721) (xy 189.739484 -235.352381) (xy 189.740032 -235.362496)
			(xy 189.740032 -235.771436) (xy 195.781168 -235.771436) (xy 195.781168 -235.362496) (xy 195.781618 -235.352346)
			(xy 195.789409 -235.333599) (xy 195.803796 -235.319277) (xy 195.822578 -235.311572) (xy 195.83273 -235.311188)
			(xy 197.23227 -235.311188) (xy 197.242388 -235.311749) (xy 197.261099 -235.319458) (xy 197.275455 -235.333721)
			(xy 197.283284 -235.352381) (xy 197.283832 -235.362496) (xy 197.283832 -235.771436) (xy 203.324968 -235.771436)
			(xy 203.324968 -235.362496) (xy 203.325418 -235.352346) (xy 203.333209 -235.333599) (xy 203.347596 -235.319277)
			(xy 203.366378 -235.311572) (xy 203.37653 -235.311188) (xy 204.77607 -235.311188) (xy 204.786188 -235.311749)
			(xy 204.804899 -235.319458) (xy 204.819255 -235.333721) (xy 204.827084 -235.352381) (xy 204.827632 -235.362496)
			(xy 204.827632 -235.771436) (xy 210.868768 -235.771436) (xy 210.868768 -235.362496) (xy 210.869218 -235.352346)
			(xy 210.877009 -235.333599) (xy 210.891396 -235.319277) (xy 210.910178 -235.311572) (xy 210.92033 -235.311188)
			(xy 212.31987 -235.311188) (xy 212.329988 -235.311749) (xy 212.348699 -235.319458) (xy 212.363055 -235.333721)
			(xy 212.370884 -235.352381) (xy 212.371432 -235.362496) (xy 212.371432 -235.771436) (xy 255.329436 -235.771436)
			(xy 255.329436 -235.362496) (xy 255.329819 -235.352337) (xy 255.337623 -235.333578) (xy 255.352032 -235.319253)
			(xy 255.370837 -235.31156) (xy 255.380998 -235.311188) (xy 256.780538 -235.311188) (xy 256.790661 -235.311694)
			(xy 256.809373 -235.319425) (xy 256.823726 -235.333704) (xy 256.831553 -235.352376) (xy 256.8321 -235.362496)
			(xy 256.8321 -235.771436) (xy 262.873236 -235.771436) (xy 262.873236 -235.362496) (xy 262.873619 -235.352337)
			(xy 262.881423 -235.333578) (xy 262.895832 -235.319253) (xy 262.914637 -235.31156) (xy 262.924798 -235.311188)
			(xy 264.324338 -235.311188) (xy 264.334461 -235.311694) (xy 264.353173 -235.319425) (xy 264.367526 -235.333704)
			(xy 264.375353 -235.352376) (xy 264.3759 -235.362496) (xy 264.3759 -235.771436) (xy 270.417036 -235.771436)
			(xy 270.417036 -235.362496) (xy 270.417419 -235.352337) (xy 270.425223 -235.333578) (xy 270.439632 -235.319253)
			(xy 270.458437 -235.31156) (xy 270.468598 -235.311188) (xy 271.868138 -235.311188) (xy 271.878261 -235.311694)
			(xy 271.896973 -235.319425) (xy 271.911326 -235.333704) (xy 271.919153 -235.352376) (xy 271.9197 -235.362496)
			(xy 271.9197 -235.771436) (xy 277.960836 -235.771436) (xy 277.960836 -235.362496) (xy 277.961219 -235.352337)
			(xy 277.969023 -235.333578) (xy 277.983432 -235.319253) (xy 278.002237 -235.31156) (xy 278.012398 -235.311188)
			(xy 279.411938 -235.311188) (xy 279.422061 -235.311694) (xy 279.440773 -235.319425) (xy 279.455126 -235.333704)
			(xy 279.462953 -235.352376) (xy 279.4635 -235.362496) (xy 279.4635 -235.771436) (xy 285.504636 -235.771436)
			(xy 285.504636 -235.362496) (xy 285.505019 -235.352337) (xy 285.512823 -235.333578) (xy 285.527232 -235.319253)
			(xy 285.546037 -235.31156) (xy 285.556198 -235.311188) (xy 286.955738 -235.311188) (xy 286.965861 -235.311694)
			(xy 286.984573 -235.319425) (xy 286.998926 -235.333704) (xy 287.006753 -235.352376) (xy 287.0073 -235.362496)
			(xy 287.0073 -235.771436) (xy 293.048436 -235.771436) (xy 293.048436 -235.362496) (xy 293.048819 -235.352337)
			(xy 293.056623 -235.333578) (xy 293.071032 -235.319253) (xy 293.089837 -235.31156) (xy 293.099998 -235.311188)
			(xy 294.499538 -235.311188) (xy 294.509661 -235.311694) (xy 294.528373 -235.319425) (xy 294.542726 -235.333704)
			(xy 294.550553 -235.352376) (xy 294.5511 -235.362496) (xy 294.5511 -235.771436) (xy 300.592236 -235.771436)
			(xy 300.592236 -235.362496) (xy 300.592619 -235.352337) (xy 300.600423 -235.333578) (xy 300.614832 -235.319253)
			(xy 300.633637 -235.31156) (xy 300.643798 -235.311188) (xy 302.043338 -235.311188) (xy 302.053461 -235.311694)
			(xy 302.072173 -235.319425) (xy 302.086526 -235.333704) (xy 302.094353 -235.352376) (xy 302.0949 -235.362496)
			(xy 302.0949 -235.771436) (xy 308.136036 -235.771436) (xy 308.136036 -235.362496) (xy 308.136419 -235.352337)
			(xy 308.144223 -235.333578) (xy 308.158632 -235.319253) (xy 308.177437 -235.31156) (xy 308.187598 -235.311188)
			(xy 309.587138 -235.311188) (xy 309.597261 -235.311694) (xy 309.615973 -235.319425) (xy 309.630326 -235.333704)
			(xy 309.638153 -235.352376) (xy 309.6387 -235.362496) (xy 309.6387 -235.771436) (xy 406.002236 -235.771436)
			(xy 406.002236 -235.362496) (xy 406.002619 -235.352337) (xy 406.010423 -235.333578) (xy 406.024832 -235.319253)
			(xy 406.043637 -235.31156) (xy 406.053798 -235.311188) (xy 407.453338 -235.311188) (xy 407.463461 -235.311694)
			(xy 407.482173 -235.319425) (xy 407.496526 -235.333704) (xy 407.504353 -235.352376) (xy 407.5049 -235.362496)
			(xy 407.5049 -235.771436) (xy 413.546036 -235.771436) (xy 413.546036 -235.362496) (xy 413.546419 -235.352337)
			(xy 413.554223 -235.333578) (xy 413.568632 -235.319253) (xy 413.587437 -235.31156) (xy 413.597598 -235.311188)
			(xy 414.997138 -235.311188) (xy 415.007261 -235.311694) (xy 415.025973 -235.319425) (xy 415.040326 -235.333704)
			(xy 415.048153 -235.352376) (xy 415.0487 -235.362496) (xy 415.0487 -235.771436) (xy 421.089836 -235.771436)
			(xy 421.089836 -235.362496) (xy 421.090219 -235.352337) (xy 421.098023 -235.333578) (xy 421.112432 -235.319253)
			(xy 421.131237 -235.31156) (xy 421.141398 -235.311188) (xy 422.540938 -235.311188) (xy 422.551061 -235.311694)
			(xy 422.569773 -235.319425) (xy 422.584126 -235.333704) (xy 422.591953 -235.352376) (xy 422.5925 -235.362496)
			(xy 422.5925 -235.771436) (xy 428.633636 -235.771436) (xy 428.633636 -235.362496) (xy 428.634019 -235.352337)
			(xy 428.641823 -235.333578) (xy 428.656232 -235.319253) (xy 428.675037 -235.31156) (xy 428.685198 -235.311188)
			(xy 430.084738 -235.311188) (xy 430.094861 -235.311694) (xy 430.113573 -235.319425) (xy 430.127926 -235.333704)
			(xy 430.135753 -235.352376) (xy 430.1363 -235.362496) (xy 430.1363 -235.771436) (xy 436.177436 -235.771436)
			(xy 436.177436 -235.362496) (xy 436.177819 -235.352337) (xy 436.185623 -235.333578) (xy 436.200032 -235.319253)
			(xy 436.218837 -235.31156) (xy 436.228998 -235.311188) (xy 437.628538 -235.311188) (xy 437.638661 -235.311694)
			(xy 437.657373 -235.319425) (xy 437.671726 -235.333704) (xy 437.679553 -235.352376) (xy 437.6801 -235.362496)
			(xy 437.6801 -235.771436) (xy 443.721236 -235.771436) (xy 443.721236 -235.362496) (xy 443.721619 -235.352337)
			(xy 443.729423 -235.333578) (xy 443.743832 -235.319253) (xy 443.762637 -235.31156) (xy 443.772798 -235.311188)
			(xy 445.172338 -235.311188) (xy 445.182461 -235.311694) (xy 445.201173 -235.319425) (xy 445.215526 -235.333704)
			(xy 445.223353 -235.352376) (xy 445.2239 -235.362496) (xy 445.2239 -235.771436) (xy 451.265036 -235.771436)
			(xy 451.265036 -235.362496) (xy 451.265419 -235.352337) (xy 451.273223 -235.333578) (xy 451.287632 -235.319253)
			(xy 451.306437 -235.31156) (xy 451.316598 -235.311188) (xy 452.716138 -235.311188) (xy 452.726261 -235.311694)
			(xy 452.744973 -235.319425) (xy 452.759326 -235.333704) (xy 452.767153 -235.352376) (xy 452.7677 -235.362496)
			(xy 452.7677 -235.771436) (xy 458.808836 -235.771436) (xy 458.808836 -235.362496) (xy 458.809219 -235.352337)
			(xy 458.817023 -235.333578) (xy 458.831432 -235.319253) (xy 458.850237 -235.31156) (xy 458.860398 -235.311188)
			(xy 460.259938 -235.311188) (xy 460.270061 -235.311694) (xy 460.288773 -235.319425) (xy 460.303126 -235.333704)
			(xy 460.310953 -235.352376) (xy 460.3115 -235.362496) (xy 460.3115 -235.771436) (xy 460.311108 -235.781592)
			(xy 460.3033 -235.800346) (xy 460.288895 -235.814668) (xy 460.270097 -235.822366) (xy 460.259938 -235.822744)
			(xy 458.860398 -235.822744) (xy 458.850269 -235.822274) (xy 458.831545 -235.814543) (xy 458.817188 -235.800251)
			(xy 458.809372 -235.781562) (xy 458.808836 -235.771436) (xy 452.7677 -235.771436) (xy 452.767308 -235.781592)
			(xy 452.7595 -235.800346) (xy 452.745095 -235.814668) (xy 452.726297 -235.822366) (xy 452.716138 -235.822744)
			(xy 451.316598 -235.822744) (xy 451.306469 -235.822274) (xy 451.287745 -235.814543) (xy 451.273388 -235.800251)
			(xy 451.265572 -235.781562) (xy 451.265036 -235.771436) (xy 445.2239 -235.771436) (xy 445.223508 -235.781592)
			(xy 445.2157 -235.800346) (xy 445.201295 -235.814668) (xy 445.182497 -235.822366) (xy 445.172338 -235.822744)
			(xy 443.772798 -235.822744) (xy 443.762669 -235.822274) (xy 443.743945 -235.814543) (xy 443.729588 -235.800251)
			(xy 443.721772 -235.781562) (xy 443.721236 -235.771436) (xy 437.6801 -235.771436) (xy 437.679708 -235.781592)
			(xy 437.6719 -235.800346) (xy 437.657495 -235.814668) (xy 437.638697 -235.822366) (xy 437.628538 -235.822744)
			(xy 436.228998 -235.822744) (xy 436.218869 -235.822274) (xy 436.200145 -235.814543) (xy 436.185788 -235.800251)
			(xy 436.177972 -235.781562) (xy 436.177436 -235.771436) (xy 430.1363 -235.771436) (xy 430.135908 -235.781592)
			(xy 430.1281 -235.800346) (xy 430.113695 -235.814668) (xy 430.094897 -235.822366) (xy 430.084738 -235.822744)
			(xy 428.685198 -235.822744) (xy 428.675069 -235.822274) (xy 428.656345 -235.814543) (xy 428.641988 -235.800251)
			(xy 428.634172 -235.781562) (xy 428.633636 -235.771436) (xy 422.5925 -235.771436) (xy 422.592108 -235.781592)
			(xy 422.5843 -235.800346) (xy 422.569895 -235.814668) (xy 422.551097 -235.822366) (xy 422.540938 -235.822744)
			(xy 421.141398 -235.822744) (xy 421.131269 -235.822274) (xy 421.112545 -235.814543) (xy 421.098188 -235.800251)
			(xy 421.090372 -235.781562) (xy 421.089836 -235.771436) (xy 415.0487 -235.771436) (xy 415.048308 -235.781592)
			(xy 415.0405 -235.800346) (xy 415.026095 -235.814668) (xy 415.007297 -235.822366) (xy 414.997138 -235.822744)
			(xy 413.597598 -235.822744) (xy 413.587469 -235.822274) (xy 413.568745 -235.814543) (xy 413.554388 -235.800251)
			(xy 413.546572 -235.781562) (xy 413.546036 -235.771436) (xy 407.5049 -235.771436) (xy 407.504508 -235.781592)
			(xy 407.4967 -235.800346) (xy 407.482295 -235.814668) (xy 407.463497 -235.822366) (xy 407.453338 -235.822744)
			(xy 406.053798 -235.822744) (xy 406.043669 -235.822274) (xy 406.024945 -235.814543) (xy 406.010588 -235.800251)
			(xy 406.002772 -235.781562) (xy 406.002236 -235.771436) (xy 309.6387 -235.771436) (xy 309.638308 -235.781592)
			(xy 309.6305 -235.800346) (xy 309.616095 -235.814668) (xy 309.597297 -235.822366) (xy 309.587138 -235.822744)
			(xy 308.187598 -235.822744) (xy 308.177469 -235.822274) (xy 308.158745 -235.814543) (xy 308.144388 -235.800251)
			(xy 308.136572 -235.781562) (xy 308.136036 -235.771436) (xy 302.0949 -235.771436) (xy 302.094508 -235.781592)
			(xy 302.0867 -235.800346) (xy 302.072295 -235.814668) (xy 302.053497 -235.822366) (xy 302.043338 -235.822744)
			(xy 300.643798 -235.822744) (xy 300.633669 -235.822274) (xy 300.614945 -235.814543) (xy 300.600588 -235.800251)
			(xy 300.592772 -235.781562) (xy 300.592236 -235.771436) (xy 294.5511 -235.771436) (xy 294.550708 -235.781592)
			(xy 294.5429 -235.800346) (xy 294.528495 -235.814668) (xy 294.509697 -235.822366) (xy 294.499538 -235.822744)
			(xy 293.099998 -235.822744) (xy 293.089869 -235.822274) (xy 293.071145 -235.814543) (xy 293.056788 -235.800251)
			(xy 293.048972 -235.781562) (xy 293.048436 -235.771436) (xy 287.0073 -235.771436) (xy 287.006908 -235.781592)
			(xy 286.9991 -235.800346) (xy 286.984695 -235.814668) (xy 286.965897 -235.822366) (xy 286.955738 -235.822744)
			(xy 285.556198 -235.822744) (xy 285.546069 -235.822274) (xy 285.527345 -235.814543) (xy 285.512988 -235.800251)
			(xy 285.505172 -235.781562) (xy 285.504636 -235.771436) (xy 279.4635 -235.771436) (xy 279.463108 -235.781592)
			(xy 279.4553 -235.800346) (xy 279.440895 -235.814668) (xy 279.422097 -235.822366) (xy 279.411938 -235.822744)
			(xy 278.012398 -235.822744) (xy 278.002269 -235.822274) (xy 277.983545 -235.814543) (xy 277.969188 -235.800251)
			(xy 277.961372 -235.781562) (xy 277.960836 -235.771436) (xy 271.9197 -235.771436) (xy 271.919308 -235.781592)
			(xy 271.9115 -235.800346) (xy 271.897095 -235.814668) (xy 271.878297 -235.822366) (xy 271.868138 -235.822744)
			(xy 270.468598 -235.822744) (xy 270.458469 -235.822274) (xy 270.439745 -235.814543) (xy 270.425388 -235.800251)
			(xy 270.417572 -235.781562) (xy 270.417036 -235.771436) (xy 264.3759 -235.771436) (xy 264.375508 -235.781592)
			(xy 264.3677 -235.800346) (xy 264.353295 -235.814668) (xy 264.334497 -235.822366) (xy 264.324338 -235.822744)
			(xy 262.924798 -235.822744) (xy 262.914669 -235.822274) (xy 262.895945 -235.814543) (xy 262.881588 -235.800251)
			(xy 262.873772 -235.781562) (xy 262.873236 -235.771436) (xy 256.8321 -235.771436) (xy 256.831708 -235.781592)
			(xy 256.8239 -235.800346) (xy 256.809495 -235.814668) (xy 256.790697 -235.822366) (xy 256.780538 -235.822744)
			(xy 255.380998 -235.822744) (xy 255.370869 -235.822274) (xy 255.352145 -235.814543) (xy 255.337788 -235.800251)
			(xy 255.329972 -235.781562) (xy 255.329436 -235.771436) (xy 212.371432 -235.771436) (xy 212.371009 -235.781588)
			(xy 212.363207 -235.800335) (xy 212.348812 -235.814656) (xy 212.330025 -235.822361) (xy 212.31987 -235.822744)
			(xy 210.92033 -235.822744) (xy 210.910203 -235.822249) (xy 210.89148 -235.814528) (xy 210.877122 -235.800244)
			(xy 210.869304 -235.78156) (xy 210.868768 -235.771436) (xy 204.827632 -235.771436) (xy 204.827209 -235.781588)
			(xy 204.819407 -235.800335) (xy 204.805012 -235.814656) (xy 204.786225 -235.822361) (xy 204.77607 -235.822744)
			(xy 203.37653 -235.822744) (xy 203.366403 -235.822249) (xy 203.34768 -235.814528) (xy 203.333322 -235.800244)
			(xy 203.325504 -235.78156) (xy 203.324968 -235.771436) (xy 197.283832 -235.771436) (xy 197.283409 -235.781588)
			(xy 197.275607 -235.800335) (xy 197.261212 -235.814656) (xy 197.242425 -235.822361) (xy 197.23227 -235.822744)
			(xy 195.83273 -235.822744) (xy 195.822603 -235.822249) (xy 195.80388 -235.814528) (xy 195.789522 -235.800244)
			(xy 195.781704 -235.78156) (xy 195.781168 -235.771436) (xy 189.740032 -235.771436) (xy 189.739609 -235.781588)
			(xy 189.731807 -235.800335) (xy 189.717412 -235.814656) (xy 189.698625 -235.822361) (xy 189.68847 -235.822744)
			(xy 188.28893 -235.822744) (xy 188.278803 -235.822249) (xy 188.26008 -235.814528) (xy 188.245722 -235.800244)
			(xy 188.237904 -235.78156) (xy 188.237368 -235.771436) (xy 182.196232 -235.771436) (xy 182.195809 -235.781588)
			(xy 182.188007 -235.800335) (xy 182.173612 -235.814656) (xy 182.154825 -235.822361) (xy 182.14467 -235.822744)
			(xy 180.74513 -235.822744) (xy 180.735003 -235.822249) (xy 180.71628 -235.814528) (xy 180.701922 -235.800244)
			(xy 180.694104 -235.78156) (xy 180.693568 -235.771436) (xy 174.652432 -235.771436) (xy 174.652009 -235.781588)
			(xy 174.644207 -235.800335) (xy 174.629812 -235.814656) (xy 174.611025 -235.822361) (xy 174.60087 -235.822744)
			(xy 173.20133 -235.822744) (xy 173.191203 -235.822249) (xy 173.17248 -235.814528) (xy 173.158122 -235.800244)
			(xy 173.150304 -235.78156) (xy 173.149768 -235.771436) (xy 167.108632 -235.771436) (xy 167.108209 -235.781588)
			(xy 167.100407 -235.800335) (xy 167.086012 -235.814656) (xy 167.067225 -235.822361) (xy 167.05707 -235.822744)
			(xy 165.65753 -235.822744) (xy 165.647403 -235.822249) (xy 165.62868 -235.814528) (xy 165.614322 -235.800244)
			(xy 165.606504 -235.78156) (xy 165.605968 -235.771436) (xy 159.564832 -235.771436) (xy 159.564409 -235.781588)
			(xy 159.556607 -235.800335) (xy 159.542212 -235.814656) (xy 159.523425 -235.822361) (xy 159.51327 -235.822744)
			(xy 158.11373 -235.822744) (xy 158.103603 -235.822249) (xy 158.08488 -235.814528) (xy 158.070522 -235.800244)
			(xy 158.062704 -235.78156) (xy 158.062168 -235.771436) (xy 61.698632 -235.771436) (xy 61.698209 -235.781588)
			(xy 61.690407 -235.800335) (xy 61.676012 -235.814656) (xy 61.657225 -235.822361) (xy 61.64707 -235.822744)
			(xy 60.24753 -235.822744) (xy 60.237403 -235.822249) (xy 60.21868 -235.814528) (xy 60.204322 -235.800244)
			(xy 60.196504 -235.78156) (xy 60.195968 -235.771436) (xy 54.154832 -235.771436) (xy 54.154409 -235.781588)
			(xy 54.146607 -235.800335) (xy 54.132212 -235.814656) (xy 54.113425 -235.822361) (xy 54.10327 -235.822744)
			(xy 52.70373 -235.822744) (xy 52.693603 -235.822249) (xy 52.67488 -235.814528) (xy 52.660522 -235.800244)
			(xy 52.652704 -235.78156) (xy 52.652168 -235.771436) (xy 46.611032 -235.771436) (xy 46.610609 -235.781588)
			(xy 46.602807 -235.800335) (xy 46.588412 -235.814656) (xy 46.569625 -235.822361) (xy 46.55947 -235.822744)
			(xy 45.15993 -235.822744) (xy 45.149803 -235.822249) (xy 45.13108 -235.814528) (xy 45.116722 -235.800244)
			(xy 45.108904 -235.78156) (xy 45.108368 -235.771436) (xy 39.067232 -235.771436) (xy 39.066809 -235.781588)
			(xy 39.059007 -235.800335) (xy 39.044612 -235.814656) (xy 39.025825 -235.822361) (xy 39.01567 -235.822744)
			(xy 37.61613 -235.822744) (xy 37.606003 -235.822249) (xy 37.58728 -235.814528) (xy 37.572922 -235.800244)
			(xy 37.565104 -235.78156) (xy 37.564568 -235.771436) (xy 31.523432 -235.771436) (xy 31.523009 -235.781588)
			(xy 31.515207 -235.800335) (xy 31.500812 -235.814656) (xy 31.482025 -235.822361) (xy 31.47187 -235.822744)
			(xy 30.07233 -235.822744) (xy 30.062203 -235.822249) (xy 30.04348 -235.814528) (xy 30.029122 -235.800244)
			(xy 30.021304 -235.78156) (xy 30.020768 -235.771436) (xy 23.979632 -235.771436) (xy 23.979209 -235.781588)
			(xy 23.971407 -235.800335) (xy 23.957012 -235.814656) (xy 23.938225 -235.822361) (xy 23.92807 -235.822744)
			(xy 22.52853 -235.822744) (xy 22.518403 -235.822249) (xy 22.49968 -235.814528) (xy 22.485322 -235.800244)
			(xy 22.477504 -235.78156) (xy 22.476968 -235.771436) (xy 16.435832 -235.771436) (xy 16.435409 -235.781588)
			(xy 16.427607 -235.800335) (xy 16.413212 -235.814656) (xy 16.394425 -235.822361) (xy 16.38427 -235.822744)
			(xy 14.98473 -235.822744) (xy 14.974603 -235.822249) (xy 14.95588 -235.814528) (xy 14.941522 -235.800244)
			(xy 14.933704 -235.78156) (xy 14.933168 -235.771436) (xy 8.892032 -235.771436) (xy 8.891609 -235.781588)
			(xy 8.883807 -235.800335) (xy 8.869412 -235.814656) (xy 8.850625 -235.822361) (xy 8.84047 -235.822744)
			(xy 7.44093 -235.822744) (xy 7.430803 -235.822249) (xy 7.41208 -235.814528) (xy 7.397722 -235.800244)
			(xy 7.389904 -235.78156) (xy 7.389368 -235.771436) (xy 2.509012 -235.771436) (xy 2.509012 -236.62132)
			(xy 11.489436 -236.62132) (xy 11.489436 -236.21238) (xy 11.489806 -236.20222) (xy 11.497615 -236.18346)
			(xy 11.512028 -236.169136) (xy 11.530836 -236.161444) (xy 11.540998 -236.161072) (xy 12.940538 -236.161072)
			(xy 12.950671 -236.161496) (xy 12.969399 -236.169243) (xy 12.983755 -236.183548) (xy 12.991567 -236.202249)
			(xy 12.9921 -236.21238) (xy 12.9921 -236.62132) (xy 19.033236 -236.62132) (xy 19.033236 -236.21238)
			(xy 19.033606 -236.20222) (xy 19.041415 -236.18346) (xy 19.055828 -236.169136) (xy 19.074636 -236.161444)
			(xy 19.084798 -236.161072) (xy 20.484338 -236.161072) (xy 20.494471 -236.161496) (xy 20.513199 -236.169243)
			(xy 20.527555 -236.183548) (xy 20.535367 -236.202249) (xy 20.5359 -236.21238) (xy 20.5359 -236.62132)
			(xy 26.577036 -236.62132) (xy 26.577036 -236.21238) (xy 26.577406 -236.20222) (xy 26.585215 -236.18346)
			(xy 26.599628 -236.169136) (xy 26.618436 -236.161444) (xy 26.628598 -236.161072) (xy 28.028138 -236.161072)
			(xy 28.038271 -236.161496) (xy 28.056999 -236.169243) (xy 28.071355 -236.183548) (xy 28.079167 -236.202249)
			(xy 28.0797 -236.21238) (xy 28.0797 -236.62132) (xy 34.120836 -236.62132) (xy 34.120836 -236.21238)
			(xy 34.121206 -236.20222) (xy 34.129015 -236.18346) (xy 34.143428 -236.169136) (xy 34.162236 -236.161444)
			(xy 34.172398 -236.161072) (xy 35.571938 -236.161072) (xy 35.582071 -236.161496) (xy 35.600799 -236.169243)
			(xy 35.615155 -236.183548) (xy 35.622967 -236.202249) (xy 35.6235 -236.21238) (xy 35.6235 -236.62132)
			(xy 41.664636 -236.62132) (xy 41.664636 -236.21238) (xy 41.665006 -236.20222) (xy 41.672815 -236.18346)
			(xy 41.687228 -236.169136) (xy 41.706036 -236.161444) (xy 41.716198 -236.161072) (xy 43.115738 -236.161072)
			(xy 43.125871 -236.161496) (xy 43.144599 -236.169243) (xy 43.158955 -236.183548) (xy 43.166767 -236.202249)
			(xy 43.1673 -236.21238) (xy 43.1673 -236.62132) (xy 49.208436 -236.62132) (xy 49.208436 -236.21238)
			(xy 49.208806 -236.20222) (xy 49.216615 -236.18346) (xy 49.231028 -236.169136) (xy 49.249836 -236.161444)
			(xy 49.259998 -236.161072) (xy 50.659538 -236.161072) (xy 50.669671 -236.161496) (xy 50.688399 -236.169243)
			(xy 50.702755 -236.183548) (xy 50.710567 -236.202249) (xy 50.7111 -236.21238) (xy 50.7111 -236.62132)
			(xy 56.752236 -236.62132) (xy 56.752236 -236.21238) (xy 56.752606 -236.20222) (xy 56.760415 -236.18346)
			(xy 56.774828 -236.169136) (xy 56.793636 -236.161444) (xy 56.803798 -236.161072) (xy 58.203338 -236.161072)
			(xy 58.213471 -236.161496) (xy 58.232199 -236.169243) (xy 58.246555 -236.183548) (xy 58.254367 -236.202249)
			(xy 58.2549 -236.21238) (xy 58.2549 -236.62132) (xy 64.296036 -236.62132) (xy 64.296036 -236.21238)
			(xy 64.296406 -236.20222) (xy 64.304215 -236.18346) (xy 64.318628 -236.169136) (xy 64.337436 -236.161444)
			(xy 64.347598 -236.161072) (xy 65.747138 -236.161072) (xy 65.757271 -236.161496) (xy 65.775999 -236.169243)
			(xy 65.790355 -236.183548) (xy 65.798167 -236.202249) (xy 65.7987 -236.21238) (xy 65.7987 -236.62132)
			(xy 162.162236 -236.62132) (xy 162.162236 -236.21238) (xy 162.162606 -236.20222) (xy 162.170415 -236.18346)
			(xy 162.184828 -236.169136) (xy 162.203636 -236.161444) (xy 162.213798 -236.161072) (xy 163.613338 -236.161072)
			(xy 163.623471 -236.161496) (xy 163.642199 -236.169243) (xy 163.656555 -236.183548) (xy 163.664367 -236.202249)
			(xy 163.6649 -236.21238) (xy 163.6649 -236.62132) (xy 169.706036 -236.62132) (xy 169.706036 -236.21238)
			(xy 169.706406 -236.20222) (xy 169.714215 -236.18346) (xy 169.728628 -236.169136) (xy 169.747436 -236.161444)
			(xy 169.757598 -236.161072) (xy 171.157138 -236.161072) (xy 171.167271 -236.161496) (xy 171.185999 -236.169243)
			(xy 171.200355 -236.183548) (xy 171.208167 -236.202249) (xy 171.2087 -236.21238) (xy 171.2087 -236.62132)
			(xy 177.249836 -236.62132) (xy 177.249836 -236.21238) (xy 177.250206 -236.20222) (xy 177.258015 -236.18346)
			(xy 177.272428 -236.169136) (xy 177.291236 -236.161444) (xy 177.301398 -236.161072) (xy 178.700938 -236.161072)
			(xy 178.711071 -236.161496) (xy 178.729799 -236.169243) (xy 178.744155 -236.183548) (xy 178.751967 -236.202249)
			(xy 178.7525 -236.21238) (xy 178.7525 -236.62132) (xy 184.793636 -236.62132) (xy 184.793636 -236.21238)
			(xy 184.794006 -236.20222) (xy 184.801815 -236.18346) (xy 184.816228 -236.169136) (xy 184.835036 -236.161444)
			(xy 184.845198 -236.161072) (xy 186.244738 -236.161072) (xy 186.254871 -236.161496) (xy 186.273599 -236.169243)
			(xy 186.287955 -236.183548) (xy 186.295767 -236.202249) (xy 186.2963 -236.21238) (xy 186.2963 -236.62132)
			(xy 192.337436 -236.62132) (xy 192.337436 -236.21238) (xy 192.337806 -236.20222) (xy 192.345615 -236.18346)
			(xy 192.360028 -236.169136) (xy 192.378836 -236.161444) (xy 192.388998 -236.161072) (xy 193.788538 -236.161072)
			(xy 193.798671 -236.161496) (xy 193.817399 -236.169243) (xy 193.831755 -236.183548) (xy 193.839567 -236.202249)
			(xy 193.8401 -236.21238) (xy 193.8401 -236.62132) (xy 199.881236 -236.62132) (xy 199.881236 -236.21238)
			(xy 199.881606 -236.20222) (xy 199.889415 -236.18346) (xy 199.903828 -236.169136) (xy 199.922636 -236.161444)
			(xy 199.932798 -236.161072) (xy 201.332338 -236.161072) (xy 201.342471 -236.161496) (xy 201.361199 -236.169243)
			(xy 201.375555 -236.183548) (xy 201.383367 -236.202249) (xy 201.3839 -236.21238) (xy 201.3839 -236.62132)
			(xy 207.425036 -236.62132) (xy 207.425036 -236.21238) (xy 207.425406 -236.20222) (xy 207.433215 -236.18346)
			(xy 207.447628 -236.169136) (xy 207.466436 -236.161444) (xy 207.476598 -236.161072) (xy 208.876138 -236.161072)
			(xy 208.886271 -236.161496) (xy 208.904999 -236.169243) (xy 208.919355 -236.183548) (xy 208.927167 -236.202249)
			(xy 208.9277 -236.21238) (xy 208.9277 -236.62132) (xy 214.968836 -236.62132) (xy 214.968836 -236.21238)
			(xy 214.969206 -236.20222) (xy 214.977015 -236.18346) (xy 214.991428 -236.169136) (xy 215.010236 -236.161444)
			(xy 215.020398 -236.161072) (xy 216.419938 -236.161072) (xy 216.430071 -236.161496) (xy 216.448799 -236.169243)
			(xy 216.463155 -236.183548) (xy 216.470967 -236.202249) (xy 216.4715 -236.21238) (xy 216.4715 -236.62132)
			(xy 259.429504 -236.62132) (xy 259.429504 -236.21238) (xy 259.429905 -236.202224) (xy 259.437708 -236.18347)
			(xy 259.452111 -236.169148) (xy 259.470908 -236.161449) (xy 259.481066 -236.161072) (xy 260.880606 -236.161072)
			(xy 260.890737 -236.161523) (xy 260.909464 -236.169258) (xy 260.923821 -236.183556) (xy 260.931635 -236.202251)
			(xy 260.932168 -236.21238) (xy 260.932168 -236.62132) (xy 266.973304 -236.62132) (xy 266.973304 -236.21238)
			(xy 266.973705 -236.202224) (xy 266.981508 -236.18347) (xy 266.995911 -236.169148) (xy 267.014708 -236.161449)
			(xy 267.024866 -236.161072) (xy 268.424406 -236.161072) (xy 268.434537 -236.161523) (xy 268.453264 -236.169258)
			(xy 268.467621 -236.183556) (xy 268.475435 -236.202251) (xy 268.475968 -236.21238) (xy 268.475968 -236.62132)
			(xy 274.517104 -236.62132) (xy 274.517104 -236.21238) (xy 274.517505 -236.202224) (xy 274.525308 -236.18347)
			(xy 274.539711 -236.169148) (xy 274.558508 -236.161449) (xy 274.568666 -236.161072) (xy 275.968206 -236.161072)
			(xy 275.978337 -236.161523) (xy 275.997064 -236.169258) (xy 276.011421 -236.183556) (xy 276.019235 -236.202251)
			(xy 276.019768 -236.21238) (xy 276.019768 -236.62132) (xy 282.060904 -236.62132) (xy 282.060904 -236.21238)
			(xy 282.061305 -236.202224) (xy 282.069108 -236.18347) (xy 282.083511 -236.169148) (xy 282.102308 -236.161449)
			(xy 282.112466 -236.161072) (xy 283.512006 -236.161072) (xy 283.522137 -236.161523) (xy 283.540864 -236.169258)
			(xy 283.555221 -236.183556) (xy 283.563035 -236.202251) (xy 283.563568 -236.21238) (xy 283.563568 -236.62132)
			(xy 289.604704 -236.62132) (xy 289.604704 -236.21238) (xy 289.605105 -236.202224) (xy 289.612908 -236.18347)
			(xy 289.627311 -236.169148) (xy 289.646108 -236.161449) (xy 289.656266 -236.161072) (xy 291.055806 -236.161072)
			(xy 291.065937 -236.161523) (xy 291.084664 -236.169258) (xy 291.099021 -236.183556) (xy 291.106835 -236.202251)
			(xy 291.107368 -236.21238) (xy 291.107368 -236.62132) (xy 297.148504 -236.62132) (xy 297.148504 -236.21238)
			(xy 297.148905 -236.202224) (xy 297.156708 -236.18347) (xy 297.171111 -236.169148) (xy 297.189908 -236.161449)
			(xy 297.200066 -236.161072) (xy 298.599606 -236.161072) (xy 298.609737 -236.161523) (xy 298.628464 -236.169258)
			(xy 298.642821 -236.183556) (xy 298.650635 -236.202251) (xy 298.651168 -236.21238) (xy 298.651168 -236.62132)
			(xy 304.692304 -236.62132) (xy 304.692304 -236.21238) (xy 304.692705 -236.202224) (xy 304.700508 -236.18347)
			(xy 304.714911 -236.169148) (xy 304.733708 -236.161449) (xy 304.743866 -236.161072) (xy 306.143406 -236.161072)
			(xy 306.153537 -236.161523) (xy 306.172264 -236.169258) (xy 306.186621 -236.183556) (xy 306.194435 -236.202251)
			(xy 306.194968 -236.21238) (xy 306.194968 -236.62132) (xy 312.236104 -236.62132) (xy 312.236104 -236.21238)
			(xy 312.236505 -236.202224) (xy 312.244308 -236.18347) (xy 312.258711 -236.169148) (xy 312.277508 -236.161449)
			(xy 312.287666 -236.161072) (xy 313.687206 -236.161072) (xy 313.697337 -236.161523) (xy 313.716064 -236.169258)
			(xy 313.730421 -236.183556) (xy 313.738235 -236.202251) (xy 313.738768 -236.21238) (xy 313.738768 -236.62132)
			(xy 410.102304 -236.62132) (xy 410.102304 -236.21238) (xy 410.102705 -236.202224) (xy 410.110508 -236.18347)
			(xy 410.124911 -236.169148) (xy 410.143708 -236.161449) (xy 410.153866 -236.161072) (xy 411.553406 -236.161072)
			(xy 411.563537 -236.161523) (xy 411.582264 -236.169258) (xy 411.596621 -236.183556) (xy 411.604435 -236.202251)
			(xy 411.604968 -236.21238) (xy 411.604968 -236.62132) (xy 417.646104 -236.62132) (xy 417.646104 -236.21238)
			(xy 417.646505 -236.202224) (xy 417.654308 -236.18347) (xy 417.668711 -236.169148) (xy 417.687508 -236.161449)
			(xy 417.697666 -236.161072) (xy 419.097206 -236.161072) (xy 419.107337 -236.161523) (xy 419.126064 -236.169258)
			(xy 419.140421 -236.183556) (xy 419.148235 -236.202251) (xy 419.148768 -236.21238) (xy 419.148768 -236.62132)
			(xy 425.189904 -236.62132) (xy 425.189904 -236.21238) (xy 425.190305 -236.202224) (xy 425.198108 -236.18347)
			(xy 425.212511 -236.169148) (xy 425.231308 -236.161449) (xy 425.241466 -236.161072) (xy 426.641006 -236.161072)
			(xy 426.651137 -236.161523) (xy 426.669864 -236.169258) (xy 426.684221 -236.183556) (xy 426.692035 -236.202251)
			(xy 426.692568 -236.21238) (xy 426.692568 -236.62132) (xy 432.733704 -236.62132) (xy 432.733704 -236.21238)
			(xy 432.734105 -236.202224) (xy 432.741908 -236.18347) (xy 432.756311 -236.169148) (xy 432.775108 -236.161449)
			(xy 432.785266 -236.161072) (xy 434.184806 -236.161072) (xy 434.194937 -236.161523) (xy 434.213664 -236.169258)
			(xy 434.228021 -236.183556) (xy 434.235835 -236.202251) (xy 434.236368 -236.21238) (xy 434.236368 -236.62132)
			(xy 440.277504 -236.62132) (xy 440.277504 -236.21238) (xy 440.277905 -236.202224) (xy 440.285708 -236.18347)
			(xy 440.300111 -236.169148) (xy 440.318908 -236.161449) (xy 440.329066 -236.161072) (xy 441.728606 -236.161072)
			(xy 441.738737 -236.161523) (xy 441.757464 -236.169258) (xy 441.771821 -236.183556) (xy 441.779635 -236.202251)
			(xy 441.780168 -236.21238) (xy 441.780168 -236.62132) (xy 447.821304 -236.62132) (xy 447.821304 -236.21238)
			(xy 447.821705 -236.202224) (xy 447.829508 -236.18347) (xy 447.843911 -236.169148) (xy 447.862708 -236.161449)
			(xy 447.872866 -236.161072) (xy 449.272406 -236.161072) (xy 449.282537 -236.161523) (xy 449.301264 -236.169258)
			(xy 449.315621 -236.183556) (xy 449.323435 -236.202251) (xy 449.323968 -236.21238) (xy 449.323968 -236.62132)
			(xy 455.365104 -236.62132) (xy 455.365104 -236.21238) (xy 455.365505 -236.202224) (xy 455.373308 -236.18347)
			(xy 455.387711 -236.169148) (xy 455.406508 -236.161449) (xy 455.416666 -236.161072) (xy 456.816206 -236.161072)
			(xy 456.826337 -236.161523) (xy 456.845064 -236.169258) (xy 456.859421 -236.183556) (xy 456.867235 -236.202251)
			(xy 456.867768 -236.21238) (xy 456.867768 -236.62132) (xy 462.908904 -236.62132) (xy 462.908904 -236.21238)
			(xy 462.909305 -236.202224) (xy 462.917108 -236.18347) (xy 462.931511 -236.169148) (xy 462.950308 -236.161449)
			(xy 462.960466 -236.161072) (xy 464.360006 -236.161072) (xy 464.370137 -236.161523) (xy 464.388864 -236.169258)
			(xy 464.403221 -236.183556) (xy 464.411035 -236.202251) (xy 464.411568 -236.21238) (xy 464.411568 -236.62132)
			(xy 464.411194 -236.631479) (xy 464.403386 -236.650239) (xy 464.388974 -236.664562) (xy 464.370168 -236.672256)
			(xy 464.360006 -236.672628) (xy 462.960466 -236.672628) (xy 462.950333 -236.6722) (xy 462.931605 -236.664456)
			(xy 462.917249 -236.650151) (xy 462.909437 -236.631451) (xy 462.908904 -236.62132) (xy 456.867768 -236.62132)
			(xy 456.867394 -236.631479) (xy 456.859586 -236.650239) (xy 456.845174 -236.664562) (xy 456.826368 -236.672256)
			(xy 456.816206 -236.672628) (xy 455.416666 -236.672628) (xy 455.406533 -236.6722) (xy 455.387805 -236.664456)
			(xy 455.373449 -236.650151) (xy 455.365637 -236.631451) (xy 455.365104 -236.62132) (xy 449.323968 -236.62132)
			(xy 449.323594 -236.631479) (xy 449.315786 -236.650239) (xy 449.301374 -236.664562) (xy 449.282568 -236.672256)
			(xy 449.272406 -236.672628) (xy 447.872866 -236.672628) (xy 447.862733 -236.6722) (xy 447.844005 -236.664456)
			(xy 447.829649 -236.650151) (xy 447.821837 -236.631451) (xy 447.821304 -236.62132) (xy 441.780168 -236.62132)
			(xy 441.779794 -236.631479) (xy 441.771986 -236.650239) (xy 441.757574 -236.664562) (xy 441.738768 -236.672256)
			(xy 441.728606 -236.672628) (xy 440.329066 -236.672628) (xy 440.318933 -236.6722) (xy 440.300205 -236.664456)
			(xy 440.285849 -236.650151) (xy 440.278037 -236.631451) (xy 440.277504 -236.62132) (xy 434.236368 -236.62132)
			(xy 434.235994 -236.631479) (xy 434.228186 -236.650239) (xy 434.213774 -236.664562) (xy 434.194968 -236.672256)
			(xy 434.184806 -236.672628) (xy 432.785266 -236.672628) (xy 432.775133 -236.6722) (xy 432.756405 -236.664456)
			(xy 432.742049 -236.650151) (xy 432.734237 -236.631451) (xy 432.733704 -236.62132) (xy 426.692568 -236.62132)
			(xy 426.692194 -236.631479) (xy 426.684386 -236.650239) (xy 426.669974 -236.664562) (xy 426.651168 -236.672256)
			(xy 426.641006 -236.672628) (xy 425.241466 -236.672628) (xy 425.231333 -236.6722) (xy 425.212605 -236.664456)
			(xy 425.198249 -236.650151) (xy 425.190437 -236.631451) (xy 425.189904 -236.62132) (xy 419.148768 -236.62132)
			(xy 419.148394 -236.631479) (xy 419.140586 -236.650239) (xy 419.126174 -236.664562) (xy 419.107368 -236.672256)
			(xy 419.097206 -236.672628) (xy 417.697666 -236.672628) (xy 417.687533 -236.6722) (xy 417.668805 -236.664456)
			(xy 417.654449 -236.650151) (xy 417.646637 -236.631451) (xy 417.646104 -236.62132) (xy 411.604968 -236.62132)
			(xy 411.604594 -236.631479) (xy 411.596786 -236.650239) (xy 411.582374 -236.664562) (xy 411.563568 -236.672256)
			(xy 411.553406 -236.672628) (xy 410.153866 -236.672628) (xy 410.143733 -236.6722) (xy 410.125005 -236.664456)
			(xy 410.110649 -236.650151) (xy 410.102837 -236.631451) (xy 410.102304 -236.62132) (xy 313.738768 -236.62132)
			(xy 313.738394 -236.631479) (xy 313.730586 -236.650239) (xy 313.716174 -236.664562) (xy 313.697368 -236.672256)
			(xy 313.687206 -236.672628) (xy 312.287666 -236.672628) (xy 312.277533 -236.6722) (xy 312.258805 -236.664456)
			(xy 312.244449 -236.650151) (xy 312.236637 -236.631451) (xy 312.236104 -236.62132) (xy 306.194968 -236.62132)
			(xy 306.194594 -236.631479) (xy 306.186786 -236.650239) (xy 306.172374 -236.664562) (xy 306.153568 -236.672256)
			(xy 306.143406 -236.672628) (xy 304.743866 -236.672628) (xy 304.733733 -236.6722) (xy 304.715005 -236.664456)
			(xy 304.700649 -236.650151) (xy 304.692837 -236.631451) (xy 304.692304 -236.62132) (xy 298.651168 -236.62132)
			(xy 298.650794 -236.631479) (xy 298.642986 -236.650239) (xy 298.628574 -236.664562) (xy 298.609768 -236.672256)
			(xy 298.599606 -236.672628) (xy 297.200066 -236.672628) (xy 297.189933 -236.6722) (xy 297.171205 -236.664456)
			(xy 297.156849 -236.650151) (xy 297.149037 -236.631451) (xy 297.148504 -236.62132) (xy 291.107368 -236.62132)
			(xy 291.106994 -236.631479) (xy 291.099186 -236.650239) (xy 291.084774 -236.664562) (xy 291.065968 -236.672256)
			(xy 291.055806 -236.672628) (xy 289.656266 -236.672628) (xy 289.646133 -236.6722) (xy 289.627405 -236.664456)
			(xy 289.613049 -236.650151) (xy 289.605237 -236.631451) (xy 289.604704 -236.62132) (xy 283.563568 -236.62132)
			(xy 283.563194 -236.631479) (xy 283.555386 -236.650239) (xy 283.540974 -236.664562) (xy 283.522168 -236.672256)
			(xy 283.512006 -236.672628) (xy 282.112466 -236.672628) (xy 282.102333 -236.6722) (xy 282.083605 -236.664456)
			(xy 282.069249 -236.650151) (xy 282.061437 -236.631451) (xy 282.060904 -236.62132) (xy 276.019768 -236.62132)
			(xy 276.019394 -236.631479) (xy 276.011586 -236.650239) (xy 275.997174 -236.664562) (xy 275.978368 -236.672256)
			(xy 275.968206 -236.672628) (xy 274.568666 -236.672628) (xy 274.558533 -236.6722) (xy 274.539805 -236.664456)
			(xy 274.525449 -236.650151) (xy 274.517637 -236.631451) (xy 274.517104 -236.62132) (xy 268.475968 -236.62132)
			(xy 268.475594 -236.631479) (xy 268.467786 -236.650239) (xy 268.453374 -236.664562) (xy 268.434568 -236.672256)
			(xy 268.424406 -236.672628) (xy 267.024866 -236.672628) (xy 267.014733 -236.6722) (xy 266.996005 -236.664456)
			(xy 266.981649 -236.650151) (xy 266.973837 -236.631451) (xy 266.973304 -236.62132) (xy 260.932168 -236.62132)
			(xy 260.931794 -236.631479) (xy 260.923986 -236.650239) (xy 260.909574 -236.664562) (xy 260.890768 -236.672256)
			(xy 260.880606 -236.672628) (xy 259.481066 -236.672628) (xy 259.470933 -236.6722) (xy 259.452205 -236.664456)
			(xy 259.437849 -236.650151) (xy 259.430037 -236.631451) (xy 259.429504 -236.62132) (xy 216.4715 -236.62132)
			(xy 216.471095 -236.631475) (xy 216.463293 -236.650228) (xy 216.448891 -236.664551) (xy 216.430096 -236.67225)
			(xy 216.419938 -236.672628) (xy 215.020398 -236.672628) (xy 215.010267 -236.672174) (xy 214.99154 -236.66444)
			(xy 214.977183 -236.650143) (xy 214.969369 -236.631449) (xy 214.968836 -236.62132) (xy 208.9277 -236.62132)
			(xy 208.927295 -236.631475) (xy 208.919493 -236.650228) (xy 208.905091 -236.664551) (xy 208.886296 -236.67225)
			(xy 208.876138 -236.672628) (xy 207.476598 -236.672628) (xy 207.466467 -236.672174) (xy 207.44774 -236.66444)
			(xy 207.433383 -236.650143) (xy 207.425569 -236.631449) (xy 207.425036 -236.62132) (xy 201.3839 -236.62132)
			(xy 201.383495 -236.631475) (xy 201.375693 -236.650228) (xy 201.361291 -236.664551) (xy 201.342496 -236.67225)
			(xy 201.332338 -236.672628) (xy 199.932798 -236.672628) (xy 199.922667 -236.672174) (xy 199.90394 -236.66444)
			(xy 199.889583 -236.650143) (xy 199.881769 -236.631449) (xy 199.881236 -236.62132) (xy 193.8401 -236.62132)
			(xy 193.839695 -236.631475) (xy 193.831893 -236.650228) (xy 193.817491 -236.664551) (xy 193.798696 -236.67225)
			(xy 193.788538 -236.672628) (xy 192.388998 -236.672628) (xy 192.378867 -236.672174) (xy 192.36014 -236.66444)
			(xy 192.345783 -236.650143) (xy 192.337969 -236.631449) (xy 192.337436 -236.62132) (xy 186.2963 -236.62132)
			(xy 186.295895 -236.631475) (xy 186.288093 -236.650228) (xy 186.273691 -236.664551) (xy 186.254896 -236.67225)
			(xy 186.244738 -236.672628) (xy 184.845198 -236.672628) (xy 184.835067 -236.672174) (xy 184.81634 -236.66444)
			(xy 184.801983 -236.650143) (xy 184.794169 -236.631449) (xy 184.793636 -236.62132) (xy 178.7525 -236.62132)
			(xy 178.752095 -236.631475) (xy 178.744293 -236.650228) (xy 178.729891 -236.664551) (xy 178.711096 -236.67225)
			(xy 178.700938 -236.672628) (xy 177.301398 -236.672628) (xy 177.291267 -236.672174) (xy 177.27254 -236.66444)
			(xy 177.258183 -236.650143) (xy 177.250369 -236.631449) (xy 177.249836 -236.62132) (xy 171.2087 -236.62132)
			(xy 171.208295 -236.631475) (xy 171.200493 -236.650228) (xy 171.186091 -236.664551) (xy 171.167296 -236.67225)
			(xy 171.157138 -236.672628) (xy 169.757598 -236.672628) (xy 169.747467 -236.672174) (xy 169.72874 -236.66444)
			(xy 169.714383 -236.650143) (xy 169.706569 -236.631449) (xy 169.706036 -236.62132) (xy 163.6649 -236.62132)
			(xy 163.664495 -236.631475) (xy 163.656693 -236.650228) (xy 163.642291 -236.664551) (xy 163.623496 -236.67225)
			(xy 163.613338 -236.672628) (xy 162.213798 -236.672628) (xy 162.203667 -236.672174) (xy 162.18494 -236.66444)
			(xy 162.170583 -236.650143) (xy 162.162769 -236.631449) (xy 162.162236 -236.62132) (xy 65.7987 -236.62132)
			(xy 65.798295 -236.631475) (xy 65.790493 -236.650228) (xy 65.776091 -236.664551) (xy 65.757296 -236.67225)
			(xy 65.747138 -236.672628) (xy 64.347598 -236.672628) (xy 64.337467 -236.672174) (xy 64.31874 -236.66444)
			(xy 64.304383 -236.650143) (xy 64.296569 -236.631449) (xy 64.296036 -236.62132) (xy 58.2549 -236.62132)
			(xy 58.254495 -236.631475) (xy 58.246693 -236.650228) (xy 58.232291 -236.664551) (xy 58.213496 -236.67225)
			(xy 58.203338 -236.672628) (xy 56.803798 -236.672628) (xy 56.793667 -236.672174) (xy 56.77494 -236.66444)
			(xy 56.760583 -236.650143) (xy 56.752769 -236.631449) (xy 56.752236 -236.62132) (xy 50.7111 -236.62132)
			(xy 50.710695 -236.631475) (xy 50.702893 -236.650228) (xy 50.688491 -236.664551) (xy 50.669696 -236.67225)
			(xy 50.659538 -236.672628) (xy 49.259998 -236.672628) (xy 49.249867 -236.672174) (xy 49.23114 -236.66444)
			(xy 49.216783 -236.650143) (xy 49.208969 -236.631449) (xy 49.208436 -236.62132) (xy 43.1673 -236.62132)
			(xy 43.166895 -236.631475) (xy 43.159093 -236.650228) (xy 43.144691 -236.664551) (xy 43.125896 -236.67225)
			(xy 43.115738 -236.672628) (xy 41.716198 -236.672628) (xy 41.706067 -236.672174) (xy 41.68734 -236.66444)
			(xy 41.672983 -236.650143) (xy 41.665169 -236.631449) (xy 41.664636 -236.62132) (xy 35.6235 -236.62132)
			(xy 35.623095 -236.631475) (xy 35.615293 -236.650228) (xy 35.600891 -236.664551) (xy 35.582096 -236.67225)
			(xy 35.571938 -236.672628) (xy 34.172398 -236.672628) (xy 34.162267 -236.672174) (xy 34.14354 -236.66444)
			(xy 34.129183 -236.650143) (xy 34.121369 -236.631449) (xy 34.120836 -236.62132) (xy 28.0797 -236.62132)
			(xy 28.079295 -236.631475) (xy 28.071493 -236.650228) (xy 28.057091 -236.664551) (xy 28.038296 -236.67225)
			(xy 28.028138 -236.672628) (xy 26.628598 -236.672628) (xy 26.618467 -236.672174) (xy 26.59974 -236.66444)
			(xy 26.585383 -236.650143) (xy 26.577569 -236.631449) (xy 26.577036 -236.62132) (xy 20.5359 -236.62132)
			(xy 20.535495 -236.631475) (xy 20.527693 -236.650228) (xy 20.513291 -236.664551) (xy 20.494496 -236.67225)
			(xy 20.484338 -236.672628) (xy 19.084798 -236.672628) (xy 19.074667 -236.672174) (xy 19.05594 -236.66444)
			(xy 19.041583 -236.650143) (xy 19.033769 -236.631449) (xy 19.033236 -236.62132) (xy 12.9921 -236.62132)
			(xy 12.991695 -236.631475) (xy 12.983893 -236.650228) (xy 12.969491 -236.664551) (xy 12.950696 -236.67225)
			(xy 12.940538 -236.672628) (xy 11.540998 -236.672628) (xy 11.530867 -236.672174) (xy 11.51214 -236.66444)
			(xy 11.497783 -236.650143) (xy 11.489969 -236.631449) (xy 11.489436 -236.62132) (xy 2.509012 -236.62132)
			(xy 2.509012 -237.471458) (xy 7.389368 -237.471458) (xy 7.389368 -237.062518) (xy 7.389779 -237.052344)
			(xy 7.397564 -237.033544) (xy 7.411954 -237.019157) (xy 7.430756 -237.011377) (xy 7.44093 -237.010956)
			(xy 8.84047 -237.010956) (xy 8.850642 -237.011389) (xy 8.869439 -237.019167) (xy 8.883826 -237.033551)
			(xy 8.891609 -237.052346) (xy 8.892032 -237.062518) (xy 8.892032 -237.471458) (xy 11.489436 -237.471458)
			(xy 11.489436 -237.062518) (xy 11.489878 -237.052348) (xy 11.497657 -237.033554) (xy 11.512037 -237.019168)
			(xy 11.530828 -237.011382) (xy 11.540998 -237.010956) (xy 12.940538 -237.010956) (xy 12.9507 -237.011403)
			(xy 12.969474 -237.019193) (xy 12.983838 -237.033573) (xy 12.991608 -237.052355) (xy 12.9921 -237.062518)
			(xy 12.9921 -237.471458) (xy 14.933168 -237.471458) (xy 14.933168 -237.062518) (xy 14.933579 -237.052344)
			(xy 14.941364 -237.033544) (xy 14.955754 -237.019157) (xy 14.974556 -237.011377) (xy 14.98473 -237.010956)
			(xy 16.38427 -237.010956) (xy 16.394442 -237.011389) (xy 16.413239 -237.019167) (xy 16.427626 -237.033551)
			(xy 16.435409 -237.052346) (xy 16.435832 -237.062518) (xy 16.435832 -237.471458) (xy 19.033236 -237.471458)
			(xy 19.033236 -237.062518) (xy 19.033678 -237.052348) (xy 19.041457 -237.033554) (xy 19.055837 -237.019168)
			(xy 19.074628 -237.011382) (xy 19.084798 -237.010956) (xy 20.484338 -237.010956) (xy 20.4945 -237.011403)
			(xy 20.513274 -237.019193) (xy 20.527638 -237.033573) (xy 20.535408 -237.052355) (xy 20.5359 -237.062518)
			(xy 20.5359 -237.471458) (xy 22.476968 -237.471458) (xy 22.476968 -237.062518) (xy 22.477379 -237.052344)
			(xy 22.485164 -237.033544) (xy 22.499554 -237.019157) (xy 22.518356 -237.011377) (xy 22.52853 -237.010956)
			(xy 23.92807 -237.010956) (xy 23.938242 -237.011389) (xy 23.957039 -237.019167) (xy 23.971426 -237.033551)
			(xy 23.979209 -237.052346) (xy 23.979632 -237.062518) (xy 23.979632 -237.471458) (xy 26.577036 -237.471458)
			(xy 26.577036 -237.062518) (xy 26.577478 -237.052348) (xy 26.585257 -237.033554) (xy 26.599637 -237.019168)
			(xy 26.618428 -237.011382) (xy 26.628598 -237.010956) (xy 28.028138 -237.010956) (xy 28.0383 -237.011403)
			(xy 28.057074 -237.019193) (xy 28.071438 -237.033573) (xy 28.079208 -237.052355) (xy 28.0797 -237.062518)
			(xy 28.0797 -237.471458) (xy 30.020768 -237.471458) (xy 30.020768 -237.062518) (xy 30.021179 -237.052344)
			(xy 30.028964 -237.033544) (xy 30.043354 -237.019157) (xy 30.062156 -237.011377) (xy 30.07233 -237.010956)
			(xy 31.47187 -237.010956) (xy 31.482042 -237.011389) (xy 31.500839 -237.019167) (xy 31.515226 -237.033551)
			(xy 31.523009 -237.052346) (xy 31.523432 -237.062518) (xy 31.523432 -237.471458) (xy 34.120836 -237.471458)
			(xy 34.120836 -237.062518) (xy 34.121278 -237.052348) (xy 34.129057 -237.033554) (xy 34.143437 -237.019168)
			(xy 34.162228 -237.011382) (xy 34.172398 -237.010956) (xy 35.571938 -237.010956) (xy 35.5821 -237.011403)
			(xy 35.600874 -237.019193) (xy 35.615238 -237.033573) (xy 35.623008 -237.052355) (xy 35.6235 -237.062518)
			(xy 35.6235 -237.471458) (xy 37.564568 -237.471458) (xy 37.564568 -237.062518) (xy 37.564979 -237.052344)
			(xy 37.572764 -237.033544) (xy 37.587154 -237.019157) (xy 37.605956 -237.011377) (xy 37.61613 -237.010956)
			(xy 39.01567 -237.010956) (xy 39.025842 -237.011389) (xy 39.044639 -237.019167) (xy 39.059026 -237.033551)
			(xy 39.066809 -237.052346) (xy 39.067232 -237.062518) (xy 39.067232 -237.471458) (xy 41.664636 -237.471458)
			(xy 41.664636 -237.062518) (xy 41.665078 -237.052348) (xy 41.672857 -237.033554) (xy 41.687237 -237.019168)
			(xy 41.706028 -237.011382) (xy 41.716198 -237.010956) (xy 43.115738 -237.010956) (xy 43.1259 -237.011403)
			(xy 43.144674 -237.019193) (xy 43.159038 -237.033573) (xy 43.166808 -237.052355) (xy 43.1673 -237.062518)
			(xy 43.1673 -237.471458) (xy 45.108368 -237.471458) (xy 45.108368 -237.062518) (xy 45.108779 -237.052344)
			(xy 45.116564 -237.033544) (xy 45.130954 -237.019157) (xy 45.149756 -237.011377) (xy 45.15993 -237.010956)
			(xy 46.55947 -237.010956) (xy 46.569642 -237.011389) (xy 46.588439 -237.019167) (xy 46.602826 -237.033551)
			(xy 46.610609 -237.052346) (xy 46.611032 -237.062518) (xy 46.611032 -237.471458) (xy 49.208436 -237.471458)
			(xy 49.208436 -237.062518) (xy 49.208878 -237.052348) (xy 49.216657 -237.033554) (xy 49.231037 -237.019168)
			(xy 49.249828 -237.011382) (xy 49.259998 -237.010956) (xy 50.659538 -237.010956) (xy 50.6697 -237.011403)
			(xy 50.688474 -237.019193) (xy 50.702838 -237.033573) (xy 50.710608 -237.052355) (xy 50.7111 -237.062518)
			(xy 50.7111 -237.471458) (xy 52.652168 -237.471458) (xy 52.652168 -237.062518) (xy 52.652579 -237.052344)
			(xy 52.660364 -237.033544) (xy 52.674754 -237.019157) (xy 52.693556 -237.011377) (xy 52.70373 -237.010956)
			(xy 54.10327 -237.010956) (xy 54.113442 -237.011389) (xy 54.132239 -237.019167) (xy 54.146626 -237.033551)
			(xy 54.154409 -237.052346) (xy 54.154832 -237.062518) (xy 54.154832 -237.471458) (xy 56.752236 -237.471458)
			(xy 56.752236 -237.062518) (xy 56.752678 -237.052348) (xy 56.760457 -237.033554) (xy 56.774837 -237.019168)
			(xy 56.793628 -237.011382) (xy 56.803798 -237.010956) (xy 58.203338 -237.010956) (xy 58.2135 -237.011403)
			(xy 58.232274 -237.019193) (xy 58.246638 -237.033573) (xy 58.254408 -237.052355) (xy 58.2549 -237.062518)
			(xy 58.2549 -237.471458) (xy 60.195968 -237.471458) (xy 60.195968 -237.062518) (xy 60.196379 -237.052344)
			(xy 60.204164 -237.033544) (xy 60.218554 -237.019157) (xy 60.237356 -237.011377) (xy 60.24753 -237.010956)
			(xy 61.64707 -237.010956) (xy 61.657242 -237.011389) (xy 61.676039 -237.019167) (xy 61.690426 -237.033551)
			(xy 61.698209 -237.052346) (xy 61.698632 -237.062518) (xy 61.698632 -237.471458) (xy 64.296036 -237.471458)
			(xy 64.296036 -237.062518) (xy 64.296478 -237.052348) (xy 64.304257 -237.033554) (xy 64.318637 -237.019168)
			(xy 64.337428 -237.011382) (xy 64.347598 -237.010956) (xy 65.747138 -237.010956) (xy 65.7573 -237.011403)
			(xy 65.776074 -237.019193) (xy 65.790438 -237.033573) (xy 65.798208 -237.052355) (xy 65.7987 -237.062518)
			(xy 65.7987 -237.471458) (xy 158.062168 -237.471458) (xy 158.062168 -237.062518) (xy 158.062579 -237.052344)
			(xy 158.070364 -237.033544) (xy 158.084754 -237.019157) (xy 158.103556 -237.011377) (xy 158.11373 -237.010956)
			(xy 159.51327 -237.010956) (xy 159.523442 -237.011389) (xy 159.542239 -237.019167) (xy 159.556626 -237.033551)
			(xy 159.564409 -237.052346) (xy 159.564832 -237.062518) (xy 159.564832 -237.471458) (xy 162.162236 -237.471458)
			(xy 162.162236 -237.062518) (xy 162.162678 -237.052348) (xy 162.170457 -237.033554) (xy 162.184837 -237.019168)
			(xy 162.203628 -237.011382) (xy 162.213798 -237.010956) (xy 163.613338 -237.010956) (xy 163.6235 -237.011403)
			(xy 163.642274 -237.019193) (xy 163.656638 -237.033573) (xy 163.664408 -237.052355) (xy 163.6649 -237.062518)
			(xy 163.6649 -237.471458) (xy 165.605968 -237.471458) (xy 165.605968 -237.062518) (xy 165.606379 -237.052344)
			(xy 165.614164 -237.033544) (xy 165.628554 -237.019157) (xy 165.647356 -237.011377) (xy 165.65753 -237.010956)
			(xy 167.05707 -237.010956) (xy 167.067242 -237.011389) (xy 167.086039 -237.019167) (xy 167.100426 -237.033551)
			(xy 167.108209 -237.052346) (xy 167.108632 -237.062518) (xy 167.108632 -237.471458) (xy 169.706036 -237.471458)
			(xy 169.706036 -237.062518) (xy 169.706478 -237.052348) (xy 169.714257 -237.033554) (xy 169.728637 -237.019168)
			(xy 169.747428 -237.011382) (xy 169.757598 -237.010956) (xy 171.157138 -237.010956) (xy 171.1673 -237.011403)
			(xy 171.186074 -237.019193) (xy 171.200438 -237.033573) (xy 171.208208 -237.052355) (xy 171.2087 -237.062518)
			(xy 171.2087 -237.471458) (xy 173.149768 -237.471458) (xy 173.149768 -237.062518) (xy 173.150179 -237.052344)
			(xy 173.157964 -237.033544) (xy 173.172354 -237.019157) (xy 173.191156 -237.011377) (xy 173.20133 -237.010956)
			(xy 174.60087 -237.010956) (xy 174.611042 -237.011389) (xy 174.629839 -237.019167) (xy 174.644226 -237.033551)
			(xy 174.652009 -237.052346) (xy 174.652432 -237.062518) (xy 174.652432 -237.471458) (xy 177.249836 -237.471458)
			(xy 177.249836 -237.062518) (xy 177.250278 -237.052348) (xy 177.258057 -237.033554) (xy 177.272437 -237.019168)
			(xy 177.291228 -237.011382) (xy 177.301398 -237.010956) (xy 178.700938 -237.010956) (xy 178.7111 -237.011403)
			(xy 178.729874 -237.019193) (xy 178.744238 -237.033573) (xy 178.752008 -237.052355) (xy 178.7525 -237.062518)
			(xy 178.7525 -237.471458) (xy 180.693568 -237.471458) (xy 180.693568 -237.062518) (xy 180.693979 -237.052344)
			(xy 180.701764 -237.033544) (xy 180.716154 -237.019157) (xy 180.734956 -237.011377) (xy 180.74513 -237.010956)
			(xy 182.14467 -237.010956) (xy 182.154842 -237.011389) (xy 182.173639 -237.019167) (xy 182.188026 -237.033551)
			(xy 182.195809 -237.052346) (xy 182.196232 -237.062518) (xy 182.196232 -237.471458) (xy 184.793636 -237.471458)
			(xy 184.793636 -237.062518) (xy 184.794078 -237.052348) (xy 184.801857 -237.033554) (xy 184.816237 -237.019168)
			(xy 184.835028 -237.011382) (xy 184.845198 -237.010956) (xy 186.244738 -237.010956) (xy 186.2549 -237.011403)
			(xy 186.273674 -237.019193) (xy 186.288038 -237.033573) (xy 186.295808 -237.052355) (xy 186.2963 -237.062518)
			(xy 186.2963 -237.471458) (xy 188.237368 -237.471458) (xy 188.237368 -237.062518) (xy 188.237779 -237.052344)
			(xy 188.245564 -237.033544) (xy 188.259954 -237.019157) (xy 188.278756 -237.011377) (xy 188.28893 -237.010956)
			(xy 189.68847 -237.010956) (xy 189.698642 -237.011389) (xy 189.717439 -237.019167) (xy 189.731826 -237.033551)
			(xy 189.739609 -237.052346) (xy 189.740032 -237.062518) (xy 189.740032 -237.471458) (xy 192.337436 -237.471458)
			(xy 192.337436 -237.062518) (xy 192.337878 -237.052348) (xy 192.345657 -237.033554) (xy 192.360037 -237.019168)
			(xy 192.378828 -237.011382) (xy 192.388998 -237.010956) (xy 193.788538 -237.010956) (xy 193.7987 -237.011403)
			(xy 193.817474 -237.019193) (xy 193.831838 -237.033573) (xy 193.839608 -237.052355) (xy 193.8401 -237.062518)
			(xy 193.8401 -237.471458) (xy 195.781168 -237.471458) (xy 195.781168 -237.062518) (xy 195.781579 -237.052344)
			(xy 195.789364 -237.033544) (xy 195.803754 -237.019157) (xy 195.822556 -237.011377) (xy 195.83273 -237.010956)
			(xy 197.23227 -237.010956) (xy 197.242442 -237.011389) (xy 197.261239 -237.019167) (xy 197.275626 -237.033551)
			(xy 197.283409 -237.052346) (xy 197.283832 -237.062518) (xy 197.283832 -237.471458) (xy 199.881236 -237.471458)
			(xy 199.881236 -237.062518) (xy 199.881678 -237.052348) (xy 199.889457 -237.033554) (xy 199.903837 -237.019168)
			(xy 199.922628 -237.011382) (xy 199.932798 -237.010956) (xy 201.332338 -237.010956) (xy 201.3425 -237.011403)
			(xy 201.361274 -237.019193) (xy 201.375638 -237.033573) (xy 201.383408 -237.052355) (xy 201.3839 -237.062518)
			(xy 201.3839 -237.471458) (xy 203.324968 -237.471458) (xy 203.324968 -237.062518) (xy 203.325379 -237.052344)
			(xy 203.333164 -237.033544) (xy 203.347554 -237.019157) (xy 203.366356 -237.011377) (xy 203.37653 -237.010956)
			(xy 204.77607 -237.010956) (xy 204.786242 -237.011389) (xy 204.805039 -237.019167) (xy 204.819426 -237.033551)
			(xy 204.827209 -237.052346) (xy 204.827632 -237.062518) (xy 204.827632 -237.471458) (xy 207.425036 -237.471458)
			(xy 207.425036 -237.062518) (xy 207.425478 -237.052348) (xy 207.433257 -237.033554) (xy 207.447637 -237.019168)
			(xy 207.466428 -237.011382) (xy 207.476598 -237.010956) (xy 208.876138 -237.010956) (xy 208.8863 -237.011403)
			(xy 208.905074 -237.019193) (xy 208.919438 -237.033573) (xy 208.927208 -237.052355) (xy 208.9277 -237.062518)
			(xy 208.9277 -237.471458) (xy 210.868768 -237.471458) (xy 210.868768 -237.062518) (xy 210.869179 -237.052344)
			(xy 210.876964 -237.033544) (xy 210.891354 -237.019157) (xy 210.910156 -237.011377) (xy 210.92033 -237.010956)
			(xy 212.31987 -237.010956) (xy 212.330042 -237.011389) (xy 212.348839 -237.019167) (xy 212.363226 -237.033551)
			(xy 212.371009 -237.052346) (xy 212.371432 -237.062518) (xy 212.371432 -237.471458) (xy 214.968836 -237.471458)
			(xy 214.968836 -237.062518) (xy 214.969278 -237.052348) (xy 214.977057 -237.033554) (xy 214.991437 -237.019168)
			(xy 215.010228 -237.011382) (xy 215.020398 -237.010956) (xy 216.419938 -237.010956) (xy 216.4301 -237.011403)
			(xy 216.448874 -237.019193) (xy 216.463238 -237.033573) (xy 216.471008 -237.052355) (xy 216.4715 -237.062518)
			(xy 216.4715 -237.471458) (xy 255.329436 -237.471458) (xy 255.329436 -237.062518) (xy 255.329878 -237.052348)
			(xy 255.337657 -237.033554) (xy 255.352037 -237.019168) (xy 255.370828 -237.011382) (xy 255.380998 -237.010956)
			(xy 256.780538 -237.010956) (xy 256.7907 -237.011403) (xy 256.809474 -237.019193) (xy 256.823838 -237.033573)
			(xy 256.831608 -237.052355) (xy 256.8321 -237.062518) (xy 256.8321 -237.471458) (xy 259.429504 -237.471458)
			(xy 259.429504 -237.062518) (xy 259.430047 -237.052366) (xy 259.437809 -237.033603) (xy 259.45216 -237.019239)
			(xy 259.470914 -237.011457) (xy 259.481066 -237.010956) (xy 260.880606 -237.010956) (xy 260.89078 -237.011359)
			(xy 260.909578 -237.01915) (xy 260.923964 -237.033542) (xy 260.931745 -237.052344) (xy 260.932168 -237.062518)
			(xy 260.932168 -237.471458) (xy 262.873236 -237.471458) (xy 262.873236 -237.062518) (xy 262.873678 -237.052348)
			(xy 262.881457 -237.033554) (xy 262.895837 -237.019168) (xy 262.914628 -237.011382) (xy 262.924798 -237.010956)
			(xy 264.324338 -237.010956) (xy 264.3345 -237.011403) (xy 264.353274 -237.019193) (xy 264.367638 -237.033573)
			(xy 264.375408 -237.052355) (xy 264.3759 -237.062518) (xy 264.3759 -237.471458) (xy 266.973304 -237.471458)
			(xy 266.973304 -237.062518) (xy 266.973847 -237.052366) (xy 266.981609 -237.033603) (xy 266.99596 -237.019239)
			(xy 267.014714 -237.011457) (xy 267.024866 -237.010956) (xy 268.424406 -237.010956) (xy 268.43458 -237.011359)
			(xy 268.453378 -237.01915) (xy 268.467764 -237.033542) (xy 268.475545 -237.052344) (xy 268.475968 -237.062518)
			(xy 268.475968 -237.471458) (xy 270.417036 -237.471458) (xy 270.417036 -237.062518) (xy 270.417478 -237.052348)
			(xy 270.425257 -237.033554) (xy 270.439637 -237.019168) (xy 270.458428 -237.011382) (xy 270.468598 -237.010956)
			(xy 271.868138 -237.010956) (xy 271.8783 -237.011403) (xy 271.897074 -237.019193) (xy 271.911438 -237.033573)
			(xy 271.919208 -237.052355) (xy 271.9197 -237.062518) (xy 271.9197 -237.471458) (xy 274.517104 -237.471458)
			(xy 274.517104 -237.062518) (xy 274.517647 -237.052366) (xy 274.525409 -237.033603) (xy 274.53976 -237.019239)
			(xy 274.558514 -237.011457) (xy 274.568666 -237.010956) (xy 275.968206 -237.010956) (xy 275.97838 -237.011359)
			(xy 275.997178 -237.01915) (xy 276.011564 -237.033542) (xy 276.019345 -237.052344) (xy 276.019768 -237.062518)
			(xy 276.019768 -237.471458) (xy 277.960836 -237.471458) (xy 277.960836 -237.062518) (xy 277.961278 -237.052348)
			(xy 277.969057 -237.033554) (xy 277.983437 -237.019168) (xy 278.002228 -237.011382) (xy 278.012398 -237.010956)
			(xy 279.411938 -237.010956) (xy 279.4221 -237.011403) (xy 279.440874 -237.019193) (xy 279.455238 -237.033573)
			(xy 279.463008 -237.052355) (xy 279.4635 -237.062518) (xy 279.4635 -237.471458) (xy 282.060904 -237.471458)
			(xy 282.060904 -237.062518) (xy 282.061447 -237.052366) (xy 282.069209 -237.033603) (xy 282.08356 -237.019239)
			(xy 282.102314 -237.011457) (xy 282.112466 -237.010956) (xy 283.512006 -237.010956) (xy 283.52218 -237.011359)
			(xy 283.540978 -237.01915) (xy 283.555364 -237.033542) (xy 283.563145 -237.052344) (xy 283.563568 -237.062518)
			(xy 283.563568 -237.471458) (xy 285.504636 -237.471458) (xy 285.504636 -237.062518) (xy 285.505078 -237.052348)
			(xy 285.512857 -237.033554) (xy 285.527237 -237.019168) (xy 285.546028 -237.011382) (xy 285.556198 -237.010956)
			(xy 286.955738 -237.010956) (xy 286.9659 -237.011403) (xy 286.984674 -237.019193) (xy 286.999038 -237.033573)
			(xy 287.006808 -237.052355) (xy 287.0073 -237.062518) (xy 287.0073 -237.471458) (xy 289.604704 -237.471458)
			(xy 289.604704 -237.062518) (xy 289.605247 -237.052366) (xy 289.613009 -237.033603) (xy 289.62736 -237.019239)
			(xy 289.646114 -237.011457) (xy 289.656266 -237.010956) (xy 291.055806 -237.010956) (xy 291.06598 -237.011359)
			(xy 291.084778 -237.01915) (xy 291.099164 -237.033542) (xy 291.106945 -237.052344) (xy 291.107368 -237.062518)
			(xy 291.107368 -237.471458) (xy 293.048436 -237.471458) (xy 293.048436 -237.062518) (xy 293.048878 -237.052348)
			(xy 293.056657 -237.033554) (xy 293.071037 -237.019168) (xy 293.089828 -237.011382) (xy 293.099998 -237.010956)
			(xy 294.499538 -237.010956) (xy 294.5097 -237.011403) (xy 294.528474 -237.019193) (xy 294.542838 -237.033573)
			(xy 294.550608 -237.052355) (xy 294.5511 -237.062518) (xy 294.5511 -237.471458) (xy 297.148504 -237.471458)
			(xy 297.148504 -237.062518) (xy 297.149047 -237.052366) (xy 297.156809 -237.033603) (xy 297.17116 -237.019239)
			(xy 297.189914 -237.011457) (xy 297.200066 -237.010956) (xy 298.599606 -237.010956) (xy 298.60978 -237.011359)
			(xy 298.628578 -237.01915) (xy 298.642964 -237.033542) (xy 298.650745 -237.052344) (xy 298.651168 -237.062518)
			(xy 298.651168 -237.471458) (xy 300.592236 -237.471458) (xy 300.592236 -237.062518) (xy 300.592678 -237.052348)
			(xy 300.600457 -237.033554) (xy 300.614837 -237.019168) (xy 300.633628 -237.011382) (xy 300.643798 -237.010956)
			(xy 302.043338 -237.010956) (xy 302.0535 -237.011403) (xy 302.072274 -237.019193) (xy 302.086638 -237.033573)
			(xy 302.094408 -237.052355) (xy 302.0949 -237.062518) (xy 302.0949 -237.471458) (xy 304.692304 -237.471458)
			(xy 304.692304 -237.062518) (xy 304.692847 -237.052366) (xy 304.700609 -237.033603) (xy 304.71496 -237.019239)
			(xy 304.733714 -237.011457) (xy 304.743866 -237.010956) (xy 306.143406 -237.010956) (xy 306.15358 -237.011359)
			(xy 306.172378 -237.01915) (xy 306.186764 -237.033542) (xy 306.194545 -237.052344) (xy 306.194968 -237.062518)
			(xy 306.194968 -237.471458) (xy 308.136036 -237.471458) (xy 308.136036 -237.062518) (xy 308.136478 -237.052348)
			(xy 308.144257 -237.033554) (xy 308.158637 -237.019168) (xy 308.177428 -237.011382) (xy 308.187598 -237.010956)
			(xy 309.587138 -237.010956) (xy 309.5973 -237.011403) (xy 309.616074 -237.019193) (xy 309.630438 -237.033573)
			(xy 309.638208 -237.052355) (xy 309.6387 -237.062518) (xy 309.6387 -237.471458) (xy 312.236104 -237.471458)
			(xy 312.236104 -237.062518) (xy 312.236647 -237.052366) (xy 312.244409 -237.033603) (xy 312.25876 -237.019239)
			(xy 312.277514 -237.011457) (xy 312.287666 -237.010956) (xy 313.687206 -237.010956) (xy 313.69738 -237.011359)
			(xy 313.716178 -237.01915) (xy 313.730564 -237.033542) (xy 313.738345 -237.052344) (xy 313.738768 -237.062518)
			(xy 313.738768 -237.471458) (xy 406.002236 -237.471458) (xy 406.002236 -237.062518) (xy 406.002678 -237.052348)
			(xy 406.010457 -237.033554) (xy 406.024837 -237.019168) (xy 406.043628 -237.011382) (xy 406.053798 -237.010956)
			(xy 407.453338 -237.010956) (xy 407.4635 -237.011403) (xy 407.482274 -237.019193) (xy 407.496638 -237.033573)
			(xy 407.504408 -237.052355) (xy 407.5049 -237.062518) (xy 407.5049 -237.471458) (xy 410.102304 -237.471458)
			(xy 410.102304 -237.062518) (xy 410.102847 -237.052366) (xy 410.110609 -237.033603) (xy 410.12496 -237.019239)
			(xy 410.143714 -237.011457) (xy 410.153866 -237.010956) (xy 411.553406 -237.010956) (xy 411.56358 -237.011359)
			(xy 411.582378 -237.01915) (xy 411.596764 -237.033542) (xy 411.604545 -237.052344) (xy 411.604968 -237.062518)
			(xy 411.604968 -237.471458) (xy 413.546036 -237.471458) (xy 413.546036 -237.062518) (xy 413.546478 -237.052348)
			(xy 413.554257 -237.033554) (xy 413.568637 -237.019168) (xy 413.587428 -237.011382) (xy 413.597598 -237.010956)
			(xy 414.997138 -237.010956) (xy 415.0073 -237.011403) (xy 415.026074 -237.019193) (xy 415.040438 -237.033573)
			(xy 415.048208 -237.052355) (xy 415.0487 -237.062518) (xy 415.0487 -237.471458) (xy 417.646104 -237.471458)
			(xy 417.646104 -237.062518) (xy 417.646647 -237.052366) (xy 417.654409 -237.033603) (xy 417.66876 -237.019239)
			(xy 417.687514 -237.011457) (xy 417.697666 -237.010956) (xy 419.097206 -237.010956) (xy 419.10738 -237.011359)
			(xy 419.126178 -237.01915) (xy 419.140564 -237.033542) (xy 419.148345 -237.052344) (xy 419.148768 -237.062518)
			(xy 419.148768 -237.471458) (xy 421.089836 -237.471458) (xy 421.089836 -237.062518) (xy 421.090278 -237.052348)
			(xy 421.098057 -237.033554) (xy 421.112437 -237.019168) (xy 421.131228 -237.011382) (xy 421.141398 -237.010956)
			(xy 422.540938 -237.010956) (xy 422.5511 -237.011403) (xy 422.569874 -237.019193) (xy 422.584238 -237.033573)
			(xy 422.592008 -237.052355) (xy 422.5925 -237.062518) (xy 422.5925 -237.471458) (xy 425.189904 -237.471458)
			(xy 425.189904 -237.062518) (xy 425.190447 -237.052366) (xy 425.198209 -237.033603) (xy 425.21256 -237.019239)
			(xy 425.231314 -237.011457) (xy 425.241466 -237.010956) (xy 426.641006 -237.010956) (xy 426.65118 -237.011359)
			(xy 426.669978 -237.01915) (xy 426.684364 -237.033542) (xy 426.692145 -237.052344) (xy 426.692568 -237.062518)
			(xy 426.692568 -237.471458) (xy 428.633636 -237.471458) (xy 428.633636 -237.062518) (xy 428.634078 -237.052348)
			(xy 428.641857 -237.033554) (xy 428.656237 -237.019168) (xy 428.675028 -237.011382) (xy 428.685198 -237.010956)
			(xy 430.084738 -237.010956) (xy 430.0949 -237.011403) (xy 430.113674 -237.019193) (xy 430.128038 -237.033573)
			(xy 430.135808 -237.052355) (xy 430.1363 -237.062518) (xy 430.1363 -237.471458) (xy 432.733704 -237.471458)
			(xy 432.733704 -237.062518) (xy 432.734247 -237.052366) (xy 432.742009 -237.033603) (xy 432.75636 -237.019239)
			(xy 432.775114 -237.011457) (xy 432.785266 -237.010956) (xy 434.184806 -237.010956) (xy 434.19498 -237.011359)
			(xy 434.213778 -237.01915) (xy 434.228164 -237.033542) (xy 434.235945 -237.052344) (xy 434.236368 -237.062518)
			(xy 434.236368 -237.471458) (xy 436.177436 -237.471458) (xy 436.177436 -237.062518) (xy 436.177878 -237.052348)
			(xy 436.185657 -237.033554) (xy 436.200037 -237.019168) (xy 436.218828 -237.011382) (xy 436.228998 -237.010956)
			(xy 437.628538 -237.010956) (xy 437.6387 -237.011403) (xy 437.657474 -237.019193) (xy 437.671838 -237.033573)
			(xy 437.679608 -237.052355) (xy 437.6801 -237.062518) (xy 437.6801 -237.471458) (xy 440.277504 -237.471458)
			(xy 440.277504 -237.062518) (xy 440.278047 -237.052366) (xy 440.285809 -237.033603) (xy 440.30016 -237.019239)
			(xy 440.318914 -237.011457) (xy 440.329066 -237.010956) (xy 441.728606 -237.010956) (xy 441.73878 -237.011359)
			(xy 441.757578 -237.01915) (xy 441.771964 -237.033542) (xy 441.779745 -237.052344) (xy 441.780168 -237.062518)
			(xy 441.780168 -237.471458) (xy 443.721236 -237.471458) (xy 443.721236 -237.062518) (xy 443.721678 -237.052348)
			(xy 443.729457 -237.033554) (xy 443.743837 -237.019168) (xy 443.762628 -237.011382) (xy 443.772798 -237.010956)
			(xy 445.172338 -237.010956) (xy 445.1825 -237.011403) (xy 445.201274 -237.019193) (xy 445.215638 -237.033573)
			(xy 445.223408 -237.052355) (xy 445.2239 -237.062518) (xy 445.2239 -237.471458) (xy 447.821304 -237.471458)
			(xy 447.821304 -237.062518) (xy 447.821847 -237.052366) (xy 447.829609 -237.033603) (xy 447.84396 -237.019239)
			(xy 447.862714 -237.011457) (xy 447.872866 -237.010956) (xy 449.272406 -237.010956) (xy 449.28258 -237.011359)
			(xy 449.301378 -237.01915) (xy 449.315764 -237.033542) (xy 449.323545 -237.052344) (xy 449.323968 -237.062518)
			(xy 449.323968 -237.471458) (xy 451.265036 -237.471458) (xy 451.265036 -237.062518) (xy 451.265478 -237.052348)
			(xy 451.273257 -237.033554) (xy 451.287637 -237.019168) (xy 451.306428 -237.011382) (xy 451.316598 -237.010956)
			(xy 452.716138 -237.010956) (xy 452.7263 -237.011403) (xy 452.745074 -237.019193) (xy 452.759438 -237.033573)
			(xy 452.767208 -237.052355) (xy 452.7677 -237.062518) (xy 452.7677 -237.471458) (xy 455.365104 -237.471458)
			(xy 455.365104 -237.062518) (xy 455.365647 -237.052366) (xy 455.373409 -237.033603) (xy 455.38776 -237.019239)
			(xy 455.406514 -237.011457) (xy 455.416666 -237.010956) (xy 456.816206 -237.010956) (xy 456.82638 -237.011359)
			(xy 456.845178 -237.01915) (xy 456.859564 -237.033542) (xy 456.867345 -237.052344) (xy 456.867768 -237.062518)
			(xy 456.867768 -237.471458) (xy 458.808836 -237.471458) (xy 458.808836 -237.062518) (xy 458.809278 -237.052348)
			(xy 458.817057 -237.033554) (xy 458.831437 -237.019168) (xy 458.850228 -237.011382) (xy 458.860398 -237.010956)
			(xy 460.259938 -237.010956) (xy 460.2701 -237.011403) (xy 460.288874 -237.019193) (xy 460.303238 -237.033573)
			(xy 460.311008 -237.052355) (xy 460.3115 -237.062518) (xy 460.3115 -237.471458) (xy 462.908904 -237.471458)
			(xy 462.908904 -237.062518) (xy 462.909447 -237.052366) (xy 462.917209 -237.033603) (xy 462.93156 -237.019239)
			(xy 462.950314 -237.011457) (xy 462.960466 -237.010956) (xy 464.360006 -237.010956) (xy 464.37018 -237.011359)
			(xy 464.388978 -237.01915) (xy 464.403364 -237.033542) (xy 464.411145 -237.052344) (xy 464.411568 -237.062518)
			(xy 464.411568 -237.471458) (xy 464.411102 -237.481626) (xy 464.403332 -237.500419) (xy 464.388959 -237.514805)
			(xy 464.370174 -237.522592) (xy 464.360006 -237.52302) (xy 462.960466 -237.52302) (xy 462.950287 -237.522663)
			(xy 462.931483 -237.514859) (xy 462.917098 -237.500453) (xy 462.909322 -237.481638) (xy 462.908904 -237.471458)
			(xy 460.3115 -237.471458) (xy 460.311003 -237.481622) (xy 460.303239 -237.500409) (xy 460.288876 -237.514794)
			(xy 460.270102 -237.522587) (xy 460.259938 -237.52302) (xy 458.860398 -237.52302) (xy 458.850221 -237.522637)
			(xy 458.831418 -237.514843) (xy 458.817032 -237.500445) (xy 458.809255 -237.481635) (xy 458.808836 -237.471458)
			(xy 456.867768 -237.471458) (xy 456.867302 -237.481626) (xy 456.859532 -237.500419) (xy 456.845159 -237.514805)
			(xy 456.826374 -237.522592) (xy 456.816206 -237.52302) (xy 455.416666 -237.52302) (xy 455.406487 -237.522663)
			(xy 455.387683 -237.514859) (xy 455.373298 -237.500453) (xy 455.365522 -237.481638) (xy 455.365104 -237.471458)
			(xy 452.7677 -237.471458) (xy 452.767203 -237.481622) (xy 452.759439 -237.500409) (xy 452.745076 -237.514794)
			(xy 452.726302 -237.522587) (xy 452.716138 -237.52302) (xy 451.316598 -237.52302) (xy 451.306421 -237.522637)
			(xy 451.287618 -237.514843) (xy 451.273232 -237.500445) (xy 451.265455 -237.481635) (xy 451.265036 -237.471458)
			(xy 449.323968 -237.471458) (xy 449.323502 -237.481626) (xy 449.315732 -237.500419) (xy 449.301359 -237.514805)
			(xy 449.282574 -237.522592) (xy 449.272406 -237.52302) (xy 447.872866 -237.52302) (xy 447.862687 -237.522663)
			(xy 447.843883 -237.514859) (xy 447.829498 -237.500453) (xy 447.821722 -237.481638) (xy 447.821304 -237.471458)
			(xy 445.2239 -237.471458) (xy 445.223403 -237.481622) (xy 445.215639 -237.500409) (xy 445.201276 -237.514794)
			(xy 445.182502 -237.522587) (xy 445.172338 -237.52302) (xy 443.772798 -237.52302) (xy 443.762621 -237.522637)
			(xy 443.743818 -237.514843) (xy 443.729432 -237.500445) (xy 443.721655 -237.481635) (xy 443.721236 -237.471458)
			(xy 441.780168 -237.471458) (xy 441.779702 -237.481626) (xy 441.771932 -237.500419) (xy 441.757559 -237.514805)
			(xy 441.738774 -237.522592) (xy 441.728606 -237.52302) (xy 440.329066 -237.52302) (xy 440.318887 -237.522663)
			(xy 440.300083 -237.514859) (xy 440.285698 -237.500453) (xy 440.277922 -237.481638) (xy 440.277504 -237.471458)
			(xy 437.6801 -237.471458) (xy 437.679603 -237.481622) (xy 437.671839 -237.500409) (xy 437.657476 -237.514794)
			(xy 437.638702 -237.522587) (xy 437.628538 -237.52302) (xy 436.228998 -237.52302) (xy 436.218821 -237.522637)
			(xy 436.200018 -237.514843) (xy 436.185632 -237.500445) (xy 436.177855 -237.481635) (xy 436.177436 -237.471458)
			(xy 434.236368 -237.471458) (xy 434.235902 -237.481626) (xy 434.228132 -237.500419) (xy 434.213759 -237.514805)
			(xy 434.194974 -237.522592) (xy 434.184806 -237.52302) (xy 432.785266 -237.52302) (xy 432.775087 -237.522663)
			(xy 432.756283 -237.514859) (xy 432.741898 -237.500453) (xy 432.734122 -237.481638) (xy 432.733704 -237.471458)
			(xy 430.1363 -237.471458) (xy 430.135803 -237.481622) (xy 430.128039 -237.500409) (xy 430.113676 -237.514794)
			(xy 430.094902 -237.522587) (xy 430.084738 -237.52302) (xy 428.685198 -237.52302) (xy 428.675021 -237.522637)
			(xy 428.656218 -237.514843) (xy 428.641832 -237.500445) (xy 428.634055 -237.481635) (xy 428.633636 -237.471458)
			(xy 426.692568 -237.471458) (xy 426.692102 -237.481626) (xy 426.684332 -237.500419) (xy 426.669959 -237.514805)
			(xy 426.651174 -237.522592) (xy 426.641006 -237.52302) (xy 425.241466 -237.52302) (xy 425.231287 -237.522663)
			(xy 425.212483 -237.514859) (xy 425.198098 -237.500453) (xy 425.190322 -237.481638) (xy 425.189904 -237.471458)
			(xy 422.5925 -237.471458) (xy 422.592003 -237.481622) (xy 422.584239 -237.500409) (xy 422.569876 -237.514794)
			(xy 422.551102 -237.522587) (xy 422.540938 -237.52302) (xy 421.141398 -237.52302) (xy 421.131221 -237.522637)
			(xy 421.112418 -237.514843) (xy 421.098032 -237.500445) (xy 421.090255 -237.481635) (xy 421.089836 -237.471458)
			(xy 419.148768 -237.471458) (xy 419.148302 -237.481626) (xy 419.140532 -237.500419) (xy 419.126159 -237.514805)
			(xy 419.107374 -237.522592) (xy 419.097206 -237.52302) (xy 417.697666 -237.52302) (xy 417.687487 -237.522663)
			(xy 417.668683 -237.514859) (xy 417.654298 -237.500453) (xy 417.646522 -237.481638) (xy 417.646104 -237.471458)
			(xy 415.0487 -237.471458) (xy 415.048203 -237.481622) (xy 415.040439 -237.500409) (xy 415.026076 -237.514794)
			(xy 415.007302 -237.522587) (xy 414.997138 -237.52302) (xy 413.597598 -237.52302) (xy 413.587421 -237.522637)
			(xy 413.568618 -237.514843) (xy 413.554232 -237.500445) (xy 413.546455 -237.481635) (xy 413.546036 -237.471458)
			(xy 411.604968 -237.471458) (xy 411.604502 -237.481626) (xy 411.596732 -237.500419) (xy 411.582359 -237.514805)
			(xy 411.563574 -237.522592) (xy 411.553406 -237.52302) (xy 410.153866 -237.52302) (xy 410.143687 -237.522663)
			(xy 410.124883 -237.514859) (xy 410.110498 -237.500453) (xy 410.102722 -237.481638) (xy 410.102304 -237.471458)
			(xy 407.5049 -237.471458) (xy 407.504403 -237.481622) (xy 407.496639 -237.500409) (xy 407.482276 -237.514794)
			(xy 407.463502 -237.522587) (xy 407.453338 -237.52302) (xy 406.053798 -237.52302) (xy 406.043621 -237.522637)
			(xy 406.024818 -237.514843) (xy 406.010432 -237.500445) (xy 406.002655 -237.481635) (xy 406.002236 -237.471458)
			(xy 313.738768 -237.471458) (xy 313.738302 -237.481626) (xy 313.730532 -237.500419) (xy 313.716159 -237.514805)
			(xy 313.697374 -237.522592) (xy 313.687206 -237.52302) (xy 312.287666 -237.52302) (xy 312.277487 -237.522663)
			(xy 312.258683 -237.514859) (xy 312.244298 -237.500453) (xy 312.236522 -237.481638) (xy 312.236104 -237.471458)
			(xy 309.6387 -237.471458) (xy 309.638203 -237.481622) (xy 309.630439 -237.500409) (xy 309.616076 -237.514794)
			(xy 309.597302 -237.522587) (xy 309.587138 -237.52302) (xy 308.187598 -237.52302) (xy 308.177421 -237.522637)
			(xy 308.158618 -237.514843) (xy 308.144232 -237.500445) (xy 308.136455 -237.481635) (xy 308.136036 -237.471458)
			(xy 306.194968 -237.471458) (xy 306.194502 -237.481626) (xy 306.186732 -237.500419) (xy 306.172359 -237.514805)
			(xy 306.153574 -237.522592) (xy 306.143406 -237.52302) (xy 304.743866 -237.52302) (xy 304.733687 -237.522663)
			(xy 304.714883 -237.514859) (xy 304.700498 -237.500453) (xy 304.692722 -237.481638) (xy 304.692304 -237.471458)
			(xy 302.0949 -237.471458) (xy 302.094403 -237.481622) (xy 302.086639 -237.500409) (xy 302.072276 -237.514794)
			(xy 302.053502 -237.522587) (xy 302.043338 -237.52302) (xy 300.643798 -237.52302) (xy 300.633621 -237.522637)
			(xy 300.614818 -237.514843) (xy 300.600432 -237.500445) (xy 300.592655 -237.481635) (xy 300.592236 -237.471458)
			(xy 298.651168 -237.471458) (xy 298.650702 -237.481626) (xy 298.642932 -237.500419) (xy 298.628559 -237.514805)
			(xy 298.609774 -237.522592) (xy 298.599606 -237.52302) (xy 297.200066 -237.52302) (xy 297.189887 -237.522663)
			(xy 297.171083 -237.514859) (xy 297.156698 -237.500453) (xy 297.148922 -237.481638) (xy 297.148504 -237.471458)
			(xy 294.5511 -237.471458) (xy 294.550603 -237.481622) (xy 294.542839 -237.500409) (xy 294.528476 -237.514794)
			(xy 294.509702 -237.522587) (xy 294.499538 -237.52302) (xy 293.099998 -237.52302) (xy 293.089821 -237.522637)
			(xy 293.071018 -237.514843) (xy 293.056632 -237.500445) (xy 293.048855 -237.481635) (xy 293.048436 -237.471458)
			(xy 291.107368 -237.471458) (xy 291.106902 -237.481626) (xy 291.099132 -237.500419) (xy 291.084759 -237.514805)
			(xy 291.065974 -237.522592) (xy 291.055806 -237.52302) (xy 289.656266 -237.52302) (xy 289.646087 -237.522663)
			(xy 289.627283 -237.514859) (xy 289.612898 -237.500453) (xy 289.605122 -237.481638) (xy 289.604704 -237.471458)
			(xy 287.0073 -237.471458) (xy 287.006803 -237.481622) (xy 286.999039 -237.500409) (xy 286.984676 -237.514794)
			(xy 286.965902 -237.522587) (xy 286.955738 -237.52302) (xy 285.556198 -237.52302) (xy 285.546021 -237.522637)
			(xy 285.527218 -237.514843) (xy 285.512832 -237.500445) (xy 285.505055 -237.481635) (xy 285.504636 -237.471458)
			(xy 283.563568 -237.471458) (xy 283.563102 -237.481626) (xy 283.555332 -237.500419) (xy 283.540959 -237.514805)
			(xy 283.522174 -237.522592) (xy 283.512006 -237.52302) (xy 282.112466 -237.52302) (xy 282.102287 -237.522663)
			(xy 282.083483 -237.514859) (xy 282.069098 -237.500453) (xy 282.061322 -237.481638) (xy 282.060904 -237.471458)
			(xy 279.4635 -237.471458) (xy 279.463003 -237.481622) (xy 279.455239 -237.500409) (xy 279.440876 -237.514794)
			(xy 279.422102 -237.522587) (xy 279.411938 -237.52302) (xy 278.012398 -237.52302) (xy 278.002221 -237.522637)
			(xy 277.983418 -237.514843) (xy 277.969032 -237.500445) (xy 277.961255 -237.481635) (xy 277.960836 -237.471458)
			(xy 276.019768 -237.471458) (xy 276.019302 -237.481626) (xy 276.011532 -237.500419) (xy 275.997159 -237.514805)
			(xy 275.978374 -237.522592) (xy 275.968206 -237.52302) (xy 274.568666 -237.52302) (xy 274.558487 -237.522663)
			(xy 274.539683 -237.514859) (xy 274.525298 -237.500453) (xy 274.517522 -237.481638) (xy 274.517104 -237.471458)
			(xy 271.9197 -237.471458) (xy 271.919203 -237.481622) (xy 271.911439 -237.500409) (xy 271.897076 -237.514794)
			(xy 271.878302 -237.522587) (xy 271.868138 -237.52302) (xy 270.468598 -237.52302) (xy 270.458421 -237.522637)
			(xy 270.439618 -237.514843) (xy 270.425232 -237.500445) (xy 270.417455 -237.481635) (xy 270.417036 -237.471458)
			(xy 268.475968 -237.471458) (xy 268.475502 -237.481626) (xy 268.467732 -237.500419) (xy 268.453359 -237.514805)
			(xy 268.434574 -237.522592) (xy 268.424406 -237.52302) (xy 267.024866 -237.52302) (xy 267.014687 -237.522663)
			(xy 266.995883 -237.514859) (xy 266.981498 -237.500453) (xy 266.973722 -237.481638) (xy 266.973304 -237.471458)
			(xy 264.3759 -237.471458) (xy 264.375403 -237.481622) (xy 264.367639 -237.500409) (xy 264.353276 -237.514794)
			(xy 264.334502 -237.522587) (xy 264.324338 -237.52302) (xy 262.924798 -237.52302) (xy 262.914621 -237.522637)
			(xy 262.895818 -237.514843) (xy 262.881432 -237.500445) (xy 262.873655 -237.481635) (xy 262.873236 -237.471458)
			(xy 260.932168 -237.471458) (xy 260.931702 -237.481626) (xy 260.923932 -237.500419) (xy 260.909559 -237.514805)
			(xy 260.890774 -237.522592) (xy 260.880606 -237.52302) (xy 259.481066 -237.52302) (xy 259.470887 -237.522663)
			(xy 259.452083 -237.514859) (xy 259.437698 -237.500453) (xy 259.429922 -237.481638) (xy 259.429504 -237.471458)
			(xy 256.8321 -237.471458) (xy 256.831603 -237.481622) (xy 256.823839 -237.500409) (xy 256.809476 -237.514794)
			(xy 256.790702 -237.522587) (xy 256.780538 -237.52302) (xy 255.380998 -237.52302) (xy 255.370821 -237.522637)
			(xy 255.352018 -237.514843) (xy 255.337632 -237.500445) (xy 255.329855 -237.481635) (xy 255.329436 -237.471458)
			(xy 216.4715 -237.471458) (xy 216.471003 -237.481622) (xy 216.463239 -237.500409) (xy 216.448876 -237.514794)
			(xy 216.430102 -237.522587) (xy 216.419938 -237.52302) (xy 215.020398 -237.52302) (xy 215.010221 -237.522637)
			(xy 214.991418 -237.514843) (xy 214.977032 -237.500445) (xy 214.969255 -237.481635) (xy 214.968836 -237.471458)
			(xy 212.371432 -237.471458) (xy 212.371001 -237.481631) (xy 212.363224 -237.50043) (xy 212.34884 -237.514818)
			(xy 212.330043 -237.522599) (xy 212.31987 -237.52302) (xy 210.92033 -237.52302) (xy 210.910155 -237.52261)
			(xy 210.891353 -237.514828) (xy 210.876966 -237.500437) (xy 210.869187 -237.481633) (xy 210.868768 -237.471458)
			(xy 208.9277 -237.471458) (xy 208.927203 -237.481622) (xy 208.919439 -237.500409) (xy 208.905076 -237.514794)
			(xy 208.886302 -237.522587) (xy 208.876138 -237.52302) (xy 207.476598 -237.52302) (xy 207.466421 -237.522637)
			(xy 207.447618 -237.514843) (xy 207.433232 -237.500445) (xy 207.425455 -237.481635) (xy 207.425036 -237.471458)
			(xy 204.827632 -237.471458) (xy 204.827201 -237.481631) (xy 204.819424 -237.50043) (xy 204.80504 -237.514818)
			(xy 204.786243 -237.522599) (xy 204.77607 -237.52302) (xy 203.37653 -237.52302) (xy 203.366355 -237.52261)
			(xy 203.347553 -237.514828) (xy 203.333166 -237.500437) (xy 203.325387 -237.481633) (xy 203.324968 -237.471458)
			(xy 201.3839 -237.471458) (xy 201.383403 -237.481622) (xy 201.375639 -237.500409) (xy 201.361276 -237.514794)
			(xy 201.342502 -237.522587) (xy 201.332338 -237.52302) (xy 199.932798 -237.52302) (xy 199.922621 -237.522637)
			(xy 199.903818 -237.514843) (xy 199.889432 -237.500445) (xy 199.881655 -237.481635) (xy 199.881236 -237.471458)
			(xy 197.283832 -237.471458) (xy 197.283401 -237.481631) (xy 197.275624 -237.50043) (xy 197.26124 -237.514818)
			(xy 197.242443 -237.522599) (xy 197.23227 -237.52302) (xy 195.83273 -237.52302) (xy 195.822555 -237.52261)
			(xy 195.803753 -237.514828) (xy 195.789366 -237.500437) (xy 195.781587 -237.481633) (xy 195.781168 -237.471458)
			(xy 193.8401 -237.471458) (xy 193.839603 -237.481622) (xy 193.831839 -237.500409) (xy 193.817476 -237.514794)
			(xy 193.798702 -237.522587) (xy 193.788538 -237.52302) (xy 192.388998 -237.52302) (xy 192.378821 -237.522637)
			(xy 192.360018 -237.514843) (xy 192.345632 -237.500445) (xy 192.337855 -237.481635) (xy 192.337436 -237.471458)
			(xy 189.740032 -237.471458) (xy 189.739601 -237.481631) (xy 189.731824 -237.50043) (xy 189.71744 -237.514818)
			(xy 189.698643 -237.522599) (xy 189.68847 -237.52302) (xy 188.28893 -237.52302) (xy 188.278755 -237.52261)
			(xy 188.259953 -237.514828) (xy 188.245566 -237.500437) (xy 188.237787 -237.481633) (xy 188.237368 -237.471458)
			(xy 186.2963 -237.471458) (xy 186.295803 -237.481622) (xy 186.288039 -237.500409) (xy 186.273676 -237.514794)
			(xy 186.254902 -237.522587) (xy 186.244738 -237.52302) (xy 184.845198 -237.52302) (xy 184.835021 -237.522637)
			(xy 184.816218 -237.514843) (xy 184.801832 -237.500445) (xy 184.794055 -237.481635) (xy 184.793636 -237.471458)
			(xy 182.196232 -237.471458) (xy 182.195801 -237.481631) (xy 182.188024 -237.50043) (xy 182.17364 -237.514818)
			(xy 182.154843 -237.522599) (xy 182.14467 -237.52302) (xy 180.74513 -237.52302) (xy 180.734955 -237.52261)
			(xy 180.716153 -237.514828) (xy 180.701766 -237.500437) (xy 180.693987 -237.481633) (xy 180.693568 -237.471458)
			(xy 178.7525 -237.471458) (xy 178.752003 -237.481622) (xy 178.744239 -237.500409) (xy 178.729876 -237.514794)
			(xy 178.711102 -237.522587) (xy 178.700938 -237.52302) (xy 177.301398 -237.52302) (xy 177.291221 -237.522637)
			(xy 177.272418 -237.514843) (xy 177.258032 -237.500445) (xy 177.250255 -237.481635) (xy 177.249836 -237.471458)
			(xy 174.652432 -237.471458) (xy 174.652001 -237.481631) (xy 174.644224 -237.50043) (xy 174.62984 -237.514818)
			(xy 174.611043 -237.522599) (xy 174.60087 -237.52302) (xy 173.20133 -237.52302) (xy 173.191155 -237.52261)
			(xy 173.172353 -237.514828) (xy 173.157966 -237.500437) (xy 173.150187 -237.481633) (xy 173.149768 -237.471458)
			(xy 171.2087 -237.471458) (xy 171.208203 -237.481622) (xy 171.200439 -237.500409) (xy 171.186076 -237.514794)
			(xy 171.167302 -237.522587) (xy 171.157138 -237.52302) (xy 169.757598 -237.52302) (xy 169.747421 -237.522637)
			(xy 169.728618 -237.514843) (xy 169.714232 -237.500445) (xy 169.706455 -237.481635) (xy 169.706036 -237.471458)
			(xy 167.108632 -237.471458) (xy 167.108201 -237.481631) (xy 167.100424 -237.50043) (xy 167.08604 -237.514818)
			(xy 167.067243 -237.522599) (xy 167.05707 -237.52302) (xy 165.65753 -237.52302) (xy 165.647355 -237.52261)
			(xy 165.628553 -237.514828) (xy 165.614166 -237.500437) (xy 165.606387 -237.481633) (xy 165.605968 -237.471458)
			(xy 163.6649 -237.471458) (xy 163.664403 -237.481622) (xy 163.656639 -237.500409) (xy 163.642276 -237.514794)
			(xy 163.623502 -237.522587) (xy 163.613338 -237.52302) (xy 162.213798 -237.52302) (xy 162.203621 -237.522637)
			(xy 162.184818 -237.514843) (xy 162.170432 -237.500445) (xy 162.162655 -237.481635) (xy 162.162236 -237.471458)
			(xy 159.564832 -237.471458) (xy 159.564401 -237.481631) (xy 159.556624 -237.50043) (xy 159.54224 -237.514818)
			(xy 159.523443 -237.522599) (xy 159.51327 -237.52302) (xy 158.11373 -237.52302) (xy 158.103555 -237.52261)
			(xy 158.084753 -237.514828) (xy 158.070366 -237.500437) (xy 158.062587 -237.481633) (xy 158.062168 -237.471458)
			(xy 65.7987 -237.471458) (xy 65.798203 -237.481622) (xy 65.790439 -237.500409) (xy 65.776076 -237.514794)
			(xy 65.757302 -237.522587) (xy 65.747138 -237.52302) (xy 64.347598 -237.52302) (xy 64.337421 -237.522637)
			(xy 64.318618 -237.514843) (xy 64.304232 -237.500445) (xy 64.296455 -237.481635) (xy 64.296036 -237.471458)
			(xy 61.698632 -237.471458) (xy 61.698201 -237.481631) (xy 61.690424 -237.50043) (xy 61.67604 -237.514818)
			(xy 61.657243 -237.522599) (xy 61.64707 -237.52302) (xy 60.24753 -237.52302) (xy 60.237355 -237.52261)
			(xy 60.218553 -237.514828) (xy 60.204166 -237.500437) (xy 60.196387 -237.481633) (xy 60.195968 -237.471458)
			(xy 58.2549 -237.471458) (xy 58.254403 -237.481622) (xy 58.246639 -237.500409) (xy 58.232276 -237.514794)
			(xy 58.213502 -237.522587) (xy 58.203338 -237.52302) (xy 56.803798 -237.52302) (xy 56.793621 -237.522637)
			(xy 56.774818 -237.514843) (xy 56.760432 -237.500445) (xy 56.752655 -237.481635) (xy 56.752236 -237.471458)
			(xy 54.154832 -237.471458) (xy 54.154401 -237.481631) (xy 54.146624 -237.50043) (xy 54.13224 -237.514818)
			(xy 54.113443 -237.522599) (xy 54.10327 -237.52302) (xy 52.70373 -237.52302) (xy 52.693555 -237.52261)
			(xy 52.674753 -237.514828) (xy 52.660366 -237.500437) (xy 52.652587 -237.481633) (xy 52.652168 -237.471458)
			(xy 50.7111 -237.471458) (xy 50.710603 -237.481622) (xy 50.702839 -237.500409) (xy 50.688476 -237.514794)
			(xy 50.669702 -237.522587) (xy 50.659538 -237.52302) (xy 49.259998 -237.52302) (xy 49.249821 -237.522637)
			(xy 49.231018 -237.514843) (xy 49.216632 -237.500445) (xy 49.208855 -237.481635) (xy 49.208436 -237.471458)
			(xy 46.611032 -237.471458) (xy 46.610601 -237.481631) (xy 46.602824 -237.50043) (xy 46.58844 -237.514818)
			(xy 46.569643 -237.522599) (xy 46.55947 -237.52302) (xy 45.15993 -237.52302) (xy 45.149755 -237.52261)
			(xy 45.130953 -237.514828) (xy 45.116566 -237.500437) (xy 45.108787 -237.481633) (xy 45.108368 -237.471458)
			(xy 43.1673 -237.471458) (xy 43.166803 -237.481622) (xy 43.159039 -237.500409) (xy 43.144676 -237.514794)
			(xy 43.125902 -237.522587) (xy 43.115738 -237.52302) (xy 41.716198 -237.52302) (xy 41.706021 -237.522637)
			(xy 41.687218 -237.514843) (xy 41.672832 -237.500445) (xy 41.665055 -237.481635) (xy 41.664636 -237.471458)
			(xy 39.067232 -237.471458) (xy 39.066801 -237.481631) (xy 39.059024 -237.50043) (xy 39.04464 -237.514818)
			(xy 39.025843 -237.522599) (xy 39.01567 -237.52302) (xy 37.61613 -237.52302) (xy 37.605955 -237.52261)
			(xy 37.587153 -237.514828) (xy 37.572766 -237.500437) (xy 37.564987 -237.481633) (xy 37.564568 -237.471458)
			(xy 35.6235 -237.471458) (xy 35.623003 -237.481622) (xy 35.615239 -237.500409) (xy 35.600876 -237.514794)
			(xy 35.582102 -237.522587) (xy 35.571938 -237.52302) (xy 34.172398 -237.52302) (xy 34.162221 -237.522637)
			(xy 34.143418 -237.514843) (xy 34.129032 -237.500445) (xy 34.121255 -237.481635) (xy 34.120836 -237.471458)
			(xy 31.523432 -237.471458) (xy 31.523001 -237.481631) (xy 31.515224 -237.50043) (xy 31.50084 -237.514818)
			(xy 31.482043 -237.522599) (xy 31.47187 -237.52302) (xy 30.07233 -237.52302) (xy 30.062155 -237.52261)
			(xy 30.043353 -237.514828) (xy 30.028966 -237.500437) (xy 30.021187 -237.481633) (xy 30.020768 -237.471458)
			(xy 28.0797 -237.471458) (xy 28.079203 -237.481622) (xy 28.071439 -237.500409) (xy 28.057076 -237.514794)
			(xy 28.038302 -237.522587) (xy 28.028138 -237.52302) (xy 26.628598 -237.52302) (xy 26.618421 -237.522637)
			(xy 26.599618 -237.514843) (xy 26.585232 -237.500445) (xy 26.577455 -237.481635) (xy 26.577036 -237.471458)
			(xy 23.979632 -237.471458) (xy 23.979201 -237.481631) (xy 23.971424 -237.50043) (xy 23.95704 -237.514818)
			(xy 23.938243 -237.522599) (xy 23.92807 -237.52302) (xy 22.52853 -237.52302) (xy 22.518355 -237.52261)
			(xy 22.499553 -237.514828) (xy 22.485166 -237.500437) (xy 22.477387 -237.481633) (xy 22.476968 -237.471458)
			(xy 20.5359 -237.471458) (xy 20.535403 -237.481622) (xy 20.527639 -237.500409) (xy 20.513276 -237.514794)
			(xy 20.494502 -237.522587) (xy 20.484338 -237.52302) (xy 19.084798 -237.52302) (xy 19.074621 -237.522637)
			(xy 19.055818 -237.514843) (xy 19.041432 -237.500445) (xy 19.033655 -237.481635) (xy 19.033236 -237.471458)
			(xy 16.435832 -237.471458) (xy 16.435401 -237.481631) (xy 16.427624 -237.50043) (xy 16.41324 -237.514818)
			(xy 16.394443 -237.522599) (xy 16.38427 -237.52302) (xy 14.98473 -237.52302) (xy 14.974555 -237.52261)
			(xy 14.955753 -237.514828) (xy 14.941366 -237.500437) (xy 14.933587 -237.481633) (xy 14.933168 -237.471458)
			(xy 12.9921 -237.471458) (xy 12.991603 -237.481622) (xy 12.983839 -237.500409) (xy 12.969476 -237.514794)
			(xy 12.950702 -237.522587) (xy 12.940538 -237.52302) (xy 11.540998 -237.52302) (xy 11.530821 -237.522637)
			(xy 11.512018 -237.514843) (xy 11.497632 -237.500445) (xy 11.489855 -237.481635) (xy 11.489436 -237.471458)
			(xy 8.892032 -237.471458) (xy 8.891601 -237.481631) (xy 8.883824 -237.50043) (xy 8.86944 -237.514818)
			(xy 8.850643 -237.522599) (xy 8.84047 -237.52302) (xy 7.44093 -237.52302) (xy 7.430755 -237.52261)
			(xy 7.411953 -237.514828) (xy 7.397566 -237.500437) (xy 7.389787 -237.481633) (xy 7.389368 -237.471458)
			(xy 2.509012 -237.471458) (xy 2.509012 -238.321342) (xy 7.389368 -238.321342) (xy 7.389368 -237.912402)
			(xy 7.389766 -237.902227) (xy 7.397556 -237.883426) (xy 7.41195 -237.86904) (xy 7.430755 -237.861261)
			(xy 7.44093 -237.86084) (xy 8.84047 -237.86084) (xy 8.85064 -237.861289) (xy 8.869434 -237.869064)
			(xy 8.88382 -237.883442) (xy 8.891606 -237.902232) (xy 8.892032 -237.912402) (xy 8.892032 -238.321342)
			(xy 14.933168 -238.321342) (xy 14.933168 -237.912402) (xy 14.933566 -237.902227) (xy 14.941356 -237.883426)
			(xy 14.95575 -237.86904) (xy 14.974555 -237.861261) (xy 14.98473 -237.86084) (xy 16.38427 -237.86084)
			(xy 16.39444 -237.861289) (xy 16.413234 -237.869064) (xy 16.42762 -237.883442) (xy 16.435406 -237.902232)
			(xy 16.435832 -237.912402) (xy 16.435832 -238.321342) (xy 22.476968 -238.321342) (xy 22.476968 -237.912402)
			(xy 22.477366 -237.902227) (xy 22.485156 -237.883426) (xy 22.49955 -237.86904) (xy 22.518355 -237.861261)
			(xy 22.52853 -237.86084) (xy 23.92807 -237.86084) (xy 23.93824 -237.861289) (xy 23.957034 -237.869064)
			(xy 23.97142 -237.883442) (xy 23.979206 -237.902232) (xy 23.979632 -237.912402) (xy 23.979632 -238.321342)
			(xy 30.020768 -238.321342) (xy 30.020768 -237.912402) (xy 30.021166 -237.902227) (xy 30.028956 -237.883426)
			(xy 30.04335 -237.86904) (xy 30.062155 -237.861261) (xy 30.07233 -237.86084) (xy 31.47187 -237.86084)
			(xy 31.48204 -237.861289) (xy 31.500834 -237.869064) (xy 31.51522 -237.883442) (xy 31.523006 -237.902232)
			(xy 31.523432 -237.912402) (xy 31.523432 -238.321342) (xy 37.564568 -238.321342) (xy 37.564568 -237.912402)
			(xy 37.564966 -237.902227) (xy 37.572756 -237.883426) (xy 37.58715 -237.86904) (xy 37.605955 -237.861261)
			(xy 37.61613 -237.86084) (xy 39.01567 -237.86084) (xy 39.02584 -237.861289) (xy 39.044634 -237.869064)
			(xy 39.05902 -237.883442) (xy 39.066806 -237.902232) (xy 39.067232 -237.912402) (xy 39.067232 -238.321342)
			(xy 45.108368 -238.321342) (xy 45.108368 -237.912402) (xy 45.108766 -237.902227) (xy 45.116556 -237.883426)
			(xy 45.13095 -237.86904) (xy 45.149755 -237.861261) (xy 45.15993 -237.86084) (xy 46.55947 -237.86084)
			(xy 46.56964 -237.861289) (xy 46.588434 -237.869064) (xy 46.60282 -237.883442) (xy 46.610606 -237.902232)
			(xy 46.611032 -237.912402) (xy 46.611032 -238.321342) (xy 52.652168 -238.321342) (xy 52.652168 -237.912402)
			(xy 52.652566 -237.902227) (xy 52.660356 -237.883426) (xy 52.67475 -237.86904) (xy 52.693555 -237.861261)
			(xy 52.70373 -237.86084) (xy 54.10327 -237.86084) (xy 54.11344 -237.861289) (xy 54.132234 -237.869064)
			(xy 54.14662 -237.883442) (xy 54.154406 -237.902232) (xy 54.154832 -237.912402) (xy 54.154832 -238.321342)
			(xy 60.195968 -238.321342) (xy 60.195968 -237.912402) (xy 60.196366 -237.902227) (xy 60.204156 -237.883426)
			(xy 60.21855 -237.86904) (xy 60.237355 -237.861261) (xy 60.24753 -237.86084) (xy 61.64707 -237.86084)
			(xy 61.65724 -237.861289) (xy 61.676034 -237.869064) (xy 61.69042 -237.883442) (xy 61.698206 -237.902232)
			(xy 61.698632 -237.912402) (xy 61.698632 -238.321342) (xy 158.062168 -238.321342) (xy 158.062168 -237.912402)
			(xy 158.062566 -237.902227) (xy 158.070356 -237.883426) (xy 158.08475 -237.86904) (xy 158.103555 -237.861261)
			(xy 158.11373 -237.86084) (xy 159.51327 -237.86084) (xy 159.52344 -237.861289) (xy 159.542234 -237.869064)
			(xy 159.55662 -237.883442) (xy 159.564406 -237.902232) (xy 159.564832 -237.912402) (xy 159.564832 -238.321342)
			(xy 165.605968 -238.321342) (xy 165.605968 -237.912402) (xy 165.606366 -237.902227) (xy 165.614156 -237.883426)
			(xy 165.62855 -237.86904) (xy 165.647355 -237.861261) (xy 165.65753 -237.86084) (xy 167.05707 -237.86084)
			(xy 167.06724 -237.861289) (xy 167.086034 -237.869064) (xy 167.10042 -237.883442) (xy 167.108206 -237.902232)
			(xy 167.108632 -237.912402) (xy 167.108632 -238.321342) (xy 173.149768 -238.321342) (xy 173.149768 -237.912402)
			(xy 173.150166 -237.902227) (xy 173.157956 -237.883426) (xy 173.17235 -237.86904) (xy 173.191155 -237.861261)
			(xy 173.20133 -237.86084) (xy 174.60087 -237.86084) (xy 174.61104 -237.861289) (xy 174.629834 -237.869064)
			(xy 174.64422 -237.883442) (xy 174.652006 -237.902232) (xy 174.652432 -237.912402) (xy 174.652432 -238.321342)
			(xy 180.693568 -238.321342) (xy 180.693568 -237.912402) (xy 180.693966 -237.902227) (xy 180.701756 -237.883426)
			(xy 180.71615 -237.86904) (xy 180.734955 -237.861261) (xy 180.74513 -237.86084) (xy 182.14467 -237.86084)
			(xy 182.15484 -237.861289) (xy 182.173634 -237.869064) (xy 182.18802 -237.883442) (xy 182.195806 -237.902232)
			(xy 182.196232 -237.912402) (xy 182.196232 -238.321342) (xy 188.237368 -238.321342) (xy 188.237368 -237.912402)
			(xy 188.237766 -237.902227) (xy 188.245556 -237.883426) (xy 188.25995 -237.86904) (xy 188.278755 -237.861261)
			(xy 188.28893 -237.86084) (xy 189.68847 -237.86084) (xy 189.69864 -237.861289) (xy 189.717434 -237.869064)
			(xy 189.73182 -237.883442) (xy 189.739606 -237.902232) (xy 189.740032 -237.912402) (xy 189.740032 -238.321342)
			(xy 195.781168 -238.321342) (xy 195.781168 -237.912402) (xy 195.781566 -237.902227) (xy 195.789356 -237.883426)
			(xy 195.80375 -237.86904) (xy 195.822555 -237.861261) (xy 195.83273 -237.86084) (xy 197.23227 -237.86084)
			(xy 197.24244 -237.861289) (xy 197.261234 -237.869064) (xy 197.27562 -237.883442) (xy 197.283406 -237.902232)
			(xy 197.283832 -237.912402) (xy 197.283832 -238.321342) (xy 203.324968 -238.321342) (xy 203.324968 -237.912402)
			(xy 203.325366 -237.902227) (xy 203.333156 -237.883426) (xy 203.34755 -237.86904) (xy 203.366355 -237.861261)
			(xy 203.37653 -237.86084) (xy 204.77607 -237.86084) (xy 204.78624 -237.861289) (xy 204.805034 -237.869064)
			(xy 204.81942 -237.883442) (xy 204.827206 -237.902232) (xy 204.827632 -237.912402) (xy 204.827632 -238.321342)
			(xy 210.868768 -238.321342) (xy 210.868768 -237.912402) (xy 210.869166 -237.902227) (xy 210.876956 -237.883426)
			(xy 210.89135 -237.86904) (xy 210.910155 -237.861261) (xy 210.92033 -237.86084) (xy 212.31987 -237.86084)
			(xy 212.33004 -237.861289) (xy 212.348834 -237.869064) (xy 212.36322 -237.883442) (xy 212.371006 -237.902232)
			(xy 212.371432 -237.912402) (xy 212.371432 -238.321342) (xy 255.329436 -238.321342) (xy 255.329436 -237.912402)
			(xy 255.329935 -237.902245) (xy 255.337708 -237.883476) (xy 255.352073 -237.869111) (xy 255.370841 -237.861336)
			(xy 255.380998 -237.86084) (xy 256.780538 -237.86084) (xy 256.790698 -237.861302) (xy 256.809469 -237.86909)
			(xy 256.823833 -237.883465) (xy 256.831606 -237.902241) (xy 256.8321 -237.912402) (xy 256.8321 -238.321342)
			(xy 262.873236 -238.321342) (xy 262.873236 -237.912402) (xy 262.873735 -237.902245) (xy 262.881508 -237.883476)
			(xy 262.895873 -237.869111) (xy 262.914641 -237.861336) (xy 262.924798 -237.86084) (xy 264.324338 -237.86084)
			(xy 264.334498 -237.861302) (xy 264.353269 -237.86909) (xy 264.367633 -237.883465) (xy 264.375406 -237.902241)
			(xy 264.3759 -237.912402) (xy 264.3759 -238.321342) (xy 270.417036 -238.321342) (xy 270.417036 -237.912402)
			(xy 270.417535 -237.902245) (xy 270.425308 -237.883476) (xy 270.439673 -237.869111) (xy 270.458441 -237.861336)
			(xy 270.468598 -237.86084) (xy 271.868138 -237.86084) (xy 271.878298 -237.861302) (xy 271.897069 -237.86909)
			(xy 271.911433 -237.883465) (xy 271.919206 -237.902241) (xy 271.9197 -237.912402) (xy 271.9197 -238.321342)
			(xy 277.960836 -238.321342) (xy 277.960836 -237.912402) (xy 277.961335 -237.902245) (xy 277.969108 -237.883476)
			(xy 277.983473 -237.869111) (xy 278.002241 -237.861336) (xy 278.012398 -237.86084) (xy 279.411938 -237.86084)
			(xy 279.422098 -237.861302) (xy 279.440869 -237.86909) (xy 279.455233 -237.883465) (xy 279.463006 -237.902241)
			(xy 279.4635 -237.912402) (xy 279.4635 -238.321342) (xy 285.504636 -238.321342) (xy 285.504636 -237.912402)
			(xy 285.505135 -237.902245) (xy 285.512908 -237.883476) (xy 285.527273 -237.869111) (xy 285.546041 -237.861336)
			(xy 285.556198 -237.86084) (xy 286.955738 -237.86084) (xy 286.965898 -237.861302) (xy 286.984669 -237.86909)
			(xy 286.999033 -237.883465) (xy 287.006806 -237.902241) (xy 287.0073 -237.912402) (xy 287.0073 -238.321342)
			(xy 293.048436 -238.321342) (xy 293.048436 -237.912402) (xy 293.048935 -237.902245) (xy 293.056708 -237.883476)
			(xy 293.071073 -237.869111) (xy 293.089841 -237.861336) (xy 293.099998 -237.86084) (xy 294.499538 -237.86084)
			(xy 294.509698 -237.861302) (xy 294.528469 -237.86909) (xy 294.542833 -237.883465) (xy 294.550606 -237.902241)
			(xy 294.5511 -237.912402) (xy 294.5511 -238.321342) (xy 300.592236 -238.321342) (xy 300.592236 -237.912402)
			(xy 300.592735 -237.902245) (xy 300.600508 -237.883476) (xy 300.614873 -237.869111) (xy 300.633641 -237.861336)
			(xy 300.643798 -237.86084) (xy 302.043338 -237.86084) (xy 302.053498 -237.861302) (xy 302.072269 -237.86909)
			(xy 302.086633 -237.883465) (xy 302.094406 -237.902241) (xy 302.0949 -237.912402) (xy 302.0949 -238.321342)
			(xy 308.136036 -238.321342) (xy 308.136036 -237.912402) (xy 308.136535 -237.902245) (xy 308.144308 -237.883476)
			(xy 308.158673 -237.869111) (xy 308.177441 -237.861336) (xy 308.187598 -237.86084) (xy 309.587138 -237.86084)
			(xy 309.597298 -237.861302) (xy 309.616069 -237.86909) (xy 309.630433 -237.883465) (xy 309.638206 -237.902241)
			(xy 309.6387 -237.912402) (xy 309.6387 -238.321342) (xy 406.002236 -238.321342) (xy 406.002236 -237.912402)
			(xy 406.002735 -237.902245) (xy 406.010508 -237.883476) (xy 406.024873 -237.869111) (xy 406.043641 -237.861336)
			(xy 406.053798 -237.86084) (xy 407.453338 -237.86084) (xy 407.463498 -237.861302) (xy 407.482269 -237.86909)
			(xy 407.496633 -237.883465) (xy 407.504406 -237.902241) (xy 407.5049 -237.912402) (xy 407.5049 -238.321342)
			(xy 413.546036 -238.321342) (xy 413.546036 -237.912402) (xy 413.546535 -237.902245) (xy 413.554308 -237.883476)
			(xy 413.568673 -237.869111) (xy 413.587441 -237.861336) (xy 413.597598 -237.86084) (xy 414.997138 -237.86084)
			(xy 415.007298 -237.861302) (xy 415.026069 -237.86909) (xy 415.040433 -237.883465) (xy 415.048206 -237.902241)
			(xy 415.0487 -237.912402) (xy 415.0487 -238.321342) (xy 421.089836 -238.321342) (xy 421.089836 -237.912402)
			(xy 421.090335 -237.902245) (xy 421.098108 -237.883476) (xy 421.112473 -237.869111) (xy 421.131241 -237.861336)
			(xy 421.141398 -237.86084) (xy 422.540938 -237.86084) (xy 422.551098 -237.861302) (xy 422.569869 -237.86909)
			(xy 422.584233 -237.883465) (xy 422.592006 -237.902241) (xy 422.5925 -237.912402) (xy 422.5925 -238.321342)
			(xy 428.633636 -238.321342) (xy 428.633636 -237.912402) (xy 428.634135 -237.902245) (xy 428.641908 -237.883476)
			(xy 428.656273 -237.869111) (xy 428.675041 -237.861336) (xy 428.685198 -237.86084) (xy 430.084738 -237.86084)
			(xy 430.094898 -237.861302) (xy 430.113669 -237.86909) (xy 430.128033 -237.883465) (xy 430.135806 -237.902241)
			(xy 430.1363 -237.912402) (xy 430.1363 -238.321342) (xy 436.177436 -238.321342) (xy 436.177436 -237.912402)
			(xy 436.177935 -237.902245) (xy 436.185708 -237.883476) (xy 436.200073 -237.869111) (xy 436.218841 -237.861336)
			(xy 436.228998 -237.86084) (xy 437.628538 -237.86084) (xy 437.638698 -237.861302) (xy 437.657469 -237.86909)
			(xy 437.671833 -237.883465) (xy 437.679606 -237.902241) (xy 437.6801 -237.912402) (xy 437.6801 -238.321342)
			(xy 443.721236 -238.321342) (xy 443.721236 -237.912402) (xy 443.721735 -237.902245) (xy 443.729508 -237.883476)
			(xy 443.743873 -237.869111) (xy 443.762641 -237.861336) (xy 443.772798 -237.86084) (xy 445.172338 -237.86084)
			(xy 445.182498 -237.861302) (xy 445.201269 -237.86909) (xy 445.215633 -237.883465) (xy 445.223406 -237.902241)
			(xy 445.2239 -237.912402) (xy 445.2239 -238.321342) (xy 451.265036 -238.321342) (xy 451.265036 -237.912402)
			(xy 451.265535 -237.902245) (xy 451.273308 -237.883476) (xy 451.287673 -237.869111) (xy 451.306441 -237.861336)
			(xy 451.316598 -237.86084) (xy 452.716138 -237.86084) (xy 452.726298 -237.861302) (xy 452.745069 -237.86909)
			(xy 452.759433 -237.883465) (xy 452.767206 -237.902241) (xy 452.7677 -237.912402) (xy 452.7677 -238.321342)
			(xy 458.808836 -238.321342) (xy 458.808836 -237.912402) (xy 458.809335 -237.902245) (xy 458.817108 -237.883476)
			(xy 458.831473 -237.869111) (xy 458.850241 -237.861336) (xy 458.860398 -237.86084) (xy 460.259938 -237.86084)
			(xy 460.270098 -237.861302) (xy 460.288869 -237.86909) (xy 460.303233 -237.883465) (xy 460.311006 -237.902241)
			(xy 460.3115 -237.912402) (xy 460.3115 -238.321342) (xy 460.311002 -238.331498) (xy 460.303221 -238.350261)
			(xy 460.288857 -238.364623) (xy 460.270094 -238.372403) (xy 460.259938 -238.372904) (xy 458.860398 -238.372904)
			(xy 458.850245 -238.372369) (xy 458.831484 -238.364602) (xy 458.817121 -238.350249) (xy 458.809339 -238.331494)
			(xy 458.808836 -238.321342) (xy 452.7677 -238.321342) (xy 452.767202 -238.331498) (xy 452.759421 -238.350261)
			(xy 452.745057 -238.364623) (xy 452.726294 -238.372403) (xy 452.716138 -238.372904) (xy 451.316598 -238.372904)
			(xy 451.306445 -238.372369) (xy 451.287684 -238.364602) (xy 451.273321 -238.350249) (xy 451.265539 -238.331494)
			(xy 451.265036 -238.321342) (xy 445.2239 -238.321342) (xy 445.223402 -238.331498) (xy 445.215621 -238.350261)
			(xy 445.201257 -238.364623) (xy 445.182494 -238.372403) (xy 445.172338 -238.372904) (xy 443.772798 -238.372904)
			(xy 443.762645 -238.372369) (xy 443.743884 -238.364602) (xy 443.729521 -238.350249) (xy 443.721739 -238.331494)
			(xy 443.721236 -238.321342) (xy 437.6801 -238.321342) (xy 437.679602 -238.331498) (xy 437.671821 -238.350261)
			(xy 437.657457 -238.364623) (xy 437.638694 -238.372403) (xy 437.628538 -238.372904) (xy 436.228998 -238.372904)
			(xy 436.218845 -238.372369) (xy 436.200084 -238.364602) (xy 436.185721 -238.350249) (xy 436.177939 -238.331494)
			(xy 436.177436 -238.321342) (xy 430.1363 -238.321342) (xy 430.135802 -238.331498) (xy 430.128021 -238.350261)
			(xy 430.113657 -238.364623) (xy 430.094894 -238.372403) (xy 430.084738 -238.372904) (xy 428.685198 -238.372904)
			(xy 428.675045 -238.372369) (xy 428.656284 -238.364602) (xy 428.641921 -238.350249) (xy 428.634139 -238.331494)
			(xy 428.633636 -238.321342) (xy 422.5925 -238.321342) (xy 422.592002 -238.331498) (xy 422.584221 -238.350261)
			(xy 422.569857 -238.364623) (xy 422.551094 -238.372403) (xy 422.540938 -238.372904) (xy 421.141398 -238.372904)
			(xy 421.131245 -238.372369) (xy 421.112484 -238.364602) (xy 421.098121 -238.350249) (xy 421.090339 -238.331494)
			(xy 421.089836 -238.321342) (xy 415.0487 -238.321342) (xy 415.048202 -238.331498) (xy 415.040421 -238.350261)
			(xy 415.026057 -238.364623) (xy 415.007294 -238.372403) (xy 414.997138 -238.372904) (xy 413.597598 -238.372904)
			(xy 413.587445 -238.372369) (xy 413.568684 -238.364602) (xy 413.554321 -238.350249) (xy 413.546539 -238.331494)
			(xy 413.546036 -238.321342) (xy 407.5049 -238.321342) (xy 407.504402 -238.331498) (xy 407.496621 -238.350261)
			(xy 407.482257 -238.364623) (xy 407.463494 -238.372403) (xy 407.453338 -238.372904) (xy 406.053798 -238.372904)
			(xy 406.043645 -238.372369) (xy 406.024884 -238.364602) (xy 406.010521 -238.350249) (xy 406.002739 -238.331494)
			(xy 406.002236 -238.321342) (xy 309.6387 -238.321342) (xy 309.638202 -238.331498) (xy 309.630421 -238.350261)
			(xy 309.616057 -238.364623) (xy 309.597294 -238.372403) (xy 309.587138 -238.372904) (xy 308.187598 -238.372904)
			(xy 308.177445 -238.372369) (xy 308.158684 -238.364602) (xy 308.144321 -238.350249) (xy 308.136539 -238.331494)
			(xy 308.136036 -238.321342) (xy 302.0949 -238.321342) (xy 302.094402 -238.331498) (xy 302.086621 -238.350261)
			(xy 302.072257 -238.364623) (xy 302.053494 -238.372403) (xy 302.043338 -238.372904) (xy 300.643798 -238.372904)
			(xy 300.633645 -238.372369) (xy 300.614884 -238.364602) (xy 300.600521 -238.350249) (xy 300.592739 -238.331494)
			(xy 300.592236 -238.321342) (xy 294.5511 -238.321342) (xy 294.550602 -238.331498) (xy 294.542821 -238.350261)
			(xy 294.528457 -238.364623) (xy 294.509694 -238.372403) (xy 294.499538 -238.372904) (xy 293.099998 -238.372904)
			(xy 293.089845 -238.372369) (xy 293.071084 -238.364602) (xy 293.056721 -238.350249) (xy 293.048939 -238.331494)
			(xy 293.048436 -238.321342) (xy 287.0073 -238.321342) (xy 287.006802 -238.331498) (xy 286.999021 -238.350261)
			(xy 286.984657 -238.364623) (xy 286.965894 -238.372403) (xy 286.955738 -238.372904) (xy 285.556198 -238.372904)
			(xy 285.546045 -238.372369) (xy 285.527284 -238.364602) (xy 285.512921 -238.350249) (xy 285.505139 -238.331494)
			(xy 285.504636 -238.321342) (xy 279.4635 -238.321342) (xy 279.463002 -238.331498) (xy 279.455221 -238.350261)
			(xy 279.440857 -238.364623) (xy 279.422094 -238.372403) (xy 279.411938 -238.372904) (xy 278.012398 -238.372904)
			(xy 278.002245 -238.372369) (xy 277.983484 -238.364602) (xy 277.969121 -238.350249) (xy 277.961339 -238.331494)
			(xy 277.960836 -238.321342) (xy 271.9197 -238.321342) (xy 271.919202 -238.331498) (xy 271.911421 -238.350261)
			(xy 271.897057 -238.364623) (xy 271.878294 -238.372403) (xy 271.868138 -238.372904) (xy 270.468598 -238.372904)
			(xy 270.458445 -238.372369) (xy 270.439684 -238.364602) (xy 270.425321 -238.350249) (xy 270.417539 -238.331494)
			(xy 270.417036 -238.321342) (xy 264.3759 -238.321342) (xy 264.375402 -238.331498) (xy 264.367621 -238.350261)
			(xy 264.353257 -238.364623) (xy 264.334494 -238.372403) (xy 264.324338 -238.372904) (xy 262.924798 -238.372904)
			(xy 262.914645 -238.372369) (xy 262.895884 -238.364602) (xy 262.881521 -238.350249) (xy 262.873739 -238.331494)
			(xy 262.873236 -238.321342) (xy 256.8321 -238.321342) (xy 256.831602 -238.331498) (xy 256.823821 -238.350261)
			(xy 256.809457 -238.364623) (xy 256.790694 -238.372403) (xy 256.780538 -238.372904) (xy 255.380998 -238.372904)
			(xy 255.370845 -238.372369) (xy 255.352084 -238.364602) (xy 255.337721 -238.350249) (xy 255.329939 -238.331494)
			(xy 255.329436 -238.321342) (xy 212.371432 -238.321342) (xy 212.371 -238.331506) (xy 212.363206 -238.350282)
			(xy 212.348822 -238.364647) (xy 212.330035 -238.372414) (xy 212.31987 -238.372904) (xy 210.92033 -238.372904)
			(xy 210.910179 -238.372343) (xy 210.891419 -238.364587) (xy 210.877054 -238.350242) (xy 210.869271 -238.331492)
			(xy 210.868768 -238.321342) (xy 204.827632 -238.321342) (xy 204.8272 -238.331506) (xy 204.819406 -238.350282)
			(xy 204.805022 -238.364647) (xy 204.786235 -238.372414) (xy 204.77607 -238.372904) (xy 203.37653 -238.372904)
			(xy 203.366379 -238.372343) (xy 203.347619 -238.364587) (xy 203.333254 -238.350242) (xy 203.325471 -238.331492)
			(xy 203.324968 -238.321342) (xy 197.283832 -238.321342) (xy 197.2834 -238.331506) (xy 197.275606 -238.350282)
			(xy 197.261222 -238.364647) (xy 197.242435 -238.372414) (xy 197.23227 -238.372904) (xy 195.83273 -238.372904)
			(xy 195.822579 -238.372343) (xy 195.803819 -238.364587) (xy 195.789454 -238.350242) (xy 195.781671 -238.331492)
			(xy 195.781168 -238.321342) (xy 189.740032 -238.321342) (xy 189.7396 -238.331506) (xy 189.731806 -238.350282)
			(xy 189.717422 -238.364647) (xy 189.698635 -238.372414) (xy 189.68847 -238.372904) (xy 188.28893 -238.372904)
			(xy 188.278779 -238.372343) (xy 188.260019 -238.364587) (xy 188.245654 -238.350242) (xy 188.237871 -238.331492)
			(xy 188.237368 -238.321342) (xy 182.196232 -238.321342) (xy 182.1958 -238.331506) (xy 182.188006 -238.350282)
			(xy 182.173622 -238.364647) (xy 182.154835 -238.372414) (xy 182.14467 -238.372904) (xy 180.74513 -238.372904)
			(xy 180.734979 -238.372343) (xy 180.716219 -238.364587) (xy 180.701854 -238.350242) (xy 180.694071 -238.331492)
			(xy 180.693568 -238.321342) (xy 174.652432 -238.321342) (xy 174.652 -238.331506) (xy 174.644206 -238.350282)
			(xy 174.629822 -238.364647) (xy 174.611035 -238.372414) (xy 174.60087 -238.372904) (xy 173.20133 -238.372904)
			(xy 173.191179 -238.372343) (xy 173.172419 -238.364587) (xy 173.158054 -238.350242) (xy 173.150271 -238.331492)
			(xy 173.149768 -238.321342) (xy 167.108632 -238.321342) (xy 167.1082 -238.331506) (xy 167.100406 -238.350282)
			(xy 167.086022 -238.364647) (xy 167.067235 -238.372414) (xy 167.05707 -238.372904) (xy 165.65753 -238.372904)
			(xy 165.647379 -238.372343) (xy 165.628619 -238.364587) (xy 165.614254 -238.350242) (xy 165.606471 -238.331492)
			(xy 165.605968 -238.321342) (xy 159.564832 -238.321342) (xy 159.5644 -238.331506) (xy 159.556606 -238.350282)
			(xy 159.542222 -238.364647) (xy 159.523435 -238.372414) (xy 159.51327 -238.372904) (xy 158.11373 -238.372904)
			(xy 158.103579 -238.372343) (xy 158.084819 -238.364587) (xy 158.070454 -238.350242) (xy 158.062671 -238.331492)
			(xy 158.062168 -238.321342) (xy 61.698632 -238.321342) (xy 61.6982 -238.331506) (xy 61.690406 -238.350282)
			(xy 61.676022 -238.364647) (xy 61.657235 -238.372414) (xy 61.64707 -238.372904) (xy 60.24753 -238.372904)
			(xy 60.237379 -238.372343) (xy 60.218619 -238.364587) (xy 60.204254 -238.350242) (xy 60.196471 -238.331492)
			(xy 60.195968 -238.321342) (xy 54.154832 -238.321342) (xy 54.1544 -238.331506) (xy 54.146606 -238.350282)
			(xy 54.132222 -238.364647) (xy 54.113435 -238.372414) (xy 54.10327 -238.372904) (xy 52.70373 -238.372904)
			(xy 52.693579 -238.372343) (xy 52.674819 -238.364587) (xy 52.660454 -238.350242) (xy 52.652671 -238.331492)
			(xy 52.652168 -238.321342) (xy 46.611032 -238.321342) (xy 46.6106 -238.331506) (xy 46.602806 -238.350282)
			(xy 46.588422 -238.364647) (xy 46.569635 -238.372414) (xy 46.55947 -238.372904) (xy 45.15993 -238.372904)
			(xy 45.149779 -238.372343) (xy 45.131019 -238.364587) (xy 45.116654 -238.350242) (xy 45.108871 -238.331492)
			(xy 45.108368 -238.321342) (xy 39.067232 -238.321342) (xy 39.0668 -238.331506) (xy 39.059006 -238.350282)
			(xy 39.044622 -238.364647) (xy 39.025835 -238.372414) (xy 39.01567 -238.372904) (xy 37.61613 -238.372904)
			(xy 37.605979 -238.372343) (xy 37.587219 -238.364587) (xy 37.572854 -238.350242) (xy 37.565071 -238.331492)
			(xy 37.564568 -238.321342) (xy 31.523432 -238.321342) (xy 31.523 -238.331506) (xy 31.515206 -238.350282)
			(xy 31.500822 -238.364647) (xy 31.482035 -238.372414) (xy 31.47187 -238.372904) (xy 30.07233 -238.372904)
			(xy 30.062179 -238.372343) (xy 30.043419 -238.364587) (xy 30.029054 -238.350242) (xy 30.021271 -238.331492)
			(xy 30.020768 -238.321342) (xy 23.979632 -238.321342) (xy 23.9792 -238.331506) (xy 23.971406 -238.350282)
			(xy 23.957022 -238.364647) (xy 23.938235 -238.372414) (xy 23.92807 -238.372904) (xy 22.52853 -238.372904)
			(xy 22.518379 -238.372343) (xy 22.499619 -238.364587) (xy 22.485254 -238.350242) (xy 22.477471 -238.331492)
			(xy 22.476968 -238.321342) (xy 16.435832 -238.321342) (xy 16.4354 -238.331506) (xy 16.427606 -238.350282)
			(xy 16.413222 -238.364647) (xy 16.394435 -238.372414) (xy 16.38427 -238.372904) (xy 14.98473 -238.372904)
			(xy 14.974579 -238.372343) (xy 14.955819 -238.364587) (xy 14.941454 -238.350242) (xy 14.933671 -238.331492)
			(xy 14.933168 -238.321342) (xy 8.892032 -238.321342) (xy 8.8916 -238.331506) (xy 8.883806 -238.350282)
			(xy 8.869422 -238.364647) (xy 8.850635 -238.372414) (xy 8.84047 -238.372904) (xy 7.44093 -238.372904)
			(xy 7.430779 -238.372343) (xy 7.412019 -238.364587) (xy 7.397654 -238.350242) (xy 7.389871 -238.331492)
			(xy 7.389368 -238.321342) (xy 2.509012 -238.321342) (xy 2.509012 -239.17148) (xy 11.489436 -239.17148)
			(xy 11.489436 -238.76254) (xy 11.489855 -238.752384) (xy 11.497644 -238.733626) (xy 11.512043 -238.7193)
			(xy 11.53084 -238.711605) (xy 11.540998 -238.711232) (xy 12.940538 -238.711232) (xy 12.950666 -238.711695)
			(xy 12.969387 -238.719434) (xy 12.983741 -238.733727) (xy 12.991561 -238.752414) (xy 12.9921 -238.76254)
			(xy 12.9921 -239.17148) (xy 19.033236 -239.17148) (xy 19.033236 -238.76254) (xy 19.033655 -238.752384)
			(xy 19.041444 -238.733626) (xy 19.055843 -238.7193) (xy 19.07464 -238.711605) (xy 19.084798 -238.711232)
			(xy 20.484338 -238.711232) (xy 20.494466 -238.711695) (xy 20.513187 -238.719434) (xy 20.527541 -238.733727)
			(xy 20.535361 -238.752414) (xy 20.5359 -238.76254) (xy 20.5359 -239.17148) (xy 26.577036 -239.17148)
			(xy 26.577036 -238.76254) (xy 26.577455 -238.752384) (xy 26.585244 -238.733626) (xy 26.599643 -238.7193)
			(xy 26.61844 -238.711605) (xy 26.628598 -238.711232) (xy 28.028138 -238.711232) (xy 28.038266 -238.711695)
			(xy 28.056987 -238.719434) (xy 28.071341 -238.733727) (xy 28.079161 -238.752414) (xy 28.0797 -238.76254)
			(xy 28.0797 -239.17148) (xy 34.120836 -239.17148) (xy 34.120836 -238.76254) (xy 34.121255 -238.752384)
			(xy 34.129044 -238.733626) (xy 34.143443 -238.7193) (xy 34.16224 -238.711605) (xy 34.172398 -238.711232)
			(xy 35.571938 -238.711232) (xy 35.582066 -238.711695) (xy 35.600787 -238.719434) (xy 35.615141 -238.733727)
			(xy 35.622961 -238.752414) (xy 35.6235 -238.76254) (xy 35.6235 -239.17148) (xy 41.664636 -239.17148)
			(xy 41.664636 -238.76254) (xy 41.665055 -238.752384) (xy 41.672844 -238.733626) (xy 41.687243 -238.7193)
			(xy 41.70604 -238.711605) (xy 41.716198 -238.711232) (xy 43.115738 -238.711232) (xy 43.125866 -238.711695)
			(xy 43.144587 -238.719434) (xy 43.158941 -238.733727) (xy 43.166761 -238.752414) (xy 43.1673 -238.76254)
			(xy 43.1673 -239.17148) (xy 49.208436 -239.17148) (xy 49.208436 -238.76254) (xy 49.208855 -238.752384)
			(xy 49.216644 -238.733626) (xy 49.231043 -238.7193) (xy 49.24984 -238.711605) (xy 49.259998 -238.711232)
			(xy 50.659538 -238.711232) (xy 50.669666 -238.711695) (xy 50.688387 -238.719434) (xy 50.702741 -238.733727)
			(xy 50.710561 -238.752414) (xy 50.7111 -238.76254) (xy 50.7111 -239.17148) (xy 56.752236 -239.17148)
			(xy 56.752236 -238.76254) (xy 56.752655 -238.752384) (xy 56.760444 -238.733626) (xy 56.774843 -238.7193)
			(xy 56.79364 -238.711605) (xy 56.803798 -238.711232) (xy 58.203338 -238.711232) (xy 58.213466 -238.711695)
			(xy 58.232187 -238.719434) (xy 58.246541 -238.733727) (xy 58.254361 -238.752414) (xy 58.2549 -238.76254)
			(xy 58.2549 -239.17148) (xy 64.296036 -239.17148) (xy 64.296036 -238.76254) (xy 64.296455 -238.752384)
			(xy 64.304244 -238.733626) (xy 64.318643 -238.7193) (xy 64.33744 -238.711605) (xy 64.347598 -238.711232)
			(xy 65.747138 -238.711232) (xy 65.757266 -238.711695) (xy 65.775987 -238.719434) (xy 65.790341 -238.733727)
			(xy 65.798161 -238.752414) (xy 65.7987 -238.76254) (xy 65.7987 -239.17148) (xy 162.162236 -239.17148)
			(xy 162.162236 -238.76254) (xy 162.162655 -238.752384) (xy 162.170444 -238.733626) (xy 162.184843 -238.7193)
			(xy 162.20364 -238.711605) (xy 162.213798 -238.711232) (xy 163.613338 -238.711232) (xy 163.623466 -238.711695)
			(xy 163.642187 -238.719434) (xy 163.656541 -238.733727) (xy 163.664361 -238.752414) (xy 163.6649 -238.76254)
			(xy 163.6649 -239.17148) (xy 169.706036 -239.17148) (xy 169.706036 -238.76254) (xy 169.706455 -238.752384)
			(xy 169.714244 -238.733626) (xy 169.728643 -238.7193) (xy 169.74744 -238.711605) (xy 169.757598 -238.711232)
			(xy 171.157138 -238.711232) (xy 171.167266 -238.711695) (xy 171.185987 -238.719434) (xy 171.200341 -238.733727)
			(xy 171.208161 -238.752414) (xy 171.2087 -238.76254) (xy 171.2087 -239.17148) (xy 177.249836 -239.17148)
			(xy 177.249836 -238.76254) (xy 177.250255 -238.752384) (xy 177.258044 -238.733626) (xy 177.272443 -238.7193)
			(xy 177.29124 -238.711605) (xy 177.301398 -238.711232) (xy 178.700938 -238.711232) (xy 178.711066 -238.711695)
			(xy 178.729787 -238.719434) (xy 178.744141 -238.733727) (xy 178.751961 -238.752414) (xy 178.7525 -238.76254)
			(xy 178.7525 -239.17148) (xy 184.793636 -239.17148) (xy 184.793636 -238.76254) (xy 184.794055 -238.752384)
			(xy 184.801844 -238.733626) (xy 184.816243 -238.7193) (xy 184.83504 -238.711605) (xy 184.845198 -238.711232)
			(xy 186.244738 -238.711232) (xy 186.254866 -238.711695) (xy 186.273587 -238.719434) (xy 186.287941 -238.733727)
			(xy 186.295761 -238.752414) (xy 186.2963 -238.76254) (xy 186.2963 -239.17148) (xy 192.337436 -239.17148)
			(xy 192.337436 -238.76254) (xy 192.337855 -238.752384) (xy 192.345644 -238.733626) (xy 192.360043 -238.7193)
			(xy 192.37884 -238.711605) (xy 192.388998 -238.711232) (xy 193.788538 -238.711232) (xy 193.798666 -238.711695)
			(xy 193.817387 -238.719434) (xy 193.831741 -238.733727) (xy 193.839561 -238.752414) (xy 193.8401 -238.76254)
			(xy 193.8401 -239.17148) (xy 199.881236 -239.17148) (xy 199.881236 -238.76254) (xy 199.881655 -238.752384)
			(xy 199.889444 -238.733626) (xy 199.903843 -238.7193) (xy 199.92264 -238.711605) (xy 199.932798 -238.711232)
			(xy 201.332338 -238.711232) (xy 201.342466 -238.711695) (xy 201.361187 -238.719434) (xy 201.375541 -238.733727)
			(xy 201.383361 -238.752414) (xy 201.3839 -238.76254) (xy 201.3839 -239.17148) (xy 207.425036 -239.17148)
			(xy 207.425036 -238.76254) (xy 207.425455 -238.752384) (xy 207.433244 -238.733626) (xy 207.447643 -238.7193)
			(xy 207.46644 -238.711605) (xy 207.476598 -238.711232) (xy 208.876138 -238.711232) (xy 208.886266 -238.711695)
			(xy 208.904987 -238.719434) (xy 208.919341 -238.733727) (xy 208.927161 -238.752414) (xy 208.9277 -238.76254)
			(xy 208.9277 -239.17148) (xy 214.968836 -239.17148) (xy 214.968836 -238.76254) (xy 214.969255 -238.752384)
			(xy 214.977044 -238.733626) (xy 214.991443 -238.7193) (xy 215.01024 -238.711605) (xy 215.020398 -238.711232)
			(xy 216.419938 -238.711232) (xy 216.430066 -238.711695) (xy 216.448787 -238.719434) (xy 216.463141 -238.733727)
			(xy 216.470961 -238.752414) (xy 216.4715 -238.76254) (xy 216.4715 -239.17148) (xy 259.429504 -239.17148)
			(xy 259.429504 -238.76254) (xy 259.429955 -238.752388) (xy 259.437738 -238.733636) (xy 259.452126 -238.719311)
			(xy 259.470912 -238.71161) (xy 259.481066 -238.711232) (xy 260.880606 -238.711232) (xy 260.890732 -238.711722)
			(xy 260.909452 -238.71945) (xy 260.923808 -238.733735) (xy 260.931628 -238.752416) (xy 260.932168 -238.76254)
			(xy 260.932168 -239.17148) (xy 266.973304 -239.17148) (xy 266.973304 -238.76254) (xy 266.973755 -238.752388)
			(xy 266.981538 -238.733636) (xy 266.995926 -238.719311) (xy 267.014712 -238.71161) (xy 267.024866 -238.711232)
			(xy 268.424406 -238.711232) (xy 268.434532 -238.711722) (xy 268.453252 -238.71945) (xy 268.467608 -238.733735)
			(xy 268.475428 -238.752416) (xy 268.475968 -238.76254) (xy 268.475968 -239.17148) (xy 274.517104 -239.17148)
			(xy 274.517104 -238.76254) (xy 274.517555 -238.752388) (xy 274.525338 -238.733636) (xy 274.539726 -238.719311)
			(xy 274.558512 -238.71161) (xy 274.568666 -238.711232) (xy 275.968206 -238.711232) (xy 275.978332 -238.711722)
			(xy 275.997052 -238.71945) (xy 276.011408 -238.733735) (xy 276.019228 -238.752416) (xy 276.019768 -238.76254)
			(xy 276.019768 -239.17148) (xy 282.060904 -239.17148) (xy 282.060904 -238.76254) (xy 282.061355 -238.752388)
			(xy 282.069138 -238.733636) (xy 282.083526 -238.719311) (xy 282.102312 -238.71161) (xy 282.112466 -238.711232)
			(xy 283.512006 -238.711232) (xy 283.522132 -238.711722) (xy 283.540852 -238.71945) (xy 283.555208 -238.733735)
			(xy 283.563028 -238.752416) (xy 283.563568 -238.76254) (xy 283.563568 -239.17148) (xy 289.604704 -239.17148)
			(xy 289.604704 -238.76254) (xy 289.605155 -238.752388) (xy 289.612938 -238.733636) (xy 289.627326 -238.719311)
			(xy 289.646112 -238.71161) (xy 289.656266 -238.711232) (xy 291.055806 -238.711232) (xy 291.065932 -238.711722)
			(xy 291.084652 -238.71945) (xy 291.099008 -238.733735) (xy 291.106828 -238.752416) (xy 291.107368 -238.76254)
			(xy 291.107368 -239.17148) (xy 297.148504 -239.17148) (xy 297.148504 -238.76254) (xy 297.148955 -238.752388)
			(xy 297.156738 -238.733636) (xy 297.171126 -238.719311) (xy 297.189912 -238.71161) (xy 297.200066 -238.711232)
			(xy 298.599606 -238.711232) (xy 298.609732 -238.711722) (xy 298.628452 -238.71945) (xy 298.642808 -238.733735)
			(xy 298.650628 -238.752416) (xy 298.651168 -238.76254) (xy 298.651168 -239.17148) (xy 304.692304 -239.17148)
			(xy 304.692304 -238.76254) (xy 304.692755 -238.752388) (xy 304.700538 -238.733636) (xy 304.714926 -238.719311)
			(xy 304.733712 -238.71161) (xy 304.743866 -238.711232) (xy 306.143406 -238.711232) (xy 306.153532 -238.711722)
			(xy 306.172252 -238.71945) (xy 306.186608 -238.733735) (xy 306.194428 -238.752416) (xy 306.194968 -238.76254)
			(xy 306.194968 -239.17148) (xy 312.236104 -239.17148) (xy 312.236104 -238.76254) (xy 312.236555 -238.752388)
			(xy 312.244338 -238.733636) (xy 312.258726 -238.719311) (xy 312.277512 -238.71161) (xy 312.287666 -238.711232)
			(xy 313.687206 -238.711232) (xy 313.697332 -238.711722) (xy 313.716052 -238.71945) (xy 313.730408 -238.733735)
			(xy 313.738228 -238.752416) (xy 313.738768 -238.76254) (xy 313.738768 -239.17148) (xy 410.102304 -239.17148)
			(xy 410.102304 -238.76254) (xy 410.102755 -238.752388) (xy 410.110538 -238.733636) (xy 410.124926 -238.719311)
			(xy 410.143712 -238.71161) (xy 410.153866 -238.711232) (xy 411.553406 -238.711232) (xy 411.563532 -238.711722)
			(xy 411.582252 -238.71945) (xy 411.596608 -238.733735) (xy 411.604428 -238.752416) (xy 411.604968 -238.76254)
			(xy 411.604968 -239.17148) (xy 417.646104 -239.17148) (xy 417.646104 -238.76254) (xy 417.646555 -238.752388)
			(xy 417.654338 -238.733636) (xy 417.668726 -238.719311) (xy 417.687512 -238.71161) (xy 417.697666 -238.711232)
			(xy 419.097206 -238.711232) (xy 419.107332 -238.711722) (xy 419.126052 -238.71945) (xy 419.140408 -238.733735)
			(xy 419.148228 -238.752416) (xy 419.148768 -238.76254) (xy 419.148768 -239.17148) (xy 425.189904 -239.17148)
			(xy 425.189904 -238.76254) (xy 425.190355 -238.752388) (xy 425.198138 -238.733636) (xy 425.212526 -238.719311)
			(xy 425.231312 -238.71161) (xy 425.241466 -238.711232) (xy 426.641006 -238.711232) (xy 426.651132 -238.711722)
			(xy 426.669852 -238.71945) (xy 426.684208 -238.733735) (xy 426.692028 -238.752416) (xy 426.692568 -238.76254)
			(xy 426.692568 -239.17148) (xy 432.733704 -239.17148) (xy 432.733704 -238.76254) (xy 432.734155 -238.752388)
			(xy 432.741938 -238.733636) (xy 432.756326 -238.719311) (xy 432.775112 -238.71161) (xy 432.785266 -238.711232)
			(xy 434.184806 -238.711232) (xy 434.194932 -238.711722) (xy 434.213652 -238.71945) (xy 434.228008 -238.733735)
			(xy 434.235828 -238.752416) (xy 434.236368 -238.76254) (xy 434.236368 -239.17148) (xy 440.277504 -239.17148)
			(xy 440.277504 -238.76254) (xy 440.277955 -238.752388) (xy 440.285738 -238.733636) (xy 440.300126 -238.719311)
			(xy 440.318912 -238.71161) (xy 440.329066 -238.711232) (xy 441.728606 -238.711232) (xy 441.738732 -238.711722)
			(xy 441.757452 -238.71945) (xy 441.771808 -238.733735) (xy 441.779628 -238.752416) (xy 441.780168 -238.76254)
			(xy 441.780168 -239.17148) (xy 447.821304 -239.17148) (xy 447.821304 -238.76254) (xy 447.821755 -238.752388)
			(xy 447.829538 -238.733636) (xy 447.843926 -238.719311) (xy 447.862712 -238.71161) (xy 447.872866 -238.711232)
			(xy 449.272406 -238.711232) (xy 449.282532 -238.711722) (xy 449.301252 -238.71945) (xy 449.315608 -238.733735)
			(xy 449.323428 -238.752416) (xy 449.323968 -238.76254) (xy 449.323968 -239.17148) (xy 455.365104 -239.17148)
			(xy 455.365104 -238.76254) (xy 455.365555 -238.752388) (xy 455.373338 -238.733636) (xy 455.387726 -238.719311)
			(xy 455.406512 -238.71161) (xy 455.416666 -238.711232) (xy 456.816206 -238.711232) (xy 456.826332 -238.711722)
			(xy 456.845052 -238.71945) (xy 456.859408 -238.733735) (xy 456.867228 -238.752416) (xy 456.867768 -238.76254)
			(xy 456.867768 -239.17148) (xy 462.908904 -239.17148) (xy 462.908904 -238.76254) (xy 462.909355 -238.752388)
			(xy 462.917138 -238.733636) (xy 462.931526 -238.719311) (xy 462.950312 -238.71161) (xy 462.960466 -238.711232)
			(xy 464.360006 -238.711232) (xy 464.370132 -238.711722) (xy 464.388852 -238.71945) (xy 464.403208 -238.733735)
			(xy 464.411028 -238.752416) (xy 464.411568 -238.76254) (xy 464.411568 -239.17148) (xy 464.411162 -239.181637)
			(xy 464.403367 -239.200395) (xy 464.388965 -239.21472) (xy 464.370165 -239.222415) (xy 464.360006 -239.222788)
			(xy 462.960466 -239.222788) (xy 462.950341 -239.222302) (xy 462.931624 -239.214568) (xy 462.91727 -239.200283)
			(xy 462.909447 -239.181603) (xy 462.908904 -239.17148) (xy 456.867768 -239.17148) (xy 456.867362 -239.181637)
			(xy 456.859567 -239.200395) (xy 456.845165 -239.21472) (xy 456.826365 -239.222415) (xy 456.816206 -239.222788)
			(xy 455.416666 -239.222788) (xy 455.406541 -239.222302) (xy 455.387824 -239.214568) (xy 455.37347 -239.200283)
			(xy 455.365647 -239.181603) (xy 455.365104 -239.17148) (xy 449.323968 -239.17148) (xy 449.323562 -239.181637)
			(xy 449.315767 -239.200395) (xy 449.301365 -239.21472) (xy 449.282565 -239.222415) (xy 449.272406 -239.222788)
			(xy 447.872866 -239.222788) (xy 447.862741 -239.222302) (xy 447.844024 -239.214568) (xy 447.82967 -239.200283)
			(xy 447.821847 -239.181603) (xy 447.821304 -239.17148) (xy 441.780168 -239.17148) (xy 441.779762 -239.181637)
			(xy 441.771967 -239.200395) (xy 441.757565 -239.21472) (xy 441.738765 -239.222415) (xy 441.728606 -239.222788)
			(xy 440.329066 -239.222788) (xy 440.318941 -239.222302) (xy 440.300224 -239.214568) (xy 440.28587 -239.200283)
			(xy 440.278047 -239.181603) (xy 440.277504 -239.17148) (xy 434.236368 -239.17148) (xy 434.235962 -239.181637)
			(xy 434.228167 -239.200395) (xy 434.213765 -239.21472) (xy 434.194965 -239.222415) (xy 434.184806 -239.222788)
			(xy 432.785266 -239.222788) (xy 432.775141 -239.222302) (xy 432.756424 -239.214568) (xy 432.74207 -239.200283)
			(xy 432.734247 -239.181603) (xy 432.733704 -239.17148) (xy 426.692568 -239.17148) (xy 426.692162 -239.181637)
			(xy 426.684367 -239.200395) (xy 426.669965 -239.21472) (xy 426.651165 -239.222415) (xy 426.641006 -239.222788)
			(xy 425.241466 -239.222788) (xy 425.231341 -239.222302) (xy 425.212624 -239.214568) (xy 425.19827 -239.200283)
			(xy 425.190447 -239.181603) (xy 425.189904 -239.17148) (xy 419.148768 -239.17148) (xy 419.148362 -239.181637)
			(xy 419.140567 -239.200395) (xy 419.126165 -239.21472) (xy 419.107365 -239.222415) (xy 419.097206 -239.222788)
			(xy 417.697666 -239.222788) (xy 417.687541 -239.222302) (xy 417.668824 -239.214568) (xy 417.65447 -239.200283)
			(xy 417.646647 -239.181603) (xy 417.646104 -239.17148) (xy 411.604968 -239.17148) (xy 411.604562 -239.181637)
			(xy 411.596767 -239.200395) (xy 411.582365 -239.21472) (xy 411.563565 -239.222415) (xy 411.553406 -239.222788)
			(xy 410.153866 -239.222788) (xy 410.143741 -239.222302) (xy 410.125024 -239.214568) (xy 410.11067 -239.200283)
			(xy 410.102847 -239.181603) (xy 410.102304 -239.17148) (xy 313.738768 -239.17148) (xy 313.738362 -239.181637)
			(xy 313.730567 -239.200395) (xy 313.716165 -239.21472) (xy 313.697365 -239.222415) (xy 313.687206 -239.222788)
			(xy 312.287666 -239.222788) (xy 312.277541 -239.222302) (xy 312.258824 -239.214568) (xy 312.24447 -239.200283)
			(xy 312.236647 -239.181603) (xy 312.236104 -239.17148) (xy 306.194968 -239.17148) (xy 306.194562 -239.181637)
			(xy 306.186767 -239.200395) (xy 306.172365 -239.21472) (xy 306.153565 -239.222415) (xy 306.143406 -239.222788)
			(xy 304.743866 -239.222788) (xy 304.733741 -239.222302) (xy 304.715024 -239.214568) (xy 304.70067 -239.200283)
			(xy 304.692847 -239.181603) (xy 304.692304 -239.17148) (xy 298.651168 -239.17148) (xy 298.650762 -239.181637)
			(xy 298.642967 -239.200395) (xy 298.628565 -239.21472) (xy 298.609765 -239.222415) (xy 298.599606 -239.222788)
			(xy 297.200066 -239.222788) (xy 297.189941 -239.222302) (xy 297.171224 -239.214568) (xy 297.15687 -239.200283)
			(xy 297.149047 -239.181603) (xy 297.148504 -239.17148) (xy 291.107368 -239.17148) (xy 291.106962 -239.181637)
			(xy 291.099167 -239.200395) (xy 291.084765 -239.21472) (xy 291.065965 -239.222415) (xy 291.055806 -239.222788)
			(xy 289.656266 -239.222788) (xy 289.646141 -239.222302) (xy 289.627424 -239.214568) (xy 289.61307 -239.200283)
			(xy 289.605247 -239.181603) (xy 289.604704 -239.17148) (xy 283.563568 -239.17148) (xy 283.563162 -239.181637)
			(xy 283.555367 -239.200395) (xy 283.540965 -239.21472) (xy 283.522165 -239.222415) (xy 283.512006 -239.222788)
			(xy 282.112466 -239.222788) (xy 282.102341 -239.222302) (xy 282.083624 -239.214568) (xy 282.06927 -239.200283)
			(xy 282.061447 -239.181603) (xy 282.060904 -239.17148) (xy 276.019768 -239.17148) (xy 276.019362 -239.181637)
			(xy 276.011567 -239.200395) (xy 275.997165 -239.21472) (xy 275.978365 -239.222415) (xy 275.968206 -239.222788)
			(xy 274.568666 -239.222788) (xy 274.558541 -239.222302) (xy 274.539824 -239.214568) (xy 274.52547 -239.200283)
			(xy 274.517647 -239.181603) (xy 274.517104 -239.17148) (xy 268.475968 -239.17148) (xy 268.475562 -239.181637)
			(xy 268.467767 -239.200395) (xy 268.453365 -239.21472) (xy 268.434565 -239.222415) (xy 268.424406 -239.222788)
			(xy 267.024866 -239.222788) (xy 267.014741 -239.222302) (xy 266.996024 -239.214568) (xy 266.98167 -239.200283)
			(xy 266.973847 -239.181603) (xy 266.973304 -239.17148) (xy 260.932168 -239.17148) (xy 260.931762 -239.181637)
			(xy 260.923967 -239.200395) (xy 260.909565 -239.21472) (xy 260.890765 -239.222415) (xy 260.880606 -239.222788)
			(xy 259.481066 -239.222788) (xy 259.470941 -239.222302) (xy 259.452224 -239.214568) (xy 259.43787 -239.200283)
			(xy 259.430047 -239.181603) (xy 259.429504 -239.17148) (xy 216.4715 -239.17148) (xy 216.471062 -239.181633)
			(xy 216.463273 -239.200385) (xy 216.448881 -239.214709) (xy 216.430093 -239.222409) (xy 216.419938 -239.222788)
			(xy 215.020398 -239.222788) (xy 215.010275 -239.222276) (xy 214.991559 -239.214553) (xy 214.977204 -239.200275)
			(xy 214.96938 -239.181601) (xy 214.968836 -239.17148) (xy 208.9277 -239.17148) (xy 208.927262 -239.181633)
			(xy 208.919473 -239.200385) (xy 208.905081 -239.214709) (xy 208.886293 -239.222409) (xy 208.876138 -239.222788)
			(xy 207.476598 -239.222788) (xy 207.466475 -239.222276) (xy 207.447759 -239.214553) (xy 207.433404 -239.200275)
			(xy 207.42558 -239.181601) (xy 207.425036 -239.17148) (xy 201.3839 -239.17148) (xy 201.383462 -239.181633)
			(xy 201.375673 -239.200385) (xy 201.361281 -239.214709) (xy 201.342493 -239.222409) (xy 201.332338 -239.222788)
			(xy 199.932798 -239.222788) (xy 199.922675 -239.222276) (xy 199.903959 -239.214553) (xy 199.889604 -239.200275)
			(xy 199.88178 -239.181601) (xy 199.881236 -239.17148) (xy 193.8401 -239.17148) (xy 193.839662 -239.181633)
			(xy 193.831873 -239.200385) (xy 193.817481 -239.214709) (xy 193.798693 -239.222409) (xy 193.788538 -239.222788)
			(xy 192.388998 -239.222788) (xy 192.378875 -239.222276) (xy 192.360159 -239.214553) (xy 192.345804 -239.200275)
			(xy 192.33798 -239.181601) (xy 192.337436 -239.17148) (xy 186.2963 -239.17148) (xy 186.295862 -239.181633)
			(xy 186.288073 -239.200385) (xy 186.273681 -239.214709) (xy 186.254893 -239.222409) (xy 186.244738 -239.222788)
			(xy 184.845198 -239.222788) (xy 184.835075 -239.222276) (xy 184.816359 -239.214553) (xy 184.802004 -239.200275)
			(xy 184.79418 -239.181601) (xy 184.793636 -239.17148) (xy 178.7525 -239.17148) (xy 178.752062 -239.181633)
			(xy 178.744273 -239.200385) (xy 178.729881 -239.214709) (xy 178.711093 -239.222409) (xy 178.700938 -239.222788)
			(xy 177.301398 -239.222788) (xy 177.291275 -239.222276) (xy 177.272559 -239.214553) (xy 177.258204 -239.200275)
			(xy 177.25038 -239.181601) (xy 177.249836 -239.17148) (xy 171.2087 -239.17148) (xy 171.208262 -239.181633)
			(xy 171.200473 -239.200385) (xy 171.186081 -239.214709) (xy 171.167293 -239.222409) (xy 171.157138 -239.222788)
			(xy 169.757598 -239.222788) (xy 169.747475 -239.222276) (xy 169.728759 -239.214553) (xy 169.714404 -239.200275)
			(xy 169.70658 -239.181601) (xy 169.706036 -239.17148) (xy 163.6649 -239.17148) (xy 163.664462 -239.181633)
			(xy 163.656673 -239.200385) (xy 163.642281 -239.214709) (xy 163.623493 -239.222409) (xy 163.613338 -239.222788)
			(xy 162.213798 -239.222788) (xy 162.203675 -239.222276) (xy 162.184959 -239.214553) (xy 162.170604 -239.200275)
			(xy 162.16278 -239.181601) (xy 162.162236 -239.17148) (xy 65.7987 -239.17148) (xy 65.798262 -239.181633)
			(xy 65.790473 -239.200385) (xy 65.776081 -239.214709) (xy 65.757293 -239.222409) (xy 65.747138 -239.222788)
			(xy 64.347598 -239.222788) (xy 64.337475 -239.222276) (xy 64.318759 -239.214553) (xy 64.304404 -239.200275)
			(xy 64.29658 -239.181601) (xy 64.296036 -239.17148) (xy 58.2549 -239.17148) (xy 58.254462 -239.181633)
			(xy 58.246673 -239.200385) (xy 58.232281 -239.214709) (xy 58.213493 -239.222409) (xy 58.203338 -239.222788)
			(xy 56.803798 -239.222788) (xy 56.793675 -239.222276) (xy 56.774959 -239.214553) (xy 56.760604 -239.200275)
			(xy 56.75278 -239.181601) (xy 56.752236 -239.17148) (xy 50.7111 -239.17148) (xy 50.710662 -239.181633)
			(xy 50.702873 -239.200385) (xy 50.688481 -239.214709) (xy 50.669693 -239.222409) (xy 50.659538 -239.222788)
			(xy 49.259998 -239.222788) (xy 49.249875 -239.222276) (xy 49.231159 -239.214553) (xy 49.216804 -239.200275)
			(xy 49.20898 -239.181601) (xy 49.208436 -239.17148) (xy 43.1673 -239.17148) (xy 43.166862 -239.181633)
			(xy 43.159073 -239.200385) (xy 43.144681 -239.214709) (xy 43.125893 -239.222409) (xy 43.115738 -239.222788)
			(xy 41.716198 -239.222788) (xy 41.706075 -239.222276) (xy 41.687359 -239.214553) (xy 41.673004 -239.200275)
			(xy 41.66518 -239.181601) (xy 41.664636 -239.17148) (xy 35.6235 -239.17148) (xy 35.623062 -239.181633)
			(xy 35.615273 -239.200385) (xy 35.600881 -239.214709) (xy 35.582093 -239.222409) (xy 35.571938 -239.222788)
			(xy 34.172398 -239.222788) (xy 34.162275 -239.222276) (xy 34.143559 -239.214553) (xy 34.129204 -239.200275)
			(xy 34.12138 -239.181601) (xy 34.120836 -239.17148) (xy 28.0797 -239.17148) (xy 28.079262 -239.181633)
			(xy 28.071473 -239.200385) (xy 28.057081 -239.214709) (xy 28.038293 -239.222409) (xy 28.028138 -239.222788)
			(xy 26.628598 -239.222788) (xy 26.618475 -239.222276) (xy 26.599759 -239.214553) (xy 26.585404 -239.200275)
			(xy 26.57758 -239.181601) (xy 26.577036 -239.17148) (xy 20.5359 -239.17148) (xy 20.535462 -239.181633)
			(xy 20.527673 -239.200385) (xy 20.513281 -239.214709) (xy 20.494493 -239.222409) (xy 20.484338 -239.222788)
			(xy 19.084798 -239.222788) (xy 19.074675 -239.222276) (xy 19.055959 -239.214553) (xy 19.041604 -239.200275)
			(xy 19.03378 -239.181601) (xy 19.033236 -239.17148) (xy 12.9921 -239.17148) (xy 12.991662 -239.181633)
			(xy 12.983873 -239.200385) (xy 12.969481 -239.214709) (xy 12.950693 -239.222409) (xy 12.940538 -239.222788)
			(xy 11.540998 -239.222788) (xy 11.530875 -239.222276) (xy 11.512159 -239.214553) (xy 11.497804 -239.200275)
			(xy 11.48998 -239.181601) (xy 11.489436 -239.17148) (xy 2.509012 -239.17148) (xy 2.509012 -240.021364)
			(xy 7.389368 -240.021364) (xy 7.389368 -239.612424) (xy 7.38984 -239.602275) (xy 7.397622 -239.58353)
			(xy 7.412003 -239.569206) (xy 7.43078 -239.5615) (xy 7.44093 -239.561116) (xy 8.84047 -239.561116)
			(xy 8.850592 -239.56165) (xy 8.869308 -239.569364) (xy 8.883664 -239.583635) (xy 8.891489 -239.602305)
			(xy 8.892032 -239.612424) (xy 8.892032 -240.021364) (xy 14.933168 -240.021364) (xy 14.933168 -239.612424)
			(xy 14.93364 -239.602275) (xy 14.941422 -239.58353) (xy 14.955803 -239.569206) (xy 14.97458 -239.5615)
			(xy 14.98473 -239.561116) (xy 16.38427 -239.561116) (xy 16.394392 -239.56165) (xy 16.413108 -239.569364)
			(xy 16.427464 -239.583635) (xy 16.435289 -239.602305) (xy 16.435832 -239.612424) (xy 16.435832 -240.021364)
			(xy 22.476968 -240.021364) (xy 22.476968 -239.612424) (xy 22.47744 -239.602275) (xy 22.485222 -239.58353)
			(xy 22.499603 -239.569206) (xy 22.51838 -239.5615) (xy 22.52853 -239.561116) (xy 23.92807 -239.561116)
			(xy 23.938192 -239.56165) (xy 23.956908 -239.569364) (xy 23.971264 -239.583635) (xy 23.979089 -239.602305)
			(xy 23.979632 -239.612424) (xy 23.979632 -240.021364) (xy 30.020768 -240.021364) (xy 30.020768 -239.612424)
			(xy 30.02124 -239.602275) (xy 30.029022 -239.58353) (xy 30.043403 -239.569206) (xy 30.06218 -239.5615)
			(xy 30.07233 -239.561116) (xy 31.47187 -239.561116) (xy 31.481992 -239.56165) (xy 31.500708 -239.569364)
			(xy 31.515064 -239.583635) (xy 31.522889 -239.602305) (xy 31.523432 -239.612424) (xy 31.523432 -240.021364)
			(xy 37.564568 -240.021364) (xy 37.564568 -239.612424) (xy 37.56504 -239.602275) (xy 37.572822 -239.58353)
			(xy 37.587203 -239.569206) (xy 37.60598 -239.5615) (xy 37.61613 -239.561116) (xy 39.01567 -239.561116)
			(xy 39.025792 -239.56165) (xy 39.044508 -239.569364) (xy 39.058864 -239.583635) (xy 39.066689 -239.602305)
			(xy 39.067232 -239.612424) (xy 39.067232 -240.021364) (xy 45.108368 -240.021364) (xy 45.108368 -239.612424)
			(xy 45.10884 -239.602275) (xy 45.116622 -239.58353) (xy 45.131003 -239.569206) (xy 45.14978 -239.5615)
			(xy 45.15993 -239.561116) (xy 46.55947 -239.561116) (xy 46.569592 -239.56165) (xy 46.588308 -239.569364)
			(xy 46.602664 -239.583635) (xy 46.610489 -239.602305) (xy 46.611032 -239.612424) (xy 46.611032 -240.021364)
			(xy 52.652168 -240.021364) (xy 52.652168 -239.612424) (xy 52.65264 -239.602275) (xy 52.660422 -239.58353)
			(xy 52.674803 -239.569206) (xy 52.69358 -239.5615) (xy 52.70373 -239.561116) (xy 54.10327 -239.561116)
			(xy 54.113392 -239.56165) (xy 54.132108 -239.569364) (xy 54.146464 -239.583635) (xy 54.154289 -239.602305)
			(xy 54.154832 -239.612424) (xy 54.154832 -240.021364) (xy 60.195968 -240.021364) (xy 60.195968 -239.612424)
			(xy 60.19644 -239.602275) (xy 60.204222 -239.58353) (xy 60.218603 -239.569206) (xy 60.23738 -239.5615)
			(xy 60.24753 -239.561116) (xy 61.64707 -239.561116) (xy 61.657192 -239.56165) (xy 61.675908 -239.569364)
			(xy 61.690264 -239.583635) (xy 61.698089 -239.602305) (xy 61.698632 -239.612424) (xy 61.698632 -240.021364)
			(xy 158.062168 -240.021364) (xy 158.062168 -239.612424) (xy 158.06264 -239.602275) (xy 158.070422 -239.58353)
			(xy 158.084803 -239.569206) (xy 158.10358 -239.5615) (xy 158.11373 -239.561116) (xy 159.51327 -239.561116)
			(xy 159.523392 -239.56165) (xy 159.542108 -239.569364) (xy 159.556464 -239.583635) (xy 159.564289 -239.602305)
			(xy 159.564832 -239.612424) (xy 159.564832 -240.021364) (xy 165.605968 -240.021364) (xy 165.605968 -239.612424)
			(xy 165.60644 -239.602275) (xy 165.614222 -239.58353) (xy 165.628603 -239.569206) (xy 165.64738 -239.5615)
			(xy 165.65753 -239.561116) (xy 167.05707 -239.561116) (xy 167.067192 -239.56165) (xy 167.085908 -239.569364)
			(xy 167.100264 -239.583635) (xy 167.108089 -239.602305) (xy 167.108632 -239.612424) (xy 167.108632 -240.021364)
			(xy 173.149768 -240.021364) (xy 173.149768 -239.612424) (xy 173.15024 -239.602275) (xy 173.158022 -239.58353)
			(xy 173.172403 -239.569206) (xy 173.19118 -239.5615) (xy 173.20133 -239.561116) (xy 174.60087 -239.561116)
			(xy 174.610992 -239.56165) (xy 174.629708 -239.569364) (xy 174.644064 -239.583635) (xy 174.651889 -239.602305)
			(xy 174.652432 -239.612424) (xy 174.652432 -240.021364) (xy 180.693568 -240.021364) (xy 180.693568 -239.612424)
			(xy 180.69404 -239.602275) (xy 180.701822 -239.58353) (xy 180.716203 -239.569206) (xy 180.73498 -239.5615)
			(xy 180.74513 -239.561116) (xy 182.14467 -239.561116) (xy 182.154792 -239.56165) (xy 182.173508 -239.569364)
			(xy 182.187864 -239.583635) (xy 182.195689 -239.602305) (xy 182.196232 -239.612424) (xy 182.196232 -240.021364)
			(xy 188.237368 -240.021364) (xy 188.237368 -239.612424) (xy 188.23784 -239.602275) (xy 188.245622 -239.58353)
			(xy 188.260003 -239.569206) (xy 188.27878 -239.5615) (xy 188.28893 -239.561116) (xy 189.68847 -239.561116)
			(xy 189.698592 -239.56165) (xy 189.717308 -239.569364) (xy 189.731664 -239.583635) (xy 189.739489 -239.602305)
			(xy 189.740032 -239.612424) (xy 189.740032 -240.021364) (xy 195.781168 -240.021364) (xy 195.781168 -239.612424)
			(xy 195.78164 -239.602275) (xy 195.789422 -239.58353) (xy 195.803803 -239.569206) (xy 195.82258 -239.5615)
			(xy 195.83273 -239.561116) (xy 197.23227 -239.561116) (xy 197.242392 -239.56165) (xy 197.261108 -239.569364)
			(xy 197.275464 -239.583635) (xy 197.283289 -239.602305) (xy 197.283832 -239.612424) (xy 197.283832 -240.021364)
			(xy 203.324968 -240.021364) (xy 203.324968 -239.612424) (xy 203.32544 -239.602275) (xy 203.333222 -239.58353)
			(xy 203.347603 -239.569206) (xy 203.36638 -239.5615) (xy 203.37653 -239.561116) (xy 204.77607 -239.561116)
			(xy 204.786192 -239.56165) (xy 204.804908 -239.569364) (xy 204.819264 -239.583635) (xy 204.827089 -239.602305)
			(xy 204.827632 -239.612424) (xy 204.827632 -240.021364) (xy 210.868768 -240.021364) (xy 210.868768 -239.612424)
			(xy 210.86924 -239.602275) (xy 210.877022 -239.58353) (xy 210.891403 -239.569206) (xy 210.91018 -239.5615)
			(xy 210.92033 -239.561116) (xy 212.31987 -239.561116) (xy 212.329992 -239.56165) (xy 212.348708 -239.569364)
			(xy 212.363064 -239.583635) (xy 212.370889 -239.602305) (xy 212.371432 -239.612424) (xy 212.371432 -240.021364)
			(xy 255.329436 -240.021364) (xy 255.329436 -239.612424) (xy 255.329842 -239.602267) (xy 255.337636 -239.583508)
			(xy 255.352039 -239.569182) (xy 255.370839 -239.561488) (xy 255.380998 -239.561116) (xy 256.780538 -239.561116)
			(xy 256.790664 -239.561595) (xy 256.809382 -239.569331) (xy 256.823736 -239.583619) (xy 256.831558 -239.6023)
			(xy 256.8321 -239.612424) (xy 256.8321 -240.021364) (xy 262.873236 -240.021364) (xy 262.873236 -239.612424)
			(xy 262.873642 -239.602267) (xy 262.881436 -239.583508) (xy 262.895839 -239.569182) (xy 262.914639 -239.561488)
			(xy 262.924798 -239.561116) (xy 264.324338 -239.561116) (xy 264.334464 -239.561595) (xy 264.353182 -239.569331)
			(xy 264.367536 -239.583619) (xy 264.375358 -239.6023) (xy 264.3759 -239.612424) (xy 264.3759 -240.021364)
			(xy 270.417036 -240.021364) (xy 270.417036 -239.612424) (xy 270.417442 -239.602267) (xy 270.425236 -239.583508)
			(xy 270.439639 -239.569182) (xy 270.458439 -239.561488) (xy 270.468598 -239.561116) (xy 271.868138 -239.561116)
			(xy 271.878264 -239.561595) (xy 271.896982 -239.569331) (xy 271.911336 -239.583619) (xy 271.919158 -239.6023)
			(xy 271.9197 -239.612424) (xy 271.9197 -240.021364) (xy 277.960836 -240.021364) (xy 277.960836 -239.612424)
			(xy 277.961242 -239.602267) (xy 277.969036 -239.583508) (xy 277.983439 -239.569182) (xy 278.002239 -239.561488)
			(xy 278.012398 -239.561116) (xy 279.411938 -239.561116) (xy 279.422064 -239.561595) (xy 279.440782 -239.569331)
			(xy 279.455136 -239.583619) (xy 279.462958 -239.6023) (xy 279.4635 -239.612424) (xy 279.4635 -240.021364)
			(xy 285.504636 -240.021364) (xy 285.504636 -239.612424) (xy 285.505042 -239.602267) (xy 285.512836 -239.583508)
			(xy 285.527239 -239.569182) (xy 285.546039 -239.561488) (xy 285.556198 -239.561116) (xy 286.955738 -239.561116)
			(xy 286.965864 -239.561595) (xy 286.984582 -239.569331) (xy 286.998936 -239.583619) (xy 287.006758 -239.6023)
			(xy 287.0073 -239.612424) (xy 287.0073 -240.021364) (xy 293.048436 -240.021364) (xy 293.048436 -239.612424)
			(xy 293.048842 -239.602267) (xy 293.056636 -239.583508) (xy 293.071039 -239.569182) (xy 293.089839 -239.561488)
			(xy 293.099998 -239.561116) (xy 294.499538 -239.561116) (xy 294.509664 -239.561595) (xy 294.528382 -239.569331)
			(xy 294.542736 -239.583619) (xy 294.550558 -239.6023) (xy 294.5511 -239.612424) (xy 294.5511 -240.021364)
			(xy 300.592236 -240.021364) (xy 300.592236 -239.612424) (xy 300.592642 -239.602267) (xy 300.600436 -239.583508)
			(xy 300.614839 -239.569182) (xy 300.633639 -239.561488) (xy 300.643798 -239.561116) (xy 302.043338 -239.561116)
			(xy 302.053464 -239.561595) (xy 302.072182 -239.569331) (xy 302.086536 -239.583619) (xy 302.094358 -239.6023)
			(xy 302.0949 -239.612424) (xy 302.0949 -240.021364) (xy 308.136036 -240.021364) (xy 308.136036 -239.612424)
			(xy 308.136442 -239.602267) (xy 308.144236 -239.583508) (xy 308.158639 -239.569182) (xy 308.177439 -239.561488)
			(xy 308.187598 -239.561116) (xy 309.587138 -239.561116) (xy 309.597264 -239.561595) (xy 309.615982 -239.569331)
			(xy 309.630336 -239.583619) (xy 309.638158 -239.6023) (xy 309.6387 -239.612424) (xy 309.6387 -240.021364)
			(xy 406.002236 -240.021364) (xy 406.002236 -239.612424) (xy 406.002642 -239.602267) (xy 406.010436 -239.583508)
			(xy 406.024839 -239.569182) (xy 406.043639 -239.561488) (xy 406.053798 -239.561116) (xy 407.453338 -239.561116)
			(xy 407.463464 -239.561595) (xy 407.482182 -239.569331) (xy 407.496536 -239.583619) (xy 407.504358 -239.6023)
			(xy 407.5049 -239.612424) (xy 407.5049 -240.021364) (xy 413.546036 -240.021364) (xy 413.546036 -239.612424)
			(xy 413.546442 -239.602267) (xy 413.554236 -239.583508) (xy 413.568639 -239.569182) (xy 413.587439 -239.561488)
			(xy 413.597598 -239.561116) (xy 414.997138 -239.561116) (xy 415.007264 -239.561595) (xy 415.025982 -239.569331)
			(xy 415.040336 -239.583619) (xy 415.048158 -239.6023) (xy 415.0487 -239.612424) (xy 415.0487 -240.021364)
			(xy 421.089836 -240.021364) (xy 421.089836 -239.612424) (xy 421.090242 -239.602267) (xy 421.098036 -239.583508)
			(xy 421.112439 -239.569182) (xy 421.131239 -239.561488) (xy 421.141398 -239.561116) (xy 422.540938 -239.561116)
			(xy 422.551064 -239.561595) (xy 422.569782 -239.569331) (xy 422.584136 -239.583619) (xy 422.591958 -239.6023)
			(xy 422.5925 -239.612424) (xy 422.5925 -240.021364) (xy 428.633636 -240.021364) (xy 428.633636 -239.612424)
			(xy 428.634042 -239.602267) (xy 428.641836 -239.583508) (xy 428.656239 -239.569182) (xy 428.675039 -239.561488)
			(xy 428.685198 -239.561116) (xy 430.084738 -239.561116) (xy 430.094864 -239.561595) (xy 430.113582 -239.569331)
			(xy 430.127936 -239.583619) (xy 430.135758 -239.6023) (xy 430.1363 -239.612424) (xy 430.1363 -240.021364)
			(xy 436.177436 -240.021364) (xy 436.177436 -239.612424) (xy 436.177842 -239.602267) (xy 436.185636 -239.583508)
			(xy 436.200039 -239.569182) (xy 436.218839 -239.561488) (xy 436.228998 -239.561116) (xy 437.628538 -239.561116)
			(xy 437.638664 -239.561595) (xy 437.657382 -239.569331) (xy 437.671736 -239.583619) (xy 437.679558 -239.6023)
			(xy 437.6801 -239.612424) (xy 437.6801 -240.021364) (xy 443.721236 -240.021364) (xy 443.721236 -239.612424)
			(xy 443.721642 -239.602267) (xy 443.729436 -239.583508) (xy 443.743839 -239.569182) (xy 443.762639 -239.561488)
			(xy 443.772798 -239.561116) (xy 445.172338 -239.561116) (xy 445.182464 -239.561595) (xy 445.201182 -239.569331)
			(xy 445.215536 -239.583619) (xy 445.223358 -239.6023) (xy 445.2239 -239.612424) (xy 445.2239 -240.021364)
			(xy 451.265036 -240.021364) (xy 451.265036 -239.612424) (xy 451.265442 -239.602267) (xy 451.273236 -239.583508)
			(xy 451.287639 -239.569182) (xy 451.306439 -239.561488) (xy 451.316598 -239.561116) (xy 452.716138 -239.561116)
			(xy 452.726264 -239.561595) (xy 452.744982 -239.569331) (xy 452.759336 -239.583619) (xy 452.767158 -239.6023)
			(xy 452.7677 -239.612424) (xy 452.7677 -240.021364) (xy 458.808836 -240.021364) (xy 458.808836 -239.612424)
			(xy 458.809242 -239.602267) (xy 458.817036 -239.583508) (xy 458.831439 -239.569182) (xy 458.850239 -239.561488)
			(xy 458.860398 -239.561116) (xy 460.259938 -239.561116) (xy 460.270064 -239.561595) (xy 460.288782 -239.569331)
			(xy 460.303136 -239.583619) (xy 460.310958 -239.6023) (xy 460.3115 -239.612424) (xy 460.3115 -240.021364)
			(xy 460.311049 -240.031516) (xy 460.303265 -240.050267) (xy 460.288877 -240.064592) (xy 460.270091 -240.072293)
			(xy 460.259938 -240.072672) (xy 458.860398 -240.072672) (xy 458.850273 -240.072175) (xy 458.831554 -240.064449)
			(xy 458.817198 -240.050166) (xy 458.809377 -240.031487) (xy 458.808836 -240.021364) (xy 452.7677 -240.021364)
			(xy 452.767249 -240.031516) (xy 452.759465 -240.050267) (xy 452.745077 -240.064592) (xy 452.726291 -240.072293)
			(xy 452.716138 -240.072672) (xy 451.316598 -240.072672) (xy 451.306473 -240.072175) (xy 451.287754 -240.064449)
			(xy 451.273398 -240.050166) (xy 451.265577 -240.031487) (xy 451.265036 -240.021364) (xy 445.2239 -240.021364)
			(xy 445.223449 -240.031516) (xy 445.215665 -240.050267) (xy 445.201277 -240.064592) (xy 445.182491 -240.072293)
			(xy 445.172338 -240.072672) (xy 443.772798 -240.072672) (xy 443.762673 -240.072175) (xy 443.743954 -240.064449)
			(xy 443.729598 -240.050166) (xy 443.721777 -240.031487) (xy 443.721236 -240.021364) (xy 437.6801 -240.021364)
			(xy 437.679649 -240.031516) (xy 437.671865 -240.050267) (xy 437.657477 -240.064592) (xy 437.638691 -240.072293)
			(xy 437.628538 -240.072672) (xy 436.228998 -240.072672) (xy 436.218873 -240.072175) (xy 436.200154 -240.064449)
			(xy 436.185798 -240.050166) (xy 436.177977 -240.031487) (xy 436.177436 -240.021364) (xy 430.1363 -240.021364)
			(xy 430.135849 -240.031516) (xy 430.128065 -240.050267) (xy 430.113677 -240.064592) (xy 430.094891 -240.072293)
			(xy 430.084738 -240.072672) (xy 428.685198 -240.072672) (xy 428.675073 -240.072175) (xy 428.656354 -240.064449)
			(xy 428.641998 -240.050166) (xy 428.634177 -240.031487) (xy 428.633636 -240.021364) (xy 422.5925 -240.021364)
			(xy 422.592049 -240.031516) (xy 422.584265 -240.050267) (xy 422.569877 -240.064592) (xy 422.551091 -240.072293)
			(xy 422.540938 -240.072672) (xy 421.141398 -240.072672) (xy 421.131273 -240.072175) (xy 421.112554 -240.064449)
			(xy 421.098198 -240.050166) (xy 421.090377 -240.031487) (xy 421.089836 -240.021364) (xy 415.0487 -240.021364)
			(xy 415.048249 -240.031516) (xy 415.040465 -240.050267) (xy 415.026077 -240.064592) (xy 415.007291 -240.072293)
			(xy 414.997138 -240.072672) (xy 413.597598 -240.072672) (xy 413.587473 -240.072175) (xy 413.568754 -240.064449)
			(xy 413.554398 -240.050166) (xy 413.546577 -240.031487) (xy 413.546036 -240.021364) (xy 407.5049 -240.021364)
			(xy 407.504449 -240.031516) (xy 407.496665 -240.050267) (xy 407.482277 -240.064592) (xy 407.463491 -240.072293)
			(xy 407.453338 -240.072672) (xy 406.053798 -240.072672) (xy 406.043673 -240.072175) (xy 406.024954 -240.064449)
			(xy 406.010598 -240.050166) (xy 406.002777 -240.031487) (xy 406.002236 -240.021364) (xy 309.6387 -240.021364)
			(xy 309.638249 -240.031516) (xy 309.630465 -240.050267) (xy 309.616077 -240.064592) (xy 309.597291 -240.072293)
			(xy 309.587138 -240.072672) (xy 308.187598 -240.072672) (xy 308.177473 -240.072175) (xy 308.158754 -240.064449)
			(xy 308.144398 -240.050166) (xy 308.136577 -240.031487) (xy 308.136036 -240.021364) (xy 302.0949 -240.021364)
			(xy 302.094449 -240.031516) (xy 302.086665 -240.050267) (xy 302.072277 -240.064592) (xy 302.053491 -240.072293)
			(xy 302.043338 -240.072672) (xy 300.643798 -240.072672) (xy 300.633673 -240.072175) (xy 300.614954 -240.064449)
			(xy 300.600598 -240.050166) (xy 300.592777 -240.031487) (xy 300.592236 -240.021364) (xy 294.5511 -240.021364)
			(xy 294.550649 -240.031516) (xy 294.542865 -240.050267) (xy 294.528477 -240.064592) (xy 294.509691 -240.072293)
			(xy 294.499538 -240.072672) (xy 293.099998 -240.072672) (xy 293.089873 -240.072175) (xy 293.071154 -240.064449)
			(xy 293.056798 -240.050166) (xy 293.048977 -240.031487) (xy 293.048436 -240.021364) (xy 287.0073 -240.021364)
			(xy 287.006849 -240.031516) (xy 286.999065 -240.050267) (xy 286.984677 -240.064592) (xy 286.965891 -240.072293)
			(xy 286.955738 -240.072672) (xy 285.556198 -240.072672) (xy 285.546073 -240.072175) (xy 285.527354 -240.064449)
			(xy 285.512998 -240.050166) (xy 285.505177 -240.031487) (xy 285.504636 -240.021364) (xy 279.4635 -240.021364)
			(xy 279.463049 -240.031516) (xy 279.455265 -240.050267) (xy 279.440877 -240.064592) (xy 279.422091 -240.072293)
			(xy 279.411938 -240.072672) (xy 278.012398 -240.072672) (xy 278.002273 -240.072175) (xy 277.983554 -240.064449)
			(xy 277.969198 -240.050166) (xy 277.961377 -240.031487) (xy 277.960836 -240.021364) (xy 271.9197 -240.021364)
			(xy 271.919249 -240.031516) (xy 271.911465 -240.050267) (xy 271.897077 -240.064592) (xy 271.878291 -240.072293)
			(xy 271.868138 -240.072672) (xy 270.468598 -240.072672) (xy 270.458473 -240.072175) (xy 270.439754 -240.064449)
			(xy 270.425398 -240.050166) (xy 270.417577 -240.031487) (xy 270.417036 -240.021364) (xy 264.3759 -240.021364)
			(xy 264.375449 -240.031516) (xy 264.367665 -240.050267) (xy 264.353277 -240.064592) (xy 264.334491 -240.072293)
			(xy 264.324338 -240.072672) (xy 262.924798 -240.072672) (xy 262.914673 -240.072175) (xy 262.895954 -240.064449)
			(xy 262.881598 -240.050166) (xy 262.873777 -240.031487) (xy 262.873236 -240.021364) (xy 256.8321 -240.021364)
			(xy 256.831649 -240.031516) (xy 256.823865 -240.050267) (xy 256.809477 -240.064592) (xy 256.790691 -240.072293)
			(xy 256.780538 -240.072672) (xy 255.380998 -240.072672) (xy 255.370873 -240.072175) (xy 255.352154 -240.064449)
			(xy 255.337798 -240.050166) (xy 255.329977 -240.031487) (xy 255.329436 -240.021364) (xy 212.371432 -240.021364)
			(xy 212.370949 -240.031512) (xy 212.363172 -240.050257) (xy 212.348794 -240.064581) (xy 212.330019 -240.072287)
			(xy 212.31987 -240.072672) (xy 210.92033 -240.072672) (xy 210.910207 -240.072149) (xy 210.891488 -240.064434)
			(xy 210.877131 -240.050158) (xy 210.869309 -240.031484) (xy 210.868768 -240.021364) (xy 204.827632 -240.021364)
			(xy 204.827149 -240.031512) (xy 204.819372 -240.050257) (xy 204.804994 -240.064581) (xy 204.786219 -240.072287)
			(xy 204.77607 -240.072672) (xy 203.37653 -240.072672) (xy 203.366407 -240.072149) (xy 203.347688 -240.064434)
			(xy 203.333331 -240.050158) (xy 203.325509 -240.031484) (xy 203.324968 -240.021364) (xy 197.283832 -240.021364)
			(xy 197.283349 -240.031512) (xy 197.275572 -240.050257) (xy 197.261194 -240.064581) (xy 197.242419 -240.072287)
			(xy 197.23227 -240.072672) (xy 195.83273 -240.072672) (xy 195.822607 -240.072149) (xy 195.803888 -240.064434)
			(xy 195.789531 -240.050158) (xy 195.781709 -240.031484) (xy 195.781168 -240.021364) (xy 189.740032 -240.021364)
			(xy 189.739549 -240.031512) (xy 189.731772 -240.050257) (xy 189.717394 -240.064581) (xy 189.698619 -240.072287)
			(xy 189.68847 -240.072672) (xy 188.28893 -240.072672) (xy 188.278807 -240.072149) (xy 188.260088 -240.064434)
			(xy 188.245731 -240.050158) (xy 188.237909 -240.031484) (xy 188.237368 -240.021364) (xy 182.196232 -240.021364)
			(xy 182.195749 -240.031512) (xy 182.187972 -240.050257) (xy 182.173594 -240.064581) (xy 182.154819 -240.072287)
			(xy 182.14467 -240.072672) (xy 180.74513 -240.072672) (xy 180.735007 -240.072149) (xy 180.716288 -240.064434)
			(xy 180.701931 -240.050158) (xy 180.694109 -240.031484) (xy 180.693568 -240.021364) (xy 174.652432 -240.021364)
			(xy 174.651949 -240.031512) (xy 174.644172 -240.050257) (xy 174.629794 -240.064581) (xy 174.611019 -240.072287)
			(xy 174.60087 -240.072672) (xy 173.20133 -240.072672) (xy 173.191207 -240.072149) (xy 173.172488 -240.064434)
			(xy 173.158131 -240.050158) (xy 173.150309 -240.031484) (xy 173.149768 -240.021364) (xy 167.108632 -240.021364)
			(xy 167.108149 -240.031512) (xy 167.100372 -240.050257) (xy 167.085994 -240.064581) (xy 167.067219 -240.072287)
			(xy 167.05707 -240.072672) (xy 165.65753 -240.072672) (xy 165.647407 -240.072149) (xy 165.628688 -240.064434)
			(xy 165.614331 -240.050158) (xy 165.606509 -240.031484) (xy 165.605968 -240.021364) (xy 159.564832 -240.021364)
			(xy 159.564349 -240.031512) (xy 159.556572 -240.050257) (xy 159.542194 -240.064581) (xy 159.523419 -240.072287)
			(xy 159.51327 -240.072672) (xy 158.11373 -240.072672) (xy 158.103607 -240.072149) (xy 158.084888 -240.064434)
			(xy 158.070531 -240.050158) (xy 158.062709 -240.031484) (xy 158.062168 -240.021364) (xy 61.698632 -240.021364)
			(xy 61.698149 -240.031512) (xy 61.690372 -240.050257) (xy 61.675994 -240.064581) (xy 61.657219 -240.072287)
			(xy 61.64707 -240.072672) (xy 60.24753 -240.072672) (xy 60.237407 -240.072149) (xy 60.218688 -240.064434)
			(xy 60.204331 -240.050158) (xy 60.196509 -240.031484) (xy 60.195968 -240.021364) (xy 54.154832 -240.021364)
			(xy 54.154349 -240.031512) (xy 54.146572 -240.050257) (xy 54.132194 -240.064581) (xy 54.113419 -240.072287)
			(xy 54.10327 -240.072672) (xy 52.70373 -240.072672) (xy 52.693607 -240.072149) (xy 52.674888 -240.064434)
			(xy 52.660531 -240.050158) (xy 52.652709 -240.031484) (xy 52.652168 -240.021364) (xy 46.611032 -240.021364)
			(xy 46.610549 -240.031512) (xy 46.602772 -240.050257) (xy 46.588394 -240.064581) (xy 46.569619 -240.072287)
			(xy 46.55947 -240.072672) (xy 45.15993 -240.072672) (xy 45.149807 -240.072149) (xy 45.131088 -240.064434)
			(xy 45.116731 -240.050158) (xy 45.108909 -240.031484) (xy 45.108368 -240.021364) (xy 39.067232 -240.021364)
			(xy 39.066749 -240.031512) (xy 39.058972 -240.050257) (xy 39.044594 -240.064581) (xy 39.025819 -240.072287)
			(xy 39.01567 -240.072672) (xy 37.61613 -240.072672) (xy 37.606007 -240.072149) (xy 37.587288 -240.064434)
			(xy 37.572931 -240.050158) (xy 37.565109 -240.031484) (xy 37.564568 -240.021364) (xy 31.523432 -240.021364)
			(xy 31.522949 -240.031512) (xy 31.515172 -240.050257) (xy 31.500794 -240.064581) (xy 31.482019 -240.072287)
			(xy 31.47187 -240.072672) (xy 30.07233 -240.072672) (xy 30.062207 -240.072149) (xy 30.043488 -240.064434)
			(xy 30.029131 -240.050158) (xy 30.021309 -240.031484) (xy 30.020768 -240.021364) (xy 23.979632 -240.021364)
			(xy 23.979149 -240.031512) (xy 23.971372 -240.050257) (xy 23.956994 -240.064581) (xy 23.938219 -240.072287)
			(xy 23.92807 -240.072672) (xy 22.52853 -240.072672) (xy 22.518407 -240.072149) (xy 22.499688 -240.064434)
			(xy 22.485331 -240.050158) (xy 22.477509 -240.031484) (xy 22.476968 -240.021364) (xy 16.435832 -240.021364)
			(xy 16.435349 -240.031512) (xy 16.427572 -240.050257) (xy 16.413194 -240.064581) (xy 16.394419 -240.072287)
			(xy 16.38427 -240.072672) (xy 14.98473 -240.072672) (xy 14.974607 -240.072149) (xy 14.955888 -240.064434)
			(xy 14.941531 -240.050158) (xy 14.933709 -240.031484) (xy 14.933168 -240.021364) (xy 8.892032 -240.021364)
			(xy 8.891549 -240.031512) (xy 8.883772 -240.050257) (xy 8.869394 -240.064581) (xy 8.850619 -240.072287)
			(xy 8.84047 -240.072672) (xy 7.44093 -240.072672) (xy 7.430807 -240.072149) (xy 7.412088 -240.064434)
			(xy 7.397731 -240.050158) (xy 7.389909 -240.031484) (xy 7.389368 -240.021364) (xy 2.509012 -240.021364)
			(xy 2.509012 -240.871502) (xy 11.489436 -240.871502) (xy 11.489436 -240.462562) (xy 11.489902 -240.452402)
			(xy 11.497689 -240.433632) (xy 11.512063 -240.419269) (xy 11.530838 -240.411495) (xy 11.540998 -240.411)
			(xy 12.940538 -240.411) (xy 12.950694 -240.411501) (xy 12.969456 -240.419281) (xy 12.983819 -240.433644)
			(xy 12.991599 -240.452406) (xy 12.9921 -240.462562) (xy 12.9921 -240.871502) (xy 19.033236 -240.871502)
			(xy 19.033236 -240.462562) (xy 19.033702 -240.452402) (xy 19.041489 -240.433632) (xy 19.055863 -240.419269)
			(xy 19.074638 -240.411495) (xy 19.084798 -240.411) (xy 20.484338 -240.411) (xy 20.494494 -240.411501)
			(xy 20.513256 -240.419281) (xy 20.527619 -240.433644) (xy 20.535399 -240.452406) (xy 20.5359 -240.462562)
			(xy 20.5359 -240.871502) (xy 26.577036 -240.871502) (xy 26.577036 -240.462562) (xy 26.577502 -240.452402)
			(xy 26.585289 -240.433632) (xy 26.599663 -240.419269) (xy 26.618438 -240.411495) (xy 26.628598 -240.411)
			(xy 28.028138 -240.411) (xy 28.038294 -240.411501) (xy 28.057056 -240.419281) (xy 28.071419 -240.433644)
			(xy 28.079199 -240.452406) (xy 28.0797 -240.462562) (xy 28.0797 -240.871502) (xy 34.120836 -240.871502)
			(xy 34.120836 -240.462562) (xy 34.121302 -240.452402) (xy 34.129089 -240.433632) (xy 34.143463 -240.419269)
			(xy 34.162238 -240.411495) (xy 34.172398 -240.411) (xy 35.571938 -240.411) (xy 35.582094 -240.411501)
			(xy 35.600856 -240.419281) (xy 35.615219 -240.433644) (xy 35.622999 -240.452406) (xy 35.6235 -240.462562)
			(xy 35.6235 -240.871502) (xy 41.664636 -240.871502) (xy 41.664636 -240.462562) (xy 41.665102 -240.452402)
			(xy 41.672889 -240.433632) (xy 41.687263 -240.419269) (xy 41.706038 -240.411495) (xy 41.716198 -240.411)
			(xy 43.115738 -240.411) (xy 43.125894 -240.411501) (xy 43.144656 -240.419281) (xy 43.159019 -240.433644)
			(xy 43.166799 -240.452406) (xy 43.1673 -240.462562) (xy 43.1673 -240.871502) (xy 49.208436 -240.871502)
			(xy 49.208436 -240.462562) (xy 49.208902 -240.452402) (xy 49.216689 -240.433632) (xy 49.231063 -240.419269)
			(xy 49.249838 -240.411495) (xy 49.259998 -240.411) (xy 50.659538 -240.411) (xy 50.669694 -240.411501)
			(xy 50.688456 -240.419281) (xy 50.702819 -240.433644) (xy 50.710599 -240.452406) (xy 50.7111 -240.462562)
			(xy 50.7111 -240.871502) (xy 56.752236 -240.871502) (xy 56.752236 -240.462562) (xy 56.752702 -240.452402)
			(xy 56.760489 -240.433632) (xy 56.774863 -240.419269) (xy 56.793638 -240.411495) (xy 56.803798 -240.411)
			(xy 58.203338 -240.411) (xy 58.213494 -240.411501) (xy 58.232256 -240.419281) (xy 58.246619 -240.433644)
			(xy 58.254399 -240.452406) (xy 58.2549 -240.462562) (xy 58.2549 -240.871502) (xy 64.296036 -240.871502)
			(xy 64.296036 -240.462562) (xy 64.296502 -240.452402) (xy 64.304289 -240.433632) (xy 64.318663 -240.419269)
			(xy 64.337438 -240.411495) (xy 64.347598 -240.411) (xy 65.747138 -240.411) (xy 65.757294 -240.411501)
			(xy 65.776056 -240.419281) (xy 65.790419 -240.433644) (xy 65.798199 -240.452406) (xy 65.7987 -240.462562)
			(xy 65.7987 -240.871502) (xy 162.162236 -240.871502) (xy 162.162236 -240.462562) (xy 162.162702 -240.452402)
			(xy 162.170489 -240.433632) (xy 162.184863 -240.419269) (xy 162.203638 -240.411495) (xy 162.213798 -240.411)
			(xy 163.613338 -240.411) (xy 163.623494 -240.411501) (xy 163.642256 -240.419281) (xy 163.656619 -240.433644)
			(xy 163.664399 -240.452406) (xy 163.6649 -240.462562) (xy 163.6649 -240.871502) (xy 169.706036 -240.871502)
			(xy 169.706036 -240.462562) (xy 169.706502 -240.452402) (xy 169.714289 -240.433632) (xy 169.728663 -240.419269)
			(xy 169.747438 -240.411495) (xy 169.757598 -240.411) (xy 171.157138 -240.411) (xy 171.167294 -240.411501)
			(xy 171.186056 -240.419281) (xy 171.200419 -240.433644) (xy 171.208199 -240.452406) (xy 171.2087 -240.462562)
			(xy 171.2087 -240.871502) (xy 177.249836 -240.871502) (xy 177.249836 -240.462562) (xy 177.250302 -240.452402)
			(xy 177.258089 -240.433632) (xy 177.272463 -240.419269) (xy 177.291238 -240.411495) (xy 177.301398 -240.411)
			(xy 178.700938 -240.411) (xy 178.711094 -240.411501) (xy 178.729856 -240.419281) (xy 178.744219 -240.433644)
			(xy 178.751999 -240.452406) (xy 178.7525 -240.462562) (xy 178.7525 -240.871502) (xy 184.793636 -240.871502)
			(xy 184.793636 -240.462562) (xy 184.794102 -240.452402) (xy 184.801889 -240.433632) (xy 184.816263 -240.419269)
			(xy 184.835038 -240.411495) (xy 184.845198 -240.411) (xy 186.244738 -240.411) (xy 186.254894 -240.411501)
			(xy 186.273656 -240.419281) (xy 186.288019 -240.433644) (xy 186.295799 -240.452406) (xy 186.2963 -240.462562)
			(xy 186.2963 -240.871502) (xy 192.337436 -240.871502) (xy 192.337436 -240.462562) (xy 192.337902 -240.452402)
			(xy 192.345689 -240.433632) (xy 192.360063 -240.419269) (xy 192.378838 -240.411495) (xy 192.388998 -240.411)
			(xy 193.788538 -240.411) (xy 193.798694 -240.411501) (xy 193.817456 -240.419281) (xy 193.831819 -240.433644)
			(xy 193.839599 -240.452406) (xy 193.8401 -240.462562) (xy 193.8401 -240.871502) (xy 199.881236 -240.871502)
			(xy 199.881236 -240.462562) (xy 199.881702 -240.452402) (xy 199.889489 -240.433632) (xy 199.903863 -240.419269)
			(xy 199.922638 -240.411495) (xy 199.932798 -240.411) (xy 201.332338 -240.411) (xy 201.342494 -240.411501)
			(xy 201.361256 -240.419281) (xy 201.375619 -240.433644) (xy 201.383399 -240.452406) (xy 201.3839 -240.462562)
			(xy 201.3839 -240.871502) (xy 207.425036 -240.871502) (xy 207.425036 -240.462562) (xy 207.425502 -240.452402)
			(xy 207.433289 -240.433632) (xy 207.447663 -240.419269) (xy 207.466438 -240.411495) (xy 207.476598 -240.411)
			(xy 208.876138 -240.411) (xy 208.886294 -240.411501) (xy 208.905056 -240.419281) (xy 208.919419 -240.433644)
			(xy 208.927199 -240.452406) (xy 208.9277 -240.462562) (xy 208.9277 -240.871502) (xy 214.968836 -240.871502)
			(xy 214.968836 -240.462562) (xy 214.969302 -240.452402) (xy 214.977089 -240.433632) (xy 214.991463 -240.419269)
			(xy 215.010238 -240.411495) (xy 215.020398 -240.411) (xy 216.419938 -240.411) (xy 216.430094 -240.411501)
			(xy 216.448856 -240.419281) (xy 216.463219 -240.433644) (xy 216.470999 -240.452406) (xy 216.4715 -240.462562)
			(xy 216.4715 -240.871502) (xy 259.429504 -240.871502) (xy 259.429504 -240.462562) (xy 259.430001 -240.452406)
			(xy 259.437782 -240.433642) (xy 259.452146 -240.41928) (xy 259.47091 -240.411501) (xy 259.481066 -240.411)
			(xy 260.880606 -240.411) (xy 260.890759 -240.411528) (xy 260.909521 -240.419297) (xy 260.923885 -240.433652)
			(xy 260.931666 -240.452409) (xy 260.932168 -240.462562) (xy 260.932168 -240.871502) (xy 266.973304 -240.871502)
			(xy 266.973304 -240.462562) (xy 266.973801 -240.452406) (xy 266.981582 -240.433642) (xy 266.995946 -240.41928)
			(xy 267.01471 -240.411501) (xy 267.024866 -240.411) (xy 268.424406 -240.411) (xy 268.434559 -240.411528)
			(xy 268.453321 -240.419297) (xy 268.467685 -240.433652) (xy 268.475466 -240.452409) (xy 268.475968 -240.462562)
			(xy 268.475968 -240.871502) (xy 274.517104 -240.871502) (xy 274.517104 -240.462562) (xy 274.517601 -240.452406)
			(xy 274.525382 -240.433642) (xy 274.539746 -240.41928) (xy 274.55851 -240.411501) (xy 274.568666 -240.411)
			(xy 275.968206 -240.411) (xy 275.978359 -240.411528) (xy 275.997121 -240.419297) (xy 276.011485 -240.433652)
			(xy 276.019266 -240.452409) (xy 276.019768 -240.462562) (xy 276.019768 -240.871502) (xy 282.060904 -240.871502)
			(xy 282.060904 -240.462562) (xy 282.061401 -240.452406) (xy 282.069182 -240.433642) (xy 282.083546 -240.41928)
			(xy 282.10231 -240.411501) (xy 282.112466 -240.411) (xy 283.512006 -240.411) (xy 283.522159 -240.411528)
			(xy 283.540921 -240.419297) (xy 283.555285 -240.433652) (xy 283.563066 -240.452409) (xy 283.563568 -240.462562)
			(xy 283.563568 -240.871502) (xy 289.604704 -240.871502) (xy 289.604704 -240.462562) (xy 289.605201 -240.452406)
			(xy 289.612982 -240.433642) (xy 289.627346 -240.41928) (xy 289.64611 -240.411501) (xy 289.656266 -240.411)
			(xy 291.055806 -240.411) (xy 291.065959 -240.411528) (xy 291.084721 -240.419297) (xy 291.099085 -240.433652)
			(xy 291.106866 -240.452409) (xy 291.107368 -240.462562) (xy 291.107368 -240.871502) (xy 297.148504 -240.871502)
			(xy 297.148504 -240.462562) (xy 297.149001 -240.452406) (xy 297.156782 -240.433642) (xy 297.171146 -240.41928)
			(xy 297.18991 -240.411501) (xy 297.200066 -240.411) (xy 298.599606 -240.411) (xy 298.609759 -240.411528)
			(xy 298.628521 -240.419297) (xy 298.642885 -240.433652) (xy 298.650666 -240.452409) (xy 298.651168 -240.462562)
			(xy 298.651168 -240.871502) (xy 304.692304 -240.871502) (xy 304.692304 -240.462562) (xy 304.692801 -240.452406)
			(xy 304.700582 -240.433642) (xy 304.714946 -240.41928) (xy 304.73371 -240.411501) (xy 304.743866 -240.411)
			(xy 306.143406 -240.411) (xy 306.153559 -240.411528) (xy 306.172321 -240.419297) (xy 306.186685 -240.433652)
			(xy 306.194466 -240.452409) (xy 306.194968 -240.462562) (xy 306.194968 -240.871502) (xy 312.236104 -240.871502)
			(xy 312.236104 -240.462562) (xy 312.236601 -240.452406) (xy 312.244382 -240.433642) (xy 312.258746 -240.41928)
			(xy 312.27751 -240.411501) (xy 312.287666 -240.411) (xy 313.687206 -240.411) (xy 313.697359 -240.411528)
			(xy 313.716121 -240.419297) (xy 313.730485 -240.433652) (xy 313.738266 -240.452409) (xy 313.738768 -240.462562)
			(xy 313.738768 -240.871502) (xy 410.102304 -240.871502) (xy 410.102304 -240.462562) (xy 410.102801 -240.452406)
			(xy 410.110582 -240.433642) (xy 410.124946 -240.41928) (xy 410.14371 -240.411501) (xy 410.153866 -240.411)
			(xy 411.553406 -240.411) (xy 411.563559 -240.411528) (xy 411.582321 -240.419297) (xy 411.596685 -240.433652)
			(xy 411.604466 -240.452409) (xy 411.604968 -240.462562) (xy 411.604968 -240.871502) (xy 417.646104 -240.871502)
			(xy 417.646104 -240.462562) (xy 417.646601 -240.452406) (xy 417.654382 -240.433642) (xy 417.668746 -240.41928)
			(xy 417.68751 -240.411501) (xy 417.697666 -240.411) (xy 419.097206 -240.411) (xy 419.107359 -240.411528)
			(xy 419.126121 -240.419297) (xy 419.140485 -240.433652) (xy 419.148266 -240.452409) (xy 419.148768 -240.462562)
			(xy 419.148768 -240.871502) (xy 425.189904 -240.871502) (xy 425.189904 -240.462562) (xy 425.190401 -240.452406)
			(xy 425.198182 -240.433642) (xy 425.212546 -240.41928) (xy 425.23131 -240.411501) (xy 425.241466 -240.411)
			(xy 426.641006 -240.411) (xy 426.651159 -240.411528) (xy 426.669921 -240.419297) (xy 426.684285 -240.433652)
			(xy 426.692066 -240.452409) (xy 426.692568 -240.462562) (xy 426.692568 -240.871502) (xy 432.733704 -240.871502)
			(xy 432.733704 -240.462562) (xy 432.734201 -240.452406) (xy 432.741982 -240.433642) (xy 432.756346 -240.41928)
			(xy 432.77511 -240.411501) (xy 432.785266 -240.411) (xy 434.184806 -240.411) (xy 434.194959 -240.411528)
			(xy 434.213721 -240.419297) (xy 434.228085 -240.433652) (xy 434.235866 -240.452409) (xy 434.236368 -240.462562)
			(xy 434.236368 -240.871502) (xy 440.277504 -240.871502) (xy 440.277504 -240.462562) (xy 440.278001 -240.452406)
			(xy 440.285782 -240.433642) (xy 440.300146 -240.41928) (xy 440.31891 -240.411501) (xy 440.329066 -240.411)
			(xy 441.728606 -240.411) (xy 441.738759 -240.411528) (xy 441.757521 -240.419297) (xy 441.771885 -240.433652)
			(xy 441.779666 -240.452409) (xy 441.780168 -240.462562) (xy 441.780168 -240.871502) (xy 447.821304 -240.871502)
			(xy 447.821304 -240.462562) (xy 447.821801 -240.452406) (xy 447.829582 -240.433642) (xy 447.843946 -240.41928)
			(xy 447.86271 -240.411501) (xy 447.872866 -240.411) (xy 449.272406 -240.411) (xy 449.282559 -240.411528)
			(xy 449.301321 -240.419297) (xy 449.315685 -240.433652) (xy 449.323466 -240.452409) (xy 449.323968 -240.462562)
			(xy 449.323968 -240.871502) (xy 455.365104 -240.871502) (xy 455.365104 -240.462562) (xy 455.365601 -240.452406)
			(xy 455.373382 -240.433642) (xy 455.387746 -240.41928) (xy 455.40651 -240.411501) (xy 455.416666 -240.411)
			(xy 456.816206 -240.411) (xy 456.826359 -240.411528) (xy 456.845121 -240.419297) (xy 456.859485 -240.433652)
			(xy 456.867266 -240.452409) (xy 456.867768 -240.462562) (xy 456.867768 -240.871502) (xy 462.908904 -240.871502)
			(xy 462.908904 -240.462562) (xy 462.909401 -240.452406) (xy 462.917182 -240.433642) (xy 462.931546 -240.41928)
			(xy 462.95031 -240.411501) (xy 462.960466 -240.411) (xy 464.360006 -240.411) (xy 464.370159 -240.411528)
			(xy 464.388921 -240.419297) (xy 464.403285 -240.433652) (xy 464.411066 -240.452409) (xy 464.411568 -240.462562)
			(xy 464.411568 -240.871502) (xy 464.411068 -240.881659) (xy 464.403294 -240.900427) (xy 464.388931 -240.914792)
			(xy 464.370163 -240.922568) (xy 464.360006 -240.923064) (xy 462.960466 -240.923064) (xy 462.950306 -240.922595)
			(xy 462.931537 -240.914809) (xy 462.917173 -240.900436) (xy 462.909399 -240.881662) (xy 462.908904 -240.871502)
			(xy 456.867768 -240.871502) (xy 456.867268 -240.881659) (xy 456.859494 -240.900427) (xy 456.845131 -240.914792)
			(xy 456.826363 -240.922568) (xy 456.816206 -240.923064) (xy 455.416666 -240.923064) (xy 455.406506 -240.922595)
			(xy 455.387737 -240.914809) (xy 455.373373 -240.900436) (xy 455.365599 -240.881662) (xy 455.365104 -240.871502)
			(xy 449.323968 -240.871502) (xy 449.323468 -240.881659) (xy 449.315694 -240.900427) (xy 449.301331 -240.914792)
			(xy 449.282563 -240.922568) (xy 449.272406 -240.923064) (xy 447.872866 -240.923064) (xy 447.862706 -240.922595)
			(xy 447.843937 -240.914809) (xy 447.829573 -240.900436) (xy 447.821799 -240.881662) (xy 447.821304 -240.871502)
			(xy 441.780168 -240.871502) (xy 441.779668 -240.881659) (xy 441.771894 -240.900427) (xy 441.757531 -240.914792)
			(xy 441.738763 -240.922568) (xy 441.728606 -240.923064) (xy 440.329066 -240.923064) (xy 440.318906 -240.922595)
			(xy 440.300137 -240.914809) (xy 440.285773 -240.900436) (xy 440.277999 -240.881662) (xy 440.277504 -240.871502)
			(xy 434.236368 -240.871502) (xy 434.235868 -240.881659) (xy 434.228094 -240.900427) (xy 434.213731 -240.914792)
			(xy 434.194963 -240.922568) (xy 434.184806 -240.923064) (xy 432.785266 -240.923064) (xy 432.775106 -240.922595)
			(xy 432.756337 -240.914809) (xy 432.741973 -240.900436) (xy 432.734199 -240.881662) (xy 432.733704 -240.871502)
			(xy 426.692568 -240.871502) (xy 426.692068 -240.881659) (xy 426.684294 -240.900427) (xy 426.669931 -240.914792)
			(xy 426.651163 -240.922568) (xy 426.641006 -240.923064) (xy 425.241466 -240.923064) (xy 425.231306 -240.922595)
			(xy 425.212537 -240.914809) (xy 425.198173 -240.900436) (xy 425.190399 -240.881662) (xy 425.189904 -240.871502)
			(xy 419.148768 -240.871502) (xy 419.148268 -240.881659) (xy 419.140494 -240.900427) (xy 419.126131 -240.914792)
			(xy 419.107363 -240.922568) (xy 419.097206 -240.923064) (xy 417.697666 -240.923064) (xy 417.687506 -240.922595)
			(xy 417.668737 -240.914809) (xy 417.654373 -240.900436) (xy 417.646599 -240.881662) (xy 417.646104 -240.871502)
			(xy 411.604968 -240.871502) (xy 411.604468 -240.881659) (xy 411.596694 -240.900427) (xy 411.582331 -240.914792)
			(xy 411.563563 -240.922568) (xy 411.553406 -240.923064) (xy 410.153866 -240.923064) (xy 410.143706 -240.922595)
			(xy 410.124937 -240.914809) (xy 410.110573 -240.900436) (xy 410.102799 -240.881662) (xy 410.102304 -240.871502)
			(xy 313.738768 -240.871502) (xy 313.738268 -240.881659) (xy 313.730494 -240.900427) (xy 313.716131 -240.914792)
			(xy 313.697363 -240.922568) (xy 313.687206 -240.923064) (xy 312.287666 -240.923064) (xy 312.277506 -240.922595)
			(xy 312.258737 -240.914809) (xy 312.244373 -240.900436) (xy 312.236599 -240.881662) (xy 312.236104 -240.871502)
			(xy 306.194968 -240.871502) (xy 306.194468 -240.881659) (xy 306.186694 -240.900427) (xy 306.172331 -240.914792)
			(xy 306.153563 -240.922568) (xy 306.143406 -240.923064) (xy 304.743866 -240.923064) (xy 304.733706 -240.922595)
			(xy 304.714937 -240.914809) (xy 304.700573 -240.900436) (xy 304.692799 -240.881662) (xy 304.692304 -240.871502)
			(xy 298.651168 -240.871502) (xy 298.650668 -240.881659) (xy 298.642894 -240.900427) (xy 298.628531 -240.914792)
			(xy 298.609763 -240.922568) (xy 298.599606 -240.923064) (xy 297.200066 -240.923064) (xy 297.189906 -240.922595)
			(xy 297.171137 -240.914809) (xy 297.156773 -240.900436) (xy 297.148999 -240.881662) (xy 297.148504 -240.871502)
			(xy 291.107368 -240.871502) (xy 291.106868 -240.881659) (xy 291.099094 -240.900427) (xy 291.084731 -240.914792)
			(xy 291.065963 -240.922568) (xy 291.055806 -240.923064) (xy 289.656266 -240.923064) (xy 289.646106 -240.922595)
			(xy 289.627337 -240.914809) (xy 289.612973 -240.900436) (xy 289.605199 -240.881662) (xy 289.604704 -240.871502)
			(xy 283.563568 -240.871502) (xy 283.563068 -240.881659) (xy 283.555294 -240.900427) (xy 283.540931 -240.914792)
			(xy 283.522163 -240.922568) (xy 283.512006 -240.923064) (xy 282.112466 -240.923064) (xy 282.102306 -240.922595)
			(xy 282.083537 -240.914809) (xy 282.069173 -240.900436) (xy 282.061399 -240.881662) (xy 282.060904 -240.871502)
			(xy 276.019768 -240.871502) (xy 276.019268 -240.881659) (xy 276.011494 -240.900427) (xy 275.997131 -240.914792)
			(xy 275.978363 -240.922568) (xy 275.968206 -240.923064) (xy 274.568666 -240.923064) (xy 274.558506 -240.922595)
			(xy 274.539737 -240.914809) (xy 274.525373 -240.900436) (xy 274.517599 -240.881662) (xy 274.517104 -240.871502)
			(xy 268.475968 -240.871502) (xy 268.475468 -240.881659) (xy 268.467694 -240.900427) (xy 268.453331 -240.914792)
			(xy 268.434563 -240.922568) (xy 268.424406 -240.923064) (xy 267.024866 -240.923064) (xy 267.014706 -240.922595)
			(xy 266.995937 -240.914809) (xy 266.981573 -240.900436) (xy 266.973799 -240.881662) (xy 266.973304 -240.871502)
			(xy 260.932168 -240.871502) (xy 260.931668 -240.881659) (xy 260.923894 -240.900427) (xy 260.909531 -240.914792)
			(xy 260.890763 -240.922568) (xy 260.880606 -240.923064) (xy 259.481066 -240.923064) (xy 259.470906 -240.922595)
			(xy 259.452137 -240.914809) (xy 259.437773 -240.900436) (xy 259.429999 -240.881662) (xy 259.429504 -240.871502)
			(xy 216.4715 -240.871502) (xy 216.470969 -240.881655) (xy 216.463201 -240.900417) (xy 216.448847 -240.914781)
			(xy 216.430091 -240.922562) (xy 216.419938 -240.923064) (xy 215.020398 -240.923064) (xy 215.01024 -240.922568)
			(xy 214.991472 -240.914794) (xy 214.977106 -240.900428) (xy 214.969332 -240.88166) (xy 214.968836 -240.871502)
			(xy 208.9277 -240.871502) (xy 208.927169 -240.881655) (xy 208.919401 -240.900417) (xy 208.905047 -240.914781)
			(xy 208.886291 -240.922562) (xy 208.876138 -240.923064) (xy 207.476598 -240.923064) (xy 207.46644 -240.922568)
			(xy 207.447672 -240.914794) (xy 207.433306 -240.900428) (xy 207.425532 -240.88166) (xy 207.425036 -240.871502)
			(xy 201.3839 -240.871502) (xy 201.383369 -240.881655) (xy 201.375601 -240.900417) (xy 201.361247 -240.914781)
			(xy 201.342491 -240.922562) (xy 201.332338 -240.923064) (xy 199.932798 -240.923064) (xy 199.92264 -240.922568)
			(xy 199.903872 -240.914794) (xy 199.889506 -240.900428) (xy 199.881732 -240.88166) (xy 199.881236 -240.871502)
			(xy 193.8401 -240.871502) (xy 193.839569 -240.881655) (xy 193.831801 -240.900417) (xy 193.817447 -240.914781)
			(xy 193.798691 -240.922562) (xy 193.788538 -240.923064) (xy 192.388998 -240.923064) (xy 192.37884 -240.922568)
			(xy 192.360072 -240.914794) (xy 192.345706 -240.900428) (xy 192.337932 -240.88166) (xy 192.337436 -240.871502)
			(xy 186.2963 -240.871502) (xy 186.295769 -240.881655) (xy 186.288001 -240.900417) (xy 186.273647 -240.914781)
			(xy 186.254891 -240.922562) (xy 186.244738 -240.923064) (xy 184.845198 -240.923064) (xy 184.83504 -240.922568)
			(xy 184.816272 -240.914794) (xy 184.801906 -240.900428) (xy 184.794132 -240.88166) (xy 184.793636 -240.871502)
			(xy 178.7525 -240.871502) (xy 178.751969 -240.881655) (xy 178.744201 -240.900417) (xy 178.729847 -240.914781)
			(xy 178.711091 -240.922562) (xy 178.700938 -240.923064) (xy 177.301398 -240.923064) (xy 177.29124 -240.922568)
			(xy 177.272472 -240.914794) (xy 177.258106 -240.900428) (xy 177.250332 -240.88166) (xy 177.249836 -240.871502)
			(xy 171.2087 -240.871502) (xy 171.208169 -240.881655) (xy 171.200401 -240.900417) (xy 171.186047 -240.914781)
			(xy 171.167291 -240.922562) (xy 171.157138 -240.923064) (xy 169.757598 -240.923064) (xy 169.74744 -240.922568)
			(xy 169.728672 -240.914794) (xy 169.714306 -240.900428) (xy 169.706532 -240.88166) (xy 169.706036 -240.871502)
			(xy 163.6649 -240.871502) (xy 163.664369 -240.881655) (xy 163.656601 -240.900417) (xy 163.642247 -240.914781)
			(xy 163.623491 -240.922562) (xy 163.613338 -240.923064) (xy 162.213798 -240.923064) (xy 162.20364 -240.922568)
			(xy 162.184872 -240.914794) (xy 162.170506 -240.900428) (xy 162.162732 -240.88166) (xy 162.162236 -240.871502)
			(xy 65.7987 -240.871502) (xy 65.798169 -240.881655) (xy 65.790401 -240.900417) (xy 65.776047 -240.914781)
			(xy 65.757291 -240.922562) (xy 65.747138 -240.923064) (xy 64.347598 -240.923064) (xy 64.33744 -240.922568)
			(xy 64.318672 -240.914794) (xy 64.304306 -240.900428) (xy 64.296532 -240.88166) (xy 64.296036 -240.871502)
			(xy 58.2549 -240.871502) (xy 58.254369 -240.881655) (xy 58.246601 -240.900417) (xy 58.232247 -240.914781)
			(xy 58.213491 -240.922562) (xy 58.203338 -240.923064) (xy 56.803798 -240.923064) (xy 56.79364 -240.922568)
			(xy 56.774872 -240.914794) (xy 56.760506 -240.900428) (xy 56.752732 -240.88166) (xy 56.752236 -240.871502)
			(xy 50.7111 -240.871502) (xy 50.710569 -240.881655) (xy 50.702801 -240.900417) (xy 50.688447 -240.914781)
			(xy 50.669691 -240.922562) (xy 50.659538 -240.923064) (xy 49.259998 -240.923064) (xy 49.24984 -240.922568)
			(xy 49.231072 -240.914794) (xy 49.216706 -240.900428) (xy 49.208932 -240.88166) (xy 49.208436 -240.871502)
			(xy 43.1673 -240.871502) (xy 43.166769 -240.881655) (xy 43.159001 -240.900417) (xy 43.144647 -240.914781)
			(xy 43.125891 -240.922562) (xy 43.115738 -240.923064) (xy 41.716198 -240.923064) (xy 41.70604 -240.922568)
			(xy 41.687272 -240.914794) (xy 41.672906 -240.900428) (xy 41.665132 -240.88166) (xy 41.664636 -240.871502)
			(xy 35.6235 -240.871502) (xy 35.622969 -240.881655) (xy 35.615201 -240.900417) (xy 35.600847 -240.914781)
			(xy 35.582091 -240.922562) (xy 35.571938 -240.923064) (xy 34.172398 -240.923064) (xy 34.16224 -240.922568)
			(xy 34.143472 -240.914794) (xy 34.129106 -240.900428) (xy 34.121332 -240.88166) (xy 34.120836 -240.871502)
			(xy 28.0797 -240.871502) (xy 28.079169 -240.881655) (xy 28.071401 -240.900417) (xy 28.057047 -240.914781)
			(xy 28.038291 -240.922562) (xy 28.028138 -240.923064) (xy 26.628598 -240.923064) (xy 26.61844 -240.922568)
			(xy 26.599672 -240.914794) (xy 26.585306 -240.900428) (xy 26.577532 -240.88166) (xy 26.577036 -240.871502)
			(xy 20.5359 -240.871502) (xy 20.535369 -240.881655) (xy 20.527601 -240.900417) (xy 20.513247 -240.914781)
			(xy 20.494491 -240.922562) (xy 20.484338 -240.923064) (xy 19.084798 -240.923064) (xy 19.07464 -240.922568)
			(xy 19.055872 -240.914794) (xy 19.041506 -240.900428) (xy 19.033732 -240.88166) (xy 19.033236 -240.871502)
			(xy 12.9921 -240.871502) (xy 12.991569 -240.881655) (xy 12.983801 -240.900417) (xy 12.969447 -240.914781)
			(xy 12.950691 -240.922562) (xy 12.940538 -240.923064) (xy 11.540998 -240.923064) (xy 11.53084 -240.922568)
			(xy 11.512072 -240.914794) (xy 11.497706 -240.900428) (xy 11.489932 -240.88166) (xy 11.489436 -240.871502)
			(xy 2.509012 -240.871502) (xy 2.509012 -241.721386) (xy 7.389368 -241.721386) (xy 7.389368 -241.312446)
			(xy 7.389802 -241.302274) (xy 7.397578 -241.283474) (xy 7.411961 -241.269087) (xy 7.430758 -241.261305)
			(xy 7.44093 -241.260884) (xy 8.84047 -241.260884) (xy 8.850645 -241.26129) (xy 8.869448 -241.269073)
			(xy 8.883836 -241.283465) (xy 8.891613 -241.302271) (xy 8.892032 -241.312446) (xy 8.892032 -241.721386)
			(xy 14.933168 -241.721386) (xy 14.933168 -241.312446) (xy 14.933602 -241.302274) (xy 14.941378 -241.283474)
			(xy 14.955761 -241.269087) (xy 14.974558 -241.261305) (xy 14.98473 -241.260884) (xy 16.38427 -241.260884)
			(xy 16.394445 -241.26129) (xy 16.413248 -241.269073) (xy 16.427636 -241.283465) (xy 16.435413 -241.302271)
			(xy 16.435832 -241.312446) (xy 16.435832 -241.721386) (xy 22.476968 -241.721386) (xy 22.476968 -241.312446)
			(xy 22.477402 -241.302274) (xy 22.485178 -241.283474) (xy 22.499561 -241.269087) (xy 22.518358 -241.261305)
			(xy 22.52853 -241.260884) (xy 23.92807 -241.260884) (xy 23.938245 -241.26129) (xy 23.957048 -241.269073)
			(xy 23.971436 -241.283465) (xy 23.979213 -241.302271) (xy 23.979632 -241.312446) (xy 23.979632 -241.721386)
			(xy 30.020768 -241.721386) (xy 30.020768 -241.312446) (xy 30.021202 -241.302274) (xy 30.028978 -241.283474)
			(xy 30.043361 -241.269087) (xy 30.062158 -241.261305) (xy 30.07233 -241.260884) (xy 31.47187 -241.260884)
			(xy 31.482045 -241.26129) (xy 31.500848 -241.269073) (xy 31.515236 -241.283465) (xy 31.523013 -241.302271)
			(xy 31.523432 -241.312446) (xy 31.523432 -241.721386) (xy 37.564568 -241.721386) (xy 37.564568 -241.312446)
			(xy 37.565002 -241.302274) (xy 37.572778 -241.283474) (xy 37.587161 -241.269087) (xy 37.605958 -241.261305)
			(xy 37.61613 -241.260884) (xy 39.01567 -241.260884) (xy 39.025845 -241.26129) (xy 39.044648 -241.269073)
			(xy 39.059036 -241.283465) (xy 39.066813 -241.302271) (xy 39.067232 -241.312446) (xy 39.067232 -241.721386)
			(xy 45.108368 -241.721386) (xy 45.108368 -241.312446) (xy 45.108802 -241.302274) (xy 45.116578 -241.283474)
			(xy 45.130961 -241.269087) (xy 45.149758 -241.261305) (xy 45.15993 -241.260884) (xy 46.55947 -241.260884)
			(xy 46.569645 -241.26129) (xy 46.588448 -241.269073) (xy 46.602836 -241.283465) (xy 46.610613 -241.302271)
			(xy 46.611032 -241.312446) (xy 46.611032 -241.721386) (xy 52.652168 -241.721386) (xy 52.652168 -241.312446)
			(xy 52.652602 -241.302274) (xy 52.660378 -241.283474) (xy 52.674761 -241.269087) (xy 52.693558 -241.261305)
			(xy 52.70373 -241.260884) (xy 54.10327 -241.260884) (xy 54.113445 -241.26129) (xy 54.132248 -241.269073)
			(xy 54.146636 -241.283465) (xy 54.154413 -241.302271) (xy 54.154832 -241.312446) (xy 54.154832 -241.721386)
			(xy 60.195968 -241.721386) (xy 60.195968 -241.312446) (xy 60.196402 -241.302274) (xy 60.204178 -241.283474)
			(xy 60.218561 -241.269087) (xy 60.237358 -241.261305) (xy 60.24753 -241.260884) (xy 61.64707 -241.260884)
			(xy 61.657245 -241.26129) (xy 61.676048 -241.269073) (xy 61.690436 -241.283465) (xy 61.698213 -241.302271)
			(xy 61.698632 -241.312446) (xy 61.698632 -241.721386) (xy 158.062168 -241.721386) (xy 158.062168 -241.312446)
			(xy 158.062602 -241.302274) (xy 158.070378 -241.283474) (xy 158.084761 -241.269087) (xy 158.103558 -241.261305)
			(xy 158.11373 -241.260884) (xy 159.51327 -241.260884) (xy 159.523445 -241.26129) (xy 159.542248 -241.269073)
			(xy 159.556636 -241.283465) (xy 159.564413 -241.302271) (xy 159.564832 -241.312446) (xy 159.564832 -241.721386)
			(xy 165.605968 -241.721386) (xy 165.605968 -241.312446) (xy 165.606402 -241.302274) (xy 165.614178 -241.283474)
			(xy 165.628561 -241.269087) (xy 165.647358 -241.261305) (xy 165.65753 -241.260884) (xy 167.05707 -241.260884)
			(xy 167.067245 -241.26129) (xy 167.086048 -241.269073) (xy 167.100436 -241.283465) (xy 167.108213 -241.302271)
			(xy 167.108632 -241.312446) (xy 167.108632 -241.721386) (xy 173.149768 -241.721386) (xy 173.149768 -241.312446)
			(xy 173.150202 -241.302274) (xy 173.157978 -241.283474) (xy 173.172361 -241.269087) (xy 173.191158 -241.261305)
			(xy 173.20133 -241.260884) (xy 174.60087 -241.260884) (xy 174.611045 -241.26129) (xy 174.629848 -241.269073)
			(xy 174.644236 -241.283465) (xy 174.652013 -241.302271) (xy 174.652432 -241.312446) (xy 174.652432 -241.721386)
			(xy 180.693568 -241.721386) (xy 180.693568 -241.312446) (xy 180.694002 -241.302274) (xy 180.701778 -241.283474)
			(xy 180.716161 -241.269087) (xy 180.734958 -241.261305) (xy 180.74513 -241.260884) (xy 182.14467 -241.260884)
			(xy 182.154845 -241.26129) (xy 182.173648 -241.269073) (xy 182.188036 -241.283465) (xy 182.195813 -241.302271)
			(xy 182.196232 -241.312446) (xy 182.196232 -241.721386) (xy 188.237368 -241.721386) (xy 188.237368 -241.312446)
			(xy 188.237802 -241.302274) (xy 188.245578 -241.283474) (xy 188.259961 -241.269087) (xy 188.278758 -241.261305)
			(xy 188.28893 -241.260884) (xy 189.68847 -241.260884) (xy 189.698645 -241.26129) (xy 189.717448 -241.269073)
			(xy 189.731836 -241.283465) (xy 189.739613 -241.302271) (xy 189.740032 -241.312446) (xy 189.740032 -241.721386)
			(xy 195.781168 -241.721386) (xy 195.781168 -241.312446) (xy 195.781602 -241.302274) (xy 195.789378 -241.283474)
			(xy 195.803761 -241.269087) (xy 195.822558 -241.261305) (xy 195.83273 -241.260884) (xy 197.23227 -241.260884)
			(xy 197.242445 -241.26129) (xy 197.261248 -241.269073) (xy 197.275636 -241.283465) (xy 197.283413 -241.302271)
			(xy 197.283832 -241.312446) (xy 197.283832 -241.721386) (xy 203.324968 -241.721386) (xy 203.324968 -241.312446)
			(xy 203.325402 -241.302274) (xy 203.333178 -241.283474) (xy 203.347561 -241.269087) (xy 203.366358 -241.261305)
			(xy 203.37653 -241.260884) (xy 204.77607 -241.260884) (xy 204.786245 -241.26129) (xy 204.805048 -241.269073)
			(xy 204.819436 -241.283465) (xy 204.827213 -241.302271) (xy 204.827632 -241.312446) (xy 204.827632 -241.721386)
			(xy 210.868768 -241.721386) (xy 210.868768 -241.312446) (xy 210.869202 -241.302274) (xy 210.876978 -241.283474)
			(xy 210.891361 -241.269087) (xy 210.910158 -241.261305) (xy 210.92033 -241.260884) (xy 212.31987 -241.260884)
			(xy 212.330045 -241.26129) (xy 212.348848 -241.269073) (xy 212.363236 -241.283465) (xy 212.371013 -241.302271)
			(xy 212.371432 -241.312446) (xy 212.371432 -241.721386) (xy 255.329436 -241.721386) (xy 255.329436 -241.312446)
			(xy 255.329901 -241.302278) (xy 255.337671 -241.283484) (xy 255.352044 -241.269098) (xy 255.37083 -241.261311)
			(xy 255.380998 -241.260884) (xy 256.780538 -241.260884) (xy 256.790718 -241.261234) (xy 256.809522 -241.26904)
			(xy 256.823907 -241.283448) (xy 256.831683 -241.302266) (xy 256.8321 -241.312446) (xy 256.8321 -241.721386)
			(xy 262.873236 -241.721386) (xy 262.873236 -241.312446) (xy 262.873701 -241.302278) (xy 262.881471 -241.283484)
			(xy 262.895844 -241.269098) (xy 262.91463 -241.261311) (xy 262.924798 -241.260884) (xy 264.324338 -241.260884)
			(xy 264.334518 -241.261234) (xy 264.353322 -241.26904) (xy 264.367707 -241.283448) (xy 264.375483 -241.302266)
			(xy 264.3759 -241.312446) (xy 264.3759 -241.721386) (xy 270.417036 -241.721386) (xy 270.417036 -241.312446)
			(xy 270.417501 -241.302278) (xy 270.425271 -241.283484) (xy 270.439644 -241.269098) (xy 270.45843 -241.261311)
			(xy 270.468598 -241.260884) (xy 271.868138 -241.260884) (xy 271.878318 -241.261234) (xy 271.897122 -241.26904)
			(xy 271.911507 -241.283448) (xy 271.919283 -241.302266) (xy 271.9197 -241.312446) (xy 271.9197 -241.721386)
			(xy 277.960836 -241.721386) (xy 277.960836 -241.312446) (xy 277.961301 -241.302278) (xy 277.969071 -241.283484)
			(xy 277.983444 -241.269098) (xy 278.00223 -241.261311) (xy 278.012398 -241.260884) (xy 279.411938 -241.260884)
			(xy 279.422118 -241.261234) (xy 279.440922 -241.26904) (xy 279.455307 -241.283448) (xy 279.463083 -241.302266)
			(xy 279.4635 -241.312446) (xy 279.4635 -241.721386) (xy 285.504636 -241.721386) (xy 285.504636 -241.312446)
			(xy 285.505101 -241.302278) (xy 285.512871 -241.283484) (xy 285.527244 -241.269098) (xy 285.54603 -241.261311)
			(xy 285.556198 -241.260884) (xy 286.955738 -241.260884) (xy 286.965918 -241.261234) (xy 286.984722 -241.26904)
			(xy 286.999107 -241.283448) (xy 287.006883 -241.302266) (xy 287.0073 -241.312446) (xy 287.0073 -241.721386)
			(xy 293.048436 -241.721386) (xy 293.048436 -241.312446) (xy 293.048901 -241.302278) (xy 293.056671 -241.283484)
			(xy 293.071044 -241.269098) (xy 293.08983 -241.261311) (xy 293.099998 -241.260884) (xy 294.499538 -241.260884)
			(xy 294.509718 -241.261234) (xy 294.528522 -241.26904) (xy 294.542907 -241.283448) (xy 294.550683 -241.302266)
			(xy 294.5511 -241.312446) (xy 294.5511 -241.721386) (xy 300.592236 -241.721386) (xy 300.592236 -241.312446)
			(xy 300.592701 -241.302278) (xy 300.600471 -241.283484) (xy 300.614844 -241.269098) (xy 300.63363 -241.261311)
			(xy 300.643798 -241.260884) (xy 302.043338 -241.260884) (xy 302.053518 -241.261234) (xy 302.072322 -241.26904)
			(xy 302.086707 -241.283448) (xy 302.094483 -241.302266) (xy 302.0949 -241.312446) (xy 302.0949 -241.721386)
			(xy 308.136036 -241.721386) (xy 308.136036 -241.312446) (xy 308.136501 -241.302278) (xy 308.144271 -241.283484)
			(xy 308.158644 -241.269098) (xy 308.17743 -241.261311) (xy 308.187598 -241.260884) (xy 309.587138 -241.260884)
			(xy 309.597318 -241.261234) (xy 309.616122 -241.26904) (xy 309.630507 -241.283448) (xy 309.638283 -241.302266)
			(xy 309.6387 -241.312446) (xy 309.6387 -241.721386) (xy 406.002236 -241.721386) (xy 406.002236 -241.312446)
			(xy 406.002701 -241.302278) (xy 406.010471 -241.283484) (xy 406.024844 -241.269098) (xy 406.04363 -241.261311)
			(xy 406.053798 -241.260884) (xy 407.453338 -241.260884) (xy 407.463518 -241.261234) (xy 407.482322 -241.26904)
			(xy 407.496707 -241.283448) (xy 407.504483 -241.302266) (xy 407.5049 -241.312446) (xy 407.5049 -241.721386)
			(xy 413.546036 -241.721386) (xy 413.546036 -241.312446) (xy 413.546501 -241.302278) (xy 413.554271 -241.283484)
			(xy 413.568644 -241.269098) (xy 413.58743 -241.261311) (xy 413.597598 -241.260884) (xy 414.997138 -241.260884)
			(xy 415.007318 -241.261234) (xy 415.026122 -241.26904) (xy 415.040507 -241.283448) (xy 415.048283 -241.302266)
			(xy 415.0487 -241.312446) (xy 415.0487 -241.721386) (xy 421.089836 -241.721386) (xy 421.089836 -241.312446)
			(xy 421.090301 -241.302278) (xy 421.098071 -241.283484) (xy 421.112444 -241.269098) (xy 421.13123 -241.261311)
			(xy 421.141398 -241.260884) (xy 422.540938 -241.260884) (xy 422.551118 -241.261234) (xy 422.569922 -241.26904)
			(xy 422.584307 -241.283448) (xy 422.592083 -241.302266) (xy 422.5925 -241.312446) (xy 422.5925 -241.721386)
			(xy 428.633636 -241.721386) (xy 428.633636 -241.312446) (xy 428.634101 -241.302278) (xy 428.641871 -241.283484)
			(xy 428.656244 -241.269098) (xy 428.67503 -241.261311) (xy 428.685198 -241.260884) (xy 430.084738 -241.260884)
			(xy 430.094918 -241.261234) (xy 430.113722 -241.26904) (xy 430.128107 -241.283448) (xy 430.135883 -241.302266)
			(xy 430.1363 -241.312446) (xy 430.1363 -241.721386) (xy 436.177436 -241.721386) (xy 436.177436 -241.312446)
			(xy 436.177901 -241.302278) (xy 436.185671 -241.283484) (xy 436.200044 -241.269098) (xy 436.21883 -241.261311)
			(xy 436.228998 -241.260884) (xy 437.628538 -241.260884) (xy 437.638718 -241.261234) (xy 437.657522 -241.26904)
			(xy 437.671907 -241.283448) (xy 437.679683 -241.302266) (xy 437.6801 -241.312446) (xy 437.6801 -241.721386)
			(xy 443.721236 -241.721386) (xy 443.721236 -241.312446) (xy 443.721701 -241.302278) (xy 443.729471 -241.283484)
			(xy 443.743844 -241.269098) (xy 443.76263 -241.261311) (xy 443.772798 -241.260884) (xy 445.172338 -241.260884)
			(xy 445.182518 -241.261234) (xy 445.201322 -241.26904) (xy 445.215707 -241.283448) (xy 445.223483 -241.302266)
			(xy 445.2239 -241.312446) (xy 445.2239 -241.721386) (xy 451.265036 -241.721386) (xy 451.265036 -241.312446)
			(xy 451.265501 -241.302278) (xy 451.273271 -241.283484) (xy 451.287644 -241.269098) (xy 451.30643 -241.261311)
			(xy 451.316598 -241.260884) (xy 452.716138 -241.260884) (xy 452.726318 -241.261234) (xy 452.745122 -241.26904)
			(xy 452.759507 -241.283448) (xy 452.767283 -241.302266) (xy 452.7677 -241.312446) (xy 452.7677 -241.721386)
			(xy 458.808836 -241.721386) (xy 458.808836 -241.312446) (xy 458.809301 -241.302278) (xy 458.817071 -241.283484)
			(xy 458.831444 -241.269098) (xy 458.85023 -241.261311) (xy 458.860398 -241.260884) (xy 460.259938 -241.260884)
			(xy 460.270118 -241.261234) (xy 460.288922 -241.26904) (xy 460.303307 -241.283448) (xy 460.311083 -241.302266)
			(xy 460.3115 -241.312446) (xy 460.3115 -241.721386) (xy 460.310956 -241.731538) (xy 460.303193 -241.7503)
			(xy 460.288843 -241.764664) (xy 460.27009 -241.772446) (xy 460.259938 -241.772948) (xy 458.860398 -241.772948)
			(xy 458.850225 -241.772537) (xy 458.831427 -241.764749) (xy 458.817042 -241.750359) (xy 458.809259 -241.73156)
			(xy 458.808836 -241.721386) (xy 452.7677 -241.721386) (xy 452.767156 -241.731538) (xy 452.759393 -241.7503)
			(xy 452.745043 -241.764664) (xy 452.72629 -241.772446) (xy 452.716138 -241.772948) (xy 451.316598 -241.772948)
			(xy 451.306425 -241.772537) (xy 451.287627 -241.764749) (xy 451.273242 -241.750359) (xy 451.265459 -241.73156)
			(xy 451.265036 -241.721386) (xy 445.2239 -241.721386) (xy 445.223356 -241.731538) (xy 445.215593 -241.7503)
			(xy 445.201243 -241.764664) (xy 445.18249 -241.772446) (xy 445.172338 -241.772948) (xy 443.772798 -241.772948)
			(xy 443.762625 -241.772537) (xy 443.743827 -241.764749) (xy 443.729442 -241.750359) (xy 443.721659 -241.73156)
			(xy 443.721236 -241.721386) (xy 437.6801 -241.721386) (xy 437.679556 -241.731538) (xy 437.671793 -241.7503)
			(xy 437.657443 -241.764664) (xy 437.63869 -241.772446) (xy 437.628538 -241.772948) (xy 436.228998 -241.772948)
			(xy 436.218825 -241.772537) (xy 436.200027 -241.764749) (xy 436.185642 -241.750359) (xy 436.177859 -241.73156)
			(xy 436.177436 -241.721386) (xy 430.1363 -241.721386) (xy 430.135756 -241.731538) (xy 430.127993 -241.7503)
			(xy 430.113643 -241.764664) (xy 430.09489 -241.772446) (xy 430.084738 -241.772948) (xy 428.685198 -241.772948)
			(xy 428.675025 -241.772537) (xy 428.656227 -241.764749) (xy 428.641842 -241.750359) (xy 428.634059 -241.73156)
			(xy 428.633636 -241.721386) (xy 422.5925 -241.721386) (xy 422.591956 -241.731538) (xy 422.584193 -241.7503)
			(xy 422.569843 -241.764664) (xy 422.55109 -241.772446) (xy 422.540938 -241.772948) (xy 421.141398 -241.772948)
			(xy 421.131225 -241.772537) (xy 421.112427 -241.764749) (xy 421.098042 -241.750359) (xy 421.090259 -241.73156)
			(xy 421.089836 -241.721386) (xy 415.0487 -241.721386) (xy 415.048156 -241.731538) (xy 415.040393 -241.7503)
			(xy 415.026043 -241.764664) (xy 415.00729 -241.772446) (xy 414.997138 -241.772948) (xy 413.597598 -241.772948)
			(xy 413.587425 -241.772537) (xy 413.568627 -241.764749) (xy 413.554242 -241.750359) (xy 413.546459 -241.73156)
			(xy 413.546036 -241.721386) (xy 407.5049 -241.721386) (xy 407.504356 -241.731538) (xy 407.496593 -241.7503)
			(xy 407.482243 -241.764664) (xy 407.46349 -241.772446) (xy 407.453338 -241.772948) (xy 406.053798 -241.772948)
			(xy 406.043625 -241.772537) (xy 406.024827 -241.764749) (xy 406.010442 -241.750359) (xy 406.002659 -241.73156)
			(xy 406.002236 -241.721386) (xy 309.6387 -241.721386) (xy 309.638156 -241.731538) (xy 309.630393 -241.7503)
			(xy 309.616043 -241.764664) (xy 309.59729 -241.772446) (xy 309.587138 -241.772948) (xy 308.187598 -241.772948)
			(xy 308.177425 -241.772537) (xy 308.158627 -241.764749) (xy 308.144242 -241.750359) (xy 308.136459 -241.73156)
			(xy 308.136036 -241.721386) (xy 302.0949 -241.721386) (xy 302.094356 -241.731538) (xy 302.086593 -241.7503)
			(xy 302.072243 -241.764664) (xy 302.05349 -241.772446) (xy 302.043338 -241.772948) (xy 300.643798 -241.772948)
			(xy 300.633625 -241.772537) (xy 300.614827 -241.764749) (xy 300.600442 -241.750359) (xy 300.592659 -241.73156)
			(xy 300.592236 -241.721386) (xy 294.5511 -241.721386) (xy 294.550556 -241.731538) (xy 294.542793 -241.7503)
			(xy 294.528443 -241.764664) (xy 294.50969 -241.772446) (xy 294.499538 -241.772948) (xy 293.099998 -241.772948)
			(xy 293.089825 -241.772537) (xy 293.071027 -241.764749) (xy 293.056642 -241.750359) (xy 293.048859 -241.73156)
			(xy 293.048436 -241.721386) (xy 287.0073 -241.721386) (xy 287.006756 -241.731538) (xy 286.998993 -241.7503)
			(xy 286.984643 -241.764664) (xy 286.96589 -241.772446) (xy 286.955738 -241.772948) (xy 285.556198 -241.772948)
			(xy 285.546025 -241.772537) (xy 285.527227 -241.764749) (xy 285.512842 -241.750359) (xy 285.505059 -241.73156)
			(xy 285.504636 -241.721386) (xy 279.4635 -241.721386) (xy 279.462956 -241.731538) (xy 279.455193 -241.7503)
			(xy 279.440843 -241.764664) (xy 279.42209 -241.772446) (xy 279.411938 -241.772948) (xy 278.012398 -241.772948)
			(xy 278.002225 -241.772537) (xy 277.983427 -241.764749) (xy 277.969042 -241.750359) (xy 277.961259 -241.73156)
			(xy 277.960836 -241.721386) (xy 271.9197 -241.721386) (xy 271.919156 -241.731538) (xy 271.911393 -241.7503)
			(xy 271.897043 -241.764664) (xy 271.87829 -241.772446) (xy 271.868138 -241.772948) (xy 270.468598 -241.772948)
			(xy 270.458425 -241.772537) (xy 270.439627 -241.764749) (xy 270.425242 -241.750359) (xy 270.417459 -241.73156)
			(xy 270.417036 -241.721386) (xy 264.3759 -241.721386) (xy 264.375356 -241.731538) (xy 264.367593 -241.7503)
			(xy 264.353243 -241.764664) (xy 264.33449 -241.772446) (xy 264.324338 -241.772948) (xy 262.924798 -241.772948)
			(xy 262.914625 -241.772537) (xy 262.895827 -241.764749) (xy 262.881442 -241.750359) (xy 262.873659 -241.73156)
			(xy 262.873236 -241.721386) (xy 256.8321 -241.721386) (xy 256.831556 -241.731538) (xy 256.823793 -241.7503)
			(xy 256.809443 -241.764664) (xy 256.79069 -241.772446) (xy 256.780538 -241.772948) (xy 255.380998 -241.772948)
			(xy 255.370825 -241.772537) (xy 255.352027 -241.764749) (xy 255.337642 -241.750359) (xy 255.329859 -241.73156)
			(xy 255.329436 -241.721386) (xy 212.371432 -241.721386) (xy 212.371024 -241.73156) (xy 212.363238 -241.750361)
			(xy 212.348847 -241.764747) (xy 212.330045 -241.772527) (xy 212.31987 -241.772948) (xy 210.92033 -241.772948)
			(xy 210.910159 -241.772511) (xy 210.891362 -241.764733) (xy 210.876976 -241.750351) (xy 210.869192 -241.731557)
			(xy 210.868768 -241.721386) (xy 204.827632 -241.721386) (xy 204.827224 -241.73156) (xy 204.819438 -241.750361)
			(xy 204.805047 -241.764747) (xy 204.786245 -241.772527) (xy 204.77607 -241.772948) (xy 203.37653 -241.772948)
			(xy 203.366359 -241.772511) (xy 203.347562 -241.764733) (xy 203.333176 -241.750351) (xy 203.325392 -241.731557)
			(xy 203.324968 -241.721386) (xy 197.283832 -241.721386) (xy 197.283424 -241.73156) (xy 197.275638 -241.750361)
			(xy 197.261247 -241.764747) (xy 197.242445 -241.772527) (xy 197.23227 -241.772948) (xy 195.83273 -241.772948)
			(xy 195.822559 -241.772511) (xy 195.803762 -241.764733) (xy 195.789376 -241.750351) (xy 195.781592 -241.731557)
			(xy 195.781168 -241.721386) (xy 189.740032 -241.721386) (xy 189.739624 -241.73156) (xy 189.731838 -241.750361)
			(xy 189.717447 -241.764747) (xy 189.698645 -241.772527) (xy 189.68847 -241.772948) (xy 188.28893 -241.772948)
			(xy 188.278759 -241.772511) (xy 188.259962 -241.764733) (xy 188.245576 -241.750351) (xy 188.237792 -241.731557)
			(xy 188.237368 -241.721386) (xy 182.196232 -241.721386) (xy 182.195824 -241.73156) (xy 182.188038 -241.750361)
			(xy 182.173647 -241.764747) (xy 182.154845 -241.772527) (xy 182.14467 -241.772948) (xy 180.74513 -241.772948)
			(xy 180.734959 -241.772511) (xy 180.716162 -241.764733) (xy 180.701776 -241.750351) (xy 180.693992 -241.731557)
			(xy 180.693568 -241.721386) (xy 174.652432 -241.721386) (xy 174.652024 -241.73156) (xy 174.644238 -241.750361)
			(xy 174.629847 -241.764747) (xy 174.611045 -241.772527) (xy 174.60087 -241.772948) (xy 173.20133 -241.772948)
			(xy 173.191159 -241.772511) (xy 173.172362 -241.764733) (xy 173.157976 -241.750351) (xy 173.150192 -241.731557)
			(xy 173.149768 -241.721386) (xy 167.108632 -241.721386) (xy 167.108224 -241.73156) (xy 167.100438 -241.750361)
			(xy 167.086047 -241.764747) (xy 167.067245 -241.772527) (xy 167.05707 -241.772948) (xy 165.65753 -241.772948)
			(xy 165.647359 -241.772511) (xy 165.628562 -241.764733) (xy 165.614176 -241.750351) (xy 165.606392 -241.731557)
			(xy 165.605968 -241.721386) (xy 159.564832 -241.721386) (xy 159.564424 -241.73156) (xy 159.556638 -241.750361)
			(xy 159.542247 -241.764747) (xy 159.523445 -241.772527) (xy 159.51327 -241.772948) (xy 158.11373 -241.772948)
			(xy 158.103559 -241.772511) (xy 158.084762 -241.764733) (xy 158.070376 -241.750351) (xy 158.062592 -241.731557)
			(xy 158.062168 -241.721386) (xy 61.698632 -241.721386) (xy 61.698224 -241.73156) (xy 61.690438 -241.750361)
			(xy 61.676047 -241.764747) (xy 61.657245 -241.772527) (xy 61.64707 -241.772948) (xy 60.24753 -241.772948)
			(xy 60.237359 -241.772511) (xy 60.218562 -241.764733) (xy 60.204176 -241.750351) (xy 60.196392 -241.731557)
			(xy 60.195968 -241.721386) (xy 54.154832 -241.721386) (xy 54.154424 -241.73156) (xy 54.146638 -241.750361)
			(xy 54.132247 -241.764747) (xy 54.113445 -241.772527) (xy 54.10327 -241.772948) (xy 52.70373 -241.772948)
			(xy 52.693559 -241.772511) (xy 52.674762 -241.764733) (xy 52.660376 -241.750351) (xy 52.652592 -241.731557)
			(xy 52.652168 -241.721386) (xy 46.611032 -241.721386) (xy 46.610624 -241.73156) (xy 46.602838 -241.750361)
			(xy 46.588447 -241.764747) (xy 46.569645 -241.772527) (xy 46.55947 -241.772948) (xy 45.15993 -241.772948)
			(xy 45.149759 -241.772511) (xy 45.130962 -241.764733) (xy 45.116576 -241.750351) (xy 45.108792 -241.731557)
			(xy 45.108368 -241.721386) (xy 39.067232 -241.721386) (xy 39.066824 -241.73156) (xy 39.059038 -241.750361)
			(xy 39.044647 -241.764747) (xy 39.025845 -241.772527) (xy 39.01567 -241.772948) (xy 37.61613 -241.772948)
			(xy 37.605959 -241.772511) (xy 37.587162 -241.764733) (xy 37.572776 -241.750351) (xy 37.564992 -241.731557)
			(xy 37.564568 -241.721386) (xy 31.523432 -241.721386) (xy 31.523024 -241.73156) (xy 31.515238 -241.750361)
			(xy 31.500847 -241.764747) (xy 31.482045 -241.772527) (xy 31.47187 -241.772948) (xy 30.07233 -241.772948)
			(xy 30.062159 -241.772511) (xy 30.043362 -241.764733) (xy 30.028976 -241.750351) (xy 30.021192 -241.731557)
			(xy 30.020768 -241.721386) (xy 23.979632 -241.721386) (xy 23.979224 -241.73156) (xy 23.971438 -241.750361)
			(xy 23.957047 -241.764747) (xy 23.938245 -241.772527) (xy 23.92807 -241.772948) (xy 22.52853 -241.772948)
			(xy 22.518359 -241.772511) (xy 22.499562 -241.764733) (xy 22.485176 -241.750351) (xy 22.477392 -241.731557)
			(xy 22.476968 -241.721386) (xy 16.435832 -241.721386) (xy 16.435424 -241.73156) (xy 16.427638 -241.750361)
			(xy 16.413247 -241.764747) (xy 16.394445 -241.772527) (xy 16.38427 -241.772948) (xy 14.98473 -241.772948)
			(xy 14.974559 -241.772511) (xy 14.955762 -241.764733) (xy 14.941376 -241.750351) (xy 14.933592 -241.731557)
			(xy 14.933168 -241.721386) (xy 8.892032 -241.721386) (xy 8.891624 -241.73156) (xy 8.883838 -241.750361)
			(xy 8.869447 -241.764747) (xy 8.850645 -241.772527) (xy 8.84047 -241.772948) (xy 7.44093 -241.772948)
			(xy 7.430759 -241.772511) (xy 7.411962 -241.764733) (xy 7.397576 -241.750351) (xy 7.389792 -241.731557)
			(xy 7.389368 -241.721386) (xy 2.509012 -241.721386) (xy 2.509012 -243.421408) (xy 7.389368 -243.421408)
			(xy 7.389368 -243.012468) (xy 7.389795 -243.002316) (xy 7.397595 -242.983569) (xy 7.411989 -242.969248)
			(xy 7.430776 -242.961543) (xy 7.44093 -242.96116) (xy 8.84047 -242.96116) (xy 8.850597 -242.961652)
			(xy 8.869322 -242.969373) (xy 8.88368 -242.983658) (xy 8.891496 -243.002343) (xy 8.892032 -243.012468)
			(xy 8.892032 -243.421408) (xy 14.933168 -243.421408) (xy 14.933168 -243.012468) (xy 14.933595 -243.002316)
			(xy 14.941395 -242.983569) (xy 14.955789 -242.969248) (xy 14.974576 -242.961543) (xy 14.98473 -242.96116)
			(xy 16.38427 -242.96116) (xy 16.394397 -242.961652) (xy 16.413122 -242.969373) (xy 16.42748 -242.983658)
			(xy 16.435296 -243.002343) (xy 16.435832 -243.012468) (xy 16.435832 -243.421408) (xy 22.476968 -243.421408)
			(xy 22.476968 -243.012468) (xy 22.477395 -243.002316) (xy 22.485195 -242.983569) (xy 22.499589 -242.969248)
			(xy 22.518376 -242.961543) (xy 22.52853 -242.96116) (xy 23.92807 -242.96116) (xy 23.938197 -242.961652)
			(xy 23.956922 -242.969373) (xy 23.97128 -242.983658) (xy 23.979096 -243.002343) (xy 23.979632 -243.012468)
			(xy 23.979632 -243.421408) (xy 30.020768 -243.421408) (xy 30.020768 -243.012468) (xy 30.021195 -243.002316)
			(xy 30.028995 -242.983569) (xy 30.043389 -242.969248) (xy 30.062176 -242.961543) (xy 30.07233 -242.96116)
			(xy 31.47187 -242.96116) (xy 31.481997 -242.961652) (xy 31.500722 -242.969373) (xy 31.51508 -242.983658)
			(xy 31.522896 -243.002343) (xy 31.523432 -243.012468) (xy 31.523432 -243.421408) (xy 37.564568 -243.421408)
			(xy 37.564568 -243.012468) (xy 37.564995 -243.002316) (xy 37.572795 -242.983569) (xy 37.587189 -242.969248)
			(xy 37.605976 -242.961543) (xy 37.61613 -242.96116) (xy 39.01567 -242.96116) (xy 39.025797 -242.961652)
			(xy 39.044522 -242.969373) (xy 39.05888 -242.983658) (xy 39.066696 -243.002343) (xy 39.067232 -243.012468)
			(xy 39.067232 -243.421408) (xy 45.108368 -243.421408) (xy 45.108368 -243.012468) (xy 45.108795 -243.002316)
			(xy 45.116595 -242.983569) (xy 45.130989 -242.969248) (xy 45.149776 -242.961543) (xy 45.15993 -242.96116)
			(xy 46.55947 -242.96116) (xy 46.569597 -242.961652) (xy 46.588322 -242.969373) (xy 46.60268 -242.983658)
			(xy 46.610496 -243.002343) (xy 46.611032 -243.012468) (xy 46.611032 -243.421408) (xy 52.652168 -243.421408)
			(xy 52.652168 -243.012468) (xy 52.652595 -243.002316) (xy 52.660395 -242.983569) (xy 52.674789 -242.969248)
			(xy 52.693576 -242.961543) (xy 52.70373 -242.96116) (xy 54.10327 -242.96116) (xy 54.113397 -242.961652)
			(xy 54.132122 -242.969373) (xy 54.14648 -242.983658) (xy 54.154296 -243.002343) (xy 54.154832 -243.012468)
			(xy 54.154832 -243.421408) (xy 60.195968 -243.421408) (xy 60.195968 -243.012468) (xy 60.196395 -243.002316)
			(xy 60.204195 -242.983569) (xy 60.218589 -242.969248) (xy 60.237376 -242.961543) (xy 60.24753 -242.96116)
			(xy 61.64707 -242.96116) (xy 61.657197 -242.961652) (xy 61.675922 -242.969373) (xy 61.69028 -242.983658)
			(xy 61.698096 -243.002343) (xy 61.698632 -243.012468) (xy 61.698632 -243.421408) (xy 158.062168 -243.421408)
			(xy 158.062168 -243.012468) (xy 158.062595 -243.002316) (xy 158.070395 -242.983569) (xy 158.084789 -242.969248)
			(xy 158.103576 -242.961543) (xy 158.11373 -242.96116) (xy 159.51327 -242.96116) (xy 159.523397 -242.961652)
			(xy 159.542122 -242.969373) (xy 159.55648 -242.983658) (xy 159.564296 -243.002343) (xy 159.564832 -243.012468)
			(xy 159.564832 -243.421408) (xy 165.605968 -243.421408) (xy 165.605968 -243.012468) (xy 165.606395 -243.002316)
			(xy 165.614195 -242.983569) (xy 165.628589 -242.969248) (xy 165.647376 -242.961543) (xy 165.65753 -242.96116)
			(xy 167.05707 -242.96116) (xy 167.067197 -242.961652) (xy 167.085922 -242.969373) (xy 167.10028 -242.983658)
			(xy 167.108096 -243.002343) (xy 167.108632 -243.012468) (xy 167.108632 -243.421408) (xy 173.149768 -243.421408)
			(xy 173.149768 -243.012468) (xy 173.150195 -243.002316) (xy 173.157995 -242.983569) (xy 173.172389 -242.969248)
			(xy 173.191176 -242.961543) (xy 173.20133 -242.96116) (xy 174.60087 -242.96116) (xy 174.610997 -242.961652)
			(xy 174.629722 -242.969373) (xy 174.64408 -242.983658) (xy 174.651896 -243.002343) (xy 174.652432 -243.012468)
			(xy 174.652432 -243.421408) (xy 180.693568 -243.421408) (xy 180.693568 -243.012468) (xy 180.693995 -243.002316)
			(xy 180.701795 -242.983569) (xy 180.716189 -242.969248) (xy 180.734976 -242.961543) (xy 180.74513 -242.96116)
			(xy 182.14467 -242.96116) (xy 182.154797 -242.961652) (xy 182.173522 -242.969373) (xy 182.18788 -242.983658)
			(xy 182.195696 -243.002343) (xy 182.196232 -243.012468) (xy 182.196232 -243.421408) (xy 188.237368 -243.421408)
			(xy 188.237368 -243.012468) (xy 188.237795 -243.002316) (xy 188.245595 -242.983569) (xy 188.259989 -242.969248)
			(xy 188.278776 -242.961543) (xy 188.28893 -242.96116) (xy 189.68847 -242.96116) (xy 189.698597 -242.961652)
			(xy 189.717322 -242.969373) (xy 189.73168 -242.983658) (xy 189.739496 -243.002343) (xy 189.740032 -243.012468)
			(xy 189.740032 -243.421408) (xy 195.781168 -243.421408) (xy 195.781168 -243.012468) (xy 195.781595 -243.002316)
			(xy 195.789395 -242.983569) (xy 195.803789 -242.969248) (xy 195.822576 -242.961543) (xy 195.83273 -242.96116)
			(xy 197.23227 -242.96116) (xy 197.242397 -242.961652) (xy 197.261122 -242.969373) (xy 197.27548 -242.983658)
			(xy 197.283296 -243.002343) (xy 197.283832 -243.012468) (xy 197.283832 -243.421408) (xy 203.324968 -243.421408)
			(xy 203.324968 -243.012468) (xy 203.325395 -243.002316) (xy 203.333195 -242.983569) (xy 203.347589 -242.969248)
			(xy 203.366376 -242.961543) (xy 203.37653 -242.96116) (xy 204.77607 -242.96116) (xy 204.786197 -242.961652)
			(xy 204.804922 -242.969373) (xy 204.81928 -242.983658) (xy 204.827096 -243.002343) (xy 204.827632 -243.012468)
			(xy 204.827632 -243.421408) (xy 210.868768 -243.421408) (xy 210.868768 -243.012468) (xy 210.869195 -243.002316)
			(xy 210.876995 -242.983569) (xy 210.891389 -242.969248) (xy 210.910176 -242.961543) (xy 210.92033 -242.96116)
			(xy 212.31987 -242.96116) (xy 212.329997 -242.961652) (xy 212.348722 -242.969373) (xy 212.36308 -242.983658)
			(xy 212.370896 -243.002343) (xy 212.371432 -243.012468) (xy 212.371432 -243.421408) (xy 255.329436 -243.421408)
			(xy 255.329436 -243.012468) (xy 255.329796 -243.002307) (xy 255.337609 -242.983547) (xy 255.352025 -242.969224)
			(xy 255.370835 -242.961532) (xy 255.380998 -242.96116) (xy 256.780538 -242.96116) (xy 256.79067 -242.961596)
			(xy 256.809395 -242.96934) (xy 256.823751 -242.983642) (xy 256.831565 -243.002338) (xy 256.8321 -243.012468)
			(xy 256.8321 -243.421408) (xy 262.873236 -243.421408) (xy 262.873236 -243.012468) (xy 262.873596 -243.002307)
			(xy 262.881409 -242.983547) (xy 262.895825 -242.969224) (xy 262.914635 -242.961532) (xy 262.924798 -242.96116)
			(xy 264.324338 -242.96116) (xy 264.33447 -242.961596) (xy 264.353195 -242.96934) (xy 264.367551 -242.983642)
			(xy 264.375365 -243.002338) (xy 264.3759 -243.012468) (xy 264.3759 -243.421408) (xy 270.417036 -243.421408)
			(xy 270.417036 -243.012468) (xy 270.417396 -243.002307) (xy 270.425209 -242.983547) (xy 270.439625 -242.969224)
			(xy 270.458435 -242.961532) (xy 270.468598 -242.96116) (xy 271.868138 -242.96116) (xy 271.87827 -242.961596)
			(xy 271.896995 -242.96934) (xy 271.911351 -242.983642) (xy 271.919165 -243.002338) (xy 271.9197 -243.012468)
			(xy 271.9197 -243.421408) (xy 277.960836 -243.421408) (xy 277.960836 -243.012468) (xy 277.961196 -243.002307)
			(xy 277.969009 -242.983547) (xy 277.983425 -242.969224) (xy 278.002235 -242.961532) (xy 278.012398 -242.96116)
			(xy 279.411938 -242.96116) (xy 279.42207 -242.961596) (xy 279.440795 -242.96934) (xy 279.455151 -242.983642)
			(xy 279.462965 -243.002338) (xy 279.4635 -243.012468) (xy 279.4635 -243.421408) (xy 285.504636 -243.421408)
			(xy 285.504636 -243.012468) (xy 285.504996 -243.002307) (xy 285.512809 -242.983547) (xy 285.527225 -242.969224)
			(xy 285.546035 -242.961532) (xy 285.556198 -242.96116) (xy 286.955738 -242.96116) (xy 286.96587 -242.961596)
			(xy 286.984595 -242.96934) (xy 286.998951 -242.983642) (xy 287.006765 -243.002338) (xy 287.0073 -243.012468)
			(xy 287.0073 -243.421408) (xy 293.048436 -243.421408) (xy 293.048436 -243.012468) (xy 293.048796 -243.002307)
			(xy 293.056609 -242.983547) (xy 293.071025 -242.969224) (xy 293.089835 -242.961532) (xy 293.099998 -242.96116)
			(xy 294.499538 -242.96116) (xy 294.50967 -242.961596) (xy 294.528395 -242.96934) (xy 294.542751 -242.983642)
			(xy 294.550565 -243.002338) (xy 294.5511 -243.012468) (xy 294.5511 -243.421408) (xy 300.592236 -243.421408)
			(xy 300.592236 -243.012468) (xy 300.592596 -243.002307) (xy 300.600409 -242.983547) (xy 300.614825 -242.969224)
			(xy 300.633635 -242.961532) (xy 300.643798 -242.96116) (xy 302.043338 -242.96116) (xy 302.05347 -242.961596)
			(xy 302.072195 -242.96934) (xy 302.086551 -242.983642) (xy 302.094365 -243.002338) (xy 302.0949 -243.012468)
			(xy 302.0949 -243.421408) (xy 308.136036 -243.421408) (xy 308.136036 -243.012468) (xy 308.136396 -243.002307)
			(xy 308.144209 -242.983547) (xy 308.158625 -242.969224) (xy 308.177435 -242.961532) (xy 308.187598 -242.96116)
			(xy 309.587138 -242.96116) (xy 309.59727 -242.961596) (xy 309.615995 -242.96934) (xy 309.630351 -242.983642)
			(xy 309.638165 -243.002338) (xy 309.6387 -243.012468) (xy 309.6387 -243.421408) (xy 406.002236 -243.421408)
			(xy 406.002236 -243.012468) (xy 406.002596 -243.002307) (xy 406.010409 -242.983547) (xy 406.024825 -242.969224)
			(xy 406.043635 -242.961532) (xy 406.053798 -242.96116) (xy 407.453338 -242.96116) (xy 407.46347 -242.961596)
			(xy 407.482195 -242.96934) (xy 407.496551 -242.983642) (xy 407.504365 -243.002338) (xy 407.5049 -243.012468)
			(xy 407.5049 -243.421408) (xy 413.546036 -243.421408) (xy 413.546036 -243.012468) (xy 413.546396 -243.002307)
			(xy 413.554209 -242.983547) (xy 413.568625 -242.969224) (xy 413.587435 -242.961532) (xy 413.597598 -242.96116)
			(xy 414.997138 -242.96116) (xy 415.00727 -242.961596) (xy 415.025995 -242.96934) (xy 415.040351 -242.983642)
			(xy 415.048165 -243.002338) (xy 415.0487 -243.012468) (xy 415.0487 -243.421408) (xy 421.089836 -243.421408)
			(xy 421.089836 -243.012468) (xy 421.090196 -243.002307) (xy 421.098009 -242.983547) (xy 421.112425 -242.969224)
			(xy 421.131235 -242.961532) (xy 421.141398 -242.96116) (xy 422.540938 -242.96116) (xy 422.55107 -242.961596)
			(xy 422.569795 -242.96934) (xy 422.584151 -242.983642) (xy 422.591965 -243.002338) (xy 422.5925 -243.012468)
			(xy 422.5925 -243.421408) (xy 428.633636 -243.421408) (xy 428.633636 -243.012468) (xy 428.633996 -243.002307)
			(xy 428.641809 -242.983547) (xy 428.656225 -242.969224) (xy 428.675035 -242.961532) (xy 428.685198 -242.96116)
			(xy 430.084738 -242.96116) (xy 430.09487 -242.961596) (xy 430.113595 -242.96934) (xy 430.127951 -242.983642)
			(xy 430.135765 -243.002338) (xy 430.1363 -243.012468) (xy 430.1363 -243.421408) (xy 436.177436 -243.421408)
			(xy 436.177436 -243.012468) (xy 436.177796 -243.002307) (xy 436.185609 -242.983547) (xy 436.200025 -242.969224)
			(xy 436.218835 -242.961532) (xy 436.228998 -242.96116) (xy 437.628538 -242.96116) (xy 437.63867 -242.961596)
			(xy 437.657395 -242.96934) (xy 437.671751 -242.983642) (xy 437.679565 -243.002338) (xy 437.6801 -243.012468)
			(xy 437.6801 -243.421408) (xy 443.721236 -243.421408) (xy 443.721236 -243.012468) (xy 443.721596 -243.002307)
			(xy 443.729409 -242.983547) (xy 443.743825 -242.969224) (xy 443.762635 -242.961532) (xy 443.772798 -242.96116)
			(xy 445.172338 -242.96116) (xy 445.18247 -242.961596) (xy 445.201195 -242.96934) (xy 445.215551 -242.983642)
			(xy 445.223365 -243.002338) (xy 445.2239 -243.012468) (xy 445.2239 -243.421408) (xy 451.265036 -243.421408)
			(xy 451.265036 -243.012468) (xy 451.265396 -243.002307) (xy 451.273209 -242.983547) (xy 451.287625 -242.969224)
			(xy 451.306435 -242.961532) (xy 451.316598 -242.96116) (xy 452.716138 -242.96116) (xy 452.72627 -242.961596)
			(xy 452.744995 -242.96934) (xy 452.759351 -242.983642) (xy 452.767165 -243.002338) (xy 452.7677 -243.012468)
			(xy 452.7677 -243.421408) (xy 458.808836 -243.421408) (xy 458.808836 -243.012468) (xy 458.809196 -243.002307)
			(xy 458.817009 -242.983547) (xy 458.831425 -242.969224) (xy 458.850235 -242.961532) (xy 458.860398 -242.96116)
			(xy 460.259938 -242.96116) (xy 460.27007 -242.961596) (xy 460.288795 -242.96934) (xy 460.303151 -242.983642)
			(xy 460.310965 -243.002338) (xy 460.3115 -243.012468) (xy 460.3115 -243.421408) (xy 460.311085 -243.431563)
			(xy 460.303287 -243.450315) (xy 460.288888 -243.464638) (xy 460.270095 -243.472338) (xy 460.259938 -243.472716)
			(xy 458.860398 -243.472716) (xy 458.850266 -243.472274) (xy 458.831536 -243.464537) (xy 458.817179 -243.450237)
			(xy 458.809367 -243.431538) (xy 458.808836 -243.421408) (xy 452.7677 -243.421408) (xy 452.767285 -243.431563)
			(xy 452.759487 -243.450315) (xy 452.745088 -243.464638) (xy 452.726295 -243.472338) (xy 452.716138 -243.472716)
			(xy 451.316598 -243.472716) (xy 451.306466 -243.472274) (xy 451.287736 -243.464537) (xy 451.273379 -243.450237)
			(xy 451.265567 -243.431538) (xy 451.265036 -243.421408) (xy 445.2239 -243.421408) (xy 445.223485 -243.431563)
			(xy 445.215687 -243.450315) (xy 445.201288 -243.464638) (xy 445.182495 -243.472338) (xy 445.172338 -243.472716)
			(xy 443.772798 -243.472716) (xy 443.762666 -243.472274) (xy 443.743936 -243.464537) (xy 443.729579 -243.450237)
			(xy 443.721767 -243.431538) (xy 443.721236 -243.421408) (xy 437.6801 -243.421408) (xy 437.679685 -243.431563)
			(xy 437.671887 -243.450315) (xy 437.657488 -243.464638) (xy 437.638695 -243.472338) (xy 437.628538 -243.472716)
			(xy 436.228998 -243.472716) (xy 436.218866 -243.472274) (xy 436.200136 -243.464537) (xy 436.185779 -243.450237)
			(xy 436.177967 -243.431538) (xy 436.177436 -243.421408) (xy 430.1363 -243.421408) (xy 430.135885 -243.431563)
			(xy 430.128087 -243.450315) (xy 430.113688 -243.464638) (xy 430.094895 -243.472338) (xy 430.084738 -243.472716)
			(xy 428.685198 -243.472716) (xy 428.675066 -243.472274) (xy 428.656336 -243.464537) (xy 428.641979 -243.450237)
			(xy 428.634167 -243.431538) (xy 428.633636 -243.421408) (xy 422.5925 -243.421408) (xy 422.592085 -243.431563)
			(xy 422.584287 -243.450315) (xy 422.569888 -243.464638) (xy 422.551095 -243.472338) (xy 422.540938 -243.472716)
			(xy 421.141398 -243.472716) (xy 421.131266 -243.472274) (xy 421.112536 -243.464537) (xy 421.098179 -243.450237)
			(xy 421.090367 -243.431538) (xy 421.089836 -243.421408) (xy 415.0487 -243.421408) (xy 415.048285 -243.431563)
			(xy 415.040487 -243.450315) (xy 415.026088 -243.464638) (xy 415.007295 -243.472338) (xy 414.997138 -243.472716)
			(xy 413.597598 -243.472716) (xy 413.587466 -243.472274) (xy 413.568736 -243.464537) (xy 413.554379 -243.450237)
			(xy 413.546567 -243.431538) (xy 413.546036 -243.421408) (xy 407.5049 -243.421408) (xy 407.504485 -243.431563)
			(xy 407.496687 -243.450315) (xy 407.482288 -243.464638) (xy 407.463495 -243.472338) (xy 407.453338 -243.472716)
			(xy 406.053798 -243.472716) (xy 406.043666 -243.472274) (xy 406.024936 -243.464537) (xy 406.010579 -243.450237)
			(xy 406.002767 -243.431538) (xy 406.002236 -243.421408) (xy 309.6387 -243.421408) (xy 309.638285 -243.431563)
			(xy 309.630487 -243.450315) (xy 309.616088 -243.464638) (xy 309.597295 -243.472338) (xy 309.587138 -243.472716)
			(xy 308.187598 -243.472716) (xy 308.177466 -243.472274) (xy 308.158736 -243.464537) (xy 308.144379 -243.450237)
			(xy 308.136567 -243.431538) (xy 308.136036 -243.421408) (xy 302.0949 -243.421408) (xy 302.094485 -243.431563)
			(xy 302.086687 -243.450315) (xy 302.072288 -243.464638) (xy 302.053495 -243.472338) (xy 302.043338 -243.472716)
			(xy 300.643798 -243.472716) (xy 300.633666 -243.472274) (xy 300.614936 -243.464537) (xy 300.600579 -243.450237)
			(xy 300.592767 -243.431538) (xy 300.592236 -243.421408) (xy 294.5511 -243.421408) (xy 294.550685 -243.431563)
			(xy 294.542887 -243.450315) (xy 294.528488 -243.464638) (xy 294.509695 -243.472338) (xy 294.499538 -243.472716)
			(xy 293.099998 -243.472716) (xy 293.089866 -243.472274) (xy 293.071136 -243.464537) (xy 293.056779 -243.450237)
			(xy 293.048967 -243.431538) (xy 293.048436 -243.421408) (xy 287.0073 -243.421408) (xy 287.006885 -243.431563)
			(xy 286.999087 -243.450315) (xy 286.984688 -243.464638) (xy 286.965895 -243.472338) (xy 286.955738 -243.472716)
			(xy 285.556198 -243.472716) (xy 285.546066 -243.472274) (xy 285.527336 -243.464537) (xy 285.512979 -243.450237)
			(xy 285.505167 -243.431538) (xy 285.504636 -243.421408) (xy 279.4635 -243.421408) (xy 279.463085 -243.431563)
			(xy 279.455287 -243.450315) (xy 279.440888 -243.464638) (xy 279.422095 -243.472338) (xy 279.411938 -243.472716)
			(xy 278.012398 -243.472716) (xy 278.002266 -243.472274) (xy 277.983536 -243.464537) (xy 277.969179 -243.450237)
			(xy 277.961367 -243.431538) (xy 277.960836 -243.421408) (xy 271.9197 -243.421408) (xy 271.919285 -243.431563)
			(xy 271.911487 -243.450315) (xy 271.897088 -243.464638) (xy 271.878295 -243.472338) (xy 271.868138 -243.472716)
			(xy 270.468598 -243.472716) (xy 270.458466 -243.472274) (xy 270.439736 -243.464537) (xy 270.425379 -243.450237)
			(xy 270.417567 -243.431538) (xy 270.417036 -243.421408) (xy 264.3759 -243.421408) (xy 264.375485 -243.431563)
			(xy 264.367687 -243.450315) (xy 264.353288 -243.464638) (xy 264.334495 -243.472338) (xy 264.324338 -243.472716)
			(xy 262.924798 -243.472716) (xy 262.914666 -243.472274) (xy 262.895936 -243.464537) (xy 262.881579 -243.450237)
			(xy 262.873767 -243.431538) (xy 262.873236 -243.421408) (xy 256.8321 -243.421408) (xy 256.831685 -243.431563)
			(xy 256.823887 -243.450315) (xy 256.809488 -243.464638) (xy 256.790695 -243.472338) (xy 256.780538 -243.472716)
			(xy 255.380998 -243.472716) (xy 255.370866 -243.472274) (xy 255.352136 -243.464537) (xy 255.337779 -243.450237)
			(xy 255.329967 -243.431538) (xy 255.329436 -243.421408) (xy 212.371432 -243.421408) (xy 212.370985 -243.431559)
			(xy 212.363193 -243.450305) (xy 212.348805 -243.464627) (xy 212.330022 -243.472332) (xy 212.31987 -243.472716)
			(xy 210.92033 -243.472716) (xy 210.9102 -243.472248) (xy 210.891471 -243.464522) (xy 210.877112 -243.450229)
			(xy 210.869299 -243.431536) (xy 210.868768 -243.421408) (xy 204.827632 -243.421408) (xy 204.827185 -243.431559)
			(xy 204.819393 -243.450305) (xy 204.805005 -243.464627) (xy 204.786222 -243.472332) (xy 204.77607 -243.472716)
			(xy 203.37653 -243.472716) (xy 203.3664 -243.472248) (xy 203.347671 -243.464522) (xy 203.333312 -243.450229)
			(xy 203.325499 -243.431536) (xy 203.324968 -243.421408) (xy 197.283832 -243.421408) (xy 197.283385 -243.431559)
			(xy 197.275593 -243.450305) (xy 197.261205 -243.464627) (xy 197.242422 -243.472332) (xy 197.23227 -243.472716)
			(xy 195.83273 -243.472716) (xy 195.8226 -243.472248) (xy 195.803871 -243.464522) (xy 195.789512 -243.450229)
			(xy 195.781699 -243.431536) (xy 195.781168 -243.421408) (xy 189.740032 -243.421408) (xy 189.739585 -243.431559)
			(xy 189.731793 -243.450305) (xy 189.717405 -243.464627) (xy 189.698622 -243.472332) (xy 189.68847 -243.472716)
			(xy 188.28893 -243.472716) (xy 188.2788 -243.472248) (xy 188.260071 -243.464522) (xy 188.245712 -243.450229)
			(xy 188.237899 -243.431536) (xy 188.237368 -243.421408) (xy 182.196232 -243.421408) (xy 182.195785 -243.431559)
			(xy 182.187993 -243.450305) (xy 182.173605 -243.464627) (xy 182.154822 -243.472332) (xy 182.14467 -243.472716)
			(xy 180.74513 -243.472716) (xy 180.735 -243.472248) (xy 180.716271 -243.464522) (xy 180.701912 -243.450229)
			(xy 180.694099 -243.431536) (xy 180.693568 -243.421408) (xy 174.652432 -243.421408) (xy 174.651985 -243.431559)
			(xy 174.644193 -243.450305) (xy 174.629805 -243.464627) (xy 174.611022 -243.472332) (xy 174.60087 -243.472716)
			(xy 173.20133 -243.472716) (xy 173.1912 -243.472248) (xy 173.172471 -243.464522) (xy 173.158112 -243.450229)
			(xy 173.150299 -243.431536) (xy 173.149768 -243.421408) (xy 167.108632 -243.421408) (xy 167.108185 -243.431559)
			(xy 167.100393 -243.450305) (xy 167.086005 -243.464627) (xy 167.067222 -243.472332) (xy 167.05707 -243.472716)
			(xy 165.65753 -243.472716) (xy 165.6474 -243.472248) (xy 165.628671 -243.464522) (xy 165.614312 -243.450229)
			(xy 165.606499 -243.431536) (xy 165.605968 -243.421408) (xy 159.564832 -243.421408) (xy 159.564385 -243.431559)
			(xy 159.556593 -243.450305) (xy 159.542205 -243.464627) (xy 159.523422 -243.472332) (xy 159.51327 -243.472716)
			(xy 158.11373 -243.472716) (xy 158.1036 -243.472248) (xy 158.084871 -243.464522) (xy 158.070512 -243.450229)
			(xy 158.062699 -243.431536) (xy 158.062168 -243.421408) (xy 61.698632 -243.421408) (xy 61.698185 -243.431559)
			(xy 61.690393 -243.450305) (xy 61.676005 -243.464627) (xy 61.657222 -243.472332) (xy 61.64707 -243.472716)
			(xy 60.24753 -243.472716) (xy 60.2374 -243.472248) (xy 60.218671 -243.464522) (xy 60.204312 -243.450229)
			(xy 60.196499 -243.431536) (xy 60.195968 -243.421408) (xy 54.154832 -243.421408) (xy 54.154385 -243.431559)
			(xy 54.146593 -243.450305) (xy 54.132205 -243.464627) (xy 54.113422 -243.472332) (xy 54.10327 -243.472716)
			(xy 52.70373 -243.472716) (xy 52.6936 -243.472248) (xy 52.674871 -243.464522) (xy 52.660512 -243.450229)
			(xy 52.652699 -243.431536) (xy 52.652168 -243.421408) (xy 46.611032 -243.421408) (xy 46.610585 -243.431559)
			(xy 46.602793 -243.450305) (xy 46.588405 -243.464627) (xy 46.569622 -243.472332) (xy 46.55947 -243.472716)
			(xy 45.15993 -243.472716) (xy 45.1498 -243.472248) (xy 45.131071 -243.464522) (xy 45.116712 -243.450229)
			(xy 45.108899 -243.431536) (xy 45.108368 -243.421408) (xy 39.067232 -243.421408) (xy 39.066785 -243.431559)
			(xy 39.058993 -243.450305) (xy 39.044605 -243.464627) (xy 39.025822 -243.472332) (xy 39.01567 -243.472716)
			(xy 37.61613 -243.472716) (xy 37.606 -243.472248) (xy 37.587271 -243.464522) (xy 37.572912 -243.450229)
			(xy 37.565099 -243.431536) (xy 37.564568 -243.421408) (xy 31.523432 -243.421408) (xy 31.522985 -243.431559)
			(xy 31.515193 -243.450305) (xy 31.500805 -243.464627) (xy 31.482022 -243.472332) (xy 31.47187 -243.472716)
			(xy 30.07233 -243.472716) (xy 30.0622 -243.472248) (xy 30.043471 -243.464522) (xy 30.029112 -243.450229)
			(xy 30.021299 -243.431536) (xy 30.020768 -243.421408) (xy 23.979632 -243.421408) (xy 23.979185 -243.431559)
			(xy 23.971393 -243.450305) (xy 23.957005 -243.464627) (xy 23.938222 -243.472332) (xy 23.92807 -243.472716)
			(xy 22.52853 -243.472716) (xy 22.5184 -243.472248) (xy 22.499671 -243.464522) (xy 22.485312 -243.450229)
			(xy 22.477499 -243.431536) (xy 22.476968 -243.421408) (xy 16.435832 -243.421408) (xy 16.435385 -243.431559)
			(xy 16.427593 -243.450305) (xy 16.413205 -243.464627) (xy 16.394422 -243.472332) (xy 16.38427 -243.472716)
			(xy 14.98473 -243.472716) (xy 14.9746 -243.472248) (xy 14.955871 -243.464522) (xy 14.941512 -243.450229)
			(xy 14.933699 -243.431536) (xy 14.933168 -243.421408) (xy 8.892032 -243.421408) (xy 8.891585 -243.431559)
			(xy 8.883793 -243.450305) (xy 8.869405 -243.464627) (xy 8.850622 -243.472332) (xy 8.84047 -243.472716)
			(xy 7.44093 -243.472716) (xy 7.4308 -243.472248) (xy 7.412071 -243.464522) (xy 7.397712 -243.450229)
			(xy 7.389899 -243.431536) (xy 7.389368 -243.421408) (xy 2.509012 -243.421408) (xy 2.509012 -244.271292)
			(xy 7.389368 -244.271292) (xy 7.389368 -243.862352) (xy 7.389782 -243.852199) (xy 7.397587 -243.833452)
			(xy 7.411985 -243.819131) (xy 7.430775 -243.811427) (xy 7.44093 -243.811044) (xy 8.84047 -243.811044)
			(xy 8.850595 -243.811551) (xy 8.869317 -243.81927) (xy 8.883674 -243.83355) (xy 8.891494 -243.852229)
			(xy 8.892032 -243.862352) (xy 8.892032 -244.271292) (xy 14.933168 -244.271292) (xy 14.933168 -243.862352)
			(xy 14.933582 -243.852199) (xy 14.941387 -243.833452) (xy 14.955785 -243.819131) (xy 14.974575 -243.811427)
			(xy 14.98473 -243.811044) (xy 16.38427 -243.811044) (xy 16.394395 -243.811551) (xy 16.413117 -243.81927)
			(xy 16.427474 -243.83355) (xy 16.435294 -243.852229) (xy 16.435832 -243.862352) (xy 16.435832 -244.271292)
			(xy 22.476968 -244.271292) (xy 22.476968 -243.862352) (xy 22.477382 -243.852199) (xy 22.485187 -243.833452)
			(xy 22.499585 -243.819131) (xy 22.518375 -243.811427) (xy 22.52853 -243.811044) (xy 23.92807 -243.811044)
			(xy 23.938195 -243.811551) (xy 23.956917 -243.81927) (xy 23.971274 -243.83355) (xy 23.979094 -243.852229)
			(xy 23.979632 -243.862352) (xy 23.979632 -244.271292) (xy 30.020768 -244.271292) (xy 30.020768 -243.862352)
			(xy 30.021182 -243.852199) (xy 30.028987 -243.833452) (xy 30.043385 -243.819131) (xy 30.062175 -243.811427)
			(xy 30.07233 -243.811044) (xy 31.47187 -243.811044) (xy 31.481995 -243.811551) (xy 31.500717 -243.81927)
			(xy 31.515074 -243.83355) (xy 31.522894 -243.852229) (xy 31.523432 -243.862352) (xy 31.523432 -244.271292)
			(xy 37.564568 -244.271292) (xy 37.564568 -243.862352) (xy 37.564982 -243.852199) (xy 37.572787 -243.833452)
			(xy 37.587185 -243.819131) (xy 37.605975 -243.811427) (xy 37.61613 -243.811044) (xy 39.01567 -243.811044)
			(xy 39.025795 -243.811551) (xy 39.044517 -243.81927) (xy 39.058874 -243.83355) (xy 39.066694 -243.852229)
			(xy 39.067232 -243.862352) (xy 39.067232 -244.271292) (xy 45.108368 -244.271292) (xy 45.108368 -243.862352)
			(xy 45.108782 -243.852199) (xy 45.116587 -243.833452) (xy 45.130985 -243.819131) (xy 45.149775 -243.811427)
			(xy 45.15993 -243.811044) (xy 46.55947 -243.811044) (xy 46.569595 -243.811551) (xy 46.588317 -243.81927)
			(xy 46.602674 -243.83355) (xy 46.610494 -243.852229) (xy 46.611032 -243.862352) (xy 46.611032 -244.271292)
			(xy 52.652168 -244.271292) (xy 52.652168 -243.862352) (xy 52.652582 -243.852199) (xy 52.660387 -243.833452)
			(xy 52.674785 -243.819131) (xy 52.693575 -243.811427) (xy 52.70373 -243.811044) (xy 54.10327 -243.811044)
			(xy 54.113395 -243.811551) (xy 54.132117 -243.81927) (xy 54.146474 -243.83355) (xy 54.154294 -243.852229)
			(xy 54.154832 -243.862352) (xy 54.154832 -244.271292) (xy 60.195968 -244.271292) (xy 60.195968 -243.862352)
			(xy 60.196382 -243.852199) (xy 60.204187 -243.833452) (xy 60.218585 -243.819131) (xy 60.237375 -243.811427)
			(xy 60.24753 -243.811044) (xy 61.64707 -243.811044) (xy 61.657195 -243.811551) (xy 61.675917 -243.81927)
			(xy 61.690274 -243.83355) (xy 61.698094 -243.852229) (xy 61.698632 -243.862352) (xy 61.698632 -244.271292)
			(xy 158.062168 -244.271292) (xy 158.062168 -243.862352) (xy 158.062582 -243.852199) (xy 158.070387 -243.833452)
			(xy 158.084785 -243.819131) (xy 158.103575 -243.811427) (xy 158.11373 -243.811044) (xy 159.51327 -243.811044)
			(xy 159.523395 -243.811551) (xy 159.542117 -243.81927) (xy 159.556474 -243.83355) (xy 159.564294 -243.852229)
			(xy 159.564832 -243.862352) (xy 159.564832 -244.271292) (xy 165.605968 -244.271292) (xy 165.605968 -243.862352)
			(xy 165.606382 -243.852199) (xy 165.614187 -243.833452) (xy 165.628585 -243.819131) (xy 165.647375 -243.811427)
			(xy 165.65753 -243.811044) (xy 167.05707 -243.811044) (xy 167.067195 -243.811551) (xy 167.085917 -243.81927)
			(xy 167.100274 -243.83355) (xy 167.108094 -243.852229) (xy 167.108632 -243.862352) (xy 167.108632 -244.271292)
			(xy 173.149768 -244.271292) (xy 173.149768 -243.862352) (xy 173.150182 -243.852199) (xy 173.157987 -243.833452)
			(xy 173.172385 -243.819131) (xy 173.191175 -243.811427) (xy 173.20133 -243.811044) (xy 174.60087 -243.811044)
			(xy 174.610995 -243.811551) (xy 174.629717 -243.81927) (xy 174.644074 -243.83355) (xy 174.651894 -243.852229)
			(xy 174.652432 -243.862352) (xy 174.652432 -244.271292) (xy 180.693568 -244.271292) (xy 180.693568 -243.862352)
			(xy 180.693982 -243.852199) (xy 180.701787 -243.833452) (xy 180.716185 -243.819131) (xy 180.734975 -243.811427)
			(xy 180.74513 -243.811044) (xy 182.14467 -243.811044) (xy 182.154795 -243.811551) (xy 182.173517 -243.81927)
			(xy 182.187874 -243.83355) (xy 182.195694 -243.852229) (xy 182.196232 -243.862352) (xy 182.196232 -244.271292)
			(xy 188.237368 -244.271292) (xy 188.237368 -243.862352) (xy 188.237782 -243.852199) (xy 188.245587 -243.833452)
			(xy 188.259985 -243.819131) (xy 188.278775 -243.811427) (xy 188.28893 -243.811044) (xy 189.68847 -243.811044)
			(xy 189.698595 -243.811551) (xy 189.717317 -243.81927) (xy 189.731674 -243.83355) (xy 189.739494 -243.852229)
			(xy 189.740032 -243.862352) (xy 189.740032 -244.271292) (xy 195.781168 -244.271292) (xy 195.781168 -243.862352)
			(xy 195.781582 -243.852199) (xy 195.789387 -243.833452) (xy 195.803785 -243.819131) (xy 195.822575 -243.811427)
			(xy 195.83273 -243.811044) (xy 197.23227 -243.811044) (xy 197.242395 -243.811551) (xy 197.261117 -243.81927)
			(xy 197.275474 -243.83355) (xy 197.283294 -243.852229) (xy 197.283832 -243.862352) (xy 197.283832 -244.271292)
			(xy 203.324968 -244.271292) (xy 203.324968 -243.862352) (xy 203.325382 -243.852199) (xy 203.333187 -243.833452)
			(xy 203.347585 -243.819131) (xy 203.366375 -243.811427) (xy 203.37653 -243.811044) (xy 204.77607 -243.811044)
			(xy 204.786195 -243.811551) (xy 204.804917 -243.81927) (xy 204.819274 -243.83355) (xy 204.827094 -243.852229)
			(xy 204.827632 -243.862352) (xy 204.827632 -244.271292) (xy 210.868768 -244.271292) (xy 210.868768 -243.862352)
			(xy 210.869182 -243.852199) (xy 210.876987 -243.833452) (xy 210.891385 -243.819131) (xy 210.910175 -243.811427)
			(xy 210.92033 -243.811044) (xy 212.31987 -243.811044) (xy 212.329995 -243.811551) (xy 212.348717 -243.81927)
			(xy 212.363074 -243.83355) (xy 212.370894 -243.852229) (xy 212.371432 -243.862352) (xy 212.371432 -244.271292)
			(xy 255.329436 -244.271292) (xy 255.329436 -243.862352) (xy 255.329783 -243.85219) (xy 255.337601 -243.83343)
			(xy 255.352021 -243.819107) (xy 255.370834 -243.811416) (xy 255.380998 -243.811044) (xy 256.780538 -243.811044)
			(xy 256.790668 -243.811496) (xy 256.80939 -243.819237) (xy 256.823746 -243.833533) (xy 256.831563 -243.852224)
			(xy 256.8321 -243.862352) (xy 256.8321 -244.271292) (xy 262.873236 -244.271292) (xy 262.873236 -243.862352)
			(xy 262.873583 -243.85219) (xy 262.881401 -243.83343) (xy 262.895821 -243.819107) (xy 262.914634 -243.811416)
			(xy 262.924798 -243.811044) (xy 264.324338 -243.811044) (xy 264.334468 -243.811496) (xy 264.35319 -243.819237)
			(xy 264.367546 -243.833533) (xy 264.375363 -243.852224) (xy 264.3759 -243.862352) (xy 264.3759 -244.271292)
			(xy 270.417036 -244.271292) (xy 270.417036 -243.862352) (xy 270.417383 -243.85219) (xy 270.425201 -243.83343)
			(xy 270.439621 -243.819107) (xy 270.458434 -243.811416) (xy 270.468598 -243.811044) (xy 271.868138 -243.811044)
			(xy 271.878268 -243.811496) (xy 271.89699 -243.819237) (xy 271.911346 -243.833533) (xy 271.919163 -243.852224)
			(xy 271.9197 -243.862352) (xy 271.9197 -244.271292) (xy 277.960836 -244.271292) (xy 277.960836 -243.862352)
			(xy 277.961183 -243.85219) (xy 277.969001 -243.83343) (xy 277.983421 -243.819107) (xy 278.002234 -243.811416)
			(xy 278.012398 -243.811044) (xy 279.411938 -243.811044) (xy 279.422068 -243.811496) (xy 279.44079 -243.819237)
			(xy 279.455146 -243.833533) (xy 279.462963 -243.852224) (xy 279.4635 -243.862352) (xy 279.4635 -244.271292)
			(xy 285.504636 -244.271292) (xy 285.504636 -243.862352) (xy 285.504983 -243.85219) (xy 285.512801 -243.83343)
			(xy 285.527221 -243.819107) (xy 285.546034 -243.811416) (xy 285.556198 -243.811044) (xy 286.955738 -243.811044)
			(xy 286.965868 -243.811496) (xy 286.98459 -243.819237) (xy 286.998946 -243.833533) (xy 287.006763 -243.852224)
			(xy 287.0073 -243.862352) (xy 287.0073 -244.271292) (xy 293.048436 -244.271292) (xy 293.048436 -243.862352)
			(xy 293.048783 -243.85219) (xy 293.056601 -243.83343) (xy 293.071021 -243.819107) (xy 293.089834 -243.811416)
			(xy 293.099998 -243.811044) (xy 294.499538 -243.811044) (xy 294.509668 -243.811496) (xy 294.52839 -243.819237)
			(xy 294.542746 -243.833533) (xy 294.550563 -243.852224) (xy 294.5511 -243.862352) (xy 294.5511 -244.271292)
			(xy 300.592236 -244.271292) (xy 300.592236 -243.862352) (xy 300.592583 -243.85219) (xy 300.600401 -243.83343)
			(xy 300.614821 -243.819107) (xy 300.633634 -243.811416) (xy 300.643798 -243.811044) (xy 302.043338 -243.811044)
			(xy 302.053468 -243.811496) (xy 302.07219 -243.819237) (xy 302.086546 -243.833533) (xy 302.094363 -243.852224)
			(xy 302.0949 -243.862352) (xy 302.0949 -244.271292) (xy 308.136036 -244.271292) (xy 308.136036 -243.862352)
			(xy 308.136383 -243.85219) (xy 308.144201 -243.83343) (xy 308.158621 -243.819107) (xy 308.177434 -243.811416)
			(xy 308.187598 -243.811044) (xy 309.587138 -243.811044) (xy 309.597268 -243.811496) (xy 309.61599 -243.819237)
			(xy 309.630346 -243.833533) (xy 309.638163 -243.852224) (xy 309.6387 -243.862352) (xy 309.6387 -244.271292)
			(xy 406.002236 -244.271292) (xy 406.002236 -243.862352) (xy 406.002583 -243.85219) (xy 406.010401 -243.83343)
			(xy 406.024821 -243.819107) (xy 406.043634 -243.811416) (xy 406.053798 -243.811044) (xy 407.453338 -243.811044)
			(xy 407.463468 -243.811496) (xy 407.48219 -243.819237) (xy 407.496546 -243.833533) (xy 407.504363 -243.852224)
			(xy 407.5049 -243.862352) (xy 407.5049 -244.271292) (xy 413.546036 -244.271292) (xy 413.546036 -243.862352)
			(xy 413.546383 -243.85219) (xy 413.554201 -243.83343) (xy 413.568621 -243.819107) (xy 413.587434 -243.811416)
			(xy 413.597598 -243.811044) (xy 414.997138 -243.811044) (xy 415.007268 -243.811496) (xy 415.02599 -243.819237)
			(xy 415.040346 -243.833533) (xy 415.048163 -243.852224) (xy 415.0487 -243.862352) (xy 415.0487 -244.271292)
			(xy 421.089836 -244.271292) (xy 421.089836 -243.862352) (xy 421.090183 -243.85219) (xy 421.098001 -243.83343)
			(xy 421.112421 -243.819107) (xy 421.131234 -243.811416) (xy 421.141398 -243.811044) (xy 422.540938 -243.811044)
			(xy 422.551068 -243.811496) (xy 422.56979 -243.819237) (xy 422.584146 -243.833533) (xy 422.591963 -243.852224)
			(xy 422.5925 -243.862352) (xy 422.5925 -244.271292) (xy 428.633636 -244.271292) (xy 428.633636 -243.862352)
			(xy 428.633983 -243.85219) (xy 428.641801 -243.83343) (xy 428.656221 -243.819107) (xy 428.675034 -243.811416)
			(xy 428.685198 -243.811044) (xy 430.084738 -243.811044) (xy 430.094868 -243.811496) (xy 430.11359 -243.819237)
			(xy 430.127946 -243.833533) (xy 430.135763 -243.852224) (xy 430.1363 -243.862352) (xy 430.1363 -244.271292)
			(xy 436.177436 -244.271292) (xy 436.177436 -243.862352) (xy 436.177783 -243.85219) (xy 436.185601 -243.83343)
			(xy 436.200021 -243.819107) (xy 436.218834 -243.811416) (xy 436.228998 -243.811044) (xy 437.628538 -243.811044)
			(xy 437.638668 -243.811496) (xy 437.65739 -243.819237) (xy 437.671746 -243.833533) (xy 437.679563 -243.852224)
			(xy 437.6801 -243.862352) (xy 437.6801 -244.271292) (xy 443.721236 -244.271292) (xy 443.721236 -243.862352)
			(xy 443.721583 -243.85219) (xy 443.729401 -243.83343) (xy 443.743821 -243.819107) (xy 443.762634 -243.811416)
			(xy 443.772798 -243.811044) (xy 445.172338 -243.811044) (xy 445.182468 -243.811496) (xy 445.20119 -243.819237)
			(xy 445.215546 -243.833533) (xy 445.223363 -243.852224) (xy 445.2239 -243.862352) (xy 445.2239 -244.271292)
			(xy 451.265036 -244.271292) (xy 451.265036 -243.862352) (xy 451.265383 -243.85219) (xy 451.273201 -243.83343)
			(xy 451.287621 -243.819107) (xy 451.306434 -243.811416) (xy 451.316598 -243.811044) (xy 452.716138 -243.811044)
			(xy 452.726268 -243.811496) (xy 452.74499 -243.819237) (xy 452.759346 -243.833533) (xy 452.767163 -243.852224)
			(xy 452.7677 -243.862352) (xy 452.7677 -244.271292) (xy 458.808836 -244.271292) (xy 458.808836 -243.862352)
			(xy 458.809183 -243.85219) (xy 458.817001 -243.83343) (xy 458.831421 -243.819107) (xy 458.850234 -243.811416)
			(xy 458.860398 -243.811044) (xy 460.259938 -243.811044) (xy 460.270068 -243.811496) (xy 460.28879 -243.819237)
			(xy 460.303146 -243.833533) (xy 460.310963 -243.852224) (xy 460.3115 -243.862352) (xy 460.3115 -244.271292)
			(xy 460.311072 -244.281446) (xy 460.303279 -244.300198) (xy 460.288884 -244.314521) (xy 460.270094 -244.322221)
			(xy 460.259938 -244.3226) (xy 458.860398 -244.3226) (xy 458.850276 -244.322076) (xy 458.831563 -244.314355)
			(xy 458.817208 -244.300081) (xy 458.809382 -244.281411) (xy 458.808836 -244.271292) (xy 452.7677 -244.271292)
			(xy 452.767272 -244.281446) (xy 452.759479 -244.300198) (xy 452.745084 -244.314521) (xy 452.726294 -244.322221)
			(xy 452.716138 -244.3226) (xy 451.316598 -244.3226) (xy 451.306476 -244.322076) (xy 451.287763 -244.314355)
			(xy 451.273408 -244.300081) (xy 451.265582 -244.281411) (xy 451.265036 -244.271292) (xy 445.2239 -244.271292)
			(xy 445.223472 -244.281446) (xy 445.215679 -244.300198) (xy 445.201284 -244.314521) (xy 445.182494 -244.322221)
			(xy 445.172338 -244.3226) (xy 443.772798 -244.3226) (xy 443.762676 -244.322076) (xy 443.743963 -244.314355)
			(xy 443.729608 -244.300081) (xy 443.721782 -244.281411) (xy 443.721236 -244.271292) (xy 437.6801 -244.271292)
			(xy 437.679672 -244.281446) (xy 437.671879 -244.300198) (xy 437.657484 -244.314521) (xy 437.638694 -244.322221)
			(xy 437.628538 -244.3226) (xy 436.228998 -244.3226) (xy 436.218876 -244.322076) (xy 436.200163 -244.314355)
			(xy 436.185808 -244.300081) (xy 436.177982 -244.281411) (xy 436.177436 -244.271292) (xy 430.1363 -244.271292)
			(xy 430.135872 -244.281446) (xy 430.128079 -244.300198) (xy 430.113684 -244.314521) (xy 430.094894 -244.322221)
			(xy 430.084738 -244.3226) (xy 428.685198 -244.3226) (xy 428.675076 -244.322076) (xy 428.656363 -244.314355)
			(xy 428.642008 -244.300081) (xy 428.634182 -244.281411) (xy 428.633636 -244.271292) (xy 422.5925 -244.271292)
			(xy 422.592072 -244.281446) (xy 422.584279 -244.300198) (xy 422.569884 -244.314521) (xy 422.551094 -244.322221)
			(xy 422.540938 -244.3226) (xy 421.141398 -244.3226) (xy 421.131276 -244.322076) (xy 421.112563 -244.314355)
			(xy 421.098208 -244.300081) (xy 421.090382 -244.281411) (xy 421.089836 -244.271292) (xy 415.0487 -244.271292)
			(xy 415.048272 -244.281446) (xy 415.040479 -244.300198) (xy 415.026084 -244.314521) (xy 415.007294 -244.322221)
			(xy 414.997138 -244.3226) (xy 413.597598 -244.3226) (xy 413.587476 -244.322076) (xy 413.568763 -244.314355)
			(xy 413.554408 -244.300081) (xy 413.546582 -244.281411) (xy 413.546036 -244.271292) (xy 407.5049 -244.271292)
			(xy 407.504472 -244.281446) (xy 407.496679 -244.300198) (xy 407.482284 -244.314521) (xy 407.463494 -244.322221)
			(xy 407.453338 -244.3226) (xy 406.053798 -244.3226) (xy 406.043676 -244.322076) (xy 406.024963 -244.314355)
			(xy 406.010608 -244.300081) (xy 406.002782 -244.281411) (xy 406.002236 -244.271292) (xy 309.6387 -244.271292)
			(xy 309.638272 -244.281446) (xy 309.630479 -244.300198) (xy 309.616084 -244.314521) (xy 309.597294 -244.322221)
			(xy 309.587138 -244.3226) (xy 308.187598 -244.3226) (xy 308.177476 -244.322076) (xy 308.158763 -244.314355)
			(xy 308.144408 -244.300081) (xy 308.136582 -244.281411) (xy 308.136036 -244.271292) (xy 302.0949 -244.271292)
			(xy 302.094472 -244.281446) (xy 302.086679 -244.300198) (xy 302.072284 -244.314521) (xy 302.053494 -244.322221)
			(xy 302.043338 -244.3226) (xy 300.643798 -244.3226) (xy 300.633676 -244.322076) (xy 300.614963 -244.314355)
			(xy 300.600608 -244.300081) (xy 300.592782 -244.281411) (xy 300.592236 -244.271292) (xy 294.5511 -244.271292)
			(xy 294.550672 -244.281446) (xy 294.542879 -244.300198) (xy 294.528484 -244.314521) (xy 294.509694 -244.322221)
			(xy 294.499538 -244.3226) (xy 293.099998 -244.3226) (xy 293.089876 -244.322076) (xy 293.071163 -244.314355)
			(xy 293.056808 -244.300081) (xy 293.048982 -244.281411) (xy 293.048436 -244.271292) (xy 287.0073 -244.271292)
			(xy 287.006872 -244.281446) (xy 286.999079 -244.300198) (xy 286.984684 -244.314521) (xy 286.965894 -244.322221)
			(xy 286.955738 -244.3226) (xy 285.556198 -244.3226) (xy 285.546076 -244.322076) (xy 285.527363 -244.314355)
			(xy 285.513008 -244.300081) (xy 285.505182 -244.281411) (xy 285.504636 -244.271292) (xy 279.4635 -244.271292)
			(xy 279.463072 -244.281446) (xy 279.455279 -244.300198) (xy 279.440884 -244.314521) (xy 279.422094 -244.322221)
			(xy 279.411938 -244.3226) (xy 278.012398 -244.3226) (xy 278.002276 -244.322076) (xy 277.983563 -244.314355)
			(xy 277.969208 -244.300081) (xy 277.961382 -244.281411) (xy 277.960836 -244.271292) (xy 271.9197 -244.271292)
			(xy 271.919272 -244.281446) (xy 271.911479 -244.300198) (xy 271.897084 -244.314521) (xy 271.878294 -244.322221)
			(xy 271.868138 -244.3226) (xy 270.468598 -244.3226) (xy 270.458476 -244.322076) (xy 270.439763 -244.314355)
			(xy 270.425408 -244.300081) (xy 270.417582 -244.281411) (xy 270.417036 -244.271292) (xy 264.3759 -244.271292)
			(xy 264.375472 -244.281446) (xy 264.367679 -244.300198) (xy 264.353284 -244.314521) (xy 264.334494 -244.322221)
			(xy 264.324338 -244.3226) (xy 262.924798 -244.3226) (xy 262.914676 -244.322076) (xy 262.895963 -244.314355)
			(xy 262.881608 -244.300081) (xy 262.873782 -244.281411) (xy 262.873236 -244.271292) (xy 256.8321 -244.271292)
			(xy 256.831672 -244.281446) (xy 256.823879 -244.300198) (xy 256.809484 -244.314521) (xy 256.790694 -244.322221)
			(xy 256.780538 -244.3226) (xy 255.380998 -244.3226) (xy 255.370876 -244.322076) (xy 255.352163 -244.314355)
			(xy 255.337808 -244.300081) (xy 255.329982 -244.281411) (xy 255.329436 -244.271292) (xy 212.371432 -244.271292)
			(xy 212.370972 -244.281442) (xy 212.363186 -244.300188) (xy 212.348801 -244.31451) (xy 212.330021 -244.322216)
			(xy 212.31987 -244.3226) (xy 210.92033 -244.3226) (xy 210.91021 -244.32205) (xy 210.891497 -244.31434)
			(xy 210.877141 -244.300073) (xy 210.869314 -244.281409) (xy 210.868768 -244.271292) (xy 204.827632 -244.271292)
			(xy 204.827172 -244.281442) (xy 204.819386 -244.300188) (xy 204.805001 -244.31451) (xy 204.786221 -244.322216)
			(xy 204.77607 -244.3226) (xy 203.37653 -244.3226) (xy 203.36641 -244.32205) (xy 203.347697 -244.31434)
			(xy 203.333341 -244.300073) (xy 203.325514 -244.281409) (xy 203.324968 -244.271292) (xy 197.283832 -244.271292)
			(xy 197.283372 -244.281442) (xy 197.275586 -244.300188) (xy 197.261201 -244.31451) (xy 197.242421 -244.322216)
			(xy 197.23227 -244.3226) (xy 195.83273 -244.3226) (xy 195.82261 -244.32205) (xy 195.803897 -244.31434)
			(xy 195.789541 -244.300073) (xy 195.781714 -244.281409) (xy 195.781168 -244.271292) (xy 189.740032 -244.271292)
			(xy 189.739572 -244.281442) (xy 189.731786 -244.300188) (xy 189.717401 -244.31451) (xy 189.698621 -244.322216)
			(xy 189.68847 -244.3226) (xy 188.28893 -244.3226) (xy 188.27881 -244.32205) (xy 188.260097 -244.31434)
			(xy 188.245741 -244.300073) (xy 188.237914 -244.281409) (xy 188.237368 -244.271292) (xy 182.196232 -244.271292)
			(xy 182.195772 -244.281442) (xy 182.187986 -244.300188) (xy 182.173601 -244.31451) (xy 182.154821 -244.322216)
			(xy 182.14467 -244.3226) (xy 180.74513 -244.3226) (xy 180.73501 -244.32205) (xy 180.716297 -244.31434)
			(xy 180.701941 -244.300073) (xy 180.694114 -244.281409) (xy 180.693568 -244.271292) (xy 174.652432 -244.271292)
			(xy 174.651972 -244.281442) (xy 174.644186 -244.300188) (xy 174.629801 -244.31451) (xy 174.611021 -244.322216)
			(xy 174.60087 -244.3226) (xy 173.20133 -244.3226) (xy 173.19121 -244.32205) (xy 173.172497 -244.31434)
			(xy 173.158141 -244.300073) (xy 173.150314 -244.281409) (xy 173.149768 -244.271292) (xy 167.108632 -244.271292)
			(xy 167.108172 -244.281442) (xy 167.100386 -244.300188) (xy 167.086001 -244.31451) (xy 167.067221 -244.322216)
			(xy 167.05707 -244.3226) (xy 165.65753 -244.3226) (xy 165.64741 -244.32205) (xy 165.628697 -244.31434)
			(xy 165.614341 -244.300073) (xy 165.606514 -244.281409) (xy 165.605968 -244.271292) (xy 159.564832 -244.271292)
			(xy 159.564372 -244.281442) (xy 159.556586 -244.300188) (xy 159.542201 -244.31451) (xy 159.523421 -244.322216)
			(xy 159.51327 -244.3226) (xy 158.11373 -244.3226) (xy 158.10361 -244.32205) (xy 158.084897 -244.31434)
			(xy 158.070541 -244.300073) (xy 158.062714 -244.281409) (xy 158.062168 -244.271292) (xy 61.698632 -244.271292)
			(xy 61.698172 -244.281442) (xy 61.690386 -244.300188) (xy 61.676001 -244.31451) (xy 61.657221 -244.322216)
			(xy 61.64707 -244.3226) (xy 60.24753 -244.3226) (xy 60.23741 -244.32205) (xy 60.218697 -244.31434)
			(xy 60.204341 -244.300073) (xy 60.196514 -244.281409) (xy 60.195968 -244.271292) (xy 54.154832 -244.271292)
			(xy 54.154372 -244.281442) (xy 54.146586 -244.300188) (xy 54.132201 -244.31451) (xy 54.113421 -244.322216)
			(xy 54.10327 -244.3226) (xy 52.70373 -244.3226) (xy 52.69361 -244.32205) (xy 52.674897 -244.31434)
			(xy 52.660541 -244.300073) (xy 52.652714 -244.281409) (xy 52.652168 -244.271292) (xy 46.611032 -244.271292)
			(xy 46.610572 -244.281442) (xy 46.602786 -244.300188) (xy 46.588401 -244.31451) (xy 46.569621 -244.322216)
			(xy 46.55947 -244.3226) (xy 45.15993 -244.3226) (xy 45.14981 -244.32205) (xy 45.131097 -244.31434)
			(xy 45.116741 -244.300073) (xy 45.108914 -244.281409) (xy 45.108368 -244.271292) (xy 39.067232 -244.271292)
			(xy 39.066772 -244.281442) (xy 39.058986 -244.300188) (xy 39.044601 -244.31451) (xy 39.025821 -244.322216)
			(xy 39.01567 -244.3226) (xy 37.61613 -244.3226) (xy 37.60601 -244.32205) (xy 37.587297 -244.31434)
			(xy 37.572941 -244.300073) (xy 37.565114 -244.281409) (xy 37.564568 -244.271292) (xy 31.523432 -244.271292)
			(xy 31.522972 -244.281442) (xy 31.515186 -244.300188) (xy 31.500801 -244.31451) (xy 31.482021 -244.322216)
			(xy 31.47187 -244.3226) (xy 30.07233 -244.3226) (xy 30.06221 -244.32205) (xy 30.043497 -244.31434)
			(xy 30.029141 -244.300073) (xy 30.021314 -244.281409) (xy 30.020768 -244.271292) (xy 23.979632 -244.271292)
			(xy 23.979172 -244.281442) (xy 23.971386 -244.300188) (xy 23.957001 -244.31451) (xy 23.938221 -244.322216)
			(xy 23.92807 -244.3226) (xy 22.52853 -244.3226) (xy 22.51841 -244.32205) (xy 22.499697 -244.31434)
			(xy 22.485341 -244.300073) (xy 22.477514 -244.281409) (xy 22.476968 -244.271292) (xy 16.435832 -244.271292)
			(xy 16.435372 -244.281442) (xy 16.427586 -244.300188) (xy 16.413201 -244.31451) (xy 16.394421 -244.322216)
			(xy 16.38427 -244.3226) (xy 14.98473 -244.3226) (xy 14.97461 -244.32205) (xy 14.955897 -244.31434)
			(xy 14.941541 -244.300073) (xy 14.933714 -244.281409) (xy 14.933168 -244.271292) (xy 8.892032 -244.271292)
			(xy 8.891572 -244.281442) (xy 8.883786 -244.300188) (xy 8.869401 -244.31451) (xy 8.850621 -244.322216)
			(xy 8.84047 -244.3226) (xy 7.44093 -244.3226) (xy 7.43081 -244.32205) (xy 7.412097 -244.31434) (xy 7.397741 -244.300073)
			(xy 7.389914 -244.281409) (xy 7.389368 -244.271292) (xy 2.509012 -244.271292) (xy 2.509012 -245.12143)
			(xy 11.489436 -245.12143) (xy 11.489436 -244.71249) (xy 11.489925 -244.702332) (xy 11.497703 -244.683563)
			(xy 11.51207 -244.669198) (xy 11.53084 -244.661424) (xy 11.540998 -244.660928) (xy 12.940538 -244.660928)
			(xy 12.950697 -244.661402) (xy 12.969465 -244.669187) (xy 12.983829 -244.683558) (xy 12.991604 -244.702331)
			(xy 12.9921 -244.71249) (xy 12.9921 -245.12143) (xy 19.033236 -245.12143) (xy 19.033236 -244.71249)
			(xy 19.033725 -244.702332) (xy 19.041503 -244.683563) (xy 19.05587 -244.669198) (xy 19.07464 -244.661424)
			(xy 19.084798 -244.660928) (xy 20.484338 -244.660928) (xy 20.494497 -244.661402) (xy 20.513265 -244.669187)
			(xy 20.527629 -244.683558) (xy 20.535404 -244.702331) (xy 20.5359 -244.71249) (xy 20.5359 -245.12143)
			(xy 26.577036 -245.12143) (xy 26.577036 -244.71249) (xy 26.577525 -244.702332) (xy 26.585303 -244.683563)
			(xy 26.59967 -244.669198) (xy 26.61844 -244.661424) (xy 26.628598 -244.660928) (xy 28.028138 -244.660928)
			(xy 28.038297 -244.661402) (xy 28.057065 -244.669187) (xy 28.071429 -244.683558) (xy 28.079204 -244.702331)
			(xy 28.0797 -244.71249) (xy 28.0797 -245.12143) (xy 34.120836 -245.12143) (xy 34.120836 -244.71249)
			(xy 34.121325 -244.702332) (xy 34.129103 -244.683563) (xy 34.14347 -244.669198) (xy 34.16224 -244.661424)
			(xy 34.172398 -244.660928) (xy 35.571938 -244.660928) (xy 35.582097 -244.661402) (xy 35.600865 -244.669187)
			(xy 35.615229 -244.683558) (xy 35.623004 -244.702331) (xy 35.6235 -244.71249) (xy 35.6235 -245.12143)
			(xy 41.664636 -245.12143) (xy 41.664636 -244.71249) (xy 41.665125 -244.702332) (xy 41.672903 -244.683563)
			(xy 41.68727 -244.669198) (xy 41.70604 -244.661424) (xy 41.716198 -244.660928) (xy 43.115738 -244.660928)
			(xy 43.125897 -244.661402) (xy 43.144665 -244.669187) (xy 43.159029 -244.683558) (xy 43.166804 -244.702331)
			(xy 43.1673 -244.71249) (xy 43.1673 -245.12143) (xy 49.208436 -245.12143) (xy 49.208436 -244.71249)
			(xy 49.208925 -244.702332) (xy 49.216703 -244.683563) (xy 49.23107 -244.669198) (xy 49.24984 -244.661424)
			(xy 49.259998 -244.660928) (xy 50.659538 -244.660928) (xy 50.669697 -244.661402) (xy 50.688465 -244.669187)
			(xy 50.702829 -244.683558) (xy 50.710604 -244.702331) (xy 50.7111 -244.71249) (xy 50.7111 -245.12143)
			(xy 56.752236 -245.12143) (xy 56.752236 -244.71249) (xy 56.752725 -244.702332) (xy 56.760503 -244.683563)
			(xy 56.77487 -244.669198) (xy 56.79364 -244.661424) (xy 56.803798 -244.660928) (xy 58.203338 -244.660928)
			(xy 58.213497 -244.661402) (xy 58.232265 -244.669187) (xy 58.246629 -244.683558) (xy 58.254404 -244.702331)
			(xy 58.2549 -244.71249) (xy 58.2549 -245.12143) (xy 64.296036 -245.12143) (xy 64.296036 -244.71249)
			(xy 64.296525 -244.702332) (xy 64.304303 -244.683563) (xy 64.31867 -244.669198) (xy 64.33744 -244.661424)
			(xy 64.347598 -244.660928) (xy 65.747138 -244.660928) (xy 65.757297 -244.661402) (xy 65.776065 -244.669187)
			(xy 65.790429 -244.683558) (xy 65.798204 -244.702331) (xy 65.7987 -244.71249) (xy 65.7987 -245.12143)
			(xy 162.162236 -245.12143) (xy 162.162236 -244.71249) (xy 162.162725 -244.702332) (xy 162.170503 -244.683563)
			(xy 162.18487 -244.669198) (xy 162.20364 -244.661424) (xy 162.213798 -244.660928) (xy 163.613338 -244.660928)
			(xy 163.623497 -244.661402) (xy 163.642265 -244.669187) (xy 163.656629 -244.683558) (xy 163.664404 -244.702331)
			(xy 163.6649 -244.71249) (xy 163.6649 -245.12143) (xy 169.706036 -245.12143) (xy 169.706036 -244.71249)
			(xy 169.706525 -244.702332) (xy 169.714303 -244.683563) (xy 169.72867 -244.669198) (xy 169.74744 -244.661424)
			(xy 169.757598 -244.660928) (xy 171.157138 -244.660928) (xy 171.167297 -244.661402) (xy 171.186065 -244.669187)
			(xy 171.200429 -244.683558) (xy 171.208204 -244.702331) (xy 171.2087 -244.71249) (xy 171.2087 -245.12143)
			(xy 177.249836 -245.12143) (xy 177.249836 -244.71249) (xy 177.250325 -244.702332) (xy 177.258103 -244.683563)
			(xy 177.27247 -244.669198) (xy 177.29124 -244.661424) (xy 177.301398 -244.660928) (xy 178.700938 -244.660928)
			(xy 178.711097 -244.661402) (xy 178.729865 -244.669187) (xy 178.744229 -244.683558) (xy 178.752004 -244.702331)
			(xy 178.7525 -244.71249) (xy 178.7525 -245.12143) (xy 184.793636 -245.12143) (xy 184.793636 -244.71249)
			(xy 184.794125 -244.702332) (xy 184.801903 -244.683563) (xy 184.81627 -244.669198) (xy 184.83504 -244.661424)
			(xy 184.845198 -244.660928) (xy 186.244738 -244.660928) (xy 186.254897 -244.661402) (xy 186.273665 -244.669187)
			(xy 186.288029 -244.683558) (xy 186.295804 -244.702331) (xy 186.2963 -244.71249) (xy 186.2963 -245.12143)
			(xy 192.337436 -245.12143) (xy 192.337436 -244.71249) (xy 192.337925 -244.702332) (xy 192.345703 -244.683563)
			(xy 192.36007 -244.669198) (xy 192.37884 -244.661424) (xy 192.388998 -244.660928) (xy 193.788538 -244.660928)
			(xy 193.798697 -244.661402) (xy 193.817465 -244.669187) (xy 193.831829 -244.683558) (xy 193.839604 -244.702331)
			(xy 193.8401 -244.71249) (xy 193.8401 -245.12143) (xy 199.881236 -245.12143) (xy 199.881236 -244.71249)
			(xy 199.881725 -244.702332) (xy 199.889503 -244.683563) (xy 199.90387 -244.669198) (xy 199.92264 -244.661424)
			(xy 199.932798 -244.660928) (xy 201.332338 -244.660928) (xy 201.342497 -244.661402) (xy 201.361265 -244.669187)
			(xy 201.375629 -244.683558) (xy 201.383404 -244.702331) (xy 201.3839 -244.71249) (xy 201.3839 -245.12143)
			(xy 207.425036 -245.12143) (xy 207.425036 -244.71249) (xy 207.425525 -244.702332) (xy 207.433303 -244.683563)
			(xy 207.44767 -244.669198) (xy 207.46644 -244.661424) (xy 207.476598 -244.660928) (xy 208.876138 -244.660928)
			(xy 208.886297 -244.661402) (xy 208.905065 -244.669187) (xy 208.919429 -244.683558) (xy 208.927204 -244.702331)
			(xy 208.9277 -244.71249) (xy 208.9277 -245.12143) (xy 214.968836 -245.12143) (xy 214.968836 -244.71249)
			(xy 214.969325 -244.702332) (xy 214.977103 -244.683563) (xy 214.99147 -244.669198) (xy 215.01024 -244.661424)
			(xy 215.020398 -244.660928) (xy 216.419938 -244.660928) (xy 216.430097 -244.661402) (xy 216.448865 -244.669187)
			(xy 216.463229 -244.683558) (xy 216.471004 -244.702331) (xy 216.4715 -244.71249) (xy 216.4715 -245.12143)
			(xy 259.429504 -245.12143) (xy 259.429504 -244.71249) (xy 259.430025 -244.702336) (xy 259.437796 -244.683573)
			(xy 259.452153 -244.669209) (xy 259.470912 -244.661429) (xy 259.481066 -244.660928) (xy 260.880606 -244.660928)
			(xy 260.890763 -244.661428) (xy 260.90953 -244.669203) (xy 260.923895 -244.683566) (xy 260.931671 -244.702333)
			(xy 260.932168 -244.71249) (xy 260.932168 -245.12143) (xy 266.973304 -245.12143) (xy 266.973304 -244.71249)
			(xy 266.973825 -244.702336) (xy 266.981596 -244.683573) (xy 266.995953 -244.669209) (xy 267.014712 -244.661429)
			(xy 267.024866 -244.660928) (xy 268.424406 -244.660928) (xy 268.434563 -244.661428) (xy 268.45333 -244.669203)
			(xy 268.467695 -244.683566) (xy 268.475471 -244.702333) (xy 268.475968 -244.71249) (xy 268.475968 -245.12143)
			(xy 274.517104 -245.12143) (xy 274.517104 -244.71249) (xy 274.517625 -244.702336) (xy 274.525396 -244.683573)
			(xy 274.539753 -244.669209) (xy 274.558512 -244.661429) (xy 274.568666 -244.660928) (xy 275.968206 -244.660928)
			(xy 275.978363 -244.661428) (xy 275.99713 -244.669203) (xy 276.011495 -244.683566) (xy 276.019271 -244.702333)
			(xy 276.019768 -244.71249) (xy 276.019768 -245.12143) (xy 282.060904 -245.12143) (xy 282.060904 -244.71249)
			(xy 282.061425 -244.702336) (xy 282.069196 -244.683573) (xy 282.083553 -244.669209) (xy 282.102312 -244.661429)
			(xy 282.112466 -244.660928) (xy 283.512006 -244.660928) (xy 283.522163 -244.661428) (xy 283.54093 -244.669203)
			(xy 283.555295 -244.683566) (xy 283.563071 -244.702333) (xy 283.563568 -244.71249) (xy 283.563568 -245.12143)
			(xy 289.604704 -245.12143) (xy 289.604704 -244.71249) (xy 289.605225 -244.702336) (xy 289.612996 -244.683573)
			(xy 289.627353 -244.669209) (xy 289.646112 -244.661429) (xy 289.656266 -244.660928) (xy 291.055806 -244.660928)
			(xy 291.065963 -244.661428) (xy 291.08473 -244.669203) (xy 291.099095 -244.683566) (xy 291.106871 -244.702333)
			(xy 291.107368 -244.71249) (xy 291.107368 -245.12143) (xy 297.148504 -245.12143) (xy 297.148504 -244.71249)
			(xy 297.149025 -244.702336) (xy 297.156796 -244.683573) (xy 297.171153 -244.669209) (xy 297.189912 -244.661429)
			(xy 297.200066 -244.660928) (xy 298.599606 -244.660928) (xy 298.609763 -244.661428) (xy 298.62853 -244.669203)
			(xy 298.642895 -244.683566) (xy 298.650671 -244.702333) (xy 298.651168 -244.71249) (xy 298.651168 -245.12143)
			(xy 304.692304 -245.12143) (xy 304.692304 -244.71249) (xy 304.692825 -244.702336) (xy 304.700596 -244.683573)
			(xy 304.714953 -244.669209) (xy 304.733712 -244.661429) (xy 304.743866 -244.660928) (xy 306.143406 -244.660928)
			(xy 306.153563 -244.661428) (xy 306.17233 -244.669203) (xy 306.186695 -244.683566) (xy 306.194471 -244.702333)
			(xy 306.194968 -244.71249) (xy 306.194968 -245.12143) (xy 312.236104 -245.12143) (xy 312.236104 -244.71249)
			(xy 312.236625 -244.702336) (xy 312.244396 -244.683573) (xy 312.258753 -244.669209) (xy 312.277512 -244.661429)
			(xy 312.287666 -244.660928) (xy 313.687206 -244.660928) (xy 313.697363 -244.661428) (xy 313.71613 -244.669203)
			(xy 313.730495 -244.683566) (xy 313.738271 -244.702333) (xy 313.738768 -244.71249) (xy 313.738768 -245.12143)
			(xy 410.102304 -245.12143) (xy 410.102304 -244.71249) (xy 410.102825 -244.702336) (xy 410.110596 -244.683573)
			(xy 410.124953 -244.669209) (xy 410.143712 -244.661429) (xy 410.153866 -244.660928) (xy 411.553406 -244.660928)
			(xy 411.563563 -244.661428) (xy 411.58233 -244.669203) (xy 411.596695 -244.683566) (xy 411.604471 -244.702333)
			(xy 411.604968 -244.71249) (xy 411.604968 -245.12143) (xy 417.646104 -245.12143) (xy 417.646104 -244.71249)
			(xy 417.646625 -244.702336) (xy 417.654396 -244.683573) (xy 417.668753 -244.669209) (xy 417.687512 -244.661429)
			(xy 417.697666 -244.660928) (xy 419.097206 -244.660928) (xy 419.107363 -244.661428) (xy 419.12613 -244.669203)
			(xy 419.140495 -244.683566) (xy 419.148271 -244.702333) (xy 419.148768 -244.71249) (xy 419.148768 -245.12143)
			(xy 425.189904 -245.12143) (xy 425.189904 -244.71249) (xy 425.190425 -244.702336) (xy 425.198196 -244.683573)
			(xy 425.212553 -244.669209) (xy 425.231312 -244.661429) (xy 425.241466 -244.660928) (xy 426.641006 -244.660928)
			(xy 426.651163 -244.661428) (xy 426.66993 -244.669203) (xy 426.684295 -244.683566) (xy 426.692071 -244.702333)
			(xy 426.692568 -244.71249) (xy 426.692568 -245.12143) (xy 432.733704 -245.12143) (xy 432.733704 -244.71249)
			(xy 432.734225 -244.702336) (xy 432.741996 -244.683573) (xy 432.756353 -244.669209) (xy 432.775112 -244.661429)
			(xy 432.785266 -244.660928) (xy 434.184806 -244.660928) (xy 434.194963 -244.661428) (xy 434.21373 -244.669203)
			(xy 434.228095 -244.683566) (xy 434.235871 -244.702333) (xy 434.236368 -244.71249) (xy 434.236368 -245.12143)
			(xy 440.277504 -245.12143) (xy 440.277504 -244.71249) (xy 440.278025 -244.702336) (xy 440.285796 -244.683573)
			(xy 440.300153 -244.669209) (xy 440.318912 -244.661429) (xy 440.329066 -244.660928) (xy 441.728606 -244.660928)
			(xy 441.738763 -244.661428) (xy 441.75753 -244.669203) (xy 441.771895 -244.683566) (xy 441.779671 -244.702333)
			(xy 441.780168 -244.71249) (xy 441.780168 -245.12143) (xy 447.821304 -245.12143) (xy 447.821304 -244.71249)
			(xy 447.821825 -244.702336) (xy 447.829596 -244.683573) (xy 447.843953 -244.669209) (xy 447.862712 -244.661429)
			(xy 447.872866 -244.660928) (xy 449.272406 -244.660928) (xy 449.282563 -244.661428) (xy 449.30133 -244.669203)
			(xy 449.315695 -244.683566) (xy 449.323471 -244.702333) (xy 449.323968 -244.71249) (xy 449.323968 -245.12143)
			(xy 455.365104 -245.12143) (xy 455.365104 -244.71249) (xy 455.365625 -244.702336) (xy 455.373396 -244.683573)
			(xy 455.387753 -244.669209) (xy 455.406512 -244.661429) (xy 455.416666 -244.660928) (xy 456.816206 -244.660928)
			(xy 456.826363 -244.661428) (xy 456.84513 -244.669203) (xy 456.859495 -244.683566) (xy 456.867271 -244.702333)
			(xy 456.867768 -244.71249) (xy 456.867768 -245.12143) (xy 462.908904 -245.12143) (xy 462.908904 -244.71249)
			(xy 462.909425 -244.702336) (xy 462.917196 -244.683573) (xy 462.931553 -244.669209) (xy 462.950312 -244.661429)
			(xy 462.960466 -244.660928) (xy 464.360006 -244.660928) (xy 464.370163 -244.661428) (xy 464.38893 -244.669203)
			(xy 464.403295 -244.683566) (xy 464.411071 -244.702333) (xy 464.411568 -244.71249) (xy 464.411568 -245.12143)
			(xy 464.411091 -245.131589) (xy 464.403308 -245.150358) (xy 464.388938 -245.164722) (xy 464.370165 -245.172496)
			(xy 464.360006 -245.172992) (xy 462.960466 -245.172992) (xy 462.95031 -245.172495) (xy 462.931546 -245.164715)
			(xy 462.917183 -245.150351) (xy 462.909404 -245.131586) (xy 462.908904 -245.12143) (xy 456.867768 -245.12143)
			(xy 456.867291 -245.131589) (xy 456.859508 -245.150358) (xy 456.845138 -245.164722) (xy 456.826365 -245.172496)
			(xy 456.816206 -245.172992) (xy 455.416666 -245.172992) (xy 455.40651 -245.172495) (xy 455.387746 -245.164715)
			(xy 455.373383 -245.150351) (xy 455.365604 -245.131586) (xy 455.365104 -245.12143) (xy 449.323968 -245.12143)
			(xy 449.323491 -245.131589) (xy 449.315708 -245.150358) (xy 449.301338 -245.164722) (xy 449.282565 -245.172496)
			(xy 449.272406 -245.172992) (xy 447.872866 -245.172992) (xy 447.86271 -245.172495) (xy 447.843946 -245.164715)
			(xy 447.829583 -245.150351) (xy 447.821804 -245.131586) (xy 447.821304 -245.12143) (xy 441.780168 -245.12143)
			(xy 441.779691 -245.131589) (xy 441.771908 -245.150358) (xy 441.757538 -245.164722) (xy 441.738765 -245.172496)
			(xy 441.728606 -245.172992) (xy 440.329066 -245.172992) (xy 440.31891 -245.172495) (xy 440.300146 -245.164715)
			(xy 440.285783 -245.150351) (xy 440.278004 -245.131586) (xy 440.277504 -245.12143) (xy 434.236368 -245.12143)
			(xy 434.235891 -245.131589) (xy 434.228108 -245.150358) (xy 434.213738 -245.164722) (xy 434.194965 -245.172496)
			(xy 434.184806 -245.172992) (xy 432.785266 -245.172992) (xy 432.77511 -245.172495) (xy 432.756346 -245.164715)
			(xy 432.741983 -245.150351) (xy 432.734204 -245.131586) (xy 432.733704 -245.12143) (xy 426.692568 -245.12143)
			(xy 426.692091 -245.131589) (xy 426.684308 -245.150358) (xy 426.669938 -245.164722) (xy 426.651165 -245.172496)
			(xy 426.641006 -245.172992) (xy 425.241466 -245.172992) (xy 425.23131 -245.172495) (xy 425.212546 -245.164715)
			(xy 425.198183 -245.150351) (xy 425.190404 -245.131586) (xy 425.189904 -245.12143) (xy 419.148768 -245.12143)
			(xy 419.148291 -245.131589) (xy 419.140508 -245.150358) (xy 419.126138 -245.164722) (xy 419.107365 -245.172496)
			(xy 419.097206 -245.172992) (xy 417.697666 -245.172992) (xy 417.68751 -245.172495) (xy 417.668746 -245.164715)
			(xy 417.654383 -245.150351) (xy 417.646604 -245.131586) (xy 417.646104 -245.12143) (xy 411.604968 -245.12143)
			(xy 411.604491 -245.131589) (xy 411.596708 -245.150358) (xy 411.582338 -245.164722) (xy 411.563565 -245.172496)
			(xy 411.553406 -245.172992) (xy 410.153866 -245.172992) (xy 410.14371 -245.172495) (xy 410.124946 -245.164715)
			(xy 410.110583 -245.150351) (xy 410.102804 -245.131586) (xy 410.102304 -245.12143) (xy 313.738768 -245.12143)
			(xy 313.738291 -245.131589) (xy 313.730508 -245.150358) (xy 313.716138 -245.164722) (xy 313.697365 -245.172496)
			(xy 313.687206 -245.172992) (xy 312.287666 -245.172992) (xy 312.27751 -245.172495) (xy 312.258746 -245.164715)
			(xy 312.244383 -245.150351) (xy 312.236604 -245.131586) (xy 312.236104 -245.12143) (xy 306.194968 -245.12143)
			(xy 306.194491 -245.131589) (xy 306.186708 -245.150358) (xy 306.172338 -245.164722) (xy 306.153565 -245.172496)
			(xy 306.143406 -245.172992) (xy 304.743866 -245.172992) (xy 304.73371 -245.172495) (xy 304.714946 -245.164715)
			(xy 304.700583 -245.150351) (xy 304.692804 -245.131586) (xy 304.692304 -245.12143) (xy 298.651168 -245.12143)
			(xy 298.650691 -245.131589) (xy 298.642908 -245.150358) (xy 298.628538 -245.164722) (xy 298.609765 -245.172496)
			(xy 298.599606 -245.172992) (xy 297.200066 -245.172992) (xy 297.18991 -245.172495) (xy 297.171146 -245.164715)
			(xy 297.156783 -245.150351) (xy 297.149004 -245.131586) (xy 297.148504 -245.12143) (xy 291.107368 -245.12143)
			(xy 291.106891 -245.131589) (xy 291.099108 -245.150358) (xy 291.084738 -245.164722) (xy 291.065965 -245.172496)
			(xy 291.055806 -245.172992) (xy 289.656266 -245.172992) (xy 289.64611 -245.172495) (xy 289.627346 -245.164715)
			(xy 289.612983 -245.150351) (xy 289.605204 -245.131586) (xy 289.604704 -245.12143) (xy 283.563568 -245.12143)
			(xy 283.563091 -245.131589) (xy 283.555308 -245.150358) (xy 283.540938 -245.164722) (xy 283.522165 -245.172496)
			(xy 283.512006 -245.172992) (xy 282.112466 -245.172992) (xy 282.10231 -245.172495) (xy 282.083546 -245.164715)
			(xy 282.069183 -245.150351) (xy 282.061404 -245.131586) (xy 282.060904 -245.12143) (xy 276.019768 -245.12143)
			(xy 276.019291 -245.131589) (xy 276.011508 -245.150358) (xy 275.997138 -245.164722) (xy 275.978365 -245.172496)
			(xy 275.968206 -245.172992) (xy 274.568666 -245.172992) (xy 274.55851 -245.172495) (xy 274.539746 -245.164715)
			(xy 274.525383 -245.150351) (xy 274.517604 -245.131586) (xy 274.517104 -245.12143) (xy 268.475968 -245.12143)
			(xy 268.475491 -245.131589) (xy 268.467708 -245.150358) (xy 268.453338 -245.164722) (xy 268.434565 -245.172496)
			(xy 268.424406 -245.172992) (xy 267.024866 -245.172992) (xy 267.01471 -245.172495) (xy 266.995946 -245.164715)
			(xy 266.981583 -245.150351) (xy 266.973804 -245.131586) (xy 266.973304 -245.12143) (xy 260.932168 -245.12143)
			(xy 260.931691 -245.131589) (xy 260.923908 -245.150358) (xy 260.909538 -245.164722) (xy 260.890765 -245.172496)
			(xy 260.880606 -245.172992) (xy 259.481066 -245.172992) (xy 259.47091 -245.172495) (xy 259.452146 -245.164715)
			(xy 259.437783 -245.150351) (xy 259.430004 -245.131586) (xy 259.429504 -245.12143) (xy 216.4715 -245.12143)
			(xy 216.470992 -245.131585) (xy 216.463215 -245.150348) (xy 216.448854 -245.16471) (xy 216.430093 -245.172491)
			(xy 216.419938 -245.172992) (xy 215.020398 -245.172992) (xy 215.010244 -245.172469) (xy 214.99148 -245.164699)
			(xy 214.977116 -245.150343) (xy 214.969337 -245.131584) (xy 214.968836 -245.12143) (xy 208.9277 -245.12143)
			(xy 208.927192 -245.131585) (xy 208.919415 -245.150348) (xy 208.905054 -245.16471) (xy 208.886293 -245.172491)
			(xy 208.876138 -245.172992) (xy 207.476598 -245.172992) (xy 207.466444 -245.172469) (xy 207.44768 -245.164699)
			(xy 207.433316 -245.150343) (xy 207.425537 -245.131584) (xy 207.425036 -245.12143) (xy 201.3839 -245.12143)
			(xy 201.383392 -245.131585) (xy 201.375615 -245.150348) (xy 201.361254 -245.16471) (xy 201.342493 -245.172491)
			(xy 201.332338 -245.172992) (xy 199.932798 -245.172992) (xy 199.922644 -245.172469) (xy 199.90388 -245.164699)
			(xy 199.889516 -245.150343) (xy 199.881737 -245.131584) (xy 199.881236 -245.12143) (xy 193.8401 -245.12143)
			(xy 193.839592 -245.131585) (xy 193.831815 -245.150348) (xy 193.817454 -245.16471) (xy 193.798693 -245.172491)
			(xy 193.788538 -245.172992) (xy 192.388998 -245.172992) (xy 192.378844 -245.172469) (xy 192.36008 -245.164699)
			(xy 192.345716 -245.150343) (xy 192.337937 -245.131584) (xy 192.337436 -245.12143) (xy 186.2963 -245.12143)
			(xy 186.295792 -245.131585) (xy 186.288015 -245.150348) (xy 186.273654 -245.16471) (xy 186.254893 -245.172491)
			(xy 186.244738 -245.172992) (xy 184.845198 -245.172992) (xy 184.835044 -245.172469) (xy 184.81628 -245.164699)
			(xy 184.801916 -245.150343) (xy 184.794137 -245.131584) (xy 184.793636 -245.12143) (xy 178.7525 -245.12143)
			(xy 178.751992 -245.131585) (xy 178.744215 -245.150348) (xy 178.729854 -245.16471) (xy 178.711093 -245.172491)
			(xy 178.700938 -245.172992) (xy 177.301398 -245.172992) (xy 177.291244 -245.172469) (xy 177.27248 -245.164699)
			(xy 177.258116 -245.150343) (xy 177.250337 -245.131584) (xy 177.249836 -245.12143) (xy 171.2087 -245.12143)
			(xy 171.208192 -245.131585) (xy 171.200415 -245.150348) (xy 171.186054 -245.16471) (xy 171.167293 -245.172491)
			(xy 171.157138 -245.172992) (xy 169.757598 -245.172992) (xy 169.747444 -245.172469) (xy 169.72868 -245.164699)
			(xy 169.714316 -245.150343) (xy 169.706537 -245.131584) (xy 169.706036 -245.12143) (xy 163.6649 -245.12143)
			(xy 163.664392 -245.131585) (xy 163.656615 -245.150348) (xy 163.642254 -245.16471) (xy 163.623493 -245.172491)
			(xy 163.613338 -245.172992) (xy 162.213798 -245.172992) (xy 162.203644 -245.172469) (xy 162.18488 -245.164699)
			(xy 162.170516 -245.150343) (xy 162.162737 -245.131584) (xy 162.162236 -245.12143) (xy 65.7987 -245.12143)
			(xy 65.798192 -245.131585) (xy 65.790415 -245.150348) (xy 65.776054 -245.16471) (xy 65.757293 -245.172491)
			(xy 65.747138 -245.172992) (xy 64.347598 -245.172992) (xy 64.337444 -245.172469) (xy 64.31868 -245.164699)
			(xy 64.304316 -245.150343) (xy 64.296537 -245.131584) (xy 64.296036 -245.12143) (xy 58.2549 -245.12143)
			(xy 58.254392 -245.131585) (xy 58.246615 -245.150348) (xy 58.232254 -245.16471) (xy 58.213493 -245.172491)
			(xy 58.203338 -245.172992) (xy 56.803798 -245.172992) (xy 56.793644 -245.172469) (xy 56.77488 -245.164699)
			(xy 56.760516 -245.150343) (xy 56.752737 -245.131584) (xy 56.752236 -245.12143) (xy 50.7111 -245.12143)
			(xy 50.710592 -245.131585) (xy 50.702815 -245.150348) (xy 50.688454 -245.16471) (xy 50.669693 -245.172491)
			(xy 50.659538 -245.172992) (xy 49.259998 -245.172992) (xy 49.249844 -245.172469) (xy 49.23108 -245.164699)
			(xy 49.216716 -245.150343) (xy 49.208937 -245.131584) (xy 49.208436 -245.12143) (xy 43.1673 -245.12143)
			(xy 43.166792 -245.131585) (xy 43.159015 -245.150348) (xy 43.144654 -245.16471) (xy 43.125893 -245.172491)
			(xy 43.115738 -245.172992) (xy 41.716198 -245.172992) (xy 41.706044 -245.172469) (xy 41.68728 -245.164699)
			(xy 41.672916 -245.150343) (xy 41.665137 -245.131584) (xy 41.664636 -245.12143) (xy 35.6235 -245.12143)
			(xy 35.622992 -245.131585) (xy 35.615215 -245.150348) (xy 35.600854 -245.16471) (xy 35.582093 -245.172491)
			(xy 35.571938 -245.172992) (xy 34.172398 -245.172992) (xy 34.162244 -245.172469) (xy 34.14348 -245.164699)
			(xy 34.129116 -245.150343) (xy 34.121337 -245.131584) (xy 34.120836 -245.12143) (xy 28.0797 -245.12143)
			(xy 28.079192 -245.131585) (xy 28.071415 -245.150348) (xy 28.057054 -245.16471) (xy 28.038293 -245.172491)
			(xy 28.028138 -245.172992) (xy 26.628598 -245.172992) (xy 26.618444 -245.172469) (xy 26.59968 -245.164699)
			(xy 26.585316 -245.150343) (xy 26.577537 -245.131584) (xy 26.577036 -245.12143) (xy 20.5359 -245.12143)
			(xy 20.535392 -245.131585) (xy 20.527615 -245.150348) (xy 20.513254 -245.16471) (xy 20.494493 -245.172491)
			(xy 20.484338 -245.172992) (xy 19.084798 -245.172992) (xy 19.074644 -245.172469) (xy 19.05588 -245.164699)
			(xy 19.041516 -245.150343) (xy 19.033737 -245.131584) (xy 19.033236 -245.12143) (xy 12.9921 -245.12143)
			(xy 12.991592 -245.131585) (xy 12.983815 -245.150348) (xy 12.969454 -245.16471) (xy 12.950693 -245.172491)
			(xy 12.940538 -245.172992) (xy 11.540998 -245.172992) (xy 11.530844 -245.172469) (xy 11.51208 -245.164699)
			(xy 11.497716 -245.150343) (xy 11.489937 -245.131584) (xy 11.489436 -245.12143) (xy 2.509012 -245.12143)
			(xy 2.509012 -245.971314) (xy 7.389368 -245.971314) (xy 7.389368 -245.562374) (xy 7.389743 -245.552197)
			(xy 7.397542 -245.533396) (xy 7.411943 -245.519011) (xy 7.430752 -245.511232) (xy 7.44093 -245.510812)
			(xy 8.84047 -245.510812) (xy 8.850636 -245.511288) (xy 8.869425 -245.519058) (xy 8.88381 -245.533428)
			(xy 8.891601 -245.552208) (xy 8.892032 -245.562374) (xy 8.892032 -245.971314) (xy 14.933168 -245.971314)
			(xy 14.933168 -245.562374) (xy 14.933543 -245.552197) (xy 14.941342 -245.533396) (xy 14.955743 -245.519011)
			(xy 14.974552 -245.511232) (xy 14.98473 -245.510812) (xy 16.38427 -245.510812) (xy 16.394436 -245.511288)
			(xy 16.413225 -245.519058) (xy 16.42761 -245.533428) (xy 16.435401 -245.552208) (xy 16.435832 -245.562374)
			(xy 16.435832 -245.971314) (xy 22.476968 -245.971314) (xy 22.476968 -245.562374) (xy 22.477343 -245.552197)
			(xy 22.485142 -245.533396) (xy 22.499543 -245.519011) (xy 22.518352 -245.511232) (xy 22.52853 -245.510812)
			(xy 23.92807 -245.510812) (xy 23.938236 -245.511288) (xy 23.957025 -245.519058) (xy 23.97141 -245.533428)
			(xy 23.979201 -245.552208) (xy 23.979632 -245.562374) (xy 23.979632 -245.971314) (xy 30.020768 -245.971314)
			(xy 30.020768 -245.562374) (xy 30.021143 -245.552197) (xy 30.028942 -245.533396) (xy 30.043343 -245.519011)
			(xy 30.062152 -245.511232) (xy 30.07233 -245.510812) (xy 31.47187 -245.510812) (xy 31.482036 -245.511288)
			(xy 31.500825 -245.519058) (xy 31.51521 -245.533428) (xy 31.523001 -245.552208) (xy 31.523432 -245.562374)
			(xy 31.523432 -245.971314) (xy 37.564568 -245.971314) (xy 37.564568 -245.562374) (xy 37.564943 -245.552197)
			(xy 37.572742 -245.533396) (xy 37.587143 -245.519011) (xy 37.605952 -245.511232) (xy 37.61613 -245.510812)
			(xy 39.01567 -245.510812) (xy 39.025836 -245.511288) (xy 39.044625 -245.519058) (xy 39.05901 -245.533428)
			(xy 39.066801 -245.552208) (xy 39.067232 -245.562374) (xy 39.067232 -245.971314) (xy 45.108368 -245.971314)
			(xy 45.108368 -245.562374) (xy 45.108743 -245.552197) (xy 45.116542 -245.533396) (xy 45.130943 -245.519011)
			(xy 45.149752 -245.511232) (xy 45.15993 -245.510812) (xy 46.55947 -245.510812) (xy 46.569636 -245.511288)
			(xy 46.588425 -245.519058) (xy 46.60281 -245.533428) (xy 46.610601 -245.552208) (xy 46.611032 -245.562374)
			(xy 46.611032 -245.971314) (xy 52.652168 -245.971314) (xy 52.652168 -245.562374) (xy 52.652543 -245.552197)
			(xy 52.660342 -245.533396) (xy 52.674743 -245.519011) (xy 52.693552 -245.511232) (xy 52.70373 -245.510812)
			(xy 54.10327 -245.510812) (xy 54.113436 -245.511288) (xy 54.132225 -245.519058) (xy 54.14661 -245.533428)
			(xy 54.154401 -245.552208) (xy 54.154832 -245.562374) (xy 54.154832 -245.971314) (xy 60.195968 -245.971314)
			(xy 60.195968 -245.562374) (xy 60.196343 -245.552197) (xy 60.204142 -245.533396) (xy 60.218543 -245.519011)
			(xy 60.237352 -245.511232) (xy 60.24753 -245.510812) (xy 61.64707 -245.510812) (xy 61.657236 -245.511288)
			(xy 61.676025 -245.519058) (xy 61.69041 -245.533428) (xy 61.698201 -245.552208) (xy 61.698632 -245.562374)
			(xy 61.698632 -245.971314) (xy 158.062168 -245.971314) (xy 158.062168 -245.562374) (xy 158.062543 -245.552197)
			(xy 158.070342 -245.533396) (xy 158.084743 -245.519011) (xy 158.103552 -245.511232) (xy 158.11373 -245.510812)
			(xy 159.51327 -245.510812) (xy 159.523436 -245.511288) (xy 159.542225 -245.519058) (xy 159.55661 -245.533428)
			(xy 159.564401 -245.552208) (xy 159.564832 -245.562374) (xy 159.564832 -245.971314) (xy 165.605968 -245.971314)
			(xy 165.605968 -245.562374) (xy 165.606343 -245.552197) (xy 165.614142 -245.533396) (xy 165.628543 -245.519011)
			(xy 165.647352 -245.511232) (xy 165.65753 -245.510812) (xy 167.05707 -245.510812) (xy 167.067236 -245.511288)
			(xy 167.086025 -245.519058) (xy 167.10041 -245.533428) (xy 167.108201 -245.552208) (xy 167.108632 -245.562374)
			(xy 167.108632 -245.971314) (xy 173.149768 -245.971314) (xy 173.149768 -245.562374) (xy 173.150143 -245.552197)
			(xy 173.157942 -245.533396) (xy 173.172343 -245.519011) (xy 173.191152 -245.511232) (xy 173.20133 -245.510812)
			(xy 174.60087 -245.510812) (xy 174.611036 -245.511288) (xy 174.629825 -245.519058) (xy 174.64421 -245.533428)
			(xy 174.652001 -245.552208) (xy 174.652432 -245.562374) (xy 174.652432 -245.971314) (xy 180.693568 -245.971314)
			(xy 180.693568 -245.562374) (xy 180.693943 -245.552197) (xy 180.701742 -245.533396) (xy 180.716143 -245.519011)
			(xy 180.734952 -245.511232) (xy 180.74513 -245.510812) (xy 182.14467 -245.510812) (xy 182.154836 -245.511288)
			(xy 182.173625 -245.519058) (xy 182.18801 -245.533428) (xy 182.195801 -245.552208) (xy 182.196232 -245.562374)
			(xy 182.196232 -245.971314) (xy 188.237368 -245.971314) (xy 188.237368 -245.562374) (xy 188.237743 -245.552197)
			(xy 188.245542 -245.533396) (xy 188.259943 -245.519011) (xy 188.278752 -245.511232) (xy 188.28893 -245.510812)
			(xy 189.68847 -245.510812) (xy 189.698636 -245.511288) (xy 189.717425 -245.519058) (xy 189.73181 -245.533428)
			(xy 189.739601 -245.552208) (xy 189.740032 -245.562374) (xy 189.740032 -245.971314) (xy 195.781168 -245.971314)
			(xy 195.781168 -245.562374) (xy 195.781543 -245.552197) (xy 195.789342 -245.533396) (xy 195.803743 -245.519011)
			(xy 195.822552 -245.511232) (xy 195.83273 -245.510812) (xy 197.23227 -245.510812) (xy 197.242436 -245.511288)
			(xy 197.261225 -245.519058) (xy 197.27561 -245.533428) (xy 197.283401 -245.552208) (xy 197.283832 -245.562374)
			(xy 197.283832 -245.971314) (xy 203.324968 -245.971314) (xy 203.324968 -245.562374) (xy 203.325343 -245.552197)
			(xy 203.333142 -245.533396) (xy 203.347543 -245.519011) (xy 203.366352 -245.511232) (xy 203.37653 -245.510812)
			(xy 204.77607 -245.510812) (xy 204.786236 -245.511288) (xy 204.805025 -245.519058) (xy 204.81941 -245.533428)
			(xy 204.827201 -245.552208) (xy 204.827632 -245.562374) (xy 204.827632 -245.971314) (xy 210.868768 -245.971314)
			(xy 210.868768 -245.562374) (xy 210.869143 -245.552197) (xy 210.876942 -245.533396) (xy 210.891343 -245.519011)
			(xy 210.910152 -245.511232) (xy 210.92033 -245.510812) (xy 212.31987 -245.510812) (xy 212.330036 -245.511288)
			(xy 212.348825 -245.519058) (xy 212.36321 -245.533428) (xy 212.371001 -245.552208) (xy 212.371432 -245.562374)
			(xy 212.371432 -245.971314) (xy 255.329436 -245.971314) (xy 255.329436 -245.562374) (xy 255.329912 -245.552215)
			(xy 255.337695 -245.533445) (xy 255.352066 -245.519081) (xy 255.370839 -245.511307) (xy 255.380998 -245.510812)
			(xy 256.780538 -245.510812) (xy 256.790695 -245.511302) (xy 256.80946 -245.519084) (xy 256.823823 -245.53345)
			(xy 256.831601 -245.552217) (xy 256.8321 -245.562374) (xy 256.8321 -245.971314) (xy 262.873236 -245.971314)
			(xy 262.873236 -245.562374) (xy 262.873712 -245.552215) (xy 262.881495 -245.533445) (xy 262.895866 -245.519081)
			(xy 262.914639 -245.511307) (xy 262.924798 -245.510812) (xy 264.324338 -245.510812) (xy 264.334495 -245.511302)
			(xy 264.35326 -245.519084) (xy 264.367623 -245.53345) (xy 264.375401 -245.552217) (xy 264.3759 -245.562374)
			(xy 264.3759 -245.971314) (xy 270.417036 -245.971314) (xy 270.417036 -245.562374) (xy 270.417512 -245.552215)
			(xy 270.425295 -245.533445) (xy 270.439666 -245.519081) (xy 270.458439 -245.511307) (xy 270.468598 -245.510812)
			(xy 271.868138 -245.510812) (xy 271.878295 -245.511302) (xy 271.89706 -245.519084) (xy 271.911423 -245.53345)
			(xy 271.919201 -245.552217) (xy 271.9197 -245.562374) (xy 271.9197 -245.971314) (xy 277.960836 -245.971314)
			(xy 277.960836 -245.562374) (xy 277.961312 -245.552215) (xy 277.969095 -245.533445) (xy 277.983466 -245.519081)
			(xy 278.002239 -245.511307) (xy 278.012398 -245.510812) (xy 279.411938 -245.510812) (xy 279.422095 -245.511302)
			(xy 279.44086 -245.519084) (xy 279.455223 -245.53345) (xy 279.463001 -245.552217) (xy 279.4635 -245.562374)
			(xy 279.4635 -245.971314) (xy 285.504636 -245.971314) (xy 285.504636 -245.562374) (xy 285.505112 -245.552215)
			(xy 285.512895 -245.533445) (xy 285.527266 -245.519081) (xy 285.546039 -245.511307) (xy 285.556198 -245.510812)
			(xy 286.955738 -245.510812) (xy 286.965895 -245.511302) (xy 286.98466 -245.519084) (xy 286.999023 -245.53345)
			(xy 287.006801 -245.552217) (xy 287.0073 -245.562374) (xy 287.0073 -245.971314) (xy 293.048436 -245.971314)
			(xy 293.048436 -245.562374) (xy 293.048912 -245.552215) (xy 293.056695 -245.533445) (xy 293.071066 -245.519081)
			(xy 293.089839 -245.511307) (xy 293.099998 -245.510812) (xy 294.499538 -245.510812) (xy 294.509695 -245.511302)
			(xy 294.52846 -245.519084) (xy 294.542823 -245.53345) (xy 294.550601 -245.552217) (xy 294.5511 -245.562374)
			(xy 294.5511 -245.971314) (xy 300.592236 -245.971314) (xy 300.592236 -245.562374) (xy 300.592712 -245.552215)
			(xy 300.600495 -245.533445) (xy 300.614866 -245.519081) (xy 300.633639 -245.511307) (xy 300.643798 -245.510812)
			(xy 302.043338 -245.510812) (xy 302.053495 -245.511302) (xy 302.07226 -245.519084) (xy 302.086623 -245.53345)
			(xy 302.094401 -245.552217) (xy 302.0949 -245.562374) (xy 302.0949 -245.971314) (xy 308.136036 -245.971314)
			(xy 308.136036 -245.562374) (xy 308.136512 -245.552215) (xy 308.144295 -245.533445) (xy 308.158666 -245.519081)
			(xy 308.177439 -245.511307) (xy 308.187598 -245.510812) (xy 309.587138 -245.510812) (xy 309.597295 -245.511302)
			(xy 309.61606 -245.519084) (xy 309.630423 -245.53345) (xy 309.638201 -245.552217) (xy 309.6387 -245.562374)
			(xy 309.6387 -245.971314) (xy 406.002236 -245.971314) (xy 406.002236 -245.562374) (xy 406.002712 -245.552215)
			(xy 406.010495 -245.533445) (xy 406.024866 -245.519081) (xy 406.043639 -245.511307) (xy 406.053798 -245.510812)
			(xy 407.453338 -245.510812) (xy 407.463495 -245.511302) (xy 407.48226 -245.519084) (xy 407.496623 -245.53345)
			(xy 407.504401 -245.552217) (xy 407.5049 -245.562374) (xy 407.5049 -245.971314) (xy 413.546036 -245.971314)
			(xy 413.546036 -245.562374) (xy 413.546512 -245.552215) (xy 413.554295 -245.533445) (xy 413.568666 -245.519081)
			(xy 413.587439 -245.511307) (xy 413.597598 -245.510812) (xy 414.997138 -245.510812) (xy 415.007295 -245.511302)
			(xy 415.02606 -245.519084) (xy 415.040423 -245.53345) (xy 415.048201 -245.552217) (xy 415.0487 -245.562374)
			(xy 415.0487 -245.971314) (xy 421.089836 -245.971314) (xy 421.089836 -245.562374) (xy 421.090312 -245.552215)
			(xy 421.098095 -245.533445) (xy 421.112466 -245.519081) (xy 421.131239 -245.511307) (xy 421.141398 -245.510812)
			(xy 422.540938 -245.510812) (xy 422.551095 -245.511302) (xy 422.56986 -245.519084) (xy 422.584223 -245.53345)
			(xy 422.592001 -245.552217) (xy 422.5925 -245.562374) (xy 422.5925 -245.971314) (xy 428.633636 -245.971314)
			(xy 428.633636 -245.562374) (xy 428.634112 -245.552215) (xy 428.641895 -245.533445) (xy 428.656266 -245.519081)
			(xy 428.675039 -245.511307) (xy 428.685198 -245.510812) (xy 430.084738 -245.510812) (xy 430.094895 -245.511302)
			(xy 430.11366 -245.519084) (xy 430.128023 -245.53345) (xy 430.135801 -245.552217) (xy 430.1363 -245.562374)
			(xy 430.1363 -245.971314) (xy 436.177436 -245.971314) (xy 436.177436 -245.562374) (xy 436.177912 -245.552215)
			(xy 436.185695 -245.533445) (xy 436.200066 -245.519081) (xy 436.218839 -245.511307) (xy 436.228998 -245.510812)
			(xy 437.628538 -245.510812) (xy 437.638695 -245.511302) (xy 437.65746 -245.519084) (xy 437.671823 -245.53345)
			(xy 437.679601 -245.552217) (xy 437.6801 -245.562374) (xy 437.6801 -245.971314) (xy 443.721236 -245.971314)
			(xy 443.721236 -245.562374) (xy 443.721712 -245.552215) (xy 443.729495 -245.533445) (xy 443.743866 -245.519081)
			(xy 443.762639 -245.511307) (xy 443.772798 -245.510812) (xy 445.172338 -245.510812) (xy 445.182495 -245.511302)
			(xy 445.20126 -245.519084) (xy 445.215623 -245.53345) (xy 445.223401 -245.552217) (xy 445.2239 -245.562374)
			(xy 445.2239 -245.971314) (xy 451.265036 -245.971314) (xy 451.265036 -245.562374) (xy 451.265512 -245.552215)
			(xy 451.273295 -245.533445) (xy 451.287666 -245.519081) (xy 451.306439 -245.511307) (xy 451.316598 -245.510812)
			(xy 452.716138 -245.510812) (xy 452.726295 -245.511302) (xy 452.74506 -245.519084) (xy 452.759423 -245.53345)
			(xy 452.767201 -245.552217) (xy 452.7677 -245.562374) (xy 452.7677 -245.971314) (xy 458.808836 -245.971314)
			(xy 458.808836 -245.562374) (xy 458.809312 -245.552215) (xy 458.817095 -245.533445) (xy 458.831466 -245.519081)
			(xy 458.850239 -245.511307) (xy 458.860398 -245.510812) (xy 460.259938 -245.510812) (xy 460.270095 -245.511302)
			(xy 460.28886 -245.519084) (xy 460.303223 -245.53345) (xy 460.311001 -245.552217) (xy 460.3115 -245.562374)
			(xy 460.3115 -245.971314) (xy 460.310979 -245.981468) (xy 460.303207 -246.00023) (xy 460.28885 -246.014593)
			(xy 460.270092 -246.022374) (xy 460.259938 -246.022876) (xy 458.860398 -246.022876) (xy 458.850242 -246.022369)
			(xy 458.831475 -246.014596) (xy 458.817111 -246.000235) (xy 458.809334 -245.98147) (xy 458.808836 -245.971314)
			(xy 452.7677 -245.971314) (xy 452.767179 -245.981468) (xy 452.759407 -246.00023) (xy 452.74505 -246.014593)
			(xy 452.726292 -246.022374) (xy 452.716138 -246.022876) (xy 451.316598 -246.022876) (xy 451.306442 -246.022369)
			(xy 451.287675 -246.014596) (xy 451.273311 -246.000235) (xy 451.265534 -245.98147) (xy 451.265036 -245.971314)
			(xy 445.2239 -245.971314) (xy 445.223379 -245.981468) (xy 445.215607 -246.00023) (xy 445.20125 -246.014593)
			(xy 445.182492 -246.022374) (xy 445.172338 -246.022876) (xy 443.772798 -246.022876) (xy 443.762642 -246.022369)
			(xy 443.743875 -246.014596) (xy 443.729511 -246.000235) (xy 443.721734 -245.98147) (xy 443.721236 -245.971314)
			(xy 437.6801 -245.971314) (xy 437.679579 -245.981468) (xy 437.671807 -246.00023) (xy 437.65745 -246.014593)
			(xy 437.638692 -246.022374) (xy 437.628538 -246.022876) (xy 436.228998 -246.022876) (xy 436.218842 -246.022369)
			(xy 436.200075 -246.014596) (xy 436.185711 -246.000235) (xy 436.177934 -245.98147) (xy 436.177436 -245.971314)
			(xy 430.1363 -245.971314) (xy 430.135779 -245.981468) (xy 430.128007 -246.00023) (xy 430.11365 -246.014593)
			(xy 430.094892 -246.022374) (xy 430.084738 -246.022876) (xy 428.685198 -246.022876) (xy 428.675042 -246.022369)
			(xy 428.656275 -246.014596) (xy 428.641911 -246.000235) (xy 428.634134 -245.98147) (xy 428.633636 -245.971314)
			(xy 422.5925 -245.971314) (xy 422.591979 -245.981468) (xy 422.584207 -246.00023) (xy 422.56985 -246.014593)
			(xy 422.551092 -246.022374) (xy 422.540938 -246.022876) (xy 421.141398 -246.022876) (xy 421.131242 -246.022369)
			(xy 421.112475 -246.014596) (xy 421.098111 -246.000235) (xy 421.090334 -245.98147) (xy 421.089836 -245.971314)
			(xy 415.0487 -245.971314) (xy 415.048179 -245.981468) (xy 415.040407 -246.00023) (xy 415.02605 -246.014593)
			(xy 415.007292 -246.022374) (xy 414.997138 -246.022876) (xy 413.597598 -246.022876) (xy 413.587442 -246.022369)
			(xy 413.568675 -246.014596) (xy 413.554311 -246.000235) (xy 413.546534 -245.98147) (xy 413.546036 -245.971314)
			(xy 407.5049 -245.971314) (xy 407.504379 -245.981468) (xy 407.496607 -246.00023) (xy 407.48225 -246.014593)
			(xy 407.463492 -246.022374) (xy 407.453338 -246.022876) (xy 406.053798 -246.022876) (xy 406.043642 -246.022369)
			(xy 406.024875 -246.014596) (xy 406.010511 -246.000235) (xy 406.002734 -245.98147) (xy 406.002236 -245.971314)
			(xy 309.6387 -245.971314) (xy 309.638179 -245.981468) (xy 309.630407 -246.00023) (xy 309.61605 -246.014593)
			(xy 309.597292 -246.022374) (xy 309.587138 -246.022876) (xy 308.187598 -246.022876) (xy 308.177442 -246.022369)
			(xy 308.158675 -246.014596) (xy 308.144311 -246.000235) (xy 308.136534 -245.98147) (xy 308.136036 -245.971314)
			(xy 302.0949 -245.971314) (xy 302.094379 -245.981468) (xy 302.086607 -246.00023) (xy 302.07225 -246.014593)
			(xy 302.053492 -246.022374) (xy 302.043338 -246.022876) (xy 300.643798 -246.022876) (xy 300.633642 -246.022369)
			(xy 300.614875 -246.014596) (xy 300.600511 -246.000235) (xy 300.592734 -245.98147) (xy 300.592236 -245.971314)
			(xy 294.5511 -245.971314) (xy 294.550579 -245.981468) (xy 294.542807 -246.00023) (xy 294.52845 -246.014593)
			(xy 294.509692 -246.022374) (xy 294.499538 -246.022876) (xy 293.099998 -246.022876) (xy 293.089842 -246.022369)
			(xy 293.071075 -246.014596) (xy 293.056711 -246.000235) (xy 293.048934 -245.98147) (xy 293.048436 -245.971314)
			(xy 287.0073 -245.971314) (xy 287.006779 -245.981468) (xy 286.999007 -246.00023) (xy 286.98465 -246.014593)
			(xy 286.965892 -246.022374) (xy 286.955738 -246.022876) (xy 285.556198 -246.022876) (xy 285.546042 -246.022369)
			(xy 285.527275 -246.014596) (xy 285.512911 -246.000235) (xy 285.505134 -245.98147) (xy 285.504636 -245.971314)
			(xy 279.4635 -245.971314) (xy 279.462979 -245.981468) (xy 279.455207 -246.00023) (xy 279.44085 -246.014593)
			(xy 279.422092 -246.022374) (xy 279.411938 -246.022876) (xy 278.012398 -246.022876) (xy 278.002242 -246.022369)
			(xy 277.983475 -246.014596) (xy 277.969111 -246.000235) (xy 277.961334 -245.98147) (xy 277.960836 -245.971314)
			(xy 271.9197 -245.971314) (xy 271.919179 -245.981468) (xy 271.911407 -246.00023) (xy 271.89705 -246.014593)
			(xy 271.878292 -246.022374) (xy 271.868138 -246.022876) (xy 270.468598 -246.022876) (xy 270.458442 -246.022369)
			(xy 270.439675 -246.014596) (xy 270.425311 -246.000235) (xy 270.417534 -245.98147) (xy 270.417036 -245.971314)
			(xy 264.3759 -245.971314) (xy 264.375379 -245.981468) (xy 264.367607 -246.00023) (xy 264.35325 -246.014593)
			(xy 264.334492 -246.022374) (xy 264.324338 -246.022876) (xy 262.924798 -246.022876) (xy 262.914642 -246.022369)
			(xy 262.895875 -246.014596) (xy 262.881511 -246.000235) (xy 262.873734 -245.98147) (xy 262.873236 -245.971314)
			(xy 256.8321 -245.971314) (xy 256.831579 -245.981468) (xy 256.823807 -246.00023) (xy 256.80945 -246.014593)
			(xy 256.790692 -246.022374) (xy 256.780538 -246.022876) (xy 255.380998 -246.022876) (xy 255.370842 -246.022369)
			(xy 255.352075 -246.014596) (xy 255.337711 -246.000235) (xy 255.329934 -245.98147) (xy 255.329436 -245.971314)
			(xy 212.371432 -245.971314) (xy 212.371047 -245.98149) (xy 212.363252 -246.000291) (xy 212.348854 -246.014676)
			(xy 212.330047 -246.022455) (xy 212.31987 -246.022876) (xy 210.92033 -246.022876) (xy 210.910162 -246.022412)
			(xy 210.891371 -246.014639) (xy 210.876985 -246.000266) (xy 210.869197 -245.981482) (xy 210.868768 -245.971314)
			(xy 204.827632 -245.971314) (xy 204.827247 -245.98149) (xy 204.819452 -246.000291) (xy 204.805054 -246.014676)
			(xy 204.786247 -246.022455) (xy 204.77607 -246.022876) (xy 203.37653 -246.022876) (xy 203.366362 -246.022412)
			(xy 203.347571 -246.014639) (xy 203.333185 -246.000266) (xy 203.325397 -245.981482) (xy 203.324968 -245.971314)
			(xy 197.283832 -245.971314) (xy 197.283447 -245.98149) (xy 197.275652 -246.000291) (xy 197.261254 -246.014676)
			(xy 197.242447 -246.022455) (xy 197.23227 -246.022876) (xy 195.83273 -246.022876) (xy 195.822562 -246.022412)
			(xy 195.803771 -246.014639) (xy 195.789385 -246.000266) (xy 195.781597 -245.981482) (xy 195.781168 -245.971314)
			(xy 189.740032 -245.971314) (xy 189.739647 -245.98149) (xy 189.731852 -246.000291) (xy 189.717454 -246.014676)
			(xy 189.698647 -246.022455) (xy 189.68847 -246.022876) (xy 188.28893 -246.022876) (xy 188.278762 -246.022412)
			(xy 188.259971 -246.014639) (xy 188.245585 -246.000266) (xy 188.237797 -245.981482) (xy 188.237368 -245.971314)
			(xy 182.196232 -245.971314) (xy 182.195847 -245.98149) (xy 182.188052 -246.000291) (xy 182.173654 -246.014676)
			(xy 182.154847 -246.022455) (xy 182.14467 -246.022876) (xy 180.74513 -246.022876) (xy 180.734962 -246.022412)
			(xy 180.716171 -246.014639) (xy 180.701785 -246.000266) (xy 180.693997 -245.981482) (xy 180.693568 -245.971314)
			(xy 174.652432 -245.971314) (xy 174.652047 -245.98149) (xy 174.644252 -246.000291) (xy 174.629854 -246.014676)
			(xy 174.611047 -246.022455) (xy 174.60087 -246.022876) (xy 173.20133 -246.022876) (xy 173.191162 -246.022412)
			(xy 173.172371 -246.014639) (xy 173.157985 -246.000266) (xy 173.150197 -245.981482) (xy 173.149768 -245.971314)
			(xy 167.108632 -245.971314) (xy 167.108247 -245.98149) (xy 167.100452 -246.000291) (xy 167.086054 -246.014676)
			(xy 167.067247 -246.022455) (xy 167.05707 -246.022876) (xy 165.65753 -246.022876) (xy 165.647362 -246.022412)
			(xy 165.628571 -246.014639) (xy 165.614185 -246.000266) (xy 165.606397 -245.981482) (xy 165.605968 -245.971314)
			(xy 159.564832 -245.971314) (xy 159.564447 -245.98149) (xy 159.556652 -246.000291) (xy 159.542254 -246.014676)
			(xy 159.523447 -246.022455) (xy 159.51327 -246.022876) (xy 158.11373 -246.022876) (xy 158.103562 -246.022412)
			(xy 158.084771 -246.014639) (xy 158.070385 -246.000266) (xy 158.062597 -245.981482) (xy 158.062168 -245.971314)
			(xy 61.698632 -245.971314) (xy 61.698247 -245.98149) (xy 61.690452 -246.000291) (xy 61.676054 -246.014676)
			(xy 61.657247 -246.022455) (xy 61.64707 -246.022876) (xy 60.24753 -246.022876) (xy 60.237362 -246.022412)
			(xy 60.218571 -246.014639) (xy 60.204185 -246.000266) (xy 60.196397 -245.981482) (xy 60.195968 -245.971314)
			(xy 54.154832 -245.971314) (xy 54.154447 -245.98149) (xy 54.146652 -246.000291) (xy 54.132254 -246.014676)
			(xy 54.113447 -246.022455) (xy 54.10327 -246.022876) (xy 52.70373 -246.022876) (xy 52.693562 -246.022412)
			(xy 52.674771 -246.014639) (xy 52.660385 -246.000266) (xy 52.652597 -245.981482) (xy 52.652168 -245.971314)
			(xy 46.611032 -245.971314) (xy 46.610647 -245.98149) (xy 46.602852 -246.000291) (xy 46.588454 -246.014676)
			(xy 46.569647 -246.022455) (xy 46.55947 -246.022876) (xy 45.15993 -246.022876) (xy 45.149762 -246.022412)
			(xy 45.130971 -246.014639) (xy 45.116585 -246.000266) (xy 45.108797 -245.981482) (xy 45.108368 -245.971314)
			(xy 39.067232 -245.971314) (xy 39.066847 -245.98149) (xy 39.059052 -246.000291) (xy 39.044654 -246.014676)
			(xy 39.025847 -246.022455) (xy 39.01567 -246.022876) (xy 37.61613 -246.022876) (xy 37.605962 -246.022412)
			(xy 37.587171 -246.014639) (xy 37.572785 -246.000266) (xy 37.564997 -245.981482) (xy 37.564568 -245.971314)
			(xy 31.523432 -245.971314) (xy 31.523047 -245.98149) (xy 31.515252 -246.000291) (xy 31.500854 -246.014676)
			(xy 31.482047 -246.022455) (xy 31.47187 -246.022876) (xy 30.07233 -246.022876) (xy 30.062162 -246.022412)
			(xy 30.043371 -246.014639) (xy 30.028985 -246.000266) (xy 30.021197 -245.981482) (xy 30.020768 -245.971314)
			(xy 23.979632 -245.971314) (xy 23.979247 -245.98149) (xy 23.971452 -246.000291) (xy 23.957054 -246.014676)
			(xy 23.938247 -246.022455) (xy 23.92807 -246.022876) (xy 22.52853 -246.022876) (xy 22.518362 -246.022412)
			(xy 22.499571 -246.014639) (xy 22.485185 -246.000266) (xy 22.477397 -245.981482) (xy 22.476968 -245.971314)
			(xy 16.435832 -245.971314) (xy 16.435447 -245.98149) (xy 16.427652 -246.000291) (xy 16.413254 -246.014676)
			(xy 16.394447 -246.022455) (xy 16.38427 -246.022876) (xy 14.98473 -246.022876) (xy 14.974562 -246.022412)
			(xy 14.955771 -246.014639) (xy 14.941385 -246.000266) (xy 14.933597 -245.981482) (xy 14.933168 -245.971314)
			(xy 8.892032 -245.971314) (xy 8.891647 -245.98149) (xy 8.883852 -246.000291) (xy 8.869454 -246.014676)
			(xy 8.850647 -246.022455) (xy 8.84047 -246.022876) (xy 7.44093 -246.022876) (xy 7.430762 -246.022412)
			(xy 7.411971 -246.014639) (xy 7.397585 -246.000266) (xy 7.389797 -245.981482) (xy 7.389368 -245.971314)
			(xy 2.509012 -245.971314) (xy 2.509012 -246.821452) (xy 11.489436 -246.821452) (xy 11.489436 -246.412512)
			(xy 11.489832 -246.402354) (xy 11.49763 -246.383595) (xy 11.512036 -246.36927) (xy 11.530838 -246.361576)
			(xy 11.540998 -246.361204) (xy 12.940538 -246.361204) (xy 12.950663 -246.361694) (xy 12.969378 -246.369428)
			(xy 12.983732 -246.383712) (xy 12.991556 -246.40239) (xy 12.9921 -246.412512) (xy 12.9921 -246.821452)
			(xy 19.033236 -246.821452) (xy 19.033236 -246.412512) (xy 19.033632 -246.402354) (xy 19.04143 -246.383595)
			(xy 19.055836 -246.36927) (xy 19.074638 -246.361576) (xy 19.084798 -246.361204) (xy 20.484338 -246.361204)
			(xy 20.494463 -246.361694) (xy 20.513178 -246.369428) (xy 20.527532 -246.383712) (xy 20.535356 -246.40239)
			(xy 20.5359 -246.412512) (xy 20.5359 -246.821452) (xy 26.577036 -246.821452) (xy 26.577036 -246.412512)
			(xy 26.577432 -246.402354) (xy 26.58523 -246.383595) (xy 26.599636 -246.36927) (xy 26.618438 -246.361576)
			(xy 26.628598 -246.361204) (xy 28.028138 -246.361204) (xy 28.038263 -246.361694) (xy 28.056978 -246.369428)
			(xy 28.071332 -246.383712) (xy 28.079156 -246.40239) (xy 28.0797 -246.412512) (xy 28.0797 -246.821452)
			(xy 34.120836 -246.821452) (xy 34.120836 -246.412512) (xy 34.121232 -246.402354) (xy 34.12903 -246.383595)
			(xy 34.143436 -246.36927) (xy 34.162238 -246.361576) (xy 34.172398 -246.361204) (xy 35.571938 -246.361204)
			(xy 35.582063 -246.361694) (xy 35.600778 -246.369428) (xy 35.615132 -246.383712) (xy 35.622956 -246.40239)
			(xy 35.6235 -246.412512) (xy 35.6235 -246.821452) (xy 41.664636 -246.821452) (xy 41.664636 -246.412512)
			(xy 41.665032 -246.402354) (xy 41.67283 -246.383595) (xy 41.687236 -246.36927) (xy 41.706038 -246.361576)
			(xy 41.716198 -246.361204) (xy 43.115738 -246.361204) (xy 43.125863 -246.361694) (xy 43.144578 -246.369428)
			(xy 43.158932 -246.383712) (xy 43.166756 -246.40239) (xy 43.1673 -246.412512) (xy 43.1673 -246.821452)
			(xy 49.208436 -246.821452) (xy 49.208436 -246.412512) (xy 49.208832 -246.402354) (xy 49.21663 -246.383595)
			(xy 49.231036 -246.36927) (xy 49.249838 -246.361576) (xy 49.259998 -246.361204) (xy 50.659538 -246.361204)
			(xy 50.669663 -246.361694) (xy 50.688378 -246.369428) (xy 50.702732 -246.383712) (xy 50.710556 -246.40239)
			(xy 50.7111 -246.412512) (xy 50.7111 -246.821452) (xy 56.752236 -246.821452) (xy 56.752236 -246.412512)
			(xy 56.752632 -246.402354) (xy 56.76043 -246.383595) (xy 56.774836 -246.36927) (xy 56.793638 -246.361576)
			(xy 56.803798 -246.361204) (xy 58.203338 -246.361204) (xy 58.213463 -246.361694) (xy 58.232178 -246.369428)
			(xy 58.246532 -246.383712) (xy 58.254356 -246.40239) (xy 58.2549 -246.412512) (xy 58.2549 -246.821452)
			(xy 64.296036 -246.821452) (xy 64.296036 -246.412512) (xy 64.296432 -246.402354) (xy 64.30423 -246.383595)
			(xy 64.318636 -246.36927) (xy 64.337438 -246.361576) (xy 64.347598 -246.361204) (xy 65.747138 -246.361204)
			(xy 65.757263 -246.361694) (xy 65.775978 -246.369428) (xy 65.790332 -246.383712) (xy 65.798156 -246.40239)
			(xy 65.7987 -246.412512) (xy 65.7987 -246.821452) (xy 162.162236 -246.821452) (xy 162.162236 -246.412512)
			(xy 162.162632 -246.402354) (xy 162.17043 -246.383595) (xy 162.184836 -246.36927) (xy 162.203638 -246.361576)
			(xy 162.213798 -246.361204) (xy 163.613338 -246.361204) (xy 163.623463 -246.361694) (xy 163.642178 -246.369428)
			(xy 163.656532 -246.383712) (xy 163.664356 -246.40239) (xy 163.6649 -246.412512) (xy 163.6649 -246.821452)
			(xy 169.706036 -246.821452) (xy 169.706036 -246.412512) (xy 169.706432 -246.402354) (xy 169.71423 -246.383595)
			(xy 169.728636 -246.36927) (xy 169.747438 -246.361576) (xy 169.757598 -246.361204) (xy 171.157138 -246.361204)
			(xy 171.167263 -246.361694) (xy 171.185978 -246.369428) (xy 171.200332 -246.383712) (xy 171.208156 -246.40239)
			(xy 171.2087 -246.412512) (xy 171.2087 -246.821452) (xy 177.249836 -246.821452) (xy 177.249836 -246.412512)
			(xy 177.250232 -246.402354) (xy 177.25803 -246.383595) (xy 177.272436 -246.36927) (xy 177.291238 -246.361576)
			(xy 177.301398 -246.361204) (xy 178.700938 -246.361204) (xy 178.711063 -246.361694) (xy 178.729778 -246.369428)
			(xy 178.744132 -246.383712) (xy 178.751956 -246.40239) (xy 178.7525 -246.412512) (xy 178.7525 -246.821452)
			(xy 184.793636 -246.821452) (xy 184.793636 -246.412512) (xy 184.794032 -246.402354) (xy 184.80183 -246.383595)
			(xy 184.816236 -246.36927) (xy 184.835038 -246.361576) (xy 184.845198 -246.361204) (xy 186.244738 -246.361204)
			(xy 186.254863 -246.361694) (xy 186.273578 -246.369428) (xy 186.287932 -246.383712) (xy 186.295756 -246.40239)
			(xy 186.2963 -246.412512) (xy 186.2963 -246.821452) (xy 192.337436 -246.821452) (xy 192.337436 -246.412512)
			(xy 192.337832 -246.402354) (xy 192.34563 -246.383595) (xy 192.360036 -246.36927) (xy 192.378838 -246.361576)
			(xy 192.388998 -246.361204) (xy 193.788538 -246.361204) (xy 193.798663 -246.361694) (xy 193.817378 -246.369428)
			(xy 193.831732 -246.383712) (xy 193.839556 -246.40239) (xy 193.8401 -246.412512) (xy 193.8401 -246.821452)
			(xy 199.881236 -246.821452) (xy 199.881236 -246.412512) (xy 199.881632 -246.402354) (xy 199.88943 -246.383595)
			(xy 199.903836 -246.36927) (xy 199.922638 -246.361576) (xy 199.932798 -246.361204) (xy 201.332338 -246.361204)
			(xy 201.342463 -246.361694) (xy 201.361178 -246.369428) (xy 201.375532 -246.383712) (xy 201.383356 -246.40239)
			(xy 201.3839 -246.412512) (xy 201.3839 -246.821452) (xy 207.425036 -246.821452) (xy 207.425036 -246.412512)
			(xy 207.425432 -246.402354) (xy 207.43323 -246.383595) (xy 207.447636 -246.36927) (xy 207.466438 -246.361576)
			(xy 207.476598 -246.361204) (xy 208.876138 -246.361204) (xy 208.886263 -246.361694) (xy 208.904978 -246.369428)
			(xy 208.919332 -246.383712) (xy 208.927156 -246.40239) (xy 208.9277 -246.412512) (xy 208.9277 -246.821452)
			(xy 214.968836 -246.821452) (xy 214.968836 -246.412512) (xy 214.969232 -246.402354) (xy 214.97703 -246.383595)
			(xy 214.991436 -246.36927) (xy 215.010238 -246.361576) (xy 215.020398 -246.361204) (xy 216.419938 -246.361204)
			(xy 216.430063 -246.361694) (xy 216.448778 -246.369428) (xy 216.463132 -246.383712) (xy 216.470956 -246.40239)
			(xy 216.4715 -246.412512) (xy 216.4715 -246.821452) (xy 216.471039 -246.831603) (xy 216.463259 -246.850354)
			(xy 216.448874 -246.864679) (xy 216.430091 -246.872381) (xy 216.419938 -246.87276) (xy 215.020398 -246.87276)
			(xy 215.010271 -246.872275) (xy 214.99155 -246.864547) (xy 214.977194 -246.85026) (xy 214.969375 -246.831576)
			(xy 214.968836 -246.821452) (xy 208.9277 -246.821452) (xy 208.927239 -246.831603) (xy 208.919459 -246.850354)
			(xy 208.905074 -246.864679) (xy 208.886291 -246.872381) (xy 208.876138 -246.87276) (xy 207.476598 -246.87276)
			(xy 207.466471 -246.872275) (xy 207.44775 -246.864547) (xy 207.433394 -246.85026) (xy 207.425575 -246.831576)
			(xy 207.425036 -246.821452) (xy 201.3839 -246.821452) (xy 201.383439 -246.831603) (xy 201.375659 -246.850354)
			(xy 201.361274 -246.864679) (xy 201.342491 -246.872381) (xy 201.332338 -246.87276) (xy 199.932798 -246.87276)
			(xy 199.922671 -246.872275) (xy 199.90395 -246.864547) (xy 199.889594 -246.85026) (xy 199.881775 -246.831576)
			(xy 199.881236 -246.821452) (xy 193.8401 -246.821452) (xy 193.839639 -246.831603) (xy 193.831859 -246.850354)
			(xy 193.817474 -246.864679) (xy 193.798691 -246.872381) (xy 193.788538 -246.87276) (xy 192.388998 -246.87276)
			(xy 192.378871 -246.872275) (xy 192.36015 -246.864547) (xy 192.345794 -246.85026) (xy 192.337975 -246.831576)
			(xy 192.337436 -246.821452) (xy 186.2963 -246.821452) (xy 186.295839 -246.831603) (xy 186.288059 -246.850354)
			(xy 186.273674 -246.864679) (xy 186.254891 -246.872381) (xy 186.244738 -246.87276) (xy 184.845198 -246.87276)
			(xy 184.835071 -246.872275) (xy 184.81635 -246.864547) (xy 184.801994 -246.85026) (xy 184.794175 -246.831576)
			(xy 184.793636 -246.821452) (xy 178.7525 -246.821452) (xy 178.752039 -246.831603) (xy 178.744259 -246.850354)
			(xy 178.729874 -246.864679) (xy 178.711091 -246.872381) (xy 178.700938 -246.87276) (xy 177.301398 -246.87276)
			(xy 177.291271 -246.872275) (xy 177.27255 -246.864547) (xy 177.258194 -246.85026) (xy 177.250375 -246.831576)
			(xy 177.249836 -246.821452) (xy 171.2087 -246.821452) (xy 171.208239 -246.831603) (xy 171.200459 -246.850354)
			(xy 171.186074 -246.864679) (xy 171.167291 -246.872381) (xy 171.157138 -246.87276) (xy 169.757598 -246.87276)
			(xy 169.747471 -246.872275) (xy 169.72875 -246.864547) (xy 169.714394 -246.85026) (xy 169.706575 -246.831576)
			(xy 169.706036 -246.821452) (xy 163.6649 -246.821452) (xy 163.664439 -246.831603) (xy 163.656659 -246.850354)
			(xy 163.642274 -246.864679) (xy 163.623491 -246.872381) (xy 163.613338 -246.87276) (xy 162.213798 -246.87276)
			(xy 162.203671 -246.872275) (xy 162.18495 -246.864547) (xy 162.170594 -246.85026) (xy 162.162775 -246.831576)
			(xy 162.162236 -246.821452) (xy 65.7987 -246.821452) (xy 65.798239 -246.831603) (xy 65.790459 -246.850354)
			(xy 65.776074 -246.864679) (xy 65.757291 -246.872381) (xy 65.747138 -246.87276) (xy 64.347598 -246.87276)
			(xy 64.337471 -246.872275) (xy 64.31875 -246.864547) (xy 64.304394 -246.85026) (xy 64.296575 -246.831576)
			(xy 64.296036 -246.821452) (xy 58.2549 -246.821452) (xy 58.254439 -246.831603) (xy 58.246659 -246.850354)
			(xy 58.232274 -246.864679) (xy 58.213491 -246.872381) (xy 58.203338 -246.87276) (xy 56.803798 -246.87276)
			(xy 56.793671 -246.872275) (xy 56.77495 -246.864547) (xy 56.760594 -246.85026) (xy 56.752775 -246.831576)
			(xy 56.752236 -246.821452) (xy 50.7111 -246.821452) (xy 50.710639 -246.831603) (xy 50.702859 -246.850354)
			(xy 50.688474 -246.864679) (xy 50.669691 -246.872381) (xy 50.659538 -246.87276) (xy 49.259998 -246.87276)
			(xy 49.249871 -246.872275) (xy 49.23115 -246.864547) (xy 49.216794 -246.85026) (xy 49.208975 -246.831576)
			(xy 49.208436 -246.821452) (xy 43.1673 -246.821452) (xy 43.166839 -246.831603) (xy 43.159059 -246.850354)
			(xy 43.144674 -246.864679) (xy 43.125891 -246.872381) (xy 43.115738 -246.87276) (xy 41.716198 -246.87276)
			(xy 41.706071 -246.872275) (xy 41.68735 -246.864547) (xy 41.672994 -246.85026) (xy 41.665175 -246.831576)
			(xy 41.664636 -246.821452) (xy 35.6235 -246.821452) (xy 35.623039 -246.831603) (xy 35.615259 -246.850354)
			(xy 35.600874 -246.864679) (xy 35.582091 -246.872381) (xy 35.571938 -246.87276) (xy 34.172398 -246.87276)
			(xy 34.162271 -246.872275) (xy 34.14355 -246.864547) (xy 34.129194 -246.85026) (xy 34.121375 -246.831576)
			(xy 34.120836 -246.821452) (xy 28.0797 -246.821452) (xy 28.079239 -246.831603) (xy 28.071459 -246.850354)
			(xy 28.057074 -246.864679) (xy 28.038291 -246.872381) (xy 28.028138 -246.87276) (xy 26.628598 -246.87276)
			(xy 26.618471 -246.872275) (xy 26.59975 -246.864547) (xy 26.585394 -246.85026) (xy 26.577575 -246.831576)
			(xy 26.577036 -246.821452) (xy 20.5359 -246.821452) (xy 20.535439 -246.831603) (xy 20.527659 -246.850354)
			(xy 20.513274 -246.864679) (xy 20.494491 -246.872381) (xy 20.484338 -246.87276) (xy 19.084798 -246.87276)
			(xy 19.074671 -246.872275) (xy 19.05595 -246.864547) (xy 19.041594 -246.85026) (xy 19.033775 -246.831576)
			(xy 19.033236 -246.821452) (xy 12.9921 -246.821452) (xy 12.991639 -246.831603) (xy 12.983859 -246.850354)
			(xy 12.969474 -246.864679) (xy 12.950691 -246.872381) (xy 12.940538 -246.87276) (xy 11.540998 -246.87276)
			(xy 11.530871 -246.872275) (xy 11.51215 -246.864547) (xy 11.497794 -246.85026) (xy 11.489975 -246.831576)
			(xy 11.489436 -246.821452) (xy 2.509012 -246.821452) (xy 2.509012 -247.671336) (xy 7.389368 -247.671336)
			(xy 7.389368 -247.262396) (xy 7.389818 -247.252246) (xy 7.397609 -247.233499) (xy 7.411996 -247.219177)
			(xy 7.430778 -247.211472) (xy 7.44093 -247.211088) (xy 8.84047 -247.211088) (xy 8.850588 -247.211649)
			(xy 8.869299 -247.219358) (xy 8.883655 -247.233621) (xy 8.891484 -247.252281) (xy 8.892032 -247.262396)
			(xy 8.892032 -247.671336) (xy 14.933168 -247.671336) (xy 14.933168 -247.262396) (xy 14.933618 -247.252246)
			(xy 14.941409 -247.233499) (xy 14.955796 -247.219177) (xy 14.974578 -247.211472) (xy 14.98473 -247.211088)
			(xy 16.38427 -247.211088) (xy 16.394388 -247.211649) (xy 16.413099 -247.219358) (xy 16.427455 -247.233621)
			(xy 16.435284 -247.252281) (xy 16.435832 -247.262396) (xy 16.435832 -247.671336) (xy 22.476968 -247.671336)
			(xy 22.476968 -247.262396) (xy 22.477418 -247.252246) (xy 22.485209 -247.233499) (xy 22.499596 -247.219177)
			(xy 22.518378 -247.211472) (xy 22.52853 -247.211088) (xy 23.92807 -247.211088) (xy 23.938188 -247.211649)
			(xy 23.956899 -247.219358) (xy 23.971255 -247.233621) (xy 23.979084 -247.252281) (xy 23.979632 -247.262396)
			(xy 23.979632 -247.671336) (xy 30.020768 -247.671336) (xy 30.020768 -247.262396) (xy 30.021218 -247.252246)
			(xy 30.029009 -247.233499) (xy 30.043396 -247.219177) (xy 30.062178 -247.211472) (xy 30.07233 -247.211088)
			(xy 31.47187 -247.211088) (xy 31.481988 -247.211649) (xy 31.500699 -247.219358) (xy 31.515055 -247.233621)
			(xy 31.522884 -247.252281) (xy 31.523432 -247.262396) (xy 31.523432 -247.671336) (xy 37.564568 -247.671336)
			(xy 37.564568 -247.262396) (xy 37.565018 -247.252246) (xy 37.572809 -247.233499) (xy 37.587196 -247.219177)
			(xy 37.605978 -247.211472) (xy 37.61613 -247.211088) (xy 39.01567 -247.211088) (xy 39.025788 -247.211649)
			(xy 39.044499 -247.219358) (xy 39.058855 -247.233621) (xy 39.066684 -247.252281) (xy 39.067232 -247.262396)
			(xy 39.067232 -247.671336) (xy 45.108368 -247.671336) (xy 45.108368 -247.262396) (xy 45.108818 -247.252246)
			(xy 45.116609 -247.233499) (xy 45.130996 -247.219177) (xy 45.149778 -247.211472) (xy 45.15993 -247.211088)
			(xy 46.55947 -247.211088) (xy 46.569588 -247.211649) (xy 46.588299 -247.219358) (xy 46.602655 -247.233621)
			(xy 46.610484 -247.252281) (xy 46.611032 -247.262396) (xy 46.611032 -247.671336) (xy 52.652168 -247.671336)
			(xy 52.652168 -247.262396) (xy 52.652618 -247.252246) (xy 52.660409 -247.233499) (xy 52.674796 -247.219177)
			(xy 52.693578 -247.211472) (xy 52.70373 -247.211088) (xy 54.10327 -247.211088) (xy 54.113388 -247.211649)
			(xy 54.132099 -247.219358) (xy 54.146455 -247.233621) (xy 54.154284 -247.252281) (xy 54.154832 -247.262396)
			(xy 54.154832 -247.671336) (xy 60.195968 -247.671336) (xy 60.195968 -247.262396) (xy 60.196418 -247.252246)
			(xy 60.204209 -247.233499) (xy 60.218596 -247.219177) (xy 60.237378 -247.211472) (xy 60.24753 -247.211088)
			(xy 61.64707 -247.211088) (xy 61.657188 -247.211649) (xy 61.675899 -247.219358) (xy 61.690255 -247.233621)
			(xy 61.698084 -247.252281) (xy 61.698632 -247.262396) (xy 61.698632 -247.671336) (xy 158.062168 -247.671336)
			(xy 158.062168 -247.262396) (xy 158.062618 -247.252246) (xy 158.070409 -247.233499) (xy 158.084796 -247.219177)
			(xy 158.103578 -247.211472) (xy 158.11373 -247.211088) (xy 159.51327 -247.211088) (xy 159.523388 -247.211649)
			(xy 159.542099 -247.219358) (xy 159.556455 -247.233621) (xy 159.564284 -247.252281) (xy 159.564832 -247.262396)
			(xy 159.564832 -247.671336) (xy 165.605968 -247.671336) (xy 165.605968 -247.262396) (xy 165.606418 -247.252246)
			(xy 165.614209 -247.233499) (xy 165.628596 -247.219177) (xy 165.647378 -247.211472) (xy 165.65753 -247.211088)
			(xy 167.05707 -247.211088) (xy 167.067188 -247.211649) (xy 167.085899 -247.219358) (xy 167.100255 -247.233621)
			(xy 167.108084 -247.252281) (xy 167.108632 -247.262396) (xy 167.108632 -247.671336) (xy 173.149768 -247.671336)
			(xy 173.149768 -247.262396) (xy 173.150218 -247.252246) (xy 173.158009 -247.233499) (xy 173.172396 -247.219177)
			(xy 173.191178 -247.211472) (xy 173.20133 -247.211088) (xy 174.60087 -247.211088) (xy 174.610988 -247.211649)
			(xy 174.629699 -247.219358) (xy 174.644055 -247.233621) (xy 174.651884 -247.252281) (xy 174.652432 -247.262396)
			(xy 174.652432 -247.671336) (xy 180.693568 -247.671336) (xy 180.693568 -247.262396) (xy 180.694018 -247.252246)
			(xy 180.701809 -247.233499) (xy 180.716196 -247.219177) (xy 180.734978 -247.211472) (xy 180.74513 -247.211088)
			(xy 182.14467 -247.211088) (xy 182.154788 -247.211649) (xy 182.173499 -247.219358) (xy 182.187855 -247.233621)
			(xy 182.195684 -247.252281) (xy 182.196232 -247.262396) (xy 182.196232 -247.671336) (xy 188.237368 -247.671336)
			(xy 188.237368 -247.262396) (xy 188.237818 -247.252246) (xy 188.245609 -247.233499) (xy 188.259996 -247.219177)
			(xy 188.278778 -247.211472) (xy 188.28893 -247.211088) (xy 189.68847 -247.211088) (xy 189.698588 -247.211649)
			(xy 189.717299 -247.219358) (xy 189.731655 -247.233621) (xy 189.739484 -247.252281) (xy 189.740032 -247.262396)
			(xy 189.740032 -247.671336) (xy 195.781168 -247.671336) (xy 195.781168 -247.262396) (xy 195.781618 -247.252246)
			(xy 195.789409 -247.233499) (xy 195.803796 -247.219177) (xy 195.822578 -247.211472) (xy 195.83273 -247.211088)
			(xy 197.23227 -247.211088) (xy 197.242388 -247.211649) (xy 197.261099 -247.219358) (xy 197.275455 -247.233621)
			(xy 197.283284 -247.252281) (xy 197.283832 -247.262396) (xy 197.283832 -247.671336) (xy 203.324968 -247.671336)
			(xy 203.324968 -247.262396) (xy 203.325418 -247.252246) (xy 203.333209 -247.233499) (xy 203.347596 -247.219177)
			(xy 203.366378 -247.211472) (xy 203.37653 -247.211088) (xy 204.77607 -247.211088) (xy 204.786188 -247.211649)
			(xy 204.804899 -247.219358) (xy 204.819255 -247.233621) (xy 204.827084 -247.252281) (xy 204.827632 -247.262396)
			(xy 204.827632 -247.671336) (xy 210.868768 -247.671336) (xy 210.868768 -247.262396) (xy 210.869218 -247.252246)
			(xy 210.877009 -247.233499) (xy 210.891396 -247.219177) (xy 210.910178 -247.211472) (xy 210.92033 -247.211088)
			(xy 212.31987 -247.211088) (xy 212.329988 -247.211649) (xy 212.348699 -247.219358) (xy 212.363055 -247.233621)
			(xy 212.370884 -247.252281) (xy 212.371432 -247.262396) (xy 212.371432 -247.620536) (xy 228.175312 -247.620536)
			(xy 228.175312 -246.756936) (xy 228.175798 -246.729685) (xy 228.183554 -246.675737) (xy 228.198909 -246.623442)
			(xy 228.221551 -246.573865) (xy 228.251017 -246.528015) (xy 228.286708 -246.486824) (xy 228.327899 -246.451133)
			(xy 228.373749 -246.421667) (xy 228.423326 -246.399025) (xy 228.475621 -246.38367) (xy 228.529569 -246.375914)
			(xy 228.584071 -246.375914) (xy 228.638019 -246.38367) (xy 228.690314 -246.399025) (xy 228.739891 -246.421667)
			(xy 228.785741 -246.451133) (xy 228.826932 -246.486824) (xy 228.862623 -246.528015) (xy 228.892089 -246.573865)
			(xy 228.914731 -246.623442) (xy 228.930086 -246.675737) (xy 228.937842 -246.729685) (xy 228.938328 -246.756936)
			(xy 228.938328 -246.821452) (xy 259.429504 -246.821452) (xy 259.429504 -246.412512) (xy 259.429931 -246.402358)
			(xy 259.437724 -246.383605) (xy 259.452119 -246.369281) (xy 259.47091 -246.361582) (xy 259.481066 -246.361204)
			(xy 260.880606 -246.361204) (xy 260.890729 -246.361721) (xy 260.909443 -246.369444) (xy 260.923798 -246.38372)
			(xy 260.931623 -246.402392) (xy 260.932168 -246.412512) (xy 260.932168 -246.821452) (xy 266.973304 -246.821452)
			(xy 266.973304 -246.412512) (xy 266.973731 -246.402358) (xy 266.981524 -246.383605) (xy 266.995919 -246.369281)
			(xy 267.01471 -246.361582) (xy 267.024866 -246.361204) (xy 268.424406 -246.361204) (xy 268.434529 -246.361721)
			(xy 268.453243 -246.369444) (xy 268.467598 -246.38372) (xy 268.475423 -246.402392) (xy 268.475968 -246.412512)
			(xy 268.475968 -246.821452) (xy 274.517104 -246.821452) (xy 274.517104 -246.412512) (xy 274.517531 -246.402358)
			(xy 274.525324 -246.383605) (xy 274.539719 -246.369281) (xy 274.55851 -246.361582) (xy 274.568666 -246.361204)
			(xy 275.968206 -246.361204) (xy 275.978329 -246.361721) (xy 275.997043 -246.369444) (xy 276.011398 -246.38372)
			(xy 276.019223 -246.402392) (xy 276.019768 -246.412512) (xy 276.019768 -246.821452) (xy 282.060904 -246.821452)
			(xy 282.060904 -246.412512) (xy 282.061331 -246.402358) (xy 282.069124 -246.383605) (xy 282.083519 -246.369281)
			(xy 282.10231 -246.361582) (xy 282.112466 -246.361204) (xy 283.512006 -246.361204) (xy 283.522129 -246.361721)
			(xy 283.540843 -246.369444) (xy 283.555198 -246.38372) (xy 283.563023 -246.402392) (xy 283.563568 -246.412512)
			(xy 283.563568 -246.821452) (xy 289.604704 -246.821452) (xy 289.604704 -246.412512) (xy 289.605131 -246.402358)
			(xy 289.612924 -246.383605) (xy 289.627319 -246.369281) (xy 289.64611 -246.361582) (xy 289.656266 -246.361204)
			(xy 291.055806 -246.361204) (xy 291.065929 -246.361721) (xy 291.084643 -246.369444) (xy 291.098998 -246.38372)
			(xy 291.106823 -246.402392) (xy 291.107368 -246.412512) (xy 291.107368 -246.821452) (xy 297.148504 -246.821452)
			(xy 297.148504 -246.412512) (xy 297.148931 -246.402358) (xy 297.156724 -246.383605) (xy 297.171119 -246.369281)
			(xy 297.18991 -246.361582) (xy 297.200066 -246.361204) (xy 298.599606 -246.361204) (xy 298.609729 -246.361721)
			(xy 298.628443 -246.369444) (xy 298.642798 -246.38372) (xy 298.650623 -246.402392) (xy 298.651168 -246.412512)
			(xy 298.651168 -246.821452) (xy 304.692304 -246.821452) (xy 304.692304 -246.412512) (xy 304.692731 -246.402358)
			(xy 304.700524 -246.383605) (xy 304.714919 -246.369281) (xy 304.73371 -246.361582) (xy 304.743866 -246.361204)
			(xy 306.143406 -246.361204) (xy 306.153529 -246.361721) (xy 306.172243 -246.369444) (xy 306.186598 -246.38372)
			(xy 306.194423 -246.402392) (xy 306.194968 -246.412512) (xy 306.194968 -246.821452) (xy 312.236104 -246.821452)
			(xy 312.236104 -246.412512) (xy 312.236531 -246.402358) (xy 312.244324 -246.383605) (xy 312.258719 -246.369281)
			(xy 312.27751 -246.361582) (xy 312.287666 -246.361204) (xy 313.687206 -246.361204) (xy 313.697329 -246.361721)
			(xy 313.716043 -246.369444) (xy 313.730398 -246.38372) (xy 313.738223 -246.402392) (xy 313.738768 -246.412512)
			(xy 313.738768 -246.821452) (xy 410.102304 -246.821452) (xy 410.102304 -246.412512) (xy 410.102731 -246.402358)
			(xy 410.110524 -246.383605) (xy 410.124919 -246.369281) (xy 410.14371 -246.361582) (xy 410.153866 -246.361204)
			(xy 411.553406 -246.361204) (xy 411.563529 -246.361721) (xy 411.582243 -246.369444) (xy 411.596598 -246.38372)
			(xy 411.604423 -246.402392) (xy 411.604968 -246.412512) (xy 411.604968 -246.821452) (xy 417.646104 -246.821452)
			(xy 417.646104 -246.412512) (xy 417.646531 -246.402358) (xy 417.654324 -246.383605) (xy 417.668719 -246.369281)
			(xy 417.68751 -246.361582) (xy 417.697666 -246.361204) (xy 419.097206 -246.361204) (xy 419.107329 -246.361721)
			(xy 419.126043 -246.369444) (xy 419.140398 -246.38372) (xy 419.148223 -246.402392) (xy 419.148768 -246.412512)
			(xy 419.148768 -246.821452) (xy 425.189904 -246.821452) (xy 425.189904 -246.412512) (xy 425.190331 -246.402358)
			(xy 425.198124 -246.383605) (xy 425.212519 -246.369281) (xy 425.23131 -246.361582) (xy 425.241466 -246.361204)
			(xy 426.641006 -246.361204) (xy 426.651129 -246.361721) (xy 426.669843 -246.369444) (xy 426.684198 -246.38372)
			(xy 426.692023 -246.402392) (xy 426.692568 -246.412512) (xy 426.692568 -246.821452) (xy 432.733704 -246.821452)
			(xy 432.733704 -246.412512) (xy 432.734131 -246.402358) (xy 432.741924 -246.383605) (xy 432.756319 -246.369281)
			(xy 432.77511 -246.361582) (xy 432.785266 -246.361204) (xy 434.184806 -246.361204) (xy 434.194929 -246.361721)
			(xy 434.213643 -246.369444) (xy 434.227998 -246.38372) (xy 434.235823 -246.402392) (xy 434.236368 -246.412512)
			(xy 434.236368 -246.821452) (xy 440.277504 -246.821452) (xy 440.277504 -246.412512) (xy 440.277931 -246.402358)
			(xy 440.285724 -246.383605) (xy 440.300119 -246.369281) (xy 440.31891 -246.361582) (xy 440.329066 -246.361204)
			(xy 441.728606 -246.361204) (xy 441.738729 -246.361721) (xy 441.757443 -246.369444) (xy 441.771798 -246.38372)
			(xy 441.779623 -246.402392) (xy 441.780168 -246.412512) (xy 441.780168 -246.821452) (xy 447.821304 -246.821452)
			(xy 447.821304 -246.412512) (xy 447.821731 -246.402358) (xy 447.829524 -246.383605) (xy 447.843919 -246.369281)
			(xy 447.86271 -246.361582) (xy 447.872866 -246.361204) (xy 449.272406 -246.361204) (xy 449.282529 -246.361721)
			(xy 449.301243 -246.369444) (xy 449.315598 -246.38372) (xy 449.323423 -246.402392) (xy 449.323968 -246.412512)
			(xy 449.323968 -246.821452) (xy 455.365104 -246.821452) (xy 455.365104 -246.412512) (xy 455.365531 -246.402358)
			(xy 455.373324 -246.383605) (xy 455.387719 -246.369281) (xy 455.40651 -246.361582) (xy 455.416666 -246.361204)
			(xy 456.816206 -246.361204) (xy 456.826329 -246.361721) (xy 456.845043 -246.369444) (xy 456.859398 -246.38372)
			(xy 456.867223 -246.402392) (xy 456.867768 -246.412512) (xy 456.867768 -246.821452) (xy 462.908904 -246.821452)
			(xy 462.908904 -246.412512) (xy 462.909331 -246.402358) (xy 462.917124 -246.383605) (xy 462.931519 -246.369281)
			(xy 462.95031 -246.361582) (xy 462.960466 -246.361204) (xy 464.360006 -246.361204) (xy 464.370129 -246.361721)
			(xy 464.388843 -246.369444) (xy 464.403198 -246.38372) (xy 464.411023 -246.402392) (xy 464.411568 -246.412512)
			(xy 464.411568 -246.821452) (xy 464.411138 -246.831607) (xy 464.403353 -246.850365) (xy 464.388958 -246.864691)
			(xy 464.370163 -246.872386) (xy 464.360006 -246.87276) (xy 462.960466 -246.87276) (xy 462.950337 -246.872301)
			(xy 462.931615 -246.864562) (xy 462.91726 -246.850268) (xy 462.909442 -246.831579) (xy 462.908904 -246.821452)
			(xy 456.867768 -246.821452) (xy 456.867338 -246.831607) (xy 456.859553 -246.850365) (xy 456.845158 -246.864691)
			(xy 456.826363 -246.872386) (xy 456.816206 -246.87276) (xy 455.416666 -246.87276) (xy 455.406537 -246.872301)
			(xy 455.387815 -246.864562) (xy 455.37346 -246.850268) (xy 455.365642 -246.831579) (xy 455.365104 -246.821452)
			(xy 449.323968 -246.821452) (xy 449.323538 -246.831607) (xy 449.315753 -246.850365) (xy 449.301358 -246.864691)
			(xy 449.282563 -246.872386) (xy 449.272406 -246.87276) (xy 447.872866 -246.87276) (xy 447.862737 -246.872301)
			(xy 447.844015 -246.864562) (xy 447.82966 -246.850268) (xy 447.821842 -246.831579) (xy 447.821304 -246.821452)
			(xy 441.780168 -246.821452) (xy 441.779738 -246.831607) (xy 441.771953 -246.850365) (xy 441.757558 -246.864691)
			(xy 441.738763 -246.872386) (xy 441.728606 -246.87276) (xy 440.329066 -246.87276) (xy 440.318937 -246.872301)
			(xy 440.300215 -246.864562) (xy 440.28586 -246.850268) (xy 440.278042 -246.831579) (xy 440.277504 -246.821452)
			(xy 434.236368 -246.821452) (xy 434.235938 -246.831607) (xy 434.228153 -246.850365) (xy 434.213758 -246.864691)
			(xy 434.194963 -246.872386) (xy 434.184806 -246.87276) (xy 432.785266 -246.87276) (xy 432.775137 -246.872301)
			(xy 432.756415 -246.864562) (xy 432.74206 -246.850268) (xy 432.734242 -246.831579) (xy 432.733704 -246.821452)
			(xy 426.692568 -246.821452) (xy 426.692138 -246.831607) (xy 426.684353 -246.850365) (xy 426.669958 -246.864691)
			(xy 426.651163 -246.872386) (xy 426.641006 -246.87276) (xy 425.241466 -246.87276) (xy 425.231337 -246.872301)
			(xy 425.212615 -246.864562) (xy 425.19826 -246.850268) (xy 425.190442 -246.831579) (xy 425.189904 -246.821452)
			(xy 419.148768 -246.821452) (xy 419.148338 -246.831607) (xy 419.140553 -246.850365) (xy 419.126158 -246.864691)
			(xy 419.107363 -246.872386) (xy 419.097206 -246.87276) (xy 417.697666 -246.87276) (xy 417.687537 -246.872301)
			(xy 417.668815 -246.864562) (xy 417.65446 -246.850268) (xy 417.646642 -246.831579) (xy 417.646104 -246.821452)
			(xy 411.604968 -246.821452) (xy 411.604538 -246.831607) (xy 411.596753 -246.850365) (xy 411.582358 -246.864691)
			(xy 411.563563 -246.872386) (xy 411.553406 -246.87276) (xy 410.153866 -246.87276) (xy 410.143737 -246.872301)
			(xy 410.125015 -246.864562) (xy 410.11066 -246.850268) (xy 410.102842 -246.831579) (xy 410.102304 -246.821452)
			(xy 313.738768 -246.821452) (xy 313.738338 -246.831607) (xy 313.730553 -246.850365) (xy 313.716158 -246.864691)
			(xy 313.697363 -246.872386) (xy 313.687206 -246.87276) (xy 312.287666 -246.87276) (xy 312.277537 -246.872301)
			(xy 312.258815 -246.864562) (xy 312.24446 -246.850268) (xy 312.236642 -246.831579) (xy 312.236104 -246.821452)
			(xy 306.194968 -246.821452) (xy 306.194538 -246.831607) (xy 306.186753 -246.850365) (xy 306.172358 -246.864691)
			(xy 306.153563 -246.872386) (xy 306.143406 -246.87276) (xy 304.743866 -246.87276) (xy 304.733737 -246.872301)
			(xy 304.715015 -246.864562) (xy 304.70066 -246.850268) (xy 304.692842 -246.831579) (xy 304.692304 -246.821452)
			(xy 298.651168 -246.821452) (xy 298.650738 -246.831607) (xy 298.642953 -246.850365) (xy 298.628558 -246.864691)
			(xy 298.609763 -246.872386) (xy 298.599606 -246.87276) (xy 297.200066 -246.87276) (xy 297.189937 -246.872301)
			(xy 297.171215 -246.864562) (xy 297.15686 -246.850268) (xy 297.149042 -246.831579) (xy 297.148504 -246.821452)
			(xy 291.107368 -246.821452) (xy 291.106938 -246.831607) (xy 291.099153 -246.850365) (xy 291.084758 -246.864691)
			(xy 291.065963 -246.872386) (xy 291.055806 -246.87276) (xy 289.656266 -246.87276) (xy 289.646137 -246.872301)
			(xy 289.627415 -246.864562) (xy 289.61306 -246.850268) (xy 289.605242 -246.831579) (xy 289.604704 -246.821452)
			(xy 283.563568 -246.821452) (xy 283.563138 -246.831607) (xy 283.555353 -246.850365) (xy 283.540958 -246.864691)
			(xy 283.522163 -246.872386) (xy 283.512006 -246.87276) (xy 282.112466 -246.87276) (xy 282.102337 -246.872301)
			(xy 282.083615 -246.864562) (xy 282.06926 -246.850268) (xy 282.061442 -246.831579) (xy 282.060904 -246.821452)
			(xy 276.019768 -246.821452) (xy 276.019338 -246.831607) (xy 276.011553 -246.850365) (xy 275.997158 -246.864691)
			(xy 275.978363 -246.872386) (xy 275.968206 -246.87276) (xy 274.568666 -246.87276) (xy 274.558537 -246.872301)
			(xy 274.539815 -246.864562) (xy 274.52546 -246.850268) (xy 274.517642 -246.831579) (xy 274.517104 -246.821452)
			(xy 268.475968 -246.821452) (xy 268.475538 -246.831607) (xy 268.467753 -246.850365) (xy 268.453358 -246.864691)
			(xy 268.434563 -246.872386) (xy 268.424406 -246.87276) (xy 267.024866 -246.87276) (xy 267.014737 -246.872301)
			(xy 266.996015 -246.864562) (xy 266.98166 -246.850268) (xy 266.973842 -246.831579) (xy 266.973304 -246.821452)
			(xy 260.932168 -246.821452) (xy 260.931738 -246.831607) (xy 260.923953 -246.850365) (xy 260.909558 -246.864691)
			(xy 260.890763 -246.872386) (xy 260.880606 -246.87276) (xy 259.481066 -246.87276) (xy 259.470937 -246.872301)
			(xy 259.452215 -246.864562) (xy 259.43786 -246.850268) (xy 259.430042 -246.831579) (xy 259.429504 -246.821452)
			(xy 228.938328 -246.821452) (xy 228.938328 -247.620536) (xy 228.937842 -247.647787) (xy 228.934456 -247.671336)
			(xy 255.329436 -247.671336) (xy 255.329436 -247.262396) (xy 255.329819 -247.252237) (xy 255.337623 -247.233478)
			(xy 255.352032 -247.219153) (xy 255.370837 -247.21146) (xy 255.380998 -247.211088) (xy 256.780538 -247.211088)
			(xy 256.790661 -247.211594) (xy 256.809373 -247.219325) (xy 256.823726 -247.233604) (xy 256.831553 -247.252276)
			(xy 256.8321 -247.262396) (xy 256.8321 -247.671336) (xy 262.873236 -247.671336) (xy 262.873236 -247.262396)
			(xy 262.873619 -247.252237) (xy 262.881423 -247.233478) (xy 262.895832 -247.219153) (xy 262.914637 -247.21146)
			(xy 262.924798 -247.211088) (xy 264.324338 -247.211088) (xy 264.334461 -247.211594) (xy 264.353173 -247.219325)
			(xy 264.367526 -247.233604) (xy 264.375353 -247.252276) (xy 264.3759 -247.262396) (xy 264.3759 -247.671336)
			(xy 270.417036 -247.671336) (xy 270.417036 -247.262396) (xy 270.417419 -247.252237) (xy 270.425223 -247.233478)
			(xy 270.439632 -247.219153) (xy 270.458437 -247.21146) (xy 270.468598 -247.211088) (xy 271.868138 -247.211088)
			(xy 271.878261 -247.211594) (xy 271.896973 -247.219325) (xy 271.911326 -247.233604) (xy 271.919153 -247.252276)
			(xy 271.9197 -247.262396) (xy 271.9197 -247.671336) (xy 277.960836 -247.671336) (xy 277.960836 -247.262396)
			(xy 277.961219 -247.252237) (xy 277.969023 -247.233478) (xy 277.983432 -247.219153) (xy 278.002237 -247.21146)
			(xy 278.012398 -247.211088) (xy 279.411938 -247.211088) (xy 279.422061 -247.211594) (xy 279.440773 -247.219325)
			(xy 279.455126 -247.233604) (xy 279.462953 -247.252276) (xy 279.4635 -247.262396) (xy 279.4635 -247.671336)
			(xy 285.504636 -247.671336) (xy 285.504636 -247.262396) (xy 285.505019 -247.252237) (xy 285.512823 -247.233478)
			(xy 285.527232 -247.219153) (xy 285.546037 -247.21146) (xy 285.556198 -247.211088) (xy 286.955738 -247.211088)
			(xy 286.965861 -247.211594) (xy 286.984573 -247.219325) (xy 286.998926 -247.233604) (xy 287.006753 -247.252276)
			(xy 287.0073 -247.262396) (xy 287.0073 -247.671336) (xy 293.048436 -247.671336) (xy 293.048436 -247.262396)
			(xy 293.048819 -247.252237) (xy 293.056623 -247.233478) (xy 293.071032 -247.219153) (xy 293.089837 -247.21146)
			(xy 293.099998 -247.211088) (xy 294.499538 -247.211088) (xy 294.509661 -247.211594) (xy 294.528373 -247.219325)
			(xy 294.542726 -247.233604) (xy 294.550553 -247.252276) (xy 294.5511 -247.262396) (xy 294.5511 -247.671336)
			(xy 300.592236 -247.671336) (xy 300.592236 -247.262396) (xy 300.592619 -247.252237) (xy 300.600423 -247.233478)
			(xy 300.614832 -247.219153) (xy 300.633637 -247.21146) (xy 300.643798 -247.211088) (xy 302.043338 -247.211088)
			(xy 302.053461 -247.211594) (xy 302.072173 -247.219325) (xy 302.086526 -247.233604) (xy 302.094353 -247.252276)
			(xy 302.0949 -247.262396) (xy 302.0949 -247.671336) (xy 308.136036 -247.671336) (xy 308.136036 -247.262396)
			(xy 308.136419 -247.252237) (xy 308.144223 -247.233478) (xy 308.158632 -247.219153) (xy 308.177437 -247.21146)
			(xy 308.187598 -247.211088) (xy 309.587138 -247.211088) (xy 309.597261 -247.211594) (xy 309.615973 -247.219325)
			(xy 309.630326 -247.233604) (xy 309.638153 -247.252276) (xy 309.6387 -247.262396) (xy 309.6387 -247.671336)
			(xy 406.002236 -247.671336) (xy 406.002236 -247.262396) (xy 406.002619 -247.252237) (xy 406.010423 -247.233478)
			(xy 406.024832 -247.219153) (xy 406.043637 -247.21146) (xy 406.053798 -247.211088) (xy 407.453338 -247.211088)
			(xy 407.463461 -247.211594) (xy 407.482173 -247.219325) (xy 407.496526 -247.233604) (xy 407.504353 -247.252276)
			(xy 407.5049 -247.262396) (xy 407.5049 -247.671336) (xy 413.546036 -247.671336) (xy 413.546036 -247.262396)
			(xy 413.546419 -247.252237) (xy 413.554223 -247.233478) (xy 413.568632 -247.219153) (xy 413.587437 -247.21146)
			(xy 413.597598 -247.211088) (xy 414.997138 -247.211088) (xy 415.007261 -247.211594) (xy 415.025973 -247.219325)
			(xy 415.040326 -247.233604) (xy 415.048153 -247.252276) (xy 415.0487 -247.262396) (xy 415.0487 -247.671336)
			(xy 421.089836 -247.671336) (xy 421.089836 -247.262396) (xy 421.090219 -247.252237) (xy 421.098023 -247.233478)
			(xy 421.112432 -247.219153) (xy 421.131237 -247.21146) (xy 421.141398 -247.211088) (xy 422.540938 -247.211088)
			(xy 422.551061 -247.211594) (xy 422.569773 -247.219325) (xy 422.584126 -247.233604) (xy 422.591953 -247.252276)
			(xy 422.5925 -247.262396) (xy 422.5925 -247.671336) (xy 428.633636 -247.671336) (xy 428.633636 -247.262396)
			(xy 428.634019 -247.252237) (xy 428.641823 -247.233478) (xy 428.656232 -247.219153) (xy 428.675037 -247.21146)
			(xy 428.685198 -247.211088) (xy 430.084738 -247.211088) (xy 430.094861 -247.211594) (xy 430.113573 -247.219325)
			(xy 430.127926 -247.233604) (xy 430.135753 -247.252276) (xy 430.1363 -247.262396) (xy 430.1363 -247.671336)
			(xy 436.177436 -247.671336) (xy 436.177436 -247.262396) (xy 436.177819 -247.252237) (xy 436.185623 -247.233478)
			(xy 436.200032 -247.219153) (xy 436.218837 -247.21146) (xy 436.228998 -247.211088) (xy 437.628538 -247.211088)
			(xy 437.638661 -247.211594) (xy 437.657373 -247.219325) (xy 437.671726 -247.233604) (xy 437.679553 -247.252276)
			(xy 437.6801 -247.262396) (xy 437.6801 -247.671336) (xy 443.721236 -247.671336) (xy 443.721236 -247.262396)
			(xy 443.721619 -247.252237) (xy 443.729423 -247.233478) (xy 443.743832 -247.219153) (xy 443.762637 -247.21146)
			(xy 443.772798 -247.211088) (xy 445.172338 -247.211088) (xy 445.182461 -247.211594) (xy 445.201173 -247.219325)
			(xy 445.215526 -247.233604) (xy 445.223353 -247.252276) (xy 445.2239 -247.262396) (xy 445.2239 -247.671336)
			(xy 451.265036 -247.671336) (xy 451.265036 -247.262396) (xy 451.265419 -247.252237) (xy 451.273223 -247.233478)
			(xy 451.287632 -247.219153) (xy 451.306437 -247.21146) (xy 451.316598 -247.211088) (xy 452.716138 -247.211088)
			(xy 452.726261 -247.211594) (xy 452.744973 -247.219325) (xy 452.759326 -247.233604) (xy 452.767153 -247.252276)
			(xy 452.7677 -247.262396) (xy 452.7677 -247.671336) (xy 458.808836 -247.671336) (xy 458.808836 -247.262396)
			(xy 458.809219 -247.252237) (xy 458.817023 -247.233478) (xy 458.831432 -247.219153) (xy 458.850237 -247.21146)
			(xy 458.860398 -247.211088) (xy 460.259938 -247.211088) (xy 460.270061 -247.211594) (xy 460.288773 -247.219325)
			(xy 460.303126 -247.233604) (xy 460.310953 -247.252276) (xy 460.3115 -247.262396) (xy 460.3115 -247.671336)
			(xy 460.311108 -247.681492) (xy 460.3033 -247.700246) (xy 460.288895 -247.714568) (xy 460.270097 -247.722266)
			(xy 460.259938 -247.722644) (xy 458.860398 -247.722644) (xy 458.850269 -247.722174) (xy 458.831545 -247.714443)
			(xy 458.817188 -247.700151) (xy 458.809372 -247.681462) (xy 458.808836 -247.671336) (xy 452.7677 -247.671336)
			(xy 452.767308 -247.681492) (xy 452.7595 -247.700246) (xy 452.745095 -247.714568) (xy 452.726297 -247.722266)
			(xy 452.716138 -247.722644) (xy 451.316598 -247.722644) (xy 451.306469 -247.722174) (xy 451.287745 -247.714443)
			(xy 451.273388 -247.700151) (xy 451.265572 -247.681462) (xy 451.265036 -247.671336) (xy 445.2239 -247.671336)
			(xy 445.223508 -247.681492) (xy 445.2157 -247.700246) (xy 445.201295 -247.714568) (xy 445.182497 -247.722266)
			(xy 445.172338 -247.722644) (xy 443.772798 -247.722644) (xy 443.762669 -247.722174) (xy 443.743945 -247.714443)
			(xy 443.729588 -247.700151) (xy 443.721772 -247.681462) (xy 443.721236 -247.671336) (xy 437.6801 -247.671336)
			(xy 437.679708 -247.681492) (xy 437.6719 -247.700246) (xy 437.657495 -247.714568) (xy 437.638697 -247.722266)
			(xy 437.628538 -247.722644) (xy 436.228998 -247.722644) (xy 436.218869 -247.722174) (xy 436.200145 -247.714443)
			(xy 436.185788 -247.700151) (xy 436.177972 -247.681462) (xy 436.177436 -247.671336) (xy 430.1363 -247.671336)
			(xy 430.135908 -247.681492) (xy 430.1281 -247.700246) (xy 430.113695 -247.714568) (xy 430.094897 -247.722266)
			(xy 430.084738 -247.722644) (xy 428.685198 -247.722644) (xy 428.675069 -247.722174) (xy 428.656345 -247.714443)
			(xy 428.641988 -247.700151) (xy 428.634172 -247.681462) (xy 428.633636 -247.671336) (xy 422.5925 -247.671336)
			(xy 422.592108 -247.681492) (xy 422.5843 -247.700246) (xy 422.569895 -247.714568) (xy 422.551097 -247.722266)
			(xy 422.540938 -247.722644) (xy 421.141398 -247.722644) (xy 421.131269 -247.722174) (xy 421.112545 -247.714443)
			(xy 421.098188 -247.700151) (xy 421.090372 -247.681462) (xy 421.089836 -247.671336) (xy 415.0487 -247.671336)
			(xy 415.048308 -247.681492) (xy 415.0405 -247.700246) (xy 415.026095 -247.714568) (xy 415.007297 -247.722266)
			(xy 414.997138 -247.722644) (xy 413.597598 -247.722644) (xy 413.587469 -247.722174) (xy 413.568745 -247.714443)
			(xy 413.554388 -247.700151) (xy 413.546572 -247.681462) (xy 413.546036 -247.671336) (xy 407.5049 -247.671336)
			(xy 407.504508 -247.681492) (xy 407.4967 -247.700246) (xy 407.482295 -247.714568) (xy 407.463497 -247.722266)
			(xy 407.453338 -247.722644) (xy 406.053798 -247.722644) (xy 406.043669 -247.722174) (xy 406.024945 -247.714443)
			(xy 406.010588 -247.700151) (xy 406.002772 -247.681462) (xy 406.002236 -247.671336) (xy 309.6387 -247.671336)
			(xy 309.638308 -247.681492) (xy 309.6305 -247.700246) (xy 309.616095 -247.714568) (xy 309.597297 -247.722266)
			(xy 309.587138 -247.722644) (xy 308.187598 -247.722644) (xy 308.177469 -247.722174) (xy 308.158745 -247.714443)
			(xy 308.144388 -247.700151) (xy 308.136572 -247.681462) (xy 308.136036 -247.671336) (xy 302.0949 -247.671336)
			(xy 302.094508 -247.681492) (xy 302.0867 -247.700246) (xy 302.072295 -247.714568) (xy 302.053497 -247.722266)
			(xy 302.043338 -247.722644) (xy 300.643798 -247.722644) (xy 300.633669 -247.722174) (xy 300.614945 -247.714443)
			(xy 300.600588 -247.700151) (xy 300.592772 -247.681462) (xy 300.592236 -247.671336) (xy 294.5511 -247.671336)
			(xy 294.550708 -247.681492) (xy 294.5429 -247.700246) (xy 294.528495 -247.714568) (xy 294.509697 -247.722266)
			(xy 294.499538 -247.722644) (xy 293.099998 -247.722644) (xy 293.089869 -247.722174) (xy 293.071145 -247.714443)
			(xy 293.056788 -247.700151) (xy 293.048972 -247.681462) (xy 293.048436 -247.671336) (xy 287.0073 -247.671336)
			(xy 287.006908 -247.681492) (xy 286.9991 -247.700246) (xy 286.984695 -247.714568) (xy 286.965897 -247.722266)
			(xy 286.955738 -247.722644) (xy 285.556198 -247.722644) (xy 285.546069 -247.722174) (xy 285.527345 -247.714443)
			(xy 285.512988 -247.700151) (xy 285.505172 -247.681462) (xy 285.504636 -247.671336) (xy 279.4635 -247.671336)
			(xy 279.463108 -247.681492) (xy 279.4553 -247.700246) (xy 279.440895 -247.714568) (xy 279.422097 -247.722266)
			(xy 279.411938 -247.722644) (xy 278.012398 -247.722644) (xy 278.002269 -247.722174) (xy 277.983545 -247.714443)
			(xy 277.969188 -247.700151) (xy 277.961372 -247.681462) (xy 277.960836 -247.671336) (xy 271.9197 -247.671336)
			(xy 271.919308 -247.681492) (xy 271.9115 -247.700246) (xy 271.897095 -247.714568) (xy 271.878297 -247.722266)
			(xy 271.868138 -247.722644) (xy 270.468598 -247.722644) (xy 270.458469 -247.722174) (xy 270.439745 -247.714443)
			(xy 270.425388 -247.700151) (xy 270.417572 -247.681462) (xy 270.417036 -247.671336) (xy 264.3759 -247.671336)
			(xy 264.375508 -247.681492) (xy 264.3677 -247.700246) (xy 264.353295 -247.714568) (xy 264.334497 -247.722266)
			(xy 264.324338 -247.722644) (xy 262.924798 -247.722644) (xy 262.914669 -247.722174) (xy 262.895945 -247.714443)
			(xy 262.881588 -247.700151) (xy 262.873772 -247.681462) (xy 262.873236 -247.671336) (xy 256.8321 -247.671336)
			(xy 256.831708 -247.681492) (xy 256.8239 -247.700246) (xy 256.809495 -247.714568) (xy 256.790697 -247.722266)
			(xy 256.780538 -247.722644) (xy 255.380998 -247.722644) (xy 255.370869 -247.722174) (xy 255.352145 -247.714443)
			(xy 255.337788 -247.700151) (xy 255.329972 -247.681462) (xy 255.329436 -247.671336) (xy 228.934456 -247.671336)
			(xy 228.930086 -247.701735) (xy 228.914731 -247.75403) (xy 228.892089 -247.803607) (xy 228.862623 -247.849457)
			(xy 228.826932 -247.890648) (xy 228.785741 -247.926339) (xy 228.739891 -247.955805) (xy 228.690314 -247.978447)
			(xy 228.638019 -247.993802) (xy 228.584071 -248.001558) (xy 228.529569 -248.001558) (xy 228.475621 -247.993802)
			(xy 228.423326 -247.978447) (xy 228.373749 -247.955805) (xy 228.327899 -247.926339) (xy 228.286708 -247.890648)
			(xy 228.251017 -247.849457) (xy 228.221551 -247.803607) (xy 228.198909 -247.75403) (xy 228.183554 -247.701735)
			(xy 228.175798 -247.647787) (xy 228.175312 -247.620536) (xy 212.371432 -247.620536) (xy 212.371432 -247.671336)
			(xy 212.371009 -247.681488) (xy 212.363207 -247.700235) (xy 212.348812 -247.714556) (xy 212.330025 -247.722261)
			(xy 212.31987 -247.722644) (xy 210.92033 -247.722644) (xy 210.910203 -247.722149) (xy 210.89148 -247.714428)
			(xy 210.877122 -247.700144) (xy 210.869304 -247.68146) (xy 210.868768 -247.671336) (xy 204.827632 -247.671336)
			(xy 204.827209 -247.681488) (xy 204.819407 -247.700235) (xy 204.805012 -247.714556) (xy 204.786225 -247.722261)
			(xy 204.77607 -247.722644) (xy 203.37653 -247.722644) (xy 203.366403 -247.722149) (xy 203.34768 -247.714428)
			(xy 203.333322 -247.700144) (xy 203.325504 -247.68146) (xy 203.324968 -247.671336) (xy 197.283832 -247.671336)
			(xy 197.283409 -247.681488) (xy 197.275607 -247.700235) (xy 197.261212 -247.714556) (xy 197.242425 -247.722261)
			(xy 197.23227 -247.722644) (xy 195.83273 -247.722644) (xy 195.822603 -247.722149) (xy 195.80388 -247.714428)
			(xy 195.789522 -247.700144) (xy 195.781704 -247.68146) (xy 195.781168 -247.671336) (xy 189.740032 -247.671336)
			(xy 189.739609 -247.681488) (xy 189.731807 -247.700235) (xy 189.717412 -247.714556) (xy 189.698625 -247.722261)
			(xy 189.68847 -247.722644) (xy 188.28893 -247.722644) (xy 188.278803 -247.722149) (xy 188.26008 -247.714428)
			(xy 188.245722 -247.700144) (xy 188.237904 -247.68146) (xy 188.237368 -247.671336) (xy 182.196232 -247.671336)
			(xy 182.195809 -247.681488) (xy 182.188007 -247.700235) (xy 182.173612 -247.714556) (xy 182.154825 -247.722261)
			(xy 182.14467 -247.722644) (xy 180.74513 -247.722644) (xy 180.735003 -247.722149) (xy 180.71628 -247.714428)
			(xy 180.701922 -247.700144) (xy 180.694104 -247.68146) (xy 180.693568 -247.671336) (xy 174.652432 -247.671336)
			(xy 174.652009 -247.681488) (xy 174.644207 -247.700235) (xy 174.629812 -247.714556) (xy 174.611025 -247.722261)
			(xy 174.60087 -247.722644) (xy 173.20133 -247.722644) (xy 173.191203 -247.722149) (xy 173.17248 -247.714428)
			(xy 173.158122 -247.700144) (xy 173.150304 -247.68146) (xy 173.149768 -247.671336) (xy 167.108632 -247.671336)
			(xy 167.108209 -247.681488) (xy 167.100407 -247.700235) (xy 167.086012 -247.714556) (xy 167.067225 -247.722261)
			(xy 167.05707 -247.722644) (xy 165.65753 -247.722644) (xy 165.647403 -247.722149) (xy 165.62868 -247.714428)
			(xy 165.614322 -247.700144) (xy 165.606504 -247.68146) (xy 165.605968 -247.671336) (xy 159.564832 -247.671336)
			(xy 159.564409 -247.681488) (xy 159.556607 -247.700235) (xy 159.542212 -247.714556) (xy 159.523425 -247.722261)
			(xy 159.51327 -247.722644) (xy 158.11373 -247.722644) (xy 158.103603 -247.722149) (xy 158.08488 -247.714428)
			(xy 158.070522 -247.700144) (xy 158.062704 -247.68146) (xy 158.062168 -247.671336) (xy 61.698632 -247.671336)
			(xy 61.698209 -247.681488) (xy 61.690407 -247.700235) (xy 61.676012 -247.714556) (xy 61.657225 -247.722261)
			(xy 61.64707 -247.722644) (xy 60.24753 -247.722644) (xy 60.237403 -247.722149) (xy 60.21868 -247.714428)
			(xy 60.204322 -247.700144) (xy 60.196504 -247.68146) (xy 60.195968 -247.671336) (xy 54.154832 -247.671336)
			(xy 54.154409 -247.681488) (xy 54.146607 -247.700235) (xy 54.132212 -247.714556) (xy 54.113425 -247.722261)
			(xy 54.10327 -247.722644) (xy 52.70373 -247.722644) (xy 52.693603 -247.722149) (xy 52.67488 -247.714428)
			(xy 52.660522 -247.700144) (xy 52.652704 -247.68146) (xy 52.652168 -247.671336) (xy 46.611032 -247.671336)
			(xy 46.610609 -247.681488) (xy 46.602807 -247.700235) (xy 46.588412 -247.714556) (xy 46.569625 -247.722261)
			(xy 46.55947 -247.722644) (xy 45.15993 -247.722644) (xy 45.149803 -247.722149) (xy 45.13108 -247.714428)
			(xy 45.116722 -247.700144) (xy 45.108904 -247.68146) (xy 45.108368 -247.671336) (xy 39.067232 -247.671336)
			(xy 39.066809 -247.681488) (xy 39.059007 -247.700235) (xy 39.044612 -247.714556) (xy 39.025825 -247.722261)
			(xy 39.01567 -247.722644) (xy 37.61613 -247.722644) (xy 37.606003 -247.722149) (xy 37.58728 -247.714428)
			(xy 37.572922 -247.700144) (xy 37.565104 -247.68146) (xy 37.564568 -247.671336) (xy 31.523432 -247.671336)
			(xy 31.523009 -247.681488) (xy 31.515207 -247.700235) (xy 31.500812 -247.714556) (xy 31.482025 -247.722261)
			(xy 31.47187 -247.722644) (xy 30.07233 -247.722644) (xy 30.062203 -247.722149) (xy 30.04348 -247.714428)
			(xy 30.029122 -247.700144) (xy 30.021304 -247.68146) (xy 30.020768 -247.671336) (xy 23.979632 -247.671336)
			(xy 23.979209 -247.681488) (xy 23.971407 -247.700235) (xy 23.957012 -247.714556) (xy 23.938225 -247.722261)
			(xy 23.92807 -247.722644) (xy 22.52853 -247.722644) (xy 22.518403 -247.722149) (xy 22.49968 -247.714428)
			(xy 22.485322 -247.700144) (xy 22.477504 -247.68146) (xy 22.476968 -247.671336) (xy 16.435832 -247.671336)
			(xy 16.435409 -247.681488) (xy 16.427607 -247.700235) (xy 16.413212 -247.714556) (xy 16.394425 -247.722261)
			(xy 16.38427 -247.722644) (xy 14.98473 -247.722644) (xy 14.974603 -247.722149) (xy 14.95588 -247.714428)
			(xy 14.941522 -247.700144) (xy 14.933704 -247.68146) (xy 14.933168 -247.671336) (xy 8.892032 -247.671336)
			(xy 8.891609 -247.681488) (xy 8.883807 -247.700235) (xy 8.869412 -247.714556) (xy 8.850625 -247.722261)
			(xy 8.84047 -247.722644) (xy 7.44093 -247.722644) (xy 7.430803 -247.722149) (xy 7.41208 -247.714428)
			(xy 7.397722 -247.700144) (xy 7.389904 -247.68146) (xy 7.389368 -247.671336) (xy 2.509012 -247.671336)
			(xy 2.509012 -248.521474) (xy 11.489436 -248.521474) (xy 11.489436 -248.112534) (xy 11.489892 -248.102365)
			(xy 11.497665 -248.083571) (xy 11.512041 -248.069185) (xy 11.530829 -248.061399) (xy 11.540998 -248.060972)
			(xy 12.940538 -248.060972) (xy 12.950702 -248.061403) (xy 12.969479 -248.069196) (xy 12.983844 -248.083582)
			(xy 12.991611 -248.102369) (xy 12.9921 -248.112534) (xy 12.9921 -248.521474) (xy 19.033236 -248.521474)
			(xy 19.033236 -248.112534) (xy 19.033692 -248.102365) (xy 19.041465 -248.083571) (xy 19.055841 -248.069185)
			(xy 19.074629 -248.061399) (xy 19.084798 -248.060972) (xy 20.484338 -248.060972) (xy 20.494502 -248.061403)
			(xy 20.513279 -248.069196) (xy 20.527644 -248.083582) (xy 20.535411 -248.102369) (xy 20.5359 -248.112534)
			(xy 20.5359 -248.521474) (xy 26.577036 -248.521474) (xy 26.577036 -248.112534) (xy 26.577492 -248.102365)
			(xy 26.585265 -248.083571) (xy 26.599641 -248.069185) (xy 26.618429 -248.061399) (xy 26.628598 -248.060972)
			(xy 28.028138 -248.060972) (xy 28.038302 -248.061403) (xy 28.057079 -248.069196) (xy 28.071444 -248.083582)
			(xy 28.079211 -248.102369) (xy 28.0797 -248.112534) (xy 28.0797 -248.521474) (xy 34.120836 -248.521474)
			(xy 34.120836 -248.112534) (xy 34.121292 -248.102365) (xy 34.129065 -248.083571) (xy 34.143441 -248.069185)
			(xy 34.162229 -248.061399) (xy 34.172398 -248.060972) (xy 35.571938 -248.060972) (xy 35.582102 -248.061403)
			(xy 35.600879 -248.069196) (xy 35.615244 -248.083582) (xy 35.623011 -248.102369) (xy 35.6235 -248.112534)
			(xy 35.6235 -248.521474) (xy 41.664636 -248.521474) (xy 41.664636 -248.112534) (xy 41.665092 -248.102365)
			(xy 41.672865 -248.083571) (xy 41.687241 -248.069185) (xy 41.706029 -248.061399) (xy 41.716198 -248.060972)
			(xy 43.115738 -248.060972) (xy 43.125902 -248.061403) (xy 43.144679 -248.069196) (xy 43.159044 -248.083582)
			(xy 43.166811 -248.102369) (xy 43.1673 -248.112534) (xy 43.1673 -248.521474) (xy 49.208436 -248.521474)
			(xy 49.208436 -248.112534) (xy 49.208892 -248.102365) (xy 49.216665 -248.083571) (xy 49.231041 -248.069185)
			(xy 49.249829 -248.061399) (xy 49.259998 -248.060972) (xy 50.659538 -248.060972) (xy 50.669702 -248.061403)
			(xy 50.688479 -248.069196) (xy 50.702844 -248.083582) (xy 50.710611 -248.102369) (xy 50.7111 -248.112534)
			(xy 50.7111 -248.521474) (xy 56.752236 -248.521474) (xy 56.752236 -248.112534) (xy 56.752692 -248.102365)
			(xy 56.760465 -248.083571) (xy 56.774841 -248.069185) (xy 56.793629 -248.061399) (xy 56.803798 -248.060972)
			(xy 58.203338 -248.060972) (xy 58.213502 -248.061403) (xy 58.232279 -248.069196) (xy 58.246644 -248.083582)
			(xy 58.254411 -248.102369) (xy 58.2549 -248.112534) (xy 58.2549 -248.521474) (xy 64.296036 -248.521474)
			(xy 64.296036 -248.112534) (xy 64.296492 -248.102365) (xy 64.304265 -248.083571) (xy 64.318641 -248.069185)
			(xy 64.337429 -248.061399) (xy 64.347598 -248.060972) (xy 65.747138 -248.060972) (xy 65.757302 -248.061403)
			(xy 65.776079 -248.069196) (xy 65.790444 -248.083582) (xy 65.798211 -248.102369) (xy 65.7987 -248.112534)
			(xy 65.7987 -248.521474) (xy 162.162236 -248.521474) (xy 162.162236 -248.112534) (xy 162.162692 -248.102365)
			(xy 162.170465 -248.083571) (xy 162.184841 -248.069185) (xy 162.203629 -248.061399) (xy 162.213798 -248.060972)
			(xy 163.613338 -248.060972) (xy 163.623502 -248.061403) (xy 163.642279 -248.069196) (xy 163.656644 -248.083582)
			(xy 163.664411 -248.102369) (xy 163.6649 -248.112534) (xy 163.6649 -248.521474) (xy 169.706036 -248.521474)
			(xy 169.706036 -248.112534) (xy 169.706492 -248.102365) (xy 169.714265 -248.083571) (xy 169.728641 -248.069185)
			(xy 169.747429 -248.061399) (xy 169.757598 -248.060972) (xy 171.157138 -248.060972) (xy 171.167302 -248.061403)
			(xy 171.186079 -248.069196) (xy 171.200444 -248.083582) (xy 171.208211 -248.102369) (xy 171.2087 -248.112534)
			(xy 171.2087 -248.521474) (xy 177.249836 -248.521474) (xy 177.249836 -248.112534) (xy 177.250292 -248.102365)
			(xy 177.258065 -248.083571) (xy 177.272441 -248.069185) (xy 177.291229 -248.061399) (xy 177.301398 -248.060972)
			(xy 178.700938 -248.060972) (xy 178.711102 -248.061403) (xy 178.729879 -248.069196) (xy 178.744244 -248.083582)
			(xy 178.752011 -248.102369) (xy 178.7525 -248.112534) (xy 178.7525 -248.521474) (xy 184.793636 -248.521474)
			(xy 184.793636 -248.112534) (xy 184.794092 -248.102365) (xy 184.801865 -248.083571) (xy 184.816241 -248.069185)
			(xy 184.835029 -248.061399) (xy 184.845198 -248.060972) (xy 186.244738 -248.060972) (xy 186.254902 -248.061403)
			(xy 186.273679 -248.069196) (xy 186.288044 -248.083582) (xy 186.295811 -248.102369) (xy 186.2963 -248.112534)
			(xy 186.2963 -248.521474) (xy 192.337436 -248.521474) (xy 192.337436 -248.112534) (xy 192.337892 -248.102365)
			(xy 192.345665 -248.083571) (xy 192.360041 -248.069185) (xy 192.378829 -248.061399) (xy 192.388998 -248.060972)
			(xy 193.788538 -248.060972) (xy 193.798702 -248.061403) (xy 193.817479 -248.069196) (xy 193.831844 -248.083582)
			(xy 193.839611 -248.102369) (xy 193.8401 -248.112534) (xy 193.8401 -248.521474) (xy 199.881236 -248.521474)
			(xy 199.881236 -248.112534) (xy 199.881692 -248.102365) (xy 199.889465 -248.083571) (xy 199.903841 -248.069185)
			(xy 199.922629 -248.061399) (xy 199.932798 -248.060972) (xy 201.332338 -248.060972) (xy 201.342502 -248.061403)
			(xy 201.361279 -248.069196) (xy 201.375644 -248.083582) (xy 201.383411 -248.102369) (xy 201.3839 -248.112534)
			(xy 201.3839 -248.521474) (xy 207.425036 -248.521474) (xy 207.425036 -248.112534) (xy 207.425492 -248.102365)
			(xy 207.433265 -248.083571) (xy 207.447641 -248.069185) (xy 207.466429 -248.061399) (xy 207.476598 -248.060972)
			(xy 208.876138 -248.060972) (xy 208.886302 -248.061403) (xy 208.905079 -248.069196) (xy 208.919444 -248.083582)
			(xy 208.927211 -248.102369) (xy 208.9277 -248.112534) (xy 208.9277 -248.521474) (xy 214.968836 -248.521474)
			(xy 214.968836 -248.112534) (xy 214.969292 -248.102365) (xy 214.977065 -248.083571) (xy 214.991441 -248.069185)
			(xy 215.010229 -248.061399) (xy 215.020398 -248.060972) (xy 216.419938 -248.060972) (xy 216.430102 -248.061403)
			(xy 216.448879 -248.069196) (xy 216.463244 -248.083582) (xy 216.471011 -248.102369) (xy 216.4715 -248.112534)
			(xy 216.4715 -248.521474) (xy 259.429504 -248.521474) (xy 259.429504 -248.112534) (xy 259.430061 -248.102383)
			(xy 259.437817 -248.083621) (xy 259.452164 -248.069256) (xy 259.470915 -248.061474) (xy 259.481066 -248.060972)
			(xy 260.880606 -248.060972) (xy 260.890782 -248.06136) (xy 260.909584 -248.069153) (xy 260.923969 -248.08355)
			(xy 260.931748 -248.102357) (xy 260.932168 -248.112534) (xy 260.932168 -248.521474) (xy 266.973304 -248.521474)
			(xy 266.973304 -248.112534) (xy 266.973861 -248.102383) (xy 266.981617 -248.083621) (xy 266.995964 -248.069256)
			(xy 267.014715 -248.061474) (xy 267.024866 -248.060972) (xy 268.424406 -248.060972) (xy 268.434582 -248.06136)
			(xy 268.453384 -248.069153) (xy 268.467769 -248.08355) (xy 268.475548 -248.102357) (xy 268.475968 -248.112534)
			(xy 268.475968 -248.521474) (xy 274.517104 -248.521474) (xy 274.517104 -248.112534) (xy 274.517661 -248.102383)
			(xy 274.525417 -248.083621) (xy 274.539764 -248.069256) (xy 274.558515 -248.061474) (xy 274.568666 -248.060972)
			(xy 275.968206 -248.060972) (xy 275.978382 -248.06136) (xy 275.997184 -248.069153) (xy 276.011569 -248.08355)
			(xy 276.019348 -248.102357) (xy 276.019768 -248.112534) (xy 276.019768 -248.521474) (xy 282.060904 -248.521474)
			(xy 282.060904 -248.112534) (xy 282.061461 -248.102383) (xy 282.069217 -248.083621) (xy 282.083564 -248.069256)
			(xy 282.102315 -248.061474) (xy 282.112466 -248.060972) (xy 283.512006 -248.060972) (xy 283.522182 -248.06136)
			(xy 283.540984 -248.069153) (xy 283.555369 -248.08355) (xy 283.563148 -248.102357) (xy 283.563568 -248.112534)
			(xy 283.563568 -248.521474) (xy 289.604704 -248.521474) (xy 289.604704 -248.112534) (xy 289.605261 -248.102383)
			(xy 289.613017 -248.083621) (xy 289.627364 -248.069256) (xy 289.646115 -248.061474) (xy 289.656266 -248.060972)
			(xy 291.055806 -248.060972) (xy 291.065982 -248.06136) (xy 291.084784 -248.069153) (xy 291.099169 -248.08355)
			(xy 291.106948 -248.102357) (xy 291.107368 -248.112534) (xy 291.107368 -248.521474) (xy 297.148504 -248.521474)
			(xy 297.148504 -248.112534) (xy 297.149061 -248.102383) (xy 297.156817 -248.083621) (xy 297.171164 -248.069256)
			(xy 297.189915 -248.061474) (xy 297.200066 -248.060972) (xy 298.599606 -248.060972) (xy 298.609782 -248.06136)
			(xy 298.628584 -248.069153) (xy 298.642969 -248.08355) (xy 298.650748 -248.102357) (xy 298.651168 -248.112534)
			(xy 298.651168 -248.521474) (xy 304.692304 -248.521474) (xy 304.692304 -248.112534) (xy 304.692861 -248.102383)
			(xy 304.700617 -248.083621) (xy 304.714964 -248.069256) (xy 304.733715 -248.061474) (xy 304.743866 -248.060972)
			(xy 306.143406 -248.060972) (xy 306.153582 -248.06136) (xy 306.172384 -248.069153) (xy 306.186769 -248.08355)
			(xy 306.194548 -248.102357) (xy 306.194968 -248.112534) (xy 306.194968 -248.521474) (xy 312.236104 -248.521474)
			(xy 312.236104 -248.112534) (xy 312.236661 -248.102383) (xy 312.244417 -248.083621) (xy 312.258764 -248.069256)
			(xy 312.277515 -248.061474) (xy 312.287666 -248.060972) (xy 313.687206 -248.060972) (xy 313.697382 -248.06136)
			(xy 313.716184 -248.069153) (xy 313.730569 -248.08355) (xy 313.738348 -248.102357) (xy 313.738768 -248.112534)
			(xy 313.738768 -248.521474) (xy 410.102304 -248.521474) (xy 410.102304 -248.112534) (xy 410.102861 -248.102383)
			(xy 410.110617 -248.083621) (xy 410.124964 -248.069256) (xy 410.143715 -248.061474) (xy 410.153866 -248.060972)
			(xy 411.553406 -248.060972) (xy 411.563582 -248.06136) (xy 411.582384 -248.069153) (xy 411.596769 -248.08355)
			(xy 411.604548 -248.102357) (xy 411.604968 -248.112534) (xy 411.604968 -248.521474) (xy 417.646104 -248.521474)
			(xy 417.646104 -248.112534) (xy 417.646661 -248.102383) (xy 417.654417 -248.083621) (xy 417.668764 -248.069256)
			(xy 417.687515 -248.061474) (xy 417.697666 -248.060972) (xy 419.097206 -248.060972) (xy 419.107382 -248.06136)
			(xy 419.126184 -248.069153) (xy 419.140569 -248.08355) (xy 419.148348 -248.102357) (xy 419.148768 -248.112534)
			(xy 419.148768 -248.521474) (xy 425.189904 -248.521474) (xy 425.189904 -248.112534) (xy 425.190461 -248.102383)
			(xy 425.198217 -248.083621) (xy 425.212564 -248.069256) (xy 425.231315 -248.061474) (xy 425.241466 -248.060972)
			(xy 426.641006 -248.060972) (xy 426.651182 -248.06136) (xy 426.669984 -248.069153) (xy 426.684369 -248.08355)
			(xy 426.692148 -248.102357) (xy 426.692568 -248.112534) (xy 426.692568 -248.521474) (xy 432.733704 -248.521474)
			(xy 432.733704 -248.112534) (xy 432.734261 -248.102383) (xy 432.742017 -248.083621) (xy 432.756364 -248.069256)
			(xy 432.775115 -248.061474) (xy 432.785266 -248.060972) (xy 434.184806 -248.060972) (xy 434.194982 -248.06136)
			(xy 434.213784 -248.069153) (xy 434.228169 -248.08355) (xy 434.235948 -248.102357) (xy 434.236368 -248.112534)
			(xy 434.236368 -248.521474) (xy 440.277504 -248.521474) (xy 440.277504 -248.112534) (xy 440.278061 -248.102383)
			(xy 440.285817 -248.083621) (xy 440.300164 -248.069256) (xy 440.318915 -248.061474) (xy 440.329066 -248.060972)
			(xy 441.728606 -248.060972) (xy 441.738782 -248.06136) (xy 441.757584 -248.069153) (xy 441.771969 -248.08355)
			(xy 441.779748 -248.102357) (xy 441.780168 -248.112534) (xy 441.780168 -248.521474) (xy 447.821304 -248.521474)
			(xy 447.821304 -248.112534) (xy 447.821861 -248.102383) (xy 447.829617 -248.083621) (xy 447.843964 -248.069256)
			(xy 447.862715 -248.061474) (xy 447.872866 -248.060972) (xy 449.272406 -248.060972) (xy 449.282582 -248.06136)
			(xy 449.301384 -248.069153) (xy 449.315769 -248.08355) (xy 449.323548 -248.102357) (xy 449.323968 -248.112534)
			(xy 449.323968 -248.521474) (xy 455.365104 -248.521474) (xy 455.365104 -248.112534) (xy 455.365661 -248.102383)
			(xy 455.373417 -248.083621) (xy 455.387764 -248.069256) (xy 455.406515 -248.061474) (xy 455.416666 -248.060972)
			(xy 456.816206 -248.060972) (xy 456.826382 -248.06136) (xy 456.845184 -248.069153) (xy 456.859569 -248.08355)
			(xy 456.867348 -248.102357) (xy 456.867768 -248.112534) (xy 456.867768 -248.521474) (xy 462.908904 -248.521474)
			(xy 462.908904 -248.112534) (xy 462.909461 -248.102383) (xy 462.917217 -248.083621) (xy 462.931564 -248.069256)
			(xy 462.950315 -248.061474) (xy 462.960466 -248.060972) (xy 464.360006 -248.060972) (xy 464.370182 -248.06136)
			(xy 464.388984 -248.069153) (xy 464.403369 -248.08355) (xy 464.411148 -248.102357) (xy 464.411568 -248.112534)
			(xy 464.411568 -248.521474) (xy 464.411115 -248.531643) (xy 464.40334 -248.550436) (xy 464.388963 -248.564822)
			(xy 464.370175 -248.572609) (xy 464.360006 -248.573036) (xy 462.960466 -248.573036) (xy 462.950303 -248.572594)
			(xy 462.931528 -248.564803) (xy 462.917163 -248.550422) (xy 462.909394 -248.531638) (xy 462.908904 -248.521474)
			(xy 456.867768 -248.521474) (xy 456.867315 -248.531643) (xy 456.85954 -248.550436) (xy 456.845163 -248.564822)
			(xy 456.826375 -248.572609) (xy 456.816206 -248.573036) (xy 455.416666 -248.573036) (xy 455.406503 -248.572594)
			(xy 455.387728 -248.564803) (xy 455.373363 -248.550422) (xy 455.365594 -248.531638) (xy 455.365104 -248.521474)
			(xy 449.323968 -248.521474) (xy 449.323515 -248.531643) (xy 449.31574 -248.550436) (xy 449.301363 -248.564822)
			(xy 449.282575 -248.572609) (xy 449.272406 -248.573036) (xy 447.872866 -248.573036) (xy 447.862703 -248.572594)
			(xy 447.843928 -248.564803) (xy 447.829563 -248.550422) (xy 447.821794 -248.531638) (xy 447.821304 -248.521474)
			(xy 441.780168 -248.521474) (xy 441.779715 -248.531643) (xy 441.77194 -248.550436) (xy 441.757563 -248.564822)
			(xy 441.738775 -248.572609) (xy 441.728606 -248.573036) (xy 440.329066 -248.573036) (xy 440.318903 -248.572594)
			(xy 440.300128 -248.564803) (xy 440.285763 -248.550422) (xy 440.277994 -248.531638) (xy 440.277504 -248.521474)
			(xy 434.236368 -248.521474) (xy 434.235915 -248.531643) (xy 434.22814 -248.550436) (xy 434.213763 -248.564822)
			(xy 434.194975 -248.572609) (xy 434.184806 -248.573036) (xy 432.785266 -248.573036) (xy 432.775103 -248.572594)
			(xy 432.756328 -248.564803) (xy 432.741963 -248.550422) (xy 432.734194 -248.531638) (xy 432.733704 -248.521474)
			(xy 426.692568 -248.521474) (xy 426.692115 -248.531643) (xy 426.68434 -248.550436) (xy 426.669963 -248.564822)
			(xy 426.651175 -248.572609) (xy 426.641006 -248.573036) (xy 425.241466 -248.573036) (xy 425.231303 -248.572594)
			(xy 425.212528 -248.564803) (xy 425.198163 -248.550422) (xy 425.190394 -248.531638) (xy 425.189904 -248.521474)
			(xy 419.148768 -248.521474) (xy 419.148315 -248.531643) (xy 419.14054 -248.550436) (xy 419.126163 -248.564822)
			(xy 419.107375 -248.572609) (xy 419.097206 -248.573036) (xy 417.697666 -248.573036) (xy 417.687503 -248.572594)
			(xy 417.668728 -248.564803) (xy 417.654363 -248.550422) (xy 417.646594 -248.531638) (xy 417.646104 -248.521474)
			(xy 411.604968 -248.521474) (xy 411.604515 -248.531643) (xy 411.59674 -248.550436) (xy 411.582363 -248.564822)
			(xy 411.563575 -248.572609) (xy 411.553406 -248.573036) (xy 410.153866 -248.573036) (xy 410.143703 -248.572594)
			(xy 410.124928 -248.564803) (xy 410.110563 -248.550422) (xy 410.102794 -248.531638) (xy 410.102304 -248.521474)
			(xy 313.738768 -248.521474) (xy 313.738315 -248.531643) (xy 313.73054 -248.550436) (xy 313.716163 -248.564822)
			(xy 313.697375 -248.572609) (xy 313.687206 -248.573036) (xy 312.287666 -248.573036) (xy 312.277503 -248.572594)
			(xy 312.258728 -248.564803) (xy 312.244363 -248.550422) (xy 312.236594 -248.531638) (xy 312.236104 -248.521474)
			(xy 306.194968 -248.521474) (xy 306.194515 -248.531643) (xy 306.18674 -248.550436) (xy 306.172363 -248.564822)
			(xy 306.153575 -248.572609) (xy 306.143406 -248.573036) (xy 304.743866 -248.573036) (xy 304.733703 -248.572594)
			(xy 304.714928 -248.564803) (xy 304.700563 -248.550422) (xy 304.692794 -248.531638) (xy 304.692304 -248.521474)
			(xy 298.651168 -248.521474) (xy 298.650715 -248.531643) (xy 298.64294 -248.550436) (xy 298.628563 -248.564822)
			(xy 298.609775 -248.572609) (xy 298.599606 -248.573036) (xy 297.200066 -248.573036) (xy 297.189903 -248.572594)
			(xy 297.171128 -248.564803) (xy 297.156763 -248.550422) (xy 297.148994 -248.531638) (xy 297.148504 -248.521474)
			(xy 291.107368 -248.521474) (xy 291.106915 -248.531643) (xy 291.09914 -248.550436) (xy 291.084763 -248.564822)
			(xy 291.065975 -248.572609) (xy 291.055806 -248.573036) (xy 289.656266 -248.573036) (xy 289.646103 -248.572594)
			(xy 289.627328 -248.564803) (xy 289.612963 -248.550422) (xy 289.605194 -248.531638) (xy 289.604704 -248.521474)
			(xy 283.563568 -248.521474) (xy 283.563115 -248.531643) (xy 283.55534 -248.550436) (xy 283.540963 -248.564822)
			(xy 283.522175 -248.572609) (xy 283.512006 -248.573036) (xy 282.112466 -248.573036) (xy 282.102303 -248.572594)
			(xy 282.083528 -248.564803) (xy 282.069163 -248.550422) (xy 282.061394 -248.531638) (xy 282.060904 -248.521474)
			(xy 276.019768 -248.521474) (xy 276.019315 -248.531643) (xy 276.01154 -248.550436) (xy 275.997163 -248.564822)
			(xy 275.978375 -248.572609) (xy 275.968206 -248.573036) (xy 274.568666 -248.573036) (xy 274.558503 -248.572594)
			(xy 274.539728 -248.564803) (xy 274.525363 -248.550422) (xy 274.517594 -248.531638) (xy 274.517104 -248.521474)
			(xy 268.475968 -248.521474) (xy 268.475515 -248.531643) (xy 268.46774 -248.550436) (xy 268.453363 -248.564822)
			(xy 268.434575 -248.572609) (xy 268.424406 -248.573036) (xy 267.024866 -248.573036) (xy 267.014703 -248.572594)
			(xy 266.995928 -248.564803) (xy 266.981563 -248.550422) (xy 266.973794 -248.531638) (xy 266.973304 -248.521474)
			(xy 260.932168 -248.521474) (xy 260.931715 -248.531643) (xy 260.92394 -248.550436) (xy 260.909563 -248.564822)
			(xy 260.890775 -248.572609) (xy 260.880606 -248.573036) (xy 259.481066 -248.573036) (xy 259.470903 -248.572594)
			(xy 259.452128 -248.564803) (xy 259.437763 -248.550422) (xy 259.429994 -248.531638) (xy 259.429504 -248.521474)
			(xy 216.4715 -248.521474) (xy 216.470946 -248.531625) (xy 216.463188 -248.550387) (xy 216.448841 -248.564752)
			(xy 216.430089 -248.572534) (xy 216.419938 -248.573036) (xy 215.020398 -248.573036) (xy 215.010223 -248.572637)
			(xy 214.991423 -248.564847) (xy 214.977038 -248.550453) (xy 214.969257 -248.531649) (xy 214.968836 -248.521474)
			(xy 208.9277 -248.521474) (xy 208.927146 -248.531625) (xy 208.919388 -248.550387) (xy 208.905041 -248.564752)
			(xy 208.886289 -248.572534) (xy 208.876138 -248.573036) (xy 207.476598 -248.573036) (xy 207.466423 -248.572637)
			(xy 207.447623 -248.564847) (xy 207.433238 -248.550453) (xy 207.425457 -248.531649) (xy 207.425036 -248.521474)
			(xy 201.3839 -248.521474) (xy 201.383346 -248.531625) (xy 201.375588 -248.550387) (xy 201.361241 -248.564752)
			(xy 201.342489 -248.572534) (xy 201.332338 -248.573036) (xy 199.932798 -248.573036) (xy 199.922623 -248.572637)
			(xy 199.903823 -248.564847) (xy 199.889438 -248.550453) (xy 199.881657 -248.531649) (xy 199.881236 -248.521474)
			(xy 193.8401 -248.521474) (xy 193.839546 -248.531625) (xy 193.831788 -248.550387) (xy 193.817441 -248.564752)
			(xy 193.798689 -248.572534) (xy 193.788538 -248.573036) (xy 192.388998 -248.573036) (xy 192.378823 -248.572637)
			(xy 192.360023 -248.564847) (xy 192.345638 -248.550453) (xy 192.337857 -248.531649) (xy 192.337436 -248.521474)
			(xy 186.2963 -248.521474) (xy 186.295746 -248.531625) (xy 186.287988 -248.550387) (xy 186.273641 -248.564752)
			(xy 186.254889 -248.572534) (xy 186.244738 -248.573036) (xy 184.845198 -248.573036) (xy 184.835023 -248.572637)
			(xy 184.816223 -248.564847) (xy 184.801838 -248.550453) (xy 184.794057 -248.531649) (xy 184.793636 -248.521474)
			(xy 178.7525 -248.521474) (xy 178.751946 -248.531625) (xy 178.744188 -248.550387) (xy 178.729841 -248.564752)
			(xy 178.711089 -248.572534) (xy 178.700938 -248.573036) (xy 177.301398 -248.573036) (xy 177.291223 -248.572637)
			(xy 177.272423 -248.564847) (xy 177.258038 -248.550453) (xy 177.250257 -248.531649) (xy 177.249836 -248.521474)
			(xy 171.2087 -248.521474) (xy 171.208146 -248.531625) (xy 171.200388 -248.550387) (xy 171.186041 -248.564752)
			(xy 171.167289 -248.572534) (xy 171.157138 -248.573036) (xy 169.757598 -248.573036) (xy 169.747423 -248.572637)
			(xy 169.728623 -248.564847) (xy 169.714238 -248.550453) (xy 169.706457 -248.531649) (xy 169.706036 -248.521474)
			(xy 163.6649 -248.521474) (xy 163.664346 -248.531625) (xy 163.656588 -248.550387) (xy 163.642241 -248.564752)
			(xy 163.623489 -248.572534) (xy 163.613338 -248.573036) (xy 162.213798 -248.573036) (xy 162.203623 -248.572637)
			(xy 162.184823 -248.564847) (xy 162.170438 -248.550453) (xy 162.162657 -248.531649) (xy 162.162236 -248.521474)
			(xy 65.7987 -248.521474) (xy 65.798146 -248.531625) (xy 65.790388 -248.550387) (xy 65.776041 -248.564752)
			(xy 65.757289 -248.572534) (xy 65.747138 -248.573036) (xy 64.347598 -248.573036) (xy 64.337423 -248.572637)
			(xy 64.318623 -248.564847) (xy 64.304238 -248.550453) (xy 64.296457 -248.531649) (xy 64.296036 -248.521474)
			(xy 58.2549 -248.521474) (xy 58.254346 -248.531625) (xy 58.246588 -248.550387) (xy 58.232241 -248.564752)
			(xy 58.213489 -248.572534) (xy 58.203338 -248.573036) (xy 56.803798 -248.573036) (xy 56.793623 -248.572637)
			(xy 56.774823 -248.564847) (xy 56.760438 -248.550453) (xy 56.752657 -248.531649) (xy 56.752236 -248.521474)
			(xy 50.7111 -248.521474) (xy 50.710546 -248.531625) (xy 50.702788 -248.550387) (xy 50.688441 -248.564752)
			(xy 50.669689 -248.572534) (xy 50.659538 -248.573036) (xy 49.259998 -248.573036) (xy 49.249823 -248.572637)
			(xy 49.231023 -248.564847) (xy 49.216638 -248.550453) (xy 49.208857 -248.531649) (xy 49.208436 -248.521474)
			(xy 43.1673 -248.521474) (xy 43.166746 -248.531625) (xy 43.158988 -248.550387) (xy 43.144641 -248.564752)
			(xy 43.125889 -248.572534) (xy 43.115738 -248.573036) (xy 41.716198 -248.573036) (xy 41.706023 -248.572637)
			(xy 41.687223 -248.564847) (xy 41.672838 -248.550453) (xy 41.665057 -248.531649) (xy 41.664636 -248.521474)
			(xy 35.6235 -248.521474) (xy 35.622946 -248.531625) (xy 35.615188 -248.550387) (xy 35.600841 -248.564752)
			(xy 35.582089 -248.572534) (xy 35.571938 -248.573036) (xy 34.172398 -248.573036) (xy 34.162223 -248.572637)
			(xy 34.143423 -248.564847) (xy 34.129038 -248.550453) (xy 34.121257 -248.531649) (xy 34.120836 -248.521474)
			(xy 28.0797 -248.521474) (xy 28.079146 -248.531625) (xy 28.071388 -248.550387) (xy 28.057041 -248.564752)
			(xy 28.038289 -248.572534) (xy 28.028138 -248.573036) (xy 26.628598 -248.573036) (xy 26.618423 -248.572637)
			(xy 26.599623 -248.564847) (xy 26.585238 -248.550453) (xy 26.577457 -248.531649) (xy 26.577036 -248.521474)
			(xy 20.5359 -248.521474) (xy 20.535346 -248.531625) (xy 20.527588 -248.550387) (xy 20.513241 -248.564752)
			(xy 20.494489 -248.572534) (xy 20.484338 -248.573036) (xy 19.084798 -248.573036) (xy 19.074623 -248.572637)
			(xy 19.055823 -248.564847) (xy 19.041438 -248.550453) (xy 19.033657 -248.531649) (xy 19.033236 -248.521474)
			(xy 12.9921 -248.521474) (xy 12.991546 -248.531625) (xy 12.983788 -248.550387) (xy 12.969441 -248.564752)
			(xy 12.950689 -248.572534) (xy 12.940538 -248.573036) (xy 11.540998 -248.573036) (xy 11.530823 -248.572637)
			(xy 11.512023 -248.564847) (xy 11.497638 -248.550453) (xy 11.489857 -248.531649) (xy 11.489436 -248.521474)
			(xy 2.509012 -248.521474) (xy 2.509012 -249.371358) (xy 7.389368 -249.371358) (xy 7.389368 -248.962418)
			(xy 7.389779 -248.952244) (xy 7.397564 -248.933444) (xy 7.411954 -248.919057) (xy 7.430756 -248.911277)
			(xy 7.44093 -248.910856) (xy 8.84047 -248.910856) (xy 8.850642 -248.911289) (xy 8.869439 -248.919067)
			(xy 8.883826 -248.933451) (xy 8.891609 -248.952246) (xy 8.892032 -248.962418) (xy 8.892032 -249.371358)
			(xy 14.933168 -249.371358) (xy 14.933168 -248.962418) (xy 14.933579 -248.952244) (xy 14.941364 -248.933444)
			(xy 14.955754 -248.919057) (xy 14.974556 -248.911277) (xy 14.98473 -248.910856) (xy 16.38427 -248.910856)
			(xy 16.394442 -248.911289) (xy 16.413239 -248.919067) (xy 16.427626 -248.933451) (xy 16.435409 -248.952246)
			(xy 16.435832 -248.962418) (xy 16.435832 -249.371358) (xy 22.476968 -249.371358) (xy 22.476968 -248.962418)
			(xy 22.477379 -248.952244) (xy 22.485164 -248.933444) (xy 22.499554 -248.919057) (xy 22.518356 -248.911277)
			(xy 22.52853 -248.910856) (xy 23.92807 -248.910856) (xy 23.938242 -248.911289) (xy 23.957039 -248.919067)
			(xy 23.971426 -248.933451) (xy 23.979209 -248.952246) (xy 23.979632 -248.962418) (xy 23.979632 -249.371358)
			(xy 30.020768 -249.371358) (xy 30.020768 -248.962418) (xy 30.021179 -248.952244) (xy 30.028964 -248.933444)
			(xy 30.043354 -248.919057) (xy 30.062156 -248.911277) (xy 30.07233 -248.910856) (xy 31.47187 -248.910856)
			(xy 31.482042 -248.911289) (xy 31.500839 -248.919067) (xy 31.515226 -248.933451) (xy 31.523009 -248.952246)
			(xy 31.523432 -248.962418) (xy 31.523432 -249.371358) (xy 37.564568 -249.371358) (xy 37.564568 -248.962418)
			(xy 37.564979 -248.952244) (xy 37.572764 -248.933444) (xy 37.587154 -248.919057) (xy 37.605956 -248.911277)
			(xy 37.61613 -248.910856) (xy 39.01567 -248.910856) (xy 39.025842 -248.911289) (xy 39.044639 -248.919067)
			(xy 39.059026 -248.933451) (xy 39.066809 -248.952246) (xy 39.067232 -248.962418) (xy 39.067232 -249.371358)
			(xy 45.108368 -249.371358) (xy 45.108368 -248.962418) (xy 45.108779 -248.952244) (xy 45.116564 -248.933444)
			(xy 45.130954 -248.919057) (xy 45.149756 -248.911277) (xy 45.15993 -248.910856) (xy 46.55947 -248.910856)
			(xy 46.569642 -248.911289) (xy 46.588439 -248.919067) (xy 46.602826 -248.933451) (xy 46.610609 -248.952246)
			(xy 46.611032 -248.962418) (xy 46.611032 -249.371358) (xy 52.652168 -249.371358) (xy 52.652168 -248.962418)
			(xy 52.652579 -248.952244) (xy 52.660364 -248.933444) (xy 52.674754 -248.919057) (xy 52.693556 -248.911277)
			(xy 52.70373 -248.910856) (xy 54.10327 -248.910856) (xy 54.113442 -248.911289) (xy 54.132239 -248.919067)
			(xy 54.146626 -248.933451) (xy 54.154409 -248.952246) (xy 54.154832 -248.962418) (xy 54.154832 -249.371358)
			(xy 60.195968 -249.371358) (xy 60.195968 -248.962418) (xy 60.196379 -248.952244) (xy 60.204164 -248.933444)
			(xy 60.218554 -248.919057) (xy 60.237356 -248.911277) (xy 60.24753 -248.910856) (xy 61.64707 -248.910856)
			(xy 61.657242 -248.911289) (xy 61.676039 -248.919067) (xy 61.690426 -248.933451) (xy 61.698209 -248.952246)
			(xy 61.698632 -248.962418) (xy 61.698632 -249.371358) (xy 158.062168 -249.371358) (xy 158.062168 -248.962418)
			(xy 158.062579 -248.952244) (xy 158.070364 -248.933444) (xy 158.084754 -248.919057) (xy 158.103556 -248.911277)
			(xy 158.11373 -248.910856) (xy 159.51327 -248.910856) (xy 159.523442 -248.911289) (xy 159.542239 -248.919067)
			(xy 159.556626 -248.933451) (xy 159.564409 -248.952246) (xy 159.564832 -248.962418) (xy 159.564832 -249.371358)
			(xy 165.605968 -249.371358) (xy 165.605968 -248.962418) (xy 165.606379 -248.952244) (xy 165.614164 -248.933444)
			(xy 165.628554 -248.919057) (xy 165.647356 -248.911277) (xy 165.65753 -248.910856) (xy 167.05707 -248.910856)
			(xy 167.067242 -248.911289) (xy 167.086039 -248.919067) (xy 167.100426 -248.933451) (xy 167.108209 -248.952246)
			(xy 167.108632 -248.962418) (xy 167.108632 -249.371358) (xy 173.149768 -249.371358) (xy 173.149768 -248.962418)
			(xy 173.150179 -248.952244) (xy 173.157964 -248.933444) (xy 173.172354 -248.919057) (xy 173.191156 -248.911277)
			(xy 173.20133 -248.910856) (xy 174.60087 -248.910856) (xy 174.611042 -248.911289) (xy 174.629839 -248.919067)
			(xy 174.644226 -248.933451) (xy 174.652009 -248.952246) (xy 174.652432 -248.962418) (xy 174.652432 -249.371358)
			(xy 180.693568 -249.371358) (xy 180.693568 -248.962418) (xy 180.693979 -248.952244) (xy 180.701764 -248.933444)
			(xy 180.716154 -248.919057) (xy 180.734956 -248.911277) (xy 180.74513 -248.910856) (xy 182.14467 -248.910856)
			(xy 182.154842 -248.911289) (xy 182.173639 -248.919067) (xy 182.188026 -248.933451) (xy 182.195809 -248.952246)
			(xy 182.196232 -248.962418) (xy 182.196232 -249.371358) (xy 188.237368 -249.371358) (xy 188.237368 -248.962418)
			(xy 188.237779 -248.952244) (xy 188.245564 -248.933444) (xy 188.259954 -248.919057) (xy 188.278756 -248.911277)
			(xy 188.28893 -248.910856) (xy 189.68847 -248.910856) (xy 189.698642 -248.911289) (xy 189.717439 -248.919067)
			(xy 189.731826 -248.933451) (xy 189.739609 -248.952246) (xy 189.740032 -248.962418) (xy 189.740032 -249.371358)
			(xy 195.781168 -249.371358) (xy 195.781168 -248.962418) (xy 195.781579 -248.952244) (xy 195.789364 -248.933444)
			(xy 195.803754 -248.919057) (xy 195.822556 -248.911277) (xy 195.83273 -248.910856) (xy 197.23227 -248.910856)
			(xy 197.242442 -248.911289) (xy 197.261239 -248.919067) (xy 197.275626 -248.933451) (xy 197.283409 -248.952246)
			(xy 197.283832 -248.962418) (xy 197.283832 -249.371358) (xy 203.324968 -249.371358) (xy 203.324968 -248.962418)
			(xy 203.325379 -248.952244) (xy 203.333164 -248.933444) (xy 203.347554 -248.919057) (xy 203.366356 -248.911277)
			(xy 203.37653 -248.910856) (xy 204.77607 -248.910856) (xy 204.786242 -248.911289) (xy 204.805039 -248.919067)
			(xy 204.819426 -248.933451) (xy 204.827209 -248.952246) (xy 204.827632 -248.962418) (xy 204.827632 -249.371358)
			(xy 210.868768 -249.371358) (xy 210.868768 -248.962418) (xy 210.869179 -248.952244) (xy 210.876964 -248.933444)
			(xy 210.891354 -248.919057) (xy 210.910156 -248.911277) (xy 210.92033 -248.910856) (xy 212.31987 -248.910856)
			(xy 212.330042 -248.911289) (xy 212.348839 -248.919067) (xy 212.363226 -248.933451) (xy 212.371009 -248.952246)
			(xy 212.371432 -248.962418) (xy 212.371432 -249.371358) (xy 255.329436 -249.371358) (xy 255.329436 -248.962418)
			(xy 255.329878 -248.952248) (xy 255.337657 -248.933454) (xy 255.352037 -248.919068) (xy 255.370828 -248.911282)
			(xy 255.380998 -248.910856) (xy 256.780538 -248.910856) (xy 256.7907 -248.911303) (xy 256.809474 -248.919093)
			(xy 256.823838 -248.933473) (xy 256.831608 -248.952255) (xy 256.8321 -248.962418) (xy 256.8321 -249.371358)
			(xy 262.873236 -249.371358) (xy 262.873236 -248.962418) (xy 262.873678 -248.952248) (xy 262.881457 -248.933454)
			(xy 262.895837 -248.919068) (xy 262.914628 -248.911282) (xy 262.924798 -248.910856) (xy 264.324338 -248.910856)
			(xy 264.3345 -248.911303) (xy 264.353274 -248.919093) (xy 264.367638 -248.933473) (xy 264.375408 -248.952255)
			(xy 264.3759 -248.962418) (xy 264.3759 -249.371358) (xy 270.417036 -249.371358) (xy 270.417036 -248.962418)
			(xy 270.417478 -248.952248) (xy 270.425257 -248.933454) (xy 270.439637 -248.919068) (xy 270.458428 -248.911282)
			(xy 270.468598 -248.910856) (xy 271.868138 -248.910856) (xy 271.8783 -248.911303) (xy 271.897074 -248.919093)
			(xy 271.911438 -248.933473) (xy 271.919208 -248.952255) (xy 271.9197 -248.962418) (xy 271.9197 -249.371358)
			(xy 277.960836 -249.371358) (xy 277.960836 -248.962418) (xy 277.961278 -248.952248) (xy 277.969057 -248.933454)
			(xy 277.983437 -248.919068) (xy 278.002228 -248.911282) (xy 278.012398 -248.910856) (xy 279.411938 -248.910856)
			(xy 279.4221 -248.911303) (xy 279.440874 -248.919093) (xy 279.455238 -248.933473) (xy 279.463008 -248.952255)
			(xy 279.4635 -248.962418) (xy 279.4635 -249.371358) (xy 285.504636 -249.371358) (xy 285.504636 -248.962418)
			(xy 285.505078 -248.952248) (xy 285.512857 -248.933454) (xy 285.527237 -248.919068) (xy 285.546028 -248.911282)
			(xy 285.556198 -248.910856) (xy 286.955738 -248.910856) (xy 286.9659 -248.911303) (xy 286.984674 -248.919093)
			(xy 286.999038 -248.933473) (xy 287.006808 -248.952255) (xy 287.0073 -248.962418) (xy 287.0073 -249.371358)
			(xy 293.048436 -249.371358) (xy 293.048436 -248.962418) (xy 293.048878 -248.952248) (xy 293.056657 -248.933454)
			(xy 293.071037 -248.919068) (xy 293.089828 -248.911282) (xy 293.099998 -248.910856) (xy 294.499538 -248.910856)
			(xy 294.5097 -248.911303) (xy 294.528474 -248.919093) (xy 294.542838 -248.933473) (xy 294.550608 -248.952255)
			(xy 294.5511 -248.962418) (xy 294.5511 -249.371358) (xy 300.592236 -249.371358) (xy 300.592236 -248.962418)
			(xy 300.592678 -248.952248) (xy 300.600457 -248.933454) (xy 300.614837 -248.919068) (xy 300.633628 -248.911282)
			(xy 300.643798 -248.910856) (xy 302.043338 -248.910856) (xy 302.0535 -248.911303) (xy 302.072274 -248.919093)
			(xy 302.086638 -248.933473) (xy 302.094408 -248.952255) (xy 302.0949 -248.962418) (xy 302.0949 -249.371358)
			(xy 308.136036 -249.371358) (xy 308.136036 -248.962418) (xy 308.136478 -248.952248) (xy 308.144257 -248.933454)
			(xy 308.158637 -248.919068) (xy 308.177428 -248.911282) (xy 308.187598 -248.910856) (xy 309.587138 -248.910856)
			(xy 309.5973 -248.911303) (xy 309.616074 -248.919093) (xy 309.630438 -248.933473) (xy 309.638208 -248.952255)
			(xy 309.6387 -248.962418) (xy 309.6387 -249.371358) (xy 406.002236 -249.371358) (xy 406.002236 -248.962418)
			(xy 406.002678 -248.952248) (xy 406.010457 -248.933454) (xy 406.024837 -248.919068) (xy 406.043628 -248.911282)
			(xy 406.053798 -248.910856) (xy 407.453338 -248.910856) (xy 407.4635 -248.911303) (xy 407.482274 -248.919093)
			(xy 407.496638 -248.933473) (xy 407.504408 -248.952255) (xy 407.5049 -248.962418) (xy 407.5049 -249.371358)
			(xy 413.546036 -249.371358) (xy 413.546036 -248.962418) (xy 413.546478 -248.952248) (xy 413.554257 -248.933454)
			(xy 413.568637 -248.919068) (xy 413.587428 -248.911282) (xy 413.597598 -248.910856) (xy 414.997138 -248.910856)
			(xy 415.0073 -248.911303) (xy 415.026074 -248.919093) (xy 415.040438 -248.933473) (xy 415.048208 -248.952255)
			(xy 415.0487 -248.962418) (xy 415.0487 -249.371358) (xy 421.089836 -249.371358) (xy 421.089836 -248.962418)
			(xy 421.090278 -248.952248) (xy 421.098057 -248.933454) (xy 421.112437 -248.919068) (xy 421.131228 -248.911282)
			(xy 421.141398 -248.910856) (xy 422.540938 -248.910856) (xy 422.5511 -248.911303) (xy 422.569874 -248.919093)
			(xy 422.584238 -248.933473) (xy 422.592008 -248.952255) (xy 422.5925 -248.962418) (xy 422.5925 -249.371358)
			(xy 428.633636 -249.371358) (xy 428.633636 -248.962418) (xy 428.634078 -248.952248) (xy 428.641857 -248.933454)
			(xy 428.656237 -248.919068) (xy 428.675028 -248.911282) (xy 428.685198 -248.910856) (xy 430.084738 -248.910856)
			(xy 430.0949 -248.911303) (xy 430.113674 -248.919093) (xy 430.128038 -248.933473) (xy 430.135808 -248.952255)
			(xy 430.1363 -248.962418) (xy 430.1363 -249.371358) (xy 436.177436 -249.371358) (xy 436.177436 -248.962418)
			(xy 436.177878 -248.952248) (xy 436.185657 -248.933454) (xy 436.200037 -248.919068) (xy 436.218828 -248.911282)
			(xy 436.228998 -248.910856) (xy 437.628538 -248.910856) (xy 437.6387 -248.911303) (xy 437.657474 -248.919093)
			(xy 437.671838 -248.933473) (xy 437.679608 -248.952255) (xy 437.6801 -248.962418) (xy 437.6801 -249.371358)
			(xy 443.721236 -249.371358) (xy 443.721236 -248.962418) (xy 443.721678 -248.952248) (xy 443.729457 -248.933454)
			(xy 443.743837 -248.919068) (xy 443.762628 -248.911282) (xy 443.772798 -248.910856) (xy 445.172338 -248.910856)
			(xy 445.1825 -248.911303) (xy 445.201274 -248.919093) (xy 445.215638 -248.933473) (xy 445.223408 -248.952255)
			(xy 445.2239 -248.962418) (xy 445.2239 -249.371358) (xy 451.265036 -249.371358) (xy 451.265036 -248.962418)
			(xy 451.265478 -248.952248) (xy 451.273257 -248.933454) (xy 451.287637 -248.919068) (xy 451.306428 -248.911282)
			(xy 451.316598 -248.910856) (xy 452.716138 -248.910856) (xy 452.7263 -248.911303) (xy 452.745074 -248.919093)
			(xy 452.759438 -248.933473) (xy 452.767208 -248.952255) (xy 452.7677 -248.962418) (xy 452.7677 -249.371358)
			(xy 458.808836 -249.371358) (xy 458.808836 -248.962418) (xy 458.809278 -248.952248) (xy 458.817057 -248.933454)
			(xy 458.831437 -248.919068) (xy 458.850228 -248.911282) (xy 458.860398 -248.910856) (xy 460.259938 -248.910856)
			(xy 460.2701 -248.911303) (xy 460.288874 -248.919093) (xy 460.303238 -248.933473) (xy 460.311008 -248.952255)
			(xy 460.3115 -248.962418) (xy 460.3115 -249.371358) (xy 460.311003 -249.381522) (xy 460.303239 -249.400309)
			(xy 460.288876 -249.414694) (xy 460.270102 -249.422487) (xy 460.259938 -249.42292) (xy 458.860398 -249.42292)
			(xy 458.850221 -249.422537) (xy 458.831418 -249.414743) (xy 458.817032 -249.400345) (xy 458.809255 -249.381535)
			(xy 458.808836 -249.371358) (xy 452.7677 -249.371358) (xy 452.767203 -249.381522) (xy 452.759439 -249.400309)
			(xy 452.745076 -249.414694) (xy 452.726302 -249.422487) (xy 452.716138 -249.42292) (xy 451.316598 -249.42292)
			(xy 451.306421 -249.422537) (xy 451.287618 -249.414743) (xy 451.273232 -249.400345) (xy 451.265455 -249.381535)
			(xy 451.265036 -249.371358) (xy 445.2239 -249.371358) (xy 445.223403 -249.381522) (xy 445.215639 -249.400309)
			(xy 445.201276 -249.414694) (xy 445.182502 -249.422487) (xy 445.172338 -249.42292) (xy 443.772798 -249.42292)
			(xy 443.762621 -249.422537) (xy 443.743818 -249.414743) (xy 443.729432 -249.400345) (xy 443.721655 -249.381535)
			(xy 443.721236 -249.371358) (xy 437.6801 -249.371358) (xy 437.679603 -249.381522) (xy 437.671839 -249.400309)
			(xy 437.657476 -249.414694) (xy 437.638702 -249.422487) (xy 437.628538 -249.42292) (xy 436.228998 -249.42292)
			(xy 436.218821 -249.422537) (xy 436.200018 -249.414743) (xy 436.185632 -249.400345) (xy 436.177855 -249.381535)
			(xy 436.177436 -249.371358) (xy 430.1363 -249.371358) (xy 430.135803 -249.381522) (xy 430.128039 -249.400309)
			(xy 430.113676 -249.414694) (xy 430.094902 -249.422487) (xy 430.084738 -249.42292) (xy 428.685198 -249.42292)
			(xy 428.675021 -249.422537) (xy 428.656218 -249.414743) (xy 428.641832 -249.400345) (xy 428.634055 -249.381535)
			(xy 428.633636 -249.371358) (xy 422.5925 -249.371358) (xy 422.592003 -249.381522) (xy 422.584239 -249.400309)
			(xy 422.569876 -249.414694) (xy 422.551102 -249.422487) (xy 422.540938 -249.42292) (xy 421.141398 -249.42292)
			(xy 421.131221 -249.422537) (xy 421.112418 -249.414743) (xy 421.098032 -249.400345) (xy 421.090255 -249.381535)
			(xy 421.089836 -249.371358) (xy 415.0487 -249.371358) (xy 415.048203 -249.381522) (xy 415.040439 -249.400309)
			(xy 415.026076 -249.414694) (xy 415.007302 -249.422487) (xy 414.997138 -249.42292) (xy 413.597598 -249.42292)
			(xy 413.587421 -249.422537) (xy 413.568618 -249.414743) (xy 413.554232 -249.400345) (xy 413.546455 -249.381535)
			(xy 413.546036 -249.371358) (xy 407.5049 -249.371358) (xy 407.504403 -249.381522) (xy 407.496639 -249.400309)
			(xy 407.482276 -249.414694) (xy 407.463502 -249.422487) (xy 407.453338 -249.42292) (xy 406.053798 -249.42292)
			(xy 406.043621 -249.422537) (xy 406.024818 -249.414743) (xy 406.010432 -249.400345) (xy 406.002655 -249.381535)
			(xy 406.002236 -249.371358) (xy 309.6387 -249.371358) (xy 309.638203 -249.381522) (xy 309.630439 -249.400309)
			(xy 309.616076 -249.414694) (xy 309.597302 -249.422487) (xy 309.587138 -249.42292) (xy 308.187598 -249.42292)
			(xy 308.177421 -249.422537) (xy 308.158618 -249.414743) (xy 308.144232 -249.400345) (xy 308.136455 -249.381535)
			(xy 308.136036 -249.371358) (xy 302.0949 -249.371358) (xy 302.094403 -249.381522) (xy 302.086639 -249.400309)
			(xy 302.072276 -249.414694) (xy 302.053502 -249.422487) (xy 302.043338 -249.42292) (xy 300.643798 -249.42292)
			(xy 300.633621 -249.422537) (xy 300.614818 -249.414743) (xy 300.600432 -249.400345) (xy 300.592655 -249.381535)
			(xy 300.592236 -249.371358) (xy 294.5511 -249.371358) (xy 294.550603 -249.381522) (xy 294.542839 -249.400309)
			(xy 294.528476 -249.414694) (xy 294.509702 -249.422487) (xy 294.499538 -249.42292) (xy 293.099998 -249.42292)
			(xy 293.089821 -249.422537) (xy 293.071018 -249.414743) (xy 293.056632 -249.400345) (xy 293.048855 -249.381535)
			(xy 293.048436 -249.371358) (xy 287.0073 -249.371358) (xy 287.006803 -249.381522) (xy 286.999039 -249.400309)
			(xy 286.984676 -249.414694) (xy 286.965902 -249.422487) (xy 286.955738 -249.42292) (xy 285.556198 -249.42292)
			(xy 285.546021 -249.422537) (xy 285.527218 -249.414743) (xy 285.512832 -249.400345) (xy 285.505055 -249.381535)
			(xy 285.504636 -249.371358) (xy 279.4635 -249.371358) (xy 279.463003 -249.381522) (xy 279.455239 -249.400309)
			(xy 279.440876 -249.414694) (xy 279.422102 -249.422487) (xy 279.411938 -249.42292) (xy 278.012398 -249.42292)
			(xy 278.002221 -249.422537) (xy 277.983418 -249.414743) (xy 277.969032 -249.400345) (xy 277.961255 -249.381535)
			(xy 277.960836 -249.371358) (xy 271.9197 -249.371358) (xy 271.919203 -249.381522) (xy 271.911439 -249.400309)
			(xy 271.897076 -249.414694) (xy 271.878302 -249.422487) (xy 271.868138 -249.42292) (xy 270.468598 -249.42292)
			(xy 270.458421 -249.422537) (xy 270.439618 -249.414743) (xy 270.425232 -249.400345) (xy 270.417455 -249.381535)
			(xy 270.417036 -249.371358) (xy 264.3759 -249.371358) (xy 264.375403 -249.381522) (xy 264.367639 -249.400309)
			(xy 264.353276 -249.414694) (xy 264.334502 -249.422487) (xy 264.324338 -249.42292) (xy 262.924798 -249.42292)
			(xy 262.914621 -249.422537) (xy 262.895818 -249.414743) (xy 262.881432 -249.400345) (xy 262.873655 -249.381535)
			(xy 262.873236 -249.371358) (xy 256.8321 -249.371358) (xy 256.831603 -249.381522) (xy 256.823839 -249.400309)
			(xy 256.809476 -249.414694) (xy 256.790702 -249.422487) (xy 256.780538 -249.42292) (xy 255.380998 -249.42292)
			(xy 255.370821 -249.422537) (xy 255.352018 -249.414743) (xy 255.337632 -249.400345) (xy 255.329855 -249.381535)
			(xy 255.329436 -249.371358) (xy 212.371432 -249.371358) (xy 212.371001 -249.381531) (xy 212.363224 -249.40033)
			(xy 212.34884 -249.414718) (xy 212.330043 -249.422499) (xy 212.31987 -249.42292) (xy 210.92033 -249.42292)
			(xy 210.910155 -249.42251) (xy 210.891353 -249.414728) (xy 210.876966 -249.400337) (xy 210.869187 -249.381533)
			(xy 210.868768 -249.371358) (xy 204.827632 -249.371358) (xy 204.827201 -249.381531) (xy 204.819424 -249.40033)
			(xy 204.80504 -249.414718) (xy 204.786243 -249.422499) (xy 204.77607 -249.42292) (xy 203.37653 -249.42292)
			(xy 203.366355 -249.42251) (xy 203.347553 -249.414728) (xy 203.333166 -249.400337) (xy 203.325387 -249.381533)
			(xy 203.324968 -249.371358) (xy 197.283832 -249.371358) (xy 197.283401 -249.381531) (xy 197.275624 -249.40033)
			(xy 197.26124 -249.414718) (xy 197.242443 -249.422499) (xy 197.23227 -249.42292) (xy 195.83273 -249.42292)
			(xy 195.822555 -249.42251) (xy 195.803753 -249.414728) (xy 195.789366 -249.400337) (xy 195.781587 -249.381533)
			(xy 195.781168 -249.371358) (xy 189.740032 -249.371358) (xy 189.739601 -249.381531) (xy 189.731824 -249.40033)
			(xy 189.71744 -249.414718) (xy 189.698643 -249.422499) (xy 189.68847 -249.42292) (xy 188.28893 -249.42292)
			(xy 188.278755 -249.42251) (xy 188.259953 -249.414728) (xy 188.245566 -249.400337) (xy 188.237787 -249.381533)
			(xy 188.237368 -249.371358) (xy 182.196232 -249.371358) (xy 182.195801 -249.381531) (xy 182.188024 -249.40033)
			(xy 182.17364 -249.414718) (xy 182.154843 -249.422499) (xy 182.14467 -249.42292) (xy 180.74513 -249.42292)
			(xy 180.734955 -249.42251) (xy 180.716153 -249.414728) (xy 180.701766 -249.400337) (xy 180.693987 -249.381533)
			(xy 180.693568 -249.371358) (xy 174.652432 -249.371358) (xy 174.652001 -249.381531) (xy 174.644224 -249.40033)
			(xy 174.62984 -249.414718) (xy 174.611043 -249.422499) (xy 174.60087 -249.42292) (xy 173.20133 -249.42292)
			(xy 173.191155 -249.42251) (xy 173.172353 -249.414728) (xy 173.157966 -249.400337) (xy 173.150187 -249.381533)
			(xy 173.149768 -249.371358) (xy 167.108632 -249.371358) (xy 167.108201 -249.381531) (xy 167.100424 -249.40033)
			(xy 167.08604 -249.414718) (xy 167.067243 -249.422499) (xy 167.05707 -249.42292) (xy 165.65753 -249.42292)
			(xy 165.647355 -249.42251) (xy 165.628553 -249.414728) (xy 165.614166 -249.400337) (xy 165.606387 -249.381533)
			(xy 165.605968 -249.371358) (xy 159.564832 -249.371358) (xy 159.564401 -249.381531) (xy 159.556624 -249.40033)
			(xy 159.54224 -249.414718) (xy 159.523443 -249.422499) (xy 159.51327 -249.42292) (xy 158.11373 -249.42292)
			(xy 158.103555 -249.42251) (xy 158.084753 -249.414728) (xy 158.070366 -249.400337) (xy 158.062587 -249.381533)
			(xy 158.062168 -249.371358) (xy 61.698632 -249.371358) (xy 61.698201 -249.381531) (xy 61.690424 -249.40033)
			(xy 61.67604 -249.414718) (xy 61.657243 -249.422499) (xy 61.64707 -249.42292) (xy 60.24753 -249.42292)
			(xy 60.237355 -249.42251) (xy 60.218553 -249.414728) (xy 60.204166 -249.400337) (xy 60.196387 -249.381533)
			(xy 60.195968 -249.371358) (xy 54.154832 -249.371358) (xy 54.154401 -249.381531) (xy 54.146624 -249.40033)
			(xy 54.13224 -249.414718) (xy 54.113443 -249.422499) (xy 54.10327 -249.42292) (xy 52.70373 -249.42292)
			(xy 52.693555 -249.42251) (xy 52.674753 -249.414728) (xy 52.660366 -249.400337) (xy 52.652587 -249.381533)
			(xy 52.652168 -249.371358) (xy 46.611032 -249.371358) (xy 46.610601 -249.381531) (xy 46.602824 -249.40033)
			(xy 46.58844 -249.414718) (xy 46.569643 -249.422499) (xy 46.55947 -249.42292) (xy 45.15993 -249.42292)
			(xy 45.149755 -249.42251) (xy 45.130953 -249.414728) (xy 45.116566 -249.400337) (xy 45.108787 -249.381533)
			(xy 45.108368 -249.371358) (xy 39.067232 -249.371358) (xy 39.066801 -249.381531) (xy 39.059024 -249.40033)
			(xy 39.04464 -249.414718) (xy 39.025843 -249.422499) (xy 39.01567 -249.42292) (xy 37.61613 -249.42292)
			(xy 37.605955 -249.42251) (xy 37.587153 -249.414728) (xy 37.572766 -249.400337) (xy 37.564987 -249.381533)
			(xy 37.564568 -249.371358) (xy 31.523432 -249.371358) (xy 31.523001 -249.381531) (xy 31.515224 -249.40033)
			(xy 31.50084 -249.414718) (xy 31.482043 -249.422499) (xy 31.47187 -249.42292) (xy 30.07233 -249.42292)
			(xy 30.062155 -249.42251) (xy 30.043353 -249.414728) (xy 30.028966 -249.400337) (xy 30.021187 -249.381533)
			(xy 30.020768 -249.371358) (xy 23.979632 -249.371358) (xy 23.979201 -249.381531) (xy 23.971424 -249.40033)
			(xy 23.95704 -249.414718) (xy 23.938243 -249.422499) (xy 23.92807 -249.42292) (xy 22.52853 -249.42292)
			(xy 22.518355 -249.42251) (xy 22.499553 -249.414728) (xy 22.485166 -249.400337) (xy 22.477387 -249.381533)
			(xy 22.476968 -249.371358) (xy 16.435832 -249.371358) (xy 16.435401 -249.381531) (xy 16.427624 -249.40033)
			(xy 16.41324 -249.414718) (xy 16.394443 -249.422499) (xy 16.38427 -249.42292) (xy 14.98473 -249.42292)
			(xy 14.974555 -249.42251) (xy 14.955753 -249.414728) (xy 14.941366 -249.400337) (xy 14.933587 -249.381533)
			(xy 14.933168 -249.371358) (xy 8.892032 -249.371358) (xy 8.891601 -249.381531) (xy 8.883824 -249.40033)
			(xy 8.86944 -249.414718) (xy 8.850643 -249.422499) (xy 8.84047 -249.42292) (xy 7.44093 -249.42292)
			(xy 7.430755 -249.42251) (xy 7.411953 -249.414728) (xy 7.397566 -249.400337) (xy 7.389787 -249.381533)
			(xy 7.389368 -249.371358) (xy 2.509012 -249.371358) (xy 2.509012 -250.221496) (xy 11.489436 -250.221496)
			(xy 11.489436 -249.812556) (xy 11.489786 -249.802394) (xy 11.497603 -249.783634) (xy 11.512022 -249.769311)
			(xy 11.530834 -249.76162) (xy 11.540998 -249.761248) (xy 12.940538 -249.761248) (xy 12.950668 -249.761696)
			(xy 12.969392 -249.769437) (xy 12.983747 -249.783735) (xy 12.991563 -249.802428) (xy 12.9921 -249.812556)
			(xy 12.9921 -250.221496) (xy 19.033236 -250.221496) (xy 19.033236 -249.812556) (xy 19.033586 -249.802394)
			(xy 19.041403 -249.783634) (xy 19.055822 -249.769311) (xy 19.074634 -249.76162) (xy 19.084798 -249.761248)
			(xy 20.484338 -249.761248) (xy 20.494468 -249.761696) (xy 20.513192 -249.769437) (xy 20.527547 -249.783735)
			(xy 20.535363 -249.802428) (xy 20.5359 -249.812556) (xy 20.5359 -250.221496) (xy 26.577036 -250.221496)
			(xy 26.577036 -249.812556) (xy 26.577386 -249.802394) (xy 26.585203 -249.783634) (xy 26.599622 -249.769311)
			(xy 26.618434 -249.76162) (xy 26.628598 -249.761248) (xy 28.028138 -249.761248) (xy 28.038268 -249.761696)
			(xy 28.056992 -249.769437) (xy 28.071347 -249.783735) (xy 28.079163 -249.802428) (xy 28.0797 -249.812556)
			(xy 28.0797 -250.221496) (xy 34.120836 -250.221496) (xy 34.120836 -249.812556) (xy 34.121186 -249.802394)
			(xy 34.129003 -249.783634) (xy 34.143422 -249.769311) (xy 34.162234 -249.76162) (xy 34.172398 -249.761248)
			(xy 35.571938 -249.761248) (xy 35.582068 -249.761696) (xy 35.600792 -249.769437) (xy 35.615147 -249.783735)
			(xy 35.622963 -249.802428) (xy 35.6235 -249.812556) (xy 35.6235 -250.221496) (xy 41.664636 -250.221496)
			(xy 41.664636 -249.812556) (xy 41.664986 -249.802394) (xy 41.672803 -249.783634) (xy 41.687222 -249.769311)
			(xy 41.706034 -249.76162) (xy 41.716198 -249.761248) (xy 43.115738 -249.761248) (xy 43.125868 -249.761696)
			(xy 43.144592 -249.769437) (xy 43.158947 -249.783735) (xy 43.166763 -249.802428) (xy 43.1673 -249.812556)
			(xy 43.1673 -250.221496) (xy 49.208436 -250.221496) (xy 49.208436 -249.812556) (xy 49.208786 -249.802394)
			(xy 49.216603 -249.783634) (xy 49.231022 -249.769311) (xy 49.249834 -249.76162) (xy 49.259998 -249.761248)
			(xy 50.659538 -249.761248) (xy 50.669668 -249.761696) (xy 50.688392 -249.769437) (xy 50.702747 -249.783735)
			(xy 50.710563 -249.802428) (xy 50.7111 -249.812556) (xy 50.7111 -250.221496) (xy 56.752236 -250.221496)
			(xy 56.752236 -249.812556) (xy 56.752586 -249.802394) (xy 56.760403 -249.783634) (xy 56.774822 -249.769311)
			(xy 56.793634 -249.76162) (xy 56.803798 -249.761248) (xy 58.203338 -249.761248) (xy 58.213468 -249.761696)
			(xy 58.232192 -249.769437) (xy 58.246547 -249.783735) (xy 58.254363 -249.802428) (xy 58.2549 -249.812556)
			(xy 58.2549 -250.221496) (xy 64.296036 -250.221496) (xy 64.296036 -249.812556) (xy 64.296386 -249.802394)
			(xy 64.304203 -249.783634) (xy 64.318622 -249.769311) (xy 64.337434 -249.76162) (xy 64.347598 -249.761248)
			(xy 65.747138 -249.761248) (xy 65.757268 -249.761696) (xy 65.775992 -249.769437) (xy 65.790347 -249.783735)
			(xy 65.798163 -249.802428) (xy 65.7987 -249.812556) (xy 65.7987 -250.221496) (xy 65.798275 -250.23165)
			(xy 65.790481 -250.250402) (xy 65.776085 -250.264726) (xy 65.757294 -250.272425) (xy 65.747138 -250.272804)
			(xy 64.347598 -250.272804) (xy 64.337477 -250.272276) (xy 64.318764 -250.264556) (xy 64.304409 -250.250283)
			(xy 64.296582 -250.231614) (xy 64.296036 -250.221496) (xy 58.2549 -250.221496) (xy 58.254475 -250.23165)
			(xy 58.246681 -250.250402) (xy 58.232285 -250.264726) (xy 58.213494 -250.272425) (xy 58.203338 -250.272804)
			(xy 56.803798 -250.272804) (xy 56.793677 -250.272276) (xy 56.774964 -250.264556) (xy 56.760609 -250.250283)
			(xy 56.752782 -250.231614) (xy 56.752236 -250.221496) (xy 50.7111 -250.221496) (xy 50.710675 -250.23165)
			(xy 50.702881 -250.250402) (xy 50.688485 -250.264726) (xy 50.669694 -250.272425) (xy 50.659538 -250.272804)
			(xy 49.259998 -250.272804) (xy 49.249877 -250.272276) (xy 49.231164 -250.264556) (xy 49.216809 -250.250283)
			(xy 49.208982 -250.231614) (xy 49.208436 -250.221496) (xy 43.1673 -250.221496) (xy 43.166875 -250.23165)
			(xy 43.159081 -250.250402) (xy 43.144685 -250.264726) (xy 43.125894 -250.272425) (xy 43.115738 -250.272804)
			(xy 41.716198 -250.272804) (xy 41.706077 -250.272276) (xy 41.687364 -250.264556) (xy 41.673009 -250.250283)
			(xy 41.665182 -250.231614) (xy 41.664636 -250.221496) (xy 35.6235 -250.221496) (xy 35.623075 -250.23165)
			(xy 35.615281 -250.250402) (xy 35.600885 -250.264726) (xy 35.582094 -250.272425) (xy 35.571938 -250.272804)
			(xy 34.172398 -250.272804) (xy 34.162277 -250.272276) (xy 34.143564 -250.264556) (xy 34.129209 -250.250283)
			(xy 34.121382 -250.231614) (xy 34.120836 -250.221496) (xy 28.0797 -250.221496) (xy 28.079275 -250.23165)
			(xy 28.071481 -250.250402) (xy 28.057085 -250.264726) (xy 28.038294 -250.272425) (xy 28.028138 -250.272804)
			(xy 26.628598 -250.272804) (xy 26.618477 -250.272276) (xy 26.599764 -250.264556) (xy 26.585409 -250.250283)
			(xy 26.577582 -250.231614) (xy 26.577036 -250.221496) (xy 20.5359 -250.221496) (xy 20.535475 -250.23165)
			(xy 20.527681 -250.250402) (xy 20.513285 -250.264726) (xy 20.494494 -250.272425) (xy 20.484338 -250.272804)
			(xy 19.084798 -250.272804) (xy 19.074677 -250.272276) (xy 19.055964 -250.264556) (xy 19.041609 -250.250283)
			(xy 19.033782 -250.231614) (xy 19.033236 -250.221496) (xy 12.9921 -250.221496) (xy 12.991675 -250.23165)
			(xy 12.983881 -250.250402) (xy 12.969485 -250.264726) (xy 12.950694 -250.272425) (xy 12.940538 -250.272804)
			(xy 11.540998 -250.272804) (xy 11.530877 -250.272276) (xy 11.512164 -250.264556) (xy 11.497809 -250.250283)
			(xy 11.489982 -250.231614) (xy 11.489436 -250.221496) (xy 2.509012 -250.221496) (xy 2.509012 -251.07138)
			(xy 7.389368 -251.07138) (xy 7.389368 -250.66244) (xy 7.389854 -250.652292) (xy 7.39763 -250.633547)
			(xy 7.412007 -250.619224) (xy 7.430781 -250.611517) (xy 7.44093 -250.611132) (xy 8.84047 -250.611132)
			(xy 8.850594 -250.611651) (xy 8.869313 -250.619367) (xy 8.88367 -250.633644) (xy 8.891492 -250.652319)
			(xy 8.892032 -250.66244) (xy 8.892032 -251.07138) (xy 14.933168 -251.07138) (xy 14.933168 -250.66244)
			(xy 14.933654 -250.652292) (xy 14.94143 -250.633547) (xy 14.955807 -250.619224) (xy 14.974581 -250.611517)
			(xy 14.98473 -250.611132) (xy 16.38427 -250.611132) (xy 16.394394 -250.611651) (xy 16.413113 -250.619367)
			(xy 16.42747 -250.633644) (xy 16.435292 -250.652319) (xy 16.435832 -250.66244) (xy 16.435832 -251.07138)
			(xy 22.476968 -251.07138) (xy 22.476968 -250.66244) (xy 22.477454 -250.652292) (xy 22.48523 -250.633547)
			(xy 22.499607 -250.619224) (xy 22.518381 -250.611517) (xy 22.52853 -250.611132) (xy 23.92807 -250.611132)
			(xy 23.938194 -250.611651) (xy 23.956913 -250.619367) (xy 23.97127 -250.633644) (xy 23.979092 -250.652319)
			(xy 23.979632 -250.66244) (xy 23.979632 -251.07138) (xy 30.020768 -251.07138) (xy 30.020768 -250.66244)
			(xy 30.021254 -250.652292) (xy 30.02903 -250.633547) (xy 30.043407 -250.619224) (xy 30.062181 -250.611517)
			(xy 30.07233 -250.611132) (xy 31.47187 -250.611132) (xy 31.481994 -250.611651) (xy 31.500713 -250.619367)
			(xy 31.51507 -250.633644) (xy 31.522892 -250.652319) (xy 31.523432 -250.66244) (xy 31.523432 -251.07138)
			(xy 37.564568 -251.07138) (xy 37.564568 -250.66244) (xy 37.565054 -250.652292) (xy 37.57283 -250.633547)
			(xy 37.587207 -250.619224) (xy 37.605981 -250.611517) (xy 37.61613 -250.611132) (xy 39.01567 -250.611132)
			(xy 39.025794 -250.611651) (xy 39.044513 -250.619367) (xy 39.05887 -250.633644) (xy 39.066692 -250.652319)
			(xy 39.067232 -250.66244) (xy 39.067232 -251.07138) (xy 45.108368 -251.07138) (xy 45.108368 -250.66244)
			(xy 45.108854 -250.652292) (xy 45.11663 -250.633547) (xy 45.131007 -250.619224) (xy 45.149781 -250.611517)
			(xy 45.15993 -250.611132) (xy 46.55947 -250.611132) (xy 46.569594 -250.611651) (xy 46.588313 -250.619367)
			(xy 46.60267 -250.633644) (xy 46.610492 -250.652319) (xy 46.611032 -250.66244) (xy 46.611032 -251.07138)
			(xy 52.652168 -251.07138) (xy 52.652168 -250.66244) (xy 52.652654 -250.652292) (xy 52.66043 -250.633547)
			(xy 52.674807 -250.619224) (xy 52.693581 -250.611517) (xy 52.70373 -250.611132) (xy 54.10327 -250.611132)
			(xy 54.113394 -250.611651) (xy 54.132113 -250.619367) (xy 54.14647 -250.633644) (xy 54.154292 -250.652319)
			(xy 54.154832 -250.66244) (xy 54.154832 -251.07138) (xy 60.195968 -251.07138) (xy 60.195968 -250.66244)
			(xy 60.196454 -250.652292) (xy 60.20423 -250.633547) (xy 60.218607 -250.619224) (xy 60.237381 -250.611517)
			(xy 60.24753 -250.611132) (xy 61.64707 -250.611132) (xy 61.657194 -250.611651) (xy 61.675913 -250.619367)
			(xy 61.69027 -250.633644) (xy 61.698092 -250.652319) (xy 61.698632 -250.66244) (xy 61.698632 -251.07138)
			(xy 61.698163 -251.081529) (xy 61.69038 -251.100275) (xy 61.675998 -251.114598) (xy 61.65722 -251.122304)
			(xy 61.64707 -251.122688) (xy 60.24753 -251.122688) (xy 60.237409 -251.12215) (xy 60.218693 -251.114437)
			(xy 60.204337 -251.100167) (xy 60.196512 -251.081498) (xy 60.195968 -251.07138) (xy 54.154832 -251.07138)
			(xy 54.154363 -251.081529) (xy 54.14658 -251.100275) (xy 54.132198 -251.114598) (xy 54.11342 -251.122304)
			(xy 54.10327 -251.122688) (xy 52.70373 -251.122688) (xy 52.693609 -251.12215) (xy 52.674893 -251.114437)
			(xy 52.660537 -251.100167) (xy 52.652712 -251.081498) (xy 52.652168 -251.07138) (xy 46.611032 -251.07138)
			(xy 46.610563 -251.081529) (xy 46.60278 -251.100275) (xy 46.588398 -251.114598) (xy 46.56962 -251.122304)
			(xy 46.55947 -251.122688) (xy 45.15993 -251.122688) (xy 45.149809 -251.12215) (xy 45.131093 -251.114437)
			(xy 45.116737 -251.100167) (xy 45.108912 -251.081498) (xy 45.108368 -251.07138) (xy 39.067232 -251.07138)
			(xy 39.066763 -251.081529) (xy 39.05898 -251.100275) (xy 39.044598 -251.114598) (xy 39.02582 -251.122304)
			(xy 39.01567 -251.122688) (xy 37.61613 -251.122688) (xy 37.606009 -251.12215) (xy 37.587293 -251.114437)
			(xy 37.572937 -251.100167) (xy 37.565112 -251.081498) (xy 37.564568 -251.07138) (xy 31.523432 -251.07138)
			(xy 31.522963 -251.081529) (xy 31.51518 -251.100275) (xy 31.500798 -251.114598) (xy 31.48202 -251.122304)
			(xy 31.47187 -251.122688) (xy 30.07233 -251.122688) (xy 30.062209 -251.12215) (xy 30.043493 -251.114437)
			(xy 30.029137 -251.100167) (xy 30.021312 -251.081498) (xy 30.020768 -251.07138) (xy 23.979632 -251.07138)
			(xy 23.979163 -251.081529) (xy 23.97138 -251.100275) (xy 23.956998 -251.114598) (xy 23.93822 -251.122304)
			(xy 23.92807 -251.122688) (xy 22.52853 -251.122688) (xy 22.518409 -251.12215) (xy 22.499693 -251.114437)
			(xy 22.485337 -251.100167) (xy 22.477512 -251.081498) (xy 22.476968 -251.07138) (xy 16.435832 -251.07138)
			(xy 16.435363 -251.081529) (xy 16.42758 -251.100275) (xy 16.413198 -251.114598) (xy 16.39442 -251.122304)
			(xy 16.38427 -251.122688) (xy 14.98473 -251.122688) (xy 14.974609 -251.12215) (xy 14.955893 -251.114437)
			(xy 14.941537 -251.100167) (xy 14.933712 -251.081498) (xy 14.933168 -251.07138) (xy 8.892032 -251.07138)
			(xy 8.891563 -251.081529) (xy 8.88378 -251.100275) (xy 8.869398 -251.114598) (xy 8.85062 -251.122304)
			(xy 8.84047 -251.122688) (xy 7.44093 -251.122688) (xy 7.430809 -251.12215) (xy 7.412093 -251.114437)
			(xy 7.397737 -251.100167) (xy 7.389912 -251.081498) (xy 7.389368 -251.07138) (xy 2.509012 -251.07138)
			(xy 2.509012 -251.921518) (xy 11.489436 -251.921518) (xy 11.489436 -251.512578) (xy 11.489915 -251.502419)
			(xy 11.497696 -251.48365) (xy 11.512067 -251.469285) (xy 11.530839 -251.461511) (xy 11.540998 -251.461016)
			(xy 12.940538 -251.461016) (xy 12.950695 -251.461502) (xy 12.969461 -251.469285) (xy 12.983824 -251.483652)
			(xy 12.991601 -251.50242) (xy 12.9921 -251.512578) (xy 12.9921 -251.921518) (xy 19.033236 -251.921518)
			(xy 19.033236 -251.512578) (xy 19.033715 -251.502419) (xy 19.041496 -251.48365) (xy 19.055867 -251.469285)
			(xy 19.074639 -251.461511) (xy 19.084798 -251.461016) (xy 20.484338 -251.461016) (xy 20.494495 -251.461502)
			(xy 20.513261 -251.469285) (xy 20.527624 -251.483652) (xy 20.535401 -251.50242) (xy 20.5359 -251.512578)
			(xy 20.5359 -251.921518) (xy 26.577036 -251.921518) (xy 26.577036 -251.512578) (xy 26.577515 -251.502419)
			(xy 26.585296 -251.48365) (xy 26.599667 -251.469285) (xy 26.618439 -251.461511) (xy 26.628598 -251.461016)
			(xy 28.028138 -251.461016) (xy 28.038295 -251.461502) (xy 28.057061 -251.469285) (xy 28.071424 -251.483652)
			(xy 28.079201 -251.50242) (xy 28.0797 -251.512578) (xy 28.0797 -251.921518) (xy 34.120836 -251.921518)
			(xy 34.120836 -251.512578) (xy 34.121315 -251.502419) (xy 34.129096 -251.48365) (xy 34.143467 -251.469285)
			(xy 34.162239 -251.461511) (xy 34.172398 -251.461016) (xy 35.571938 -251.461016) (xy 35.582095 -251.461502)
			(xy 35.600861 -251.469285) (xy 35.615224 -251.483652) (xy 35.623001 -251.50242) (xy 35.6235 -251.512578)
			(xy 35.6235 -251.921518) (xy 41.664636 -251.921518) (xy 41.664636 -251.512578) (xy 41.665115 -251.502419)
			(xy 41.672896 -251.48365) (xy 41.687267 -251.469285) (xy 41.706039 -251.461511) (xy 41.716198 -251.461016)
			(xy 43.115738 -251.461016) (xy 43.125895 -251.461502) (xy 43.144661 -251.469285) (xy 43.159024 -251.483652)
			(xy 43.166801 -251.50242) (xy 43.1673 -251.512578) (xy 43.1673 -251.921518) (xy 49.208436 -251.921518)
			(xy 49.208436 -251.512578) (xy 49.208915 -251.502419) (xy 49.216696 -251.48365) (xy 49.231067 -251.469285)
			(xy 49.249839 -251.461511) (xy 49.259998 -251.461016) (xy 50.659538 -251.461016) (xy 50.669695 -251.461502)
			(xy 50.688461 -251.469285) (xy 50.702824 -251.483652) (xy 50.710601 -251.50242) (xy 50.7111 -251.512578)
			(xy 50.7111 -251.921518) (xy 56.752236 -251.921518) (xy 56.752236 -251.512578) (xy 56.752715 -251.502419)
			(xy 56.760496 -251.48365) (xy 56.774867 -251.469285) (xy 56.793639 -251.461511) (xy 56.803798 -251.461016)
			(xy 58.203338 -251.461016) (xy 58.213495 -251.461502) (xy 58.232261 -251.469285) (xy 58.246624 -251.483652)
			(xy 58.254401 -251.50242) (xy 58.2549 -251.512578) (xy 58.2549 -251.921518) (xy 64.296036 -251.921518)
			(xy 64.296036 -251.512578) (xy 64.296515 -251.502419) (xy 64.304296 -251.48365) (xy 64.318667 -251.469285)
			(xy 64.337439 -251.461511) (xy 64.347598 -251.461016) (xy 65.747138 -251.461016) (xy 65.757295 -251.461502)
			(xy 65.776061 -251.469285) (xy 65.790424 -251.483652) (xy 65.798201 -251.50242) (xy 65.7987 -251.512578)
			(xy 65.7987 -251.76988) (xy 75.695566 -251.76988) (xy 75.699547 -251.63686) (xy 75.711476 -251.504315)
			(xy 75.731311 -251.372722) (xy 75.75898 -251.24255) (xy 75.794384 -251.114265) (xy 75.837397 -250.988328)
			(xy 75.887864 -250.865189) (xy 75.945605 -250.745288) (xy 76.010414 -250.629055) (xy 76.082058 -250.516905)
			(xy 76.16028 -250.409241) (xy 76.244801 -250.306448) (xy 76.335319 -250.208893) (xy 76.431508 -250.116927)
			(xy 76.533026 -250.030877) (xy 76.639507 -249.951053) (xy 76.750572 -249.87774) (xy 76.865823 -249.8112)
			(xy 76.984847 -249.751671) (xy 77.107218 -249.699367) (xy 77.232497 -249.654475) (xy 77.360238 -249.617156)
			(xy 77.489981 -249.587543) (xy 77.621263 -249.565742) (xy 77.753614 -249.551832) (xy 77.88656 -249.545861)
			(xy 78.019625 -249.547852) (xy 78.152333 -249.557797) (xy 78.284209 -249.575661) (xy 78.41478 -249.601379)
			(xy 78.54358 -249.63486) (xy 78.670146 -249.675984) (xy 78.794027 -249.724604) (xy 78.914778 -249.780545)
			(xy 79.031968 -249.843607) (xy 79.145177 -249.913565) (xy 79.253999 -249.990169) (xy 79.358045 -250.073143)
			(xy 79.456943 -250.162191) (xy 79.550338 -250.256994) (xy 79.637896 -250.357212) (xy 79.719305 -250.462488)
			(xy 79.794271 -250.572444) (xy 79.862528 -250.686686) (xy 79.92383 -250.804806) (xy 79.977959 -250.926381)
			(xy 80.02472 -251.050975) (xy 80.063946 -251.178143) (xy 80.095496 -251.307429) (xy 80.119259 -251.43837)
			(xy 80.135148 -251.570498) (xy 80.143106 -251.70334) (xy 80.143604 -251.76988) (xy 143.715496 -251.76988)
			(xy 143.719477 -251.63686) (xy 143.731406 -251.504315) (xy 143.751241 -251.372722) (xy 143.77891 -251.24255)
			(xy 143.814314 -251.114265) (xy 143.857327 -250.988328) (xy 143.907794 -250.865189) (xy 143.965535 -250.745288)
			(xy 144.030344 -250.629055) (xy 144.101988 -250.516905) (xy 144.18021 -250.409241) (xy 144.264731 -250.306448)
			(xy 144.355249 -250.208893) (xy 144.451438 -250.116927) (xy 144.552956 -250.030877) (xy 144.659437 -249.951053)
			(xy 144.770502 -249.87774) (xy 144.885753 -249.8112) (xy 145.004777 -249.751671) (xy 145.127148 -249.699367)
			(xy 145.252427 -249.654475) (xy 145.380168 -249.617156) (xy 145.509911 -249.587543) (xy 145.641193 -249.565742)
			(xy 145.773544 -249.551832) (xy 145.90649 -249.545861) (xy 146.039555 -249.547852) (xy 146.172263 -249.557797)
			(xy 146.304139 -249.575661) (xy 146.43471 -249.601379) (xy 146.56351 -249.63486) (xy 146.690076 -249.675984)
			(xy 146.813957 -249.724604) (xy 146.934708 -249.780545) (xy 147.051898 -249.843607) (xy 147.165107 -249.913565)
			(xy 147.273929 -249.990169) (xy 147.377975 -250.073143) (xy 147.476873 -250.162191) (xy 147.535297 -250.221496)
			(xy 162.162236 -250.221496) (xy 162.162236 -249.812556) (xy 162.162586 -249.802394) (xy 162.170403 -249.783634)
			(xy 162.184822 -249.769311) (xy 162.203634 -249.76162) (xy 162.213798 -249.761248) (xy 163.613338 -249.761248)
			(xy 163.623468 -249.761696) (xy 163.642192 -249.769437) (xy 163.656547 -249.783735) (xy 163.664363 -249.802428)
			(xy 163.6649 -249.812556) (xy 163.6649 -250.221496) (xy 169.706036 -250.221496) (xy 169.706036 -249.812556)
			(xy 169.706386 -249.802394) (xy 169.714203 -249.783634) (xy 169.728622 -249.769311) (xy 169.747434 -249.76162)
			(xy 169.757598 -249.761248) (xy 171.157138 -249.761248) (xy 171.167268 -249.761696) (xy 171.185992 -249.769437)
			(xy 171.200347 -249.783735) (xy 171.208163 -249.802428) (xy 171.2087 -249.812556) (xy 171.2087 -250.221496)
			(xy 177.249836 -250.221496) (xy 177.249836 -249.812556) (xy 177.250186 -249.802394) (xy 177.258003 -249.783634)
			(xy 177.272422 -249.769311) (xy 177.291234 -249.76162) (xy 177.301398 -249.761248) (xy 178.700938 -249.761248)
			(xy 178.711068 -249.761696) (xy 178.729792 -249.769437) (xy 178.744147 -249.783735) (xy 178.751963 -249.802428)
			(xy 178.7525 -249.812556) (xy 178.7525 -250.221496) (xy 184.793636 -250.221496) (xy 184.793636 -249.812556)
			(xy 184.793986 -249.802394) (xy 184.801803 -249.783634) (xy 184.816222 -249.769311) (xy 184.835034 -249.76162)
			(xy 184.845198 -249.761248) (xy 186.244738 -249.761248) (xy 186.254868 -249.761696) (xy 186.273592 -249.769437)
			(xy 186.287947 -249.783735) (xy 186.295763 -249.802428) (xy 186.2963 -249.812556) (xy 186.2963 -250.221496)
			(xy 192.337436 -250.221496) (xy 192.337436 -249.812556) (xy 192.337786 -249.802394) (xy 192.345603 -249.783634)
			(xy 192.360022 -249.769311) (xy 192.378834 -249.76162) (xy 192.388998 -249.761248) (xy 193.788538 -249.761248)
			(xy 193.798668 -249.761696) (xy 193.817392 -249.769437) (xy 193.831747 -249.783735) (xy 193.839563 -249.802428)
			(xy 193.8401 -249.812556) (xy 193.8401 -250.221496) (xy 199.881236 -250.221496) (xy 199.881236 -249.812556)
			(xy 199.881586 -249.802394) (xy 199.889403 -249.783634) (xy 199.903822 -249.769311) (xy 199.922634 -249.76162)
			(xy 199.932798 -249.761248) (xy 201.332338 -249.761248) (xy 201.342468 -249.761696) (xy 201.361192 -249.769437)
			(xy 201.375547 -249.783735) (xy 201.383363 -249.802428) (xy 201.3839 -249.812556) (xy 201.3839 -250.221496)
			(xy 207.425036 -250.221496) (xy 207.425036 -249.812556) (xy 207.425386 -249.802394) (xy 207.433203 -249.783634)
			(xy 207.447622 -249.769311) (xy 207.466434 -249.76162) (xy 207.476598 -249.761248) (xy 208.876138 -249.761248)
			(xy 208.886268 -249.761696) (xy 208.904992 -249.769437) (xy 208.919347 -249.783735) (xy 208.927163 -249.802428)
			(xy 208.9277 -249.812556) (xy 208.9277 -250.221496) (xy 214.968836 -250.221496) (xy 214.968836 -249.812556)
			(xy 214.969186 -249.802394) (xy 214.977003 -249.783634) (xy 214.991422 -249.769311) (xy 215.010234 -249.76162)
			(xy 215.020398 -249.761248) (xy 216.419938 -249.761248) (xy 216.430068 -249.761696) (xy 216.448792 -249.769437)
			(xy 216.463147 -249.783735) (xy 216.470963 -249.802428) (xy 216.4715 -249.812556) (xy 216.4715 -250.221496)
			(xy 259.429504 -250.221496) (xy 259.429504 -249.812556) (xy 259.429886 -249.802399) (xy 259.437697 -249.783644)
			(xy 259.452105 -249.769323) (xy 259.470906 -249.761625) (xy 259.481066 -249.761248) (xy 260.880606 -249.761248)
			(xy 260.890734 -249.761722) (xy 260.909457 -249.769453) (xy 260.923813 -249.783743) (xy 260.931631 -249.80243)
			(xy 260.932168 -249.812556) (xy 260.932168 -250.221496) (xy 266.973304 -250.221496) (xy 266.973304 -249.812556)
			(xy 266.973686 -249.802399) (xy 266.981497 -249.783644) (xy 266.995905 -249.769323) (xy 267.014706 -249.761625)
			(xy 267.024866 -249.761248) (xy 268.424406 -249.761248) (xy 268.434534 -249.761722) (xy 268.453257 -249.769453)
			(xy 268.467613 -249.783743) (xy 268.475431 -249.80243) (xy 268.475968 -249.812556) (xy 268.475968 -250.221496)
			(xy 274.517104 -250.221496) (xy 274.517104 -249.812556) (xy 274.517486 -249.802399) (xy 274.525297 -249.783644)
			(xy 274.539705 -249.769323) (xy 274.558506 -249.761625) (xy 274.568666 -249.761248) (xy 275.968206 -249.761248)
			(xy 275.978334 -249.761722) (xy 275.997057 -249.769453) (xy 276.011413 -249.783743) (xy 276.019231 -249.80243)
			(xy 276.019768 -249.812556) (xy 276.019768 -250.221496) (xy 282.060904 -250.221496) (xy 282.060904 -249.812556)
			(xy 282.061286 -249.802399) (xy 282.069097 -249.783644) (xy 282.083505 -249.769323) (xy 282.102306 -249.761625)
			(xy 282.112466 -249.761248) (xy 283.512006 -249.761248) (xy 283.522134 -249.761722) (xy 283.540857 -249.769453)
			(xy 283.555213 -249.783743) (xy 283.563031 -249.80243) (xy 283.563568 -249.812556) (xy 283.563568 -250.221496)
			(xy 289.604704 -250.221496) (xy 289.604704 -249.812556) (xy 289.605086 -249.802399) (xy 289.612897 -249.783644)
			(xy 289.627305 -249.769323) (xy 289.646106 -249.761625) (xy 289.656266 -249.761248) (xy 291.055806 -249.761248)
			(xy 291.065934 -249.761722) (xy 291.084657 -249.769453) (xy 291.099013 -249.783743) (xy 291.106831 -249.80243)
			(xy 291.107368 -249.812556) (xy 291.107368 -250.221496) (xy 297.148504 -250.221496) (xy 297.148504 -249.812556)
			(xy 297.148886 -249.802399) (xy 297.156697 -249.783644) (xy 297.171105 -249.769323) (xy 297.189906 -249.761625)
			(xy 297.200066 -249.761248) (xy 298.599606 -249.761248) (xy 298.609734 -249.761722) (xy 298.628457 -249.769453)
			(xy 298.642813 -249.783743) (xy 298.650631 -249.80243) (xy 298.651168 -249.812556) (xy 298.651168 -250.221496)
			(xy 304.692304 -250.221496) (xy 304.692304 -249.812556) (xy 304.692686 -249.802399) (xy 304.700497 -249.783644)
			(xy 304.714905 -249.769323) (xy 304.733706 -249.761625) (xy 304.743866 -249.761248) (xy 306.143406 -249.761248)
			(xy 306.153534 -249.761722) (xy 306.172257 -249.769453) (xy 306.186613 -249.783743) (xy 306.194431 -249.80243)
			(xy 306.194968 -249.812556) (xy 306.194968 -250.221496) (xy 312.236104 -250.221496) (xy 312.236104 -249.812556)
			(xy 312.236486 -249.802399) (xy 312.244297 -249.783644) (xy 312.258705 -249.769323) (xy 312.277506 -249.761625)
			(xy 312.287666 -249.761248) (xy 313.687206 -249.761248) (xy 313.697334 -249.761722) (xy 313.716057 -249.769453)
			(xy 313.730413 -249.783743) (xy 313.738231 -249.80243) (xy 313.738768 -249.812556) (xy 313.738768 -250.221496)
			(xy 313.738374 -250.231654) (xy 313.730574 -250.250412) (xy 313.716168 -250.264737) (xy 313.697366 -250.272431)
			(xy 313.687206 -250.272804) (xy 312.287666 -250.272804) (xy 312.277543 -250.272303) (xy 312.258829 -250.264572)
			(xy 312.244475 -250.250291) (xy 312.23665 -250.231617) (xy 312.236104 -250.221496) (xy 306.194968 -250.221496)
			(xy 306.194574 -250.231654) (xy 306.186774 -250.250412) (xy 306.172368 -250.264737) (xy 306.153566 -250.272431)
			(xy 306.143406 -250.272804) (xy 304.743866 -250.272804) (xy 304.733743 -250.272303) (xy 304.715029 -250.264572)
			(xy 304.700675 -250.250291) (xy 304.69285 -250.231617) (xy 304.692304 -250.221496) (xy 298.651168 -250.221496)
			(xy 298.650774 -250.231654) (xy 298.642974 -250.250412) (xy 298.628568 -250.264737) (xy 298.609766 -250.272431)
			(xy 298.599606 -250.272804) (xy 297.200066 -250.272804) (xy 297.189943 -250.272303) (xy 297.171229 -250.264572)
			(xy 297.156875 -250.250291) (xy 297.14905 -250.231617) (xy 297.148504 -250.221496) (xy 291.107368 -250.221496)
			(xy 291.106974 -250.231654) (xy 291.099174 -250.250412) (xy 291.084768 -250.264737) (xy 291.065966 -250.272431)
			(xy 291.055806 -250.272804) (xy 289.656266 -250.272804) (xy 289.646143 -250.272303) (xy 289.627429 -250.264572)
			(xy 289.613075 -250.250291) (xy 289.60525 -250.231617) (xy 289.604704 -250.221496) (xy 283.563568 -250.221496)
			(xy 283.563174 -250.231654) (xy 283.555374 -250.250412) (xy 283.540968 -250.264737) (xy 283.522166 -250.272431)
			(xy 283.512006 -250.272804) (xy 282.112466 -250.272804) (xy 282.102343 -250.272303) (xy 282.083629 -250.264572)
			(xy 282.069275 -250.250291) (xy 282.06145 -250.231617) (xy 282.060904 -250.221496) (xy 276.019768 -250.221496)
			(xy 276.019374 -250.231654) (xy 276.011574 -250.250412) (xy 275.997168 -250.264737) (xy 275.978366 -250.272431)
			(xy 275.968206 -250.272804) (xy 274.568666 -250.272804) (xy 274.558543 -250.272303) (xy 274.539829 -250.264572)
			(xy 274.525475 -250.250291) (xy 274.51765 -250.231617) (xy 274.517104 -250.221496) (xy 268.475968 -250.221496)
			(xy 268.475574 -250.231654) (xy 268.467774 -250.250412) (xy 268.453368 -250.264737) (xy 268.434566 -250.272431)
			(xy 268.424406 -250.272804) (xy 267.024866 -250.272804) (xy 267.014743 -250.272303) (xy 266.996029 -250.264572)
			(xy 266.981675 -250.250291) (xy 266.97385 -250.231617) (xy 266.973304 -250.221496) (xy 260.932168 -250.221496)
			(xy 260.931774 -250.231654) (xy 260.923974 -250.250412) (xy 260.909568 -250.264737) (xy 260.890766 -250.272431)
			(xy 260.880606 -250.272804) (xy 259.481066 -250.272804) (xy 259.470943 -250.272303) (xy 259.452229 -250.264572)
			(xy 259.437875 -250.250291) (xy 259.43005 -250.231617) (xy 259.429504 -250.221496) (xy 216.4715 -250.221496)
			(xy 216.471075 -250.23165) (xy 216.463281 -250.250402) (xy 216.448885 -250.264726) (xy 216.430094 -250.272425)
			(xy 216.419938 -250.272804) (xy 215.020398 -250.272804) (xy 215.010277 -250.272276) (xy 214.991564 -250.264556)
			(xy 214.977209 -250.250283) (xy 214.969382 -250.231614) (xy 214.968836 -250.221496) (xy 208.9277 -250.221496)
			(xy 208.927275 -250.23165) (xy 208.919481 -250.250402) (xy 208.905085 -250.264726) (xy 208.886294 -250.272425)
			(xy 208.876138 -250.272804) (xy 207.476598 -250.272804) (xy 207.466477 -250.272276) (xy 207.447764 -250.264556)
			(xy 207.433409 -250.250283) (xy 207.425582 -250.231614) (xy 207.425036 -250.221496) (xy 201.3839 -250.221496)
			(xy 201.383475 -250.23165) (xy 201.375681 -250.250402) (xy 201.361285 -250.264726) (xy 201.342494 -250.272425)
			(xy 201.332338 -250.272804) (xy 199.932798 -250.272804) (xy 199.922677 -250.272276) (xy 199.903964 -250.264556)
			(xy 199.889609 -250.250283) (xy 199.881782 -250.231614) (xy 199.881236 -250.221496) (xy 193.8401 -250.221496)
			(xy 193.839675 -250.23165) (xy 193.831881 -250.250402) (xy 193.817485 -250.264726) (xy 193.798694 -250.272425)
			(xy 193.788538 -250.272804) (xy 192.388998 -250.272804) (xy 192.378877 -250.272276) (xy 192.360164 -250.264556)
			(xy 192.345809 -250.250283) (xy 192.337982 -250.231614) (xy 192.337436 -250.221496) (xy 186.2963 -250.221496)
			(xy 186.295875 -250.23165) (xy 186.288081 -250.250402) (xy 186.273685 -250.264726) (xy 186.254894 -250.272425)
			(xy 186.244738 -250.272804) (xy 184.845198 -250.272804) (xy 184.835077 -250.272276) (xy 184.816364 -250.264556)
			(xy 184.802009 -250.250283) (xy 184.794182 -250.231614) (xy 184.793636 -250.221496) (xy 178.7525 -250.221496)
			(xy 178.752075 -250.23165) (xy 178.744281 -250.250402) (xy 178.729885 -250.264726) (xy 178.711094 -250.272425)
			(xy 178.700938 -250.272804) (xy 177.301398 -250.272804) (xy 177.291277 -250.272276) (xy 177.272564 -250.264556)
			(xy 177.258209 -250.250283) (xy 177.250382 -250.231614) (xy 177.249836 -250.221496) (xy 171.2087 -250.221496)
			(xy 171.208275 -250.23165) (xy 171.200481 -250.250402) (xy 171.186085 -250.264726) (xy 171.167294 -250.272425)
			(xy 171.157138 -250.272804) (xy 169.757598 -250.272804) (xy 169.747477 -250.272276) (xy 169.728764 -250.264556)
			(xy 169.714409 -250.250283) (xy 169.706582 -250.231614) (xy 169.706036 -250.221496) (xy 163.6649 -250.221496)
			(xy 163.664475 -250.23165) (xy 163.656681 -250.250402) (xy 163.642285 -250.264726) (xy 163.623494 -250.272425)
			(xy 163.613338 -250.272804) (xy 162.213798 -250.272804) (xy 162.203677 -250.272276) (xy 162.184964 -250.264556)
			(xy 162.170609 -250.250283) (xy 162.162782 -250.231614) (xy 162.162236 -250.221496) (xy 147.535297 -250.221496)
			(xy 147.570268 -250.256994) (xy 147.657826 -250.357212) (xy 147.739235 -250.462488) (xy 147.814201 -250.572444)
			(xy 147.882458 -250.686686) (xy 147.94376 -250.804806) (xy 147.997889 -250.926381) (xy 148.04465 -251.050975)
			(xy 148.050944 -251.07138) (xy 158.062168 -251.07138) (xy 158.062168 -250.66244) (xy 158.062654 -250.652292)
			(xy 158.07043 -250.633547) (xy 158.084807 -250.619224) (xy 158.103581 -250.611517) (xy 158.11373 -250.611132)
			(xy 159.51327 -250.611132) (xy 159.523394 -250.611651) (xy 159.542113 -250.619367) (xy 159.55647 -250.633644)
			(xy 159.564292 -250.652319) (xy 159.564832 -250.66244) (xy 159.564832 -251.07138) (xy 165.605968 -251.07138)
			(xy 165.605968 -250.66244) (xy 165.606454 -250.652292) (xy 165.61423 -250.633547) (xy 165.628607 -250.619224)
			(xy 165.647381 -250.611517) (xy 165.65753 -250.611132) (xy 167.05707 -250.611132) (xy 167.067194 -250.611651)
			(xy 167.085913 -250.619367) (xy 167.10027 -250.633644) (xy 167.108092 -250.652319) (xy 167.108632 -250.66244)
			(xy 167.108632 -251.07138) (xy 173.149768 -251.07138) (xy 173.149768 -250.66244) (xy 173.150254 -250.652292)
			(xy 173.15803 -250.633547) (xy 173.172407 -250.619224) (xy 173.191181 -250.611517) (xy 173.20133 -250.611132)
			(xy 174.60087 -250.611132) (xy 174.610994 -250.611651) (xy 174.629713 -250.619367) (xy 174.64407 -250.633644)
			(xy 174.651892 -250.652319) (xy 174.652432 -250.66244) (xy 174.652432 -251.07138) (xy 180.693568 -251.07138)
			(xy 180.693568 -250.66244) (xy 180.694054 -250.652292) (xy 180.70183 -250.633547) (xy 180.716207 -250.619224)
			(xy 180.734981 -250.611517) (xy 180.74513 -250.611132) (xy 182.14467 -250.611132) (xy 182.154794 -250.611651)
			(xy 182.173513 -250.619367) (xy 182.18787 -250.633644) (xy 182.195692 -250.652319) (xy 182.196232 -250.66244)
			(xy 182.196232 -251.07138) (xy 188.237368 -251.07138) (xy 188.237368 -250.66244) (xy 188.237854 -250.652292)
			(xy 188.24563 -250.633547) (xy 188.260007 -250.619224) (xy 188.278781 -250.611517) (xy 188.28893 -250.611132)
			(xy 189.68847 -250.611132) (xy 189.698594 -250.611651) (xy 189.717313 -250.619367) (xy 189.73167 -250.633644)
			(xy 189.739492 -250.652319) (xy 189.740032 -250.66244) (xy 189.740032 -251.07138) (xy 195.781168 -251.07138)
			(xy 195.781168 -250.66244) (xy 195.781654 -250.652292) (xy 195.78943 -250.633547) (xy 195.803807 -250.619224)
			(xy 195.822581 -250.611517) (xy 195.83273 -250.611132) (xy 197.23227 -250.611132) (xy 197.242394 -250.611651)
			(xy 197.261113 -250.619367) (xy 197.27547 -250.633644) (xy 197.283292 -250.652319) (xy 197.283832 -250.66244)
			(xy 197.283832 -251.07138) (xy 203.324968 -251.07138) (xy 203.324968 -250.66244) (xy 203.325454 -250.652292)
			(xy 203.33323 -250.633547) (xy 203.347607 -250.619224) (xy 203.366381 -250.611517) (xy 203.37653 -250.611132)
			(xy 204.77607 -250.611132) (xy 204.786194 -250.611651) (xy 204.804913 -250.619367) (xy 204.81927 -250.633644)
			(xy 204.827092 -250.652319) (xy 204.827632 -250.66244) (xy 204.827632 -251.07138) (xy 210.868768 -251.07138)
			(xy 210.868768 -250.66244) (xy 210.869254 -250.652292) (xy 210.87703 -250.633547) (xy 210.891407 -250.619224)
			(xy 210.910181 -250.611517) (xy 210.92033 -250.611132) (xy 212.31987 -250.611132) (xy 212.329994 -250.611651)
			(xy 212.348713 -250.619367) (xy 212.36307 -250.633644) (xy 212.370892 -250.652319) (xy 212.371432 -250.66244)
			(xy 212.371432 -251.07138) (xy 255.329436 -251.07138) (xy 255.329436 -250.66244) (xy 255.329855 -250.652284)
			(xy 255.337644 -250.633526) (xy 255.352043 -250.6192) (xy 255.37084 -250.611505) (xy 255.380998 -250.611132)
			(xy 256.780538 -250.611132) (xy 256.790666 -250.611595) (xy 256.809387 -250.619334) (xy 256.823741 -250.633627)
			(xy 256.831561 -250.652314) (xy 256.8321 -250.66244) (xy 256.8321 -251.07138) (xy 262.873236 -251.07138)
			(xy 262.873236 -250.66244) (xy 262.873655 -250.652284) (xy 262.881444 -250.633526) (xy 262.895843 -250.6192)
			(xy 262.91464 -250.611505) (xy 262.924798 -250.611132) (xy 264.324338 -250.611132) (xy 264.334466 -250.611595)
			(xy 264.353187 -250.619334) (xy 264.367541 -250.633627) (xy 264.375361 -250.652314) (xy 264.3759 -250.66244)
			(xy 264.3759 -251.07138) (xy 270.417036 -251.07138) (xy 270.417036 -250.66244) (xy 270.417455 -250.652284)
			(xy 270.425244 -250.633526) (xy 270.439643 -250.6192) (xy 270.45844 -250.611505) (xy 270.468598 -250.611132)
			(xy 271.868138 -250.611132) (xy 271.878266 -250.611595) (xy 271.896987 -250.619334) (xy 271.911341 -250.633627)
			(xy 271.919161 -250.652314) (xy 271.9197 -250.66244) (xy 271.9197 -251.07138) (xy 277.960836 -251.07138)
			(xy 277.960836 -250.66244) (xy 277.961255 -250.652284) (xy 277.969044 -250.633526) (xy 277.983443 -250.6192)
			(xy 278.00224 -250.611505) (xy 278.012398 -250.611132) (xy 279.411938 -250.611132) (xy 279.422066 -250.611595)
			(xy 279.440787 -250.619334) (xy 279.455141 -250.633627) (xy 279.462961 -250.652314) (xy 279.4635 -250.66244)
			(xy 279.4635 -251.07138) (xy 285.504636 -251.07138) (xy 285.504636 -250.66244) (xy 285.505055 -250.652284)
			(xy 285.512844 -250.633526) (xy 285.527243 -250.6192) (xy 285.54604 -250.611505) (xy 285.556198 -250.611132)
			(xy 286.955738 -250.611132) (xy 286.965866 -250.611595) (xy 286.984587 -250.619334) (xy 286.998941 -250.633627)
			(xy 287.006761 -250.652314) (xy 287.0073 -250.66244) (xy 287.0073 -251.07138) (xy 293.048436 -251.07138)
			(xy 293.048436 -250.66244) (xy 293.048855 -250.652284) (xy 293.056644 -250.633526) (xy 293.071043 -250.6192)
			(xy 293.08984 -250.611505) (xy 293.099998 -250.611132) (xy 294.499538 -250.611132) (xy 294.509666 -250.611595)
			(xy 294.528387 -250.619334) (xy 294.542741 -250.633627) (xy 294.550561 -250.652314) (xy 294.5511 -250.66244)
			(xy 294.5511 -251.07138) (xy 300.592236 -251.07138) (xy 300.592236 -250.66244) (xy 300.592655 -250.652284)
			(xy 300.600444 -250.633526) (xy 300.614843 -250.6192) (xy 300.63364 -250.611505) (xy 300.643798 -250.611132)
			(xy 302.043338 -250.611132) (xy 302.053466 -250.611595) (xy 302.072187 -250.619334) (xy 302.086541 -250.633627)
			(xy 302.094361 -250.652314) (xy 302.0949 -250.66244) (xy 302.0949 -251.07138) (xy 308.136036 -251.07138)
			(xy 308.136036 -250.66244) (xy 308.136455 -250.652284) (xy 308.144244 -250.633526) (xy 308.158643 -250.6192)
			(xy 308.17744 -250.611505) (xy 308.187598 -250.611132) (xy 309.587138 -250.611132) (xy 309.597266 -250.611595)
			(xy 309.615987 -250.619334) (xy 309.630341 -250.633627) (xy 309.638161 -250.652314) (xy 309.6387 -250.66244)
			(xy 309.6387 -251.07138) (xy 309.638262 -251.081533) (xy 309.630473 -251.100285) (xy 309.616081 -251.114609)
			(xy 309.597293 -251.122309) (xy 309.587138 -251.122688) (xy 308.187598 -251.122688) (xy 308.177475 -251.122176)
			(xy 308.158759 -251.114453) (xy 308.144404 -251.100175) (xy 308.13658 -251.081501) (xy 308.136036 -251.07138)
			(xy 302.0949 -251.07138) (xy 302.094462 -251.081533) (xy 302.086673 -251.100285) (xy 302.072281 -251.114609)
			(xy 302.053493 -251.122309) (xy 302.043338 -251.122688) (xy 300.643798 -251.122688) (xy 300.633675 -251.122176)
			(xy 300.614959 -251.114453) (xy 300.600604 -251.100175) (xy 300.59278 -251.081501) (xy 300.592236 -251.07138)
			(xy 294.5511 -251.07138) (xy 294.550662 -251.081533) (xy 294.542873 -251.100285) (xy 294.528481 -251.114609)
			(xy 294.509693 -251.122309) (xy 294.499538 -251.122688) (xy 293.099998 -251.122688) (xy 293.089875 -251.122176)
			(xy 293.071159 -251.114453) (xy 293.056804 -251.100175) (xy 293.04898 -251.081501) (xy 293.048436 -251.07138)
			(xy 287.0073 -251.07138) (xy 287.006862 -251.081533) (xy 286.999073 -251.100285) (xy 286.984681 -251.114609)
			(xy 286.965893 -251.122309) (xy 286.955738 -251.122688) (xy 285.556198 -251.122688) (xy 285.546075 -251.122176)
			(xy 285.527359 -251.114453) (xy 285.513004 -251.100175) (xy 285.50518 -251.081501) (xy 285.504636 -251.07138)
			(xy 279.4635 -251.07138) (xy 279.463062 -251.081533) (xy 279.455273 -251.100285) (xy 279.440881 -251.114609)
			(xy 279.422093 -251.122309) (xy 279.411938 -251.122688) (xy 278.012398 -251.122688) (xy 278.002275 -251.122176)
			(xy 277.983559 -251.114453) (xy 277.969204 -251.100175) (xy 277.96138 -251.081501) (xy 277.960836 -251.07138)
			(xy 271.9197 -251.07138) (xy 271.919262 -251.081533) (xy 271.911473 -251.100285) (xy 271.897081 -251.114609)
			(xy 271.878293 -251.122309) (xy 271.868138 -251.122688) (xy 270.468598 -251.122688) (xy 270.458475 -251.122176)
			(xy 270.439759 -251.114453) (xy 270.425404 -251.100175) (xy 270.41758 -251.081501) (xy 270.417036 -251.07138)
			(xy 264.3759 -251.07138) (xy 264.375462 -251.081533) (xy 264.367673 -251.100285) (xy 264.353281 -251.114609)
			(xy 264.334493 -251.122309) (xy 264.324338 -251.122688) (xy 262.924798 -251.122688) (xy 262.914675 -251.122176)
			(xy 262.895959 -251.114453) (xy 262.881604 -251.100175) (xy 262.87378 -251.081501) (xy 262.873236 -251.07138)
			(xy 256.8321 -251.07138) (xy 256.831662 -251.081533) (xy 256.823873 -251.100285) (xy 256.809481 -251.114609)
			(xy 256.790693 -251.122309) (xy 256.780538 -251.122688) (xy 255.380998 -251.122688) (xy 255.370875 -251.122176)
			(xy 255.352159 -251.114453) (xy 255.337804 -251.100175) (xy 255.32998 -251.081501) (xy 255.329436 -251.07138)
			(xy 212.371432 -251.07138) (xy 212.370963 -251.081529) (xy 212.36318 -251.100275) (xy 212.348798 -251.114598)
			(xy 212.33002 -251.122304) (xy 212.31987 -251.122688) (xy 210.92033 -251.122688) (xy 210.910209 -251.12215)
			(xy 210.891493 -251.114437) (xy 210.877137 -251.100167) (xy 210.869312 -251.081498) (xy 210.868768 -251.07138)
			(xy 204.827632 -251.07138) (xy 204.827163 -251.081529) (xy 204.81938 -251.100275) (xy 204.804998 -251.114598)
			(xy 204.78622 -251.122304) (xy 204.77607 -251.122688) (xy 203.37653 -251.122688) (xy 203.366409 -251.12215)
			(xy 203.347693 -251.114437) (xy 203.333337 -251.100167) (xy 203.325512 -251.081498) (xy 203.324968 -251.07138)
			(xy 197.283832 -251.07138) (xy 197.283363 -251.081529) (xy 197.27558 -251.100275) (xy 197.261198 -251.114598)
			(xy 197.24242 -251.122304) (xy 197.23227 -251.122688) (xy 195.83273 -251.122688) (xy 195.822609 -251.12215)
			(xy 195.803893 -251.114437) (xy 195.789537 -251.100167) (xy 195.781712 -251.081498) (xy 195.781168 -251.07138)
			(xy 189.740032 -251.07138) (xy 189.739563 -251.081529) (xy 189.73178 -251.100275) (xy 189.717398 -251.114598)
			(xy 189.69862 -251.122304) (xy 189.68847 -251.122688) (xy 188.28893 -251.122688) (xy 188.278809 -251.12215)
			(xy 188.260093 -251.114437) (xy 188.245737 -251.100167) (xy 188.237912 -251.081498) (xy 188.237368 -251.07138)
			(xy 182.196232 -251.07138) (xy 182.195763 -251.081529) (xy 182.18798 -251.100275) (xy 182.173598 -251.114598)
			(xy 182.15482 -251.122304) (xy 182.14467 -251.122688) (xy 180.74513 -251.122688) (xy 180.735009 -251.12215)
			(xy 180.716293 -251.114437) (xy 180.701937 -251.100167) (xy 180.694112 -251.081498) (xy 180.693568 -251.07138)
			(xy 174.652432 -251.07138) (xy 174.651963 -251.081529) (xy 174.64418 -251.100275) (xy 174.629798 -251.114598)
			(xy 174.61102 -251.122304) (xy 174.60087 -251.122688) (xy 173.20133 -251.122688) (xy 173.191209 -251.12215)
			(xy 173.172493 -251.114437) (xy 173.158137 -251.100167) (xy 173.150312 -251.081498) (xy 173.149768 -251.07138)
			(xy 167.108632 -251.07138) (xy 167.108163 -251.081529) (xy 167.10038 -251.100275) (xy 167.085998 -251.114598)
			(xy 167.06722 -251.122304) (xy 167.05707 -251.122688) (xy 165.65753 -251.122688) (xy 165.647409 -251.12215)
			(xy 165.628693 -251.114437) (xy 165.614337 -251.100167) (xy 165.606512 -251.081498) (xy 165.605968 -251.07138)
			(xy 159.564832 -251.07138) (xy 159.564363 -251.081529) (xy 159.55658 -251.100275) (xy 159.542198 -251.114598)
			(xy 159.52342 -251.122304) (xy 159.51327 -251.122688) (xy 158.11373 -251.122688) (xy 158.103609 -251.12215)
			(xy 158.084893 -251.114437) (xy 158.070537 -251.100167) (xy 158.062712 -251.081498) (xy 158.062168 -251.07138)
			(xy 148.050944 -251.07138) (xy 148.083876 -251.178143) (xy 148.115426 -251.307429) (xy 148.139189 -251.43837)
			(xy 148.155078 -251.570498) (xy 148.163036 -251.70334) (xy 148.163534 -251.76988) (xy 148.163036 -251.83642)
			(xy 148.157938 -251.921518) (xy 162.162236 -251.921518) (xy 162.162236 -251.512578) (xy 162.162715 -251.502419)
			(xy 162.170496 -251.48365) (xy 162.184867 -251.469285) (xy 162.203639 -251.461511) (xy 162.213798 -251.461016)
			(xy 163.613338 -251.461016) (xy 163.623495 -251.461502) (xy 163.642261 -251.469285) (xy 163.656624 -251.483652)
			(xy 163.664401 -251.50242) (xy 163.6649 -251.512578) (xy 163.6649 -251.921518) (xy 169.706036 -251.921518)
			(xy 169.706036 -251.512578) (xy 169.706515 -251.502419) (xy 169.714296 -251.48365) (xy 169.728667 -251.469285)
			(xy 169.747439 -251.461511) (xy 169.757598 -251.461016) (xy 171.157138 -251.461016) (xy 171.167295 -251.461502)
			(xy 171.186061 -251.469285) (xy 171.200424 -251.483652) (xy 171.208201 -251.50242) (xy 171.2087 -251.512578)
			(xy 171.2087 -251.921518) (xy 177.249836 -251.921518) (xy 177.249836 -251.512578) (xy 177.250315 -251.502419)
			(xy 177.258096 -251.48365) (xy 177.272467 -251.469285) (xy 177.291239 -251.461511) (xy 177.301398 -251.461016)
			(xy 178.700938 -251.461016) (xy 178.711095 -251.461502) (xy 178.729861 -251.469285) (xy 178.744224 -251.483652)
			(xy 178.752001 -251.50242) (xy 178.7525 -251.512578) (xy 178.7525 -251.921518) (xy 184.793636 -251.921518)
			(xy 184.793636 -251.512578) (xy 184.794115 -251.502419) (xy 184.801896 -251.48365) (xy 184.816267 -251.469285)
			(xy 184.835039 -251.461511) (xy 184.845198 -251.461016) (xy 186.244738 -251.461016) (xy 186.254895 -251.461502)
			(xy 186.273661 -251.469285) (xy 186.288024 -251.483652) (xy 186.295801 -251.50242) (xy 186.2963 -251.512578)
			(xy 186.2963 -251.921518) (xy 192.337436 -251.921518) (xy 192.337436 -251.512578) (xy 192.337915 -251.502419)
			(xy 192.345696 -251.48365) (xy 192.360067 -251.469285) (xy 192.378839 -251.461511) (xy 192.388998 -251.461016)
			(xy 193.788538 -251.461016) (xy 193.798695 -251.461502) (xy 193.817461 -251.469285) (xy 193.831824 -251.483652)
			(xy 193.839601 -251.50242) (xy 193.8401 -251.512578) (xy 193.8401 -251.921518) (xy 199.881236 -251.921518)
			(xy 199.881236 -251.512578) (xy 199.881715 -251.502419) (xy 199.889496 -251.48365) (xy 199.903867 -251.469285)
			(xy 199.922639 -251.461511) (xy 199.932798 -251.461016) (xy 201.332338 -251.461016) (xy 201.342495 -251.461502)
			(xy 201.361261 -251.469285) (xy 201.375624 -251.483652) (xy 201.383401 -251.50242) (xy 201.3839 -251.512578)
			(xy 201.3839 -251.921518) (xy 207.425036 -251.921518) (xy 207.425036 -251.512578) (xy 207.425515 -251.502419)
			(xy 207.433296 -251.48365) (xy 207.447667 -251.469285) (xy 207.466439 -251.461511) (xy 207.476598 -251.461016)
			(xy 208.876138 -251.461016) (xy 208.886295 -251.461502) (xy 208.905061 -251.469285) (xy 208.919424 -251.483652)
			(xy 208.927201 -251.50242) (xy 208.9277 -251.512578) (xy 208.9277 -251.921518) (xy 214.968836 -251.921518)
			(xy 214.968836 -251.512578) (xy 214.969315 -251.502419) (xy 214.977096 -251.48365) (xy 214.991467 -251.469285)
			(xy 215.010239 -251.461511) (xy 215.020398 -251.461016) (xy 216.419938 -251.461016) (xy 216.430095 -251.461502)
			(xy 216.448861 -251.469285) (xy 216.463224 -251.483652) (xy 216.471001 -251.50242) (xy 216.4715 -251.512578)
			(xy 216.4715 -251.921518) (xy 259.429504 -251.921518) (xy 259.429504 -251.512578) (xy 259.430014 -251.502423)
			(xy 259.43779 -251.48366) (xy 259.45215 -251.469296) (xy 259.470911 -251.461517) (xy 259.481066 -251.461016)
			(xy 260.880606 -251.461016) (xy 260.890761 -251.461528) (xy 260.909526 -251.4693) (xy 260.923891 -251.48366)
			(xy 260.931669 -251.502423) (xy 260.932168 -251.512578) (xy 260.932168 -251.921518) (xy 266.973304 -251.921518)
			(xy 266.973304 -251.512578) (xy 266.973814 -251.502423) (xy 266.98159 -251.48366) (xy 266.99595 -251.469296)
			(xy 267.014711 -251.461517) (xy 267.024866 -251.461016) (xy 268.424406 -251.461016) (xy 268.434561 -251.461528)
			(xy 268.453326 -251.4693) (xy 268.467691 -251.48366) (xy 268.475469 -251.502423) (xy 268.475968 -251.512578)
			(xy 268.475968 -251.921518) (xy 274.517104 -251.921518) (xy 274.517104 -251.512578) (xy 274.517614 -251.502423)
			(xy 274.52539 -251.48366) (xy 274.53975 -251.469296) (xy 274.558511 -251.461517) (xy 274.568666 -251.461016)
			(xy 275.968206 -251.461016) (xy 275.978361 -251.461528) (xy 275.997126 -251.4693) (xy 276.011491 -251.48366)
			(xy 276.019269 -251.502423) (xy 276.019768 -251.512578) (xy 276.019768 -251.921518) (xy 282.060904 -251.921518)
			(xy 282.060904 -251.512578) (xy 282.061414 -251.502423) (xy 282.06919 -251.48366) (xy 282.08355 -251.469296)
			(xy 282.102311 -251.461517) (xy 282.112466 -251.461016) (xy 283.512006 -251.461016) (xy 283.522161 -251.461528)
			(xy 283.540926 -251.4693) (xy 283.555291 -251.48366) (xy 283.563069 -251.502423) (xy 283.563568 -251.512578)
			(xy 283.563568 -251.921518) (xy 289.604704 -251.921518) (xy 289.604704 -251.512578) (xy 289.605214 -251.502423)
			(xy 289.61299 -251.48366) (xy 289.62735 -251.469296) (xy 289.646111 -251.461517) (xy 289.656266 -251.461016)
			(xy 291.055806 -251.461016) (xy 291.065961 -251.461528) (xy 291.084726 -251.4693) (xy 291.099091 -251.48366)
			(xy 291.106869 -251.502423) (xy 291.107368 -251.512578) (xy 291.107368 -251.921518) (xy 297.148504 -251.921518)
			(xy 297.148504 -251.512578) (xy 297.149014 -251.502423) (xy 297.15679 -251.48366) (xy 297.17115 -251.469296)
			(xy 297.189911 -251.461517) (xy 297.200066 -251.461016) (xy 298.599606 -251.461016) (xy 298.609761 -251.461528)
			(xy 298.628526 -251.4693) (xy 298.642891 -251.48366) (xy 298.650669 -251.502423) (xy 298.651168 -251.512578)
			(xy 298.651168 -251.921518) (xy 304.692304 -251.921518) (xy 304.692304 -251.512578) (xy 304.692814 -251.502423)
			(xy 304.70059 -251.48366) (xy 304.71495 -251.469296) (xy 304.733711 -251.461517) (xy 304.743866 -251.461016)
			(xy 306.143406 -251.461016) (xy 306.153561 -251.461528) (xy 306.172326 -251.4693) (xy 306.186691 -251.48366)
			(xy 306.194469 -251.502423) (xy 306.194968 -251.512578) (xy 306.194968 -251.921518) (xy 312.236104 -251.921518)
			(xy 312.236104 -251.512578) (xy 312.236614 -251.502423) (xy 312.24439 -251.48366) (xy 312.25875 -251.469296)
			(xy 312.277511 -251.461517) (xy 312.287666 -251.461016) (xy 313.687206 -251.461016) (xy 313.697361 -251.461528)
			(xy 313.716126 -251.4693) (xy 313.730491 -251.48366) (xy 313.738269 -251.502423) (xy 313.738768 -251.512578)
			(xy 313.738768 -251.76988) (xy 323.635634 -251.76988) (xy 323.639615 -251.63686) (xy 323.651544 -251.504315)
			(xy 323.671379 -251.372722) (xy 323.699048 -251.24255) (xy 323.734452 -251.114265) (xy 323.777465 -250.988328)
			(xy 323.827932 -250.865189) (xy 323.885673 -250.745288) (xy 323.950482 -250.629055) (xy 324.022126 -250.516905)
			(xy 324.100348 -250.409241) (xy 324.184869 -250.306448) (xy 324.275387 -250.208893) (xy 324.371576 -250.116927)
			(xy 324.473094 -250.030877) (xy 324.579575 -249.951053) (xy 324.69064 -249.87774) (xy 324.805891 -249.8112)
			(xy 324.924915 -249.751671) (xy 325.047286 -249.699367) (xy 325.172565 -249.654475) (xy 325.300306 -249.617156)
			(xy 325.430049 -249.587543) (xy 325.561331 -249.565742) (xy 325.693682 -249.551832) (xy 325.826628 -249.545861)
			(xy 325.959693 -249.547852) (xy 326.092401 -249.557797) (xy 326.224277 -249.575661) (xy 326.354848 -249.601379)
			(xy 326.483648 -249.63486) (xy 326.610214 -249.675984) (xy 326.734095 -249.724604) (xy 326.854846 -249.780545)
			(xy 326.972036 -249.843607) (xy 327.085245 -249.913565) (xy 327.194067 -249.990169) (xy 327.298113 -250.073143)
			(xy 327.397011 -250.162191) (xy 327.490406 -250.256994) (xy 327.577964 -250.357212) (xy 327.659373 -250.462488)
			(xy 327.734339 -250.572444) (xy 327.802596 -250.686686) (xy 327.863898 -250.804806) (xy 327.918027 -250.926381)
			(xy 327.964788 -251.050975) (xy 328.004014 -251.178143) (xy 328.035564 -251.307429) (xy 328.059327 -251.43837)
			(xy 328.075216 -251.570498) (xy 328.083174 -251.70334) (xy 328.083672 -251.76988) (xy 391.655564 -251.76988)
			(xy 391.659545 -251.63686) (xy 391.671474 -251.504315) (xy 391.691309 -251.372722) (xy 391.718978 -251.24255)
			(xy 391.754382 -251.114265) (xy 391.797395 -250.988328) (xy 391.847862 -250.865189) (xy 391.905603 -250.745288)
			(xy 391.970412 -250.629055) (xy 392.042056 -250.516905) (xy 392.120278 -250.409241) (xy 392.204799 -250.306448)
			(xy 392.295317 -250.208893) (xy 392.391506 -250.116927) (xy 392.493024 -250.030877) (xy 392.599505 -249.951053)
			(xy 392.71057 -249.87774) (xy 392.825821 -249.8112) (xy 392.944845 -249.751671) (xy 393.067216 -249.699367)
			(xy 393.192495 -249.654475) (xy 393.320236 -249.617156) (xy 393.449979 -249.587543) (xy 393.581261 -249.565742)
			(xy 393.713612 -249.551832) (xy 393.846558 -249.545861) (xy 393.979623 -249.547852) (xy 394.112331 -249.557797)
			(xy 394.244207 -249.575661) (xy 394.374778 -249.601379) (xy 394.503578 -249.63486) (xy 394.630144 -249.675984)
			(xy 394.754025 -249.724604) (xy 394.874776 -249.780545) (xy 394.991966 -249.843607) (xy 395.105175 -249.913565)
			(xy 395.213997 -249.990169) (xy 395.318043 -250.073143) (xy 395.416941 -250.162191) (xy 395.475365 -250.221496)
			(xy 410.102304 -250.221496) (xy 410.102304 -249.812556) (xy 410.102686 -249.802399) (xy 410.110497 -249.783644)
			(xy 410.124905 -249.769323) (xy 410.143706 -249.761625) (xy 410.153866 -249.761248) (xy 411.553406 -249.761248)
			(xy 411.563534 -249.761722) (xy 411.582257 -249.769453) (xy 411.596613 -249.783743) (xy 411.604431 -249.80243)
			(xy 411.604968 -249.812556) (xy 411.604968 -250.221496) (xy 417.646104 -250.221496) (xy 417.646104 -249.812556)
			(xy 417.646486 -249.802399) (xy 417.654297 -249.783644) (xy 417.668705 -249.769323) (xy 417.687506 -249.761625)
			(xy 417.697666 -249.761248) (xy 419.097206 -249.761248) (xy 419.107334 -249.761722) (xy 419.126057 -249.769453)
			(xy 419.140413 -249.783743) (xy 419.148231 -249.80243) (xy 419.148768 -249.812556) (xy 419.148768 -250.221496)
			(xy 425.189904 -250.221496) (xy 425.189904 -249.812556) (xy 425.190286 -249.802399) (xy 425.198097 -249.783644)
			(xy 425.212505 -249.769323) (xy 425.231306 -249.761625) (xy 425.241466 -249.761248) (xy 426.641006 -249.761248)
			(xy 426.651134 -249.761722) (xy 426.669857 -249.769453) (xy 426.684213 -249.783743) (xy 426.692031 -249.80243)
			(xy 426.692568 -249.812556) (xy 426.692568 -250.221496) (xy 432.733704 -250.221496) (xy 432.733704 -249.812556)
			(xy 432.734086 -249.802399) (xy 432.741897 -249.783644) (xy 432.756305 -249.769323) (xy 432.775106 -249.761625)
			(xy 432.785266 -249.761248) (xy 434.184806 -249.761248) (xy 434.194934 -249.761722) (xy 434.213657 -249.769453)
			(xy 434.228013 -249.783743) (xy 434.235831 -249.80243) (xy 434.236368 -249.812556) (xy 434.236368 -250.221496)
			(xy 440.277504 -250.221496) (xy 440.277504 -249.812556) (xy 440.277886 -249.802399) (xy 440.285697 -249.783644)
			(xy 440.300105 -249.769323) (xy 440.318906 -249.761625) (xy 440.329066 -249.761248) (xy 441.728606 -249.761248)
			(xy 441.738734 -249.761722) (xy 441.757457 -249.769453) (xy 441.771813 -249.783743) (xy 441.779631 -249.80243)
			(xy 441.780168 -249.812556) (xy 441.780168 -250.221496) (xy 447.821304 -250.221496) (xy 447.821304 -249.812556)
			(xy 447.821686 -249.802399) (xy 447.829497 -249.783644) (xy 447.843905 -249.769323) (xy 447.862706 -249.761625)
			(xy 447.872866 -249.761248) (xy 449.272406 -249.761248) (xy 449.282534 -249.761722) (xy 449.301257 -249.769453)
			(xy 449.315613 -249.783743) (xy 449.323431 -249.80243) (xy 449.323968 -249.812556) (xy 449.323968 -250.221496)
			(xy 455.365104 -250.221496) (xy 455.365104 -249.812556) (xy 455.365486 -249.802399) (xy 455.373297 -249.783644)
			(xy 455.387705 -249.769323) (xy 455.406506 -249.761625) (xy 455.416666 -249.761248) (xy 456.816206 -249.761248)
			(xy 456.826334 -249.761722) (xy 456.845057 -249.769453) (xy 456.859413 -249.783743) (xy 456.867231 -249.80243)
			(xy 456.867768 -249.812556) (xy 456.867768 -250.221496) (xy 462.908904 -250.221496) (xy 462.908904 -249.812556)
			(xy 462.909286 -249.802399) (xy 462.917097 -249.783644) (xy 462.931505 -249.769323) (xy 462.950306 -249.761625)
			(xy 462.960466 -249.761248) (xy 464.360006 -249.761248) (xy 464.370134 -249.761722) (xy 464.388857 -249.769453)
			(xy 464.403213 -249.783743) (xy 464.411031 -249.80243) (xy 464.411568 -249.812556) (xy 464.411568 -250.221496)
			(xy 464.411174 -250.231654) (xy 464.403374 -250.250412) (xy 464.388968 -250.264737) (xy 464.370166 -250.272431)
			(xy 464.360006 -250.272804) (xy 462.960466 -250.272804) (xy 462.950343 -250.272303) (xy 462.931629 -250.264572)
			(xy 462.917275 -250.250291) (xy 462.90945 -250.231617) (xy 462.908904 -250.221496) (xy 456.867768 -250.221496)
			(xy 456.867374 -250.231654) (xy 456.859574 -250.250412) (xy 456.845168 -250.264737) (xy 456.826366 -250.272431)
			(xy 456.816206 -250.272804) (xy 455.416666 -250.272804) (xy 455.406543 -250.272303) (xy 455.387829 -250.264572)
			(xy 455.373475 -250.250291) (xy 455.36565 -250.231617) (xy 455.365104 -250.221496) (xy 449.323968 -250.221496)
			(xy 449.323574 -250.231654) (xy 449.315774 -250.250412) (xy 449.301368 -250.264737) (xy 449.282566 -250.272431)
			(xy 449.272406 -250.272804) (xy 447.872866 -250.272804) (xy 447.862743 -250.272303) (xy 447.844029 -250.264572)
			(xy 447.829675 -250.250291) (xy 447.82185 -250.231617) (xy 447.821304 -250.221496) (xy 441.780168 -250.221496)
			(xy 441.779774 -250.231654) (xy 441.771974 -250.250412) (xy 441.757568 -250.264737) (xy 441.738766 -250.272431)
			(xy 441.728606 -250.272804) (xy 440.329066 -250.272804) (xy 440.318943 -250.272303) (xy 440.300229 -250.264572)
			(xy 440.285875 -250.250291) (xy 440.27805 -250.231617) (xy 440.277504 -250.221496) (xy 434.236368 -250.221496)
			(xy 434.235974 -250.231654) (xy 434.228174 -250.250412) (xy 434.213768 -250.264737) (xy 434.194966 -250.272431)
			(xy 434.184806 -250.272804) (xy 432.785266 -250.272804) (xy 432.775143 -250.272303) (xy 432.756429 -250.264572)
			(xy 432.742075 -250.250291) (xy 432.73425 -250.231617) (xy 432.733704 -250.221496) (xy 426.692568 -250.221496)
			(xy 426.692174 -250.231654) (xy 426.684374 -250.250412) (xy 426.669968 -250.264737) (xy 426.651166 -250.272431)
			(xy 426.641006 -250.272804) (xy 425.241466 -250.272804) (xy 425.231343 -250.272303) (xy 425.212629 -250.264572)
			(xy 425.198275 -250.250291) (xy 425.19045 -250.231617) (xy 425.189904 -250.221496) (xy 419.148768 -250.221496)
			(xy 419.148374 -250.231654) (xy 419.140574 -250.250412) (xy 419.126168 -250.264737) (xy 419.107366 -250.272431)
			(xy 419.097206 -250.272804) (xy 417.697666 -250.272804) (xy 417.687543 -250.272303) (xy 417.668829 -250.264572)
			(xy 417.654475 -250.250291) (xy 417.64665 -250.231617) (xy 417.646104 -250.221496) (xy 411.604968 -250.221496)
			(xy 411.604574 -250.231654) (xy 411.596774 -250.250412) (xy 411.582368 -250.264737) (xy 411.563566 -250.272431)
			(xy 411.553406 -250.272804) (xy 410.153866 -250.272804) (xy 410.143743 -250.272303) (xy 410.125029 -250.264572)
			(xy 410.110675 -250.250291) (xy 410.10285 -250.231617) (xy 410.102304 -250.221496) (xy 395.475365 -250.221496)
			(xy 395.510336 -250.256994) (xy 395.597894 -250.357212) (xy 395.679303 -250.462488) (xy 395.754269 -250.572444)
			(xy 395.822526 -250.686686) (xy 395.883828 -250.804806) (xy 395.937957 -250.926381) (xy 395.984718 -251.050975)
			(xy 395.991012 -251.07138) (xy 406.002236 -251.07138) (xy 406.002236 -250.66244) (xy 406.002655 -250.652284)
			(xy 406.010444 -250.633526) (xy 406.024843 -250.6192) (xy 406.04364 -250.611505) (xy 406.053798 -250.611132)
			(xy 407.453338 -250.611132) (xy 407.463466 -250.611595) (xy 407.482187 -250.619334) (xy 407.496541 -250.633627)
			(xy 407.504361 -250.652314) (xy 407.5049 -250.66244) (xy 407.5049 -251.07138) (xy 413.546036 -251.07138)
			(xy 413.546036 -250.66244) (xy 413.546455 -250.652284) (xy 413.554244 -250.633526) (xy 413.568643 -250.6192)
			(xy 413.58744 -250.611505) (xy 413.597598 -250.611132) (xy 414.997138 -250.611132) (xy 415.007266 -250.611595)
			(xy 415.025987 -250.619334) (xy 415.040341 -250.633627) (xy 415.048161 -250.652314) (xy 415.0487 -250.66244)
			(xy 415.0487 -251.07138) (xy 421.089836 -251.07138) (xy 421.089836 -250.66244) (xy 421.090255 -250.652284)
			(xy 421.098044 -250.633526) (xy 421.112443 -250.6192) (xy 421.13124 -250.611505) (xy 421.141398 -250.611132)
			(xy 422.540938 -250.611132) (xy 422.551066 -250.611595) (xy 422.569787 -250.619334) (xy 422.584141 -250.633627)
			(xy 422.591961 -250.652314) (xy 422.5925 -250.66244) (xy 422.5925 -251.07138) (xy 428.633636 -251.07138)
			(xy 428.633636 -250.66244) (xy 428.634055 -250.652284) (xy 428.641844 -250.633526) (xy 428.656243 -250.6192)
			(xy 428.67504 -250.611505) (xy 428.685198 -250.611132) (xy 430.084738 -250.611132) (xy 430.094866 -250.611595)
			(xy 430.113587 -250.619334) (xy 430.127941 -250.633627) (xy 430.135761 -250.652314) (xy 430.1363 -250.66244)
			(xy 430.1363 -251.07138) (xy 436.177436 -251.07138) (xy 436.177436 -250.66244) (xy 436.177855 -250.652284)
			(xy 436.185644 -250.633526) (xy 436.200043 -250.6192) (xy 436.21884 -250.611505) (xy 436.228998 -250.611132)
			(xy 437.628538 -250.611132) (xy 437.638666 -250.611595) (xy 437.657387 -250.619334) (xy 437.671741 -250.633627)
			(xy 437.679561 -250.652314) (xy 437.6801 -250.66244) (xy 437.6801 -251.07138) (xy 443.721236 -251.07138)
			(xy 443.721236 -250.66244) (xy 443.721655 -250.652284) (xy 443.729444 -250.633526) (xy 443.743843 -250.6192)
			(xy 443.76264 -250.611505) (xy 443.772798 -250.611132) (xy 445.172338 -250.611132) (xy 445.182466 -250.611595)
			(xy 445.201187 -250.619334) (xy 445.215541 -250.633627) (xy 445.223361 -250.652314) (xy 445.2239 -250.66244)
			(xy 445.2239 -251.07138) (xy 451.265036 -251.07138) (xy 451.265036 -250.66244) (xy 451.265455 -250.652284)
			(xy 451.273244 -250.633526) (xy 451.287643 -250.6192) (xy 451.30644 -250.611505) (xy 451.316598 -250.611132)
			(xy 452.716138 -250.611132) (xy 452.726266 -250.611595) (xy 452.744987 -250.619334) (xy 452.759341 -250.633627)
			(xy 452.767161 -250.652314) (xy 452.7677 -250.66244) (xy 452.7677 -251.07138) (xy 458.808836 -251.07138)
			(xy 458.808836 -250.66244) (xy 458.809255 -250.652284) (xy 458.817044 -250.633526) (xy 458.831443 -250.6192)
			(xy 458.85024 -250.611505) (xy 458.860398 -250.611132) (xy 460.259938 -250.611132) (xy 460.270066 -250.611595)
			(xy 460.288787 -250.619334) (xy 460.303141 -250.633627) (xy 460.310961 -250.652314) (xy 460.3115 -250.66244)
			(xy 460.3115 -251.07138) (xy 460.311062 -251.081533) (xy 460.303273 -251.100285) (xy 460.288881 -251.114609)
			(xy 460.270093 -251.122309) (xy 460.259938 -251.122688) (xy 458.860398 -251.122688) (xy 458.850275 -251.122176)
			(xy 458.831559 -251.114453) (xy 458.817204 -251.100175) (xy 458.80938 -251.081501) (xy 458.808836 -251.07138)
			(xy 452.7677 -251.07138) (xy 452.767262 -251.081533) (xy 452.759473 -251.100285) (xy 452.745081 -251.114609)
			(xy 452.726293 -251.122309) (xy 452.716138 -251.122688) (xy 451.316598 -251.122688) (xy 451.306475 -251.122176)
			(xy 451.287759 -251.114453) (xy 451.273404 -251.100175) (xy 451.26558 -251.081501) (xy 451.265036 -251.07138)
			(xy 445.2239 -251.07138) (xy 445.223462 -251.081533) (xy 445.215673 -251.100285) (xy 445.201281 -251.114609)
			(xy 445.182493 -251.122309) (xy 445.172338 -251.122688) (xy 443.772798 -251.122688) (xy 443.762675 -251.122176)
			(xy 443.743959 -251.114453) (xy 443.729604 -251.100175) (xy 443.72178 -251.081501) (xy 443.721236 -251.07138)
			(xy 437.6801 -251.07138) (xy 437.679662 -251.081533) (xy 437.671873 -251.100285) (xy 437.657481 -251.114609)
			(xy 437.638693 -251.122309) (xy 437.628538 -251.122688) (xy 436.228998 -251.122688) (xy 436.218875 -251.122176)
			(xy 436.200159 -251.114453) (xy 436.185804 -251.100175) (xy 436.17798 -251.081501) (xy 436.177436 -251.07138)
			(xy 430.1363 -251.07138) (xy 430.135862 -251.081533) (xy 430.128073 -251.100285) (xy 430.113681 -251.114609)
			(xy 430.094893 -251.122309) (xy 430.084738 -251.122688) (xy 428.685198 -251.122688) (xy 428.675075 -251.122176)
			(xy 428.656359 -251.114453) (xy 428.642004 -251.100175) (xy 428.63418 -251.081501) (xy 428.633636 -251.07138)
			(xy 422.5925 -251.07138) (xy 422.592062 -251.081533) (xy 422.584273 -251.100285) (xy 422.569881 -251.114609)
			(xy 422.551093 -251.122309) (xy 422.540938 -251.122688) (xy 421.141398 -251.122688) (xy 421.131275 -251.122176)
			(xy 421.112559 -251.114453) (xy 421.098204 -251.100175) (xy 421.09038 -251.081501) (xy 421.089836 -251.07138)
			(xy 415.0487 -251.07138) (xy 415.048262 -251.081533) (xy 415.040473 -251.100285) (xy 415.026081 -251.114609)
			(xy 415.007293 -251.122309) (xy 414.997138 -251.122688) (xy 413.597598 -251.122688) (xy 413.587475 -251.122176)
			(xy 413.568759 -251.114453) (xy 413.554404 -251.100175) (xy 413.54658 -251.081501) (xy 413.546036 -251.07138)
			(xy 407.5049 -251.07138) (xy 407.504462 -251.081533) (xy 407.496673 -251.100285) (xy 407.482281 -251.114609)
			(xy 407.463493 -251.122309) (xy 407.453338 -251.122688) (xy 406.053798 -251.122688) (xy 406.043675 -251.122176)
			(xy 406.024959 -251.114453) (xy 406.010604 -251.100175) (xy 406.00278 -251.081501) (xy 406.002236 -251.07138)
			(xy 395.991012 -251.07138) (xy 396.023944 -251.178143) (xy 396.055494 -251.307429) (xy 396.079257 -251.43837)
			(xy 396.095146 -251.570498) (xy 396.103104 -251.70334) (xy 396.103602 -251.76988) (xy 396.103104 -251.83642)
			(xy 396.098006 -251.921518) (xy 410.102304 -251.921518) (xy 410.102304 -251.512578) (xy 410.102814 -251.502423)
			(xy 410.11059 -251.48366) (xy 410.12495 -251.469296) (xy 410.143711 -251.461517) (xy 410.153866 -251.461016)
			(xy 411.553406 -251.461016) (xy 411.563561 -251.461528) (xy 411.582326 -251.4693) (xy 411.596691 -251.48366)
			(xy 411.604469 -251.502423) (xy 411.604968 -251.512578) (xy 411.604968 -251.921518) (xy 417.646104 -251.921518)
			(xy 417.646104 -251.512578) (xy 417.646614 -251.502423) (xy 417.65439 -251.48366) (xy 417.66875 -251.469296)
			(xy 417.687511 -251.461517) (xy 417.697666 -251.461016) (xy 419.097206 -251.461016) (xy 419.107361 -251.461528)
			(xy 419.126126 -251.4693) (xy 419.140491 -251.48366) (xy 419.148269 -251.502423) (xy 419.148768 -251.512578)
			(xy 419.148768 -251.921518) (xy 425.189904 -251.921518) (xy 425.189904 -251.512578) (xy 425.190414 -251.502423)
			(xy 425.19819 -251.48366) (xy 425.21255 -251.469296) (xy 425.231311 -251.461517) (xy 425.241466 -251.461016)
			(xy 426.641006 -251.461016) (xy 426.651161 -251.461528) (xy 426.669926 -251.4693) (xy 426.684291 -251.48366)
			(xy 426.692069 -251.502423) (xy 426.692568 -251.512578) (xy 426.692568 -251.921518) (xy 432.733704 -251.921518)
			(xy 432.733704 -251.512578) (xy 432.734214 -251.502423) (xy 432.74199 -251.48366) (xy 432.75635 -251.469296)
			(xy 432.775111 -251.461517) (xy 432.785266 -251.461016) (xy 434.184806 -251.461016) (xy 434.194961 -251.461528)
			(xy 434.213726 -251.4693) (xy 434.228091 -251.48366) (xy 434.235869 -251.502423) (xy 434.236368 -251.512578)
			(xy 434.236368 -251.921518) (xy 440.277504 -251.921518) (xy 440.277504 -251.512578) (xy 440.278014 -251.502423)
			(xy 440.28579 -251.48366) (xy 440.30015 -251.469296) (xy 440.318911 -251.461517) (xy 440.329066 -251.461016)
			(xy 441.728606 -251.461016) (xy 441.738761 -251.461528) (xy 441.757526 -251.4693) (xy 441.771891 -251.48366)
			(xy 441.779669 -251.502423) (xy 441.780168 -251.512578) (xy 441.780168 -251.921518) (xy 447.821304 -251.921518)
			(xy 447.821304 -251.512578) (xy 447.821814 -251.502423) (xy 447.82959 -251.48366) (xy 447.84395 -251.469296)
			(xy 447.862711 -251.461517) (xy 447.872866 -251.461016) (xy 449.272406 -251.461016) (xy 449.282561 -251.461528)
			(xy 449.301326 -251.4693) (xy 449.315691 -251.48366) (xy 449.323469 -251.502423) (xy 449.323968 -251.512578)
			(xy 449.323968 -251.921518) (xy 455.365104 -251.921518) (xy 455.365104 -251.512578) (xy 455.365614 -251.502423)
			(xy 455.37339 -251.48366) (xy 455.38775 -251.469296) (xy 455.406511 -251.461517) (xy 455.416666 -251.461016)
			(xy 456.816206 -251.461016) (xy 456.826361 -251.461528) (xy 456.845126 -251.4693) (xy 456.859491 -251.48366)
			(xy 456.867269 -251.502423) (xy 456.867768 -251.512578) (xy 456.867768 -251.921518) (xy 462.908904 -251.921518)
			(xy 462.908904 -251.512578) (xy 462.909414 -251.502423) (xy 462.91719 -251.48366) (xy 462.93155 -251.469296)
			(xy 462.950311 -251.461517) (xy 462.960466 -251.461016) (xy 464.360006 -251.461016) (xy 464.370161 -251.461528)
			(xy 464.388926 -251.4693) (xy 464.403291 -251.48366) (xy 464.411069 -251.502423) (xy 464.411568 -251.512578)
			(xy 464.411568 -251.921518) (xy 464.411082 -251.931676) (xy 464.403302 -251.950445) (xy 464.388935 -251.964809)
			(xy 464.370164 -251.972584) (xy 464.360006 -251.97308) (xy 462.960466 -251.97308) (xy 462.950308 -251.972595)
			(xy 462.931542 -251.964813) (xy 462.917178 -251.950445) (xy 462.909402 -251.931676) (xy 462.908904 -251.921518)
			(xy 456.867768 -251.921518) (xy 456.867282 -251.931676) (xy 456.859502 -251.950445) (xy 456.845135 -251.964809)
			(xy 456.826364 -251.972584) (xy 456.816206 -251.97308) (xy 455.416666 -251.97308) (xy 455.406508 -251.972595)
			(xy 455.387742 -251.964813) (xy 455.373378 -251.950445) (xy 455.365602 -251.931676) (xy 455.365104 -251.921518)
			(xy 449.323968 -251.921518) (xy 449.323482 -251.931676) (xy 449.315702 -251.950445) (xy 449.301335 -251.964809)
			(xy 449.282564 -251.972584) (xy 449.272406 -251.97308) (xy 447.872866 -251.97308) (xy 447.862708 -251.972595)
			(xy 447.843942 -251.964813) (xy 447.829578 -251.950445) (xy 447.821802 -251.931676) (xy 447.821304 -251.921518)
			(xy 441.780168 -251.921518) (xy 441.779682 -251.931676) (xy 441.771902 -251.950445) (xy 441.757535 -251.964809)
			(xy 441.738764 -251.972584) (xy 441.728606 -251.97308) (xy 440.329066 -251.97308) (xy 440.318908 -251.972595)
			(xy 440.300142 -251.964813) (xy 440.285778 -251.950445) (xy 440.278002 -251.931676) (xy 440.277504 -251.921518)
			(xy 434.236368 -251.921518) (xy 434.235882 -251.931676) (xy 434.228102 -251.950445) (xy 434.213735 -251.964809)
			(xy 434.194964 -251.972584) (xy 434.184806 -251.97308) (xy 432.785266 -251.97308) (xy 432.775108 -251.972595)
			(xy 432.756342 -251.964813) (xy 432.741978 -251.950445) (xy 432.734202 -251.931676) (xy 432.733704 -251.921518)
			(xy 426.692568 -251.921518) (xy 426.692082 -251.931676) (xy 426.684302 -251.950445) (xy 426.669935 -251.964809)
			(xy 426.651164 -251.972584) (xy 426.641006 -251.97308) (xy 425.241466 -251.97308) (xy 425.231308 -251.972595)
			(xy 425.212542 -251.964813) (xy 425.198178 -251.950445) (xy 425.190402 -251.931676) (xy 425.189904 -251.921518)
			(xy 419.148768 -251.921518) (xy 419.148282 -251.931676) (xy 419.140502 -251.950445) (xy 419.126135 -251.964809)
			(xy 419.107364 -251.972584) (xy 419.097206 -251.97308) (xy 417.697666 -251.97308) (xy 417.687508 -251.972595)
			(xy 417.668742 -251.964813) (xy 417.654378 -251.950445) (xy 417.646602 -251.931676) (xy 417.646104 -251.921518)
			(xy 411.604968 -251.921518) (xy 411.604482 -251.931676) (xy 411.596702 -251.950445) (xy 411.582335 -251.964809)
			(xy 411.563564 -251.972584) (xy 411.553406 -251.97308) (xy 410.153866 -251.97308) (xy 410.143708 -251.972595)
			(xy 410.124942 -251.964813) (xy 410.110578 -251.950445) (xy 410.102802 -251.931676) (xy 410.102304 -251.921518)
			(xy 396.098006 -251.921518) (xy 396.095146 -251.969262) (xy 396.079257 -252.10139) (xy 396.055494 -252.232331)
			(xy 396.023944 -252.361617) (xy 395.984718 -252.488785) (xy 395.937957 -252.613379) (xy 395.883828 -252.734954)
			(xy 395.864912 -252.771402) (xy 406.002236 -252.771402) (xy 406.002236 -252.362462) (xy 406.002702 -252.352302)
			(xy 406.010489 -252.333532) (xy 406.024863 -252.319169) (xy 406.043638 -252.311395) (xy 406.053798 -252.3109)
			(xy 407.453338 -252.3109) (xy 407.463494 -252.311401) (xy 407.482256 -252.319181) (xy 407.496619 -252.333544)
			(xy 407.504399 -252.352306) (xy 407.5049 -252.362462) (xy 407.5049 -252.771402) (xy 413.546036 -252.771402)
			(xy 413.546036 -252.362462) (xy 413.546502 -252.352302) (xy 413.554289 -252.333532) (xy 413.568663 -252.319169)
			(xy 413.587438 -252.311395) (xy 413.597598 -252.3109) (xy 414.997138 -252.3109) (xy 415.007294 -252.311401)
			(xy 415.026056 -252.319181) (xy 415.040419 -252.333544) (xy 415.048199 -252.352306) (xy 415.0487 -252.362462)
			(xy 415.0487 -252.771402) (xy 421.089836 -252.771402) (xy 421.089836 -252.362462) (xy 421.090302 -252.352302)
			(xy 421.098089 -252.333532) (xy 421.112463 -252.319169) (xy 421.131238 -252.311395) (xy 421.141398 -252.3109)
			(xy 422.540938 -252.3109) (xy 422.551094 -252.311401) (xy 422.569856 -252.319181) (xy 422.584219 -252.333544)
			(xy 422.591999 -252.352306) (xy 422.5925 -252.362462) (xy 422.5925 -252.771402) (xy 428.633636 -252.771402)
			(xy 428.633636 -252.362462) (xy 428.634102 -252.352302) (xy 428.641889 -252.333532) (xy 428.656263 -252.319169)
			(xy 428.675038 -252.311395) (xy 428.685198 -252.3109) (xy 430.084738 -252.3109) (xy 430.094894 -252.311401)
			(xy 430.113656 -252.319181) (xy 430.128019 -252.333544) (xy 430.135799 -252.352306) (xy 430.1363 -252.362462)
			(xy 430.1363 -252.771402) (xy 436.177436 -252.771402) (xy 436.177436 -252.362462) (xy 436.177902 -252.352302)
			(xy 436.185689 -252.333532) (xy 436.200063 -252.319169) (xy 436.218838 -252.311395) (xy 436.228998 -252.3109)
			(xy 437.628538 -252.3109) (xy 437.638694 -252.311401) (xy 437.657456 -252.319181) (xy 437.671819 -252.333544)
			(xy 437.679599 -252.352306) (xy 437.6801 -252.362462) (xy 437.6801 -252.771402) (xy 443.721236 -252.771402)
			(xy 443.721236 -252.362462) (xy 443.721702 -252.352302) (xy 443.729489 -252.333532) (xy 443.743863 -252.319169)
			(xy 443.762638 -252.311395) (xy 443.772798 -252.3109) (xy 445.172338 -252.3109) (xy 445.182494 -252.311401)
			(xy 445.201256 -252.319181) (xy 445.215619 -252.333544) (xy 445.223399 -252.352306) (xy 445.2239 -252.362462)
			(xy 445.2239 -252.771402) (xy 451.265036 -252.771402) (xy 451.265036 -252.362462) (xy 451.265502 -252.352302)
			(xy 451.273289 -252.333532) (xy 451.287663 -252.319169) (xy 451.306438 -252.311395) (xy 451.316598 -252.3109)
			(xy 452.716138 -252.3109) (xy 452.726294 -252.311401) (xy 452.745056 -252.319181) (xy 452.759419 -252.333544)
			(xy 452.767199 -252.352306) (xy 452.7677 -252.362462) (xy 452.7677 -252.771402) (xy 458.808836 -252.771402)
			(xy 458.808836 -252.362462) (xy 458.809302 -252.352302) (xy 458.817089 -252.333532) (xy 458.831463 -252.319169)
			(xy 458.850238 -252.311395) (xy 458.860398 -252.3109) (xy 460.259938 -252.3109) (xy 460.270094 -252.311401)
			(xy 460.288856 -252.319181) (xy 460.303219 -252.333544) (xy 460.310999 -252.352306) (xy 460.3115 -252.362462)
			(xy 460.3115 -252.771402) (xy 460.310969 -252.781555) (xy 460.303201 -252.800317) (xy 460.288847 -252.814681)
			(xy 460.270091 -252.822462) (xy 460.259938 -252.822964) (xy 458.860398 -252.822964) (xy 458.85024 -252.822468)
			(xy 458.831472 -252.814694) (xy 458.817106 -252.800328) (xy 458.809332 -252.78156) (xy 458.808836 -252.771402)
			(xy 452.7677 -252.771402) (xy 452.767169 -252.781555) (xy 452.759401 -252.800317) (xy 452.745047 -252.814681)
			(xy 452.726291 -252.822462) (xy 452.716138 -252.822964) (xy 451.316598 -252.822964) (xy 451.30644 -252.822468)
			(xy 451.287672 -252.814694) (xy 451.273306 -252.800328) (xy 451.265532 -252.78156) (xy 451.265036 -252.771402)
			(xy 445.2239 -252.771402) (xy 445.223369 -252.781555) (xy 445.215601 -252.800317) (xy 445.201247 -252.814681)
			(xy 445.182491 -252.822462) (xy 445.172338 -252.822964) (xy 443.772798 -252.822964) (xy 443.76264 -252.822468)
			(xy 443.743872 -252.814694) (xy 443.729506 -252.800328) (xy 443.721732 -252.78156) (xy 443.721236 -252.771402)
			(xy 437.6801 -252.771402) (xy 437.679569 -252.781555) (xy 437.671801 -252.800317) (xy 437.657447 -252.814681)
			(xy 437.638691 -252.822462) (xy 437.628538 -252.822964) (xy 436.228998 -252.822964) (xy 436.21884 -252.822468)
			(xy 436.200072 -252.814694) (xy 436.185706 -252.800328) (xy 436.177932 -252.78156) (xy 436.177436 -252.771402)
			(xy 430.1363 -252.771402) (xy 430.135769 -252.781555) (xy 430.128001 -252.800317) (xy 430.113647 -252.814681)
			(xy 430.094891 -252.822462) (xy 430.084738 -252.822964) (xy 428.685198 -252.822964) (xy 428.67504 -252.822468)
			(xy 428.656272 -252.814694) (xy 428.641906 -252.800328) (xy 428.634132 -252.78156) (xy 428.633636 -252.771402)
			(xy 422.5925 -252.771402) (xy 422.591969 -252.781555) (xy 422.584201 -252.800317) (xy 422.569847 -252.814681)
			(xy 422.551091 -252.822462) (xy 422.540938 -252.822964) (xy 421.141398 -252.822964) (xy 421.13124 -252.822468)
			(xy 421.112472 -252.814694) (xy 421.098106 -252.800328) (xy 421.090332 -252.78156) (xy 421.089836 -252.771402)
			(xy 415.0487 -252.771402) (xy 415.048169 -252.781555) (xy 415.040401 -252.800317) (xy 415.026047 -252.814681)
			(xy 415.007291 -252.822462) (xy 414.997138 -252.822964) (xy 413.597598 -252.822964) (xy 413.58744 -252.822468)
			(xy 413.568672 -252.814694) (xy 413.554306 -252.800328) (xy 413.546532 -252.78156) (xy 413.546036 -252.771402)
			(xy 407.5049 -252.771402) (xy 407.504369 -252.781555) (xy 407.496601 -252.800317) (xy 407.482247 -252.814681)
			(xy 407.463491 -252.822462) (xy 407.453338 -252.822964) (xy 406.053798 -252.822964) (xy 406.04364 -252.822468)
			(xy 406.024872 -252.814694) (xy 406.010506 -252.800328) (xy 406.002732 -252.78156) (xy 406.002236 -252.771402)
			(xy 395.864912 -252.771402) (xy 395.822526 -252.853074) (xy 395.754269 -252.967316) (xy 395.679303 -253.077272)
			(xy 395.597894 -253.182548) (xy 395.510336 -253.282766) (xy 395.416941 -253.377569) (xy 395.318043 -253.466617)
			(xy 395.213997 -253.549591) (xy 395.105175 -253.626195) (xy 394.991966 -253.696153) (xy 394.874776 -253.759215)
			(xy 394.754025 -253.815156) (xy 394.630144 -253.863776) (xy 394.503578 -253.9049) (xy 394.374778 -253.938381)
			(xy 394.244207 -253.964099) (xy 394.112331 -253.981963) (xy 393.979623 -253.991908) (xy 393.846558 -253.993899)
			(xy 393.713612 -253.987928) (xy 393.581261 -253.974018) (xy 393.449979 -253.952217) (xy 393.320236 -253.922604)
			(xy 393.192495 -253.885285) (xy 393.067216 -253.840393) (xy 392.944845 -253.788089) (xy 392.825821 -253.72856)
			(xy 392.71057 -253.66202) (xy 392.599505 -253.588707) (xy 392.493024 -253.508883) (xy 392.391506 -253.422833)
			(xy 392.295317 -253.330867) (xy 392.204799 -253.233312) (xy 392.120278 -253.130519) (xy 392.042056 -253.022855)
			(xy 391.970412 -252.910705) (xy 391.905603 -252.794472) (xy 391.847862 -252.674571) (xy 391.797395 -252.551432)
			(xy 391.754382 -252.425495) (xy 391.718978 -252.29721) (xy 391.691309 -252.167038) (xy 391.671474 -252.035445)
			(xy 391.659545 -251.9029) (xy 391.655564 -251.76988) (xy 328.083672 -251.76988) (xy 328.083174 -251.83642)
			(xy 328.075216 -251.969262) (xy 328.059327 -252.10139) (xy 328.035564 -252.232331) (xy 328.004014 -252.361617)
			(xy 327.964788 -252.488785) (xy 327.918027 -252.613379) (xy 327.863898 -252.734954) (xy 327.802596 -252.853074)
			(xy 327.734339 -252.967316) (xy 327.659373 -253.077272) (xy 327.577964 -253.182548) (xy 327.490406 -253.282766)
			(xy 327.397011 -253.377569) (xy 327.298113 -253.466617) (xy 327.194067 -253.549591) (xy 327.085245 -253.626195)
			(xy 326.972036 -253.696153) (xy 326.854846 -253.759215) (xy 326.734095 -253.815156) (xy 326.610214 -253.863776)
			(xy 326.483648 -253.9049) (xy 326.354848 -253.938381) (xy 326.224277 -253.964099) (xy 326.092401 -253.981963)
			(xy 325.959693 -253.991908) (xy 325.826628 -253.993899) (xy 325.693682 -253.987928) (xy 325.561331 -253.974018)
			(xy 325.430049 -253.952217) (xy 325.300306 -253.922604) (xy 325.172565 -253.885285) (xy 325.047286 -253.840393)
			(xy 324.924915 -253.788089) (xy 324.805891 -253.72856) (xy 324.69064 -253.66202) (xy 324.579575 -253.588707)
			(xy 324.473094 -253.508883) (xy 324.371576 -253.422833) (xy 324.275387 -253.330867) (xy 324.184869 -253.233312)
			(xy 324.100348 -253.130519) (xy 324.022126 -253.022855) (xy 323.950482 -252.910705) (xy 323.885673 -252.794472)
			(xy 323.827932 -252.674571) (xy 323.777465 -252.551432) (xy 323.734452 -252.425495) (xy 323.699048 -252.29721)
			(xy 323.671379 -252.167038) (xy 323.651544 -252.035445) (xy 323.639615 -251.9029) (xy 323.635634 -251.76988)
			(xy 313.738768 -251.76988) (xy 313.738768 -251.921518) (xy 313.738282 -251.931676) (xy 313.730502 -251.950445)
			(xy 313.716135 -251.964809) (xy 313.697364 -251.972584) (xy 313.687206 -251.97308) (xy 312.287666 -251.97308)
			(xy 312.277508 -251.972595) (xy 312.258742 -251.964813) (xy 312.244378 -251.950445) (xy 312.236602 -251.931676)
			(xy 312.236104 -251.921518) (xy 306.194968 -251.921518) (xy 306.194482 -251.931676) (xy 306.186702 -251.950445)
			(xy 306.172335 -251.964809) (xy 306.153564 -251.972584) (xy 306.143406 -251.97308) (xy 304.743866 -251.97308)
			(xy 304.733708 -251.972595) (xy 304.714942 -251.964813) (xy 304.700578 -251.950445) (xy 304.692802 -251.931676)
			(xy 304.692304 -251.921518) (xy 298.651168 -251.921518) (xy 298.650682 -251.931676) (xy 298.642902 -251.950445)
			(xy 298.628535 -251.964809) (xy 298.609764 -251.972584) (xy 298.599606 -251.97308) (xy 297.200066 -251.97308)
			(xy 297.189908 -251.972595) (xy 297.171142 -251.964813) (xy 297.156778 -251.950445) (xy 297.149002 -251.931676)
			(xy 297.148504 -251.921518) (xy 291.107368 -251.921518) (xy 291.106882 -251.931676) (xy 291.099102 -251.950445)
			(xy 291.084735 -251.964809) (xy 291.065964 -251.972584) (xy 291.055806 -251.97308) (xy 289.656266 -251.97308)
			(xy 289.646108 -251.972595) (xy 289.627342 -251.964813) (xy 289.612978 -251.950445) (xy 289.605202 -251.931676)
			(xy 289.604704 -251.921518) (xy 283.563568 -251.921518) (xy 283.563082 -251.931676) (xy 283.555302 -251.950445)
			(xy 283.540935 -251.964809) (xy 283.522164 -251.972584) (xy 283.512006 -251.97308) (xy 282.112466 -251.97308)
			(xy 282.102308 -251.972595) (xy 282.083542 -251.964813) (xy 282.069178 -251.950445) (xy 282.061402 -251.931676)
			(xy 282.060904 -251.921518) (xy 276.019768 -251.921518) (xy 276.019282 -251.931676) (xy 276.011502 -251.950445)
			(xy 275.997135 -251.964809) (xy 275.978364 -251.972584) (xy 275.968206 -251.97308) (xy 274.568666 -251.97308)
			(xy 274.558508 -251.972595) (xy 274.539742 -251.964813) (xy 274.525378 -251.950445) (xy 274.517602 -251.931676)
			(xy 274.517104 -251.921518) (xy 268.475968 -251.921518) (xy 268.475482 -251.931676) (xy 268.467702 -251.950445)
			(xy 268.453335 -251.964809) (xy 268.434564 -251.972584) (xy 268.424406 -251.97308) (xy 267.024866 -251.97308)
			(xy 267.014708 -251.972595) (xy 266.995942 -251.964813) (xy 266.981578 -251.950445) (xy 266.973802 -251.931676)
			(xy 266.973304 -251.921518) (xy 260.932168 -251.921518) (xy 260.931682 -251.931676) (xy 260.923902 -251.950445)
			(xy 260.909535 -251.964809) (xy 260.890764 -251.972584) (xy 260.880606 -251.97308) (xy 259.481066 -251.97308)
			(xy 259.470908 -251.972595) (xy 259.452142 -251.964813) (xy 259.437778 -251.950445) (xy 259.430002 -251.931676)
			(xy 259.429504 -251.921518) (xy 216.4715 -251.921518) (xy 216.470983 -251.931672) (xy 216.463209 -251.950435)
			(xy 216.448851 -251.964798) (xy 216.430092 -251.972579) (xy 216.419938 -251.97308) (xy 215.020398 -251.97308)
			(xy 215.010242 -251.972569) (xy 214.991477 -251.964797) (xy 214.977112 -251.950437) (xy 214.969335 -251.931674)
			(xy 214.968836 -251.921518) (xy 208.9277 -251.921518) (xy 208.927183 -251.931672) (xy 208.919409 -251.950435)
			(xy 208.905051 -251.964798) (xy 208.886292 -251.972579) (xy 208.876138 -251.97308) (xy 207.476598 -251.97308)
			(xy 207.466442 -251.972569) (xy 207.447677 -251.964797) (xy 207.433312 -251.950437) (xy 207.425535 -251.931674)
			(xy 207.425036 -251.921518) (xy 201.3839 -251.921518) (xy 201.383383 -251.931672) (xy 201.375609 -251.950435)
			(xy 201.361251 -251.964798) (xy 201.342492 -251.972579) (xy 201.332338 -251.97308) (xy 199.932798 -251.97308)
			(xy 199.922642 -251.972569) (xy 199.903877 -251.964797) (xy 199.889512 -251.950437) (xy 199.881735 -251.931674)
			(xy 199.881236 -251.921518) (xy 193.8401 -251.921518) (xy 193.839583 -251.931672) (xy 193.831809 -251.950435)
			(xy 193.817451 -251.964798) (xy 193.798692 -251.972579) (xy 193.788538 -251.97308) (xy 192.388998 -251.97308)
			(xy 192.378842 -251.972569) (xy 192.360077 -251.964797) (xy 192.345712 -251.950437) (xy 192.337935 -251.931674)
			(xy 192.337436 -251.921518) (xy 186.2963 -251.921518) (xy 186.295783 -251.931672) (xy 186.288009 -251.950435)
			(xy 186.273651 -251.964798) (xy 186.254892 -251.972579) (xy 186.244738 -251.97308) (xy 184.845198 -251.97308)
			(xy 184.835042 -251.972569) (xy 184.816277 -251.964797) (xy 184.801912 -251.950437) (xy 184.794135 -251.931674)
			(xy 184.793636 -251.921518) (xy 178.7525 -251.921518) (xy 178.751983 -251.931672) (xy 178.744209 -251.950435)
			(xy 178.729851 -251.964798) (xy 178.711092 -251.972579) (xy 178.700938 -251.97308) (xy 177.301398 -251.97308)
			(xy 177.291242 -251.972569) (xy 177.272477 -251.964797) (xy 177.258112 -251.950437) (xy 177.250335 -251.931674)
			(xy 177.249836 -251.921518) (xy 171.2087 -251.921518) (xy 171.208183 -251.931672) (xy 171.200409 -251.950435)
			(xy 171.186051 -251.964798) (xy 171.167292 -251.972579) (xy 171.157138 -251.97308) (xy 169.757598 -251.97308)
			(xy 169.747442 -251.972569) (xy 169.728677 -251.964797) (xy 169.714312 -251.950437) (xy 169.706535 -251.931674)
			(xy 169.706036 -251.921518) (xy 163.6649 -251.921518) (xy 163.664383 -251.931672) (xy 163.656609 -251.950435)
			(xy 163.642251 -251.964798) (xy 163.623492 -251.972579) (xy 163.613338 -251.97308) (xy 162.213798 -251.97308)
			(xy 162.203642 -251.972569) (xy 162.184877 -251.964797) (xy 162.170512 -251.950437) (xy 162.162735 -251.931674)
			(xy 162.162236 -251.921518) (xy 148.157938 -251.921518) (xy 148.155078 -251.969262) (xy 148.139189 -252.10139)
			(xy 148.115426 -252.232331) (xy 148.083876 -252.361617) (xy 148.04465 -252.488785) (xy 147.997889 -252.613379)
			(xy 147.94376 -252.734954) (xy 147.924844 -252.771402) (xy 158.062168 -252.771402) (xy 158.062168 -252.362462)
			(xy 158.062603 -252.352298) (xy 158.070396 -252.333522) (xy 158.084779 -252.319157) (xy 158.103565 -252.31139)
			(xy 158.11373 -252.3109) (xy 159.51327 -252.3109) (xy 159.523421 -252.311457) (xy 159.542183 -252.319214)
			(xy 159.556548 -252.33356) (xy 159.56433 -252.352311) (xy 159.564832 -252.362462) (xy 159.564832 -252.771402)
			(xy 165.605968 -252.771402) (xy 165.605968 -252.362462) (xy 165.606403 -252.352298) (xy 165.614196 -252.333522)
			(xy 165.628579 -252.319157) (xy 165.647365 -252.31139) (xy 165.65753 -252.3109) (xy 167.05707 -252.3109)
			(xy 167.067221 -252.311457) (xy 167.085983 -252.319214) (xy 167.100348 -252.33356) (xy 167.10813 -252.352311)
			(xy 167.108632 -252.362462) (xy 167.108632 -252.771402) (xy 173.149768 -252.771402) (xy 173.149768 -252.362462)
			(xy 173.150203 -252.352298) (xy 173.157996 -252.333522) (xy 173.172379 -252.319157) (xy 173.191165 -252.31139)
			(xy 173.20133 -252.3109) (xy 174.60087 -252.3109) (xy 174.611021 -252.311457) (xy 174.629783 -252.319214)
			(xy 174.644148 -252.33356) (xy 174.65193 -252.352311) (xy 174.652432 -252.362462) (xy 174.652432 -252.771402)
			(xy 180.693568 -252.771402) (xy 180.693568 -252.362462) (xy 180.694003 -252.352298) (xy 180.701796 -252.333522)
			(xy 180.716179 -252.319157) (xy 180.734965 -252.31139) (xy 180.74513 -252.3109) (xy 182.14467 -252.3109)
			(xy 182.154821 -252.311457) (xy 182.173583 -252.319214) (xy 182.187948 -252.33356) (xy 182.19573 -252.352311)
			(xy 182.196232 -252.362462) (xy 182.196232 -252.771402) (xy 188.237368 -252.771402) (xy 188.237368 -252.362462)
			(xy 188.237803 -252.352298) (xy 188.245596 -252.333522) (xy 188.259979 -252.319157) (xy 188.278765 -252.31139)
			(xy 188.28893 -252.3109) (xy 189.68847 -252.3109) (xy 189.698621 -252.311457) (xy 189.717383 -252.319214)
			(xy 189.731748 -252.33356) (xy 189.73953 -252.352311) (xy 189.740032 -252.362462) (xy 189.740032 -252.771402)
			(xy 195.781168 -252.771402) (xy 195.781168 -252.362462) (xy 195.781603 -252.352298) (xy 195.789396 -252.333522)
			(xy 195.803779 -252.319157) (xy 195.822565 -252.31139) (xy 195.83273 -252.3109) (xy 197.23227 -252.3109)
			(xy 197.242421 -252.311457) (xy 197.261183 -252.319214) (xy 197.275548 -252.33356) (xy 197.28333 -252.352311)
			(xy 197.283832 -252.362462) (xy 197.283832 -252.771402) (xy 203.324968 -252.771402) (xy 203.324968 -252.362462)
			(xy 203.325403 -252.352298) (xy 203.333196 -252.333522) (xy 203.347579 -252.319157) (xy 203.366365 -252.31139)
			(xy 203.37653 -252.3109) (xy 204.77607 -252.3109) (xy 204.786221 -252.311457) (xy 204.804983 -252.319214)
			(xy 204.819348 -252.33356) (xy 204.82713 -252.352311) (xy 204.827632 -252.362462) (xy 204.827632 -252.771402)
			(xy 210.868768 -252.771402) (xy 210.868768 -252.362462) (xy 210.869203 -252.352298) (xy 210.876996 -252.333522)
			(xy 210.891379 -252.319157) (xy 210.910165 -252.31139) (xy 210.92033 -252.3109) (xy 212.31987 -252.3109)
			(xy 212.330021 -252.311457) (xy 212.348783 -252.319214) (xy 212.363148 -252.33356) (xy 212.37093 -252.352311)
			(xy 212.371432 -252.362462) (xy 212.371432 -252.771402) (xy 255.329436 -252.771402) (xy 255.329436 -252.362462)
			(xy 255.329902 -252.352302) (xy 255.337689 -252.333532) (xy 255.352063 -252.319169) (xy 255.370838 -252.311395)
			(xy 255.380998 -252.3109) (xy 256.780538 -252.3109) (xy 256.790694 -252.311401) (xy 256.809456 -252.319181)
			(xy 256.823819 -252.333544) (xy 256.831599 -252.352306) (xy 256.8321 -252.362462) (xy 256.8321 -252.771402)
			(xy 262.873236 -252.771402) (xy 262.873236 -252.362462) (xy 262.873702 -252.352302) (xy 262.881489 -252.333532)
			(xy 262.895863 -252.319169) (xy 262.914638 -252.311395) (xy 262.924798 -252.3109) (xy 264.324338 -252.3109)
			(xy 264.334494 -252.311401) (xy 264.353256 -252.319181) (xy 264.367619 -252.333544) (xy 264.375399 -252.352306)
			(xy 264.3759 -252.362462) (xy 264.3759 -252.771402) (xy 270.417036 -252.771402) (xy 270.417036 -252.362462)
			(xy 270.417502 -252.352302) (xy 270.425289 -252.333532) (xy 270.439663 -252.319169) (xy 270.458438 -252.311395)
			(xy 270.468598 -252.3109) (xy 271.868138 -252.3109) (xy 271.878294 -252.311401) (xy 271.897056 -252.319181)
			(xy 271.911419 -252.333544) (xy 271.919199 -252.352306) (xy 271.9197 -252.362462) (xy 271.9197 -252.771402)
			(xy 277.960836 -252.771402) (xy 277.960836 -252.362462) (xy 277.961302 -252.352302) (xy 277.969089 -252.333532)
			(xy 277.983463 -252.319169) (xy 278.002238 -252.311395) (xy 278.012398 -252.3109) (xy 279.411938 -252.3109)
			(xy 279.422094 -252.311401) (xy 279.440856 -252.319181) (xy 279.455219 -252.333544) (xy 279.462999 -252.352306)
			(xy 279.4635 -252.362462) (xy 279.4635 -252.771402) (xy 285.504636 -252.771402) (xy 285.504636 -252.362462)
			(xy 285.505102 -252.352302) (xy 285.512889 -252.333532) (xy 285.527263 -252.319169) (xy 285.546038 -252.311395)
			(xy 285.556198 -252.3109) (xy 286.955738 -252.3109) (xy 286.965894 -252.311401) (xy 286.984656 -252.319181)
			(xy 286.999019 -252.333544) (xy 287.006799 -252.352306) (xy 287.0073 -252.362462) (xy 287.0073 -252.771402)
			(xy 293.048436 -252.771402) (xy 293.048436 -252.362462) (xy 293.048902 -252.352302) (xy 293.056689 -252.333532)
			(xy 293.071063 -252.319169) (xy 293.089838 -252.311395) (xy 293.099998 -252.3109) (xy 294.499538 -252.3109)
			(xy 294.509694 -252.311401) (xy 294.528456 -252.319181) (xy 294.542819 -252.333544) (xy 294.550599 -252.352306)
			(xy 294.5511 -252.362462) (xy 294.5511 -252.771402) (xy 300.592236 -252.771402) (xy 300.592236 -252.362462)
			(xy 300.592702 -252.352302) (xy 300.600489 -252.333532) (xy 300.614863 -252.319169) (xy 300.633638 -252.311395)
			(xy 300.643798 -252.3109) (xy 302.043338 -252.3109) (xy 302.053494 -252.311401) (xy 302.072256 -252.319181)
			(xy 302.086619 -252.333544) (xy 302.094399 -252.352306) (xy 302.0949 -252.362462) (xy 302.0949 -252.771402)
			(xy 308.136036 -252.771402) (xy 308.136036 -252.362462) (xy 308.136502 -252.352302) (xy 308.144289 -252.333532)
			(xy 308.158663 -252.319169) (xy 308.177438 -252.311395) (xy 308.187598 -252.3109) (xy 309.587138 -252.3109)
			(xy 309.597294 -252.311401) (xy 309.616056 -252.319181) (xy 309.630419 -252.333544) (xy 309.638199 -252.352306)
			(xy 309.6387 -252.362462) (xy 309.6387 -252.771402) (xy 309.638169 -252.781555) (xy 309.630401 -252.800317)
			(xy 309.616047 -252.814681) (xy 309.597291 -252.822462) (xy 309.587138 -252.822964) (xy 308.187598 -252.822964)
			(xy 308.17744 -252.822468) (xy 308.158672 -252.814694) (xy 308.144306 -252.800328) (xy 308.136532 -252.78156)
			(xy 308.136036 -252.771402) (xy 302.0949 -252.771402) (xy 302.094369 -252.781555) (xy 302.086601 -252.800317)
			(xy 302.072247 -252.814681) (xy 302.053491 -252.822462) (xy 302.043338 -252.822964) (xy 300.643798 -252.822964)
			(xy 300.63364 -252.822468) (xy 300.614872 -252.814694) (xy 300.600506 -252.800328) (xy 300.592732 -252.78156)
			(xy 300.592236 -252.771402) (xy 294.5511 -252.771402) (xy 294.550569 -252.781555) (xy 294.542801 -252.800317)
			(xy 294.528447 -252.814681) (xy 294.509691 -252.822462) (xy 294.499538 -252.822964) (xy 293.099998 -252.822964)
			(xy 293.08984 -252.822468) (xy 293.071072 -252.814694) (xy 293.056706 -252.800328) (xy 293.048932 -252.78156)
			(xy 293.048436 -252.771402) (xy 287.0073 -252.771402) (xy 287.006769 -252.781555) (xy 286.999001 -252.800317)
			(xy 286.984647 -252.814681) (xy 286.965891 -252.822462) (xy 286.955738 -252.822964) (xy 285.556198 -252.822964)
			(xy 285.54604 -252.822468) (xy 285.527272 -252.814694) (xy 285.512906 -252.800328) (xy 285.505132 -252.78156)
			(xy 285.504636 -252.771402) (xy 279.4635 -252.771402) (xy 279.462969 -252.781555) (xy 279.455201 -252.800317)
			(xy 279.440847 -252.814681) (xy 279.422091 -252.822462) (xy 279.411938 -252.822964) (xy 278.012398 -252.822964)
			(xy 278.00224 -252.822468) (xy 277.983472 -252.814694) (xy 277.969106 -252.800328) (xy 277.961332 -252.78156)
			(xy 277.960836 -252.771402) (xy 271.9197 -252.771402) (xy 271.919169 -252.781555) (xy 271.911401 -252.800317)
			(xy 271.897047 -252.814681) (xy 271.878291 -252.822462) (xy 271.868138 -252.822964) (xy 270.468598 -252.822964)
			(xy 270.45844 -252.822468) (xy 270.439672 -252.814694) (xy 270.425306 -252.800328) (xy 270.417532 -252.78156)
			(xy 270.417036 -252.771402) (xy 264.3759 -252.771402) (xy 264.375369 -252.781555) (xy 264.367601 -252.800317)
			(xy 264.353247 -252.814681) (xy 264.334491 -252.822462) (xy 264.324338 -252.822964) (xy 262.924798 -252.822964)
			(xy 262.91464 -252.822468) (xy 262.895872 -252.814694) (xy 262.881506 -252.800328) (xy 262.873732 -252.78156)
			(xy 262.873236 -252.771402) (xy 256.8321 -252.771402) (xy 256.831569 -252.781555) (xy 256.823801 -252.800317)
			(xy 256.809447 -252.814681) (xy 256.790691 -252.822462) (xy 256.780538 -252.822964) (xy 255.380998 -252.822964)
			(xy 255.37084 -252.822468) (xy 255.352072 -252.814694) (xy 255.337706 -252.800328) (xy 255.329932 -252.78156)
			(xy 255.329436 -252.771402) (xy 212.371432 -252.771402) (xy 212.371037 -252.781577) (xy 212.363246 -252.800378)
			(xy 212.348851 -252.814764) (xy 212.330046 -252.822543) (xy 212.31987 -252.822964) (xy 210.92033 -252.822964)
			(xy 210.910161 -252.822511) (xy 210.891367 -252.814737) (xy 210.876981 -252.80036) (xy 210.869195 -252.781571)
			(xy 210.868768 -252.771402) (xy 204.827632 -252.771402) (xy 204.827237 -252.781577) (xy 204.819446 -252.800378)
			(xy 204.805051 -252.814764) (xy 204.786246 -252.822543) (xy 204.77607 -252.822964) (xy 203.37653 -252.822964)
			(xy 203.366361 -252.822511) (xy 203.347567 -252.814737) (xy 203.333181 -252.80036) (xy 203.325395 -252.781571)
			(xy 203.324968 -252.771402) (xy 197.283832 -252.771402) (xy 197.283437 -252.781577) (xy 197.275646 -252.800378)
			(xy 197.261251 -252.814764) (xy 197.242446 -252.822543) (xy 197.23227 -252.822964) (xy 195.83273 -252.822964)
			(xy 195.822561 -252.822511) (xy 195.803767 -252.814737) (xy 195.789381 -252.80036) (xy 195.781595 -252.781571)
			(xy 195.781168 -252.771402) (xy 189.740032 -252.771402) (xy 189.739637 -252.781577) (xy 189.731846 -252.800378)
			(xy 189.717451 -252.814764) (xy 189.698646 -252.822543) (xy 189.68847 -252.822964) (xy 188.28893 -252.822964)
			(xy 188.278761 -252.822511) (xy 188.259967 -252.814737) (xy 188.245581 -252.80036) (xy 188.237795 -252.781571)
			(xy 188.237368 -252.771402) (xy 182.196232 -252.771402) (xy 182.195837 -252.781577) (xy 182.188046 -252.800378)
			(xy 182.173651 -252.814764) (xy 182.154846 -252.822543) (xy 182.14467 -252.822964) (xy 180.74513 -252.822964)
			(xy 180.734961 -252.822511) (xy 180.716167 -252.814737) (xy 180.701781 -252.80036) (xy 180.693995 -252.781571)
			(xy 180.693568 -252.771402) (xy 174.652432 -252.771402) (xy 174.652037 -252.781577) (xy 174.644246 -252.800378)
			(xy 174.629851 -252.814764) (xy 174.611046 -252.822543) (xy 174.60087 -252.822964) (xy 173.20133 -252.822964)
			(xy 173.191161 -252.822511) (xy 173.172367 -252.814737) (xy 173.157981 -252.80036) (xy 173.150195 -252.781571)
			(xy 173.149768 -252.771402) (xy 167.108632 -252.771402) (xy 167.108237 -252.781577) (xy 167.100446 -252.800378)
			(xy 167.086051 -252.814764) (xy 167.067246 -252.822543) (xy 167.05707 -252.822964) (xy 165.65753 -252.822964)
			(xy 165.647361 -252.822511) (xy 165.628567 -252.814737) (xy 165.614181 -252.80036) (xy 165.606395 -252.781571)
			(xy 165.605968 -252.771402) (xy 159.564832 -252.771402) (xy 159.564437 -252.781577) (xy 159.556646 -252.800378)
			(xy 159.542251 -252.814764) (xy 159.523446 -252.822543) (xy 159.51327 -252.822964) (xy 158.11373 -252.822964)
			(xy 158.103561 -252.822511) (xy 158.084767 -252.814737) (xy 158.070381 -252.80036) (xy 158.062595 -252.781571)
			(xy 158.062168 -252.771402) (xy 147.924844 -252.771402) (xy 147.882458 -252.853074) (xy 147.814201 -252.967316)
			(xy 147.739235 -253.077272) (xy 147.657826 -253.182548) (xy 147.570268 -253.282766) (xy 147.476873 -253.377569)
			(xy 147.377975 -253.466617) (xy 147.273929 -253.549591) (xy 147.165107 -253.626195) (xy 147.051898 -253.696153)
			(xy 146.934708 -253.759215) (xy 146.813957 -253.815156) (xy 146.690076 -253.863776) (xy 146.56351 -253.9049)
			(xy 146.43471 -253.938381) (xy 146.304139 -253.964099) (xy 146.172263 -253.981963) (xy 146.039555 -253.991908)
			(xy 145.90649 -253.993899) (xy 145.773544 -253.987928) (xy 145.641193 -253.974018) (xy 145.509911 -253.952217)
			(xy 145.380168 -253.922604) (xy 145.252427 -253.885285) (xy 145.127148 -253.840393) (xy 145.004777 -253.788089)
			(xy 144.885753 -253.72856) (xy 144.770502 -253.66202) (xy 144.659437 -253.588707) (xy 144.552956 -253.508883)
			(xy 144.451438 -253.422833) (xy 144.355249 -253.330867) (xy 144.264731 -253.233312) (xy 144.18021 -253.130519)
			(xy 144.101988 -253.022855) (xy 144.030344 -252.910705) (xy 143.965535 -252.794472) (xy 143.907794 -252.674571)
			(xy 143.857327 -252.551432) (xy 143.814314 -252.425495) (xy 143.77891 -252.29721) (xy 143.751241 -252.167038)
			(xy 143.731406 -252.035445) (xy 143.719477 -251.9029) (xy 143.715496 -251.76988) (xy 80.143604 -251.76988)
			(xy 80.143106 -251.83642) (xy 80.135148 -251.969262) (xy 80.119259 -252.10139) (xy 80.095496 -252.232331)
			(xy 80.063946 -252.361617) (xy 80.02472 -252.488785) (xy 79.977959 -252.613379) (xy 79.92383 -252.734954)
			(xy 79.862528 -252.853074) (xy 79.794271 -252.967316) (xy 79.719305 -253.077272) (xy 79.637896 -253.182548)
			(xy 79.550338 -253.282766) (xy 79.456943 -253.377569) (xy 79.358045 -253.466617) (xy 79.253999 -253.549591)
			(xy 79.145177 -253.626195) (xy 79.031968 -253.696153) (xy 78.914778 -253.759215) (xy 78.794027 -253.815156)
			(xy 78.670146 -253.863776) (xy 78.54358 -253.9049) (xy 78.41478 -253.938381) (xy 78.284209 -253.964099)
			(xy 78.152333 -253.981963) (xy 78.019625 -253.991908) (xy 77.88656 -253.993899) (xy 77.753614 -253.987928)
			(xy 77.621263 -253.974018) (xy 77.489981 -253.952217) (xy 77.360238 -253.922604) (xy 77.232497 -253.885285)
			(xy 77.107218 -253.840393) (xy 76.984847 -253.788089) (xy 76.865823 -253.72856) (xy 76.750572 -253.66202)
			(xy 76.639507 -253.588707) (xy 76.533026 -253.508883) (xy 76.431508 -253.422833) (xy 76.335319 -253.330867)
			(xy 76.244801 -253.233312) (xy 76.16028 -253.130519) (xy 76.082058 -253.022855) (xy 76.010414 -252.910705)
			(xy 75.945605 -252.794472) (xy 75.887864 -252.674571) (xy 75.837397 -252.551432) (xy 75.794384 -252.425495)
			(xy 75.75898 -252.29721) (xy 75.731311 -252.167038) (xy 75.711476 -252.035445) (xy 75.699547 -251.9029)
			(xy 75.695566 -251.76988) (xy 65.7987 -251.76988) (xy 65.7987 -251.921518) (xy 65.798183 -251.931672)
			(xy 65.790409 -251.950435) (xy 65.776051 -251.964798) (xy 65.757292 -251.972579) (xy 65.747138 -251.97308)
			(xy 64.347598 -251.97308) (xy 64.337442 -251.972569) (xy 64.318677 -251.964797) (xy 64.304312 -251.950437)
			(xy 64.296535 -251.931674) (xy 64.296036 -251.921518) (xy 58.2549 -251.921518) (xy 58.254383 -251.931672)
			(xy 58.246609 -251.950435) (xy 58.232251 -251.964798) (xy 58.213492 -251.972579) (xy 58.203338 -251.97308)
			(xy 56.803798 -251.97308) (xy 56.793642 -251.972569) (xy 56.774877 -251.964797) (xy 56.760512 -251.950437)
			(xy 56.752735 -251.931674) (xy 56.752236 -251.921518) (xy 50.7111 -251.921518) (xy 50.710583 -251.931672)
			(xy 50.702809 -251.950435) (xy 50.688451 -251.964798) (xy 50.669692 -251.972579) (xy 50.659538 -251.97308)
			(xy 49.259998 -251.97308) (xy 49.249842 -251.972569) (xy 49.231077 -251.964797) (xy 49.216712 -251.950437)
			(xy 49.208935 -251.931674) (xy 49.208436 -251.921518) (xy 43.1673 -251.921518) (xy 43.166783 -251.931672)
			(xy 43.159009 -251.950435) (xy 43.144651 -251.964798) (xy 43.125892 -251.972579) (xy 43.115738 -251.97308)
			(xy 41.716198 -251.97308) (xy 41.706042 -251.972569) (xy 41.687277 -251.964797) (xy 41.672912 -251.950437)
			(xy 41.665135 -251.931674) (xy 41.664636 -251.921518) (xy 35.6235 -251.921518) (xy 35.622983 -251.931672)
			(xy 35.615209 -251.950435) (xy 35.600851 -251.964798) (xy 35.582092 -251.972579) (xy 35.571938 -251.97308)
			(xy 34.172398 -251.97308) (xy 34.162242 -251.972569) (xy 34.143477 -251.964797) (xy 34.129112 -251.950437)
			(xy 34.121335 -251.931674) (xy 34.120836 -251.921518) (xy 28.0797 -251.921518) (xy 28.079183 -251.931672)
			(xy 28.071409 -251.950435) (xy 28.057051 -251.964798) (xy 28.038292 -251.972579) (xy 28.028138 -251.97308)
			(xy 26.628598 -251.97308) (xy 26.618442 -251.972569) (xy 26.599677 -251.964797) (xy 26.585312 -251.950437)
			(xy 26.577535 -251.931674) (xy 26.577036 -251.921518) (xy 20.5359 -251.921518) (xy 20.535383 -251.931672)
			(xy 20.527609 -251.950435) (xy 20.513251 -251.964798) (xy 20.494492 -251.972579) (xy 20.484338 -251.97308)
			(xy 19.084798 -251.97308) (xy 19.074642 -251.972569) (xy 19.055877 -251.964797) (xy 19.041512 -251.950437)
			(xy 19.033735 -251.931674) (xy 19.033236 -251.921518) (xy 12.9921 -251.921518) (xy 12.991583 -251.931672)
			(xy 12.983809 -251.950435) (xy 12.969451 -251.964798) (xy 12.950692 -251.972579) (xy 12.940538 -251.97308)
			(xy 11.540998 -251.97308) (xy 11.530842 -251.972569) (xy 11.512077 -251.964797) (xy 11.497712 -251.950437)
			(xy 11.489935 -251.931674) (xy 11.489436 -251.921518) (xy 2.509012 -251.921518) (xy 2.509012 -252.771402)
			(xy 7.389368 -252.771402) (xy 7.389368 -252.362462) (xy 7.389803 -252.352298) (xy 7.397596 -252.333522)
			(xy 7.411979 -252.319157) (xy 7.430765 -252.31139) (xy 7.44093 -252.3109) (xy 8.84047 -252.3109)
			(xy 8.850621 -252.311457) (xy 8.869383 -252.319214) (xy 8.883748 -252.33356) (xy 8.89153 -252.352311)
			(xy 8.892032 -252.362462) (xy 8.892032 -252.771402) (xy 14.933168 -252.771402) (xy 14.933168 -252.362462)
			(xy 14.933603 -252.352298) (xy 14.941396 -252.333522) (xy 14.955779 -252.319157) (xy 14.974565 -252.31139)
			(xy 14.98473 -252.3109) (xy 16.38427 -252.3109) (xy 16.394421 -252.311457) (xy 16.413183 -252.319214)
			(xy 16.427548 -252.33356) (xy 16.43533 -252.352311) (xy 16.435832 -252.362462) (xy 16.435832 -252.771402)
			(xy 22.476968 -252.771402) (xy 22.476968 -252.362462) (xy 22.477403 -252.352298) (xy 22.485196 -252.333522)
			(xy 22.499579 -252.319157) (xy 22.518365 -252.31139) (xy 22.52853 -252.3109) (xy 23.92807 -252.3109)
			(xy 23.938221 -252.311457) (xy 23.956983 -252.319214) (xy 23.971348 -252.33356) (xy 23.97913 -252.352311)
			(xy 23.979632 -252.362462) (xy 23.979632 -252.771402) (xy 30.020768 -252.771402) (xy 30.020768 -252.362462)
			(xy 30.021203 -252.352298) (xy 30.028996 -252.333522) (xy 30.043379 -252.319157) (xy 30.062165 -252.31139)
			(xy 30.07233 -252.3109) (xy 31.47187 -252.3109) (xy 31.482021 -252.311457) (xy 31.500783 -252.319214)
			(xy 31.515148 -252.33356) (xy 31.52293 -252.352311) (xy 31.523432 -252.362462) (xy 31.523432 -252.771402)
			(xy 37.564568 -252.771402) (xy 37.564568 -252.362462) (xy 37.565003 -252.352298) (xy 37.572796 -252.333522)
			(xy 37.587179 -252.319157) (xy 37.605965 -252.31139) (xy 37.61613 -252.3109) (xy 39.01567 -252.3109)
			(xy 39.025821 -252.311457) (xy 39.044583 -252.319214) (xy 39.058948 -252.33356) (xy 39.06673 -252.352311)
			(xy 39.067232 -252.362462) (xy 39.067232 -252.771402) (xy 45.108368 -252.771402) (xy 45.108368 -252.362462)
			(xy 45.108803 -252.352298) (xy 45.116596 -252.333522) (xy 45.130979 -252.319157) (xy 45.149765 -252.31139)
			(xy 45.15993 -252.3109) (xy 46.55947 -252.3109) (xy 46.569621 -252.311457) (xy 46.588383 -252.319214)
			(xy 46.602748 -252.33356) (xy 46.61053 -252.352311) (xy 46.611032 -252.362462) (xy 46.611032 -252.771402)
			(xy 52.652168 -252.771402) (xy 52.652168 -252.362462) (xy 52.652603 -252.352298) (xy 52.660396 -252.333522)
			(xy 52.674779 -252.319157) (xy 52.693565 -252.31139) (xy 52.70373 -252.3109) (xy 54.10327 -252.3109)
			(xy 54.113421 -252.311457) (xy 54.132183 -252.319214) (xy 54.146548 -252.33356) (xy 54.15433 -252.352311)
			(xy 54.154832 -252.362462) (xy 54.154832 -252.771402) (xy 60.195968 -252.771402) (xy 60.195968 -252.362462)
			(xy 60.196403 -252.352298) (xy 60.204196 -252.333522) (xy 60.218579 -252.319157) (xy 60.237365 -252.31139)
			(xy 60.24753 -252.3109) (xy 61.64707 -252.3109) (xy 61.657221 -252.311457) (xy 61.675983 -252.319214)
			(xy 61.690348 -252.33356) (xy 61.69813 -252.352311) (xy 61.698632 -252.362462) (xy 61.698632 -252.771402)
			(xy 61.698237 -252.781577) (xy 61.690446 -252.800378) (xy 61.676051 -252.814764) (xy 61.657246 -252.822543)
			(xy 61.64707 -252.822964) (xy 60.24753 -252.822964) (xy 60.237361 -252.822511) (xy 60.218567 -252.814737)
			(xy 60.204181 -252.80036) (xy 60.196395 -252.781571) (xy 60.195968 -252.771402) (xy 54.154832 -252.771402)
			(xy 54.154437 -252.781577) (xy 54.146646 -252.800378) (xy 54.132251 -252.814764) (xy 54.113446 -252.822543)
			(xy 54.10327 -252.822964) (xy 52.70373 -252.822964) (xy 52.693561 -252.822511) (xy 52.674767 -252.814737)
			(xy 52.660381 -252.80036) (xy 52.652595 -252.781571) (xy 52.652168 -252.771402) (xy 46.611032 -252.771402)
			(xy 46.610637 -252.781577) (xy 46.602846 -252.800378) (xy 46.588451 -252.814764) (xy 46.569646 -252.822543)
			(xy 46.55947 -252.822964) (xy 45.15993 -252.822964) (xy 45.149761 -252.822511) (xy 45.130967 -252.814737)
			(xy 45.116581 -252.80036) (xy 45.108795 -252.781571) (xy 45.108368 -252.771402) (xy 39.067232 -252.771402)
			(xy 39.066837 -252.781577) (xy 39.059046 -252.800378) (xy 39.044651 -252.814764) (xy 39.025846 -252.822543)
			(xy 39.01567 -252.822964) (xy 37.61613 -252.822964) (xy 37.605961 -252.822511) (xy 37.587167 -252.814737)
			(xy 37.572781 -252.80036) (xy 37.564995 -252.781571) (xy 37.564568 -252.771402) (xy 31.523432 -252.771402)
			(xy 31.523037 -252.781577) (xy 31.515246 -252.800378) (xy 31.500851 -252.814764) (xy 31.482046 -252.822543)
			(xy 31.47187 -252.822964) (xy 30.07233 -252.822964) (xy 30.062161 -252.822511) (xy 30.043367 -252.814737)
			(xy 30.028981 -252.80036) (xy 30.021195 -252.781571) (xy 30.020768 -252.771402) (xy 23.979632 -252.771402)
			(xy 23.979237 -252.781577) (xy 23.971446 -252.800378) (xy 23.957051 -252.814764) (xy 23.938246 -252.822543)
			(xy 23.92807 -252.822964) (xy 22.52853 -252.822964) (xy 22.518361 -252.822511) (xy 22.499567 -252.814737)
			(xy 22.485181 -252.80036) (xy 22.477395 -252.781571) (xy 22.476968 -252.771402) (xy 16.435832 -252.771402)
			(xy 16.435437 -252.781577) (xy 16.427646 -252.800378) (xy 16.413251 -252.814764) (xy 16.394446 -252.822543)
			(xy 16.38427 -252.822964) (xy 14.98473 -252.822964) (xy 14.974561 -252.822511) (xy 14.955767 -252.814737)
			(xy 14.941381 -252.80036) (xy 14.933595 -252.781571) (xy 14.933168 -252.771402) (xy 8.892032 -252.771402)
			(xy 8.891637 -252.781577) (xy 8.883846 -252.800378) (xy 8.869451 -252.814764) (xy 8.850646 -252.822543)
			(xy 8.84047 -252.822964) (xy 7.44093 -252.822964) (xy 7.430761 -252.822511) (xy 7.411967 -252.814737)
			(xy 7.397581 -252.80036) (xy 7.389795 -252.781571) (xy 7.389368 -252.771402) (xy 2.509012 -252.771402)
			(xy 2.509012 -259.57149) (xy 7.389368 -259.57149) (xy 7.389368 -259.16255) (xy 7.389805 -259.152378)
			(xy 7.39758 -259.133579) (xy 7.411962 -259.119191) (xy 7.430758 -259.111409) (xy 7.44093 -259.110988)
			(xy 8.84047 -259.110988) (xy 8.850646 -259.11139) (xy 8.869449 -259.119174) (xy 8.883837 -259.133567)
			(xy 8.891614 -259.152374) (xy 8.892032 -259.16255) (xy 8.892032 -259.57149) (xy 11.489436 -259.57149)
			(xy 11.489436 -259.16255) (xy 11.489905 -259.152382) (xy 11.497673 -259.133589) (xy 11.512045 -259.119202)
			(xy 11.53083 -259.111415) (xy 11.540998 -259.110988) (xy 12.940538 -259.110988) (xy 12.950718 -259.111334)
			(xy 12.969523 -259.119141) (xy 12.983909 -259.133551) (xy 12.991684 -259.152369) (xy 12.9921 -259.16255)
			(xy 12.9921 -259.57149) (xy 14.933168 -259.57149) (xy 14.933168 -259.16255) (xy 14.933605 -259.152378)
			(xy 14.94138 -259.133579) (xy 14.955762 -259.119191) (xy 14.974558 -259.111409) (xy 14.98473 -259.110988)
			(xy 16.38427 -259.110988) (xy 16.394446 -259.11139) (xy 16.413249 -259.119174) (xy 16.427637 -259.133567)
			(xy 16.435414 -259.152374) (xy 16.435832 -259.16255) (xy 16.435832 -259.57149) (xy 19.033236 -259.57149)
			(xy 19.033236 -259.16255) (xy 19.033705 -259.152382) (xy 19.041473 -259.133589) (xy 19.055845 -259.119202)
			(xy 19.07463 -259.111415) (xy 19.084798 -259.110988) (xy 20.484338 -259.110988) (xy 20.494518 -259.111334)
			(xy 20.513323 -259.119141) (xy 20.527709 -259.133551) (xy 20.535484 -259.152369) (xy 20.5359 -259.16255)
			(xy 20.5359 -259.57149) (xy 22.476968 -259.57149) (xy 22.476968 -259.16255) (xy 22.477405 -259.152378)
			(xy 22.48518 -259.133579) (xy 22.499562 -259.119191) (xy 22.518358 -259.111409) (xy 22.52853 -259.110988)
			(xy 23.92807 -259.110988) (xy 23.938246 -259.11139) (xy 23.957049 -259.119174) (xy 23.971437 -259.133567)
			(xy 23.979214 -259.152374) (xy 23.979632 -259.16255) (xy 23.979632 -259.57149) (xy 26.577036 -259.57149)
			(xy 26.577036 -259.16255) (xy 26.577505 -259.152382) (xy 26.585273 -259.133589) (xy 26.599645 -259.119202)
			(xy 26.61843 -259.111415) (xy 26.628598 -259.110988) (xy 28.028138 -259.110988) (xy 28.038318 -259.111334)
			(xy 28.057123 -259.119141) (xy 28.071509 -259.133551) (xy 28.079284 -259.152369) (xy 28.0797 -259.16255)
			(xy 28.0797 -259.57149) (xy 30.020768 -259.57149) (xy 30.020768 -259.16255) (xy 30.021205 -259.152378)
			(xy 30.02898 -259.133579) (xy 30.043362 -259.119191) (xy 30.062158 -259.111409) (xy 30.07233 -259.110988)
			(xy 31.47187 -259.110988) (xy 31.482046 -259.11139) (xy 31.500849 -259.119174) (xy 31.515237 -259.133567)
			(xy 31.523014 -259.152374) (xy 31.523432 -259.16255) (xy 31.523432 -259.57149) (xy 34.120836 -259.57149)
			(xy 34.120836 -259.16255) (xy 34.121305 -259.152382) (xy 34.129073 -259.133589) (xy 34.143445 -259.119202)
			(xy 34.16223 -259.111415) (xy 34.172398 -259.110988) (xy 35.571938 -259.110988) (xy 35.582118 -259.111334)
			(xy 35.600923 -259.119141) (xy 35.615309 -259.133551) (xy 35.623084 -259.152369) (xy 35.6235 -259.16255)
			(xy 35.6235 -259.57149) (xy 37.564568 -259.57149) (xy 37.564568 -259.16255) (xy 37.565005 -259.152378)
			(xy 37.57278 -259.133579) (xy 37.587162 -259.119191) (xy 37.605958 -259.111409) (xy 37.61613 -259.110988)
			(xy 39.01567 -259.110988) (xy 39.025846 -259.11139) (xy 39.044649 -259.119174) (xy 39.059037 -259.133567)
			(xy 39.066814 -259.152374) (xy 39.067232 -259.16255) (xy 39.067232 -259.57149) (xy 41.664636 -259.57149)
			(xy 41.664636 -259.16255) (xy 41.665105 -259.152382) (xy 41.672873 -259.133589) (xy 41.687245 -259.119202)
			(xy 41.70603 -259.111415) (xy 41.716198 -259.110988) (xy 43.115738 -259.110988) (xy 43.125918 -259.111334)
			(xy 43.144723 -259.119141) (xy 43.159109 -259.133551) (xy 43.166884 -259.152369) (xy 43.1673 -259.16255)
			(xy 43.1673 -259.57149) (xy 45.108368 -259.57149) (xy 45.108368 -259.16255) (xy 45.108805 -259.152378)
			(xy 45.11658 -259.133579) (xy 45.130962 -259.119191) (xy 45.149758 -259.111409) (xy 45.15993 -259.110988)
			(xy 46.55947 -259.110988) (xy 46.569646 -259.11139) (xy 46.588449 -259.119174) (xy 46.602837 -259.133567)
			(xy 46.610614 -259.152374) (xy 46.611032 -259.16255) (xy 46.611032 -259.57149) (xy 49.208436 -259.57149)
			(xy 49.208436 -259.16255) (xy 49.208905 -259.152382) (xy 49.216673 -259.133589) (xy 49.231045 -259.119202)
			(xy 49.24983 -259.111415) (xy 49.259998 -259.110988) (xy 50.659538 -259.110988) (xy 50.669718 -259.111334)
			(xy 50.688523 -259.119141) (xy 50.702909 -259.133551) (xy 50.710684 -259.152369) (xy 50.7111 -259.16255)
			(xy 50.7111 -259.57149) (xy 52.652168 -259.57149) (xy 52.652168 -259.16255) (xy 52.652605 -259.152378)
			(xy 52.66038 -259.133579) (xy 52.674762 -259.119191) (xy 52.693558 -259.111409) (xy 52.70373 -259.110988)
			(xy 54.10327 -259.110988) (xy 54.113446 -259.11139) (xy 54.132249 -259.119174) (xy 54.146637 -259.133567)
			(xy 54.154414 -259.152374) (xy 54.154832 -259.16255) (xy 54.154832 -259.57149) (xy 56.752236 -259.57149)
			(xy 56.752236 -259.16255) (xy 56.752705 -259.152382) (xy 56.760473 -259.133589) (xy 56.774845 -259.119202)
			(xy 56.79363 -259.111415) (xy 56.803798 -259.110988) (xy 58.203338 -259.110988) (xy 58.213518 -259.111334)
			(xy 58.232323 -259.119141) (xy 58.246709 -259.133551) (xy 58.254484 -259.152369) (xy 58.2549 -259.16255)
			(xy 58.2549 -259.57149) (xy 60.195968 -259.57149) (xy 60.195968 -259.16255) (xy 60.196405 -259.152378)
			(xy 60.20418 -259.133579) (xy 60.218562 -259.119191) (xy 60.237358 -259.111409) (xy 60.24753 -259.110988)
			(xy 61.64707 -259.110988) (xy 61.657246 -259.11139) (xy 61.676049 -259.119174) (xy 61.690437 -259.133567)
			(xy 61.698214 -259.152374) (xy 61.698632 -259.16255) (xy 61.698632 -259.57149) (xy 64.296036 -259.57149)
			(xy 64.296036 -259.16255) (xy 64.296505 -259.152382) (xy 64.304273 -259.133589) (xy 64.318645 -259.119202)
			(xy 64.33743 -259.111415) (xy 64.347598 -259.110988) (xy 65.747138 -259.110988) (xy 65.757318 -259.111334)
			(xy 65.776123 -259.119141) (xy 65.790509 -259.133551) (xy 65.798284 -259.152369) (xy 65.7987 -259.16255)
			(xy 65.7987 -259.57149) (xy 158.062168 -259.57149) (xy 158.062168 -259.16255) (xy 158.062605 -259.152378)
			(xy 158.07038 -259.133579) (xy 158.084762 -259.119191) (xy 158.103558 -259.111409) (xy 158.11373 -259.110988)
			(xy 159.51327 -259.110988) (xy 159.523446 -259.11139) (xy 159.542249 -259.119174) (xy 159.556637 -259.133567)
			(xy 159.564414 -259.152374) (xy 159.564832 -259.16255) (xy 159.564832 -259.57149) (xy 162.162236 -259.57149)
			(xy 162.162236 -259.16255) (xy 162.162705 -259.152382) (xy 162.170473 -259.133589) (xy 162.184845 -259.119202)
			(xy 162.20363 -259.111415) (xy 162.213798 -259.110988) (xy 163.613338 -259.110988) (xy 163.623518 -259.111334)
			(xy 163.642323 -259.119141) (xy 163.656709 -259.133551) (xy 163.664484 -259.152369) (xy 163.6649 -259.16255)
			(xy 163.6649 -259.57149) (xy 165.605968 -259.57149) (xy 165.605968 -259.16255) (xy 165.606405 -259.152378)
			(xy 165.61418 -259.133579) (xy 165.628562 -259.119191) (xy 165.647358 -259.111409) (xy 165.65753 -259.110988)
			(xy 167.05707 -259.110988) (xy 167.067246 -259.11139) (xy 167.086049 -259.119174) (xy 167.100437 -259.133567)
			(xy 167.108214 -259.152374) (xy 167.108632 -259.16255) (xy 167.108632 -259.57149) (xy 169.706036 -259.57149)
			(xy 169.706036 -259.16255) (xy 169.706505 -259.152382) (xy 169.714273 -259.133589) (xy 169.728645 -259.119202)
			(xy 169.74743 -259.111415) (xy 169.757598 -259.110988) (xy 171.157138 -259.110988) (xy 171.167318 -259.111334)
			(xy 171.186123 -259.119141) (xy 171.200509 -259.133551) (xy 171.208284 -259.152369) (xy 171.2087 -259.16255)
			(xy 171.2087 -259.57149) (xy 173.149768 -259.57149) (xy 173.149768 -259.16255) (xy 173.150205 -259.152378)
			(xy 173.15798 -259.133579) (xy 173.172362 -259.119191) (xy 173.191158 -259.111409) (xy 173.20133 -259.110988)
			(xy 174.60087 -259.110988) (xy 174.611046 -259.11139) (xy 174.629849 -259.119174) (xy 174.644237 -259.133567)
			(xy 174.652014 -259.152374) (xy 174.652432 -259.16255) (xy 174.652432 -259.57149) (xy 177.249836 -259.57149)
			(xy 177.249836 -259.16255) (xy 177.250305 -259.152382) (xy 177.258073 -259.133589) (xy 177.272445 -259.119202)
			(xy 177.29123 -259.111415) (xy 177.301398 -259.110988) (xy 178.700938 -259.110988) (xy 178.711118 -259.111334)
			(xy 178.729923 -259.119141) (xy 178.744309 -259.133551) (xy 178.752084 -259.152369) (xy 178.7525 -259.16255)
			(xy 178.7525 -259.57149) (xy 180.693568 -259.57149) (xy 180.693568 -259.16255) (xy 180.694005 -259.152378)
			(xy 180.70178 -259.133579) (xy 180.716162 -259.119191) (xy 180.734958 -259.111409) (xy 180.74513 -259.110988)
			(xy 182.14467 -259.110988) (xy 182.154846 -259.11139) (xy 182.173649 -259.119174) (xy 182.188037 -259.133567)
			(xy 182.195814 -259.152374) (xy 182.196232 -259.16255) (xy 182.196232 -259.57149) (xy 184.793636 -259.57149)
			(xy 184.793636 -259.16255) (xy 184.794105 -259.152382) (xy 184.801873 -259.133589) (xy 184.816245 -259.119202)
			(xy 184.83503 -259.111415) (xy 184.845198 -259.110988) (xy 186.244738 -259.110988) (xy 186.254918 -259.111334)
			(xy 186.273723 -259.119141) (xy 186.288109 -259.133551) (xy 186.295884 -259.152369) (xy 186.2963 -259.16255)
			(xy 186.2963 -259.57149) (xy 188.237368 -259.57149) (xy 188.237368 -259.16255) (xy 188.237805 -259.152378)
			(xy 188.24558 -259.133579) (xy 188.259962 -259.119191) (xy 188.278758 -259.111409) (xy 188.28893 -259.110988)
			(xy 189.68847 -259.110988) (xy 189.698646 -259.11139) (xy 189.717449 -259.119174) (xy 189.731837 -259.133567)
			(xy 189.739614 -259.152374) (xy 189.740032 -259.16255) (xy 189.740032 -259.57149) (xy 192.337436 -259.57149)
			(xy 192.337436 -259.16255) (xy 192.337905 -259.152382) (xy 192.345673 -259.133589) (xy 192.360045 -259.119202)
			(xy 192.37883 -259.111415) (xy 192.388998 -259.110988) (xy 193.788538 -259.110988) (xy 193.798718 -259.111334)
			(xy 193.817523 -259.119141) (xy 193.831909 -259.133551) (xy 193.839684 -259.152369) (xy 193.8401 -259.16255)
			(xy 193.8401 -259.57149) (xy 195.781168 -259.57149) (xy 195.781168 -259.16255) (xy 195.781605 -259.152378)
			(xy 195.78938 -259.133579) (xy 195.803762 -259.119191) (xy 195.822558 -259.111409) (xy 195.83273 -259.110988)
			(xy 197.23227 -259.110988) (xy 197.242446 -259.11139) (xy 197.261249 -259.119174) (xy 197.275637 -259.133567)
			(xy 197.283414 -259.152374) (xy 197.283832 -259.16255) (xy 197.283832 -259.57149) (xy 199.881236 -259.57149)
			(xy 199.881236 -259.16255) (xy 199.881705 -259.152382) (xy 199.889473 -259.133589) (xy 199.903845 -259.119202)
			(xy 199.92263 -259.111415) (xy 199.932798 -259.110988) (xy 201.332338 -259.110988) (xy 201.342518 -259.111334)
			(xy 201.361323 -259.119141) (xy 201.375709 -259.133551) (xy 201.383484 -259.152369) (xy 201.3839 -259.16255)
			(xy 201.3839 -259.57149) (xy 203.324968 -259.57149) (xy 203.324968 -259.16255) (xy 203.325405 -259.152378)
			(xy 203.33318 -259.133579) (xy 203.347562 -259.119191) (xy 203.366358 -259.111409) (xy 203.37653 -259.110988)
			(xy 204.77607 -259.110988) (xy 204.786246 -259.11139) (xy 204.805049 -259.119174) (xy 204.819437 -259.133567)
			(xy 204.827214 -259.152374) (xy 204.827632 -259.16255) (xy 204.827632 -259.57149) (xy 207.425036 -259.57149)
			(xy 207.425036 -259.16255) (xy 207.425505 -259.152382) (xy 207.433273 -259.133589) (xy 207.447645 -259.119202)
			(xy 207.46643 -259.111415) (xy 207.476598 -259.110988) (xy 208.876138 -259.110988) (xy 208.886318 -259.111334)
			(xy 208.905123 -259.119141) (xy 208.919509 -259.133551) (xy 208.927284 -259.152369) (xy 208.9277 -259.16255)
			(xy 208.9277 -259.57149) (xy 210.868768 -259.57149) (xy 210.868768 -259.16255) (xy 210.869205 -259.152378)
			(xy 210.87698 -259.133579) (xy 210.891362 -259.119191) (xy 210.910158 -259.111409) (xy 210.92033 -259.110988)
			(xy 212.31987 -259.110988) (xy 212.330046 -259.11139) (xy 212.348849 -259.119174) (xy 212.363237 -259.133567)
			(xy 212.371014 -259.152374) (xy 212.371432 -259.16255) (xy 212.371432 -259.57149) (xy 214.968836 -259.57149)
			(xy 214.968836 -259.16255) (xy 214.969305 -259.152382) (xy 214.977073 -259.133589) (xy 214.991445 -259.119202)
			(xy 215.01023 -259.111415) (xy 215.020398 -259.110988) (xy 216.419938 -259.110988) (xy 216.430118 -259.111334)
			(xy 216.448923 -259.119141) (xy 216.463309 -259.133551) (xy 216.471084 -259.152369) (xy 216.4715 -259.16255)
			(xy 216.4715 -259.57149) (xy 255.329436 -259.57149) (xy 255.329436 -259.16255) (xy 255.329905 -259.152382)
			(xy 255.337673 -259.133589) (xy 255.352045 -259.119202) (xy 255.37083 -259.111415) (xy 255.380998 -259.110988)
			(xy 256.780538 -259.110988) (xy 256.790718 -259.111334) (xy 256.809523 -259.119141) (xy 256.823909 -259.133551)
			(xy 256.831684 -259.152369) (xy 256.8321 -259.16255) (xy 256.8321 -259.57149) (xy 259.429504 -259.57149)
			(xy 259.429504 -259.16255) (xy 259.430004 -259.152386) (xy 259.437766 -259.133599) (xy 259.452128 -259.119213)
			(xy 259.470903 -259.11142) (xy 259.481066 -259.110988) (xy 260.880606 -259.110988) (xy 260.890784 -259.11136)
			(xy 260.909589 -259.119156) (xy 260.923975 -259.133559) (xy 260.931751 -259.152371) (xy 260.932168 -259.16255)
			(xy 260.932168 -259.57149) (xy 262.873236 -259.57149) (xy 262.873236 -259.16255) (xy 262.873705 -259.152382)
			(xy 262.881473 -259.133589) (xy 262.895845 -259.119202) (xy 262.91463 -259.111415) (xy 262.924798 -259.110988)
			(xy 264.324338 -259.110988) (xy 264.334518 -259.111334) (xy 264.353323 -259.119141) (xy 264.367709 -259.133551)
			(xy 264.375484 -259.152369) (xy 264.3759 -259.16255) (xy 264.3759 -259.57149) (xy 266.973304 -259.57149)
			(xy 266.973304 -259.16255) (xy 266.973804 -259.152386) (xy 266.981566 -259.133599) (xy 266.995928 -259.119213)
			(xy 267.014703 -259.11142) (xy 267.024866 -259.110988) (xy 268.424406 -259.110988) (xy 268.434584 -259.11136)
			(xy 268.453389 -259.119156) (xy 268.467775 -259.133559) (xy 268.475551 -259.152371) (xy 268.475968 -259.16255)
			(xy 268.475968 -259.57149) (xy 270.417036 -259.57149) (xy 270.417036 -259.16255) (xy 270.417505 -259.152382)
			(xy 270.425273 -259.133589) (xy 270.439645 -259.119202) (xy 270.45843 -259.111415) (xy 270.468598 -259.110988)
			(xy 271.868138 -259.110988) (xy 271.878318 -259.111334) (xy 271.897123 -259.119141) (xy 271.911509 -259.133551)
			(xy 271.919284 -259.152369) (xy 271.9197 -259.16255) (xy 271.9197 -259.57149) (xy 274.517104 -259.57149)
			(xy 274.517104 -259.16255) (xy 274.517604 -259.152386) (xy 274.525366 -259.133599) (xy 274.539728 -259.119213)
			(xy 274.558503 -259.11142) (xy 274.568666 -259.110988) (xy 275.968206 -259.110988) (xy 275.978384 -259.11136)
			(xy 275.997189 -259.119156) (xy 276.011575 -259.133559) (xy 276.019351 -259.152371) (xy 276.019768 -259.16255)
			(xy 276.019768 -259.57149) (xy 277.960836 -259.57149) (xy 277.960836 -259.16255) (xy 277.961305 -259.152382)
			(xy 277.969073 -259.133589) (xy 277.983445 -259.119202) (xy 278.00223 -259.111415) (xy 278.012398 -259.110988)
			(xy 279.411938 -259.110988) (xy 279.422118 -259.111334) (xy 279.440923 -259.119141) (xy 279.455309 -259.133551)
			(xy 279.463084 -259.152369) (xy 279.4635 -259.16255) (xy 279.4635 -259.57149) (xy 282.060904 -259.57149)
			(xy 282.060904 -259.16255) (xy 282.061404 -259.152386) (xy 282.069166 -259.133599) (xy 282.083528 -259.119213)
			(xy 282.102303 -259.11142) (xy 282.112466 -259.110988) (xy 283.512006 -259.110988) (xy 283.522184 -259.11136)
			(xy 283.540989 -259.119156) (xy 283.555375 -259.133559) (xy 283.563151 -259.152371) (xy 283.563568 -259.16255)
			(xy 283.563568 -259.57149) (xy 285.504636 -259.57149) (xy 285.504636 -259.16255) (xy 285.505105 -259.152382)
			(xy 285.512873 -259.133589) (xy 285.527245 -259.119202) (xy 285.54603 -259.111415) (xy 285.556198 -259.110988)
			(xy 286.955738 -259.110988) (xy 286.965918 -259.111334) (xy 286.984723 -259.119141) (xy 286.999109 -259.133551)
			(xy 287.006884 -259.152369) (xy 287.0073 -259.16255) (xy 287.0073 -259.57149) (xy 289.604704 -259.57149)
			(xy 289.604704 -259.16255) (xy 289.605204 -259.152386) (xy 289.612966 -259.133599) (xy 289.627328 -259.119213)
			(xy 289.646103 -259.11142) (xy 289.656266 -259.110988) (xy 291.055806 -259.110988) (xy 291.065984 -259.11136)
			(xy 291.084789 -259.119156) (xy 291.099175 -259.133559) (xy 291.106951 -259.152371) (xy 291.107368 -259.16255)
			(xy 291.107368 -259.57149) (xy 293.048436 -259.57149) (xy 293.048436 -259.16255) (xy 293.048905 -259.152382)
			(xy 293.056673 -259.133589) (xy 293.071045 -259.119202) (xy 293.08983 -259.111415) (xy 293.099998 -259.110988)
			(xy 294.499538 -259.110988) (xy 294.509718 -259.111334) (xy 294.528523 -259.119141) (xy 294.542909 -259.133551)
			(xy 294.550684 -259.152369) (xy 294.5511 -259.16255) (xy 294.5511 -259.57149) (xy 297.148504 -259.57149)
			(xy 297.148504 -259.16255) (xy 297.149004 -259.152386) (xy 297.156766 -259.133599) (xy 297.171128 -259.119213)
			(xy 297.189903 -259.11142) (xy 297.200066 -259.110988) (xy 298.599606 -259.110988) (xy 298.609784 -259.11136)
			(xy 298.628589 -259.119156) (xy 298.642975 -259.133559) (xy 298.650751 -259.152371) (xy 298.651168 -259.16255)
			(xy 298.651168 -259.57149) (xy 300.592236 -259.57149) (xy 300.592236 -259.16255) (xy 300.592705 -259.152382)
			(xy 300.600473 -259.133589) (xy 300.614845 -259.119202) (xy 300.63363 -259.111415) (xy 300.643798 -259.110988)
			(xy 302.043338 -259.110988) (xy 302.053518 -259.111334) (xy 302.072323 -259.119141) (xy 302.086709 -259.133551)
			(xy 302.094484 -259.152369) (xy 302.0949 -259.16255) (xy 302.0949 -259.57149) (xy 304.692304 -259.57149)
			(xy 304.692304 -259.16255) (xy 304.692804 -259.152386) (xy 304.700566 -259.133599) (xy 304.714928 -259.119213)
			(xy 304.733703 -259.11142) (xy 304.743866 -259.110988) (xy 306.143406 -259.110988) (xy 306.153584 -259.11136)
			(xy 306.172389 -259.119156) (xy 306.186775 -259.133559) (xy 306.194551 -259.152371) (xy 306.194968 -259.16255)
			(xy 306.194968 -259.57149) (xy 308.136036 -259.57149) (xy 308.136036 -259.16255) (xy 308.136505 -259.152382)
			(xy 308.144273 -259.133589) (xy 308.158645 -259.119202) (xy 308.17743 -259.111415) (xy 308.187598 -259.110988)
			(xy 309.587138 -259.110988) (xy 309.597318 -259.111334) (xy 309.616123 -259.119141) (xy 309.630509 -259.133551)
			(xy 309.638284 -259.152369) (xy 309.6387 -259.16255) (xy 309.6387 -259.57149) (xy 312.236104 -259.57149)
			(xy 312.236104 -259.16255) (xy 312.236604 -259.152386) (xy 312.244366 -259.133599) (xy 312.258728 -259.119213)
			(xy 312.277503 -259.11142) (xy 312.287666 -259.110988) (xy 313.687206 -259.110988) (xy 313.697384 -259.11136)
			(xy 313.716189 -259.119156) (xy 313.730575 -259.133559) (xy 313.738351 -259.152371) (xy 313.738768 -259.16255)
			(xy 313.738768 -259.57149) (xy 406.002236 -259.57149) (xy 406.002236 -259.16255) (xy 406.002705 -259.152382)
			(xy 406.010473 -259.133589) (xy 406.024845 -259.119202) (xy 406.04363 -259.111415) (xy 406.053798 -259.110988)
			(xy 407.453338 -259.110988) (xy 407.463518 -259.111334) (xy 407.482323 -259.119141) (xy 407.496709 -259.133551)
			(xy 407.504484 -259.152369) (xy 407.5049 -259.16255) (xy 407.5049 -259.57149) (xy 410.102304 -259.57149)
			(xy 410.102304 -259.16255) (xy 410.102804 -259.152386) (xy 410.110566 -259.133599) (xy 410.124928 -259.119213)
			(xy 410.143703 -259.11142) (xy 410.153866 -259.110988) (xy 411.553406 -259.110988) (xy 411.563584 -259.11136)
			(xy 411.582389 -259.119156) (xy 411.596775 -259.133559) (xy 411.604551 -259.152371) (xy 411.604968 -259.16255)
			(xy 411.604968 -259.57149) (xy 413.546036 -259.57149) (xy 413.546036 -259.16255) (xy 413.546505 -259.152382)
			(xy 413.554273 -259.133589) (xy 413.568645 -259.119202) (xy 413.58743 -259.111415) (xy 413.597598 -259.110988)
			(xy 414.997138 -259.110988) (xy 415.007318 -259.111334) (xy 415.026123 -259.119141) (xy 415.040509 -259.133551)
			(xy 415.048284 -259.152369) (xy 415.0487 -259.16255) (xy 415.0487 -259.57149) (xy 417.646104 -259.57149)
			(xy 417.646104 -259.16255) (xy 417.646604 -259.152386) (xy 417.654366 -259.133599) (xy 417.668728 -259.119213)
			(xy 417.687503 -259.11142) (xy 417.697666 -259.110988) (xy 419.097206 -259.110988) (xy 419.107384 -259.11136)
			(xy 419.126189 -259.119156) (xy 419.140575 -259.133559) (xy 419.148351 -259.152371) (xy 419.148768 -259.16255)
			(xy 419.148768 -259.57149) (xy 421.089836 -259.57149) (xy 421.089836 -259.16255) (xy 421.090305 -259.152382)
			(xy 421.098073 -259.133589) (xy 421.112445 -259.119202) (xy 421.13123 -259.111415) (xy 421.141398 -259.110988)
			(xy 422.540938 -259.110988) (xy 422.551118 -259.111334) (xy 422.569923 -259.119141) (xy 422.584309 -259.133551)
			(xy 422.592084 -259.152369) (xy 422.5925 -259.16255) (xy 422.5925 -259.57149) (xy 425.189904 -259.57149)
			(xy 425.189904 -259.16255) (xy 425.190404 -259.152386) (xy 425.198166 -259.133599) (xy 425.212528 -259.119213)
			(xy 425.231303 -259.11142) (xy 425.241466 -259.110988) (xy 426.641006 -259.110988) (xy 426.651184 -259.11136)
			(xy 426.669989 -259.119156) (xy 426.684375 -259.133559) (xy 426.692151 -259.152371) (xy 426.692568 -259.16255)
			(xy 426.692568 -259.57149) (xy 428.633636 -259.57149) (xy 428.633636 -259.16255) (xy 428.634105 -259.152382)
			(xy 428.641873 -259.133589) (xy 428.656245 -259.119202) (xy 428.67503 -259.111415) (xy 428.685198 -259.110988)
			(xy 430.084738 -259.110988) (xy 430.094918 -259.111334) (xy 430.113723 -259.119141) (xy 430.128109 -259.133551)
			(xy 430.135884 -259.152369) (xy 430.1363 -259.16255) (xy 430.1363 -259.57149) (xy 432.733704 -259.57149)
			(xy 432.733704 -259.16255) (xy 432.734204 -259.152386) (xy 432.741966 -259.133599) (xy 432.756328 -259.119213)
			(xy 432.775103 -259.11142) (xy 432.785266 -259.110988) (xy 434.184806 -259.110988) (xy 434.194984 -259.11136)
			(xy 434.213789 -259.119156) (xy 434.228175 -259.133559) (xy 434.235951 -259.152371) (xy 434.236368 -259.16255)
			(xy 434.236368 -259.57149) (xy 436.177436 -259.57149) (xy 436.177436 -259.16255) (xy 436.177905 -259.152382)
			(xy 436.185673 -259.133589) (xy 436.200045 -259.119202) (xy 436.21883 -259.111415) (xy 436.228998 -259.110988)
			(xy 437.628538 -259.110988) (xy 437.638718 -259.111334) (xy 437.657523 -259.119141) (xy 437.671909 -259.133551)
			(xy 437.679684 -259.152369) (xy 437.6801 -259.16255) (xy 437.6801 -259.57149) (xy 440.277504 -259.57149)
			(xy 440.277504 -259.16255) (xy 440.278004 -259.152386) (xy 440.285766 -259.133599) (xy 440.300128 -259.119213)
			(xy 440.318903 -259.11142) (xy 440.329066 -259.110988) (xy 441.728606 -259.110988) (xy 441.738784 -259.11136)
			(xy 441.757589 -259.119156) (xy 441.771975 -259.133559) (xy 441.779751 -259.152371) (xy 441.780168 -259.16255)
			(xy 441.780168 -259.57149) (xy 443.721236 -259.57149) (xy 443.721236 -259.16255) (xy 443.721705 -259.152382)
			(xy 443.729473 -259.133589) (xy 443.743845 -259.119202) (xy 443.76263 -259.111415) (xy 443.772798 -259.110988)
			(xy 445.172338 -259.110988) (xy 445.182518 -259.111334) (xy 445.201323 -259.119141) (xy 445.215709 -259.133551)
			(xy 445.223484 -259.152369) (xy 445.2239 -259.16255) (xy 445.2239 -259.57149) (xy 447.821304 -259.57149)
			(xy 447.821304 -259.16255) (xy 447.821804 -259.152386) (xy 447.829566 -259.133599) (xy 447.843928 -259.119213)
			(xy 447.862703 -259.11142) (xy 447.872866 -259.110988) (xy 449.272406 -259.110988) (xy 449.282584 -259.11136)
			(xy 449.301389 -259.119156) (xy 449.315775 -259.133559) (xy 449.323551 -259.152371) (xy 449.323968 -259.16255)
			(xy 449.323968 -259.57149) (xy 451.265036 -259.57149) (xy 451.265036 -259.16255) (xy 451.265505 -259.152382)
			(xy 451.273273 -259.133589) (xy 451.287645 -259.119202) (xy 451.30643 -259.111415) (xy 451.316598 -259.110988)
			(xy 452.716138 -259.110988) (xy 452.726318 -259.111334) (xy 452.745123 -259.119141) (xy 452.759509 -259.133551)
			(xy 452.767284 -259.152369) (xy 452.7677 -259.16255) (xy 452.7677 -259.57149) (xy 455.365104 -259.57149)
			(xy 455.365104 -259.16255) (xy 455.365604 -259.152386) (xy 455.373366 -259.133599) (xy 455.387728 -259.119213)
			(xy 455.406503 -259.11142) (xy 455.416666 -259.110988) (xy 456.816206 -259.110988) (xy 456.826384 -259.11136)
			(xy 456.845189 -259.119156) (xy 456.859575 -259.133559) (xy 456.867351 -259.152371) (xy 456.867768 -259.16255)
			(xy 456.867768 -259.57149) (xy 458.808836 -259.57149) (xy 458.808836 -259.16255) (xy 458.809305 -259.152382)
			(xy 458.817073 -259.133589) (xy 458.831445 -259.119202) (xy 458.85023 -259.111415) (xy 458.860398 -259.110988)
			(xy 460.259938 -259.110988) (xy 460.270118 -259.111334) (xy 460.288923 -259.119141) (xy 460.303309 -259.133551)
			(xy 460.311084 -259.152369) (xy 460.3115 -259.16255) (xy 460.3115 -259.57149) (xy 462.908904 -259.57149)
			(xy 462.908904 -259.16255) (xy 462.909404 -259.152386) (xy 462.917166 -259.133599) (xy 462.931528 -259.119213)
			(xy 462.950303 -259.11142) (xy 462.960466 -259.110988) (xy 464.360006 -259.110988) (xy 464.370184 -259.11136)
			(xy 464.388989 -259.119156) (xy 464.403375 -259.133559) (xy 464.411151 -259.152371) (xy 464.411568 -259.16255)
			(xy 464.411568 -259.57149) (xy 464.411128 -259.58166) (xy 464.403348 -259.600454) (xy 464.388967 -259.614839)
			(xy 464.370176 -259.622625) (xy 464.360006 -259.623052) (xy 462.960466 -259.623052) (xy 462.950305 -259.622594)
			(xy 462.931533 -259.614807) (xy 462.917169 -259.60043) (xy 462.909397 -259.581652) (xy 462.908904 -259.57149)
			(xy 460.3115 -259.57149) (xy 460.310959 -259.581642) (xy 460.303195 -259.600404) (xy 460.288844 -259.614768)
			(xy 460.27009 -259.62255) (xy 460.259938 -259.623052) (xy 458.860398 -259.623052) (xy 458.850225 -259.622638)
			(xy 458.831428 -259.61485) (xy 458.817043 -259.600462) (xy 458.80926 -259.581663) (xy 458.808836 -259.57149)
			(xy 456.867768 -259.57149) (xy 456.867328 -259.58166) (xy 456.859548 -259.600454) (xy 456.845167 -259.614839)
			(xy 456.826376 -259.622625) (xy 456.816206 -259.623052) (xy 455.416666 -259.623052) (xy 455.406505 -259.622594)
			(xy 455.387733 -259.614807) (xy 455.373369 -259.60043) (xy 455.365597 -259.581652) (xy 455.365104 -259.57149)
			(xy 452.7677 -259.57149) (xy 452.767159 -259.581642) (xy 452.759395 -259.600404) (xy 452.745044 -259.614768)
			(xy 452.72629 -259.62255) (xy 452.716138 -259.623052) (xy 451.316598 -259.623052) (xy 451.306425 -259.622638)
			(xy 451.287628 -259.61485) (xy 451.273243 -259.600462) (xy 451.26546 -259.581663) (xy 451.265036 -259.57149)
			(xy 449.323968 -259.57149) (xy 449.323528 -259.58166) (xy 449.315748 -259.600454) (xy 449.301367 -259.614839)
			(xy 449.282576 -259.622625) (xy 449.272406 -259.623052) (xy 447.872866 -259.623052) (xy 447.862705 -259.622594)
			(xy 447.843933 -259.614807) (xy 447.829569 -259.60043) (xy 447.821797 -259.581652) (xy 447.821304 -259.57149)
			(xy 445.2239 -259.57149) (xy 445.223359 -259.581642) (xy 445.215595 -259.600404) (xy 445.201244 -259.614768)
			(xy 445.18249 -259.62255) (xy 445.172338 -259.623052) (xy 443.772798 -259.623052) (xy 443.762625 -259.622638)
			(xy 443.743828 -259.61485) (xy 443.729443 -259.600462) (xy 443.72166 -259.581663) (xy 443.721236 -259.57149)
			(xy 441.780168 -259.57149) (xy 441.779728 -259.58166) (xy 441.771948 -259.600454) (xy 441.757567 -259.614839)
			(xy 441.738776 -259.622625) (xy 441.728606 -259.623052) (xy 440.329066 -259.623052) (xy 440.318905 -259.622594)
			(xy 440.300133 -259.614807) (xy 440.285769 -259.60043) (xy 440.277997 -259.581652) (xy 440.277504 -259.57149)
			(xy 437.6801 -259.57149) (xy 437.679559 -259.581642) (xy 437.671795 -259.600404) (xy 437.657444 -259.614768)
			(xy 437.63869 -259.62255) (xy 437.628538 -259.623052) (xy 436.228998 -259.623052) (xy 436.218825 -259.622638)
			(xy 436.200028 -259.61485) (xy 436.185643 -259.600462) (xy 436.17786 -259.581663) (xy 436.177436 -259.57149)
			(xy 434.236368 -259.57149) (xy 434.235928 -259.58166) (xy 434.228148 -259.600454) (xy 434.213767 -259.614839)
			(xy 434.194976 -259.622625) (xy 434.184806 -259.623052) (xy 432.785266 -259.623052) (xy 432.775105 -259.622594)
			(xy 432.756333 -259.614807) (xy 432.741969 -259.60043) (xy 432.734197 -259.581652) (xy 432.733704 -259.57149)
			(xy 430.1363 -259.57149) (xy 430.135759 -259.581642) (xy 430.127995 -259.600404) (xy 430.113644 -259.614768)
			(xy 430.09489 -259.62255) (xy 430.084738 -259.623052) (xy 428.685198 -259.623052) (xy 428.675025 -259.622638)
			(xy 428.656228 -259.61485) (xy 428.641843 -259.600462) (xy 428.63406 -259.581663) (xy 428.633636 -259.57149)
			(xy 426.692568 -259.57149) (xy 426.692128 -259.58166) (xy 426.684348 -259.600454) (xy 426.669967 -259.614839)
			(xy 426.651176 -259.622625) (xy 426.641006 -259.623052) (xy 425.241466 -259.623052) (xy 425.231305 -259.622594)
			(xy 425.212533 -259.614807) (xy 425.198169 -259.60043) (xy 425.190397 -259.581652) (xy 425.189904 -259.57149)
			(xy 422.5925 -259.57149) (xy 422.591959 -259.581642) (xy 422.584195 -259.600404) (xy 422.569844 -259.614768)
			(xy 422.55109 -259.62255) (xy 422.540938 -259.623052) (xy 421.141398 -259.623052) (xy 421.131225 -259.622638)
			(xy 421.112428 -259.61485) (xy 421.098043 -259.600462) (xy 421.09026 -259.581663) (xy 421.089836 -259.57149)
			(xy 419.148768 -259.57149) (xy 419.148328 -259.58166) (xy 419.140548 -259.600454) (xy 419.126167 -259.614839)
			(xy 419.107376 -259.622625) (xy 419.097206 -259.623052) (xy 417.697666 -259.623052) (xy 417.687505 -259.622594)
			(xy 417.668733 -259.614807) (xy 417.654369 -259.60043) (xy 417.646597 -259.581652) (xy 417.646104 -259.57149)
			(xy 415.0487 -259.57149) (xy 415.048159 -259.581642) (xy 415.040395 -259.600404) (xy 415.026044 -259.614768)
			(xy 415.00729 -259.62255) (xy 414.997138 -259.623052) (xy 413.597598 -259.623052) (xy 413.587425 -259.622638)
			(xy 413.568628 -259.61485) (xy 413.554243 -259.600462) (xy 413.54646 -259.581663) (xy 413.546036 -259.57149)
			(xy 411.604968 -259.57149) (xy 411.604528 -259.58166) (xy 411.596748 -259.600454) (xy 411.582367 -259.614839)
			(xy 411.563576 -259.622625) (xy 411.553406 -259.623052) (xy 410.153866 -259.623052) (xy 410.143705 -259.622594)
			(xy 410.124933 -259.614807) (xy 410.110569 -259.60043) (xy 410.102797 -259.581652) (xy 410.102304 -259.57149)
			(xy 407.5049 -259.57149) (xy 407.504359 -259.581642) (xy 407.496595 -259.600404) (xy 407.482244 -259.614768)
			(xy 407.46349 -259.62255) (xy 407.453338 -259.623052) (xy 406.053798 -259.623052) (xy 406.043625 -259.622638)
			(xy 406.024828 -259.61485) (xy 406.010443 -259.600462) (xy 406.00266 -259.581663) (xy 406.002236 -259.57149)
			(xy 313.738768 -259.57149) (xy 313.738328 -259.58166) (xy 313.730548 -259.600454) (xy 313.716167 -259.614839)
			(xy 313.697376 -259.622625) (xy 313.687206 -259.623052) (xy 312.287666 -259.623052) (xy 312.277505 -259.622594)
			(xy 312.258733 -259.614807) (xy 312.244369 -259.60043) (xy 312.236597 -259.581652) (xy 312.236104 -259.57149)
			(xy 309.6387 -259.57149) (xy 309.638159 -259.581642) (xy 309.630395 -259.600404) (xy 309.616044 -259.614768)
			(xy 309.59729 -259.62255) (xy 309.587138 -259.623052) (xy 308.187598 -259.623052) (xy 308.177425 -259.622638)
			(xy 308.158628 -259.61485) (xy 308.144243 -259.600462) (xy 308.13646 -259.581663) (xy 308.136036 -259.57149)
			(xy 306.194968 -259.57149) (xy 306.194528 -259.58166) (xy 306.186748 -259.600454) (xy 306.172367 -259.614839)
			(xy 306.153576 -259.622625) (xy 306.143406 -259.623052) (xy 304.743866 -259.623052) (xy 304.733705 -259.622594)
			(xy 304.714933 -259.614807) (xy 304.700569 -259.60043) (xy 304.692797 -259.581652) (xy 304.692304 -259.57149)
			(xy 302.0949 -259.57149) (xy 302.094359 -259.581642) (xy 302.086595 -259.600404) (xy 302.072244 -259.614768)
			(xy 302.05349 -259.62255) (xy 302.043338 -259.623052) (xy 300.643798 -259.623052) (xy 300.633625 -259.622638)
			(xy 300.614828 -259.61485) (xy 300.600443 -259.600462) (xy 300.59266 -259.581663) (xy 300.592236 -259.57149)
			(xy 298.651168 -259.57149) (xy 298.650728 -259.58166) (xy 298.642948 -259.600454) (xy 298.628567 -259.614839)
			(xy 298.609776 -259.622625) (xy 298.599606 -259.623052) (xy 297.200066 -259.623052) (xy 297.189905 -259.622594)
			(xy 297.171133 -259.614807) (xy 297.156769 -259.60043) (xy 297.148997 -259.581652) (xy 297.148504 -259.57149)
			(xy 294.5511 -259.57149) (xy 294.550559 -259.581642) (xy 294.542795 -259.600404) (xy 294.528444 -259.614768)
			(xy 294.50969 -259.62255) (xy 294.499538 -259.623052) (xy 293.099998 -259.623052) (xy 293.089825 -259.622638)
			(xy 293.071028 -259.61485) (xy 293.056643 -259.600462) (xy 293.04886 -259.581663) (xy 293.048436 -259.57149)
			(xy 291.107368 -259.57149) (xy 291.106928 -259.58166) (xy 291.099148 -259.600454) (xy 291.084767 -259.614839)
			(xy 291.065976 -259.622625) (xy 291.055806 -259.623052) (xy 289.656266 -259.623052) (xy 289.646105 -259.622594)
			(xy 289.627333 -259.614807) (xy 289.612969 -259.60043) (xy 289.605197 -259.581652) (xy 289.604704 -259.57149)
			(xy 287.0073 -259.57149) (xy 287.006759 -259.581642) (xy 286.998995 -259.600404) (xy 286.984644 -259.614768)
			(xy 286.96589 -259.62255) (xy 286.955738 -259.623052) (xy 285.556198 -259.623052) (xy 285.546025 -259.622638)
			(xy 285.527228 -259.61485) (xy 285.512843 -259.600462) (xy 285.50506 -259.581663) (xy 285.504636 -259.57149)
			(xy 283.563568 -259.57149) (xy 283.563128 -259.58166) (xy 283.555348 -259.600454) (xy 283.540967 -259.614839)
			(xy 283.522176 -259.622625) (xy 283.512006 -259.623052) (xy 282.112466 -259.623052) (xy 282.102305 -259.622594)
			(xy 282.083533 -259.614807) (xy 282.069169 -259.60043) (xy 282.061397 -259.581652) (xy 282.060904 -259.57149)
			(xy 279.4635 -259.57149) (xy 279.462959 -259.581642) (xy 279.455195 -259.600404) (xy 279.440844 -259.614768)
			(xy 279.42209 -259.62255) (xy 279.411938 -259.623052) (xy 278.012398 -259.623052) (xy 278.002225 -259.622638)
			(xy 277.983428 -259.61485) (xy 277.969043 -259.600462) (xy 277.96126 -259.581663) (xy 277.960836 -259.57149)
			(xy 276.019768 -259.57149) (xy 276.019328 -259.58166) (xy 276.011548 -259.600454) (xy 275.997167 -259.614839)
			(xy 275.978376 -259.622625) (xy 275.968206 -259.623052) (xy 274.568666 -259.623052) (xy 274.558505 -259.622594)
			(xy 274.539733 -259.614807) (xy 274.525369 -259.60043) (xy 274.517597 -259.581652) (xy 274.517104 -259.57149)
			(xy 271.9197 -259.57149) (xy 271.919159 -259.581642) (xy 271.911395 -259.600404) (xy 271.897044 -259.614768)
			(xy 271.87829 -259.62255) (xy 271.868138 -259.623052) (xy 270.468598 -259.623052) (xy 270.458425 -259.622638)
			(xy 270.439628 -259.61485) (xy 270.425243 -259.600462) (xy 270.41746 -259.581663) (xy 270.417036 -259.57149)
			(xy 268.475968 -259.57149) (xy 268.475528 -259.58166) (xy 268.467748 -259.600454) (xy 268.453367 -259.614839)
			(xy 268.434576 -259.622625) (xy 268.424406 -259.623052) (xy 267.024866 -259.623052) (xy 267.014705 -259.622594)
			(xy 266.995933 -259.614807) (xy 266.981569 -259.60043) (xy 266.973797 -259.581652) (xy 266.973304 -259.57149)
			(xy 264.3759 -259.57149) (xy 264.375359 -259.581642) (xy 264.367595 -259.600404) (xy 264.353244 -259.614768)
			(xy 264.33449 -259.62255) (xy 264.324338 -259.623052) (xy 262.924798 -259.623052) (xy 262.914625 -259.622638)
			(xy 262.895828 -259.61485) (xy 262.881443 -259.600462) (xy 262.87366 -259.581663) (xy 262.873236 -259.57149)
			(xy 260.932168 -259.57149) (xy 260.931728 -259.58166) (xy 260.923948 -259.600454) (xy 260.909567 -259.614839)
			(xy 260.890776 -259.622625) (xy 260.880606 -259.623052) (xy 259.481066 -259.623052) (xy 259.470905 -259.622594)
			(xy 259.452133 -259.614807) (xy 259.437769 -259.60043) (xy 259.429997 -259.581652) (xy 259.429504 -259.57149)
			(xy 256.8321 -259.57149) (xy 256.831559 -259.581642) (xy 256.823795 -259.600404) (xy 256.809444 -259.614768)
			(xy 256.79069 -259.62255) (xy 256.780538 -259.623052) (xy 255.380998 -259.623052) (xy 255.370825 -259.622638)
			(xy 255.352028 -259.61485) (xy 255.337643 -259.600462) (xy 255.32986 -259.581663) (xy 255.329436 -259.57149)
			(xy 216.4715 -259.57149) (xy 216.470959 -259.581642) (xy 216.463195 -259.600404) (xy 216.448844 -259.614768)
			(xy 216.43009 -259.62255) (xy 216.419938 -259.623052) (xy 215.020398 -259.623052) (xy 215.010225 -259.622638)
			(xy 214.991428 -259.61485) (xy 214.977043 -259.600462) (xy 214.96926 -259.581663) (xy 214.968836 -259.57149)
			(xy 212.371432 -259.57149) (xy 212.371027 -259.581665) (xy 212.36324 -259.600465) (xy 212.348848 -259.614851)
			(xy 212.330045 -259.622631) (xy 212.31987 -259.623052) (xy 210.92033 -259.623052) (xy 210.910159 -259.622611)
			(xy 210.891363 -259.614834) (xy 210.876977 -259.600454) (xy 210.869193 -259.581661) (xy 210.868768 -259.57149)
			(xy 208.9277 -259.57149) (xy 208.927159 -259.581642) (xy 208.919395 -259.600404) (xy 208.905044 -259.614768)
			(xy 208.88629 -259.62255) (xy 208.876138 -259.623052) (xy 207.476598 -259.623052) (xy 207.466425 -259.622638)
			(xy 207.447628 -259.61485) (xy 207.433243 -259.600462) (xy 207.42546 -259.581663) (xy 207.425036 -259.57149)
			(xy 204.827632 -259.57149) (xy 204.827227 -259.581665) (xy 204.81944 -259.600465) (xy 204.805048 -259.614851)
			(xy 204.786245 -259.622631) (xy 204.77607 -259.623052) (xy 203.37653 -259.623052) (xy 203.366359 -259.622611)
			(xy 203.347563 -259.614834) (xy 203.333177 -259.600454) (xy 203.325393 -259.581661) (xy 203.324968 -259.57149)
			(xy 201.3839 -259.57149) (xy 201.383359 -259.581642) (xy 201.375595 -259.600404) (xy 201.361244 -259.614768)
			(xy 201.34249 -259.62255) (xy 201.332338 -259.623052) (xy 199.932798 -259.623052) (xy 199.922625 -259.622638)
			(xy 199.903828 -259.61485) (xy 199.889443 -259.600462) (xy 199.88166 -259.581663) (xy 199.881236 -259.57149)
			(xy 197.283832 -259.57149) (xy 197.283427 -259.581665) (xy 197.27564 -259.600465) (xy 197.261248 -259.614851)
			(xy 197.242445 -259.622631) (xy 197.23227 -259.623052) (xy 195.83273 -259.623052) (xy 195.822559 -259.622611)
			(xy 195.803763 -259.614834) (xy 195.789377 -259.600454) (xy 195.781593 -259.581661) (xy 195.781168 -259.57149)
			(xy 193.8401 -259.57149) (xy 193.839559 -259.581642) (xy 193.831795 -259.600404) (xy 193.817444 -259.614768)
			(xy 193.79869 -259.62255) (xy 193.788538 -259.623052) (xy 192.388998 -259.623052) (xy 192.378825 -259.622638)
			(xy 192.360028 -259.61485) (xy 192.345643 -259.600462) (xy 192.33786 -259.581663) (xy 192.337436 -259.57149)
			(xy 189.740032 -259.57149) (xy 189.739627 -259.581665) (xy 189.73184 -259.600465) (xy 189.717448 -259.614851)
			(xy 189.698645 -259.622631) (xy 189.68847 -259.623052) (xy 188.28893 -259.623052) (xy 188.278759 -259.622611)
			(xy 188.259963 -259.614834) (xy 188.245577 -259.600454) (xy 188.237793 -259.581661) (xy 188.237368 -259.57149)
			(xy 186.2963 -259.57149) (xy 186.295759 -259.581642) (xy 186.287995 -259.600404) (xy 186.273644 -259.614768)
			(xy 186.25489 -259.62255) (xy 186.244738 -259.623052) (xy 184.845198 -259.623052) (xy 184.835025 -259.622638)
			(xy 184.816228 -259.61485) (xy 184.801843 -259.600462) (xy 184.79406 -259.581663) (xy 184.793636 -259.57149)
			(xy 182.196232 -259.57149) (xy 182.195827 -259.581665) (xy 182.18804 -259.600465) (xy 182.173648 -259.614851)
			(xy 182.154845 -259.622631) (xy 182.14467 -259.623052) (xy 180.74513 -259.623052) (xy 180.734959 -259.622611)
			(xy 180.716163 -259.614834) (xy 180.701777 -259.600454) (xy 180.693993 -259.581661) (xy 180.693568 -259.57149)
			(xy 178.7525 -259.57149) (xy 178.751959 -259.581642) (xy 178.744195 -259.600404) (xy 178.729844 -259.614768)
			(xy 178.71109 -259.62255) (xy 178.700938 -259.623052) (xy 177.301398 -259.623052) (xy 177.291225 -259.622638)
			(xy 177.272428 -259.61485) (xy 177.258043 -259.600462) (xy 177.25026 -259.581663) (xy 177.249836 -259.57149)
			(xy 174.652432 -259.57149) (xy 174.652027 -259.581665) (xy 174.64424 -259.600465) (xy 174.629848 -259.614851)
			(xy 174.611045 -259.622631) (xy 174.60087 -259.623052) (xy 173.20133 -259.623052) (xy 173.191159 -259.622611)
			(xy 173.172363 -259.614834) (xy 173.157977 -259.600454) (xy 173.150193 -259.581661) (xy 173.149768 -259.57149)
			(xy 171.2087 -259.57149) (xy 171.208159 -259.581642) (xy 171.200395 -259.600404) (xy 171.186044 -259.614768)
			(xy 171.16729 -259.62255) (xy 171.157138 -259.623052) (xy 169.757598 -259.623052) (xy 169.747425 -259.622638)
			(xy 169.728628 -259.61485) (xy 169.714243 -259.600462) (xy 169.70646 -259.581663) (xy 169.706036 -259.57149)
			(xy 167.108632 -259.57149) (xy 167.108227 -259.581665) (xy 167.10044 -259.600465) (xy 167.086048 -259.614851)
			(xy 167.067245 -259.622631) (xy 167.05707 -259.623052) (xy 165.65753 -259.623052) (xy 165.647359 -259.622611)
			(xy 165.628563 -259.614834) (xy 165.614177 -259.600454) (xy 165.606393 -259.581661) (xy 165.605968 -259.57149)
			(xy 163.6649 -259.57149) (xy 163.664359 -259.581642) (xy 163.656595 -259.600404) (xy 163.642244 -259.614768)
			(xy 163.62349 -259.62255) (xy 163.613338 -259.623052) (xy 162.213798 -259.623052) (xy 162.203625 -259.622638)
			(xy 162.184828 -259.61485) (xy 162.170443 -259.600462) (xy 162.16266 -259.581663) (xy 162.162236 -259.57149)
			(xy 159.564832 -259.57149) (xy 159.564427 -259.581665) (xy 159.55664 -259.600465) (xy 159.542248 -259.614851)
			(xy 159.523445 -259.622631) (xy 159.51327 -259.623052) (xy 158.11373 -259.623052) (xy 158.103559 -259.622611)
			(xy 158.084763 -259.614834) (xy 158.070377 -259.600454) (xy 158.062593 -259.581661) (xy 158.062168 -259.57149)
			(xy 65.7987 -259.57149) (xy 65.798159 -259.581642) (xy 65.790395 -259.600404) (xy 65.776044 -259.614768)
			(xy 65.75729 -259.62255) (xy 65.747138 -259.623052) (xy 64.347598 -259.623052) (xy 64.337425 -259.622638)
			(xy 64.318628 -259.61485) (xy 64.304243 -259.600462) (xy 64.29646 -259.581663) (xy 64.296036 -259.57149)
			(xy 61.698632 -259.57149) (xy 61.698227 -259.581665) (xy 61.69044 -259.600465) (xy 61.676048 -259.614851)
			(xy 61.657245 -259.622631) (xy 61.64707 -259.623052) (xy 60.24753 -259.623052) (xy 60.237359 -259.622611)
			(xy 60.218563 -259.614834) (xy 60.204177 -259.600454) (xy 60.196393 -259.581661) (xy 60.195968 -259.57149)
			(xy 58.2549 -259.57149) (xy 58.254359 -259.581642) (xy 58.246595 -259.600404) (xy 58.232244 -259.614768)
			(xy 58.21349 -259.62255) (xy 58.203338 -259.623052) (xy 56.803798 -259.623052) (xy 56.793625 -259.622638)
			(xy 56.774828 -259.61485) (xy 56.760443 -259.600462) (xy 56.75266 -259.581663) (xy 56.752236 -259.57149)
			(xy 54.154832 -259.57149) (xy 54.154427 -259.581665) (xy 54.14664 -259.600465) (xy 54.132248 -259.614851)
			(xy 54.113445 -259.622631) (xy 54.10327 -259.623052) (xy 52.70373 -259.623052) (xy 52.693559 -259.622611)
			(xy 52.674763 -259.614834) (xy 52.660377 -259.600454) (xy 52.652593 -259.581661) (xy 52.652168 -259.57149)
			(xy 50.7111 -259.57149) (xy 50.710559 -259.581642) (xy 50.702795 -259.600404) (xy 50.688444 -259.614768)
			(xy 50.66969 -259.62255) (xy 50.659538 -259.623052) (xy 49.259998 -259.623052) (xy 49.249825 -259.622638)
			(xy 49.231028 -259.61485) (xy 49.216643 -259.600462) (xy 49.20886 -259.581663) (xy 49.208436 -259.57149)
			(xy 46.611032 -259.57149) (xy 46.610627 -259.581665) (xy 46.60284 -259.600465) (xy 46.588448 -259.614851)
			(xy 46.569645 -259.622631) (xy 46.55947 -259.623052) (xy 45.15993 -259.623052) (xy 45.149759 -259.622611)
			(xy 45.130963 -259.614834) (xy 45.116577 -259.600454) (xy 45.108793 -259.581661) (xy 45.108368 -259.57149)
			(xy 43.1673 -259.57149) (xy 43.166759 -259.581642) (xy 43.158995 -259.600404) (xy 43.144644 -259.614768)
			(xy 43.12589 -259.62255) (xy 43.115738 -259.623052) (xy 41.716198 -259.623052) (xy 41.706025 -259.622638)
			(xy 41.687228 -259.61485) (xy 41.672843 -259.600462) (xy 41.66506 -259.581663) (xy 41.664636 -259.57149)
			(xy 39.067232 -259.57149) (xy 39.066827 -259.581665) (xy 39.05904 -259.600465) (xy 39.044648 -259.614851)
			(xy 39.025845 -259.622631) (xy 39.01567 -259.623052) (xy 37.61613 -259.623052) (xy 37.605959 -259.622611)
			(xy 37.587163 -259.614834) (xy 37.572777 -259.600454) (xy 37.564993 -259.581661) (xy 37.564568 -259.57149)
			(xy 35.6235 -259.57149) (xy 35.622959 -259.581642) (xy 35.615195 -259.600404) (xy 35.600844 -259.614768)
			(xy 35.58209 -259.62255) (xy 35.571938 -259.623052) (xy 34.172398 -259.623052) (xy 34.162225 -259.622638)
			(xy 34.143428 -259.61485) (xy 34.129043 -259.600462) (xy 34.12126 -259.581663) (xy 34.120836 -259.57149)
			(xy 31.523432 -259.57149) (xy 31.523027 -259.581665) (xy 31.51524 -259.600465) (xy 31.500848 -259.614851)
			(xy 31.482045 -259.622631) (xy 31.47187 -259.623052) (xy 30.07233 -259.623052) (xy 30.062159 -259.622611)
			(xy 30.043363 -259.614834) (xy 30.028977 -259.600454) (xy 30.021193 -259.581661) (xy 30.020768 -259.57149)
			(xy 28.0797 -259.57149) (xy 28.079159 -259.581642) (xy 28.071395 -259.600404) (xy 28.057044 -259.614768)
			(xy 28.03829 -259.62255) (xy 28.028138 -259.623052) (xy 26.628598 -259.623052) (xy 26.618425 -259.622638)
			(xy 26.599628 -259.61485) (xy 26.585243 -259.600462) (xy 26.57746 -259.581663) (xy 26.577036 -259.57149)
			(xy 23.979632 -259.57149) (xy 23.979227 -259.581665) (xy 23.97144 -259.600465) (xy 23.957048 -259.614851)
			(xy 23.938245 -259.622631) (xy 23.92807 -259.623052) (xy 22.52853 -259.623052) (xy 22.518359 -259.622611)
			(xy 22.499563 -259.614834) (xy 22.485177 -259.600454) (xy 22.477393 -259.581661) (xy 22.476968 -259.57149)
			(xy 20.5359 -259.57149) (xy 20.535359 -259.581642) (xy 20.527595 -259.600404) (xy 20.513244 -259.614768)
			(xy 20.49449 -259.62255) (xy 20.484338 -259.623052) (xy 19.084798 -259.623052) (xy 19.074625 -259.622638)
			(xy 19.055828 -259.61485) (xy 19.041443 -259.600462) (xy 19.03366 -259.581663) (xy 19.033236 -259.57149)
			(xy 16.435832 -259.57149) (xy 16.435427 -259.581665) (xy 16.42764 -259.600465) (xy 16.413248 -259.614851)
			(xy 16.394445 -259.622631) (xy 16.38427 -259.623052) (xy 14.98473 -259.623052) (xy 14.974559 -259.622611)
			(xy 14.955763 -259.614834) (xy 14.941377 -259.600454) (xy 14.933593 -259.581661) (xy 14.933168 -259.57149)
			(xy 12.9921 -259.57149) (xy 12.991559 -259.581642) (xy 12.983795 -259.600404) (xy 12.969444 -259.614768)
			(xy 12.95069 -259.62255) (xy 12.940538 -259.623052) (xy 11.540998 -259.623052) (xy 11.530825 -259.622638)
			(xy 11.512028 -259.61485) (xy 11.497643 -259.600462) (xy 11.48986 -259.581663) (xy 11.489436 -259.57149)
			(xy 8.892032 -259.57149) (xy 8.891627 -259.581665) (xy 8.88384 -259.600465) (xy 8.869448 -259.614851)
			(xy 8.850645 -259.622631) (xy 8.84047 -259.623052) (xy 7.44093 -259.623052) (xy 7.430759 -259.622611)
			(xy 7.411963 -259.614834) (xy 7.397577 -259.600454) (xy 7.389793 -259.581661) (xy 7.389368 -259.57149)
			(xy 2.509012 -259.57149) (xy 2.509012 -260.421374) (xy 11.489436 -260.421374) (xy 11.489436 -260.012434)
			(xy 11.489892 -260.002265) (xy 11.497665 -259.983471) (xy 11.512041 -259.969085) (xy 11.530829 -259.961299)
			(xy 11.540998 -259.960872) (xy 12.940538 -259.960872) (xy 12.950702 -259.961303) (xy 12.969479 -259.969096)
			(xy 12.983844 -259.983482) (xy 12.991611 -260.002269) (xy 12.9921 -260.012434) (xy 12.9921 -260.421374)
			(xy 19.033236 -260.421374) (xy 19.033236 -260.012434) (xy 19.033692 -260.002265) (xy 19.041465 -259.983471)
			(xy 19.055841 -259.969085) (xy 19.074629 -259.961299) (xy 19.084798 -259.960872) (xy 20.484338 -259.960872)
			(xy 20.494502 -259.961303) (xy 20.513279 -259.969096) (xy 20.527644 -259.983482) (xy 20.535411 -260.002269)
			(xy 20.5359 -260.012434) (xy 20.5359 -260.421374) (xy 26.577036 -260.421374) (xy 26.577036 -260.012434)
			(xy 26.577492 -260.002265) (xy 26.585265 -259.983471) (xy 26.599641 -259.969085) (xy 26.618429 -259.961299)
			(xy 26.628598 -259.960872) (xy 28.028138 -259.960872) (xy 28.038302 -259.961303) (xy 28.057079 -259.969096)
			(xy 28.071444 -259.983482) (xy 28.079211 -260.002269) (xy 28.0797 -260.012434) (xy 28.0797 -260.421374)
			(xy 34.120836 -260.421374) (xy 34.120836 -260.012434) (xy 34.121292 -260.002265) (xy 34.129065 -259.983471)
			(xy 34.143441 -259.969085) (xy 34.162229 -259.961299) (xy 34.172398 -259.960872) (xy 35.571938 -259.960872)
			(xy 35.582102 -259.961303) (xy 35.600879 -259.969096) (xy 35.615244 -259.983482) (xy 35.623011 -260.002269)
			(xy 35.6235 -260.012434) (xy 35.6235 -260.421374) (xy 41.664636 -260.421374) (xy 41.664636 -260.012434)
			(xy 41.665092 -260.002265) (xy 41.672865 -259.983471) (xy 41.687241 -259.969085) (xy 41.706029 -259.961299)
			(xy 41.716198 -259.960872) (xy 43.115738 -259.960872) (xy 43.125902 -259.961303) (xy 43.144679 -259.969096)
			(xy 43.159044 -259.983482) (xy 43.166811 -260.002269) (xy 43.1673 -260.012434) (xy 43.1673 -260.421374)
			(xy 49.208436 -260.421374) (xy 49.208436 -260.012434) (xy 49.208892 -260.002265) (xy 49.216665 -259.983471)
			(xy 49.231041 -259.969085) (xy 49.249829 -259.961299) (xy 49.259998 -259.960872) (xy 50.659538 -259.960872)
			(xy 50.669702 -259.961303) (xy 50.688479 -259.969096) (xy 50.702844 -259.983482) (xy 50.710611 -260.002269)
			(xy 50.7111 -260.012434) (xy 50.7111 -260.421374) (xy 56.752236 -260.421374) (xy 56.752236 -260.012434)
			(xy 56.752692 -260.002265) (xy 56.760465 -259.983471) (xy 56.774841 -259.969085) (xy 56.793629 -259.961299)
			(xy 56.803798 -259.960872) (xy 58.203338 -259.960872) (xy 58.213502 -259.961303) (xy 58.232279 -259.969096)
			(xy 58.246644 -259.983482) (xy 58.254411 -260.002269) (xy 58.2549 -260.012434) (xy 58.2549 -260.421374)
			(xy 64.296036 -260.421374) (xy 64.296036 -260.012434) (xy 64.296492 -260.002265) (xy 64.304265 -259.983471)
			(xy 64.318641 -259.969085) (xy 64.337429 -259.961299) (xy 64.347598 -259.960872) (xy 65.747138 -259.960872)
			(xy 65.757302 -259.961303) (xy 65.776079 -259.969096) (xy 65.790444 -259.983482) (xy 65.798211 -260.002269)
			(xy 65.7987 -260.012434) (xy 65.7987 -260.421374) (xy 162.162236 -260.421374) (xy 162.162236 -260.012434)
			(xy 162.162692 -260.002265) (xy 162.170465 -259.983471) (xy 162.184841 -259.969085) (xy 162.203629 -259.961299)
			(xy 162.213798 -259.960872) (xy 163.613338 -259.960872) (xy 163.623502 -259.961303) (xy 163.642279 -259.969096)
			(xy 163.656644 -259.983482) (xy 163.664411 -260.002269) (xy 163.6649 -260.012434) (xy 163.6649 -260.421374)
			(xy 169.706036 -260.421374) (xy 169.706036 -260.012434) (xy 169.706492 -260.002265) (xy 169.714265 -259.983471)
			(xy 169.728641 -259.969085) (xy 169.747429 -259.961299) (xy 169.757598 -259.960872) (xy 171.157138 -259.960872)
			(xy 171.167302 -259.961303) (xy 171.186079 -259.969096) (xy 171.200444 -259.983482) (xy 171.208211 -260.002269)
			(xy 171.2087 -260.012434) (xy 171.2087 -260.421374) (xy 177.249836 -260.421374) (xy 177.249836 -260.012434)
			(xy 177.250292 -260.002265) (xy 177.258065 -259.983471) (xy 177.272441 -259.969085) (xy 177.291229 -259.961299)
			(xy 177.301398 -259.960872) (xy 178.700938 -259.960872) (xy 178.711102 -259.961303) (xy 178.729879 -259.969096)
			(xy 178.744244 -259.983482) (xy 178.752011 -260.002269) (xy 178.7525 -260.012434) (xy 178.7525 -260.421374)
			(xy 184.793636 -260.421374) (xy 184.793636 -260.012434) (xy 184.794092 -260.002265) (xy 184.801865 -259.983471)
			(xy 184.816241 -259.969085) (xy 184.835029 -259.961299) (xy 184.845198 -259.960872) (xy 186.244738 -259.960872)
			(xy 186.254902 -259.961303) (xy 186.273679 -259.969096) (xy 186.288044 -259.983482) (xy 186.295811 -260.002269)
			(xy 186.2963 -260.012434) (xy 186.2963 -260.421374) (xy 192.337436 -260.421374) (xy 192.337436 -260.012434)
			(xy 192.337892 -260.002265) (xy 192.345665 -259.983471) (xy 192.360041 -259.969085) (xy 192.378829 -259.961299)
			(xy 192.388998 -259.960872) (xy 193.788538 -259.960872) (xy 193.798702 -259.961303) (xy 193.817479 -259.969096)
			(xy 193.831844 -259.983482) (xy 193.839611 -260.002269) (xy 193.8401 -260.012434) (xy 193.8401 -260.421374)
			(xy 199.881236 -260.421374) (xy 199.881236 -260.012434) (xy 199.881692 -260.002265) (xy 199.889465 -259.983471)
			(xy 199.903841 -259.969085) (xy 199.922629 -259.961299) (xy 199.932798 -259.960872) (xy 201.332338 -259.960872)
			(xy 201.342502 -259.961303) (xy 201.361279 -259.969096) (xy 201.375644 -259.983482) (xy 201.383411 -260.002269)
			(xy 201.3839 -260.012434) (xy 201.3839 -260.421374) (xy 207.425036 -260.421374) (xy 207.425036 -260.012434)
			(xy 207.425492 -260.002265) (xy 207.433265 -259.983471) (xy 207.447641 -259.969085) (xy 207.466429 -259.961299)
			(xy 207.476598 -259.960872) (xy 208.876138 -259.960872) (xy 208.886302 -259.961303) (xy 208.905079 -259.969096)
			(xy 208.919444 -259.983482) (xy 208.927211 -260.002269) (xy 208.9277 -260.012434) (xy 208.9277 -260.421374)
			(xy 214.968836 -260.421374) (xy 214.968836 -260.012434) (xy 214.969292 -260.002265) (xy 214.977065 -259.983471)
			(xy 214.991441 -259.969085) (xy 215.010229 -259.961299) (xy 215.020398 -259.960872) (xy 216.419938 -259.960872)
			(xy 216.430102 -259.961303) (xy 216.448879 -259.969096) (xy 216.463244 -259.983482) (xy 216.471011 -260.002269)
			(xy 216.4715 -260.012434) (xy 216.4715 -260.421374) (xy 259.429504 -260.421374) (xy 259.429504 -260.012434)
			(xy 259.430061 -260.002283) (xy 259.437817 -259.983521) (xy 259.452164 -259.969156) (xy 259.470915 -259.961374)
			(xy 259.481066 -259.960872) (xy 260.880606 -259.960872) (xy 260.890782 -259.96126) (xy 260.909584 -259.969053)
			(xy 260.923969 -259.98345) (xy 260.931748 -260.002257) (xy 260.932168 -260.012434) (xy 260.932168 -260.421374)
			(xy 266.973304 -260.421374) (xy 266.973304 -260.012434) (xy 266.973861 -260.002283) (xy 266.981617 -259.983521)
			(xy 266.995964 -259.969156) (xy 267.014715 -259.961374) (xy 267.024866 -259.960872) (xy 268.424406 -259.960872)
			(xy 268.434582 -259.96126) (xy 268.453384 -259.969053) (xy 268.467769 -259.98345) (xy 268.475548 -260.002257)
			(xy 268.475968 -260.012434) (xy 268.475968 -260.421374) (xy 274.517104 -260.421374) (xy 274.517104 -260.012434)
			(xy 274.517661 -260.002283) (xy 274.525417 -259.983521) (xy 274.539764 -259.969156) (xy 274.558515 -259.961374)
			(xy 274.568666 -259.960872) (xy 275.968206 -259.960872) (xy 275.978382 -259.96126) (xy 275.997184 -259.969053)
			(xy 276.011569 -259.98345) (xy 276.019348 -260.002257) (xy 276.019768 -260.012434) (xy 276.019768 -260.421374)
			(xy 282.060904 -260.421374) (xy 282.060904 -260.012434) (xy 282.061461 -260.002283) (xy 282.069217 -259.983521)
			(xy 282.083564 -259.969156) (xy 282.102315 -259.961374) (xy 282.112466 -259.960872) (xy 283.512006 -259.960872)
			(xy 283.522182 -259.96126) (xy 283.540984 -259.969053) (xy 283.555369 -259.98345) (xy 283.563148 -260.002257)
			(xy 283.563568 -260.012434) (xy 283.563568 -260.421374) (xy 289.604704 -260.421374) (xy 289.604704 -260.012434)
			(xy 289.605261 -260.002283) (xy 289.613017 -259.983521) (xy 289.627364 -259.969156) (xy 289.646115 -259.961374)
			(xy 289.656266 -259.960872) (xy 291.055806 -259.960872) (xy 291.065982 -259.96126) (xy 291.084784 -259.969053)
			(xy 291.099169 -259.98345) (xy 291.106948 -260.002257) (xy 291.107368 -260.012434) (xy 291.107368 -260.421374)
			(xy 297.148504 -260.421374) (xy 297.148504 -260.012434) (xy 297.149061 -260.002283) (xy 297.156817 -259.983521)
			(xy 297.171164 -259.969156) (xy 297.189915 -259.961374) (xy 297.200066 -259.960872) (xy 298.599606 -259.960872)
			(xy 298.609782 -259.96126) (xy 298.628584 -259.969053) (xy 298.642969 -259.98345) (xy 298.650748 -260.002257)
			(xy 298.651168 -260.012434) (xy 298.651168 -260.421374) (xy 304.692304 -260.421374) (xy 304.692304 -260.012434)
			(xy 304.692861 -260.002283) (xy 304.700617 -259.983521) (xy 304.714964 -259.969156) (xy 304.733715 -259.961374)
			(xy 304.743866 -259.960872) (xy 306.143406 -259.960872) (xy 306.153582 -259.96126) (xy 306.172384 -259.969053)
			(xy 306.186769 -259.98345) (xy 306.194548 -260.002257) (xy 306.194968 -260.012434) (xy 306.194968 -260.421374)
			(xy 312.236104 -260.421374) (xy 312.236104 -260.012434) (xy 312.236661 -260.002283) (xy 312.244417 -259.983521)
			(xy 312.258764 -259.969156) (xy 312.277515 -259.961374) (xy 312.287666 -259.960872) (xy 313.687206 -259.960872)
			(xy 313.697382 -259.96126) (xy 313.716184 -259.969053) (xy 313.730569 -259.98345) (xy 313.738348 -260.002257)
			(xy 313.738768 -260.012434) (xy 313.738768 -260.421374) (xy 410.102304 -260.421374) (xy 410.102304 -260.012434)
			(xy 410.102861 -260.002283) (xy 410.110617 -259.983521) (xy 410.124964 -259.969156) (xy 410.143715 -259.961374)
			(xy 410.153866 -259.960872) (xy 411.553406 -259.960872) (xy 411.563582 -259.96126) (xy 411.582384 -259.969053)
			(xy 411.596769 -259.98345) (xy 411.604548 -260.002257) (xy 411.604968 -260.012434) (xy 411.604968 -260.421374)
			(xy 417.646104 -260.421374) (xy 417.646104 -260.012434) (xy 417.646661 -260.002283) (xy 417.654417 -259.983521)
			(xy 417.668764 -259.969156) (xy 417.687515 -259.961374) (xy 417.697666 -259.960872) (xy 419.097206 -259.960872)
			(xy 419.107382 -259.96126) (xy 419.126184 -259.969053) (xy 419.140569 -259.98345) (xy 419.148348 -260.002257)
			(xy 419.148768 -260.012434) (xy 419.148768 -260.421374) (xy 425.189904 -260.421374) (xy 425.189904 -260.012434)
			(xy 425.190461 -260.002283) (xy 425.198217 -259.983521) (xy 425.212564 -259.969156) (xy 425.231315 -259.961374)
			(xy 425.241466 -259.960872) (xy 426.641006 -259.960872) (xy 426.651182 -259.96126) (xy 426.669984 -259.969053)
			(xy 426.684369 -259.98345) (xy 426.692148 -260.002257) (xy 426.692568 -260.012434) (xy 426.692568 -260.421374)
			(xy 432.733704 -260.421374) (xy 432.733704 -260.012434) (xy 432.734261 -260.002283) (xy 432.742017 -259.983521)
			(xy 432.756364 -259.969156) (xy 432.775115 -259.961374) (xy 432.785266 -259.960872) (xy 434.184806 -259.960872)
			(xy 434.194982 -259.96126) (xy 434.213784 -259.969053) (xy 434.228169 -259.98345) (xy 434.235948 -260.002257)
			(xy 434.236368 -260.012434) (xy 434.236368 -260.421374) (xy 440.277504 -260.421374) (xy 440.277504 -260.012434)
			(xy 440.278061 -260.002283) (xy 440.285817 -259.983521) (xy 440.300164 -259.969156) (xy 440.318915 -259.961374)
			(xy 440.329066 -259.960872) (xy 441.728606 -259.960872) (xy 441.738782 -259.96126) (xy 441.757584 -259.969053)
			(xy 441.771969 -259.98345) (xy 441.779748 -260.002257) (xy 441.780168 -260.012434) (xy 441.780168 -260.421374)
			(xy 447.821304 -260.421374) (xy 447.821304 -260.012434) (xy 447.821861 -260.002283) (xy 447.829617 -259.983521)
			(xy 447.843964 -259.969156) (xy 447.862715 -259.961374) (xy 447.872866 -259.960872) (xy 449.272406 -259.960872)
			(xy 449.282582 -259.96126) (xy 449.301384 -259.969053) (xy 449.315769 -259.98345) (xy 449.323548 -260.002257)
			(xy 449.323968 -260.012434) (xy 449.323968 -260.421374) (xy 455.365104 -260.421374) (xy 455.365104 -260.012434)
			(xy 455.365661 -260.002283) (xy 455.373417 -259.983521) (xy 455.387764 -259.969156) (xy 455.406515 -259.961374)
			(xy 455.416666 -259.960872) (xy 456.816206 -259.960872) (xy 456.826382 -259.96126) (xy 456.845184 -259.969053)
			(xy 456.859569 -259.98345) (xy 456.867348 -260.002257) (xy 456.867768 -260.012434) (xy 456.867768 -260.421374)
			(xy 462.908904 -260.421374) (xy 462.908904 -260.012434) (xy 462.909461 -260.002283) (xy 462.917217 -259.983521)
			(xy 462.931564 -259.969156) (xy 462.950315 -259.961374) (xy 462.960466 -259.960872) (xy 464.360006 -259.960872)
			(xy 464.370182 -259.96126) (xy 464.388984 -259.969053) (xy 464.403369 -259.98345) (xy 464.411148 -260.002257)
			(xy 464.411568 -260.012434) (xy 464.411568 -260.421374) (xy 464.411115 -260.431543) (xy 464.40334 -260.450336)
			(xy 464.388963 -260.464722) (xy 464.370175 -260.472509) (xy 464.360006 -260.472936) (xy 462.960466 -260.472936)
			(xy 462.950303 -260.472494) (xy 462.931528 -260.464703) (xy 462.917163 -260.450322) (xy 462.909394 -260.431538)
			(xy 462.908904 -260.421374) (xy 456.867768 -260.421374) (xy 456.867315 -260.431543) (xy 456.85954 -260.450336)
			(xy 456.845163 -260.464722) (xy 456.826375 -260.472509) (xy 456.816206 -260.472936) (xy 455.416666 -260.472936)
			(xy 455.406503 -260.472494) (xy 455.387728 -260.464703) (xy 455.373363 -260.450322) (xy 455.365594 -260.431538)
			(xy 455.365104 -260.421374) (xy 449.323968 -260.421374) (xy 449.323515 -260.431543) (xy 449.31574 -260.450336)
			(xy 449.301363 -260.464722) (xy 449.282575 -260.472509) (xy 449.272406 -260.472936) (xy 447.872866 -260.472936)
			(xy 447.862703 -260.472494) (xy 447.843928 -260.464703) (xy 447.829563 -260.450322) (xy 447.821794 -260.431538)
			(xy 447.821304 -260.421374) (xy 441.780168 -260.421374) (xy 441.779715 -260.431543) (xy 441.77194 -260.450336)
			(xy 441.757563 -260.464722) (xy 441.738775 -260.472509) (xy 441.728606 -260.472936) (xy 440.329066 -260.472936)
			(xy 440.318903 -260.472494) (xy 440.300128 -260.464703) (xy 440.285763 -260.450322) (xy 440.277994 -260.431538)
			(xy 440.277504 -260.421374) (xy 434.236368 -260.421374) (xy 434.235915 -260.431543) (xy 434.22814 -260.450336)
			(xy 434.213763 -260.464722) (xy 434.194975 -260.472509) (xy 434.184806 -260.472936) (xy 432.785266 -260.472936)
			(xy 432.775103 -260.472494) (xy 432.756328 -260.464703) (xy 432.741963 -260.450322) (xy 432.734194 -260.431538)
			(xy 432.733704 -260.421374) (xy 426.692568 -260.421374) (xy 426.692115 -260.431543) (xy 426.68434 -260.450336)
			(xy 426.669963 -260.464722) (xy 426.651175 -260.472509) (xy 426.641006 -260.472936) (xy 425.241466 -260.472936)
			(xy 425.231303 -260.472494) (xy 425.212528 -260.464703) (xy 425.198163 -260.450322) (xy 425.190394 -260.431538)
			(xy 425.189904 -260.421374) (xy 419.148768 -260.421374) (xy 419.148315 -260.431543) (xy 419.14054 -260.450336)
			(xy 419.126163 -260.464722) (xy 419.107375 -260.472509) (xy 419.097206 -260.472936) (xy 417.697666 -260.472936)
			(xy 417.687503 -260.472494) (xy 417.668728 -260.464703) (xy 417.654363 -260.450322) (xy 417.646594 -260.431538)
			(xy 417.646104 -260.421374) (xy 411.604968 -260.421374) (xy 411.604515 -260.431543) (xy 411.59674 -260.450336)
			(xy 411.582363 -260.464722) (xy 411.563575 -260.472509) (xy 411.553406 -260.472936) (xy 410.153866 -260.472936)
			(xy 410.143703 -260.472494) (xy 410.124928 -260.464703) (xy 410.110563 -260.450322) (xy 410.102794 -260.431538)
			(xy 410.102304 -260.421374) (xy 313.738768 -260.421374) (xy 313.738315 -260.431543) (xy 313.73054 -260.450336)
			(xy 313.716163 -260.464722) (xy 313.697375 -260.472509) (xy 313.687206 -260.472936) (xy 312.287666 -260.472936)
			(xy 312.277503 -260.472494) (xy 312.258728 -260.464703) (xy 312.244363 -260.450322) (xy 312.236594 -260.431538)
			(xy 312.236104 -260.421374) (xy 306.194968 -260.421374) (xy 306.194515 -260.431543) (xy 306.18674 -260.450336)
			(xy 306.172363 -260.464722) (xy 306.153575 -260.472509) (xy 306.143406 -260.472936) (xy 304.743866 -260.472936)
			(xy 304.733703 -260.472494) (xy 304.714928 -260.464703) (xy 304.700563 -260.450322) (xy 304.692794 -260.431538)
			(xy 304.692304 -260.421374) (xy 298.651168 -260.421374) (xy 298.650715 -260.431543) (xy 298.64294 -260.450336)
			(xy 298.628563 -260.464722) (xy 298.609775 -260.472509) (xy 298.599606 -260.472936) (xy 297.200066 -260.472936)
			(xy 297.189903 -260.472494) (xy 297.171128 -260.464703) (xy 297.156763 -260.450322) (xy 297.148994 -260.431538)
			(xy 297.148504 -260.421374) (xy 291.107368 -260.421374) (xy 291.106915 -260.431543) (xy 291.09914 -260.450336)
			(xy 291.084763 -260.464722) (xy 291.065975 -260.472509) (xy 291.055806 -260.472936) (xy 289.656266 -260.472936)
			(xy 289.646103 -260.472494) (xy 289.627328 -260.464703) (xy 289.612963 -260.450322) (xy 289.605194 -260.431538)
			(xy 289.604704 -260.421374) (xy 283.563568 -260.421374) (xy 283.563115 -260.431543) (xy 283.55534 -260.450336)
			(xy 283.540963 -260.464722) (xy 283.522175 -260.472509) (xy 283.512006 -260.472936) (xy 282.112466 -260.472936)
			(xy 282.102303 -260.472494) (xy 282.083528 -260.464703) (xy 282.069163 -260.450322) (xy 282.061394 -260.431538)
			(xy 282.060904 -260.421374) (xy 276.019768 -260.421374) (xy 276.019315 -260.431543) (xy 276.01154 -260.450336)
			(xy 275.997163 -260.464722) (xy 275.978375 -260.472509) (xy 275.968206 -260.472936) (xy 274.568666 -260.472936)
			(xy 274.558503 -260.472494) (xy 274.539728 -260.464703) (xy 274.525363 -260.450322) (xy 274.517594 -260.431538)
			(xy 274.517104 -260.421374) (xy 268.475968 -260.421374) (xy 268.475515 -260.431543) (xy 268.46774 -260.450336)
			(xy 268.453363 -260.464722) (xy 268.434575 -260.472509) (xy 268.424406 -260.472936) (xy 267.024866 -260.472936)
			(xy 267.014703 -260.472494) (xy 266.995928 -260.464703) (xy 266.981563 -260.450322) (xy 266.973794 -260.431538)
			(xy 266.973304 -260.421374) (xy 260.932168 -260.421374) (xy 260.931715 -260.431543) (xy 260.92394 -260.450336)
			(xy 260.909563 -260.464722) (xy 260.890775 -260.472509) (xy 260.880606 -260.472936) (xy 259.481066 -260.472936)
			(xy 259.470903 -260.472494) (xy 259.452128 -260.464703) (xy 259.437763 -260.450322) (xy 259.429994 -260.431538)
			(xy 259.429504 -260.421374) (xy 216.4715 -260.421374) (xy 216.470946 -260.431525) (xy 216.463188 -260.450287)
			(xy 216.448841 -260.464652) (xy 216.430089 -260.472434) (xy 216.419938 -260.472936) (xy 215.020398 -260.472936)
			(xy 215.010223 -260.472537) (xy 214.991423 -260.464747) (xy 214.977038 -260.450353) (xy 214.969257 -260.431549)
			(xy 214.968836 -260.421374) (xy 208.9277 -260.421374) (xy 208.927146 -260.431525) (xy 208.919388 -260.450287)
			(xy 208.905041 -260.464652) (xy 208.886289 -260.472434) (xy 208.876138 -260.472936) (xy 207.476598 -260.472936)
			(xy 207.466423 -260.472537) (xy 207.447623 -260.464747) (xy 207.433238 -260.450353) (xy 207.425457 -260.431549)
			(xy 207.425036 -260.421374) (xy 201.3839 -260.421374) (xy 201.383346 -260.431525) (xy 201.375588 -260.450287)
			(xy 201.361241 -260.464652) (xy 201.342489 -260.472434) (xy 201.332338 -260.472936) (xy 199.932798 -260.472936)
			(xy 199.922623 -260.472537) (xy 199.903823 -260.464747) (xy 199.889438 -260.450353) (xy 199.881657 -260.431549)
			(xy 199.881236 -260.421374) (xy 193.8401 -260.421374) (xy 193.839546 -260.431525) (xy 193.831788 -260.450287)
			(xy 193.817441 -260.464652) (xy 193.798689 -260.472434) (xy 193.788538 -260.472936) (xy 192.388998 -260.472936)
			(xy 192.378823 -260.472537) (xy 192.360023 -260.464747) (xy 192.345638 -260.450353) (xy 192.337857 -260.431549)
			(xy 192.337436 -260.421374) (xy 186.2963 -260.421374) (xy 186.295746 -260.431525) (xy 186.287988 -260.450287)
			(xy 186.273641 -260.464652) (xy 186.254889 -260.472434) (xy 186.244738 -260.472936) (xy 184.845198 -260.472936)
			(xy 184.835023 -260.472537) (xy 184.816223 -260.464747) (xy 184.801838 -260.450353) (xy 184.794057 -260.431549)
			(xy 184.793636 -260.421374) (xy 178.7525 -260.421374) (xy 178.751946 -260.431525) (xy 178.744188 -260.450287)
			(xy 178.729841 -260.464652) (xy 178.711089 -260.472434) (xy 178.700938 -260.472936) (xy 177.301398 -260.472936)
			(xy 177.291223 -260.472537) (xy 177.272423 -260.464747) (xy 177.258038 -260.450353) (xy 177.250257 -260.431549)
			(xy 177.249836 -260.421374) (xy 171.2087 -260.421374) (xy 171.208146 -260.431525) (xy 171.200388 -260.450287)
			(xy 171.186041 -260.464652) (xy 171.167289 -260.472434) (xy 171.157138 -260.472936) (xy 169.757598 -260.472936)
			(xy 169.747423 -260.472537) (xy 169.728623 -260.464747) (xy 169.714238 -260.450353) (xy 169.706457 -260.431549)
			(xy 169.706036 -260.421374) (xy 163.6649 -260.421374) (xy 163.664346 -260.431525) (xy 163.656588 -260.450287)
			(xy 163.642241 -260.464652) (xy 163.623489 -260.472434) (xy 163.613338 -260.472936) (xy 162.213798 -260.472936)
			(xy 162.203623 -260.472537) (xy 162.184823 -260.464747) (xy 162.170438 -260.450353) (xy 162.162657 -260.431549)
			(xy 162.162236 -260.421374) (xy 65.7987 -260.421374) (xy 65.798146 -260.431525) (xy 65.790388 -260.450287)
			(xy 65.776041 -260.464652) (xy 65.757289 -260.472434) (xy 65.747138 -260.472936) (xy 64.347598 -260.472936)
			(xy 64.337423 -260.472537) (xy 64.318623 -260.464747) (xy 64.304238 -260.450353) (xy 64.296457 -260.431549)
			(xy 64.296036 -260.421374) (xy 58.2549 -260.421374) (xy 58.254346 -260.431525) (xy 58.246588 -260.450287)
			(xy 58.232241 -260.464652) (xy 58.213489 -260.472434) (xy 58.203338 -260.472936) (xy 56.803798 -260.472936)
			(xy 56.793623 -260.472537) (xy 56.774823 -260.464747) (xy 56.760438 -260.450353) (xy 56.752657 -260.431549)
			(xy 56.752236 -260.421374) (xy 50.7111 -260.421374) (xy 50.710546 -260.431525) (xy 50.702788 -260.450287)
			(xy 50.688441 -260.464652) (xy 50.669689 -260.472434) (xy 50.659538 -260.472936) (xy 49.259998 -260.472936)
			(xy 49.249823 -260.472537) (xy 49.231023 -260.464747) (xy 49.216638 -260.450353) (xy 49.208857 -260.431549)
			(xy 49.208436 -260.421374) (xy 43.1673 -260.421374) (xy 43.166746 -260.431525) (xy 43.158988 -260.450287)
			(xy 43.144641 -260.464652) (xy 43.125889 -260.472434) (xy 43.115738 -260.472936) (xy 41.716198 -260.472936)
			(xy 41.706023 -260.472537) (xy 41.687223 -260.464747) (xy 41.672838 -260.450353) (xy 41.665057 -260.431549)
			(xy 41.664636 -260.421374) (xy 35.6235 -260.421374) (xy 35.622946 -260.431525) (xy 35.615188 -260.450287)
			(xy 35.600841 -260.464652) (xy 35.582089 -260.472434) (xy 35.571938 -260.472936) (xy 34.172398 -260.472936)
			(xy 34.162223 -260.472537) (xy 34.143423 -260.464747) (xy 34.129038 -260.450353) (xy 34.121257 -260.431549)
			(xy 34.120836 -260.421374) (xy 28.0797 -260.421374) (xy 28.079146 -260.431525) (xy 28.071388 -260.450287)
			(xy 28.057041 -260.464652) (xy 28.038289 -260.472434) (xy 28.028138 -260.472936) (xy 26.628598 -260.472936)
			(xy 26.618423 -260.472537) (xy 26.599623 -260.464747) (xy 26.585238 -260.450353) (xy 26.577457 -260.431549)
			(xy 26.577036 -260.421374) (xy 20.5359 -260.421374) (xy 20.535346 -260.431525) (xy 20.527588 -260.450287)
			(xy 20.513241 -260.464652) (xy 20.494489 -260.472434) (xy 20.484338 -260.472936) (xy 19.084798 -260.472936)
			(xy 19.074623 -260.472537) (xy 19.055823 -260.464747) (xy 19.041438 -260.450353) (xy 19.033657 -260.431549)
			(xy 19.033236 -260.421374) (xy 12.9921 -260.421374) (xy 12.991546 -260.431525) (xy 12.983788 -260.450287)
			(xy 12.969441 -260.464652) (xy 12.950689 -260.472434) (xy 12.940538 -260.472936) (xy 11.540998 -260.472936)
			(xy 11.530823 -260.472537) (xy 11.512023 -260.464747) (xy 11.497638 -260.450353) (xy 11.489857 -260.431549)
			(xy 11.489436 -260.421374) (xy 2.509012 -260.421374) (xy 2.509012 -261.271512) (xy 7.389368 -261.271512)
			(xy 7.389368 -260.862572) (xy 7.389798 -260.85242) (xy 7.397597 -260.833673) (xy 7.41199 -260.819352)
			(xy 7.430776 -260.811647) (xy 7.44093 -260.811264) (xy 8.84047 -260.811264) (xy 8.850598 -260.811752)
			(xy 8.869323 -260.819474) (xy 8.883681 -260.833761) (xy 8.891497 -260.852447) (xy 8.892032 -260.862572)
			(xy 8.892032 -261.271512) (xy 14.933168 -261.271512) (xy 14.933168 -260.862572) (xy 14.933598 -260.85242)
			(xy 14.941397 -260.833673) (xy 14.95579 -260.819352) (xy 14.974576 -260.811647) (xy 14.98473 -260.811264)
			(xy 16.38427 -260.811264) (xy 16.394398 -260.811752) (xy 16.413123 -260.819474) (xy 16.427481 -260.833761)
			(xy 16.435297 -260.852447) (xy 16.435832 -260.862572) (xy 16.435832 -261.271512) (xy 22.476968 -261.271512)
			(xy 22.476968 -260.862572) (xy 22.477398 -260.85242) (xy 22.485197 -260.833673) (xy 22.49959 -260.819352)
			(xy 22.518376 -260.811647) (xy 22.52853 -260.811264) (xy 23.92807 -260.811264) (xy 23.938198 -260.811752)
			(xy 23.956923 -260.819474) (xy 23.971281 -260.833761) (xy 23.979097 -260.852447) (xy 23.979632 -260.862572)
			(xy 23.979632 -261.271512) (xy 30.020768 -261.271512) (xy 30.020768 -260.862572) (xy 30.021198 -260.85242)
			(xy 30.028997 -260.833673) (xy 30.04339 -260.819352) (xy 30.062176 -260.811647) (xy 30.07233 -260.811264)
			(xy 31.47187 -260.811264) (xy 31.481998 -260.811752) (xy 31.500723 -260.819474) (xy 31.515081 -260.833761)
			(xy 31.522897 -260.852447) (xy 31.523432 -260.862572) (xy 31.523432 -261.271512) (xy 37.564568 -261.271512)
			(xy 37.564568 -260.862572) (xy 37.564998 -260.85242) (xy 37.572797 -260.833673) (xy 37.58719 -260.819352)
			(xy 37.605976 -260.811647) (xy 37.61613 -260.811264) (xy 39.01567 -260.811264) (xy 39.025798 -260.811752)
			(xy 39.044523 -260.819474) (xy 39.058881 -260.833761) (xy 39.066697 -260.852447) (xy 39.067232 -260.862572)
			(xy 39.067232 -261.271512) (xy 45.108368 -261.271512) (xy 45.108368 -260.862572) (xy 45.108798 -260.85242)
			(xy 45.116597 -260.833673) (xy 45.13099 -260.819352) (xy 45.149776 -260.811647) (xy 45.15993 -260.811264)
			(xy 46.55947 -260.811264) (xy 46.569598 -260.811752) (xy 46.588323 -260.819474) (xy 46.602681 -260.833761)
			(xy 46.610497 -260.852447) (xy 46.611032 -260.862572) (xy 46.611032 -261.271512) (xy 52.652168 -261.271512)
			(xy 52.652168 -260.862572) (xy 52.652598 -260.85242) (xy 52.660397 -260.833673) (xy 52.67479 -260.819352)
			(xy 52.693576 -260.811647) (xy 52.70373 -260.811264) (xy 54.10327 -260.811264) (xy 54.113398 -260.811752)
			(xy 54.132123 -260.819474) (xy 54.146481 -260.833761) (xy 54.154297 -260.852447) (xy 54.154832 -260.862572)
			(xy 54.154832 -261.271512) (xy 60.195968 -261.271512) (xy 60.195968 -260.862572) (xy 60.196398 -260.85242)
			(xy 60.204197 -260.833673) (xy 60.21859 -260.819352) (xy 60.237376 -260.811647) (xy 60.24753 -260.811264)
			(xy 61.64707 -260.811264) (xy 61.657198 -260.811752) (xy 61.675923 -260.819474) (xy 61.690281 -260.833761)
			(xy 61.698097 -260.852447) (xy 61.698632 -260.862572) (xy 61.698632 -261.271512) (xy 158.062168 -261.271512)
			(xy 158.062168 -260.862572) (xy 158.062598 -260.85242) (xy 158.070397 -260.833673) (xy 158.08479 -260.819352)
			(xy 158.103576 -260.811647) (xy 158.11373 -260.811264) (xy 159.51327 -260.811264) (xy 159.523398 -260.811752)
			(xy 159.542123 -260.819474) (xy 159.556481 -260.833761) (xy 159.564297 -260.852447) (xy 159.564832 -260.862572)
			(xy 159.564832 -261.271512) (xy 165.605968 -261.271512) (xy 165.605968 -260.862572) (xy 165.606398 -260.85242)
			(xy 165.614197 -260.833673) (xy 165.62859 -260.819352) (xy 165.647376 -260.811647) (xy 165.65753 -260.811264)
			(xy 167.05707 -260.811264) (xy 167.067198 -260.811752) (xy 167.085923 -260.819474) (xy 167.100281 -260.833761)
			(xy 167.108097 -260.852447) (xy 167.108632 -260.862572) (xy 167.108632 -261.271512) (xy 173.149768 -261.271512)
			(xy 173.149768 -260.862572) (xy 173.150198 -260.85242) (xy 173.157997 -260.833673) (xy 173.17239 -260.819352)
			(xy 173.191176 -260.811647) (xy 173.20133 -260.811264) (xy 174.60087 -260.811264) (xy 174.610998 -260.811752)
			(xy 174.629723 -260.819474) (xy 174.644081 -260.833761) (xy 174.651897 -260.852447) (xy 174.652432 -260.862572)
			(xy 174.652432 -261.271512) (xy 180.693568 -261.271512) (xy 180.693568 -260.862572) (xy 180.693998 -260.85242)
			(xy 180.701797 -260.833673) (xy 180.71619 -260.819352) (xy 180.734976 -260.811647) (xy 180.74513 -260.811264)
			(xy 182.14467 -260.811264) (xy 182.154798 -260.811752) (xy 182.173523 -260.819474) (xy 182.187881 -260.833761)
			(xy 182.195697 -260.852447) (xy 182.196232 -260.862572) (xy 182.196232 -261.271512) (xy 188.237368 -261.271512)
			(xy 188.237368 -260.862572) (xy 188.237798 -260.85242) (xy 188.245597 -260.833673) (xy 188.25999 -260.819352)
			(xy 188.278776 -260.811647) (xy 188.28893 -260.811264) (xy 189.68847 -260.811264) (xy 189.698598 -260.811752)
			(xy 189.717323 -260.819474) (xy 189.731681 -260.833761) (xy 189.739497 -260.852447) (xy 189.740032 -260.862572)
			(xy 189.740032 -261.271512) (xy 195.781168 -261.271512) (xy 195.781168 -260.862572) (xy 195.781598 -260.85242)
			(xy 195.789397 -260.833673) (xy 195.80379 -260.819352) (xy 195.822576 -260.811647) (xy 195.83273 -260.811264)
			(xy 197.23227 -260.811264) (xy 197.242398 -260.811752) (xy 197.261123 -260.819474) (xy 197.275481 -260.833761)
			(xy 197.283297 -260.852447) (xy 197.283832 -260.862572) (xy 197.283832 -261.271512) (xy 203.324968 -261.271512)
			(xy 203.324968 -260.862572) (xy 203.325398 -260.85242) (xy 203.333197 -260.833673) (xy 203.34759 -260.819352)
			(xy 203.366376 -260.811647) (xy 203.37653 -260.811264) (xy 204.77607 -260.811264) (xy 204.786198 -260.811752)
			(xy 204.804923 -260.819474) (xy 204.819281 -260.833761) (xy 204.827097 -260.852447) (xy 204.827632 -260.862572)
			(xy 204.827632 -261.271512) (xy 210.868768 -261.271512) (xy 210.868768 -260.862572) (xy 210.869198 -260.85242)
			(xy 210.876997 -260.833673) (xy 210.89139 -260.819352) (xy 210.910176 -260.811647) (xy 210.92033 -260.811264)
			(xy 212.31987 -260.811264) (xy 212.329998 -260.811752) (xy 212.348723 -260.819474) (xy 212.363081 -260.833761)
			(xy 212.370897 -260.852447) (xy 212.371432 -260.862572) (xy 212.371432 -261.271512) (xy 255.329436 -261.271512)
			(xy 255.329436 -260.862572) (xy 255.329799 -260.852412) (xy 255.337611 -260.833652) (xy 255.352026 -260.819328)
			(xy 255.370835 -260.811636) (xy 255.380998 -260.811264) (xy 256.780538 -260.811264) (xy 256.79067 -260.811696)
			(xy 256.809397 -260.819441) (xy 256.823752 -260.833744) (xy 256.831566 -260.852442) (xy 256.8321 -260.862572)
			(xy 256.8321 -261.271512) (xy 262.873236 -261.271512) (xy 262.873236 -260.862572) (xy 262.873599 -260.852412)
			(xy 262.881411 -260.833652) (xy 262.895826 -260.819328) (xy 262.914635 -260.811636) (xy 262.924798 -260.811264)
			(xy 264.324338 -260.811264) (xy 264.33447 -260.811696) (xy 264.353197 -260.819441) (xy 264.367552 -260.833744)
			(xy 264.375366 -260.852442) (xy 264.3759 -260.862572) (xy 264.3759 -261.271512) (xy 270.417036 -261.271512)
			(xy 270.417036 -260.862572) (xy 270.417399 -260.852412) (xy 270.425211 -260.833652) (xy 270.439626 -260.819328)
			(xy 270.458435 -260.811636) (xy 270.468598 -260.811264) (xy 271.868138 -260.811264) (xy 271.87827 -260.811696)
			(xy 271.896997 -260.819441) (xy 271.911352 -260.833744) (xy 271.919166 -260.852442) (xy 271.9197 -260.862572)
			(xy 271.9197 -261.271512) (xy 277.960836 -261.271512) (xy 277.960836 -260.862572) (xy 277.961199 -260.852412)
			(xy 277.969011 -260.833652) (xy 277.983426 -260.819328) (xy 278.002235 -260.811636) (xy 278.012398 -260.811264)
			(xy 279.411938 -260.811264) (xy 279.42207 -260.811696) (xy 279.440797 -260.819441) (xy 279.455152 -260.833744)
			(xy 279.462966 -260.852442) (xy 279.4635 -260.862572) (xy 279.4635 -261.271512) (xy 285.504636 -261.271512)
			(xy 285.504636 -260.862572) (xy 285.504999 -260.852412) (xy 285.512811 -260.833652) (xy 285.527226 -260.819328)
			(xy 285.546035 -260.811636) (xy 285.556198 -260.811264) (xy 286.955738 -260.811264) (xy 286.96587 -260.811696)
			(xy 286.984597 -260.819441) (xy 286.998952 -260.833744) (xy 287.006766 -260.852442) (xy 287.0073 -260.862572)
			(xy 287.0073 -261.271512) (xy 293.048436 -261.271512) (xy 293.048436 -260.862572) (xy 293.048799 -260.852412)
			(xy 293.056611 -260.833652) (xy 293.071026 -260.819328) (xy 293.089835 -260.811636) (xy 293.099998 -260.811264)
			(xy 294.499538 -260.811264) (xy 294.50967 -260.811696) (xy 294.528397 -260.819441) (xy 294.542752 -260.833744)
			(xy 294.550566 -260.852442) (xy 294.5511 -260.862572) (xy 294.5511 -261.271512) (xy 300.592236 -261.271512)
			(xy 300.592236 -260.862572) (xy 300.592599 -260.852412) (xy 300.600411 -260.833652) (xy 300.614826 -260.819328)
			(xy 300.633635 -260.811636) (xy 300.643798 -260.811264) (xy 302.043338 -260.811264) (xy 302.05347 -260.811696)
			(xy 302.072197 -260.819441) (xy 302.086552 -260.833744) (xy 302.094366 -260.852442) (xy 302.0949 -260.862572)
			(xy 302.0949 -261.271512) (xy 308.136036 -261.271512) (xy 308.136036 -260.862572) (xy 308.136399 -260.852412)
			(xy 308.144211 -260.833652) (xy 308.158626 -260.819328) (xy 308.177435 -260.811636) (xy 308.187598 -260.811264)
			(xy 309.587138 -260.811264) (xy 309.59727 -260.811696) (xy 309.615997 -260.819441) (xy 309.630352 -260.833744)
			(xy 309.638166 -260.852442) (xy 309.6387 -260.862572) (xy 309.6387 -261.271512) (xy 406.002236 -261.271512)
			(xy 406.002236 -260.862572) (xy 406.002599 -260.852412) (xy 406.010411 -260.833652) (xy 406.024826 -260.819328)
			(xy 406.043635 -260.811636) (xy 406.053798 -260.811264) (xy 407.453338 -260.811264) (xy 407.46347 -260.811696)
			(xy 407.482197 -260.819441) (xy 407.496552 -260.833744) (xy 407.504366 -260.852442) (xy 407.5049 -260.862572)
			(xy 407.5049 -261.271512) (xy 413.546036 -261.271512) (xy 413.546036 -260.862572) (xy 413.546399 -260.852412)
			(xy 413.554211 -260.833652) (xy 413.568626 -260.819328) (xy 413.587435 -260.811636) (xy 413.597598 -260.811264)
			(xy 414.997138 -260.811264) (xy 415.00727 -260.811696) (xy 415.025997 -260.819441) (xy 415.040352 -260.833744)
			(xy 415.048166 -260.852442) (xy 415.0487 -260.862572) (xy 415.0487 -261.271512) (xy 421.089836 -261.271512)
			(xy 421.089836 -260.862572) (xy 421.090199 -260.852412) (xy 421.098011 -260.833652) (xy 421.112426 -260.819328)
			(xy 421.131235 -260.811636) (xy 421.141398 -260.811264) (xy 422.540938 -260.811264) (xy 422.55107 -260.811696)
			(xy 422.569797 -260.819441) (xy 422.584152 -260.833744) (xy 422.591966 -260.852442) (xy 422.5925 -260.862572)
			(xy 422.5925 -261.271512) (xy 428.633636 -261.271512) (xy 428.633636 -260.862572) (xy 428.633999 -260.852412)
			(xy 428.641811 -260.833652) (xy 428.656226 -260.819328) (xy 428.675035 -260.811636) (xy 428.685198 -260.811264)
			(xy 430.084738 -260.811264) (xy 430.09487 -260.811696) (xy 430.113597 -260.819441) (xy 430.127952 -260.833744)
			(xy 430.135766 -260.852442) (xy 430.1363 -260.862572) (xy 430.1363 -261.271512) (xy 436.177436 -261.271512)
			(xy 436.177436 -260.862572) (xy 436.177799 -260.852412) (xy 436.185611 -260.833652) (xy 436.200026 -260.819328)
			(xy 436.218835 -260.811636) (xy 436.228998 -260.811264) (xy 437.628538 -260.811264) (xy 437.63867 -260.811696)
			(xy 437.657397 -260.819441) (xy 437.671752 -260.833744) (xy 437.679566 -260.852442) (xy 437.6801 -260.862572)
			(xy 437.6801 -261.271512) (xy 443.721236 -261.271512) (xy 443.721236 -260.862572) (xy 443.721599 -260.852412)
			(xy 443.729411 -260.833652) (xy 443.743826 -260.819328) (xy 443.762635 -260.811636) (xy 443.772798 -260.811264)
			(xy 445.172338 -260.811264) (xy 445.18247 -260.811696) (xy 445.201197 -260.819441) (xy 445.215552 -260.833744)
			(xy 445.223366 -260.852442) (xy 445.2239 -260.862572) (xy 445.2239 -261.271512) (xy 451.265036 -261.271512)
			(xy 451.265036 -260.862572) (xy 451.265399 -260.852412) (xy 451.273211 -260.833652) (xy 451.287626 -260.819328)
			(xy 451.306435 -260.811636) (xy 451.316598 -260.811264) (xy 452.716138 -260.811264) (xy 452.72627 -260.811696)
			(xy 452.744997 -260.819441) (xy 452.759352 -260.833744) (xy 452.767166 -260.852442) (xy 452.7677 -260.862572)
			(xy 452.7677 -261.271512) (xy 458.808836 -261.271512) (xy 458.808836 -260.862572) (xy 458.809199 -260.852412)
			(xy 458.817011 -260.833652) (xy 458.831426 -260.819328) (xy 458.850235 -260.811636) (xy 458.860398 -260.811264)
			(xy 460.259938 -260.811264) (xy 460.27007 -260.811696) (xy 460.288797 -260.819441) (xy 460.303152 -260.833744)
			(xy 460.310966 -260.852442) (xy 460.3115 -260.862572) (xy 460.3115 -261.271512) (xy 460.311088 -261.281667)
			(xy 460.303289 -261.30042) (xy 460.288889 -261.314743) (xy 460.270095 -261.322442) (xy 460.259938 -261.32282)
			(xy 458.860398 -261.32282) (xy 458.850266 -261.322374) (xy 458.831538 -261.314638) (xy 458.81718 -261.300339)
			(xy 458.809368 -261.281642) (xy 458.808836 -261.271512) (xy 452.7677 -261.271512) (xy 452.767288 -261.281667)
			(xy 452.759489 -261.30042) (xy 452.745089 -261.314743) (xy 452.726295 -261.322442) (xy 452.716138 -261.32282)
			(xy 451.316598 -261.32282) (xy 451.306466 -261.322374) (xy 451.287738 -261.314638) (xy 451.27338 -261.300339)
			(xy 451.265568 -261.281642) (xy 451.265036 -261.271512) (xy 445.2239 -261.271512) (xy 445.223488 -261.281667)
			(xy 445.215689 -261.30042) (xy 445.201289 -261.314743) (xy 445.182495 -261.322442) (xy 445.172338 -261.32282)
			(xy 443.772798 -261.32282) (xy 443.762666 -261.322374) (xy 443.743938 -261.314638) (xy 443.72958 -261.300339)
			(xy 443.721768 -261.281642) (xy 443.721236 -261.271512) (xy 437.6801 -261.271512) (xy 437.679688 -261.281667)
			(xy 437.671889 -261.30042) (xy 437.657489 -261.314743) (xy 437.638695 -261.322442) (xy 437.628538 -261.32282)
			(xy 436.228998 -261.32282) (xy 436.218866 -261.322374) (xy 436.200138 -261.314638) (xy 436.18578 -261.300339)
			(xy 436.177968 -261.281642) (xy 436.177436 -261.271512) (xy 430.1363 -261.271512) (xy 430.135888 -261.281667)
			(xy 430.128089 -261.30042) (xy 430.113689 -261.314743) (xy 430.094895 -261.322442) (xy 430.084738 -261.32282)
			(xy 428.685198 -261.32282) (xy 428.675066 -261.322374) (xy 428.656338 -261.314638) (xy 428.64198 -261.300339)
			(xy 428.634168 -261.281642) (xy 428.633636 -261.271512) (xy 422.5925 -261.271512) (xy 422.592088 -261.281667)
			(xy 422.584289 -261.30042) (xy 422.569889 -261.314743) (xy 422.551095 -261.322442) (xy 422.540938 -261.32282)
			(xy 421.141398 -261.32282) (xy 421.131266 -261.322374) (xy 421.112538 -261.314638) (xy 421.09818 -261.300339)
			(xy 421.090368 -261.281642) (xy 421.089836 -261.271512) (xy 415.0487 -261.271512) (xy 415.048288 -261.281667)
			(xy 415.040489 -261.30042) (xy 415.026089 -261.314743) (xy 415.007295 -261.322442) (xy 414.997138 -261.32282)
			(xy 413.597598 -261.32282) (xy 413.587466 -261.322374) (xy 413.568738 -261.314638) (xy 413.55438 -261.300339)
			(xy 413.546568 -261.281642) (xy 413.546036 -261.271512) (xy 407.5049 -261.271512) (xy 407.504488 -261.281667)
			(xy 407.496689 -261.30042) (xy 407.482289 -261.314743) (xy 407.463495 -261.322442) (xy 407.453338 -261.32282)
			(xy 406.053798 -261.32282) (xy 406.043666 -261.322374) (xy 406.024938 -261.314638) (xy 406.01058 -261.300339)
			(xy 406.002768 -261.281642) (xy 406.002236 -261.271512) (xy 309.6387 -261.271512) (xy 309.638288 -261.281667)
			(xy 309.630489 -261.30042) (xy 309.616089 -261.314743) (xy 309.597295 -261.322442) (xy 309.587138 -261.32282)
			(xy 308.187598 -261.32282) (xy 308.177466 -261.322374) (xy 308.158738 -261.314638) (xy 308.14438 -261.300339)
			(xy 308.136568 -261.281642) (xy 308.136036 -261.271512) (xy 302.0949 -261.271512) (xy 302.094488 -261.281667)
			(xy 302.086689 -261.30042) (xy 302.072289 -261.314743) (xy 302.053495 -261.322442) (xy 302.043338 -261.32282)
			(xy 300.643798 -261.32282) (xy 300.633666 -261.322374) (xy 300.614938 -261.314638) (xy 300.60058 -261.300339)
			(xy 300.592768 -261.281642) (xy 300.592236 -261.271512) (xy 294.5511 -261.271512) (xy 294.550688 -261.281667)
			(xy 294.542889 -261.30042) (xy 294.528489 -261.314743) (xy 294.509695 -261.322442) (xy 294.499538 -261.32282)
			(xy 293.099998 -261.32282) (xy 293.089866 -261.322374) (xy 293.071138 -261.314638) (xy 293.05678 -261.300339)
			(xy 293.048968 -261.281642) (xy 293.048436 -261.271512) (xy 287.0073 -261.271512) (xy 287.006888 -261.281667)
			(xy 286.999089 -261.30042) (xy 286.984689 -261.314743) (xy 286.965895 -261.322442) (xy 286.955738 -261.32282)
			(xy 285.556198 -261.32282) (xy 285.546066 -261.322374) (xy 285.527338 -261.314638) (xy 285.51298 -261.300339)
			(xy 285.505168 -261.281642) (xy 285.504636 -261.271512) (xy 279.4635 -261.271512) (xy 279.463088 -261.281667)
			(xy 279.455289 -261.30042) (xy 279.440889 -261.314743) (xy 279.422095 -261.322442) (xy 279.411938 -261.32282)
			(xy 278.012398 -261.32282) (xy 278.002266 -261.322374) (xy 277.983538 -261.314638) (xy 277.96918 -261.300339)
			(xy 277.961368 -261.281642) (xy 277.960836 -261.271512) (xy 271.9197 -261.271512) (xy 271.919288 -261.281667)
			(xy 271.911489 -261.30042) (xy 271.897089 -261.314743) (xy 271.878295 -261.322442) (xy 271.868138 -261.32282)
			(xy 270.468598 -261.32282) (xy 270.458466 -261.322374) (xy 270.439738 -261.314638) (xy 270.42538 -261.300339)
			(xy 270.417568 -261.281642) (xy 270.417036 -261.271512) (xy 264.3759 -261.271512) (xy 264.375488 -261.281667)
			(xy 264.367689 -261.30042) (xy 264.353289 -261.314743) (xy 264.334495 -261.322442) (xy 264.324338 -261.32282)
			(xy 262.924798 -261.32282) (xy 262.914666 -261.322374) (xy 262.895938 -261.314638) (xy 262.88158 -261.300339)
			(xy 262.873768 -261.281642) (xy 262.873236 -261.271512) (xy 256.8321 -261.271512) (xy 256.831688 -261.281667)
			(xy 256.823889 -261.30042) (xy 256.809489 -261.314743) (xy 256.790695 -261.322442) (xy 256.780538 -261.32282)
			(xy 255.380998 -261.32282) (xy 255.370866 -261.322374) (xy 255.352138 -261.314638) (xy 255.33778 -261.300339)
			(xy 255.329968 -261.281642) (xy 255.329436 -261.271512) (xy 212.371432 -261.271512) (xy 212.370989 -261.281663)
			(xy 212.363196 -261.30041) (xy 212.348806 -261.314731) (xy 212.330023 -261.322436) (xy 212.31987 -261.32282)
			(xy 210.92033 -261.32282) (xy 210.9102 -261.322348) (xy 210.891472 -261.314623) (xy 210.877113 -261.300331)
			(xy 210.8693 -261.281639) (xy 210.868768 -261.271512) (xy 204.827632 -261.271512) (xy 204.827189 -261.281663)
			(xy 204.819396 -261.30041) (xy 204.805006 -261.314731) (xy 204.786223 -261.322436) (xy 204.77607 -261.32282)
			(xy 203.37653 -261.32282) (xy 203.3664 -261.322348) (xy 203.347672 -261.314623) (xy 203.333313 -261.300331)
			(xy 203.3255 -261.281639) (xy 203.324968 -261.271512) (xy 197.283832 -261.271512) (xy 197.283389 -261.281663)
			(xy 197.275596 -261.30041) (xy 197.261206 -261.314731) (xy 197.242423 -261.322436) (xy 197.23227 -261.32282)
			(xy 195.83273 -261.32282) (xy 195.8226 -261.322348) (xy 195.803872 -261.314623) (xy 195.789513 -261.300331)
			(xy 195.7817 -261.281639) (xy 195.781168 -261.271512) (xy 189.740032 -261.271512) (xy 189.739589 -261.281663)
			(xy 189.731796 -261.30041) (xy 189.717406 -261.314731) (xy 189.698623 -261.322436) (xy 189.68847 -261.32282)
			(xy 188.28893 -261.32282) (xy 188.2788 -261.322348) (xy 188.260072 -261.314623) (xy 188.245713 -261.300331)
			(xy 188.2379 -261.281639) (xy 188.237368 -261.271512) (xy 182.196232 -261.271512) (xy 182.195789 -261.281663)
			(xy 182.187996 -261.30041) (xy 182.173606 -261.314731) (xy 182.154823 -261.322436) (xy 182.14467 -261.32282)
			(xy 180.74513 -261.32282) (xy 180.735 -261.322348) (xy 180.716272 -261.314623) (xy 180.701913 -261.300331)
			(xy 180.6941 -261.281639) (xy 180.693568 -261.271512) (xy 174.652432 -261.271512) (xy 174.651989 -261.281663)
			(xy 174.644196 -261.30041) (xy 174.629806 -261.314731) (xy 174.611023 -261.322436) (xy 174.60087 -261.32282)
			(xy 173.20133 -261.32282) (xy 173.1912 -261.322348) (xy 173.172472 -261.314623) (xy 173.158113 -261.300331)
			(xy 173.1503 -261.281639) (xy 173.149768 -261.271512) (xy 167.108632 -261.271512) (xy 167.108189 -261.281663)
			(xy 167.100396 -261.30041) (xy 167.086006 -261.314731) (xy 167.067223 -261.322436) (xy 167.05707 -261.32282)
			(xy 165.65753 -261.32282) (xy 165.6474 -261.322348) (xy 165.628672 -261.314623) (xy 165.614313 -261.300331)
			(xy 165.6065 -261.281639) (xy 165.605968 -261.271512) (xy 159.564832 -261.271512) (xy 159.564389 -261.281663)
			(xy 159.556596 -261.30041) (xy 159.542206 -261.314731) (xy 159.523423 -261.322436) (xy 159.51327 -261.32282)
			(xy 158.11373 -261.32282) (xy 158.1036 -261.322348) (xy 158.084872 -261.314623) (xy 158.070513 -261.300331)
			(xy 158.0627 -261.281639) (xy 158.062168 -261.271512) (xy 61.698632 -261.271512) (xy 61.698189 -261.281663)
			(xy 61.690396 -261.30041) (xy 61.676006 -261.314731) (xy 61.657223 -261.322436) (xy 61.64707 -261.32282)
			(xy 60.24753 -261.32282) (xy 60.2374 -261.322348) (xy 60.218672 -261.314623) (xy 60.204313 -261.300331)
			(xy 60.1965 -261.281639) (xy 60.195968 -261.271512) (xy 54.154832 -261.271512) (xy 54.154389 -261.281663)
			(xy 54.146596 -261.30041) (xy 54.132206 -261.314731) (xy 54.113423 -261.322436) (xy 54.10327 -261.32282)
			(xy 52.70373 -261.32282) (xy 52.6936 -261.322348) (xy 52.674872 -261.314623) (xy 52.660513 -261.300331)
			(xy 52.6527 -261.281639) (xy 52.652168 -261.271512) (xy 46.611032 -261.271512) (xy 46.610589 -261.281663)
			(xy 46.602796 -261.30041) (xy 46.588406 -261.314731) (xy 46.569623 -261.322436) (xy 46.55947 -261.32282)
			(xy 45.15993 -261.32282) (xy 45.1498 -261.322348) (xy 45.131072 -261.314623) (xy 45.116713 -261.300331)
			(xy 45.1089 -261.281639) (xy 45.108368 -261.271512) (xy 39.067232 -261.271512) (xy 39.066789 -261.281663)
			(xy 39.058996 -261.30041) (xy 39.044606 -261.314731) (xy 39.025823 -261.322436) (xy 39.01567 -261.32282)
			(xy 37.61613 -261.32282) (xy 37.606 -261.322348) (xy 37.587272 -261.314623) (xy 37.572913 -261.300331)
			(xy 37.5651 -261.281639) (xy 37.564568 -261.271512) (xy 31.523432 -261.271512) (xy 31.522989 -261.281663)
			(xy 31.515196 -261.30041) (xy 31.500806 -261.314731) (xy 31.482023 -261.322436) (xy 31.47187 -261.32282)
			(xy 30.07233 -261.32282) (xy 30.0622 -261.322348) (xy 30.043472 -261.314623) (xy 30.029113 -261.300331)
			(xy 30.0213 -261.281639) (xy 30.020768 -261.271512) (xy 23.979632 -261.271512) (xy 23.979189 -261.281663)
			(xy 23.971396 -261.30041) (xy 23.957006 -261.314731) (xy 23.938223 -261.322436) (xy 23.92807 -261.32282)
			(xy 22.52853 -261.32282) (xy 22.5184 -261.322348) (xy 22.499672 -261.314623) (xy 22.485313 -261.300331)
			(xy 22.4775 -261.281639) (xy 22.476968 -261.271512) (xy 16.435832 -261.271512) (xy 16.435389 -261.281663)
			(xy 16.427596 -261.30041) (xy 16.413206 -261.314731) (xy 16.394423 -261.322436) (xy 16.38427 -261.32282)
			(xy 14.98473 -261.32282) (xy 14.9746 -261.322348) (xy 14.955872 -261.314623) (xy 14.941513 -261.300331)
			(xy 14.9337 -261.281639) (xy 14.933168 -261.271512) (xy 8.892032 -261.271512) (xy 8.891589 -261.281663)
			(xy 8.883796 -261.30041) (xy 8.869406 -261.314731) (xy 8.850623 -261.322436) (xy 8.84047 -261.32282)
			(xy 7.44093 -261.32282) (xy 7.4308 -261.322348) (xy 7.412072 -261.314623) (xy 7.397713 -261.300331)
			(xy 7.3899 -261.281639) (xy 7.389368 -261.271512) (xy 2.509012 -261.271512) (xy 2.509012 -262.121396)
			(xy 11.489436 -262.121396) (xy 11.489436 -261.712456) (xy 11.489786 -261.702294) (xy 11.497603 -261.683534)
			(xy 11.512022 -261.669211) (xy 11.530834 -261.66152) (xy 11.540998 -261.661148) (xy 12.940538 -261.661148)
			(xy 12.950668 -261.661596) (xy 12.969392 -261.669337) (xy 12.983747 -261.683635) (xy 12.991563 -261.702328)
			(xy 12.9921 -261.712456) (xy 12.9921 -262.121396) (xy 19.033236 -262.121396) (xy 19.033236 -261.712456)
			(xy 19.033586 -261.702294) (xy 19.041403 -261.683534) (xy 19.055822 -261.669211) (xy 19.074634 -261.66152)
			(xy 19.084798 -261.661148) (xy 20.484338 -261.661148) (xy 20.494468 -261.661596) (xy 20.513192 -261.669337)
			(xy 20.527547 -261.683635) (xy 20.535363 -261.702328) (xy 20.5359 -261.712456) (xy 20.5359 -262.121396)
			(xy 26.577036 -262.121396) (xy 26.577036 -261.712456) (xy 26.577386 -261.702294) (xy 26.585203 -261.683534)
			(xy 26.599622 -261.669211) (xy 26.618434 -261.66152) (xy 26.628598 -261.661148) (xy 28.028138 -261.661148)
			(xy 28.038268 -261.661596) (xy 28.056992 -261.669337) (xy 28.071347 -261.683635) (xy 28.079163 -261.702328)
			(xy 28.0797 -261.712456) (xy 28.0797 -262.121396) (xy 34.120836 -262.121396) (xy 34.120836 -261.712456)
			(xy 34.121186 -261.702294) (xy 34.129003 -261.683534) (xy 34.143422 -261.669211) (xy 34.162234 -261.66152)
			(xy 34.172398 -261.661148) (xy 35.571938 -261.661148) (xy 35.582068 -261.661596) (xy 35.600792 -261.669337)
			(xy 35.615147 -261.683635) (xy 35.622963 -261.702328) (xy 35.6235 -261.712456) (xy 35.6235 -262.121396)
			(xy 41.664636 -262.121396) (xy 41.664636 -261.712456) (xy 41.664986 -261.702294) (xy 41.672803 -261.683534)
			(xy 41.687222 -261.669211) (xy 41.706034 -261.66152) (xy 41.716198 -261.661148) (xy 43.115738 -261.661148)
			(xy 43.125868 -261.661596) (xy 43.144592 -261.669337) (xy 43.158947 -261.683635) (xy 43.166763 -261.702328)
			(xy 43.1673 -261.712456) (xy 43.1673 -262.121396) (xy 49.208436 -262.121396) (xy 49.208436 -261.712456)
			(xy 49.208786 -261.702294) (xy 49.216603 -261.683534) (xy 49.231022 -261.669211) (xy 49.249834 -261.66152)
			(xy 49.259998 -261.661148) (xy 50.659538 -261.661148) (xy 50.669668 -261.661596) (xy 50.688392 -261.669337)
			(xy 50.702747 -261.683635) (xy 50.710563 -261.702328) (xy 50.7111 -261.712456) (xy 50.7111 -262.121396)
			(xy 56.752236 -262.121396) (xy 56.752236 -261.712456) (xy 56.752586 -261.702294) (xy 56.760403 -261.683534)
			(xy 56.774822 -261.669211) (xy 56.793634 -261.66152) (xy 56.803798 -261.661148) (xy 58.203338 -261.661148)
			(xy 58.213468 -261.661596) (xy 58.232192 -261.669337) (xy 58.246547 -261.683635) (xy 58.254363 -261.702328)
			(xy 58.2549 -261.712456) (xy 58.2549 -262.121396) (xy 64.296036 -262.121396) (xy 64.296036 -261.712456)
			(xy 64.296386 -261.702294) (xy 64.304203 -261.683534) (xy 64.318622 -261.669211) (xy 64.337434 -261.66152)
			(xy 64.347598 -261.661148) (xy 65.747138 -261.661148) (xy 65.757268 -261.661596) (xy 65.775992 -261.669337)
			(xy 65.790347 -261.683635) (xy 65.798163 -261.702328) (xy 65.7987 -261.712456) (xy 65.7987 -262.121396)
			(xy 162.162236 -262.121396) (xy 162.162236 -261.712456) (xy 162.162586 -261.702294) (xy 162.170403 -261.683534)
			(xy 162.184822 -261.669211) (xy 162.203634 -261.66152) (xy 162.213798 -261.661148) (xy 163.613338 -261.661148)
			(xy 163.623468 -261.661596) (xy 163.642192 -261.669337) (xy 163.656547 -261.683635) (xy 163.664363 -261.702328)
			(xy 163.6649 -261.712456) (xy 163.6649 -262.121396) (xy 169.706036 -262.121396) (xy 169.706036 -261.712456)
			(xy 169.706386 -261.702294) (xy 169.714203 -261.683534) (xy 169.728622 -261.669211) (xy 169.747434 -261.66152)
			(xy 169.757598 -261.661148) (xy 171.157138 -261.661148) (xy 171.167268 -261.661596) (xy 171.185992 -261.669337)
			(xy 171.200347 -261.683635) (xy 171.208163 -261.702328) (xy 171.2087 -261.712456) (xy 171.2087 -262.121396)
			(xy 177.249836 -262.121396) (xy 177.249836 -261.712456) (xy 177.250186 -261.702294) (xy 177.258003 -261.683534)
			(xy 177.272422 -261.669211) (xy 177.291234 -261.66152) (xy 177.301398 -261.661148) (xy 178.700938 -261.661148)
			(xy 178.711068 -261.661596) (xy 178.729792 -261.669337) (xy 178.744147 -261.683635) (xy 178.751963 -261.702328)
			(xy 178.7525 -261.712456) (xy 178.7525 -262.121396) (xy 184.793636 -262.121396) (xy 184.793636 -261.712456)
			(xy 184.793986 -261.702294) (xy 184.801803 -261.683534) (xy 184.816222 -261.669211) (xy 184.835034 -261.66152)
			(xy 184.845198 -261.661148) (xy 186.244738 -261.661148) (xy 186.254868 -261.661596) (xy 186.273592 -261.669337)
			(xy 186.287947 -261.683635) (xy 186.295763 -261.702328) (xy 186.2963 -261.712456) (xy 186.2963 -262.121396)
			(xy 192.337436 -262.121396) (xy 192.337436 -261.712456) (xy 192.337786 -261.702294) (xy 192.345603 -261.683534)
			(xy 192.360022 -261.669211) (xy 192.378834 -261.66152) (xy 192.388998 -261.661148) (xy 193.788538 -261.661148)
			(xy 193.798668 -261.661596) (xy 193.817392 -261.669337) (xy 193.831747 -261.683635) (xy 193.839563 -261.702328)
			(xy 193.8401 -261.712456) (xy 193.8401 -262.121396) (xy 199.881236 -262.121396) (xy 199.881236 -261.712456)
			(xy 199.881586 -261.702294) (xy 199.889403 -261.683534) (xy 199.903822 -261.669211) (xy 199.922634 -261.66152)
			(xy 199.932798 -261.661148) (xy 201.332338 -261.661148) (xy 201.342468 -261.661596) (xy 201.361192 -261.669337)
			(xy 201.375547 -261.683635) (xy 201.383363 -261.702328) (xy 201.3839 -261.712456) (xy 201.3839 -262.121396)
			(xy 207.425036 -262.121396) (xy 207.425036 -261.712456) (xy 207.425386 -261.702294) (xy 207.433203 -261.683534)
			(xy 207.447622 -261.669211) (xy 207.466434 -261.66152) (xy 207.476598 -261.661148) (xy 208.876138 -261.661148)
			(xy 208.886268 -261.661596) (xy 208.904992 -261.669337) (xy 208.919347 -261.683635) (xy 208.927163 -261.702328)
			(xy 208.9277 -261.712456) (xy 208.9277 -262.121396) (xy 214.968836 -262.121396) (xy 214.968836 -261.712456)
			(xy 214.969186 -261.702294) (xy 214.977003 -261.683534) (xy 214.991422 -261.669211) (xy 215.010234 -261.66152)
			(xy 215.020398 -261.661148) (xy 216.419938 -261.661148) (xy 216.430068 -261.661596) (xy 216.448792 -261.669337)
			(xy 216.463147 -261.683635) (xy 216.470963 -261.702328) (xy 216.4715 -261.712456) (xy 216.4715 -262.121396)
			(xy 259.429504 -262.121396) (xy 259.429504 -261.712456) (xy 259.429886 -261.702299) (xy 259.437697 -261.683544)
			(xy 259.452105 -261.669223) (xy 259.470906 -261.661525) (xy 259.481066 -261.661148) (xy 260.880606 -261.661148)
			(xy 260.890734 -261.661622) (xy 260.909457 -261.669353) (xy 260.923813 -261.683643) (xy 260.931631 -261.70233)
			(xy 260.932168 -261.712456) (xy 260.932168 -262.121396) (xy 266.973304 -262.121396) (xy 266.973304 -261.712456)
			(xy 266.973686 -261.702299) (xy 266.981497 -261.683544) (xy 266.995905 -261.669223) (xy 267.014706 -261.661525)
			(xy 267.024866 -261.661148) (xy 268.424406 -261.661148) (xy 268.434534 -261.661622) (xy 268.453257 -261.669353)
			(xy 268.467613 -261.683643) (xy 268.475431 -261.70233) (xy 268.475968 -261.712456) (xy 268.475968 -262.121396)
			(xy 274.517104 -262.121396) (xy 274.517104 -261.712456) (xy 274.517486 -261.702299) (xy 274.525297 -261.683544)
			(xy 274.539705 -261.669223) (xy 274.558506 -261.661525) (xy 274.568666 -261.661148) (xy 275.968206 -261.661148)
			(xy 275.978334 -261.661622) (xy 275.997057 -261.669353) (xy 276.011413 -261.683643) (xy 276.019231 -261.70233)
			(xy 276.019768 -261.712456) (xy 276.019768 -262.121396) (xy 282.060904 -262.121396) (xy 282.060904 -261.712456)
			(xy 282.061286 -261.702299) (xy 282.069097 -261.683544) (xy 282.083505 -261.669223) (xy 282.102306 -261.661525)
			(xy 282.112466 -261.661148) (xy 283.512006 -261.661148) (xy 283.522134 -261.661622) (xy 283.540857 -261.669353)
			(xy 283.555213 -261.683643) (xy 283.563031 -261.70233) (xy 283.563568 -261.712456) (xy 283.563568 -262.121396)
			(xy 289.604704 -262.121396) (xy 289.604704 -261.712456) (xy 289.605086 -261.702299) (xy 289.612897 -261.683544)
			(xy 289.627305 -261.669223) (xy 289.646106 -261.661525) (xy 289.656266 -261.661148) (xy 291.055806 -261.661148)
			(xy 291.065934 -261.661622) (xy 291.084657 -261.669353) (xy 291.099013 -261.683643) (xy 291.106831 -261.70233)
			(xy 291.107368 -261.712456) (xy 291.107368 -262.121396) (xy 297.148504 -262.121396) (xy 297.148504 -261.712456)
			(xy 297.148886 -261.702299) (xy 297.156697 -261.683544) (xy 297.171105 -261.669223) (xy 297.189906 -261.661525)
			(xy 297.200066 -261.661148) (xy 298.599606 -261.661148) (xy 298.609734 -261.661622) (xy 298.628457 -261.669353)
			(xy 298.642813 -261.683643) (xy 298.650631 -261.70233) (xy 298.651168 -261.712456) (xy 298.651168 -262.121396)
			(xy 304.692304 -262.121396) (xy 304.692304 -261.712456) (xy 304.692686 -261.702299) (xy 304.700497 -261.683544)
			(xy 304.714905 -261.669223) (xy 304.733706 -261.661525) (xy 304.743866 -261.661148) (xy 306.143406 -261.661148)
			(xy 306.153534 -261.661622) (xy 306.172257 -261.669353) (xy 306.186613 -261.683643) (xy 306.194431 -261.70233)
			(xy 306.194968 -261.712456) (xy 306.194968 -262.121396) (xy 312.236104 -262.121396) (xy 312.236104 -261.712456)
			(xy 312.236486 -261.702299) (xy 312.244297 -261.683544) (xy 312.258705 -261.669223) (xy 312.277506 -261.661525)
			(xy 312.287666 -261.661148) (xy 313.687206 -261.661148) (xy 313.697334 -261.661622) (xy 313.716057 -261.669353)
			(xy 313.730413 -261.683643) (xy 313.738231 -261.70233) (xy 313.738768 -261.712456) (xy 313.738768 -262.121396)
			(xy 410.102304 -262.121396) (xy 410.102304 -261.712456) (xy 410.102686 -261.702299) (xy 410.110497 -261.683544)
			(xy 410.124905 -261.669223) (xy 410.143706 -261.661525) (xy 410.153866 -261.661148) (xy 411.553406 -261.661148)
			(xy 411.563534 -261.661622) (xy 411.582257 -261.669353) (xy 411.596613 -261.683643) (xy 411.604431 -261.70233)
			(xy 411.604968 -261.712456) (xy 411.604968 -262.121396) (xy 417.646104 -262.121396) (xy 417.646104 -261.712456)
			(xy 417.646486 -261.702299) (xy 417.654297 -261.683544) (xy 417.668705 -261.669223) (xy 417.687506 -261.661525)
			(xy 417.697666 -261.661148) (xy 419.097206 -261.661148) (xy 419.107334 -261.661622) (xy 419.126057 -261.669353)
			(xy 419.140413 -261.683643) (xy 419.148231 -261.70233) (xy 419.148768 -261.712456) (xy 419.148768 -262.121396)
			(xy 425.189904 -262.121396) (xy 425.189904 -261.712456) (xy 425.190286 -261.702299) (xy 425.198097 -261.683544)
			(xy 425.212505 -261.669223) (xy 425.231306 -261.661525) (xy 425.241466 -261.661148) (xy 426.641006 -261.661148)
			(xy 426.651134 -261.661622) (xy 426.669857 -261.669353) (xy 426.684213 -261.683643) (xy 426.692031 -261.70233)
			(xy 426.692568 -261.712456) (xy 426.692568 -262.121396) (xy 432.733704 -262.121396) (xy 432.733704 -261.712456)
			(xy 432.734086 -261.702299) (xy 432.741897 -261.683544) (xy 432.756305 -261.669223) (xy 432.775106 -261.661525)
			(xy 432.785266 -261.661148) (xy 434.184806 -261.661148) (xy 434.194934 -261.661622) (xy 434.213657 -261.669353)
			(xy 434.228013 -261.683643) (xy 434.235831 -261.70233) (xy 434.236368 -261.712456) (xy 434.236368 -262.121396)
			(xy 440.277504 -262.121396) (xy 440.277504 -261.712456) (xy 440.277886 -261.702299) (xy 440.285697 -261.683544)
			(xy 440.300105 -261.669223) (xy 440.318906 -261.661525) (xy 440.329066 -261.661148) (xy 441.728606 -261.661148)
			(xy 441.738734 -261.661622) (xy 441.757457 -261.669353) (xy 441.771813 -261.683643) (xy 441.779631 -261.70233)
			(xy 441.780168 -261.712456) (xy 441.780168 -262.121396) (xy 447.821304 -262.121396) (xy 447.821304 -261.712456)
			(xy 447.821686 -261.702299) (xy 447.829497 -261.683544) (xy 447.843905 -261.669223) (xy 447.862706 -261.661525)
			(xy 447.872866 -261.661148) (xy 449.272406 -261.661148) (xy 449.282534 -261.661622) (xy 449.301257 -261.669353)
			(xy 449.315613 -261.683643) (xy 449.323431 -261.70233) (xy 449.323968 -261.712456) (xy 449.323968 -262.121396)
			(xy 455.365104 -262.121396) (xy 455.365104 -261.712456) (xy 455.365486 -261.702299) (xy 455.373297 -261.683544)
			(xy 455.387705 -261.669223) (xy 455.406506 -261.661525) (xy 455.416666 -261.661148) (xy 456.816206 -261.661148)
			(xy 456.826334 -261.661622) (xy 456.845057 -261.669353) (xy 456.859413 -261.683643) (xy 456.867231 -261.70233)
			(xy 456.867768 -261.712456) (xy 456.867768 -262.121396) (xy 462.908904 -262.121396) (xy 462.908904 -261.712456)
			(xy 462.909286 -261.702299) (xy 462.917097 -261.683544) (xy 462.931505 -261.669223) (xy 462.950306 -261.661525)
			(xy 462.960466 -261.661148) (xy 464.360006 -261.661148) (xy 464.370134 -261.661622) (xy 464.388857 -261.669353)
			(xy 464.403213 -261.683643) (xy 464.411031 -261.70233) (xy 464.411568 -261.712456) (xy 464.411568 -262.121396)
			(xy 464.411174 -262.131554) (xy 464.403374 -262.150312) (xy 464.388968 -262.164637) (xy 464.370166 -262.172331)
			(xy 464.360006 -262.172704) (xy 462.960466 -262.172704) (xy 462.950343 -262.172203) (xy 462.931629 -262.164472)
			(xy 462.917275 -262.150191) (xy 462.90945 -262.131517) (xy 462.908904 -262.121396) (xy 456.867768 -262.121396)
			(xy 456.867374 -262.131554) (xy 456.859574 -262.150312) (xy 456.845168 -262.164637) (xy 456.826366 -262.172331)
			(xy 456.816206 -262.172704) (xy 455.416666 -262.172704) (xy 455.406543 -262.172203) (xy 455.387829 -262.164472)
			(xy 455.373475 -262.150191) (xy 455.36565 -262.131517) (xy 455.365104 -262.121396) (xy 449.323968 -262.121396)
			(xy 449.323574 -262.131554) (xy 449.315774 -262.150312) (xy 449.301368 -262.164637) (xy 449.282566 -262.172331)
			(xy 449.272406 -262.172704) (xy 447.872866 -262.172704) (xy 447.862743 -262.172203) (xy 447.844029 -262.164472)
			(xy 447.829675 -262.150191) (xy 447.82185 -262.131517) (xy 447.821304 -262.121396) (xy 441.780168 -262.121396)
			(xy 441.779774 -262.131554) (xy 441.771974 -262.150312) (xy 441.757568 -262.164637) (xy 441.738766 -262.172331)
			(xy 441.728606 -262.172704) (xy 440.329066 -262.172704) (xy 440.318943 -262.172203) (xy 440.300229 -262.164472)
			(xy 440.285875 -262.150191) (xy 440.27805 -262.131517) (xy 440.277504 -262.121396) (xy 434.236368 -262.121396)
			(xy 434.235974 -262.131554) (xy 434.228174 -262.150312) (xy 434.213768 -262.164637) (xy 434.194966 -262.172331)
			(xy 434.184806 -262.172704) (xy 432.785266 -262.172704) (xy 432.775143 -262.172203) (xy 432.756429 -262.164472)
			(xy 432.742075 -262.150191) (xy 432.73425 -262.131517) (xy 432.733704 -262.121396) (xy 426.692568 -262.121396)
			(xy 426.692174 -262.131554) (xy 426.684374 -262.150312) (xy 426.669968 -262.164637) (xy 426.651166 -262.172331)
			(xy 426.641006 -262.172704) (xy 425.241466 -262.172704) (xy 425.231343 -262.172203) (xy 425.212629 -262.164472)
			(xy 425.198275 -262.150191) (xy 425.19045 -262.131517) (xy 425.189904 -262.121396) (xy 419.148768 -262.121396)
			(xy 419.148374 -262.131554) (xy 419.140574 -262.150312) (xy 419.126168 -262.164637) (xy 419.107366 -262.172331)
			(xy 419.097206 -262.172704) (xy 417.697666 -262.172704) (xy 417.687543 -262.172203) (xy 417.668829 -262.164472)
			(xy 417.654475 -262.150191) (xy 417.64665 -262.131517) (xy 417.646104 -262.121396) (xy 411.604968 -262.121396)
			(xy 411.604574 -262.131554) (xy 411.596774 -262.150312) (xy 411.582368 -262.164637) (xy 411.563566 -262.172331)
			(xy 411.553406 -262.172704) (xy 410.153866 -262.172704) (xy 410.143743 -262.172203) (xy 410.125029 -262.164472)
			(xy 410.110675 -262.150191) (xy 410.10285 -262.131517) (xy 410.102304 -262.121396) (xy 313.738768 -262.121396)
			(xy 313.738374 -262.131554) (xy 313.730574 -262.150312) (xy 313.716168 -262.164637) (xy 313.697366 -262.172331)
			(xy 313.687206 -262.172704) (xy 312.287666 -262.172704) (xy 312.277543 -262.172203) (xy 312.258829 -262.164472)
			(xy 312.244475 -262.150191) (xy 312.23665 -262.131517) (xy 312.236104 -262.121396) (xy 306.194968 -262.121396)
			(xy 306.194574 -262.131554) (xy 306.186774 -262.150312) (xy 306.172368 -262.164637) (xy 306.153566 -262.172331)
			(xy 306.143406 -262.172704) (xy 304.743866 -262.172704) (xy 304.733743 -262.172203) (xy 304.715029 -262.164472)
			(xy 304.700675 -262.150191) (xy 304.69285 -262.131517) (xy 304.692304 -262.121396) (xy 298.651168 -262.121396)
			(xy 298.650774 -262.131554) (xy 298.642974 -262.150312) (xy 298.628568 -262.164637) (xy 298.609766 -262.172331)
			(xy 298.599606 -262.172704) (xy 297.200066 -262.172704) (xy 297.189943 -262.172203) (xy 297.171229 -262.164472)
			(xy 297.156875 -262.150191) (xy 297.14905 -262.131517) (xy 297.148504 -262.121396) (xy 291.107368 -262.121396)
			(xy 291.106974 -262.131554) (xy 291.099174 -262.150312) (xy 291.084768 -262.164637) (xy 291.065966 -262.172331)
			(xy 291.055806 -262.172704) (xy 289.656266 -262.172704) (xy 289.646143 -262.172203) (xy 289.627429 -262.164472)
			(xy 289.613075 -262.150191) (xy 289.60525 -262.131517) (xy 289.604704 -262.121396) (xy 283.563568 -262.121396)
			(xy 283.563174 -262.131554) (xy 283.555374 -262.150312) (xy 283.540968 -262.164637) (xy 283.522166 -262.172331)
			(xy 283.512006 -262.172704) (xy 282.112466 -262.172704) (xy 282.102343 -262.172203) (xy 282.083629 -262.164472)
			(xy 282.069275 -262.150191) (xy 282.06145 -262.131517) (xy 282.060904 -262.121396) (xy 276.019768 -262.121396)
			(xy 276.019374 -262.131554) (xy 276.011574 -262.150312) (xy 275.997168 -262.164637) (xy 275.978366 -262.172331)
			(xy 275.968206 -262.172704) (xy 274.568666 -262.172704) (xy 274.558543 -262.172203) (xy 274.539829 -262.164472)
			(xy 274.525475 -262.150191) (xy 274.51765 -262.131517) (xy 274.517104 -262.121396) (xy 268.475968 -262.121396)
			(xy 268.475574 -262.131554) (xy 268.467774 -262.150312) (xy 268.453368 -262.164637) (xy 268.434566 -262.172331)
			(xy 268.424406 -262.172704) (xy 267.024866 -262.172704) (xy 267.014743 -262.172203) (xy 266.996029 -262.164472)
			(xy 266.981675 -262.150191) (xy 266.97385 -262.131517) (xy 266.973304 -262.121396) (xy 260.932168 -262.121396)
			(xy 260.931774 -262.131554) (xy 260.923974 -262.150312) (xy 260.909568 -262.164637) (xy 260.890766 -262.172331)
			(xy 260.880606 -262.172704) (xy 259.481066 -262.172704) (xy 259.470943 -262.172203) (xy 259.452229 -262.164472)
			(xy 259.437875 -262.150191) (xy 259.43005 -262.131517) (xy 259.429504 -262.121396) (xy 216.4715 -262.121396)
			(xy 216.471075 -262.13155) (xy 216.463281 -262.150302) (xy 216.448885 -262.164626) (xy 216.430094 -262.172325)
			(xy 216.419938 -262.172704) (xy 215.020398 -262.172704) (xy 215.010277 -262.172176) (xy 214.991564 -262.164456)
			(xy 214.977209 -262.150183) (xy 214.969382 -262.131514) (xy 214.968836 -262.121396) (xy 208.9277 -262.121396)
			(xy 208.927275 -262.13155) (xy 208.919481 -262.150302) (xy 208.905085 -262.164626) (xy 208.886294 -262.172325)
			(xy 208.876138 -262.172704) (xy 207.476598 -262.172704) (xy 207.466477 -262.172176) (xy 207.447764 -262.164456)
			(xy 207.433409 -262.150183) (xy 207.425582 -262.131514) (xy 207.425036 -262.121396) (xy 201.3839 -262.121396)
			(xy 201.383475 -262.13155) (xy 201.375681 -262.150302) (xy 201.361285 -262.164626) (xy 201.342494 -262.172325)
			(xy 201.332338 -262.172704) (xy 199.932798 -262.172704) (xy 199.922677 -262.172176) (xy 199.903964 -262.164456)
			(xy 199.889609 -262.150183) (xy 199.881782 -262.131514) (xy 199.881236 -262.121396) (xy 193.8401 -262.121396)
			(xy 193.839675 -262.13155) (xy 193.831881 -262.150302) (xy 193.817485 -262.164626) (xy 193.798694 -262.172325)
			(xy 193.788538 -262.172704) (xy 192.388998 -262.172704) (xy 192.378877 -262.172176) (xy 192.360164 -262.164456)
			(xy 192.345809 -262.150183) (xy 192.337982 -262.131514) (xy 192.337436 -262.121396) (xy 186.2963 -262.121396)
			(xy 186.295875 -262.13155) (xy 186.288081 -262.150302) (xy 186.273685 -262.164626) (xy 186.254894 -262.172325)
			(xy 186.244738 -262.172704) (xy 184.845198 -262.172704) (xy 184.835077 -262.172176) (xy 184.816364 -262.164456)
			(xy 184.802009 -262.150183) (xy 184.794182 -262.131514) (xy 184.793636 -262.121396) (xy 178.7525 -262.121396)
			(xy 178.752075 -262.13155) (xy 178.744281 -262.150302) (xy 178.729885 -262.164626) (xy 178.711094 -262.172325)
			(xy 178.700938 -262.172704) (xy 177.301398 -262.172704) (xy 177.291277 -262.172176) (xy 177.272564 -262.164456)
			(xy 177.258209 -262.150183) (xy 177.250382 -262.131514) (xy 177.249836 -262.121396) (xy 171.2087 -262.121396)
			(xy 171.208275 -262.13155) (xy 171.200481 -262.150302) (xy 171.186085 -262.164626) (xy 171.167294 -262.172325)
			(xy 171.157138 -262.172704) (xy 169.757598 -262.172704) (xy 169.747477 -262.172176) (xy 169.728764 -262.164456)
			(xy 169.714409 -262.150183) (xy 169.706582 -262.131514) (xy 169.706036 -262.121396) (xy 163.6649 -262.121396)
			(xy 163.664475 -262.13155) (xy 163.656681 -262.150302) (xy 163.642285 -262.164626) (xy 163.623494 -262.172325)
			(xy 163.613338 -262.172704) (xy 162.213798 -262.172704) (xy 162.203677 -262.172176) (xy 162.184964 -262.164456)
			(xy 162.170609 -262.150183) (xy 162.162782 -262.131514) (xy 162.162236 -262.121396) (xy 65.7987 -262.121396)
			(xy 65.798275 -262.13155) (xy 65.790481 -262.150302) (xy 65.776085 -262.164626) (xy 65.757294 -262.172325)
			(xy 65.747138 -262.172704) (xy 64.347598 -262.172704) (xy 64.337477 -262.172176) (xy 64.318764 -262.164456)
			(xy 64.304409 -262.150183) (xy 64.296582 -262.131514) (xy 64.296036 -262.121396) (xy 58.2549 -262.121396)
			(xy 58.254475 -262.13155) (xy 58.246681 -262.150302) (xy 58.232285 -262.164626) (xy 58.213494 -262.172325)
			(xy 58.203338 -262.172704) (xy 56.803798 -262.172704) (xy 56.793677 -262.172176) (xy 56.774964 -262.164456)
			(xy 56.760609 -262.150183) (xy 56.752782 -262.131514) (xy 56.752236 -262.121396) (xy 50.7111 -262.121396)
			(xy 50.710675 -262.13155) (xy 50.702881 -262.150302) (xy 50.688485 -262.164626) (xy 50.669694 -262.172325)
			(xy 50.659538 -262.172704) (xy 49.259998 -262.172704) (xy 49.249877 -262.172176) (xy 49.231164 -262.164456)
			(xy 49.216809 -262.150183) (xy 49.208982 -262.131514) (xy 49.208436 -262.121396) (xy 43.1673 -262.121396)
			(xy 43.166875 -262.13155) (xy 43.159081 -262.150302) (xy 43.144685 -262.164626) (xy 43.125894 -262.172325)
			(xy 43.115738 -262.172704) (xy 41.716198 -262.172704) (xy 41.706077 -262.172176) (xy 41.687364 -262.164456)
			(xy 41.673009 -262.150183) (xy 41.665182 -262.131514) (xy 41.664636 -262.121396) (xy 35.6235 -262.121396)
			(xy 35.623075 -262.13155) (xy 35.615281 -262.150302) (xy 35.600885 -262.164626) (xy 35.582094 -262.172325)
			(xy 35.571938 -262.172704) (xy 34.172398 -262.172704) (xy 34.162277 -262.172176) (xy 34.143564 -262.164456)
			(xy 34.129209 -262.150183) (xy 34.121382 -262.131514) (xy 34.120836 -262.121396) (xy 28.0797 -262.121396)
			(xy 28.079275 -262.13155) (xy 28.071481 -262.150302) (xy 28.057085 -262.164626) (xy 28.038294 -262.172325)
			(xy 28.028138 -262.172704) (xy 26.628598 -262.172704) (xy 26.618477 -262.172176) (xy 26.599764 -262.164456)
			(xy 26.585409 -262.150183) (xy 26.577582 -262.131514) (xy 26.577036 -262.121396) (xy 20.5359 -262.121396)
			(xy 20.535475 -262.13155) (xy 20.527681 -262.150302) (xy 20.513285 -262.164626) (xy 20.494494 -262.172325)
			(xy 20.484338 -262.172704) (xy 19.084798 -262.172704) (xy 19.074677 -262.172176) (xy 19.055964 -262.164456)
			(xy 19.041609 -262.150183) (xy 19.033782 -262.131514) (xy 19.033236 -262.121396) (xy 12.9921 -262.121396)
			(xy 12.991675 -262.13155) (xy 12.983881 -262.150302) (xy 12.969485 -262.164626) (xy 12.950694 -262.172325)
			(xy 12.940538 -262.172704) (xy 11.540998 -262.172704) (xy 11.530877 -262.172176) (xy 11.512164 -262.164456)
			(xy 11.497809 -262.150183) (xy 11.489982 -262.131514) (xy 11.489436 -262.121396) (xy 2.509012 -262.121396)
			(xy 2.509012 -262.971534) (xy 7.389368 -262.971534) (xy 7.389368 -262.562594) (xy 7.38976 -262.552418)
			(xy 7.397552 -262.533618) (xy 7.411948 -262.519232) (xy 7.430754 -262.511453) (xy 7.44093 -262.511032)
			(xy 8.84047 -262.511032) (xy 8.850639 -262.511488) (xy 8.869432 -262.519262) (xy 8.883817 -262.533638)
			(xy 8.891604 -262.552425) (xy 8.892032 -262.562594) (xy 8.892032 -262.971534) (xy 14.933168 -262.971534)
			(xy 14.933168 -262.562594) (xy 14.93356 -262.552418) (xy 14.941352 -262.533618) (xy 14.955748 -262.519232)
			(xy 14.974554 -262.511453) (xy 14.98473 -262.511032) (xy 16.38427 -262.511032) (xy 16.394439 -262.511488)
			(xy 16.413232 -262.519262) (xy 16.427617 -262.533638) (xy 16.435404 -262.552425) (xy 16.435832 -262.562594)
			(xy 16.435832 -262.971534) (xy 22.476968 -262.971534) (xy 22.476968 -262.562594) (xy 22.47736 -262.552418)
			(xy 22.485152 -262.533618) (xy 22.499548 -262.519232) (xy 22.518354 -262.511453) (xy 22.52853 -262.511032)
			(xy 23.92807 -262.511032) (xy 23.938239 -262.511488) (xy 23.957032 -262.519262) (xy 23.971417 -262.533638)
			(xy 23.979204 -262.552425) (xy 23.979632 -262.562594) (xy 23.979632 -262.971534) (xy 30.020768 -262.971534)
			(xy 30.020768 -262.562594) (xy 30.02116 -262.552418) (xy 30.028952 -262.533618) (xy 30.043348 -262.519232)
			(xy 30.062154 -262.511453) (xy 30.07233 -262.511032) (xy 31.47187 -262.511032) (xy 31.482039 -262.511488)
			(xy 31.500832 -262.519262) (xy 31.515217 -262.533638) (xy 31.523004 -262.552425) (xy 31.523432 -262.562594)
			(xy 31.523432 -262.971534) (xy 37.564568 -262.971534) (xy 37.564568 -262.562594) (xy 37.56496 -262.552418)
			(xy 37.572752 -262.533618) (xy 37.587148 -262.519232) (xy 37.605954 -262.511453) (xy 37.61613 -262.511032)
			(xy 39.01567 -262.511032) (xy 39.025839 -262.511488) (xy 39.044632 -262.519262) (xy 39.059017 -262.533638)
			(xy 39.066804 -262.552425) (xy 39.067232 -262.562594) (xy 39.067232 -262.971534) (xy 45.108368 -262.971534)
			(xy 45.108368 -262.562594) (xy 45.10876 -262.552418) (xy 45.116552 -262.533618) (xy 45.130948 -262.519232)
			(xy 45.149754 -262.511453) (xy 45.15993 -262.511032) (xy 46.55947 -262.511032) (xy 46.569639 -262.511488)
			(xy 46.588432 -262.519262) (xy 46.602817 -262.533638) (xy 46.610604 -262.552425) (xy 46.611032 -262.562594)
			(xy 46.611032 -262.971534) (xy 52.652168 -262.971534) (xy 52.652168 -262.562594) (xy 52.65256 -262.552418)
			(xy 52.660352 -262.533618) (xy 52.674748 -262.519232) (xy 52.693554 -262.511453) (xy 52.70373 -262.511032)
			(xy 54.10327 -262.511032) (xy 54.113439 -262.511488) (xy 54.132232 -262.519262) (xy 54.146617 -262.533638)
			(xy 54.154404 -262.552425) (xy 54.154832 -262.562594) (xy 54.154832 -262.971534) (xy 60.195968 -262.971534)
			(xy 60.195968 -262.562594) (xy 60.19636 -262.552418) (xy 60.204152 -262.533618) (xy 60.218548 -262.519232)
			(xy 60.237354 -262.511453) (xy 60.24753 -262.511032) (xy 61.64707 -262.511032) (xy 61.657239 -262.511488)
			(xy 61.676032 -262.519262) (xy 61.690417 -262.533638) (xy 61.698204 -262.552425) (xy 61.698632 -262.562594)
			(xy 61.698632 -262.971534) (xy 158.062168 -262.971534) (xy 158.062168 -262.562594) (xy 158.06256 -262.552418)
			(xy 158.070352 -262.533618) (xy 158.084748 -262.519232) (xy 158.103554 -262.511453) (xy 158.11373 -262.511032)
			(xy 159.51327 -262.511032) (xy 159.523439 -262.511488) (xy 159.542232 -262.519262) (xy 159.556617 -262.533638)
			(xy 159.564404 -262.552425) (xy 159.564832 -262.562594) (xy 159.564832 -262.971534) (xy 165.605968 -262.971534)
			(xy 165.605968 -262.562594) (xy 165.60636 -262.552418) (xy 165.614152 -262.533618) (xy 165.628548 -262.519232)
			(xy 165.647354 -262.511453) (xy 165.65753 -262.511032) (xy 167.05707 -262.511032) (xy 167.067239 -262.511488)
			(xy 167.086032 -262.519262) (xy 167.100417 -262.533638) (xy 167.108204 -262.552425) (xy 167.108632 -262.562594)
			(xy 167.108632 -262.971534) (xy 173.149768 -262.971534) (xy 173.149768 -262.562594) (xy 173.15016 -262.552418)
			(xy 173.157952 -262.533618) (xy 173.172348 -262.519232) (xy 173.191154 -262.511453) (xy 173.20133 -262.511032)
			(xy 174.60087 -262.511032) (xy 174.611039 -262.511488) (xy 174.629832 -262.519262) (xy 174.644217 -262.533638)
			(xy 174.652004 -262.552425) (xy 174.652432 -262.562594) (xy 174.652432 -262.971534) (xy 180.693568 -262.971534)
			(xy 180.693568 -262.562594) (xy 180.69396 -262.552418) (xy 180.701752 -262.533618) (xy 180.716148 -262.519232)
			(xy 180.734954 -262.511453) (xy 180.74513 -262.511032) (xy 182.14467 -262.511032) (xy 182.154839 -262.511488)
			(xy 182.173632 -262.519262) (xy 182.188017 -262.533638) (xy 182.195804 -262.552425) (xy 182.196232 -262.562594)
			(xy 182.196232 -262.971534) (xy 188.237368 -262.971534) (xy 188.237368 -262.562594) (xy 188.23776 -262.552418)
			(xy 188.245552 -262.533618) (xy 188.259948 -262.519232) (xy 188.278754 -262.511453) (xy 188.28893 -262.511032)
			(xy 189.68847 -262.511032) (xy 189.698639 -262.511488) (xy 189.717432 -262.519262) (xy 189.731817 -262.533638)
			(xy 189.739604 -262.552425) (xy 189.740032 -262.562594) (xy 189.740032 -262.971534) (xy 195.781168 -262.971534)
			(xy 195.781168 -262.562594) (xy 195.78156 -262.552418) (xy 195.789352 -262.533618) (xy 195.803748 -262.519232)
			(xy 195.822554 -262.511453) (xy 195.83273 -262.511032) (xy 197.23227 -262.511032) (xy 197.242439 -262.511488)
			(xy 197.261232 -262.519262) (xy 197.275617 -262.533638) (xy 197.283404 -262.552425) (xy 197.283832 -262.562594)
			(xy 197.283832 -262.971534) (xy 203.324968 -262.971534) (xy 203.324968 -262.562594) (xy 203.32536 -262.552418)
			(xy 203.333152 -262.533618) (xy 203.347548 -262.519232) (xy 203.366354 -262.511453) (xy 203.37653 -262.511032)
			(xy 204.77607 -262.511032) (xy 204.786239 -262.511488) (xy 204.805032 -262.519262) (xy 204.819417 -262.533638)
			(xy 204.827204 -262.552425) (xy 204.827632 -262.562594) (xy 204.827632 -262.971534) (xy 210.868768 -262.971534)
			(xy 210.868768 -262.562594) (xy 210.86916 -262.552418) (xy 210.876952 -262.533618) (xy 210.891348 -262.519232)
			(xy 210.910154 -262.511453) (xy 210.92033 -262.511032) (xy 212.31987 -262.511032) (xy 212.330039 -262.511488)
			(xy 212.348832 -262.519262) (xy 212.363217 -262.533638) (xy 212.371004 -262.552425) (xy 212.371432 -262.562594)
			(xy 212.371432 -262.971534) (xy 255.329436 -262.971534) (xy 255.329436 -262.562594) (xy 255.329929 -262.552436)
			(xy 255.337705 -262.533667) (xy 255.352071 -262.519302) (xy 255.37084 -262.511528) (xy 255.380998 -262.511032)
			(xy 256.780538 -262.511032) (xy 256.790697 -262.511502) (xy 256.809466 -262.519288) (xy 256.82383 -262.533661)
			(xy 256.831604 -262.552434) (xy 256.8321 -262.562594) (xy 256.8321 -262.971534) (xy 262.873236 -262.971534)
			(xy 262.873236 -262.562594) (xy 262.873729 -262.552436) (xy 262.881505 -262.533667) (xy 262.895871 -262.519302)
			(xy 262.91464 -262.511528) (xy 262.924798 -262.511032) (xy 264.324338 -262.511032) (xy 264.334497 -262.511502)
			(xy 264.353266 -262.519288) (xy 264.36763 -262.533661) (xy 264.375404 -262.552434) (xy 264.3759 -262.562594)
			(xy 264.3759 -262.971534) (xy 270.417036 -262.971534) (xy 270.417036 -262.562594) (xy 270.417529 -262.552436)
			(xy 270.425305 -262.533667) (xy 270.439671 -262.519302) (xy 270.45844 -262.511528) (xy 270.468598 -262.511032)
			(xy 271.868138 -262.511032) (xy 271.878297 -262.511502) (xy 271.897066 -262.519288) (xy 271.91143 -262.533661)
			(xy 271.919204 -262.552434) (xy 271.9197 -262.562594) (xy 271.9197 -262.971534) (xy 277.960836 -262.971534)
			(xy 277.960836 -262.562594) (xy 277.961329 -262.552436) (xy 277.969105 -262.533667) (xy 277.983471 -262.519302)
			(xy 278.00224 -262.511528) (xy 278.012398 -262.511032) (xy 279.411938 -262.511032) (xy 279.422097 -262.511502)
			(xy 279.440866 -262.519288) (xy 279.45523 -262.533661) (xy 279.463004 -262.552434) (xy 279.4635 -262.562594)
			(xy 279.4635 -262.971534) (xy 285.504636 -262.971534) (xy 285.504636 -262.562594) (xy 285.505129 -262.552436)
			(xy 285.512905 -262.533667) (xy 285.527271 -262.519302) (xy 285.54604 -262.511528) (xy 285.556198 -262.511032)
			(xy 286.955738 -262.511032) (xy 286.965897 -262.511502) (xy 286.984666 -262.519288) (xy 286.99903 -262.533661)
			(xy 287.006804 -262.552434) (xy 287.0073 -262.562594) (xy 287.0073 -262.971534) (xy 293.048436 -262.971534)
			(xy 293.048436 -262.562594) (xy 293.048929 -262.552436) (xy 293.056705 -262.533667) (xy 293.071071 -262.519302)
			(xy 293.08984 -262.511528) (xy 293.099998 -262.511032) (xy 294.499538 -262.511032) (xy 294.509697 -262.511502)
			(xy 294.528466 -262.519288) (xy 294.54283 -262.533661) (xy 294.550604 -262.552434) (xy 294.5511 -262.562594)
			(xy 294.5511 -262.971534) (xy 300.592236 -262.971534) (xy 300.592236 -262.562594) (xy 300.592729 -262.552436)
			(xy 300.600505 -262.533667) (xy 300.614871 -262.519302) (xy 300.63364 -262.511528) (xy 300.643798 -262.511032)
			(xy 302.043338 -262.511032) (xy 302.053497 -262.511502) (xy 302.072266 -262.519288) (xy 302.08663 -262.533661)
			(xy 302.094404 -262.552434) (xy 302.0949 -262.562594) (xy 302.0949 -262.971534) (xy 308.136036 -262.971534)
			(xy 308.136036 -262.562594) (xy 308.136529 -262.552436) (xy 308.144305 -262.533667) (xy 308.158671 -262.519302)
			(xy 308.17744 -262.511528) (xy 308.187598 -262.511032) (xy 309.587138 -262.511032) (xy 309.597297 -262.511502)
			(xy 309.616066 -262.519288) (xy 309.63043 -262.533661) (xy 309.638204 -262.552434) (xy 309.6387 -262.562594)
			(xy 309.6387 -262.971534) (xy 406.002236 -262.971534) (xy 406.002236 -262.562594) (xy 406.002729 -262.552436)
			(xy 406.010505 -262.533667) (xy 406.024871 -262.519302) (xy 406.04364 -262.511528) (xy 406.053798 -262.511032)
			(xy 407.453338 -262.511032) (xy 407.463497 -262.511502) (xy 407.482266 -262.519288) (xy 407.49663 -262.533661)
			(xy 407.504404 -262.552434) (xy 407.5049 -262.562594) (xy 407.5049 -262.971534) (xy 413.546036 -262.971534)
			(xy 413.546036 -262.562594) (xy 413.546529 -262.552436) (xy 413.554305 -262.533667) (xy 413.568671 -262.519302)
			(xy 413.58744 -262.511528) (xy 413.597598 -262.511032) (xy 414.997138 -262.511032) (xy 415.007297 -262.511502)
			(xy 415.026066 -262.519288) (xy 415.04043 -262.533661) (xy 415.048204 -262.552434) (xy 415.0487 -262.562594)
			(xy 415.0487 -262.971534) (xy 421.089836 -262.971534) (xy 421.089836 -262.562594) (xy 421.090329 -262.552436)
			(xy 421.098105 -262.533667) (xy 421.112471 -262.519302) (xy 421.13124 -262.511528) (xy 421.141398 -262.511032)
			(xy 422.540938 -262.511032) (xy 422.551097 -262.511502) (xy 422.569866 -262.519288) (xy 422.58423 -262.533661)
			(xy 422.592004 -262.552434) (xy 422.5925 -262.562594) (xy 422.5925 -262.971534) (xy 428.633636 -262.971534)
			(xy 428.633636 -262.562594) (xy 428.634129 -262.552436) (xy 428.641905 -262.533667) (xy 428.656271 -262.519302)
			(xy 428.67504 -262.511528) (xy 428.685198 -262.511032) (xy 430.084738 -262.511032) (xy 430.094897 -262.511502)
			(xy 430.113666 -262.519288) (xy 430.12803 -262.533661) (xy 430.135804 -262.552434) (xy 430.1363 -262.562594)
			(xy 430.1363 -262.971534) (xy 436.177436 -262.971534) (xy 436.177436 -262.562594) (xy 436.177929 -262.552436)
			(xy 436.185705 -262.533667) (xy 436.200071 -262.519302) (xy 436.21884 -262.511528) (xy 436.228998 -262.511032)
			(xy 437.628538 -262.511032) (xy 437.638697 -262.511502) (xy 437.657466 -262.519288) (xy 437.67183 -262.533661)
			(xy 437.679604 -262.552434) (xy 437.6801 -262.562594) (xy 437.6801 -262.971534) (xy 443.721236 -262.971534)
			(xy 443.721236 -262.562594) (xy 443.721729 -262.552436) (xy 443.729505 -262.533667) (xy 443.743871 -262.519302)
			(xy 443.76264 -262.511528) (xy 443.772798 -262.511032) (xy 445.172338 -262.511032) (xy 445.182497 -262.511502)
			(xy 445.201266 -262.519288) (xy 445.21563 -262.533661) (xy 445.223404 -262.552434) (xy 445.2239 -262.562594)
			(xy 445.2239 -262.971534) (xy 451.265036 -262.971534) (xy 451.265036 -262.562594) (xy 451.265529 -262.552436)
			(xy 451.273305 -262.533667) (xy 451.287671 -262.519302) (xy 451.30644 -262.511528) (xy 451.316598 -262.511032)
			(xy 452.716138 -262.511032) (xy 452.726297 -262.511502) (xy 452.745066 -262.519288) (xy 452.75943 -262.533661)
			(xy 452.767204 -262.552434) (xy 452.7677 -262.562594) (xy 452.7677 -262.971534) (xy 458.808836 -262.971534)
			(xy 458.808836 -262.562594) (xy 458.809329 -262.552436) (xy 458.817105 -262.533667) (xy 458.831471 -262.519302)
			(xy 458.85024 -262.511528) (xy 458.860398 -262.511032) (xy 460.259938 -262.511032) (xy 460.270097 -262.511502)
			(xy 460.288866 -262.519288) (xy 460.30323 -262.533661) (xy 460.311004 -262.552434) (xy 460.3115 -262.562594)
			(xy 460.3115 -262.971534) (xy 460.310995 -262.981689) (xy 460.303217 -263.000452) (xy 460.288855 -263.014815)
			(xy 460.270093 -263.022595) (xy 460.259938 -263.023096) (xy 458.860398 -263.023096) (xy 458.850244 -263.022569)
			(xy 458.831482 -263.0148) (xy 458.817118 -263.000445) (xy 458.809337 -262.981687) (xy 458.808836 -262.971534)
			(xy 452.7677 -262.971534) (xy 452.767195 -262.981689) (xy 452.759417 -263.000452) (xy 452.745055 -263.014815)
			(xy 452.726293 -263.022595) (xy 452.716138 -263.023096) (xy 451.316598 -263.023096) (xy 451.306444 -263.022569)
			(xy 451.287682 -263.0148) (xy 451.273318 -263.000445) (xy 451.265537 -262.981687) (xy 451.265036 -262.971534)
			(xy 445.2239 -262.971534) (xy 445.223395 -262.981689) (xy 445.215617 -263.000452) (xy 445.201255 -263.014815)
			(xy 445.182493 -263.022595) (xy 445.172338 -263.023096) (xy 443.772798 -263.023096) (xy 443.762644 -263.022569)
			(xy 443.743882 -263.0148) (xy 443.729518 -263.000445) (xy 443.721737 -262.981687) (xy 443.721236 -262.971534)
			(xy 437.6801 -262.971534) (xy 437.679595 -262.981689) (xy 437.671817 -263.000452) (xy 437.657455 -263.014815)
			(xy 437.638693 -263.022595) (xy 437.628538 -263.023096) (xy 436.228998 -263.023096) (xy 436.218844 -263.022569)
			(xy 436.200082 -263.0148) (xy 436.185718 -263.000445) (xy 436.177937 -262.981687) (xy 436.177436 -262.971534)
			(xy 430.1363 -262.971534) (xy 430.135795 -262.981689) (xy 430.128017 -263.000452) (xy 430.113655 -263.014815)
			(xy 430.094893 -263.022595) (xy 430.084738 -263.023096) (xy 428.685198 -263.023096) (xy 428.675044 -263.022569)
			(xy 428.656282 -263.0148) (xy 428.641918 -263.000445) (xy 428.634137 -262.981687) (xy 428.633636 -262.971534)
			(xy 422.5925 -262.971534) (xy 422.591995 -262.981689) (xy 422.584217 -263.000452) (xy 422.569855 -263.014815)
			(xy 422.551093 -263.022595) (xy 422.540938 -263.023096) (xy 421.141398 -263.023096) (xy 421.131244 -263.022569)
			(xy 421.112482 -263.0148) (xy 421.098118 -263.000445) (xy 421.090337 -262.981687) (xy 421.089836 -262.971534)
			(xy 415.0487 -262.971534) (xy 415.048195 -262.981689) (xy 415.040417 -263.000452) (xy 415.026055 -263.014815)
			(xy 415.007293 -263.022595) (xy 414.997138 -263.023096) (xy 413.597598 -263.023096) (xy 413.587444 -263.022569)
			(xy 413.568682 -263.0148) (xy 413.554318 -263.000445) (xy 413.546537 -262.981687) (xy 413.546036 -262.971534)
			(xy 407.5049 -262.971534) (xy 407.504395 -262.981689) (xy 407.496617 -263.000452) (xy 407.482255 -263.014815)
			(xy 407.463493 -263.022595) (xy 407.453338 -263.023096) (xy 406.053798 -263.023096) (xy 406.043644 -263.022569)
			(xy 406.024882 -263.0148) (xy 406.010518 -263.000445) (xy 406.002737 -262.981687) (xy 406.002236 -262.971534)
			(xy 309.6387 -262.971534) (xy 309.638195 -262.981689) (xy 309.630417 -263.000452) (xy 309.616055 -263.014815)
			(xy 309.597293 -263.022595) (xy 309.587138 -263.023096) (xy 308.187598 -263.023096) (xy 308.177444 -263.022569)
			(xy 308.158682 -263.0148) (xy 308.144318 -263.000445) (xy 308.136537 -262.981687) (xy 308.136036 -262.971534)
			(xy 302.0949 -262.971534) (xy 302.094395 -262.981689) (xy 302.086617 -263.000452) (xy 302.072255 -263.014815)
			(xy 302.053493 -263.022595) (xy 302.043338 -263.023096) (xy 300.643798 -263.023096) (xy 300.633644 -263.022569)
			(xy 300.614882 -263.0148) (xy 300.600518 -263.000445) (xy 300.592737 -262.981687) (xy 300.592236 -262.971534)
			(xy 294.5511 -262.971534) (xy 294.550595 -262.981689) (xy 294.542817 -263.000452) (xy 294.528455 -263.014815)
			(xy 294.509693 -263.022595) (xy 294.499538 -263.023096) (xy 293.099998 -263.023096) (xy 293.089844 -263.022569)
			(xy 293.071082 -263.0148) (xy 293.056718 -263.000445) (xy 293.048937 -262.981687) (xy 293.048436 -262.971534)
			(xy 287.0073 -262.971534) (xy 287.006795 -262.981689) (xy 286.999017 -263.000452) (xy 286.984655 -263.014815)
			(xy 286.965893 -263.022595) (xy 286.955738 -263.023096) (xy 285.556198 -263.023096) (xy 285.546044 -263.022569)
			(xy 285.527282 -263.0148) (xy 285.512918 -263.000445) (xy 285.505137 -262.981687) (xy 285.504636 -262.971534)
			(xy 279.4635 -262.971534) (xy 279.462995 -262.981689) (xy 279.455217 -263.000452) (xy 279.440855 -263.014815)
			(xy 279.422093 -263.022595) (xy 279.411938 -263.023096) (xy 278.012398 -263.023096) (xy 278.002244 -263.022569)
			(xy 277.983482 -263.0148) (xy 277.969118 -263.000445) (xy 277.961337 -262.981687) (xy 277.960836 -262.971534)
			(xy 271.9197 -262.971534) (xy 271.919195 -262.981689) (xy 271.911417 -263.000452) (xy 271.897055 -263.014815)
			(xy 271.878293 -263.022595) (xy 271.868138 -263.023096) (xy 270.468598 -263.023096) (xy 270.458444 -263.022569)
			(xy 270.439682 -263.0148) (xy 270.425318 -263.000445) (xy 270.417537 -262.981687) (xy 270.417036 -262.971534)
			(xy 264.3759 -262.971534) (xy 264.375395 -262.981689) (xy 264.367617 -263.000452) (xy 264.353255 -263.014815)
			(xy 264.334493 -263.022595) (xy 264.324338 -263.023096) (xy 262.924798 -263.023096) (xy 262.914644 -263.022569)
			(xy 262.895882 -263.0148) (xy 262.881518 -263.000445) (xy 262.873737 -262.981687) (xy 262.873236 -262.971534)
			(xy 256.8321 -262.971534) (xy 256.831595 -262.981689) (xy 256.823817 -263.000452) (xy 256.809455 -263.014815)
			(xy 256.790693 -263.022595) (xy 256.780538 -263.023096) (xy 255.380998 -263.023096) (xy 255.370844 -263.022569)
			(xy 255.352082 -263.0148) (xy 255.337718 -263.000445) (xy 255.329937 -262.981687) (xy 255.329436 -262.971534)
			(xy 212.371432 -262.971534) (xy 212.370994 -262.981698) (xy 212.363203 -263.000473) (xy 212.34882 -263.014838)
			(xy 212.330034 -263.022606) (xy 212.31987 -263.023096) (xy 210.92033 -263.023096) (xy 210.910178 -263.022543)
			(xy 210.891416 -263.014785) (xy 210.877051 -263.000437) (xy 210.869269 -262.981685) (xy 210.868768 -262.971534)
			(xy 204.827632 -262.971534) (xy 204.827194 -262.981698) (xy 204.819403 -263.000473) (xy 204.80502 -263.014838)
			(xy 204.786234 -263.022606) (xy 204.77607 -263.023096) (xy 203.37653 -263.023096) (xy 203.366378 -263.022543)
			(xy 203.347616 -263.014785) (xy 203.333251 -263.000437) (xy 203.325469 -262.981685) (xy 203.324968 -262.971534)
			(xy 197.283832 -262.971534) (xy 197.283394 -262.981698) (xy 197.275603 -263.000473) (xy 197.26122 -263.014838)
			(xy 197.242434 -263.022606) (xy 197.23227 -263.023096) (xy 195.83273 -263.023096) (xy 195.822578 -263.022543)
			(xy 195.803816 -263.014785) (xy 195.789451 -263.000437) (xy 195.781669 -262.981685) (xy 195.781168 -262.971534)
			(xy 189.740032 -262.971534) (xy 189.739594 -262.981698) (xy 189.731803 -263.000473) (xy 189.71742 -263.014838)
			(xy 189.698634 -263.022606) (xy 189.68847 -263.023096) (xy 188.28893 -263.023096) (xy 188.278778 -263.022543)
			(xy 188.260016 -263.014785) (xy 188.245651 -263.000437) (xy 188.237869 -262.981685) (xy 188.237368 -262.971534)
			(xy 182.196232 -262.971534) (xy 182.195794 -262.981698) (xy 182.188003 -263.000473) (xy 182.17362 -263.014838)
			(xy 182.154834 -263.022606) (xy 182.14467 -263.023096) (xy 180.74513 -263.023096) (xy 180.734978 -263.022543)
			(xy 180.716216 -263.014785) (xy 180.701851 -263.000437) (xy 180.694069 -262.981685) (xy 180.693568 -262.971534)
			(xy 174.652432 -262.971534) (xy 174.651994 -262.981698) (xy 174.644203 -263.000473) (xy 174.62982 -263.014838)
			(xy 174.611034 -263.022606) (xy 174.60087 -263.023096) (xy 173.20133 -263.023096) (xy 173.191178 -263.022543)
			(xy 173.172416 -263.014785) (xy 173.158051 -263.000437) (xy 173.150269 -262.981685) (xy 173.149768 -262.971534)
			(xy 167.108632 -262.971534) (xy 167.108194 -262.981698) (xy 167.100403 -263.000473) (xy 167.08602 -263.014838)
			(xy 167.067234 -263.022606) (xy 167.05707 -263.023096) (xy 165.65753 -263.023096) (xy 165.647378 -263.022543)
			(xy 165.628616 -263.014785) (xy 165.614251 -263.000437) (xy 165.606469 -262.981685) (xy 165.605968 -262.971534)
			(xy 159.564832 -262.971534) (xy 159.564394 -262.981698) (xy 159.556603 -263.000473) (xy 159.54222 -263.014838)
			(xy 159.523434 -263.022606) (xy 159.51327 -263.023096) (xy 158.11373 -263.023096) (xy 158.103578 -263.022543)
			(xy 158.084816 -263.014785) (xy 158.070451 -263.000437) (xy 158.062669 -262.981685) (xy 158.062168 -262.971534)
			(xy 61.698632 -262.971534) (xy 61.698194 -262.981698) (xy 61.690403 -263.000473) (xy 61.67602 -263.014838)
			(xy 61.657234 -263.022606) (xy 61.64707 -263.023096) (xy 60.24753 -263.023096) (xy 60.237378 -263.022543)
			(xy 60.218616 -263.014785) (xy 60.204251 -263.000437) (xy 60.196469 -262.981685) (xy 60.195968 -262.971534)
			(xy 54.154832 -262.971534) (xy 54.154394 -262.981698) (xy 54.146603 -263.000473) (xy 54.13222 -263.014838)
			(xy 54.113434 -263.022606) (xy 54.10327 -263.023096) (xy 52.70373 -263.023096) (xy 52.693578 -263.022543)
			(xy 52.674816 -263.014785) (xy 52.660451 -263.000437) (xy 52.652669 -262.981685) (xy 52.652168 -262.971534)
			(xy 46.611032 -262.971534) (xy 46.610594 -262.981698) (xy 46.602803 -263.000473) (xy 46.58842 -263.014838)
			(xy 46.569634 -263.022606) (xy 46.55947 -263.023096) (xy 45.15993 -263.023096) (xy 45.149778 -263.022543)
			(xy 45.131016 -263.014785) (xy 45.116651 -263.000437) (xy 45.108869 -262.981685) (xy 45.108368 -262.971534)
			(xy 39.067232 -262.971534) (xy 39.066794 -262.981698) (xy 39.059003 -263.000473) (xy 39.04462 -263.014838)
			(xy 39.025834 -263.022606) (xy 39.01567 -263.023096) (xy 37.61613 -263.023096) (xy 37.605978 -263.022543)
			(xy 37.587216 -263.014785) (xy 37.572851 -263.000437) (xy 37.565069 -262.981685) (xy 37.564568 -262.971534)
			(xy 31.523432 -262.971534) (xy 31.522994 -262.981698) (xy 31.515203 -263.000473) (xy 31.50082 -263.014838)
			(xy 31.482034 -263.022606) (xy 31.47187 -263.023096) (xy 30.07233 -263.023096) (xy 30.062178 -263.022543)
			(xy 30.043416 -263.014785) (xy 30.029051 -263.000437) (xy 30.021269 -262.981685) (xy 30.020768 -262.971534)
			(xy 23.979632 -262.971534) (xy 23.979194 -262.981698) (xy 23.971403 -263.000473) (xy 23.95702 -263.014838)
			(xy 23.938234 -263.022606) (xy 23.92807 -263.023096) (xy 22.52853 -263.023096) (xy 22.518378 -263.022543)
			(xy 22.499616 -263.014785) (xy 22.485251 -263.000437) (xy 22.477469 -262.981685) (xy 22.476968 -262.971534)
			(xy 16.435832 -262.971534) (xy 16.435394 -262.981698) (xy 16.427603 -263.000473) (xy 16.41322 -263.014838)
			(xy 16.394434 -263.022606) (xy 16.38427 -263.023096) (xy 14.98473 -263.023096) (xy 14.974578 -263.022543)
			(xy 14.955816 -263.014785) (xy 14.941451 -263.000437) (xy 14.933669 -262.981685) (xy 14.933168 -262.971534)
			(xy 8.892032 -262.971534) (xy 8.891594 -262.981698) (xy 8.883803 -263.000473) (xy 8.86942 -263.014838)
			(xy 8.850634 -263.022606) (xy 8.84047 -263.023096) (xy 7.44093 -263.023096) (xy 7.430778 -263.022543)
			(xy 7.412016 -263.014785) (xy 7.397651 -263.000437) (xy 7.389869 -262.981685) (xy 7.389368 -262.971534)
			(xy 2.509012 -262.971534) (xy 2.509012 -263.821418) (xy 11.489436 -263.821418) (xy 11.489436 -263.412478)
			(xy 11.489915 -263.402319) (xy 11.497696 -263.38355) (xy 11.512067 -263.369185) (xy 11.530839 -263.361411)
			(xy 11.540998 -263.360916) (xy 12.940538 -263.360916) (xy 12.950695 -263.361402) (xy 12.969461 -263.369185)
			(xy 12.983824 -263.383552) (xy 12.991601 -263.40232) (xy 12.9921 -263.412478) (xy 12.9921 -263.821418)
			(xy 19.033236 -263.821418) (xy 19.033236 -263.412478) (xy 19.033715 -263.402319) (xy 19.041496 -263.38355)
			(xy 19.055867 -263.369185) (xy 19.074639 -263.361411) (xy 19.084798 -263.360916) (xy 20.484338 -263.360916)
			(xy 20.494495 -263.361402) (xy 20.513261 -263.369185) (xy 20.527624 -263.383552) (xy 20.535401 -263.40232)
			(xy 20.5359 -263.412478) (xy 20.5359 -263.821418) (xy 26.577036 -263.821418) (xy 26.577036 -263.412478)
			(xy 26.577515 -263.402319) (xy 26.585296 -263.38355) (xy 26.599667 -263.369185) (xy 26.618439 -263.361411)
			(xy 26.628598 -263.360916) (xy 28.028138 -263.360916) (xy 28.038295 -263.361402) (xy 28.057061 -263.369185)
			(xy 28.071424 -263.383552) (xy 28.079201 -263.40232) (xy 28.0797 -263.412478) (xy 28.0797 -263.821418)
			(xy 34.120836 -263.821418) (xy 34.120836 -263.412478) (xy 34.121315 -263.402319) (xy 34.129096 -263.38355)
			(xy 34.143467 -263.369185) (xy 34.162239 -263.361411) (xy 34.172398 -263.360916) (xy 35.571938 -263.360916)
			(xy 35.582095 -263.361402) (xy 35.600861 -263.369185) (xy 35.615224 -263.383552) (xy 35.623001 -263.40232)
			(xy 35.6235 -263.412478) (xy 35.6235 -263.821418) (xy 41.664636 -263.821418) (xy 41.664636 -263.412478)
			(xy 41.665115 -263.402319) (xy 41.672896 -263.38355) (xy 41.687267 -263.369185) (xy 41.706039 -263.361411)
			(xy 41.716198 -263.360916) (xy 43.115738 -263.360916) (xy 43.125895 -263.361402) (xy 43.144661 -263.369185)
			(xy 43.159024 -263.383552) (xy 43.166801 -263.40232) (xy 43.1673 -263.412478) (xy 43.1673 -263.821418)
			(xy 49.208436 -263.821418) (xy 49.208436 -263.412478) (xy 49.208915 -263.402319) (xy 49.216696 -263.38355)
			(xy 49.231067 -263.369185) (xy 49.249839 -263.361411) (xy 49.259998 -263.360916) (xy 50.659538 -263.360916)
			(xy 50.669695 -263.361402) (xy 50.688461 -263.369185) (xy 50.702824 -263.383552) (xy 50.710601 -263.40232)
			(xy 50.7111 -263.412478) (xy 50.7111 -263.821418) (xy 56.752236 -263.821418) (xy 56.752236 -263.412478)
			(xy 56.752715 -263.402319) (xy 56.760496 -263.38355) (xy 56.774867 -263.369185) (xy 56.793639 -263.361411)
			(xy 56.803798 -263.360916) (xy 58.203338 -263.360916) (xy 58.213495 -263.361402) (xy 58.232261 -263.369185)
			(xy 58.246624 -263.383552) (xy 58.254401 -263.40232) (xy 58.2549 -263.412478) (xy 58.2549 -263.821418)
			(xy 64.296036 -263.821418) (xy 64.296036 -263.412478) (xy 64.296515 -263.402319) (xy 64.304296 -263.38355)
			(xy 64.318667 -263.369185) (xy 64.337439 -263.361411) (xy 64.347598 -263.360916) (xy 65.747138 -263.360916)
			(xy 65.757295 -263.361402) (xy 65.776061 -263.369185) (xy 65.790424 -263.383552) (xy 65.798201 -263.40232)
			(xy 65.7987 -263.412478) (xy 65.7987 -263.821418) (xy 162.162236 -263.821418) (xy 162.162236 -263.412478)
			(xy 162.162715 -263.402319) (xy 162.170496 -263.38355) (xy 162.184867 -263.369185) (xy 162.203639 -263.361411)
			(xy 162.213798 -263.360916) (xy 163.613338 -263.360916) (xy 163.623495 -263.361402) (xy 163.642261 -263.369185)
			(xy 163.656624 -263.383552) (xy 163.664401 -263.40232) (xy 163.6649 -263.412478) (xy 163.6649 -263.821418)
			(xy 169.706036 -263.821418) (xy 169.706036 -263.412478) (xy 169.706515 -263.402319) (xy 169.714296 -263.38355)
			(xy 169.728667 -263.369185) (xy 169.747439 -263.361411) (xy 169.757598 -263.360916) (xy 171.157138 -263.360916)
			(xy 171.167295 -263.361402) (xy 171.186061 -263.369185) (xy 171.200424 -263.383552) (xy 171.208201 -263.40232)
			(xy 171.2087 -263.412478) (xy 171.2087 -263.821418) (xy 177.249836 -263.821418) (xy 177.249836 -263.412478)
			(xy 177.250315 -263.402319) (xy 177.258096 -263.38355) (xy 177.272467 -263.369185) (xy 177.291239 -263.361411)
			(xy 177.301398 -263.360916) (xy 178.700938 -263.360916) (xy 178.711095 -263.361402) (xy 178.729861 -263.369185)
			(xy 178.744224 -263.383552) (xy 178.752001 -263.40232) (xy 178.7525 -263.412478) (xy 178.7525 -263.821418)
			(xy 184.793636 -263.821418) (xy 184.793636 -263.412478) (xy 184.794115 -263.402319) (xy 184.801896 -263.38355)
			(xy 184.816267 -263.369185) (xy 184.835039 -263.361411) (xy 184.845198 -263.360916) (xy 186.244738 -263.360916)
			(xy 186.254895 -263.361402) (xy 186.273661 -263.369185) (xy 186.288024 -263.383552) (xy 186.295801 -263.40232)
			(xy 186.2963 -263.412478) (xy 186.2963 -263.821418) (xy 192.337436 -263.821418) (xy 192.337436 -263.412478)
			(xy 192.337915 -263.402319) (xy 192.345696 -263.38355) (xy 192.360067 -263.369185) (xy 192.378839 -263.361411)
			(xy 192.388998 -263.360916) (xy 193.788538 -263.360916) (xy 193.798695 -263.361402) (xy 193.817461 -263.369185)
			(xy 193.831824 -263.383552) (xy 193.839601 -263.40232) (xy 193.8401 -263.412478) (xy 193.8401 -263.821418)
			(xy 199.881236 -263.821418) (xy 199.881236 -263.412478) (xy 199.881715 -263.402319) (xy 199.889496 -263.38355)
			(xy 199.903867 -263.369185) (xy 199.922639 -263.361411) (xy 199.932798 -263.360916) (xy 201.332338 -263.360916)
			(xy 201.342495 -263.361402) (xy 201.361261 -263.369185) (xy 201.375624 -263.383552) (xy 201.383401 -263.40232)
			(xy 201.3839 -263.412478) (xy 201.3839 -263.821418) (xy 207.425036 -263.821418) (xy 207.425036 -263.412478)
			(xy 207.425515 -263.402319) (xy 207.433296 -263.38355) (xy 207.447667 -263.369185) (xy 207.466439 -263.361411)
			(xy 207.476598 -263.360916) (xy 208.876138 -263.360916) (xy 208.886295 -263.361402) (xy 208.905061 -263.369185)
			(xy 208.919424 -263.383552) (xy 208.927201 -263.40232) (xy 208.9277 -263.412478) (xy 208.9277 -263.821418)
			(xy 214.968836 -263.821418) (xy 214.968836 -263.412478) (xy 214.969315 -263.402319) (xy 214.977096 -263.38355)
			(xy 214.991467 -263.369185) (xy 215.010239 -263.361411) (xy 215.020398 -263.360916) (xy 216.419938 -263.360916)
			(xy 216.430095 -263.361402) (xy 216.448861 -263.369185) (xy 216.463224 -263.383552) (xy 216.471001 -263.40232)
			(xy 216.4715 -263.412478) (xy 216.4715 -263.821418) (xy 259.429504 -263.821418) (xy 259.429504 -263.412478)
			(xy 259.430014 -263.402323) (xy 259.43779 -263.38356) (xy 259.45215 -263.369196) (xy 259.470911 -263.361417)
			(xy 259.481066 -263.360916) (xy 260.880606 -263.360916) (xy 260.890761 -263.361428) (xy 260.909526 -263.3692)
			(xy 260.923891 -263.38356) (xy 260.931669 -263.402323) (xy 260.932168 -263.412478) (xy 260.932168 -263.821418)
			(xy 266.973304 -263.821418) (xy 266.973304 -263.412478) (xy 266.973814 -263.402323) (xy 266.98159 -263.38356)
			(xy 266.99595 -263.369196) (xy 267.014711 -263.361417) (xy 267.024866 -263.360916) (xy 268.424406 -263.360916)
			(xy 268.434561 -263.361428) (xy 268.453326 -263.3692) (xy 268.467691 -263.38356) (xy 268.475469 -263.402323)
			(xy 268.475968 -263.412478) (xy 268.475968 -263.821418) (xy 274.517104 -263.821418) (xy 274.517104 -263.412478)
			(xy 274.517614 -263.402323) (xy 274.52539 -263.38356) (xy 274.53975 -263.369196) (xy 274.558511 -263.361417)
			(xy 274.568666 -263.360916) (xy 275.968206 -263.360916) (xy 275.978361 -263.361428) (xy 275.997126 -263.3692)
			(xy 276.011491 -263.38356) (xy 276.019269 -263.402323) (xy 276.019768 -263.412478) (xy 276.019768 -263.821418)
			(xy 282.060904 -263.821418) (xy 282.060904 -263.412478) (xy 282.061414 -263.402323) (xy 282.06919 -263.38356)
			(xy 282.08355 -263.369196) (xy 282.102311 -263.361417) (xy 282.112466 -263.360916) (xy 283.512006 -263.360916)
			(xy 283.522161 -263.361428) (xy 283.540926 -263.3692) (xy 283.555291 -263.38356) (xy 283.563069 -263.402323)
			(xy 283.563568 -263.412478) (xy 283.563568 -263.821418) (xy 289.604704 -263.821418) (xy 289.604704 -263.412478)
			(xy 289.605214 -263.402323) (xy 289.61299 -263.38356) (xy 289.62735 -263.369196) (xy 289.646111 -263.361417)
			(xy 289.656266 -263.360916) (xy 291.055806 -263.360916) (xy 291.065961 -263.361428) (xy 291.084726 -263.3692)
			(xy 291.099091 -263.38356) (xy 291.106869 -263.402323) (xy 291.107368 -263.412478) (xy 291.107368 -263.821418)
			(xy 297.148504 -263.821418) (xy 297.148504 -263.412478) (xy 297.149014 -263.402323) (xy 297.15679 -263.38356)
			(xy 297.17115 -263.369196) (xy 297.189911 -263.361417) (xy 297.200066 -263.360916) (xy 298.599606 -263.360916)
			(xy 298.609761 -263.361428) (xy 298.628526 -263.3692) (xy 298.642891 -263.38356) (xy 298.650669 -263.402323)
			(xy 298.651168 -263.412478) (xy 298.651168 -263.821418) (xy 304.692304 -263.821418) (xy 304.692304 -263.412478)
			(xy 304.692814 -263.402323) (xy 304.70059 -263.38356) (xy 304.71495 -263.369196) (xy 304.733711 -263.361417)
			(xy 304.743866 -263.360916) (xy 306.143406 -263.360916) (xy 306.153561 -263.361428) (xy 306.172326 -263.3692)
			(xy 306.186691 -263.38356) (xy 306.194469 -263.402323) (xy 306.194968 -263.412478) (xy 306.194968 -263.821418)
			(xy 312.236104 -263.821418) (xy 312.236104 -263.412478) (xy 312.236614 -263.402323) (xy 312.24439 -263.38356)
			(xy 312.25875 -263.369196) (xy 312.277511 -263.361417) (xy 312.287666 -263.360916) (xy 313.687206 -263.360916)
			(xy 313.697361 -263.361428) (xy 313.716126 -263.3692) (xy 313.730491 -263.38356) (xy 313.738269 -263.402323)
			(xy 313.738768 -263.412478) (xy 313.738768 -263.821418) (xy 410.102304 -263.821418) (xy 410.102304 -263.412478)
			(xy 410.102814 -263.402323) (xy 410.11059 -263.38356) (xy 410.12495 -263.369196) (xy 410.143711 -263.361417)
			(xy 410.153866 -263.360916) (xy 411.553406 -263.360916) (xy 411.563561 -263.361428) (xy 411.582326 -263.3692)
			(xy 411.596691 -263.38356) (xy 411.604469 -263.402323) (xy 411.604968 -263.412478) (xy 411.604968 -263.821418)
			(xy 417.646104 -263.821418) (xy 417.646104 -263.412478) (xy 417.646614 -263.402323) (xy 417.65439 -263.38356)
			(xy 417.66875 -263.369196) (xy 417.687511 -263.361417) (xy 417.697666 -263.360916) (xy 419.097206 -263.360916)
			(xy 419.107361 -263.361428) (xy 419.126126 -263.3692) (xy 419.140491 -263.38356) (xy 419.148269 -263.402323)
			(xy 419.148768 -263.412478) (xy 419.148768 -263.821418) (xy 425.189904 -263.821418) (xy 425.189904 -263.412478)
			(xy 425.190414 -263.402323) (xy 425.19819 -263.38356) (xy 425.21255 -263.369196) (xy 425.231311 -263.361417)
			(xy 425.241466 -263.360916) (xy 426.641006 -263.360916) (xy 426.651161 -263.361428) (xy 426.669926 -263.3692)
			(xy 426.684291 -263.38356) (xy 426.692069 -263.402323) (xy 426.692568 -263.412478) (xy 426.692568 -263.821418)
			(xy 432.733704 -263.821418) (xy 432.733704 -263.412478) (xy 432.734214 -263.402323) (xy 432.74199 -263.38356)
			(xy 432.75635 -263.369196) (xy 432.775111 -263.361417) (xy 432.785266 -263.360916) (xy 434.184806 -263.360916)
			(xy 434.194961 -263.361428) (xy 434.213726 -263.3692) (xy 434.228091 -263.38356) (xy 434.235869 -263.402323)
			(xy 434.236368 -263.412478) (xy 434.236368 -263.821418) (xy 440.277504 -263.821418) (xy 440.277504 -263.412478)
			(xy 440.278014 -263.402323) (xy 440.28579 -263.38356) (xy 440.30015 -263.369196) (xy 440.318911 -263.361417)
			(xy 440.329066 -263.360916) (xy 441.728606 -263.360916) (xy 441.738761 -263.361428) (xy 441.757526 -263.3692)
			(xy 441.771891 -263.38356) (xy 441.779669 -263.402323) (xy 441.780168 -263.412478) (xy 441.780168 -263.821418)
			(xy 447.821304 -263.821418) (xy 447.821304 -263.412478) (xy 447.821814 -263.402323) (xy 447.82959 -263.38356)
			(xy 447.84395 -263.369196) (xy 447.862711 -263.361417) (xy 447.872866 -263.360916) (xy 449.272406 -263.360916)
			(xy 449.282561 -263.361428) (xy 449.301326 -263.3692) (xy 449.315691 -263.38356) (xy 449.323469 -263.402323)
			(xy 449.323968 -263.412478) (xy 449.323968 -263.821418) (xy 455.365104 -263.821418) (xy 455.365104 -263.412478)
			(xy 455.365614 -263.402323) (xy 455.37339 -263.38356) (xy 455.38775 -263.369196) (xy 455.406511 -263.361417)
			(xy 455.416666 -263.360916) (xy 456.816206 -263.360916) (xy 456.826361 -263.361428) (xy 456.845126 -263.3692)
			(xy 456.859491 -263.38356) (xy 456.867269 -263.402323) (xy 456.867768 -263.412478) (xy 456.867768 -263.821418)
			(xy 462.908904 -263.821418) (xy 462.908904 -263.412478) (xy 462.909414 -263.402323) (xy 462.91719 -263.38356)
			(xy 462.93155 -263.369196) (xy 462.950311 -263.361417) (xy 462.960466 -263.360916) (xy 464.360006 -263.360916)
			(xy 464.370161 -263.361428) (xy 464.388926 -263.3692) (xy 464.403291 -263.38356) (xy 464.411069 -263.402323)
			(xy 464.411568 -263.412478) (xy 464.411568 -263.821418) (xy 464.411082 -263.831576) (xy 464.403302 -263.850345)
			(xy 464.388935 -263.864709) (xy 464.370164 -263.872484) (xy 464.360006 -263.87298) (xy 462.960466 -263.87298)
			(xy 462.950308 -263.872495) (xy 462.931542 -263.864713) (xy 462.917178 -263.850345) (xy 462.909402 -263.831576)
			(xy 462.908904 -263.821418) (xy 456.867768 -263.821418) (xy 456.867282 -263.831576) (xy 456.859502 -263.850345)
			(xy 456.845135 -263.864709) (xy 456.826364 -263.872484) (xy 456.816206 -263.87298) (xy 455.416666 -263.87298)
			(xy 455.406508 -263.872495) (xy 455.387742 -263.864713) (xy 455.373378 -263.850345) (xy 455.365602 -263.831576)
			(xy 455.365104 -263.821418) (xy 449.323968 -263.821418) (xy 449.323482 -263.831576) (xy 449.315702 -263.850345)
			(xy 449.301335 -263.864709) (xy 449.282564 -263.872484) (xy 449.272406 -263.87298) (xy 447.872866 -263.87298)
			(xy 447.862708 -263.872495) (xy 447.843942 -263.864713) (xy 447.829578 -263.850345) (xy 447.821802 -263.831576)
			(xy 447.821304 -263.821418) (xy 441.780168 -263.821418) (xy 441.779682 -263.831576) (xy 441.771902 -263.850345)
			(xy 441.757535 -263.864709) (xy 441.738764 -263.872484) (xy 441.728606 -263.87298) (xy 440.329066 -263.87298)
			(xy 440.318908 -263.872495) (xy 440.300142 -263.864713) (xy 440.285778 -263.850345) (xy 440.278002 -263.831576)
			(xy 440.277504 -263.821418) (xy 434.236368 -263.821418) (xy 434.235882 -263.831576) (xy 434.228102 -263.850345)
			(xy 434.213735 -263.864709) (xy 434.194964 -263.872484) (xy 434.184806 -263.87298) (xy 432.785266 -263.87298)
			(xy 432.775108 -263.872495) (xy 432.756342 -263.864713) (xy 432.741978 -263.850345) (xy 432.734202 -263.831576)
			(xy 432.733704 -263.821418) (xy 426.692568 -263.821418) (xy 426.692082 -263.831576) (xy 426.684302 -263.850345)
			(xy 426.669935 -263.864709) (xy 426.651164 -263.872484) (xy 426.641006 -263.87298) (xy 425.241466 -263.87298)
			(xy 425.231308 -263.872495) (xy 425.212542 -263.864713) (xy 425.198178 -263.850345) (xy 425.190402 -263.831576)
			(xy 425.189904 -263.821418) (xy 419.148768 -263.821418) (xy 419.148282 -263.831576) (xy 419.140502 -263.850345)
			(xy 419.126135 -263.864709) (xy 419.107364 -263.872484) (xy 419.097206 -263.87298) (xy 417.697666 -263.87298)
			(xy 417.687508 -263.872495) (xy 417.668742 -263.864713) (xy 417.654378 -263.850345) (xy 417.646602 -263.831576)
			(xy 417.646104 -263.821418) (xy 411.604968 -263.821418) (xy 411.604482 -263.831576) (xy 411.596702 -263.850345)
			(xy 411.582335 -263.864709) (xy 411.563564 -263.872484) (xy 411.553406 -263.87298) (xy 410.153866 -263.87298)
			(xy 410.143708 -263.872495) (xy 410.124942 -263.864713) (xy 410.110578 -263.850345) (xy 410.102802 -263.831576)
			(xy 410.102304 -263.821418) (xy 313.738768 -263.821418) (xy 313.738282 -263.831576) (xy 313.730502 -263.850345)
			(xy 313.716135 -263.864709) (xy 313.697364 -263.872484) (xy 313.687206 -263.87298) (xy 312.287666 -263.87298)
			(xy 312.277508 -263.872495) (xy 312.258742 -263.864713) (xy 312.244378 -263.850345) (xy 312.236602 -263.831576)
			(xy 312.236104 -263.821418) (xy 306.194968 -263.821418) (xy 306.194482 -263.831576) (xy 306.186702 -263.850345)
			(xy 306.172335 -263.864709) (xy 306.153564 -263.872484) (xy 306.143406 -263.87298) (xy 304.743866 -263.87298)
			(xy 304.733708 -263.872495) (xy 304.714942 -263.864713) (xy 304.700578 -263.850345) (xy 304.692802 -263.831576)
			(xy 304.692304 -263.821418) (xy 298.651168 -263.821418) (xy 298.650682 -263.831576) (xy 298.642902 -263.850345)
			(xy 298.628535 -263.864709) (xy 298.609764 -263.872484) (xy 298.599606 -263.87298) (xy 297.200066 -263.87298)
			(xy 297.189908 -263.872495) (xy 297.171142 -263.864713) (xy 297.156778 -263.850345) (xy 297.149002 -263.831576)
			(xy 297.148504 -263.821418) (xy 291.107368 -263.821418) (xy 291.106882 -263.831576) (xy 291.099102 -263.850345)
			(xy 291.084735 -263.864709) (xy 291.065964 -263.872484) (xy 291.055806 -263.87298) (xy 289.656266 -263.87298)
			(xy 289.646108 -263.872495) (xy 289.627342 -263.864713) (xy 289.612978 -263.850345) (xy 289.605202 -263.831576)
			(xy 289.604704 -263.821418) (xy 283.563568 -263.821418) (xy 283.563082 -263.831576) (xy 283.555302 -263.850345)
			(xy 283.540935 -263.864709) (xy 283.522164 -263.872484) (xy 283.512006 -263.87298) (xy 282.112466 -263.87298)
			(xy 282.102308 -263.872495) (xy 282.083542 -263.864713) (xy 282.069178 -263.850345) (xy 282.061402 -263.831576)
			(xy 282.060904 -263.821418) (xy 276.019768 -263.821418) (xy 276.019282 -263.831576) (xy 276.011502 -263.850345)
			(xy 275.997135 -263.864709) (xy 275.978364 -263.872484) (xy 275.968206 -263.87298) (xy 274.568666 -263.87298)
			(xy 274.558508 -263.872495) (xy 274.539742 -263.864713) (xy 274.525378 -263.850345) (xy 274.517602 -263.831576)
			(xy 274.517104 -263.821418) (xy 268.475968 -263.821418) (xy 268.475482 -263.831576) (xy 268.467702 -263.850345)
			(xy 268.453335 -263.864709) (xy 268.434564 -263.872484) (xy 268.424406 -263.87298) (xy 267.024866 -263.87298)
			(xy 267.014708 -263.872495) (xy 266.995942 -263.864713) (xy 266.981578 -263.850345) (xy 266.973802 -263.831576)
			(xy 266.973304 -263.821418) (xy 260.932168 -263.821418) (xy 260.931682 -263.831576) (xy 260.923902 -263.850345)
			(xy 260.909535 -263.864709) (xy 260.890764 -263.872484) (xy 260.880606 -263.87298) (xy 259.481066 -263.87298)
			(xy 259.470908 -263.872495) (xy 259.452142 -263.864713) (xy 259.437778 -263.850345) (xy 259.430002 -263.831576)
			(xy 259.429504 -263.821418) (xy 216.4715 -263.821418) (xy 216.470983 -263.831572) (xy 216.463209 -263.850335)
			(xy 216.448851 -263.864698) (xy 216.430092 -263.872479) (xy 216.419938 -263.87298) (xy 215.020398 -263.87298)
			(xy 215.010242 -263.872469) (xy 214.991477 -263.864697) (xy 214.977112 -263.850337) (xy 214.969335 -263.831574)
			(xy 214.968836 -263.821418) (xy 208.9277 -263.821418) (xy 208.927183 -263.831572) (xy 208.919409 -263.850335)
			(xy 208.905051 -263.864698) (xy 208.886292 -263.872479) (xy 208.876138 -263.87298) (xy 207.476598 -263.87298)
			(xy 207.466442 -263.872469) (xy 207.447677 -263.864697) (xy 207.433312 -263.850337) (xy 207.425535 -263.831574)
			(xy 207.425036 -263.821418) (xy 201.3839 -263.821418) (xy 201.383383 -263.831572) (xy 201.375609 -263.850335)
			(xy 201.361251 -263.864698) (xy 201.342492 -263.872479) (xy 201.332338 -263.87298) (xy 199.932798 -263.87298)
			(xy 199.922642 -263.872469) (xy 199.903877 -263.864697) (xy 199.889512 -263.850337) (xy 199.881735 -263.831574)
			(xy 199.881236 -263.821418) (xy 193.8401 -263.821418) (xy 193.839583 -263.831572) (xy 193.831809 -263.850335)
			(xy 193.817451 -263.864698) (xy 193.798692 -263.872479) (xy 193.788538 -263.87298) (xy 192.388998 -263.87298)
			(xy 192.378842 -263.872469) (xy 192.360077 -263.864697) (xy 192.345712 -263.850337) (xy 192.337935 -263.831574)
			(xy 192.337436 -263.821418) (xy 186.2963 -263.821418) (xy 186.295783 -263.831572) (xy 186.288009 -263.850335)
			(xy 186.273651 -263.864698) (xy 186.254892 -263.872479) (xy 186.244738 -263.87298) (xy 184.845198 -263.87298)
			(xy 184.835042 -263.872469) (xy 184.816277 -263.864697) (xy 184.801912 -263.850337) (xy 184.794135 -263.831574)
			(xy 184.793636 -263.821418) (xy 178.7525 -263.821418) (xy 178.751983 -263.831572) (xy 178.744209 -263.850335)
			(xy 178.729851 -263.864698) (xy 178.711092 -263.872479) (xy 178.700938 -263.87298) (xy 177.301398 -263.87298)
			(xy 177.291242 -263.872469) (xy 177.272477 -263.864697) (xy 177.258112 -263.850337) (xy 177.250335 -263.831574)
			(xy 177.249836 -263.821418) (xy 171.2087 -263.821418) (xy 171.208183 -263.831572) (xy 171.200409 -263.850335)
			(xy 171.186051 -263.864698) (xy 171.167292 -263.872479) (xy 171.157138 -263.87298) (xy 169.757598 -263.87298)
			(xy 169.747442 -263.872469) (xy 169.728677 -263.864697) (xy 169.714312 -263.850337) (xy 169.706535 -263.831574)
			(xy 169.706036 -263.821418) (xy 163.6649 -263.821418) (xy 163.664383 -263.831572) (xy 163.656609 -263.850335)
			(xy 163.642251 -263.864698) (xy 163.623492 -263.872479) (xy 163.613338 -263.87298) (xy 162.213798 -263.87298)
			(xy 162.203642 -263.872469) (xy 162.184877 -263.864697) (xy 162.170512 -263.850337) (xy 162.162735 -263.831574)
			(xy 162.162236 -263.821418) (xy 65.7987 -263.821418) (xy 65.798183 -263.831572) (xy 65.790409 -263.850335)
			(xy 65.776051 -263.864698) (xy 65.757292 -263.872479) (xy 65.747138 -263.87298) (xy 64.347598 -263.87298)
			(xy 64.337442 -263.872469) (xy 64.318677 -263.864697) (xy 64.304312 -263.850337) (xy 64.296535 -263.831574)
			(xy 64.296036 -263.821418) (xy 58.2549 -263.821418) (xy 58.254383 -263.831572) (xy 58.246609 -263.850335)
			(xy 58.232251 -263.864698) (xy 58.213492 -263.872479) (xy 58.203338 -263.87298) (xy 56.803798 -263.87298)
			(xy 56.793642 -263.872469) (xy 56.774877 -263.864697) (xy 56.760512 -263.850337) (xy 56.752735 -263.831574)
			(xy 56.752236 -263.821418) (xy 50.7111 -263.821418) (xy 50.710583 -263.831572) (xy 50.702809 -263.850335)
			(xy 50.688451 -263.864698) (xy 50.669692 -263.872479) (xy 50.659538 -263.87298) (xy 49.259998 -263.87298)
			(xy 49.249842 -263.872469) (xy 49.231077 -263.864697) (xy 49.216712 -263.850337) (xy 49.208935 -263.831574)
			(xy 49.208436 -263.821418) (xy 43.1673 -263.821418) (xy 43.166783 -263.831572) (xy 43.159009 -263.850335)
			(xy 43.144651 -263.864698) (xy 43.125892 -263.872479) (xy 43.115738 -263.87298) (xy 41.716198 -263.87298)
			(xy 41.706042 -263.872469) (xy 41.687277 -263.864697) (xy 41.672912 -263.850337) (xy 41.665135 -263.831574)
			(xy 41.664636 -263.821418) (xy 35.6235 -263.821418) (xy 35.622983 -263.831572) (xy 35.615209 -263.850335)
			(xy 35.600851 -263.864698) (xy 35.582092 -263.872479) (xy 35.571938 -263.87298) (xy 34.172398 -263.87298)
			(xy 34.162242 -263.872469) (xy 34.143477 -263.864697) (xy 34.129112 -263.850337) (xy 34.121335 -263.831574)
			(xy 34.120836 -263.821418) (xy 28.0797 -263.821418) (xy 28.079183 -263.831572) (xy 28.071409 -263.850335)
			(xy 28.057051 -263.864698) (xy 28.038292 -263.872479) (xy 28.028138 -263.87298) (xy 26.628598 -263.87298)
			(xy 26.618442 -263.872469) (xy 26.599677 -263.864697) (xy 26.585312 -263.850337) (xy 26.577535 -263.831574)
			(xy 26.577036 -263.821418) (xy 20.5359 -263.821418) (xy 20.535383 -263.831572) (xy 20.527609 -263.850335)
			(xy 20.513251 -263.864698) (xy 20.494492 -263.872479) (xy 20.484338 -263.87298) (xy 19.084798 -263.87298)
			(xy 19.074642 -263.872469) (xy 19.055877 -263.864697) (xy 19.041512 -263.850337) (xy 19.033735 -263.831574)
			(xy 19.033236 -263.821418) (xy 12.9921 -263.821418) (xy 12.991583 -263.831572) (xy 12.983809 -263.850335)
			(xy 12.969451 -263.864698) (xy 12.950692 -263.872479) (xy 12.940538 -263.87298) (xy 11.540998 -263.87298)
			(xy 11.530842 -263.872469) (xy 11.512077 -263.864697) (xy 11.497712 -263.850337) (xy 11.489935 -263.831574)
			(xy 11.489436 -263.821418) (xy 2.509012 -263.821418) (xy 2.509012 -264.671302) (xy 7.389368 -264.671302)
			(xy 7.389368 -264.262362) (xy 7.389803 -264.252198) (xy 7.397596 -264.233422) (xy 7.411979 -264.219057)
			(xy 7.430765 -264.21129) (xy 7.44093 -264.2108) (xy 8.84047 -264.2108) (xy 8.850621 -264.211357)
			(xy 8.869383 -264.219114) (xy 8.883748 -264.23346) (xy 8.89153 -264.252211) (xy 8.892032 -264.262362)
			(xy 8.892032 -264.671302) (xy 14.933168 -264.671302) (xy 14.933168 -264.262362) (xy 14.933603 -264.252198)
			(xy 14.941396 -264.233422) (xy 14.955779 -264.219057) (xy 14.974565 -264.21129) (xy 14.98473 -264.2108)
			(xy 16.38427 -264.2108) (xy 16.394421 -264.211357) (xy 16.413183 -264.219114) (xy 16.427548 -264.23346)
			(xy 16.43533 -264.252211) (xy 16.435832 -264.262362) (xy 16.435832 -264.671302) (xy 22.476968 -264.671302)
			(xy 22.476968 -264.262362) (xy 22.477403 -264.252198) (xy 22.485196 -264.233422) (xy 22.499579 -264.219057)
			(xy 22.518365 -264.21129) (xy 22.52853 -264.2108) (xy 23.92807 -264.2108) (xy 23.938221 -264.211357)
			(xy 23.956983 -264.219114) (xy 23.971348 -264.23346) (xy 23.97913 -264.252211) (xy 23.979632 -264.262362)
			(xy 23.979632 -264.671302) (xy 30.020768 -264.671302) (xy 30.020768 -264.262362) (xy 30.021203 -264.252198)
			(xy 30.028996 -264.233422) (xy 30.043379 -264.219057) (xy 30.062165 -264.21129) (xy 30.07233 -264.2108)
			(xy 31.47187 -264.2108) (xy 31.482021 -264.211357) (xy 31.500783 -264.219114) (xy 31.515148 -264.23346)
			(xy 31.52293 -264.252211) (xy 31.523432 -264.262362) (xy 31.523432 -264.671302) (xy 37.564568 -264.671302)
			(xy 37.564568 -264.262362) (xy 37.565003 -264.252198) (xy 37.572796 -264.233422) (xy 37.587179 -264.219057)
			(xy 37.605965 -264.21129) (xy 37.61613 -264.2108) (xy 39.01567 -264.2108) (xy 39.025821 -264.211357)
			(xy 39.044583 -264.219114) (xy 39.058948 -264.23346) (xy 39.06673 -264.252211) (xy 39.067232 -264.262362)
			(xy 39.067232 -264.671302) (xy 45.108368 -264.671302) (xy 45.108368 -264.262362) (xy 45.108803 -264.252198)
			(xy 45.116596 -264.233422) (xy 45.130979 -264.219057) (xy 45.149765 -264.21129) (xy 45.15993 -264.2108)
			(xy 46.55947 -264.2108) (xy 46.569621 -264.211357) (xy 46.588383 -264.219114) (xy 46.602748 -264.23346)
			(xy 46.61053 -264.252211) (xy 46.611032 -264.262362) (xy 46.611032 -264.671302) (xy 52.652168 -264.671302)
			(xy 52.652168 -264.262362) (xy 52.652603 -264.252198) (xy 52.660396 -264.233422) (xy 52.674779 -264.219057)
			(xy 52.693565 -264.21129) (xy 52.70373 -264.2108) (xy 54.10327 -264.2108) (xy 54.113421 -264.211357)
			(xy 54.132183 -264.219114) (xy 54.146548 -264.23346) (xy 54.15433 -264.252211) (xy 54.154832 -264.262362)
			(xy 54.154832 -264.671302) (xy 60.195968 -264.671302) (xy 60.195968 -264.262362) (xy 60.196403 -264.252198)
			(xy 60.204196 -264.233422) (xy 60.218579 -264.219057) (xy 60.237365 -264.21129) (xy 60.24753 -264.2108)
			(xy 61.64707 -264.2108) (xy 61.657221 -264.211357) (xy 61.675983 -264.219114) (xy 61.690348 -264.23346)
			(xy 61.69813 -264.252211) (xy 61.698632 -264.262362) (xy 61.698632 -264.671302) (xy 158.062168 -264.671302)
			(xy 158.062168 -264.262362) (xy 158.062603 -264.252198) (xy 158.070396 -264.233422) (xy 158.084779 -264.219057)
			(xy 158.103565 -264.21129) (xy 158.11373 -264.2108) (xy 159.51327 -264.2108) (xy 159.523421 -264.211357)
			(xy 159.542183 -264.219114) (xy 159.556548 -264.23346) (xy 159.56433 -264.252211) (xy 159.564832 -264.262362)
			(xy 159.564832 -264.671302) (xy 165.605968 -264.671302) (xy 165.605968 -264.262362) (xy 165.606403 -264.252198)
			(xy 165.614196 -264.233422) (xy 165.628579 -264.219057) (xy 165.647365 -264.21129) (xy 165.65753 -264.2108)
			(xy 167.05707 -264.2108) (xy 167.067221 -264.211357) (xy 167.085983 -264.219114) (xy 167.100348 -264.23346)
			(xy 167.10813 -264.252211) (xy 167.108632 -264.262362) (xy 167.108632 -264.671302) (xy 173.149768 -264.671302)
			(xy 173.149768 -264.262362) (xy 173.150203 -264.252198) (xy 173.157996 -264.233422) (xy 173.172379 -264.219057)
			(xy 173.191165 -264.21129) (xy 173.20133 -264.2108) (xy 174.60087 -264.2108) (xy 174.611021 -264.211357)
			(xy 174.629783 -264.219114) (xy 174.644148 -264.23346) (xy 174.65193 -264.252211) (xy 174.652432 -264.262362)
			(xy 174.652432 -264.671302) (xy 180.693568 -264.671302) (xy 180.693568 -264.262362) (xy 180.694003 -264.252198)
			(xy 180.701796 -264.233422) (xy 180.716179 -264.219057) (xy 180.734965 -264.21129) (xy 180.74513 -264.2108)
			(xy 182.14467 -264.2108) (xy 182.154821 -264.211357) (xy 182.173583 -264.219114) (xy 182.187948 -264.23346)
			(xy 182.19573 -264.252211) (xy 182.196232 -264.262362) (xy 182.196232 -264.671302) (xy 188.237368 -264.671302)
			(xy 188.237368 -264.262362) (xy 188.237803 -264.252198) (xy 188.245596 -264.233422) (xy 188.259979 -264.219057)
			(xy 188.278765 -264.21129) (xy 188.28893 -264.2108) (xy 189.68847 -264.2108) (xy 189.698621 -264.211357)
			(xy 189.717383 -264.219114) (xy 189.731748 -264.23346) (xy 189.73953 -264.252211) (xy 189.740032 -264.262362)
			(xy 189.740032 -264.671302) (xy 195.781168 -264.671302) (xy 195.781168 -264.262362) (xy 195.781603 -264.252198)
			(xy 195.789396 -264.233422) (xy 195.803779 -264.219057) (xy 195.822565 -264.21129) (xy 195.83273 -264.2108)
			(xy 197.23227 -264.2108) (xy 197.242421 -264.211357) (xy 197.261183 -264.219114) (xy 197.275548 -264.23346)
			(xy 197.28333 -264.252211) (xy 197.283832 -264.262362) (xy 197.283832 -264.671302) (xy 203.324968 -264.671302)
			(xy 203.324968 -264.262362) (xy 203.325403 -264.252198) (xy 203.333196 -264.233422) (xy 203.347579 -264.219057)
			(xy 203.366365 -264.21129) (xy 203.37653 -264.2108) (xy 204.77607 -264.2108) (xy 204.786221 -264.211357)
			(xy 204.804983 -264.219114) (xy 204.819348 -264.23346) (xy 204.82713 -264.252211) (xy 204.827632 -264.262362)
			(xy 204.827632 -264.671302) (xy 210.868768 -264.671302) (xy 210.868768 -264.262362) (xy 210.869203 -264.252198)
			(xy 210.876996 -264.233422) (xy 210.891379 -264.219057) (xy 210.910165 -264.21129) (xy 210.92033 -264.2108)
			(xy 212.31987 -264.2108) (xy 212.330021 -264.211357) (xy 212.348783 -264.219114) (xy 212.363148 -264.23346)
			(xy 212.37093 -264.252211) (xy 212.371432 -264.262362) (xy 212.371432 -264.671302) (xy 255.329436 -264.671302)
			(xy 255.329436 -264.262362) (xy 255.329902 -264.252202) (xy 255.337689 -264.233432) (xy 255.352063 -264.219069)
			(xy 255.370838 -264.211295) (xy 255.380998 -264.2108) (xy 256.780538 -264.2108) (xy 256.790694 -264.211301)
			(xy 256.809456 -264.219081) (xy 256.823819 -264.233444) (xy 256.831599 -264.252206) (xy 256.8321 -264.262362)
			(xy 256.8321 -264.671302) (xy 262.873236 -264.671302) (xy 262.873236 -264.262362) (xy 262.873702 -264.252202)
			(xy 262.881489 -264.233432) (xy 262.895863 -264.219069) (xy 262.914638 -264.211295) (xy 262.924798 -264.2108)
			(xy 264.324338 -264.2108) (xy 264.334494 -264.211301) (xy 264.353256 -264.219081) (xy 264.367619 -264.233444)
			(xy 264.375399 -264.252206) (xy 264.3759 -264.262362) (xy 264.3759 -264.671302) (xy 270.417036 -264.671302)
			(xy 270.417036 -264.262362) (xy 270.417502 -264.252202) (xy 270.425289 -264.233432) (xy 270.439663 -264.219069)
			(xy 270.458438 -264.211295) (xy 270.468598 -264.2108) (xy 271.868138 -264.2108) (xy 271.878294 -264.211301)
			(xy 271.897056 -264.219081) (xy 271.911419 -264.233444) (xy 271.919199 -264.252206) (xy 271.9197 -264.262362)
			(xy 271.9197 -264.671302) (xy 277.960836 -264.671302) (xy 277.960836 -264.262362) (xy 277.961302 -264.252202)
			(xy 277.969089 -264.233432) (xy 277.983463 -264.219069) (xy 278.002238 -264.211295) (xy 278.012398 -264.2108)
			(xy 279.411938 -264.2108) (xy 279.422094 -264.211301) (xy 279.440856 -264.219081) (xy 279.455219 -264.233444)
			(xy 279.462999 -264.252206) (xy 279.4635 -264.262362) (xy 279.4635 -264.671302) (xy 285.504636 -264.671302)
			(xy 285.504636 -264.262362) (xy 285.505102 -264.252202) (xy 285.512889 -264.233432) (xy 285.527263 -264.219069)
			(xy 285.546038 -264.211295) (xy 285.556198 -264.2108) (xy 286.955738 -264.2108) (xy 286.965894 -264.211301)
			(xy 286.984656 -264.219081) (xy 286.999019 -264.233444) (xy 287.006799 -264.252206) (xy 287.0073 -264.262362)
			(xy 287.0073 -264.671302) (xy 293.048436 -264.671302) (xy 293.048436 -264.262362) (xy 293.048902 -264.252202)
			(xy 293.056689 -264.233432) (xy 293.071063 -264.219069) (xy 293.089838 -264.211295) (xy 293.099998 -264.2108)
			(xy 294.499538 -264.2108) (xy 294.509694 -264.211301) (xy 294.528456 -264.219081) (xy 294.542819 -264.233444)
			(xy 294.550599 -264.252206) (xy 294.5511 -264.262362) (xy 294.5511 -264.671302) (xy 300.592236 -264.671302)
			(xy 300.592236 -264.262362) (xy 300.592702 -264.252202) (xy 300.600489 -264.233432) (xy 300.614863 -264.219069)
			(xy 300.633638 -264.211295) (xy 300.643798 -264.2108) (xy 302.043338 -264.2108) (xy 302.053494 -264.211301)
			(xy 302.072256 -264.219081) (xy 302.086619 -264.233444) (xy 302.094399 -264.252206) (xy 302.0949 -264.262362)
			(xy 302.0949 -264.671302) (xy 308.136036 -264.671302) (xy 308.136036 -264.262362) (xy 308.136502 -264.252202)
			(xy 308.144289 -264.233432) (xy 308.158663 -264.219069) (xy 308.177438 -264.211295) (xy 308.187598 -264.2108)
			(xy 309.587138 -264.2108) (xy 309.597294 -264.211301) (xy 309.616056 -264.219081) (xy 309.630419 -264.233444)
			(xy 309.638199 -264.252206) (xy 309.6387 -264.262362) (xy 309.6387 -264.671302) (xy 406.002236 -264.671302)
			(xy 406.002236 -264.262362) (xy 406.002702 -264.252202) (xy 406.010489 -264.233432) (xy 406.024863 -264.219069)
			(xy 406.043638 -264.211295) (xy 406.053798 -264.2108) (xy 407.453338 -264.2108) (xy 407.463494 -264.211301)
			(xy 407.482256 -264.219081) (xy 407.496619 -264.233444) (xy 407.504399 -264.252206) (xy 407.5049 -264.262362)
			(xy 407.5049 -264.671302) (xy 413.546036 -264.671302) (xy 413.546036 -264.262362) (xy 413.546502 -264.252202)
			(xy 413.554289 -264.233432) (xy 413.568663 -264.219069) (xy 413.587438 -264.211295) (xy 413.597598 -264.2108)
			(xy 414.997138 -264.2108) (xy 415.007294 -264.211301) (xy 415.026056 -264.219081) (xy 415.040419 -264.233444)
			(xy 415.048199 -264.252206) (xy 415.0487 -264.262362) (xy 415.0487 -264.671302) (xy 421.089836 -264.671302)
			(xy 421.089836 -264.262362) (xy 421.090302 -264.252202) (xy 421.098089 -264.233432) (xy 421.112463 -264.219069)
			(xy 421.131238 -264.211295) (xy 421.141398 -264.2108) (xy 422.540938 -264.2108) (xy 422.551094 -264.211301)
			(xy 422.569856 -264.219081) (xy 422.584219 -264.233444) (xy 422.591999 -264.252206) (xy 422.5925 -264.262362)
			(xy 422.5925 -264.671302) (xy 428.633636 -264.671302) (xy 428.633636 -264.262362) (xy 428.634102 -264.252202)
			(xy 428.641889 -264.233432) (xy 428.656263 -264.219069) (xy 428.675038 -264.211295) (xy 428.685198 -264.2108)
			(xy 430.084738 -264.2108) (xy 430.094894 -264.211301) (xy 430.113656 -264.219081) (xy 430.128019 -264.233444)
			(xy 430.135799 -264.252206) (xy 430.1363 -264.262362) (xy 430.1363 -264.671302) (xy 436.177436 -264.671302)
			(xy 436.177436 -264.262362) (xy 436.177902 -264.252202) (xy 436.185689 -264.233432) (xy 436.200063 -264.219069)
			(xy 436.218838 -264.211295) (xy 436.228998 -264.2108) (xy 437.628538 -264.2108) (xy 437.638694 -264.211301)
			(xy 437.657456 -264.219081) (xy 437.671819 -264.233444) (xy 437.679599 -264.252206) (xy 437.6801 -264.262362)
			(xy 437.6801 -264.671302) (xy 443.721236 -264.671302) (xy 443.721236 -264.262362) (xy 443.721702 -264.252202)
			(xy 443.729489 -264.233432) (xy 443.743863 -264.219069) (xy 443.762638 -264.211295) (xy 443.772798 -264.2108)
			(xy 445.172338 -264.2108) (xy 445.182494 -264.211301) (xy 445.201256 -264.219081) (xy 445.215619 -264.233444)
			(xy 445.223399 -264.252206) (xy 445.2239 -264.262362) (xy 445.2239 -264.671302) (xy 451.265036 -264.671302)
			(xy 451.265036 -264.262362) (xy 451.265502 -264.252202) (xy 451.273289 -264.233432) (xy 451.287663 -264.219069)
			(xy 451.306438 -264.211295) (xy 451.316598 -264.2108) (xy 452.716138 -264.2108) (xy 452.726294 -264.211301)
			(xy 452.745056 -264.219081) (xy 452.759419 -264.233444) (xy 452.767199 -264.252206) (xy 452.7677 -264.262362)
			(xy 452.7677 -264.671302) (xy 458.808836 -264.671302) (xy 458.808836 -264.262362) (xy 458.809302 -264.252202)
			(xy 458.817089 -264.233432) (xy 458.831463 -264.219069) (xy 458.850238 -264.211295) (xy 458.860398 -264.2108)
			(xy 460.259938 -264.2108) (xy 460.270094 -264.211301) (xy 460.288856 -264.219081) (xy 460.303219 -264.233444)
			(xy 460.310999 -264.252206) (xy 460.3115 -264.262362) (xy 460.3115 -264.671302) (xy 460.310969 -264.681455)
			(xy 460.303201 -264.700217) (xy 460.288847 -264.714581) (xy 460.270091 -264.722362) (xy 460.259938 -264.722864)
			(xy 458.860398 -264.722864) (xy 458.85024 -264.722368) (xy 458.831472 -264.714594) (xy 458.817106 -264.700228)
			(xy 458.809332 -264.68146) (xy 458.808836 -264.671302) (xy 452.7677 -264.671302) (xy 452.767169 -264.681455)
			(xy 452.759401 -264.700217) (xy 452.745047 -264.714581) (xy 452.726291 -264.722362) (xy 452.716138 -264.722864)
			(xy 451.316598 -264.722864) (xy 451.30644 -264.722368) (xy 451.287672 -264.714594) (xy 451.273306 -264.700228)
			(xy 451.265532 -264.68146) (xy 451.265036 -264.671302) (xy 445.2239 -264.671302) (xy 445.223369 -264.681455)
			(xy 445.215601 -264.700217) (xy 445.201247 -264.714581) (xy 445.182491 -264.722362) (xy 445.172338 -264.722864)
			(xy 443.772798 -264.722864) (xy 443.76264 -264.722368) (xy 443.743872 -264.714594) (xy 443.729506 -264.700228)
			(xy 443.721732 -264.68146) (xy 443.721236 -264.671302) (xy 437.6801 -264.671302) (xy 437.679569 -264.681455)
			(xy 437.671801 -264.700217) (xy 437.657447 -264.714581) (xy 437.638691 -264.722362) (xy 437.628538 -264.722864)
			(xy 436.228998 -264.722864) (xy 436.21884 -264.722368) (xy 436.200072 -264.714594) (xy 436.185706 -264.700228)
			(xy 436.177932 -264.68146) (xy 436.177436 -264.671302) (xy 430.1363 -264.671302) (xy 430.135769 -264.681455)
			(xy 430.128001 -264.700217) (xy 430.113647 -264.714581) (xy 430.094891 -264.722362) (xy 430.084738 -264.722864)
			(xy 428.685198 -264.722864) (xy 428.67504 -264.722368) (xy 428.656272 -264.714594) (xy 428.641906 -264.700228)
			(xy 428.634132 -264.68146) (xy 428.633636 -264.671302) (xy 422.5925 -264.671302) (xy 422.591969 -264.681455)
			(xy 422.584201 -264.700217) (xy 422.569847 -264.714581) (xy 422.551091 -264.722362) (xy 422.540938 -264.722864)
			(xy 421.141398 -264.722864) (xy 421.13124 -264.722368) (xy 421.112472 -264.714594) (xy 421.098106 -264.700228)
			(xy 421.090332 -264.68146) (xy 421.089836 -264.671302) (xy 415.0487 -264.671302) (xy 415.048169 -264.681455)
			(xy 415.040401 -264.700217) (xy 415.026047 -264.714581) (xy 415.007291 -264.722362) (xy 414.997138 -264.722864)
			(xy 413.597598 -264.722864) (xy 413.58744 -264.722368) (xy 413.568672 -264.714594) (xy 413.554306 -264.700228)
			(xy 413.546532 -264.68146) (xy 413.546036 -264.671302) (xy 407.5049 -264.671302) (xy 407.504369 -264.681455)
			(xy 407.496601 -264.700217) (xy 407.482247 -264.714581) (xy 407.463491 -264.722362) (xy 407.453338 -264.722864)
			(xy 406.053798 -264.722864) (xy 406.04364 -264.722368) (xy 406.024872 -264.714594) (xy 406.010506 -264.700228)
			(xy 406.002732 -264.68146) (xy 406.002236 -264.671302) (xy 309.6387 -264.671302) (xy 309.638169 -264.681455)
			(xy 309.630401 -264.700217) (xy 309.616047 -264.714581) (xy 309.597291 -264.722362) (xy 309.587138 -264.722864)
			(xy 308.187598 -264.722864) (xy 308.17744 -264.722368) (xy 308.158672 -264.714594) (xy 308.144306 -264.700228)
			(xy 308.136532 -264.68146) (xy 308.136036 -264.671302) (xy 302.0949 -264.671302) (xy 302.094369 -264.681455)
			(xy 302.086601 -264.700217) (xy 302.072247 -264.714581) (xy 302.053491 -264.722362) (xy 302.043338 -264.722864)
			(xy 300.643798 -264.722864) (xy 300.63364 -264.722368) (xy 300.614872 -264.714594) (xy 300.600506 -264.700228)
			(xy 300.592732 -264.68146) (xy 300.592236 -264.671302) (xy 294.5511 -264.671302) (xy 294.550569 -264.681455)
			(xy 294.542801 -264.700217) (xy 294.528447 -264.714581) (xy 294.509691 -264.722362) (xy 294.499538 -264.722864)
			(xy 293.099998 -264.722864) (xy 293.08984 -264.722368) (xy 293.071072 -264.714594) (xy 293.056706 -264.700228)
			(xy 293.048932 -264.68146) (xy 293.048436 -264.671302) (xy 287.0073 -264.671302) (xy 287.006769 -264.681455)
			(xy 286.999001 -264.700217) (xy 286.984647 -264.714581) (xy 286.965891 -264.722362) (xy 286.955738 -264.722864)
			(xy 285.556198 -264.722864) (xy 285.54604 -264.722368) (xy 285.527272 -264.714594) (xy 285.512906 -264.700228)
			(xy 285.505132 -264.68146) (xy 285.504636 -264.671302) (xy 279.4635 -264.671302) (xy 279.462969 -264.681455)
			(xy 279.455201 -264.700217) (xy 279.440847 -264.714581) (xy 279.422091 -264.722362) (xy 279.411938 -264.722864)
			(xy 278.012398 -264.722864) (xy 278.00224 -264.722368) (xy 277.983472 -264.714594) (xy 277.969106 -264.700228)
			(xy 277.961332 -264.68146) (xy 277.960836 -264.671302) (xy 271.9197 -264.671302) (xy 271.919169 -264.681455)
			(xy 271.911401 -264.700217) (xy 271.897047 -264.714581) (xy 271.878291 -264.722362) (xy 271.868138 -264.722864)
			(xy 270.468598 -264.722864) (xy 270.45844 -264.722368) (xy 270.439672 -264.714594) (xy 270.425306 -264.700228)
			(xy 270.417532 -264.68146) (xy 270.417036 -264.671302) (xy 264.3759 -264.671302) (xy 264.375369 -264.681455)
			(xy 264.367601 -264.700217) (xy 264.353247 -264.714581) (xy 264.334491 -264.722362) (xy 264.324338 -264.722864)
			(xy 262.924798 -264.722864) (xy 262.91464 -264.722368) (xy 262.895872 -264.714594) (xy 262.881506 -264.700228)
			(xy 262.873732 -264.68146) (xy 262.873236 -264.671302) (xy 256.8321 -264.671302) (xy 256.831569 -264.681455)
			(xy 256.823801 -264.700217) (xy 256.809447 -264.714581) (xy 256.790691 -264.722362) (xy 256.780538 -264.722864)
			(xy 255.380998 -264.722864) (xy 255.37084 -264.722368) (xy 255.352072 -264.714594) (xy 255.337706 -264.700228)
			(xy 255.329932 -264.68146) (xy 255.329436 -264.671302) (xy 212.371432 -264.671302) (xy 212.371037 -264.681477)
			(xy 212.363246 -264.700278) (xy 212.348851 -264.714664) (xy 212.330046 -264.722443) (xy 212.31987 -264.722864)
			(xy 210.92033 -264.722864) (xy 210.910161 -264.722411) (xy 210.891367 -264.714637) (xy 210.876981 -264.70026)
			(xy 210.869195 -264.681471) (xy 210.868768 -264.671302) (xy 204.827632 -264.671302) (xy 204.827237 -264.681477)
			(xy 204.819446 -264.700278) (xy 204.805051 -264.714664) (xy 204.786246 -264.722443) (xy 204.77607 -264.722864)
			(xy 203.37653 -264.722864) (xy 203.366361 -264.722411) (xy 203.347567 -264.714637) (xy 203.333181 -264.70026)
			(xy 203.325395 -264.681471) (xy 203.324968 -264.671302) (xy 197.283832 -264.671302) (xy 197.283437 -264.681477)
			(xy 197.275646 -264.700278) (xy 197.261251 -264.714664) (xy 197.242446 -264.722443) (xy 197.23227 -264.722864)
			(xy 195.83273 -264.722864) (xy 195.822561 -264.722411) (xy 195.803767 -264.714637) (xy 195.789381 -264.70026)
			(xy 195.781595 -264.681471) (xy 195.781168 -264.671302) (xy 189.740032 -264.671302) (xy 189.739637 -264.681477)
			(xy 189.731846 -264.700278) (xy 189.717451 -264.714664) (xy 189.698646 -264.722443) (xy 189.68847 -264.722864)
			(xy 188.28893 -264.722864) (xy 188.278761 -264.722411) (xy 188.259967 -264.714637) (xy 188.245581 -264.70026)
			(xy 188.237795 -264.681471) (xy 188.237368 -264.671302) (xy 182.196232 -264.671302) (xy 182.195837 -264.681477)
			(xy 182.188046 -264.700278) (xy 182.173651 -264.714664) (xy 182.154846 -264.722443) (xy 182.14467 -264.722864)
			(xy 180.74513 -264.722864) (xy 180.734961 -264.722411) (xy 180.716167 -264.714637) (xy 180.701781 -264.70026)
			(xy 180.693995 -264.681471) (xy 180.693568 -264.671302) (xy 174.652432 -264.671302) (xy 174.652037 -264.681477)
			(xy 174.644246 -264.700278) (xy 174.629851 -264.714664) (xy 174.611046 -264.722443) (xy 174.60087 -264.722864)
			(xy 173.20133 -264.722864) (xy 173.191161 -264.722411) (xy 173.172367 -264.714637) (xy 173.157981 -264.70026)
			(xy 173.150195 -264.681471) (xy 173.149768 -264.671302) (xy 167.108632 -264.671302) (xy 167.108237 -264.681477)
			(xy 167.100446 -264.700278) (xy 167.086051 -264.714664) (xy 167.067246 -264.722443) (xy 167.05707 -264.722864)
			(xy 165.65753 -264.722864) (xy 165.647361 -264.722411) (xy 165.628567 -264.714637) (xy 165.614181 -264.70026)
			(xy 165.606395 -264.681471) (xy 165.605968 -264.671302) (xy 159.564832 -264.671302) (xy 159.564437 -264.681477)
			(xy 159.556646 -264.700278) (xy 159.542251 -264.714664) (xy 159.523446 -264.722443) (xy 159.51327 -264.722864)
			(xy 158.11373 -264.722864) (xy 158.103561 -264.722411) (xy 158.084767 -264.714637) (xy 158.070381 -264.70026)
			(xy 158.062595 -264.681471) (xy 158.062168 -264.671302) (xy 61.698632 -264.671302) (xy 61.698237 -264.681477)
			(xy 61.690446 -264.700278) (xy 61.676051 -264.714664) (xy 61.657246 -264.722443) (xy 61.64707 -264.722864)
			(xy 60.24753 -264.722864) (xy 60.237361 -264.722411) (xy 60.218567 -264.714637) (xy 60.204181 -264.70026)
			(xy 60.196395 -264.681471) (xy 60.195968 -264.671302) (xy 54.154832 -264.671302) (xy 54.154437 -264.681477)
			(xy 54.146646 -264.700278) (xy 54.132251 -264.714664) (xy 54.113446 -264.722443) (xy 54.10327 -264.722864)
			(xy 52.70373 -264.722864) (xy 52.693561 -264.722411) (xy 52.674767 -264.714637) (xy 52.660381 -264.70026)
			(xy 52.652595 -264.681471) (xy 52.652168 -264.671302) (xy 46.611032 -264.671302) (xy 46.610637 -264.681477)
			(xy 46.602846 -264.700278) (xy 46.588451 -264.714664) (xy 46.569646 -264.722443) (xy 46.55947 -264.722864)
			(xy 45.15993 -264.722864) (xy 45.149761 -264.722411) (xy 45.130967 -264.714637) (xy 45.116581 -264.70026)
			(xy 45.108795 -264.681471) (xy 45.108368 -264.671302) (xy 39.067232 -264.671302) (xy 39.066837 -264.681477)
			(xy 39.059046 -264.700278) (xy 39.044651 -264.714664) (xy 39.025846 -264.722443) (xy 39.01567 -264.722864)
			(xy 37.61613 -264.722864) (xy 37.605961 -264.722411) (xy 37.587167 -264.714637) (xy 37.572781 -264.70026)
			(xy 37.564995 -264.681471) (xy 37.564568 -264.671302) (xy 31.523432 -264.671302) (xy 31.523037 -264.681477)
			(xy 31.515246 -264.700278) (xy 31.500851 -264.714664) (xy 31.482046 -264.722443) (xy 31.47187 -264.722864)
			(xy 30.07233 -264.722864) (xy 30.062161 -264.722411) (xy 30.043367 -264.714637) (xy 30.028981 -264.70026)
			(xy 30.021195 -264.681471) (xy 30.020768 -264.671302) (xy 23.979632 -264.671302) (xy 23.979237 -264.681477)
			(xy 23.971446 -264.700278) (xy 23.957051 -264.714664) (xy 23.938246 -264.722443) (xy 23.92807 -264.722864)
			(xy 22.52853 -264.722864) (xy 22.518361 -264.722411) (xy 22.499567 -264.714637) (xy 22.485181 -264.70026)
			(xy 22.477395 -264.681471) (xy 22.476968 -264.671302) (xy 16.435832 -264.671302) (xy 16.435437 -264.681477)
			(xy 16.427646 -264.700278) (xy 16.413251 -264.714664) (xy 16.394446 -264.722443) (xy 16.38427 -264.722864)
			(xy 14.98473 -264.722864) (xy 14.974561 -264.722411) (xy 14.955767 -264.714637) (xy 14.941381 -264.70026)
			(xy 14.933595 -264.681471) (xy 14.933168 -264.671302) (xy 8.892032 -264.671302) (xy 8.891637 -264.681477)
			(xy 8.883846 -264.700278) (xy 8.869451 -264.714664) (xy 8.850646 -264.722443) (xy 8.84047 -264.722864)
			(xy 7.44093 -264.722864) (xy 7.430761 -264.722411) (xy 7.411967 -264.714637) (xy 7.397581 -264.70026)
			(xy 7.389795 -264.681471) (xy 7.389368 -264.671302) (xy 2.509012 -264.671302) (xy 2.509012 -265.52144)
			(xy 11.489436 -265.52144) (xy 11.489436 -265.1125) (xy 11.489822 -265.102341) (xy 11.497625 -265.083582)
			(xy 11.512033 -265.069257) (xy 11.530837 -265.061564) (xy 11.540998 -265.061192) (xy 12.940538 -265.061192)
			(xy 12.950661 -265.061694) (xy 12.969374 -265.069425) (xy 12.983727 -265.083706) (xy 12.991554 -265.102379)
			(xy 12.9921 -265.1125) (xy 12.9921 -265.52144) (xy 19.033236 -265.52144) (xy 19.033236 -265.1125)
			(xy 19.033622 -265.102341) (xy 19.041425 -265.083582) (xy 19.055833 -265.069257) (xy 19.074637 -265.061564)
			(xy 19.084798 -265.061192) (xy 20.484338 -265.061192) (xy 20.494461 -265.061694) (xy 20.513174 -265.069425)
			(xy 20.527527 -265.083706) (xy 20.535354 -265.102379) (xy 20.5359 -265.1125) (xy 20.5359 -265.52144)
			(xy 26.577036 -265.52144) (xy 26.577036 -265.1125) (xy 26.577422 -265.102341) (xy 26.585225 -265.083582)
			(xy 26.599633 -265.069257) (xy 26.618437 -265.061564) (xy 26.628598 -265.061192) (xy 28.028138 -265.061192)
			(xy 28.038261 -265.061694) (xy 28.056974 -265.069425) (xy 28.071327 -265.083706) (xy 28.079154 -265.102379)
			(xy 28.0797 -265.1125) (xy 28.0797 -265.52144) (xy 34.120836 -265.52144) (xy 34.120836 -265.1125)
			(xy 34.121222 -265.102341) (xy 34.129025 -265.083582) (xy 34.143433 -265.069257) (xy 34.162237 -265.061564)
			(xy 34.172398 -265.061192) (xy 35.571938 -265.061192) (xy 35.582061 -265.061694) (xy 35.600774 -265.069425)
			(xy 35.615127 -265.083706) (xy 35.622954 -265.102379) (xy 35.6235 -265.1125) (xy 35.6235 -265.52144)
			(xy 41.664636 -265.52144) (xy 41.664636 -265.1125) (xy 41.665022 -265.102341) (xy 41.672825 -265.083582)
			(xy 41.687233 -265.069257) (xy 41.706037 -265.061564) (xy 41.716198 -265.061192) (xy 43.115738 -265.061192)
			(xy 43.125861 -265.061694) (xy 43.144574 -265.069425) (xy 43.158927 -265.083706) (xy 43.166754 -265.102379)
			(xy 43.1673 -265.1125) (xy 43.1673 -265.52144) (xy 49.208436 -265.52144) (xy 49.208436 -265.1125)
			(xy 49.208822 -265.102341) (xy 49.216625 -265.083582) (xy 49.231033 -265.069257) (xy 49.249837 -265.061564)
			(xy 49.259998 -265.061192) (xy 50.659538 -265.061192) (xy 50.669661 -265.061694) (xy 50.688374 -265.069425)
			(xy 50.702727 -265.083706) (xy 50.710554 -265.102379) (xy 50.7111 -265.1125) (xy 50.7111 -265.52144)
			(xy 56.752236 -265.52144) (xy 56.752236 -265.1125) (xy 56.752622 -265.102341) (xy 56.760425 -265.083582)
			(xy 56.774833 -265.069257) (xy 56.793637 -265.061564) (xy 56.803798 -265.061192) (xy 58.203338 -265.061192)
			(xy 58.213461 -265.061694) (xy 58.232174 -265.069425) (xy 58.246527 -265.083706) (xy 58.254354 -265.102379)
			(xy 58.2549 -265.1125) (xy 58.2549 -265.52144) (xy 64.296036 -265.52144) (xy 64.296036 -265.1125)
			(xy 64.296422 -265.102341) (xy 64.304225 -265.083582) (xy 64.318633 -265.069257) (xy 64.337437 -265.061564)
			(xy 64.347598 -265.061192) (xy 65.747138 -265.061192) (xy 65.757261 -265.061694) (xy 65.775974 -265.069425)
			(xy 65.790327 -265.083706) (xy 65.798154 -265.102379) (xy 65.7987 -265.1125) (xy 65.7987 -265.52144)
			(xy 162.162236 -265.52144) (xy 162.162236 -265.1125) (xy 162.162622 -265.102341) (xy 162.170425 -265.083582)
			(xy 162.184833 -265.069257) (xy 162.203637 -265.061564) (xy 162.213798 -265.061192) (xy 163.613338 -265.061192)
			(xy 163.623461 -265.061694) (xy 163.642174 -265.069425) (xy 163.656527 -265.083706) (xy 163.664354 -265.102379)
			(xy 163.6649 -265.1125) (xy 163.6649 -265.52144) (xy 169.706036 -265.52144) (xy 169.706036 -265.1125)
			(xy 169.706422 -265.102341) (xy 169.714225 -265.083582) (xy 169.728633 -265.069257) (xy 169.747437 -265.061564)
			(xy 169.757598 -265.061192) (xy 171.157138 -265.061192) (xy 171.167261 -265.061694) (xy 171.185974 -265.069425)
			(xy 171.200327 -265.083706) (xy 171.208154 -265.102379) (xy 171.2087 -265.1125) (xy 171.2087 -265.52144)
			(xy 177.249836 -265.52144) (xy 177.249836 -265.1125) (xy 177.250222 -265.102341) (xy 177.258025 -265.083582)
			(xy 177.272433 -265.069257) (xy 177.291237 -265.061564) (xy 177.301398 -265.061192) (xy 178.700938 -265.061192)
			(xy 178.711061 -265.061694) (xy 178.729774 -265.069425) (xy 178.744127 -265.083706) (xy 178.751954 -265.102379)
			(xy 178.7525 -265.1125) (xy 178.7525 -265.52144) (xy 184.793636 -265.52144) (xy 184.793636 -265.1125)
			(xy 184.794022 -265.102341) (xy 184.801825 -265.083582) (xy 184.816233 -265.069257) (xy 184.835037 -265.061564)
			(xy 184.845198 -265.061192) (xy 186.244738 -265.061192) (xy 186.254861 -265.061694) (xy 186.273574 -265.069425)
			(xy 186.287927 -265.083706) (xy 186.295754 -265.102379) (xy 186.2963 -265.1125) (xy 186.2963 -265.52144)
			(xy 192.337436 -265.52144) (xy 192.337436 -265.1125) (xy 192.337822 -265.102341) (xy 192.345625 -265.083582)
			(xy 192.360033 -265.069257) (xy 192.378837 -265.061564) (xy 192.388998 -265.061192) (xy 193.788538 -265.061192)
			(xy 193.798661 -265.061694) (xy 193.817374 -265.069425) (xy 193.831727 -265.083706) (xy 193.839554 -265.102379)
			(xy 193.8401 -265.1125) (xy 193.8401 -265.52144) (xy 199.881236 -265.52144) (xy 199.881236 -265.1125)
			(xy 199.881622 -265.102341) (xy 199.889425 -265.083582) (xy 199.903833 -265.069257) (xy 199.922637 -265.061564)
			(xy 199.932798 -265.061192) (xy 201.332338 -265.061192) (xy 201.342461 -265.061694) (xy 201.361174 -265.069425)
			(xy 201.375527 -265.083706) (xy 201.383354 -265.102379) (xy 201.3839 -265.1125) (xy 201.3839 -265.52144)
			(xy 207.425036 -265.52144) (xy 207.425036 -265.1125) (xy 207.425422 -265.102341) (xy 207.433225 -265.083582)
			(xy 207.447633 -265.069257) (xy 207.466437 -265.061564) (xy 207.476598 -265.061192) (xy 208.876138 -265.061192)
			(xy 208.886261 -265.061694) (xy 208.904974 -265.069425) (xy 208.919327 -265.083706) (xy 208.927154 -265.102379)
			(xy 208.9277 -265.1125) (xy 208.9277 -265.52144) (xy 214.968836 -265.52144) (xy 214.968836 -265.1125)
			(xy 214.969222 -265.102341) (xy 214.977025 -265.083582) (xy 214.991433 -265.069257) (xy 215.010237 -265.061564)
			(xy 215.020398 -265.061192) (xy 216.419938 -265.061192) (xy 216.430061 -265.061694) (xy 216.448774 -265.069425)
			(xy 216.463127 -265.083706) (xy 216.470954 -265.102379) (xy 216.4715 -265.1125) (xy 216.4715 -265.52144)
			(xy 259.429504 -265.52144) (xy 259.429504 -265.1125) (xy 259.429922 -265.102345) (xy 259.437718 -265.083592)
			(xy 259.452116 -265.069269) (xy 259.470909 -265.06157) (xy 259.481066 -265.061192) (xy 260.880606 -265.061192)
			(xy 260.890727 -265.06172) (xy 260.909439 -265.069441) (xy 260.923794 -265.083714) (xy 260.931621 -265.102382)
			(xy 260.932168 -265.1125) (xy 260.932168 -265.52144) (xy 266.973304 -265.52144) (xy 266.973304 -265.1125)
			(xy 266.973722 -265.102345) (xy 266.981518 -265.083592) (xy 266.995916 -265.069269) (xy 267.014709 -265.06157)
			(xy 267.024866 -265.061192) (xy 268.424406 -265.061192) (xy 268.434527 -265.06172) (xy 268.453239 -265.069441)
			(xy 268.467594 -265.083714) (xy 268.475421 -265.102382) (xy 268.475968 -265.1125) (xy 268.475968 -265.52144)
			(xy 274.517104 -265.52144) (xy 274.517104 -265.1125) (xy 274.517522 -265.102345) (xy 274.525318 -265.083592)
			(xy 274.539716 -265.069269) (xy 274.558509 -265.06157) (xy 274.568666 -265.061192) (xy 275.968206 -265.061192)
			(xy 275.978327 -265.06172) (xy 275.997039 -265.069441) (xy 276.011394 -265.083714) (xy 276.019221 -265.102382)
			(xy 276.019768 -265.1125) (xy 276.019768 -265.52144) (xy 282.060904 -265.52144) (xy 282.060904 -265.1125)
			(xy 282.061322 -265.102345) (xy 282.069118 -265.083592) (xy 282.083516 -265.069269) (xy 282.102309 -265.06157)
			(xy 282.112466 -265.061192) (xy 283.512006 -265.061192) (xy 283.522127 -265.06172) (xy 283.540839 -265.069441)
			(xy 283.555194 -265.083714) (xy 283.563021 -265.102382) (xy 283.563568 -265.1125) (xy 283.563568 -265.52144)
			(xy 289.604704 -265.52144) (xy 289.604704 -265.1125) (xy 289.605122 -265.102345) (xy 289.612918 -265.083592)
			(xy 289.627316 -265.069269) (xy 289.646109 -265.06157) (xy 289.656266 -265.061192) (xy 291.055806 -265.061192)
			(xy 291.065927 -265.06172) (xy 291.084639 -265.069441) (xy 291.098994 -265.083714) (xy 291.106821 -265.102382)
			(xy 291.107368 -265.1125) (xy 291.107368 -265.52144) (xy 297.148504 -265.52144) (xy 297.148504 -265.1125)
			(xy 297.148922 -265.102345) (xy 297.156718 -265.083592) (xy 297.171116 -265.069269) (xy 297.189909 -265.06157)
			(xy 297.200066 -265.061192) (xy 298.599606 -265.061192) (xy 298.609727 -265.06172) (xy 298.628439 -265.069441)
			(xy 298.642794 -265.083714) (xy 298.650621 -265.102382) (xy 298.651168 -265.1125) (xy 298.651168 -265.52144)
			(xy 304.692304 -265.52144) (xy 304.692304 -265.1125) (xy 304.692722 -265.102345) (xy 304.700518 -265.083592)
			(xy 304.714916 -265.069269) (xy 304.733709 -265.06157) (xy 304.743866 -265.061192) (xy 306.143406 -265.061192)
			(xy 306.153527 -265.06172) (xy 306.172239 -265.069441) (xy 306.186594 -265.083714) (xy 306.194421 -265.102382)
			(xy 306.194968 -265.1125) (xy 306.194968 -265.52144) (xy 312.236104 -265.52144) (xy 312.236104 -265.1125)
			(xy 312.236522 -265.102345) (xy 312.244318 -265.083592) (xy 312.258716 -265.069269) (xy 312.277509 -265.06157)
			(xy 312.287666 -265.061192) (xy 313.687206 -265.061192) (xy 313.697327 -265.06172) (xy 313.716039 -265.069441)
			(xy 313.730394 -265.083714) (xy 313.738221 -265.102382) (xy 313.738768 -265.1125) (xy 313.738768 -265.52144)
			(xy 410.102304 -265.52144) (xy 410.102304 -265.1125) (xy 410.102722 -265.102345) (xy 410.110518 -265.083592)
			(xy 410.124916 -265.069269) (xy 410.143709 -265.06157) (xy 410.153866 -265.061192) (xy 411.553406 -265.061192)
			(xy 411.563527 -265.06172) (xy 411.582239 -265.069441) (xy 411.596594 -265.083714) (xy 411.604421 -265.102382)
			(xy 411.604968 -265.1125) (xy 411.604968 -265.52144) (xy 417.646104 -265.52144) (xy 417.646104 -265.1125)
			(xy 417.646522 -265.102345) (xy 417.654318 -265.083592) (xy 417.668716 -265.069269) (xy 417.687509 -265.06157)
			(xy 417.697666 -265.061192) (xy 419.097206 -265.061192) (xy 419.107327 -265.06172) (xy 419.126039 -265.069441)
			(xy 419.140394 -265.083714) (xy 419.148221 -265.102382) (xy 419.148768 -265.1125) (xy 419.148768 -265.52144)
			(xy 425.189904 -265.52144) (xy 425.189904 -265.1125) (xy 425.190322 -265.102345) (xy 425.198118 -265.083592)
			(xy 425.212516 -265.069269) (xy 425.231309 -265.06157) (xy 425.241466 -265.061192) (xy 426.641006 -265.061192)
			(xy 426.651127 -265.06172) (xy 426.669839 -265.069441) (xy 426.684194 -265.083714) (xy 426.692021 -265.102382)
			(xy 426.692568 -265.1125) (xy 426.692568 -265.52144) (xy 432.733704 -265.52144) (xy 432.733704 -265.1125)
			(xy 432.734122 -265.102345) (xy 432.741918 -265.083592) (xy 432.756316 -265.069269) (xy 432.775109 -265.06157)
			(xy 432.785266 -265.061192) (xy 434.184806 -265.061192) (xy 434.194927 -265.06172) (xy 434.213639 -265.069441)
			(xy 434.227994 -265.083714) (xy 434.235821 -265.102382) (xy 434.236368 -265.1125) (xy 434.236368 -265.52144)
			(xy 440.277504 -265.52144) (xy 440.277504 -265.1125) (xy 440.277922 -265.102345) (xy 440.285718 -265.083592)
			(xy 440.300116 -265.069269) (xy 440.318909 -265.06157) (xy 440.329066 -265.061192) (xy 441.728606 -265.061192)
			(xy 441.738727 -265.06172) (xy 441.757439 -265.069441) (xy 441.771794 -265.083714) (xy 441.779621 -265.102382)
			(xy 441.780168 -265.1125) (xy 441.780168 -265.52144) (xy 447.821304 -265.52144) (xy 447.821304 -265.1125)
			(xy 447.821722 -265.102345) (xy 447.829518 -265.083592) (xy 447.843916 -265.069269) (xy 447.862709 -265.06157)
			(xy 447.872866 -265.061192) (xy 449.272406 -265.061192) (xy 449.282527 -265.06172) (xy 449.301239 -265.069441)
			(xy 449.315594 -265.083714) (xy 449.323421 -265.102382) (xy 449.323968 -265.1125) (xy 449.323968 -265.52144)
			(xy 455.365104 -265.52144) (xy 455.365104 -265.1125) (xy 455.365522 -265.102345) (xy 455.373318 -265.083592)
			(xy 455.387716 -265.069269) (xy 455.406509 -265.06157) (xy 455.416666 -265.061192) (xy 456.816206 -265.061192)
			(xy 456.826327 -265.06172) (xy 456.845039 -265.069441) (xy 456.859394 -265.083714) (xy 456.867221 -265.102382)
			(xy 456.867768 -265.1125) (xy 456.867768 -265.52144) (xy 462.908904 -265.52144) (xy 462.908904 -265.1125)
			(xy 462.909322 -265.102345) (xy 462.917118 -265.083592) (xy 462.931516 -265.069269) (xy 462.950309 -265.06157)
			(xy 462.960466 -265.061192) (xy 464.360006 -265.061192) (xy 464.370127 -265.06172) (xy 464.388839 -265.069441)
			(xy 464.403194 -265.083714) (xy 464.411021 -265.102382) (xy 464.411568 -265.1125) (xy 464.411568 -265.52144)
			(xy 464.41121 -265.531601) (xy 464.403396 -265.55036) (xy 464.388979 -265.564683) (xy 464.370169 -265.572376)
			(xy 464.360006 -265.572748) (xy 462.960466 -265.572748) (xy 462.950336 -265.572301) (xy 462.931611 -265.56456)
			(xy 462.917256 -265.550261) (xy 462.90944 -265.531568) (xy 462.908904 -265.52144) (xy 456.867768 -265.52144)
			(xy 456.86741 -265.531601) (xy 456.859596 -265.55036) (xy 456.845179 -265.564683) (xy 456.826369 -265.572376)
			(xy 456.816206 -265.572748) (xy 455.416666 -265.572748) (xy 455.406536 -265.572301) (xy 455.387811 -265.56456)
			(xy 455.373456 -265.550261) (xy 455.36564 -265.531568) (xy 455.365104 -265.52144) (xy 449.323968 -265.52144)
			(xy 449.32361 -265.531601) (xy 449.315796 -265.55036) (xy 449.301379 -265.564683) (xy 449.282569 -265.572376)
			(xy 449.272406 -265.572748) (xy 447.872866 -265.572748) (xy 447.862736 -265.572301) (xy 447.844011 -265.56456)
			(xy 447.829656 -265.550261) (xy 447.82184 -265.531568) (xy 447.821304 -265.52144) (xy 441.780168 -265.52144)
			(xy 441.77981 -265.531601) (xy 441.771996 -265.55036) (xy 441.757579 -265.564683) (xy 441.738769 -265.572376)
			(xy 441.728606 -265.572748) (xy 440.329066 -265.572748) (xy 440.318936 -265.572301) (xy 440.300211 -265.56456)
			(xy 440.285856 -265.550261) (xy 440.27804 -265.531568) (xy 440.277504 -265.52144) (xy 434.236368 -265.52144)
			(xy 434.23601 -265.531601) (xy 434.228196 -265.55036) (xy 434.213779 -265.564683) (xy 434.194969 -265.572376)
			(xy 434.184806 -265.572748) (xy 432.785266 -265.572748) (xy 432.775136 -265.572301) (xy 432.756411 -265.56456)
			(xy 432.742056 -265.550261) (xy 432.73424 -265.531568) (xy 432.733704 -265.52144) (xy 426.692568 -265.52144)
			(xy 426.69221 -265.531601) (xy 426.684396 -265.55036) (xy 426.669979 -265.564683) (xy 426.651169 -265.572376)
			(xy 426.641006 -265.572748) (xy 425.241466 -265.572748) (xy 425.231336 -265.572301) (xy 425.212611 -265.56456)
			(xy 425.198256 -265.550261) (xy 425.19044 -265.531568) (xy 425.189904 -265.52144) (xy 419.148768 -265.52144)
			(xy 419.14841 -265.531601) (xy 419.140596 -265.55036) (xy 419.126179 -265.564683) (xy 419.107369 -265.572376)
			(xy 419.097206 -265.572748) (xy 417.697666 -265.572748) (xy 417.687536 -265.572301) (xy 417.668811 -265.56456)
			(xy 417.654456 -265.550261) (xy 417.64664 -265.531568) (xy 417.646104 -265.52144) (xy 411.604968 -265.52144)
			(xy 411.60461 -265.531601) (xy 411.596796 -265.55036) (xy 411.582379 -265.564683) (xy 411.563569 -265.572376)
			(xy 411.553406 -265.572748) (xy 410.153866 -265.572748) (xy 410.143736 -265.572301) (xy 410.125011 -265.56456)
			(xy 410.110656 -265.550261) (xy 410.10284 -265.531568) (xy 410.102304 -265.52144) (xy 313.738768 -265.52144)
			(xy 313.73841 -265.531601) (xy 313.730596 -265.55036) (xy 313.716179 -265.564683) (xy 313.697369 -265.572376)
			(xy 313.687206 -265.572748) (xy 312.287666 -265.572748) (xy 312.277536 -265.572301) (xy 312.258811 -265.56456)
			(xy 312.244456 -265.550261) (xy 312.23664 -265.531568) (xy 312.236104 -265.52144) (xy 306.194968 -265.52144)
			(xy 306.19461 -265.531601) (xy 306.186796 -265.55036) (xy 306.172379 -265.564683) (xy 306.153569 -265.572376)
			(xy 306.143406 -265.572748) (xy 304.743866 -265.572748) (xy 304.733736 -265.572301) (xy 304.715011 -265.56456)
			(xy 304.700656 -265.550261) (xy 304.69284 -265.531568) (xy 304.692304 -265.52144) (xy 298.651168 -265.52144)
			(xy 298.65081 -265.531601) (xy 298.642996 -265.55036) (xy 298.628579 -265.564683) (xy 298.609769 -265.572376)
			(xy 298.599606 -265.572748) (xy 297.200066 -265.572748) (xy 297.189936 -265.572301) (xy 297.171211 -265.56456)
			(xy 297.156856 -265.550261) (xy 297.14904 -265.531568) (xy 297.148504 -265.52144) (xy 291.107368 -265.52144)
			(xy 291.10701 -265.531601) (xy 291.099196 -265.55036) (xy 291.084779 -265.564683) (xy 291.065969 -265.572376)
			(xy 291.055806 -265.572748) (xy 289.656266 -265.572748) (xy 289.646136 -265.572301) (xy 289.627411 -265.56456)
			(xy 289.613056 -265.550261) (xy 289.60524 -265.531568) (xy 289.604704 -265.52144) (xy 283.563568 -265.52144)
			(xy 283.56321 -265.531601) (xy 283.555396 -265.55036) (xy 283.540979 -265.564683) (xy 283.522169 -265.572376)
			(xy 283.512006 -265.572748) (xy 282.112466 -265.572748) (xy 282.102336 -265.572301) (xy 282.083611 -265.56456)
			(xy 282.069256 -265.550261) (xy 282.06144 -265.531568) (xy 282.060904 -265.52144) (xy 276.019768 -265.52144)
			(xy 276.01941 -265.531601) (xy 276.011596 -265.55036) (xy 275.997179 -265.564683) (xy 275.978369 -265.572376)
			(xy 275.968206 -265.572748) (xy 274.568666 -265.572748) (xy 274.558536 -265.572301) (xy 274.539811 -265.56456)
			(xy 274.525456 -265.550261) (xy 274.51764 -265.531568) (xy 274.517104 -265.52144) (xy 268.475968 -265.52144)
			(xy 268.47561 -265.531601) (xy 268.467796 -265.55036) (xy 268.453379 -265.564683) (xy 268.434569 -265.572376)
			(xy 268.424406 -265.572748) (xy 267.024866 -265.572748) (xy 267.014736 -265.572301) (xy 266.996011 -265.56456)
			(xy 266.981656 -265.550261) (xy 266.97384 -265.531568) (xy 266.973304 -265.52144) (xy 260.932168 -265.52144)
			(xy 260.93181 -265.531601) (xy 260.923996 -265.55036) (xy 260.909579 -265.564683) (xy 260.890769 -265.572376)
			(xy 260.880606 -265.572748) (xy 259.481066 -265.572748) (xy 259.470936 -265.572301) (xy 259.452211 -265.56456)
			(xy 259.437856 -265.550261) (xy 259.43004 -265.531568) (xy 259.429504 -265.52144) (xy 216.4715 -265.52144)
			(xy 216.471111 -265.531597) (xy 216.463302 -265.55035) (xy 216.448896 -265.564672) (xy 216.430097 -265.57237)
			(xy 216.419938 -265.572748) (xy 215.020398 -265.572748) (xy 215.01027 -265.572275) (xy 214.991546 -265.564544)
			(xy 214.97719 -265.550253) (xy 214.969373 -265.531566) (xy 214.968836 -265.52144) (xy 208.9277 -265.52144)
			(xy 208.927311 -265.531597) (xy 208.919502 -265.55035) (xy 208.905096 -265.564672) (xy 208.886297 -265.57237)
			(xy 208.876138 -265.572748) (xy 207.476598 -265.572748) (xy 207.46647 -265.572275) (xy 207.447746 -265.564544)
			(xy 207.43339 -265.550253) (xy 207.425573 -265.531566) (xy 207.425036 -265.52144) (xy 201.3839 -265.52144)
			(xy 201.383511 -265.531597) (xy 201.375702 -265.55035) (xy 201.361296 -265.564672) (xy 201.342497 -265.57237)
			(xy 201.332338 -265.572748) (xy 199.932798 -265.572748) (xy 199.92267 -265.572275) (xy 199.903946 -265.564544)
			(xy 199.88959 -265.550253) (xy 199.881773 -265.531566) (xy 199.881236 -265.52144) (xy 193.8401 -265.52144)
			(xy 193.839711 -265.531597) (xy 193.831902 -265.55035) (xy 193.817496 -265.564672) (xy 193.798697 -265.57237)
			(xy 193.788538 -265.572748) (xy 192.388998 -265.572748) (xy 192.37887 -265.572275) (xy 192.360146 -265.564544)
			(xy 192.34579 -265.550253) (xy 192.337973 -265.531566) (xy 192.337436 -265.52144) (xy 186.2963 -265.52144)
			(xy 186.295911 -265.531597) (xy 186.288102 -265.55035) (xy 186.273696 -265.564672) (xy 186.254897 -265.57237)
			(xy 186.244738 -265.572748) (xy 184.845198 -265.572748) (xy 184.83507 -265.572275) (xy 184.816346 -265.564544)
			(xy 184.80199 -265.550253) (xy 184.794173 -265.531566) (xy 184.793636 -265.52144) (xy 178.7525 -265.52144)
			(xy 178.752111 -265.531597) (xy 178.744302 -265.55035) (xy 178.729896 -265.564672) (xy 178.711097 -265.57237)
			(xy 178.700938 -265.572748) (xy 177.301398 -265.572748) (xy 177.29127 -265.572275) (xy 177.272546 -265.564544)
			(xy 177.25819 -265.550253) (xy 177.250373 -265.531566) (xy 177.249836 -265.52144) (xy 171.2087 -265.52144)
			(xy 171.208311 -265.531597) (xy 171.200502 -265.55035) (xy 171.186096 -265.564672) (xy 171.167297 -265.57237)
			(xy 171.157138 -265.572748) (xy 169.757598 -265.572748) (xy 169.74747 -265.572275) (xy 169.728746 -265.564544)
			(xy 169.71439 -265.550253) (xy 169.706573 -265.531566) (xy 169.706036 -265.52144) (xy 163.6649 -265.52144)
			(xy 163.664511 -265.531597) (xy 163.656702 -265.55035) (xy 163.642296 -265.564672) (xy 163.623497 -265.57237)
			(xy 163.613338 -265.572748) (xy 162.213798 -265.572748) (xy 162.20367 -265.572275) (xy 162.184946 -265.564544)
			(xy 162.17059 -265.550253) (xy 162.162773 -265.531566) (xy 162.162236 -265.52144) (xy 65.7987 -265.52144)
			(xy 65.798311 -265.531597) (xy 65.790502 -265.55035) (xy 65.776096 -265.564672) (xy 65.757297 -265.57237)
			(xy 65.747138 -265.572748) (xy 64.347598 -265.572748) (xy 64.33747 -265.572275) (xy 64.318746 -265.564544)
			(xy 64.30439 -265.550253) (xy 64.296573 -265.531566) (xy 64.296036 -265.52144) (xy 58.2549 -265.52144)
			(xy 58.254511 -265.531597) (xy 58.246702 -265.55035) (xy 58.232296 -265.564672) (xy 58.213497 -265.57237)
			(xy 58.203338 -265.572748) (xy 56.803798 -265.572748) (xy 56.79367 -265.572275) (xy 56.774946 -265.564544)
			(xy 56.76059 -265.550253) (xy 56.752773 -265.531566) (xy 56.752236 -265.52144) (xy 50.7111 -265.52144)
			(xy 50.710711 -265.531597) (xy 50.702902 -265.55035) (xy 50.688496 -265.564672) (xy 50.669697 -265.57237)
			(xy 50.659538 -265.572748) (xy 49.259998 -265.572748) (xy 49.24987 -265.572275) (xy 49.231146 -265.564544)
			(xy 49.21679 -265.550253) (xy 49.208973 -265.531566) (xy 49.208436 -265.52144) (xy 43.1673 -265.52144)
			(xy 43.166911 -265.531597) (xy 43.159102 -265.55035) (xy 43.144696 -265.564672) (xy 43.125897 -265.57237)
			(xy 43.115738 -265.572748) (xy 41.716198 -265.572748) (xy 41.70607 -265.572275) (xy 41.687346 -265.564544)
			(xy 41.67299 -265.550253) (xy 41.665173 -265.531566) (xy 41.664636 -265.52144) (xy 35.6235 -265.52144)
			(xy 35.623111 -265.531597) (xy 35.615302 -265.55035) (xy 35.600896 -265.564672) (xy 35.582097 -265.57237)
			(xy 35.571938 -265.572748) (xy 34.172398 -265.572748) (xy 34.16227 -265.572275) (xy 34.143546 -265.564544)
			(xy 34.12919 -265.550253) (xy 34.121373 -265.531566) (xy 34.120836 -265.52144) (xy 28.0797 -265.52144)
			(xy 28.079311 -265.531597) (xy 28.071502 -265.55035) (xy 28.057096 -265.564672) (xy 28.038297 -265.57237)
			(xy 28.028138 -265.572748) (xy 26.628598 -265.572748) (xy 26.61847 -265.572275) (xy 26.599746 -265.564544)
			(xy 26.58539 -265.550253) (xy 26.577573 -265.531566) (xy 26.577036 -265.52144) (xy 20.5359 -265.52144)
			(xy 20.535511 -265.531597) (xy 20.527702 -265.55035) (xy 20.513296 -265.564672) (xy 20.494497 -265.57237)
			(xy 20.484338 -265.572748) (xy 19.084798 -265.572748) (xy 19.07467 -265.572275) (xy 19.055946 -265.564544)
			(xy 19.04159 -265.550253) (xy 19.033773 -265.531566) (xy 19.033236 -265.52144) (xy 12.9921 -265.52144)
			(xy 12.991711 -265.531597) (xy 12.983902 -265.55035) (xy 12.969496 -265.564672) (xy 12.950697 -265.57237)
			(xy 12.940538 -265.572748) (xy 11.540998 -265.572748) (xy 11.53087 -265.572275) (xy 11.512146 -265.564544)
			(xy 11.49779 -265.550253) (xy 11.489973 -265.531566) (xy 11.489436 -265.52144) (xy 2.509012 -265.52144)
			(xy 2.509012 -266.371324) (xy 7.389368 -266.371324) (xy 7.389368 -265.962384) (xy 7.389808 -265.952233)
			(xy 7.397603 -265.933486) (xy 7.411993 -265.919164) (xy 7.430777 -265.911459) (xy 7.44093 -265.911076)
			(xy 8.84047 -265.911076) (xy 8.850599 -265.911552) (xy 8.869327 -265.919277) (xy 8.883685 -265.933567)
			(xy 8.891499 -265.952257) (xy 8.892032 -265.962384) (xy 8.892032 -266.371324) (xy 14.933168 -266.371324)
			(xy 14.933168 -265.962384) (xy 14.933608 -265.952233) (xy 14.941403 -265.933486) (xy 14.955793 -265.919164)
			(xy 14.974577 -265.911459) (xy 14.98473 -265.911076) (xy 16.38427 -265.911076) (xy 16.394399 -265.911552)
			(xy 16.413127 -265.919277) (xy 16.427485 -265.933567) (xy 16.435299 -265.952257) (xy 16.435832 -265.962384)
			(xy 16.435832 -266.371324) (xy 22.476968 -266.371324) (xy 22.476968 -265.962384) (xy 22.477408 -265.952233)
			(xy 22.485203 -265.933486) (xy 22.499593 -265.919164) (xy 22.518377 -265.911459) (xy 22.52853 -265.911076)
			(xy 23.92807 -265.911076) (xy 23.938199 -265.911552) (xy 23.956927 -265.919277) (xy 23.971285 -265.933567)
			(xy 23.979099 -265.952257) (xy 23.979632 -265.962384) (xy 23.979632 -266.371324) (xy 30.020768 -266.371324)
			(xy 30.020768 -265.962384) (xy 30.021208 -265.952233) (xy 30.029003 -265.933486) (xy 30.043393 -265.919164)
			(xy 30.062177 -265.911459) (xy 30.07233 -265.911076) (xy 31.47187 -265.911076) (xy 31.481999 -265.911552)
			(xy 31.500727 -265.919277) (xy 31.515085 -265.933567) (xy 31.522899 -265.952257) (xy 31.523432 -265.962384)
			(xy 31.523432 -266.371324) (xy 37.564568 -266.371324) (xy 37.564568 -265.962384) (xy 37.565008 -265.952233)
			(xy 37.572803 -265.933486) (xy 37.587193 -265.919164) (xy 37.605977 -265.911459) (xy 37.61613 -265.911076)
			(xy 39.01567 -265.911076) (xy 39.025799 -265.911552) (xy 39.044527 -265.919277) (xy 39.058885 -265.933567)
			(xy 39.066699 -265.952257) (xy 39.067232 -265.962384) (xy 39.067232 -266.371324) (xy 45.108368 -266.371324)
			(xy 45.108368 -265.962384) (xy 45.108808 -265.952233) (xy 45.116603 -265.933486) (xy 45.130993 -265.919164)
			(xy 45.149777 -265.911459) (xy 45.15993 -265.911076) (xy 46.55947 -265.911076) (xy 46.569599 -265.911552)
			(xy 46.588327 -265.919277) (xy 46.602685 -265.933567) (xy 46.610499 -265.952257) (xy 46.611032 -265.962384)
			(xy 46.611032 -266.371324) (xy 52.652168 -266.371324) (xy 52.652168 -265.962384) (xy 52.652608 -265.952233)
			(xy 52.660403 -265.933486) (xy 52.674793 -265.919164) (xy 52.693577 -265.911459) (xy 52.70373 -265.911076)
			(xy 54.10327 -265.911076) (xy 54.113399 -265.911552) (xy 54.132127 -265.919277) (xy 54.146485 -265.933567)
			(xy 54.154299 -265.952257) (xy 54.154832 -265.962384) (xy 54.154832 -266.371324) (xy 60.195968 -266.371324)
			(xy 60.195968 -265.962384) (xy 60.196408 -265.952233) (xy 60.204203 -265.933486) (xy 60.218593 -265.919164)
			(xy 60.237377 -265.911459) (xy 60.24753 -265.911076) (xy 61.64707 -265.911076) (xy 61.657199 -265.911552)
			(xy 61.675927 -265.919277) (xy 61.690285 -265.933567) (xy 61.698099 -265.952257) (xy 61.698632 -265.962384)
			(xy 61.698632 -266.371324) (xy 158.062168 -266.371324) (xy 158.062168 -265.962384) (xy 158.062608 -265.952233)
			(xy 158.070403 -265.933486) (xy 158.084793 -265.919164) (xy 158.103577 -265.911459) (xy 158.11373 -265.911076)
			(xy 159.51327 -265.911076) (xy 159.523399 -265.911552) (xy 159.542127 -265.919277) (xy 159.556485 -265.933567)
			(xy 159.564299 -265.952257) (xy 159.564832 -265.962384) (xy 159.564832 -266.371324) (xy 165.605968 -266.371324)
			(xy 165.605968 -265.962384) (xy 165.606408 -265.952233) (xy 165.614203 -265.933486) (xy 165.628593 -265.919164)
			(xy 165.647377 -265.911459) (xy 165.65753 -265.911076) (xy 167.05707 -265.911076) (xy 167.067199 -265.911552)
			(xy 167.085927 -265.919277) (xy 167.100285 -265.933567) (xy 167.108099 -265.952257) (xy 167.108632 -265.962384)
			(xy 167.108632 -266.371324) (xy 173.149768 -266.371324) (xy 173.149768 -265.962384) (xy 173.150208 -265.952233)
			(xy 173.158003 -265.933486) (xy 173.172393 -265.919164) (xy 173.191177 -265.911459) (xy 173.20133 -265.911076)
			(xy 174.60087 -265.911076) (xy 174.610999 -265.911552) (xy 174.629727 -265.919277) (xy 174.644085 -265.933567)
			(xy 174.651899 -265.952257) (xy 174.652432 -265.962384) (xy 174.652432 -266.371324) (xy 180.693568 -266.371324)
			(xy 180.693568 -265.962384) (xy 180.694008 -265.952233) (xy 180.701803 -265.933486) (xy 180.716193 -265.919164)
			(xy 180.734977 -265.911459) (xy 180.74513 -265.911076) (xy 182.14467 -265.911076) (xy 182.154799 -265.911552)
			(xy 182.173527 -265.919277) (xy 182.187885 -265.933567) (xy 182.195699 -265.952257) (xy 182.196232 -265.962384)
			(xy 182.196232 -266.371324) (xy 188.237368 -266.371324) (xy 188.237368 -265.962384) (xy 188.237808 -265.952233)
			(xy 188.245603 -265.933486) (xy 188.259993 -265.919164) (xy 188.278777 -265.911459) (xy 188.28893 -265.911076)
			(xy 189.68847 -265.911076) (xy 189.698599 -265.911552) (xy 189.717327 -265.919277) (xy 189.731685 -265.933567)
			(xy 189.739499 -265.952257) (xy 189.740032 -265.962384) (xy 189.740032 -266.371324) (xy 195.781168 -266.371324)
			(xy 195.781168 -265.962384) (xy 195.781608 -265.952233) (xy 195.789403 -265.933486) (xy 195.803793 -265.919164)
			(xy 195.822577 -265.911459) (xy 195.83273 -265.911076) (xy 197.23227 -265.911076) (xy 197.242399 -265.911552)
			(xy 197.261127 -265.919277) (xy 197.275485 -265.933567) (xy 197.283299 -265.952257) (xy 197.283832 -265.962384)
			(xy 197.283832 -266.371324) (xy 203.324968 -266.371324) (xy 203.324968 -265.962384) (xy 203.325408 -265.952233)
			(xy 203.333203 -265.933486) (xy 203.347593 -265.919164) (xy 203.366377 -265.911459) (xy 203.37653 -265.911076)
			(xy 204.77607 -265.911076) (xy 204.786199 -265.911552) (xy 204.804927 -265.919277) (xy 204.819285 -265.933567)
			(xy 204.827099 -265.952257) (xy 204.827632 -265.962384) (xy 204.827632 -266.371324) (xy 210.868768 -266.371324)
			(xy 210.868768 -265.962384) (xy 210.869208 -265.952233) (xy 210.877003 -265.933486) (xy 210.891393 -265.919164)
			(xy 210.910177 -265.911459) (xy 210.92033 -265.911076) (xy 212.31987 -265.911076) (xy 212.329999 -265.911552)
			(xy 212.348727 -265.919277) (xy 212.363085 -265.933567) (xy 212.370899 -265.952257) (xy 212.371432 -265.962384)
			(xy 212.371432 -266.371324) (xy 255.329436 -266.371324) (xy 255.329436 -265.962384) (xy 255.329809 -265.952224)
			(xy 255.337617 -265.933465) (xy 255.352029 -265.91914) (xy 255.370836 -265.911448) (xy 255.380998 -265.911076)
			(xy 256.780538 -265.911076) (xy 256.790672 -265.911496) (xy 256.8094 -265.919243) (xy 256.823757 -265.93355)
			(xy 256.831568 -265.952252) (xy 256.8321 -265.962384) (xy 256.8321 -266.371324) (xy 262.873236 -266.371324)
			(xy 262.873236 -265.962384) (xy 262.873609 -265.952224) (xy 262.881417 -265.933465) (xy 262.895829 -265.91914)
			(xy 262.914636 -265.911448) (xy 262.924798 -265.911076) (xy 264.324338 -265.911076) (xy 264.334472 -265.911496)
			(xy 264.3532 -265.919243) (xy 264.367557 -265.93355) (xy 264.375368 -265.952252) (xy 264.3759 -265.962384)
			(xy 264.3759 -266.371324) (xy 270.417036 -266.371324) (xy 270.417036 -265.962384) (xy 270.417409 -265.952224)
			(xy 270.425217 -265.933465) (xy 270.439629 -265.91914) (xy 270.458436 -265.911448) (xy 270.468598 -265.911076)
			(xy 271.868138 -265.911076) (xy 271.878272 -265.911496) (xy 271.897 -265.919243) (xy 271.911357 -265.93355)
			(xy 271.919168 -265.952252) (xy 271.9197 -265.962384) (xy 271.9197 -266.371324) (xy 277.960836 -266.371324)
			(xy 277.960836 -265.962384) (xy 277.961209 -265.952224) (xy 277.969017 -265.933465) (xy 277.983429 -265.91914)
			(xy 278.002236 -265.911448) (xy 278.012398 -265.911076) (xy 279.411938 -265.911076) (xy 279.422072 -265.911496)
			(xy 279.4408 -265.919243) (xy 279.455157 -265.93355) (xy 279.462968 -265.952252) (xy 279.4635 -265.962384)
			(xy 279.4635 -266.371324) (xy 285.504636 -266.371324) (xy 285.504636 -265.962384) (xy 285.505009 -265.952224)
			(xy 285.512817 -265.933465) (xy 285.527229 -265.91914) (xy 285.546036 -265.911448) (xy 285.556198 -265.911076)
			(xy 286.955738 -265.911076) (xy 286.965872 -265.911496) (xy 286.9846 -265.919243) (xy 286.998957 -265.93355)
			(xy 287.006768 -265.952252) (xy 287.0073 -265.962384) (xy 287.0073 -266.371324) (xy 293.048436 -266.371324)
			(xy 293.048436 -265.962384) (xy 293.048809 -265.952224) (xy 293.056617 -265.933465) (xy 293.071029 -265.91914)
			(xy 293.089836 -265.911448) (xy 293.099998 -265.911076) (xy 294.499538 -265.911076) (xy 294.509672 -265.911496)
			(xy 294.5284 -265.919243) (xy 294.542757 -265.93355) (xy 294.550568 -265.952252) (xy 294.5511 -265.962384)
			(xy 294.5511 -266.371324) (xy 300.592236 -266.371324) (xy 300.592236 -265.962384) (xy 300.592609 -265.952224)
			(xy 300.600417 -265.933465) (xy 300.614829 -265.91914) (xy 300.633636 -265.911448) (xy 300.643798 -265.911076)
			(xy 302.043338 -265.911076) (xy 302.053472 -265.911496) (xy 302.0722 -265.919243) (xy 302.086557 -265.93355)
			(xy 302.094368 -265.952252) (xy 302.0949 -265.962384) (xy 302.0949 -266.371324) (xy 308.136036 -266.371324)
			(xy 308.136036 -265.962384) (xy 308.136409 -265.952224) (xy 308.144217 -265.933465) (xy 308.158629 -265.91914)
			(xy 308.177436 -265.911448) (xy 308.187598 -265.911076) (xy 309.587138 -265.911076) (xy 309.597272 -265.911496)
			(xy 309.616 -265.919243) (xy 309.630357 -265.93355) (xy 309.638168 -265.952252) (xy 309.6387 -265.962384)
			(xy 309.6387 -266.371324) (xy 406.002236 -266.371324) (xy 406.002236 -265.962384) (xy 406.002609 -265.952224)
			(xy 406.010417 -265.933465) (xy 406.024829 -265.91914) (xy 406.043636 -265.911448) (xy 406.053798 -265.911076)
			(xy 407.453338 -265.911076) (xy 407.463472 -265.911496) (xy 407.4822 -265.919243) (xy 407.496557 -265.93355)
			(xy 407.504368 -265.952252) (xy 407.5049 -265.962384) (xy 407.5049 -266.371324) (xy 413.546036 -266.371324)
			(xy 413.546036 -265.962384) (xy 413.546409 -265.952224) (xy 413.554217 -265.933465) (xy 413.568629 -265.91914)
			(xy 413.587436 -265.911448) (xy 413.597598 -265.911076) (xy 414.997138 -265.911076) (xy 415.007272 -265.911496)
			(xy 415.026 -265.919243) (xy 415.040357 -265.93355) (xy 415.048168 -265.952252) (xy 415.0487 -265.962384)
			(xy 415.0487 -266.371324) (xy 421.089836 -266.371324) (xy 421.089836 -265.962384) (xy 421.090209 -265.952224)
			(xy 421.098017 -265.933465) (xy 421.112429 -265.91914) (xy 421.131236 -265.911448) (xy 421.141398 -265.911076)
			(xy 422.540938 -265.911076) (xy 422.551072 -265.911496) (xy 422.5698 -265.919243) (xy 422.584157 -265.93355)
			(xy 422.591968 -265.952252) (xy 422.5925 -265.962384) (xy 422.5925 -266.371324) (xy 428.633636 -266.371324)
			(xy 428.633636 -265.962384) (xy 428.634009 -265.952224) (xy 428.641817 -265.933465) (xy 428.656229 -265.91914)
			(xy 428.675036 -265.911448) (xy 428.685198 -265.911076) (xy 430.084738 -265.911076) (xy 430.094872 -265.911496)
			(xy 430.1136 -265.919243) (xy 430.127957 -265.93355) (xy 430.135768 -265.952252) (xy 430.1363 -265.962384)
			(xy 430.1363 -266.371324) (xy 436.177436 -266.371324) (xy 436.177436 -265.962384) (xy 436.177809 -265.952224)
			(xy 436.185617 -265.933465) (xy 436.200029 -265.91914) (xy 436.218836 -265.911448) (xy 436.228998 -265.911076)
			(xy 437.628538 -265.911076) (xy 437.638672 -265.911496) (xy 437.6574 -265.919243) (xy 437.671757 -265.93355)
			(xy 437.679568 -265.952252) (xy 437.6801 -265.962384) (xy 437.6801 -266.371324) (xy 443.721236 -266.371324)
			(xy 443.721236 -265.962384) (xy 443.721609 -265.952224) (xy 443.729417 -265.933465) (xy 443.743829 -265.91914)
			(xy 443.762636 -265.911448) (xy 443.772798 -265.911076) (xy 445.172338 -265.911076) (xy 445.182472 -265.911496)
			(xy 445.2012 -265.919243) (xy 445.215557 -265.93355) (xy 445.223368 -265.952252) (xy 445.2239 -265.962384)
			(xy 445.2239 -266.371324) (xy 451.265036 -266.371324) (xy 451.265036 -265.962384) (xy 451.265409 -265.952224)
			(xy 451.273217 -265.933465) (xy 451.287629 -265.91914) (xy 451.306436 -265.911448) (xy 451.316598 -265.911076)
			(xy 452.716138 -265.911076) (xy 452.726272 -265.911496) (xy 452.745 -265.919243) (xy 452.759357 -265.93355)
			(xy 452.767168 -265.952252) (xy 452.7677 -265.962384) (xy 452.7677 -266.371324) (xy 458.808836 -266.371324)
			(xy 458.808836 -265.962384) (xy 458.809209 -265.952224) (xy 458.817017 -265.933465) (xy 458.831429 -265.91914)
			(xy 458.850236 -265.911448) (xy 458.860398 -265.911076) (xy 460.259938 -265.911076) (xy 460.270072 -265.911496)
			(xy 460.2888 -265.919243) (xy 460.303157 -265.93355) (xy 460.310968 -265.952252) (xy 460.3115 -265.962384)
			(xy 460.3115 -266.371324) (xy 460.311098 -266.38148) (xy 460.303295 -266.400233) (xy 460.288892 -266.414555)
			(xy 460.270096 -266.422254) (xy 460.259938 -266.422632) (xy 458.860398 -266.422632) (xy 458.850268 -266.422174)
			(xy 458.831541 -266.414441) (xy 458.817184 -266.400145) (xy 458.80937 -266.381452) (xy 458.808836 -266.371324)
			(xy 452.7677 -266.371324) (xy 452.767298 -266.38148) (xy 452.759495 -266.400233) (xy 452.745092 -266.414555)
			(xy 452.726296 -266.422254) (xy 452.716138 -266.422632) (xy 451.316598 -266.422632) (xy 451.306468 -266.422174)
			(xy 451.287741 -266.414441) (xy 451.273384 -266.400145) (xy 451.26557 -266.381452) (xy 451.265036 -266.371324)
			(xy 445.2239 -266.371324) (xy 445.223498 -266.38148) (xy 445.215695 -266.400233) (xy 445.201292 -266.414555)
			(xy 445.182496 -266.422254) (xy 445.172338 -266.422632) (xy 443.772798 -266.422632) (xy 443.762668 -266.422174)
			(xy 443.743941 -266.414441) (xy 443.729584 -266.400145) (xy 443.72177 -266.381452) (xy 443.721236 -266.371324)
			(xy 437.6801 -266.371324) (xy 437.679698 -266.38148) (xy 437.671895 -266.400233) (xy 437.657492 -266.414555)
			(xy 437.638696 -266.422254) (xy 437.628538 -266.422632) (xy 436.228998 -266.422632) (xy 436.218868 -266.422174)
			(xy 436.200141 -266.414441) (xy 436.185784 -266.400145) (xy 436.17797 -266.381452) (xy 436.177436 -266.371324)
			(xy 430.1363 -266.371324) (xy 430.135898 -266.38148) (xy 430.128095 -266.400233) (xy 430.113692 -266.414555)
			(xy 430.094896 -266.422254) (xy 430.084738 -266.422632) (xy 428.685198 -266.422632) (xy 428.675068 -266.422174)
			(xy 428.656341 -266.414441) (xy 428.641984 -266.400145) (xy 428.63417 -266.381452) (xy 428.633636 -266.371324)
			(xy 422.5925 -266.371324) (xy 422.592098 -266.38148) (xy 422.584295 -266.400233) (xy 422.569892 -266.414555)
			(xy 422.551096 -266.422254) (xy 422.540938 -266.422632) (xy 421.141398 -266.422632) (xy 421.131268 -266.422174)
			(xy 421.112541 -266.414441) (xy 421.098184 -266.400145) (xy 421.09037 -266.381452) (xy 421.089836 -266.371324)
			(xy 415.0487 -266.371324) (xy 415.048298 -266.38148) (xy 415.040495 -266.400233) (xy 415.026092 -266.414555)
			(xy 415.007296 -266.422254) (xy 414.997138 -266.422632) (xy 413.597598 -266.422632) (xy 413.587468 -266.422174)
			(xy 413.568741 -266.414441) (xy 413.554384 -266.400145) (xy 413.54657 -266.381452) (xy 413.546036 -266.371324)
			(xy 407.5049 -266.371324) (xy 407.504498 -266.38148) (xy 407.496695 -266.400233) (xy 407.482292 -266.414555)
			(xy 407.463496 -266.422254) (xy 407.453338 -266.422632) (xy 406.053798 -266.422632) (xy 406.043668 -266.422174)
			(xy 406.024941 -266.414441) (xy 406.010584 -266.400145) (xy 406.00277 -266.381452) (xy 406.002236 -266.371324)
			(xy 309.6387 -266.371324) (xy 309.638298 -266.38148) (xy 309.630495 -266.400233) (xy 309.616092 -266.414555)
			(xy 309.597296 -266.422254) (xy 309.587138 -266.422632) (xy 308.187598 -266.422632) (xy 308.177468 -266.422174)
			(xy 308.158741 -266.414441) (xy 308.144384 -266.400145) (xy 308.13657 -266.381452) (xy 308.136036 -266.371324)
			(xy 302.0949 -266.371324) (xy 302.094498 -266.38148) (xy 302.086695 -266.400233) (xy 302.072292 -266.414555)
			(xy 302.053496 -266.422254) (xy 302.043338 -266.422632) (xy 300.643798 -266.422632) (xy 300.633668 -266.422174)
			(xy 300.614941 -266.414441) (xy 300.600584 -266.400145) (xy 300.59277 -266.381452) (xy 300.592236 -266.371324)
			(xy 294.5511 -266.371324) (xy 294.550698 -266.38148) (xy 294.542895 -266.400233) (xy 294.528492 -266.414555)
			(xy 294.509696 -266.422254) (xy 294.499538 -266.422632) (xy 293.099998 -266.422632) (xy 293.089868 -266.422174)
			(xy 293.071141 -266.414441) (xy 293.056784 -266.400145) (xy 293.04897 -266.381452) (xy 293.048436 -266.371324)
			(xy 287.0073 -266.371324) (xy 287.006898 -266.38148) (xy 286.999095 -266.400233) (xy 286.984692 -266.414555)
			(xy 286.965896 -266.422254) (xy 286.955738 -266.422632) (xy 285.556198 -266.422632) (xy 285.546068 -266.422174)
			(xy 285.527341 -266.414441) (xy 285.512984 -266.400145) (xy 285.50517 -266.381452) (xy 285.504636 -266.371324)
			(xy 279.4635 -266.371324) (xy 279.463098 -266.38148) (xy 279.455295 -266.400233) (xy 279.440892 -266.414555)
			(xy 279.422096 -266.422254) (xy 279.411938 -266.422632) (xy 278.012398 -266.422632) (xy 278.002268 -266.422174)
			(xy 277.983541 -266.414441) (xy 277.969184 -266.400145) (xy 277.96137 -266.381452) (xy 277.960836 -266.371324)
			(xy 271.9197 -266.371324) (xy 271.919298 -266.38148) (xy 271.911495 -266.400233) (xy 271.897092 -266.414555)
			(xy 271.878296 -266.422254) (xy 271.868138 -266.422632) (xy 270.468598 -266.422632) (xy 270.458468 -266.422174)
			(xy 270.439741 -266.414441) (xy 270.425384 -266.400145) (xy 270.41757 -266.381452) (xy 270.417036 -266.371324)
			(xy 264.3759 -266.371324) (xy 264.375498 -266.38148) (xy 264.367695 -266.400233) (xy 264.353292 -266.414555)
			(xy 264.334496 -266.422254) (xy 264.324338 -266.422632) (xy 262.924798 -266.422632) (xy 262.914668 -266.422174)
			(xy 262.895941 -266.414441) (xy 262.881584 -266.400145) (xy 262.87377 -266.381452) (xy 262.873236 -266.371324)
			(xy 256.8321 -266.371324) (xy 256.831698 -266.38148) (xy 256.823895 -266.400233) (xy 256.809492 -266.414555)
			(xy 256.790696 -266.422254) (xy 256.780538 -266.422632) (xy 255.380998 -266.422632) (xy 255.370868 -266.422174)
			(xy 255.352141 -266.414441) (xy 255.337784 -266.400145) (xy 255.32997 -266.381452) (xy 255.329436 -266.371324)
			(xy 212.371432 -266.371324) (xy 212.370999 -266.381476) (xy 212.363201 -266.400223) (xy 212.348809 -266.414544)
			(xy 212.330024 -266.422249) (xy 212.31987 -266.422632) (xy 210.92033 -266.422632) (xy 210.910202 -266.422148)
			(xy 210.891476 -266.414425) (xy 210.877117 -266.400137) (xy 210.869302 -266.38145) (xy 210.868768 -266.371324)
			(xy 204.827632 -266.371324) (xy 204.827199 -266.381476) (xy 204.819401 -266.400223) (xy 204.805009 -266.414544)
			(xy 204.786224 -266.422249) (xy 204.77607 -266.422632) (xy 203.37653 -266.422632) (xy 203.366402 -266.422148)
			(xy 203.347676 -266.414425) (xy 203.333317 -266.400137) (xy 203.325502 -266.38145) (xy 203.324968 -266.371324)
			(xy 197.283832 -266.371324) (xy 197.283399 -266.381476) (xy 197.275601 -266.400223) (xy 197.261209 -266.414544)
			(xy 197.242424 -266.422249) (xy 197.23227 -266.422632) (xy 195.83273 -266.422632) (xy 195.822602 -266.422148)
			(xy 195.803876 -266.414425) (xy 195.789517 -266.400137) (xy 195.781702 -266.38145) (xy 195.781168 -266.371324)
			(xy 189.740032 -266.371324) (xy 189.739599 -266.381476) (xy 189.731801 -266.400223) (xy 189.717409 -266.414544)
			(xy 189.698624 -266.422249) (xy 189.68847 -266.422632) (xy 188.28893 -266.422632) (xy 188.278802 -266.422148)
			(xy 188.260076 -266.414425) (xy 188.245717 -266.400137) (xy 188.237902 -266.38145) (xy 188.237368 -266.371324)
			(xy 182.196232 -266.371324) (xy 182.195799 -266.381476) (xy 182.188001 -266.400223) (xy 182.173609 -266.414544)
			(xy 182.154824 -266.422249) (xy 182.14467 -266.422632) (xy 180.74513 -266.422632) (xy 180.735002 -266.422148)
			(xy 180.716276 -266.414425) (xy 180.701917 -266.400137) (xy 180.694102 -266.38145) (xy 180.693568 -266.371324)
			(xy 174.652432 -266.371324) (xy 174.651999 -266.381476) (xy 174.644201 -266.400223) (xy 174.629809 -266.414544)
			(xy 174.611024 -266.422249) (xy 174.60087 -266.422632) (xy 173.20133 -266.422632) (xy 173.191202 -266.422148)
			(xy 173.172476 -266.414425) (xy 173.158117 -266.400137) (xy 173.150302 -266.38145) (xy 173.149768 -266.371324)
			(xy 167.108632 -266.371324) (xy 167.108199 -266.381476) (xy 167.100401 -266.400223) (xy 167.086009 -266.414544)
			(xy 167.067224 -266.422249) (xy 167.05707 -266.422632) (xy 165.65753 -266.422632) (xy 165.647402 -266.422148)
			(xy 165.628676 -266.414425) (xy 165.614317 -266.400137) (xy 165.606502 -266.38145) (xy 165.605968 -266.371324)
			(xy 159.564832 -266.371324) (xy 159.564399 -266.381476) (xy 159.556601 -266.400223) (xy 159.542209 -266.414544)
			(xy 159.523424 -266.422249) (xy 159.51327 -266.422632) (xy 158.11373 -266.422632) (xy 158.103602 -266.422148)
			(xy 158.084876 -266.414425) (xy 158.070517 -266.400137) (xy 158.062702 -266.38145) (xy 158.062168 -266.371324)
			(xy 61.698632 -266.371324) (xy 61.698199 -266.381476) (xy 61.690401 -266.400223) (xy 61.676009 -266.414544)
			(xy 61.657224 -266.422249) (xy 61.64707 -266.422632) (xy 60.24753 -266.422632) (xy 60.237402 -266.422148)
			(xy 60.218676 -266.414425) (xy 60.204317 -266.400137) (xy 60.196502 -266.38145) (xy 60.195968 -266.371324)
			(xy 54.154832 -266.371324) (xy 54.154399 -266.381476) (xy 54.146601 -266.400223) (xy 54.132209 -266.414544)
			(xy 54.113424 -266.422249) (xy 54.10327 -266.422632) (xy 52.70373 -266.422632) (xy 52.693602 -266.422148)
			(xy 52.674876 -266.414425) (xy 52.660517 -266.400137) (xy 52.652702 -266.38145) (xy 52.652168 -266.371324)
			(xy 46.611032 -266.371324) (xy 46.610599 -266.381476) (xy 46.602801 -266.400223) (xy 46.588409 -266.414544)
			(xy 46.569624 -266.422249) (xy 46.55947 -266.422632) (xy 45.15993 -266.422632) (xy 45.149802 -266.422148)
			(xy 45.131076 -266.414425) (xy 45.116717 -266.400137) (xy 45.108902 -266.38145) (xy 45.108368 -266.371324)
			(xy 39.067232 -266.371324) (xy 39.066799 -266.381476) (xy 39.059001 -266.400223) (xy 39.044609 -266.414544)
			(xy 39.025824 -266.422249) (xy 39.01567 -266.422632) (xy 37.61613 -266.422632) (xy 37.606002 -266.422148)
			(xy 37.587276 -266.414425) (xy 37.572917 -266.400137) (xy 37.565102 -266.38145) (xy 37.564568 -266.371324)
			(xy 31.523432 -266.371324) (xy 31.522999 -266.381476) (xy 31.515201 -266.400223) (xy 31.500809 -266.414544)
			(xy 31.482024 -266.422249) (xy 31.47187 -266.422632) (xy 30.07233 -266.422632) (xy 30.062202 -266.422148)
			(xy 30.043476 -266.414425) (xy 30.029117 -266.400137) (xy 30.021302 -266.38145) (xy 30.020768 -266.371324)
			(xy 23.979632 -266.371324) (xy 23.979199 -266.381476) (xy 23.971401 -266.400223) (xy 23.957009 -266.414544)
			(xy 23.938224 -266.422249) (xy 23.92807 -266.422632) (xy 22.52853 -266.422632) (xy 22.518402 -266.422148)
			(xy 22.499676 -266.414425) (xy 22.485317 -266.400137) (xy 22.477502 -266.38145) (xy 22.476968 -266.371324)
			(xy 16.435832 -266.371324) (xy 16.435399 -266.381476) (xy 16.427601 -266.400223) (xy 16.413209 -266.414544)
			(xy 16.394424 -266.422249) (xy 16.38427 -266.422632) (xy 14.98473 -266.422632) (xy 14.974602 -266.422148)
			(xy 14.955876 -266.414425) (xy 14.941517 -266.400137) (xy 14.933702 -266.38145) (xy 14.933168 -266.371324)
			(xy 8.892032 -266.371324) (xy 8.891599 -266.381476) (xy 8.883801 -266.400223) (xy 8.869409 -266.414544)
			(xy 8.850624 -266.422249) (xy 8.84047 -266.422632) (xy 7.44093 -266.422632) (xy 7.430802 -266.422148)
			(xy 7.412076 -266.414425) (xy 7.397717 -266.400137) (xy 7.389902 -266.38145) (xy 7.389368 -266.371324)
			(xy 2.509012 -266.371324) (xy 2.509012 -267.221462) (xy 11.489436 -267.221462) (xy 11.489436 -266.812522)
			(xy 11.489882 -266.802352) (xy 11.497659 -266.783558) (xy 11.512038 -266.769173) (xy 11.530828 -266.761387)
			(xy 11.540998 -266.76096) (xy 12.940538 -266.76096) (xy 12.950701 -266.761403) (xy 12.969475 -266.769194)
			(xy 12.98384 -266.783575) (xy 12.991609 -266.802358) (xy 12.9921 -266.812522) (xy 12.9921 -267.221462)
			(xy 19.033236 -267.221462) (xy 19.033236 -266.812522) (xy 19.033682 -266.802352) (xy 19.041459 -266.783558)
			(xy 19.055838 -266.769173) (xy 19.074628 -266.761387) (xy 19.084798 -266.76096) (xy 20.484338 -266.76096)
			(xy 20.494501 -266.761403) (xy 20.513275 -266.769194) (xy 20.52764 -266.783575) (xy 20.535409 -266.802358)
			(xy 20.5359 -266.812522) (xy 20.5359 -267.221462) (xy 26.577036 -267.221462) (xy 26.577036 -266.812522)
			(xy 26.577482 -266.802352) (xy 26.585259 -266.783558) (xy 26.599638 -266.769173) (xy 26.618428 -266.761387)
			(xy 26.628598 -266.76096) (xy 28.028138 -266.76096) (xy 28.038301 -266.761403) (xy 28.057075 -266.769194)
			(xy 28.07144 -266.783575) (xy 28.079209 -266.802358) (xy 28.0797 -266.812522) (xy 28.0797 -267.221462)
			(xy 34.120836 -267.221462) (xy 34.120836 -266.812522) (xy 34.121282 -266.802352) (xy 34.129059 -266.783558)
			(xy 34.143438 -266.769173) (xy 34.162228 -266.761387) (xy 34.172398 -266.76096) (xy 35.571938 -266.76096)
			(xy 35.582101 -266.761403) (xy 35.600875 -266.769194) (xy 35.61524 -266.783575) (xy 35.623009 -266.802358)
			(xy 35.6235 -266.812522) (xy 35.6235 -267.221462) (xy 41.664636 -267.221462) (xy 41.664636 -266.812522)
			(xy 41.665082 -266.802352) (xy 41.672859 -266.783558) (xy 41.687238 -266.769173) (xy 41.706028 -266.761387)
			(xy 41.716198 -266.76096) (xy 43.115738 -266.76096) (xy 43.125901 -266.761403) (xy 43.144675 -266.769194)
			(xy 43.15904 -266.783575) (xy 43.166809 -266.802358) (xy 43.1673 -266.812522) (xy 43.1673 -267.221462)
			(xy 49.208436 -267.221462) (xy 49.208436 -266.812522) (xy 49.208882 -266.802352) (xy 49.216659 -266.783558)
			(xy 49.231038 -266.769173) (xy 49.249828 -266.761387) (xy 49.259998 -266.76096) (xy 50.659538 -266.76096)
			(xy 50.669701 -266.761403) (xy 50.688475 -266.769194) (xy 50.70284 -266.783575) (xy 50.710609 -266.802358)
			(xy 50.7111 -266.812522) (xy 50.7111 -267.221462) (xy 56.752236 -267.221462) (xy 56.752236 -266.812522)
			(xy 56.752682 -266.802352) (xy 56.760459 -266.783558) (xy 56.774838 -266.769173) (xy 56.793628 -266.761387)
			(xy 56.803798 -266.76096) (xy 58.203338 -266.76096) (xy 58.213501 -266.761403) (xy 58.232275 -266.769194)
			(xy 58.24664 -266.783575) (xy 58.254409 -266.802358) (xy 58.2549 -266.812522) (xy 58.2549 -267.221462)
			(xy 64.296036 -267.221462) (xy 64.296036 -266.812522) (xy 64.296482 -266.802352) (xy 64.304259 -266.783558)
			(xy 64.318638 -266.769173) (xy 64.337428 -266.761387) (xy 64.347598 -266.76096) (xy 65.747138 -266.76096)
			(xy 65.757301 -266.761403) (xy 65.776075 -266.769194) (xy 65.79044 -266.783575) (xy 65.798209 -266.802358)
			(xy 65.7987 -266.812522) (xy 65.7987 -267.221462) (xy 162.162236 -267.221462) (xy 162.162236 -266.812522)
			(xy 162.162682 -266.802352) (xy 162.170459 -266.783558) (xy 162.184838 -266.769173) (xy 162.203628 -266.761387)
			(xy 162.213798 -266.76096) (xy 163.613338 -266.76096) (xy 163.623501 -266.761403) (xy 163.642275 -266.769194)
			(xy 163.65664 -266.783575) (xy 163.664409 -266.802358) (xy 163.6649 -266.812522) (xy 163.6649 -267.221462)
			(xy 169.706036 -267.221462) (xy 169.706036 -266.812522) (xy 169.706482 -266.802352) (xy 169.714259 -266.783558)
			(xy 169.728638 -266.769173) (xy 169.747428 -266.761387) (xy 169.757598 -266.76096) (xy 171.157138 -266.76096)
			(xy 171.167301 -266.761403) (xy 171.186075 -266.769194) (xy 171.20044 -266.783575) (xy 171.208209 -266.802358)
			(xy 171.2087 -266.812522) (xy 171.2087 -267.221462) (xy 177.249836 -267.221462) (xy 177.249836 -266.812522)
			(xy 177.250282 -266.802352) (xy 177.258059 -266.783558) (xy 177.272438 -266.769173) (xy 177.291228 -266.761387)
			(xy 177.301398 -266.76096) (xy 178.700938 -266.76096) (xy 178.711101 -266.761403) (xy 178.729875 -266.769194)
			(xy 178.74424 -266.783575) (xy 178.752009 -266.802358) (xy 178.7525 -266.812522) (xy 178.7525 -267.221462)
			(xy 184.793636 -267.221462) (xy 184.793636 -266.812522) (xy 184.794082 -266.802352) (xy 184.801859 -266.783558)
			(xy 184.816238 -266.769173) (xy 184.835028 -266.761387) (xy 184.845198 -266.76096) (xy 186.244738 -266.76096)
			(xy 186.254901 -266.761403) (xy 186.273675 -266.769194) (xy 186.28804 -266.783575) (xy 186.295809 -266.802358)
			(xy 186.2963 -266.812522) (xy 186.2963 -267.221462) (xy 192.337436 -267.221462) (xy 192.337436 -266.812522)
			(xy 192.337882 -266.802352) (xy 192.345659 -266.783558) (xy 192.360038 -266.769173) (xy 192.378828 -266.761387)
			(xy 192.388998 -266.76096) (xy 193.788538 -266.76096) (xy 193.798701 -266.761403) (xy 193.817475 -266.769194)
			(xy 193.83184 -266.783575) (xy 193.839609 -266.802358) (xy 193.8401 -266.812522) (xy 193.8401 -267.221462)
			(xy 199.881236 -267.221462) (xy 199.881236 -266.812522) (xy 199.881682 -266.802352) (xy 199.889459 -266.783558)
			(xy 199.903838 -266.769173) (xy 199.922628 -266.761387) (xy 199.932798 -266.76096) (xy 201.332338 -266.76096)
			(xy 201.342501 -266.761403) (xy 201.361275 -266.769194) (xy 201.37564 -266.783575) (xy 201.383409 -266.802358)
			(xy 201.3839 -266.812522) (xy 201.3839 -267.221462) (xy 207.425036 -267.221462) (xy 207.425036 -266.812522)
			(xy 207.425482 -266.802352) (xy 207.433259 -266.783558) (xy 207.447638 -266.769173) (xy 207.466428 -266.761387)
			(xy 207.476598 -266.76096) (xy 208.876138 -266.76096) (xy 208.886301 -266.761403) (xy 208.905075 -266.769194)
			(xy 208.91944 -266.783575) (xy 208.927209 -266.802358) (xy 208.9277 -266.812522) (xy 208.9277 -267.221462)
			(xy 214.968836 -267.221462) (xy 214.968836 -266.812522) (xy 214.969282 -266.802352) (xy 214.977059 -266.783558)
			(xy 214.991438 -266.769173) (xy 215.010228 -266.761387) (xy 215.020398 -266.76096) (xy 216.419938 -266.76096)
			(xy 216.430101 -266.761403) (xy 216.448875 -266.769194) (xy 216.46324 -266.783575) (xy 216.471009 -266.802358)
			(xy 216.4715 -266.812522) (xy 216.4715 -267.221462) (xy 259.429504 -267.221462) (xy 259.429504 -266.812522)
			(xy 259.43005 -266.80237) (xy 259.437811 -266.783608) (xy 259.452161 -266.769243) (xy 259.470914 -266.761461)
			(xy 259.481066 -266.76096) (xy 260.880606 -266.76096) (xy 260.890781 -266.76136) (xy 260.90958 -266.769151)
			(xy 260.923965 -266.783544) (xy 260.931746 -266.802347) (xy 260.932168 -266.812522) (xy 260.932168 -267.221462)
			(xy 266.973304 -267.221462) (xy 266.973304 -266.812522) (xy 266.97385 -266.80237) (xy 266.981611 -266.783608)
			(xy 266.995961 -266.769243) (xy 267.014714 -266.761461) (xy 267.024866 -266.76096) (xy 268.424406 -266.76096)
			(xy 268.434581 -266.76136) (xy 268.45338 -266.769151) (xy 268.467765 -266.783544) (xy 268.475546 -266.802347)
			(xy 268.475968 -266.812522) (xy 268.475968 -267.221462) (xy 274.517104 -267.221462) (xy 274.517104 -266.812522)
			(xy 274.51765 -266.80237) (xy 274.525411 -266.783608) (xy 274.539761 -266.769243) (xy 274.558514 -266.761461)
			(xy 274.568666 -266.76096) (xy 275.968206 -266.76096) (xy 275.978381 -266.76136) (xy 275.99718 -266.769151)
			(xy 276.011565 -266.783544) (xy 276.019346 -266.802347) (xy 276.019768 -266.812522) (xy 276.019768 -267.221462)
			(xy 282.060904 -267.221462) (xy 282.060904 -266.812522) (xy 282.06145 -266.80237) (xy 282.069211 -266.783608)
			(xy 282.083561 -266.769243) (xy 282.102314 -266.761461) (xy 282.112466 -266.76096) (xy 283.512006 -266.76096)
			(xy 283.522181 -266.76136) (xy 283.54098 -266.769151) (xy 283.555365 -266.783544) (xy 283.563146 -266.802347)
			(xy 283.563568 -266.812522) (xy 283.563568 -267.221462) (xy 289.604704 -267.221462) (xy 289.604704 -266.812522)
			(xy 289.60525 -266.80237) (xy 289.613011 -266.783608) (xy 289.627361 -266.769243) (xy 289.646114 -266.761461)
			(xy 289.656266 -266.76096) (xy 291.055806 -266.76096) (xy 291.065981 -266.76136) (xy 291.08478 -266.769151)
			(xy 291.099165 -266.783544) (xy 291.106946 -266.802347) (xy 291.107368 -266.812522) (xy 291.107368 -267.221462)
			(xy 297.148504 -267.221462) (xy 297.148504 -266.812522) (xy 297.14905 -266.80237) (xy 297.156811 -266.783608)
			(xy 297.171161 -266.769243) (xy 297.189914 -266.761461) (xy 297.200066 -266.76096) (xy 298.599606 -266.76096)
			(xy 298.609781 -266.76136) (xy 298.62858 -266.769151) (xy 298.642965 -266.783544) (xy 298.650746 -266.802347)
			(xy 298.651168 -266.812522) (xy 298.651168 -267.221462) (xy 304.692304 -267.221462) (xy 304.692304 -266.812522)
			(xy 304.69285 -266.80237) (xy 304.700611 -266.783608) (xy 304.714961 -266.769243) (xy 304.733714 -266.761461)
			(xy 304.743866 -266.76096) (xy 306.143406 -266.76096) (xy 306.153581 -266.76136) (xy 306.17238 -266.769151)
			(xy 306.186765 -266.783544) (xy 306.194546 -266.802347) (xy 306.194968 -266.812522) (xy 306.194968 -267.221462)
			(xy 312.236104 -267.221462) (xy 312.236104 -266.812522) (xy 312.23665 -266.80237) (xy 312.244411 -266.783608)
			(xy 312.258761 -266.769243) (xy 312.277514 -266.761461) (xy 312.287666 -266.76096) (xy 313.687206 -266.76096)
			(xy 313.697381 -266.76136) (xy 313.71618 -266.769151) (xy 313.730565 -266.783544) (xy 313.738346 -266.802347)
			(xy 313.738768 -266.812522) (xy 313.738768 -267.221462) (xy 410.102304 -267.221462) (xy 410.102304 -266.812522)
			(xy 410.10285 -266.80237) (xy 410.110611 -266.783608) (xy 410.124961 -266.769243) (xy 410.143714 -266.761461)
			(xy 410.153866 -266.76096) (xy 411.553406 -266.76096) (xy 411.563581 -266.76136) (xy 411.58238 -266.769151)
			(xy 411.596765 -266.783544) (xy 411.604546 -266.802347) (xy 411.604968 -266.812522) (xy 411.604968 -267.221462)
			(xy 417.646104 -267.221462) (xy 417.646104 -266.812522) (xy 417.64665 -266.80237) (xy 417.654411 -266.783608)
			(xy 417.668761 -266.769243) (xy 417.687514 -266.761461) (xy 417.697666 -266.76096) (xy 419.097206 -266.76096)
			(xy 419.107381 -266.76136) (xy 419.12618 -266.769151) (xy 419.140565 -266.783544) (xy 419.148346 -266.802347)
			(xy 419.148768 -266.812522) (xy 419.148768 -267.221462) (xy 425.189904 -267.221462) (xy 425.189904 -266.812522)
			(xy 425.19045 -266.80237) (xy 425.198211 -266.783608) (xy 425.212561 -266.769243) (xy 425.231314 -266.761461)
			(xy 425.241466 -266.76096) (xy 426.641006 -266.76096) (xy 426.651181 -266.76136) (xy 426.66998 -266.769151)
			(xy 426.684365 -266.783544) (xy 426.692146 -266.802347) (xy 426.692568 -266.812522) (xy 426.692568 -267.221462)
			(xy 432.733704 -267.221462) (xy 432.733704 -266.812522) (xy 432.73425 -266.80237) (xy 432.742011 -266.783608)
			(xy 432.756361 -266.769243) (xy 432.775114 -266.761461) (xy 432.785266 -266.76096) (xy 434.184806 -266.76096)
			(xy 434.194981 -266.76136) (xy 434.21378 -266.769151) (xy 434.228165 -266.783544) (xy 434.235946 -266.802347)
			(xy 434.236368 -266.812522) (xy 434.236368 -267.221462) (xy 440.277504 -267.221462) (xy 440.277504 -266.812522)
			(xy 440.27805 -266.80237) (xy 440.285811 -266.783608) (xy 440.300161 -266.769243) (xy 440.318914 -266.761461)
			(xy 440.329066 -266.76096) (xy 441.728606 -266.76096) (xy 441.738781 -266.76136) (xy 441.75758 -266.769151)
			(xy 441.771965 -266.783544) (xy 441.779746 -266.802347) (xy 441.780168 -266.812522) (xy 441.780168 -267.221462)
			(xy 447.821304 -267.221462) (xy 447.821304 -266.812522) (xy 447.82185 -266.80237) (xy 447.829611 -266.783608)
			(xy 447.843961 -266.769243) (xy 447.862714 -266.761461) (xy 447.872866 -266.76096) (xy 449.272406 -266.76096)
			(xy 449.282581 -266.76136) (xy 449.30138 -266.769151) (xy 449.315765 -266.783544) (xy 449.323546 -266.802347)
			(xy 449.323968 -266.812522) (xy 449.323968 -267.221462) (xy 455.365104 -267.221462) (xy 455.365104 -266.812522)
			(xy 455.36565 -266.80237) (xy 455.373411 -266.783608) (xy 455.387761 -266.769243) (xy 455.406514 -266.761461)
			(xy 455.416666 -266.76096) (xy 456.816206 -266.76096) (xy 456.826381 -266.76136) (xy 456.84518 -266.769151)
			(xy 456.859565 -266.783544) (xy 456.867346 -266.802347) (xy 456.867768 -266.812522) (xy 456.867768 -267.221462)
			(xy 462.908904 -267.221462) (xy 462.908904 -266.812522) (xy 462.90945 -266.80237) (xy 462.917211 -266.783608)
			(xy 462.931561 -266.769243) (xy 462.950314 -266.761461) (xy 462.960466 -266.76096) (xy 464.360006 -266.76096)
			(xy 464.370181 -266.76136) (xy 464.38898 -266.769151) (xy 464.403365 -266.783544) (xy 464.411146 -266.802347)
			(xy 464.411568 -266.812522) (xy 464.411568 -267.221462) (xy 464.411105 -267.23163) (xy 464.403334 -267.250423)
			(xy 464.38896 -267.264809) (xy 464.370174 -267.272596) (xy 464.360006 -267.273024) (xy 462.960466 -267.273024)
			(xy 462.950287 -267.272663) (xy 462.931485 -267.26486) (xy 462.9171 -267.250455) (xy 462.909323 -267.231641)
			(xy 462.908904 -267.221462) (xy 456.867768 -267.221462) (xy 456.867305 -267.23163) (xy 456.859534 -267.250423)
			(xy 456.84516 -267.264809) (xy 456.826374 -267.272596) (xy 456.816206 -267.273024) (xy 455.416666 -267.273024)
			(xy 455.406487 -267.272663) (xy 455.387685 -267.26486) (xy 455.3733 -267.250455) (xy 455.365523 -267.231641)
			(xy 455.365104 -267.221462) (xy 449.323968 -267.221462) (xy 449.323505 -267.23163) (xy 449.315734 -267.250423)
			(xy 449.30136 -267.264809) (xy 449.282574 -267.272596) (xy 449.272406 -267.273024) (xy 447.872866 -267.273024)
			(xy 447.862687 -267.272663) (xy 447.843885 -267.26486) (xy 447.8295 -267.250455) (xy 447.821723 -267.231641)
			(xy 447.821304 -267.221462) (xy 441.780168 -267.221462) (xy 441.779705 -267.23163) (xy 441.771934 -267.250423)
			(xy 441.75756 -267.264809) (xy 441.738774 -267.272596) (xy 441.728606 -267.273024) (xy 440.329066 -267.273024)
			(xy 440.318887 -267.272663) (xy 440.300085 -267.26486) (xy 440.2857 -267.250455) (xy 440.277923 -267.231641)
			(xy 440.277504 -267.221462) (xy 434.236368 -267.221462) (xy 434.235905 -267.23163) (xy 434.228134 -267.250423)
			(xy 434.21376 -267.264809) (xy 434.194974 -267.272596) (xy 434.184806 -267.273024) (xy 432.785266 -267.273024)
			(xy 432.775087 -267.272663) (xy 432.756285 -267.26486) (xy 432.7419 -267.250455) (xy 432.734123 -267.231641)
			(xy 432.733704 -267.221462) (xy 426.692568 -267.221462) (xy 426.692105 -267.23163) (xy 426.684334 -267.250423)
			(xy 426.66996 -267.264809) (xy 426.651174 -267.272596) (xy 426.641006 -267.273024) (xy 425.241466 -267.273024)
			(xy 425.231287 -267.272663) (xy 425.212485 -267.26486) (xy 425.1981 -267.250455) (xy 425.190323 -267.231641)
			(xy 425.189904 -267.221462) (xy 419.148768 -267.221462) (xy 419.148305 -267.23163) (xy 419.140534 -267.250423)
			(xy 419.12616 -267.264809) (xy 419.107374 -267.272596) (xy 419.097206 -267.273024) (xy 417.697666 -267.273024)
			(xy 417.687487 -267.272663) (xy 417.668685 -267.26486) (xy 417.6543 -267.250455) (xy 417.646523 -267.231641)
			(xy 417.646104 -267.221462) (xy 411.604968 -267.221462) (xy 411.604505 -267.23163) (xy 411.596734 -267.250423)
			(xy 411.58236 -267.264809) (xy 411.563574 -267.272596) (xy 411.553406 -267.273024) (xy 410.153866 -267.273024)
			(xy 410.143687 -267.272663) (xy 410.124885 -267.26486) (xy 410.1105 -267.250455) (xy 410.102723 -267.231641)
			(xy 410.102304 -267.221462) (xy 313.738768 -267.221462) (xy 313.738305 -267.23163) (xy 313.730534 -267.250423)
			(xy 313.71616 -267.264809) (xy 313.697374 -267.272596) (xy 313.687206 -267.273024) (xy 312.287666 -267.273024)
			(xy 312.277487 -267.272663) (xy 312.258685 -267.26486) (xy 312.2443 -267.250455) (xy 312.236523 -267.231641)
			(xy 312.236104 -267.221462) (xy 306.194968 -267.221462) (xy 306.194505 -267.23163) (xy 306.186734 -267.250423)
			(xy 306.17236 -267.264809) (xy 306.153574 -267.272596) (xy 306.143406 -267.273024) (xy 304.743866 -267.273024)
			(xy 304.733687 -267.272663) (xy 304.714885 -267.26486) (xy 304.7005 -267.250455) (xy 304.692723 -267.231641)
			(xy 304.692304 -267.221462) (xy 298.651168 -267.221462) (xy 298.650705 -267.23163) (xy 298.642934 -267.250423)
			(xy 298.62856 -267.264809) (xy 298.609774 -267.272596) (xy 298.599606 -267.273024) (xy 297.200066 -267.273024)
			(xy 297.189887 -267.272663) (xy 297.171085 -267.26486) (xy 297.1567 -267.250455) (xy 297.148923 -267.231641)
			(xy 297.148504 -267.221462) (xy 291.107368 -267.221462) (xy 291.106905 -267.23163) (xy 291.099134 -267.250423)
			(xy 291.08476 -267.264809) (xy 291.065974 -267.272596) (xy 291.055806 -267.273024) (xy 289.656266 -267.273024)
			(xy 289.646087 -267.272663) (xy 289.627285 -267.26486) (xy 289.6129 -267.250455) (xy 289.605123 -267.231641)
			(xy 289.604704 -267.221462) (xy 283.563568 -267.221462) (xy 283.563105 -267.23163) (xy 283.555334 -267.250423)
			(xy 283.54096 -267.264809) (xy 283.522174 -267.272596) (xy 283.512006 -267.273024) (xy 282.112466 -267.273024)
			(xy 282.102287 -267.272663) (xy 282.083485 -267.26486) (xy 282.0691 -267.250455) (xy 282.061323 -267.231641)
			(xy 282.060904 -267.221462) (xy 276.019768 -267.221462) (xy 276.019305 -267.23163) (xy 276.011534 -267.250423)
			(xy 275.99716 -267.264809) (xy 275.978374 -267.272596) (xy 275.968206 -267.273024) (xy 274.568666 -267.273024)
			(xy 274.558487 -267.272663) (xy 274.539685 -267.26486) (xy 274.5253 -267.250455) (xy 274.517523 -267.231641)
			(xy 274.517104 -267.221462) (xy 268.475968 -267.221462) (xy 268.475505 -267.23163) (xy 268.467734 -267.250423)
			(xy 268.45336 -267.264809) (xy 268.434574 -267.272596) (xy 268.424406 -267.273024) (xy 267.024866 -267.273024)
			(xy 267.014687 -267.272663) (xy 266.995885 -267.26486) (xy 266.9815 -267.250455) (xy 266.973723 -267.231641)
			(xy 266.973304 -267.221462) (xy 260.932168 -267.221462) (xy 260.931705 -267.23163) (xy 260.923934 -267.250423)
			(xy 260.90956 -267.264809) (xy 260.890774 -267.272596) (xy 260.880606 -267.273024) (xy 259.481066 -267.273024)
			(xy 259.470887 -267.272663) (xy 259.452085 -267.26486) (xy 259.4377 -267.250455) (xy 259.429923 -267.231641)
			(xy 259.429504 -267.221462) (xy 216.4715 -267.221462) (xy 216.470936 -267.231613) (xy 216.463181 -267.250374)
			(xy 216.448837 -267.264739) (xy 216.430088 -267.272521) (xy 216.419938 -267.273024) (xy 215.020398 -267.273024)
			(xy 215.010222 -267.272637) (xy 214.99142 -267.264844) (xy 214.977033 -267.250447) (xy 214.969255 -267.231639)
			(xy 214.968836 -267.221462) (xy 208.9277 -267.221462) (xy 208.927136 -267.231613) (xy 208.919381 -267.250374)
			(xy 208.905037 -267.264739) (xy 208.886288 -267.272521) (xy 208.876138 -267.273024) (xy 207.476598 -267.273024)
			(xy 207.466422 -267.272637) (xy 207.44762 -267.264844) (xy 207.433233 -267.250447) (xy 207.425455 -267.231639)
			(xy 207.425036 -267.221462) (xy 201.3839 -267.221462) (xy 201.383336 -267.231613) (xy 201.375581 -267.250374)
			(xy 201.361237 -267.264739) (xy 201.342488 -267.272521) (xy 201.332338 -267.273024) (xy 199.932798 -267.273024)
			(xy 199.922622 -267.272637) (xy 199.90382 -267.264844) (xy 199.889433 -267.250447) (xy 199.881655 -267.231639)
			(xy 199.881236 -267.221462) (xy 193.8401 -267.221462) (xy 193.839536 -267.231613) (xy 193.831781 -267.250374)
			(xy 193.817437 -267.264739) (xy 193.798688 -267.272521) (xy 193.788538 -267.273024) (xy 192.388998 -267.273024)
			(xy 192.378822 -267.272637) (xy 192.36002 -267.264844) (xy 192.345633 -267.250447) (xy 192.337855 -267.231639)
			(xy 192.337436 -267.221462) (xy 186.2963 -267.221462) (xy 186.295736 -267.231613) (xy 186.287981 -267.250374)
			(xy 186.273637 -267.264739) (xy 186.254888 -267.272521) (xy 186.244738 -267.273024) (xy 184.845198 -267.273024)
			(xy 184.835022 -267.272637) (xy 184.81622 -267.264844) (xy 184.801833 -267.250447) (xy 184.794055 -267.231639)
			(xy 184.793636 -267.221462) (xy 178.7525 -267.221462) (xy 178.751936 -267.231613) (xy 178.744181 -267.250374)
			(xy 178.729837 -267.264739) (xy 178.711088 -267.272521) (xy 178.700938 -267.273024) (xy 177.301398 -267.273024)
			(xy 177.291222 -267.272637) (xy 177.27242 -267.264844) (xy 177.258033 -267.250447) (xy 177.250255 -267.231639)
			(xy 177.249836 -267.221462) (xy 171.2087 -267.221462) (xy 171.208136 -267.231613) (xy 171.200381 -267.250374)
			(xy 171.186037 -267.264739) (xy 171.167288 -267.272521) (xy 171.157138 -267.273024) (xy 169.757598 -267.273024)
			(xy 169.747422 -267.272637) (xy 169.72862 -267.264844) (xy 169.714233 -267.250447) (xy 169.706455 -267.231639)
			(xy 169.706036 -267.221462) (xy 163.6649 -267.221462) (xy 163.664336 -267.231613) (xy 163.656581 -267.250374)
			(xy 163.642237 -267.264739) (xy 163.623488 -267.272521) (xy 163.613338 -267.273024) (xy 162.213798 -267.273024)
			(xy 162.203622 -267.272637) (xy 162.18482 -267.264844) (xy 162.170433 -267.250447) (xy 162.162655 -267.231639)
			(xy 162.162236 -267.221462) (xy 65.7987 -267.221462) (xy 65.798136 -267.231613) (xy 65.790381 -267.250374)
			(xy 65.776037 -267.264739) (xy 65.757288 -267.272521) (xy 65.747138 -267.273024) (xy 64.347598 -267.273024)
			(xy 64.337422 -267.272637) (xy 64.31862 -267.264844) (xy 64.304233 -267.250447) (xy 64.296455 -267.231639)
			(xy 64.296036 -267.221462) (xy 58.2549 -267.221462) (xy 58.254336 -267.231613) (xy 58.246581 -267.250374)
			(xy 58.232237 -267.264739) (xy 58.213488 -267.272521) (xy 58.203338 -267.273024) (xy 56.803798 -267.273024)
			(xy 56.793622 -267.272637) (xy 56.77482 -267.264844) (xy 56.760433 -267.250447) (xy 56.752655 -267.231639)
			(xy 56.752236 -267.221462) (xy 50.7111 -267.221462) (xy 50.710536 -267.231613) (xy 50.702781 -267.250374)
			(xy 50.688437 -267.264739) (xy 50.669688 -267.272521) (xy 50.659538 -267.273024) (xy 49.259998 -267.273024)
			(xy 49.249822 -267.272637) (xy 49.23102 -267.264844) (xy 49.216633 -267.250447) (xy 49.208855 -267.231639)
			(xy 49.208436 -267.221462) (xy 43.1673 -267.221462) (xy 43.166736 -267.231613) (xy 43.158981 -267.250374)
			(xy 43.144637 -267.264739) (xy 43.125888 -267.272521) (xy 43.115738 -267.273024) (xy 41.716198 -267.273024)
			(xy 41.706022 -267.272637) (xy 41.68722 -267.264844) (xy 41.672833 -267.250447) (xy 41.665055 -267.231639)
			(xy 41.664636 -267.221462) (xy 35.6235 -267.221462) (xy 35.622936 -267.231613) (xy 35.615181 -267.250374)
			(xy 35.600837 -267.264739) (xy 35.582088 -267.272521) (xy 35.571938 -267.273024) (xy 34.172398 -267.273024)
			(xy 34.162222 -267.272637) (xy 34.14342 -267.264844) (xy 34.129033 -267.250447) (xy 34.121255 -267.231639)
			(xy 34.120836 -267.221462) (xy 28.0797 -267.221462) (xy 28.079136 -267.231613) (xy 28.071381 -267.250374)
			(xy 28.057037 -267.264739) (xy 28.038288 -267.272521) (xy 28.028138 -267.273024) (xy 26.628598 -267.273024)
			(xy 26.618422 -267.272637) (xy 26.59962 -267.264844) (xy 26.585233 -267.250447) (xy 26.577455 -267.231639)
			(xy 26.577036 -267.221462) (xy 20.5359 -267.221462) (xy 20.535336 -267.231613) (xy 20.527581 -267.250374)
			(xy 20.513237 -267.264739) (xy 20.494488 -267.272521) (xy 20.484338 -267.273024) (xy 19.084798 -267.273024)
			(xy 19.074622 -267.272637) (xy 19.05582 -267.264844) (xy 19.041433 -267.250447) (xy 19.033655 -267.231639)
			(xy 19.033236 -267.221462) (xy 12.9921 -267.221462) (xy 12.991536 -267.231613) (xy 12.983781 -267.250374)
			(xy 12.969437 -267.264739) (xy 12.950688 -267.272521) (xy 12.940538 -267.273024) (xy 11.540998 -267.273024)
			(xy 11.530822 -267.272637) (xy 11.51202 -267.264844) (xy 11.497633 -267.250447) (xy 11.489855 -267.231639)
			(xy 11.489436 -267.221462) (xy 2.509012 -267.221462) (xy 2.509012 -268.071346) (xy 7.389368 -268.071346)
			(xy 7.389368 -267.662406) (xy 7.389769 -267.652231) (xy 7.397558 -267.633431) (xy 7.411951 -267.619045)
			(xy 7.430755 -267.611265) (xy 7.44093 -267.610844) (xy 8.84047 -267.610844) (xy 8.85064 -267.611289)
			(xy 8.869436 -267.619065) (xy 8.883822 -267.633444) (xy 8.891607 -267.652236) (xy 8.892032 -267.662406)
			(xy 8.892032 -268.071346) (xy 14.933168 -268.071346) (xy 14.933168 -267.662406) (xy 14.933569 -267.652231)
			(xy 14.941358 -267.633431) (xy 14.955751 -267.619045) (xy 14.974555 -267.611265) (xy 14.98473 -267.610844)
			(xy 16.38427 -267.610844) (xy 16.39444 -267.611289) (xy 16.413236 -267.619065) (xy 16.427622 -267.633444)
			(xy 16.435407 -267.652236) (xy 16.435832 -267.662406) (xy 16.435832 -268.071346) (xy 22.476968 -268.071346)
			(xy 22.476968 -267.662406) (xy 22.477369 -267.652231) (xy 22.485158 -267.633431) (xy 22.499551 -267.619045)
			(xy 22.518355 -267.611265) (xy 22.52853 -267.610844) (xy 23.92807 -267.610844) (xy 23.93824 -267.611289)
			(xy 23.957036 -267.619065) (xy 23.971422 -267.633444) (xy 23.979207 -267.652236) (xy 23.979632 -267.662406)
			(xy 23.979632 -268.071346) (xy 30.020768 -268.071346) (xy 30.020768 -267.662406) (xy 30.021169 -267.652231)
			(xy 30.028958 -267.633431) (xy 30.043351 -267.619045) (xy 30.062155 -267.611265) (xy 30.07233 -267.610844)
			(xy 31.47187 -267.610844) (xy 31.48204 -267.611289) (xy 31.500836 -267.619065) (xy 31.515222 -267.633444)
			(xy 31.523007 -267.652236) (xy 31.523432 -267.662406) (xy 31.523432 -268.071346) (xy 37.564568 -268.071346)
			(xy 37.564568 -267.662406) (xy 37.564969 -267.652231) (xy 37.572758 -267.633431) (xy 37.587151 -267.619045)
			(xy 37.605955 -267.611265) (xy 37.61613 -267.610844) (xy 39.01567 -267.610844) (xy 39.02584 -267.611289)
			(xy 39.044636 -267.619065) (xy 39.059022 -267.633444) (xy 39.066807 -267.652236) (xy 39.067232 -267.662406)
			(xy 39.067232 -268.071346) (xy 45.108368 -268.071346) (xy 45.108368 -267.662406) (xy 45.108769 -267.652231)
			(xy 45.116558 -267.633431) (xy 45.130951 -267.619045) (xy 45.149755 -267.611265) (xy 45.15993 -267.610844)
			(xy 46.55947 -267.610844) (xy 46.56964 -267.611289) (xy 46.588436 -267.619065) (xy 46.602822 -267.633444)
			(xy 46.610607 -267.652236) (xy 46.611032 -267.662406) (xy 46.611032 -268.071346) (xy 52.652168 -268.071346)
			(xy 52.652168 -267.662406) (xy 52.652569 -267.652231) (xy 52.660358 -267.633431) (xy 52.674751 -267.619045)
			(xy 52.693555 -267.611265) (xy 52.70373 -267.610844) (xy 54.10327 -267.610844) (xy 54.11344 -267.611289)
			(xy 54.132236 -267.619065) (xy 54.146622 -267.633444) (xy 54.154407 -267.652236) (xy 54.154832 -267.662406)
			(xy 54.154832 -268.071346) (xy 60.195968 -268.071346) (xy 60.195968 -267.662406) (xy 60.196369 -267.652231)
			(xy 60.204158 -267.633431) (xy 60.218551 -267.619045) (xy 60.237355 -267.611265) (xy 60.24753 -267.610844)
			(xy 61.64707 -267.610844) (xy 61.65724 -267.611289) (xy 61.676036 -267.619065) (xy 61.690422 -267.633444)
			(xy 61.698207 -267.652236) (xy 61.698632 -267.662406) (xy 61.698632 -268.071346) (xy 158.062168 -268.071346)
			(xy 158.062168 -267.662406) (xy 158.062569 -267.652231) (xy 158.070358 -267.633431) (xy 158.084751 -267.619045)
			(xy 158.103555 -267.611265) (xy 158.11373 -267.610844) (xy 159.51327 -267.610844) (xy 159.52344 -267.611289)
			(xy 159.542236 -267.619065) (xy 159.556622 -267.633444) (xy 159.564407 -267.652236) (xy 159.564832 -267.662406)
			(xy 159.564832 -268.071346) (xy 165.605968 -268.071346) (xy 165.605968 -267.662406) (xy 165.606369 -267.652231)
			(xy 165.614158 -267.633431) (xy 165.628551 -267.619045) (xy 165.647355 -267.611265) (xy 165.65753 -267.610844)
			(xy 167.05707 -267.610844) (xy 167.06724 -267.611289) (xy 167.086036 -267.619065) (xy 167.100422 -267.633444)
			(xy 167.108207 -267.652236) (xy 167.108632 -267.662406) (xy 167.108632 -268.071346) (xy 173.149768 -268.071346)
			(xy 173.149768 -267.662406) (xy 173.150169 -267.652231) (xy 173.157958 -267.633431) (xy 173.172351 -267.619045)
			(xy 173.191155 -267.611265) (xy 173.20133 -267.610844) (xy 174.60087 -267.610844) (xy 174.61104 -267.611289)
			(xy 174.629836 -267.619065) (xy 174.644222 -267.633444) (xy 174.652007 -267.652236) (xy 174.652432 -267.662406)
			(xy 174.652432 -268.071346) (xy 180.693568 -268.071346) (xy 180.693568 -267.662406) (xy 180.693969 -267.652231)
			(xy 180.701758 -267.633431) (xy 180.716151 -267.619045) (xy 180.734955 -267.611265) (xy 180.74513 -267.610844)
			(xy 182.14467 -267.610844) (xy 182.15484 -267.611289) (xy 182.173636 -267.619065) (xy 182.188022 -267.633444)
			(xy 182.195807 -267.652236) (xy 182.196232 -267.662406) (xy 182.196232 -268.071346) (xy 188.237368 -268.071346)
			(xy 188.237368 -267.662406) (xy 188.237769 -267.652231) (xy 188.245558 -267.633431) (xy 188.259951 -267.619045)
			(xy 188.278755 -267.611265) (xy 188.28893 -267.610844) (xy 189.68847 -267.610844) (xy 189.69864 -267.611289)
			(xy 189.717436 -267.619065) (xy 189.731822 -267.633444) (xy 189.739607 -267.652236) (xy 189.740032 -267.662406)
			(xy 189.740032 -268.071346) (xy 195.781168 -268.071346) (xy 195.781168 -267.662406) (xy 195.781569 -267.652231)
			(xy 195.789358 -267.633431) (xy 195.803751 -267.619045) (xy 195.822555 -267.611265) (xy 195.83273 -267.610844)
			(xy 197.23227 -267.610844) (xy 197.24244 -267.611289) (xy 197.261236 -267.619065) (xy 197.275622 -267.633444)
			(xy 197.283407 -267.652236) (xy 197.283832 -267.662406) (xy 197.283832 -268.071346) (xy 203.324968 -268.071346)
			(xy 203.324968 -267.662406) (xy 203.325369 -267.652231) (xy 203.333158 -267.633431) (xy 203.347551 -267.619045)
			(xy 203.366355 -267.611265) (xy 203.37653 -267.610844) (xy 204.77607 -267.610844) (xy 204.78624 -267.611289)
			(xy 204.805036 -267.619065) (xy 204.819422 -267.633444) (xy 204.827207 -267.652236) (xy 204.827632 -267.662406)
			(xy 204.827632 -268.071346) (xy 210.868768 -268.071346) (xy 210.868768 -267.662406) (xy 210.869169 -267.652231)
			(xy 210.876958 -267.633431) (xy 210.891351 -267.619045) (xy 210.910155 -267.611265) (xy 210.92033 -267.610844)
			(xy 212.31987 -267.610844) (xy 212.33004 -267.611289) (xy 212.348836 -267.619065) (xy 212.363222 -267.633444)
			(xy 212.371007 -267.652236) (xy 212.371432 -267.662406) (xy 212.371432 -268.071346) (xy 255.329436 -268.071346)
			(xy 255.329436 -267.662406) (xy 255.329869 -267.652235) (xy 255.337651 -267.633441) (xy 255.352034 -267.619056)
			(xy 255.370827 -267.61127) (xy 255.380998 -267.610844) (xy 256.780538 -267.610844) (xy 256.790699 -267.611302)
			(xy 256.80947 -267.61909) (xy 256.823834 -267.633467) (xy 256.831606 -267.652245) (xy 256.8321 -267.662406)
			(xy 256.8321 -268.071346) (xy 262.873236 -268.071346) (xy 262.873236 -267.662406) (xy 262.873669 -267.652235)
			(xy 262.881451 -267.633441) (xy 262.895834 -267.619056) (xy 262.914627 -267.61127) (xy 262.924798 -267.610844)
			(xy 264.324338 -267.610844) (xy 264.334499 -267.611302) (xy 264.35327 -267.61909) (xy 264.367634 -267.633467)
			(xy 264.375406 -267.652245) (xy 264.3759 -267.662406) (xy 264.3759 -268.071346) (xy 270.417036 -268.071346)
			(xy 270.417036 -267.662406) (xy 270.417469 -267.652235) (xy 270.425251 -267.633441) (xy 270.439634 -267.619056)
			(xy 270.458427 -267.61127) (xy 270.468598 -267.610844) (xy 271.868138 -267.610844) (xy 271.878299 -267.611302)
			(xy 271.89707 -267.61909) (xy 271.911434 -267.633467) (xy 271.919206 -267.652245) (xy 271.9197 -267.662406)
			(xy 271.9197 -268.071346) (xy 277.960836 -268.071346) (xy 277.960836 -267.662406) (xy 277.961269 -267.652235)
			(xy 277.969051 -267.633441) (xy 277.983434 -267.619056) (xy 278.002227 -267.61127) (xy 278.012398 -267.610844)
			(xy 279.411938 -267.610844) (xy 279.422099 -267.611302) (xy 279.44087 -267.61909) (xy 279.455234 -267.633467)
			(xy 279.463006 -267.652245) (xy 279.4635 -267.662406) (xy 279.4635 -268.071346) (xy 285.504636 -268.071346)
			(xy 285.504636 -267.662406) (xy 285.505069 -267.652235) (xy 285.512851 -267.633441) (xy 285.527234 -267.619056)
			(xy 285.546027 -267.61127) (xy 285.556198 -267.610844) (xy 286.955738 -267.610844) (xy 286.965899 -267.611302)
			(xy 286.98467 -267.61909) (xy 286.999034 -267.633467) (xy 287.006806 -267.652245) (xy 287.0073 -267.662406)
			(xy 287.0073 -268.071346) (xy 293.048436 -268.071346) (xy 293.048436 -267.662406) (xy 293.048869 -267.652235)
			(xy 293.056651 -267.633441) (xy 293.071034 -267.619056) (xy 293.089827 -267.61127) (xy 293.099998 -267.610844)
			(xy 294.499538 -267.610844) (xy 294.509699 -267.611302) (xy 294.52847 -267.61909) (xy 294.542834 -267.633467)
			(xy 294.550606 -267.652245) (xy 294.5511 -267.662406) (xy 294.5511 -268.071346) (xy 300.592236 -268.071346)
			(xy 300.592236 -267.662406) (xy 300.592669 -267.652235) (xy 300.600451 -267.633441) (xy 300.614834 -267.619056)
			(xy 300.633627 -267.61127) (xy 300.643798 -267.610844) (xy 302.043338 -267.610844) (xy 302.053499 -267.611302)
			(xy 302.07227 -267.61909) (xy 302.086634 -267.633467) (xy 302.094406 -267.652245) (xy 302.0949 -267.662406)
			(xy 302.0949 -268.071346) (xy 308.136036 -268.071346) (xy 308.136036 -267.662406) (xy 308.136469 -267.652235)
			(xy 308.144251 -267.633441) (xy 308.158634 -267.619056) (xy 308.177427 -267.61127) (xy 308.187598 -267.610844)
			(xy 309.587138 -267.610844) (xy 309.597299 -267.611302) (xy 309.61607 -267.61909) (xy 309.630434 -267.633467)
			(xy 309.638206 -267.652245) (xy 309.6387 -267.662406) (xy 309.6387 -268.071346) (xy 406.002236 -268.071346)
			(xy 406.002236 -267.662406) (xy 406.002669 -267.652235) (xy 406.010451 -267.633441) (xy 406.024834 -267.619056)
			(xy 406.043627 -267.61127) (xy 406.053798 -267.610844) (xy 407.453338 -267.610844) (xy 407.463499 -267.611302)
			(xy 407.48227 -267.61909) (xy 407.496634 -267.633467) (xy 407.504406 -267.652245) (xy 407.5049 -267.662406)
			(xy 407.5049 -268.071346) (xy 413.546036 -268.071346) (xy 413.546036 -267.662406) (xy 413.546469 -267.652235)
			(xy 413.554251 -267.633441) (xy 413.568634 -267.619056) (xy 413.587427 -267.61127) (xy 413.597598 -267.610844)
			(xy 414.997138 -267.610844) (xy 415.007299 -267.611302) (xy 415.02607 -267.61909) (xy 415.040434 -267.633467)
			(xy 415.048206 -267.652245) (xy 415.0487 -267.662406) (xy 415.0487 -268.071346) (xy 421.089836 -268.071346)
			(xy 421.089836 -267.662406) (xy 421.090269 -267.652235) (xy 421.098051 -267.633441) (xy 421.112434 -267.619056)
			(xy 421.131227 -267.61127) (xy 421.141398 -267.610844) (xy 422.540938 -267.610844) (xy 422.551099 -267.611302)
			(xy 422.56987 -267.61909) (xy 422.584234 -267.633467) (xy 422.592006 -267.652245) (xy 422.5925 -267.662406)
			(xy 422.5925 -268.071346) (xy 428.633636 -268.071346) (xy 428.633636 -267.662406) (xy 428.634069 -267.652235)
			(xy 428.641851 -267.633441) (xy 428.656234 -267.619056) (xy 428.675027 -267.61127) (xy 428.685198 -267.610844)
			(xy 430.084738 -267.610844) (xy 430.094899 -267.611302) (xy 430.11367 -267.61909) (xy 430.128034 -267.633467)
			(xy 430.135806 -267.652245) (xy 430.1363 -267.662406) (xy 430.1363 -268.071346) (xy 436.177436 -268.071346)
			(xy 436.177436 -267.662406) (xy 436.177869 -267.652235) (xy 436.185651 -267.633441) (xy 436.200034 -267.619056)
			(xy 436.218827 -267.61127) (xy 436.228998 -267.610844) (xy 437.628538 -267.610844) (xy 437.638699 -267.611302)
			(xy 437.65747 -267.61909) (xy 437.671834 -267.633467) (xy 437.679606 -267.652245) (xy 437.6801 -267.662406)
			(xy 437.6801 -268.071346) (xy 443.721236 -268.071346) (xy 443.721236 -267.662406) (xy 443.721669 -267.652235)
			(xy 443.729451 -267.633441) (xy 443.743834 -267.619056) (xy 443.762627 -267.61127) (xy 443.772798 -267.610844)
			(xy 445.172338 -267.610844) (xy 445.182499 -267.611302) (xy 445.20127 -267.61909) (xy 445.215634 -267.633467)
			(xy 445.223406 -267.652245) (xy 445.2239 -267.662406) (xy 445.2239 -268.071346) (xy 451.265036 -268.071346)
			(xy 451.265036 -267.662406) (xy 451.265469 -267.652235) (xy 451.273251 -267.633441) (xy 451.287634 -267.619056)
			(xy 451.306427 -267.61127) (xy 451.316598 -267.610844) (xy 452.716138 -267.610844) (xy 452.726299 -267.611302)
			(xy 452.74507 -267.61909) (xy 452.759434 -267.633467) (xy 452.767206 -267.652245) (xy 452.7677 -267.662406)
			(xy 452.7677 -268.071346) (xy 458.808836 -268.071346) (xy 458.808836 -267.662406) (xy 458.809269 -267.652235)
			(xy 458.817051 -267.633441) (xy 458.831434 -267.619056) (xy 458.850227 -267.61127) (xy 458.860398 -267.610844)
			(xy 460.259938 -267.610844) (xy 460.270099 -267.611302) (xy 460.28887 -267.61909) (xy 460.303234 -267.633467)
			(xy 460.311006 -267.652245) (xy 460.3115 -267.662406) (xy 460.3115 -268.071346) (xy 460.311005 -268.081502)
			(xy 460.303223 -268.100265) (xy 460.288858 -268.114627) (xy 460.270094 -268.122407) (xy 460.259938 -268.122908)
			(xy 458.860398 -268.122908) (xy 458.850246 -268.122369) (xy 458.831485 -268.114603) (xy 458.817122 -268.100252)
			(xy 458.809339 -268.081498) (xy 458.808836 -268.071346) (xy 452.7677 -268.071346) (xy 452.767205 -268.081502)
			(xy 452.759423 -268.100265) (xy 452.745058 -268.114627) (xy 452.726294 -268.122407) (xy 452.716138 -268.122908)
			(xy 451.316598 -268.122908) (xy 451.306446 -268.122369) (xy 451.287685 -268.114603) (xy 451.273322 -268.100252)
			(xy 451.265539 -268.081498) (xy 451.265036 -268.071346) (xy 445.2239 -268.071346) (xy 445.223405 -268.081502)
			(xy 445.215623 -268.100265) (xy 445.201258 -268.114627) (xy 445.182494 -268.122407) (xy 445.172338 -268.122908)
			(xy 443.772798 -268.122908) (xy 443.762646 -268.122369) (xy 443.743885 -268.114603) (xy 443.729522 -268.100252)
			(xy 443.721739 -268.081498) (xy 443.721236 -268.071346) (xy 437.6801 -268.071346) (xy 437.679605 -268.081502)
			(xy 437.671823 -268.100265) (xy 437.657458 -268.114627) (xy 437.638694 -268.122407) (xy 437.628538 -268.122908)
			(xy 436.228998 -268.122908) (xy 436.218846 -268.122369) (xy 436.200085 -268.114603) (xy 436.185722 -268.100252)
			(xy 436.177939 -268.081498) (xy 436.177436 -268.071346) (xy 430.1363 -268.071346) (xy 430.135805 -268.081502)
			(xy 430.128023 -268.100265) (xy 430.113658 -268.114627) (xy 430.094894 -268.122407) (xy 430.084738 -268.122908)
			(xy 428.685198 -268.122908) (xy 428.675046 -268.122369) (xy 428.656285 -268.114603) (xy 428.641922 -268.100252)
			(xy 428.634139 -268.081498) (xy 428.633636 -268.071346) (xy 422.5925 -268.071346) (xy 422.592005 -268.081502)
			(xy 422.584223 -268.100265) (xy 422.569858 -268.114627) (xy 422.551094 -268.122407) (xy 422.540938 -268.122908)
			(xy 421.141398 -268.122908) (xy 421.131246 -268.122369) (xy 421.112485 -268.114603) (xy 421.098122 -268.100252)
			(xy 421.090339 -268.081498) (xy 421.089836 -268.071346) (xy 415.0487 -268.071346) (xy 415.048205 -268.081502)
			(xy 415.040423 -268.100265) (xy 415.026058 -268.114627) (xy 415.007294 -268.122407) (xy 414.997138 -268.122908)
			(xy 413.597598 -268.122908) (xy 413.587446 -268.122369) (xy 413.568685 -268.114603) (xy 413.554322 -268.100252)
			(xy 413.546539 -268.081498) (xy 413.546036 -268.071346) (xy 407.5049 -268.071346) (xy 407.504405 -268.081502)
			(xy 407.496623 -268.100265) (xy 407.482258 -268.114627) (xy 407.463494 -268.122407) (xy 407.453338 -268.122908)
			(xy 406.053798 -268.122908) (xy 406.043646 -268.122369) (xy 406.024885 -268.114603) (xy 406.010522 -268.100252)
			(xy 406.002739 -268.081498) (xy 406.002236 -268.071346) (xy 309.6387 -268.071346) (xy 309.638205 -268.081502)
			(xy 309.630423 -268.100265) (xy 309.616058 -268.114627) (xy 309.597294 -268.122407) (xy 309.587138 -268.122908)
			(xy 308.187598 -268.122908) (xy 308.177446 -268.122369) (xy 308.158685 -268.114603) (xy 308.144322 -268.100252)
			(xy 308.136539 -268.081498) (xy 308.136036 -268.071346) (xy 302.0949 -268.071346) (xy 302.094405 -268.081502)
			(xy 302.086623 -268.100265) (xy 302.072258 -268.114627) (xy 302.053494 -268.122407) (xy 302.043338 -268.122908)
			(xy 300.643798 -268.122908) (xy 300.633646 -268.122369) (xy 300.614885 -268.114603) (xy 300.600522 -268.100252)
			(xy 300.592739 -268.081498) (xy 300.592236 -268.071346) (xy 294.5511 -268.071346) (xy 294.550605 -268.081502)
			(xy 294.542823 -268.100265) (xy 294.528458 -268.114627) (xy 294.509694 -268.122407) (xy 294.499538 -268.122908)
			(xy 293.099998 -268.122908) (xy 293.089846 -268.122369) (xy 293.071085 -268.114603) (xy 293.056722 -268.100252)
			(xy 293.048939 -268.081498) (xy 293.048436 -268.071346) (xy 287.0073 -268.071346) (xy 287.006805 -268.081502)
			(xy 286.999023 -268.100265) (xy 286.984658 -268.114627) (xy 286.965894 -268.122407) (xy 286.955738 -268.122908)
			(xy 285.556198 -268.122908) (xy 285.546046 -268.122369) (xy 285.527285 -268.114603) (xy 285.512922 -268.100252)
			(xy 285.505139 -268.081498) (xy 285.504636 -268.071346) (xy 279.4635 -268.071346) (xy 279.463005 -268.081502)
			(xy 279.455223 -268.100265) (xy 279.440858 -268.114627) (xy 279.422094 -268.122407) (xy 279.411938 -268.122908)
			(xy 278.012398 -268.122908) (xy 278.002246 -268.122369) (xy 277.983485 -268.114603) (xy 277.969122 -268.100252)
			(xy 277.961339 -268.081498) (xy 277.960836 -268.071346) (xy 271.9197 -268.071346) (xy 271.919205 -268.081502)
			(xy 271.911423 -268.100265) (xy 271.897058 -268.114627) (xy 271.878294 -268.122407) (xy 271.868138 -268.122908)
			(xy 270.468598 -268.122908) (xy 270.458446 -268.122369) (xy 270.439685 -268.114603) (xy 270.425322 -268.100252)
			(xy 270.417539 -268.081498) (xy 270.417036 -268.071346) (xy 264.3759 -268.071346) (xy 264.375405 -268.081502)
			(xy 264.367623 -268.100265) (xy 264.353258 -268.114627) (xy 264.334494 -268.122407) (xy 264.324338 -268.122908)
			(xy 262.924798 -268.122908) (xy 262.914646 -268.122369) (xy 262.895885 -268.114603) (xy 262.881522 -268.100252)
			(xy 262.873739 -268.081498) (xy 262.873236 -268.071346) (xy 256.8321 -268.071346) (xy 256.831605 -268.081502)
			(xy 256.823823 -268.100265) (xy 256.809458 -268.114627) (xy 256.790694 -268.122407) (xy 256.780538 -268.122908)
			(xy 255.380998 -268.122908) (xy 255.370846 -268.122369) (xy 255.352085 -268.114603) (xy 255.337722 -268.100252)
			(xy 255.329939 -268.081498) (xy 255.329436 -268.071346) (xy 212.371432 -268.071346) (xy 212.371003 -268.08151)
			(xy 212.363208 -268.100286) (xy 212.348822 -268.114651) (xy 212.330035 -268.122418) (xy 212.31987 -268.122908)
			(xy 210.92033 -268.122908) (xy 210.91018 -268.122343) (xy 210.89142 -268.114587) (xy 210.877055 -268.100244)
			(xy 210.869272 -268.081495) (xy 210.868768 -268.071346) (xy 204.827632 -268.071346) (xy 204.827203 -268.08151)
			(xy 204.819408 -268.100286) (xy 204.805022 -268.114651) (xy 204.786235 -268.122418) (xy 204.77607 -268.122908)
			(xy 203.37653 -268.122908) (xy 203.36638 -268.122343) (xy 203.34762 -268.114587) (xy 203.333255 -268.100244)
			(xy 203.325472 -268.081495) (xy 203.324968 -268.071346) (xy 197.283832 -268.071346) (xy 197.283403 -268.08151)
			(xy 197.275608 -268.100286) (xy 197.261222 -268.114651) (xy 197.242435 -268.122418) (xy 197.23227 -268.122908)
			(xy 195.83273 -268.122908) (xy 195.82258 -268.122343) (xy 195.80382 -268.114587) (xy 195.789455 -268.100244)
			(xy 195.781672 -268.081495) (xy 195.781168 -268.071346) (xy 189.740032 -268.071346) (xy 189.739603 -268.08151)
			(xy 189.731808 -268.100286) (xy 189.717422 -268.114651) (xy 189.698635 -268.122418) (xy 189.68847 -268.122908)
			(xy 188.28893 -268.122908) (xy 188.27878 -268.122343) (xy 188.26002 -268.114587) (xy 188.245655 -268.100244)
			(xy 188.237872 -268.081495) (xy 188.237368 -268.071346) (xy 182.196232 -268.071346) (xy 182.195803 -268.08151)
			(xy 182.188008 -268.100286) (xy 182.173622 -268.114651) (xy 182.154835 -268.122418) (xy 182.14467 -268.122908)
			(xy 180.74513 -268.122908) (xy 180.73498 -268.122343) (xy 180.71622 -268.114587) (xy 180.701855 -268.100244)
			(xy 180.694072 -268.081495) (xy 180.693568 -268.071346) (xy 174.652432 -268.071346) (xy 174.652003 -268.08151)
			(xy 174.644208 -268.100286) (xy 174.629822 -268.114651) (xy 174.611035 -268.122418) (xy 174.60087 -268.122908)
			(xy 173.20133 -268.122908) (xy 173.19118 -268.122343) (xy 173.17242 -268.114587) (xy 173.158055 -268.100244)
			(xy 173.150272 -268.081495) (xy 173.149768 -268.071346) (xy 167.108632 -268.071346) (xy 167.108203 -268.08151)
			(xy 167.100408 -268.100286) (xy 167.086022 -268.114651) (xy 167.067235 -268.122418) (xy 167.05707 -268.122908)
			(xy 165.65753 -268.122908) (xy 165.64738 -268.122343) (xy 165.62862 -268.114587) (xy 165.614255 -268.100244)
			(xy 165.606472 -268.081495) (xy 165.605968 -268.071346) (xy 159.564832 -268.071346) (xy 159.564403 -268.08151)
			(xy 159.556608 -268.100286) (xy 159.542222 -268.114651) (xy 159.523435 -268.122418) (xy 159.51327 -268.122908)
			(xy 158.11373 -268.122908) (xy 158.10358 -268.122343) (xy 158.08482 -268.114587) (xy 158.070455 -268.100244)
			(xy 158.062672 -268.081495) (xy 158.062168 -268.071346) (xy 61.698632 -268.071346) (xy 61.698203 -268.08151)
			(xy 61.690408 -268.100286) (xy 61.676022 -268.114651) (xy 61.657235 -268.122418) (xy 61.64707 -268.122908)
			(xy 60.24753 -268.122908) (xy 60.23738 -268.122343) (xy 60.21862 -268.114587) (xy 60.204255 -268.100244)
			(xy 60.196472 -268.081495) (xy 60.195968 -268.071346) (xy 54.154832 -268.071346) (xy 54.154403 -268.08151)
			(xy 54.146608 -268.100286) (xy 54.132222 -268.114651) (xy 54.113435 -268.122418) (xy 54.10327 -268.122908)
			(xy 52.70373 -268.122908) (xy 52.69358 -268.122343) (xy 52.67482 -268.114587) (xy 52.660455 -268.100244)
			(xy 52.652672 -268.081495) (xy 52.652168 -268.071346) (xy 46.611032 -268.071346) (xy 46.610603 -268.08151)
			(xy 46.602808 -268.100286) (xy 46.588422 -268.114651) (xy 46.569635 -268.122418) (xy 46.55947 -268.122908)
			(xy 45.15993 -268.122908) (xy 45.14978 -268.122343) (xy 45.13102 -268.114587) (xy 45.116655 -268.100244)
			(xy 45.108872 -268.081495) (xy 45.108368 -268.071346) (xy 39.067232 -268.071346) (xy 39.066803 -268.08151)
			(xy 39.059008 -268.100286) (xy 39.044622 -268.114651) (xy 39.025835 -268.122418) (xy 39.01567 -268.122908)
			(xy 37.61613 -268.122908) (xy 37.60598 -268.122343) (xy 37.58722 -268.114587) (xy 37.572855 -268.100244)
			(xy 37.565072 -268.081495) (xy 37.564568 -268.071346) (xy 31.523432 -268.071346) (xy 31.523003 -268.08151)
			(xy 31.515208 -268.100286) (xy 31.500822 -268.114651) (xy 31.482035 -268.122418) (xy 31.47187 -268.122908)
			(xy 30.07233 -268.122908) (xy 30.06218 -268.122343) (xy 30.04342 -268.114587) (xy 30.029055 -268.100244)
			(xy 30.021272 -268.081495) (xy 30.020768 -268.071346) (xy 23.979632 -268.071346) (xy 23.979203 -268.08151)
			(xy 23.971408 -268.100286) (xy 23.957022 -268.114651) (xy 23.938235 -268.122418) (xy 23.92807 -268.122908)
			(xy 22.52853 -268.122908) (xy 22.51838 -268.122343) (xy 22.49962 -268.114587) (xy 22.485255 -268.100244)
			(xy 22.477472 -268.081495) (xy 22.476968 -268.071346) (xy 16.435832 -268.071346) (xy 16.435403 -268.08151)
			(xy 16.427608 -268.100286) (xy 16.413222 -268.114651) (xy 16.394435 -268.122418) (xy 16.38427 -268.122908)
			(xy 14.98473 -268.122908) (xy 14.97458 -268.122343) (xy 14.95582 -268.114587) (xy 14.941455 -268.100244)
			(xy 14.933672 -268.081495) (xy 14.933168 -268.071346) (xy 8.892032 -268.071346) (xy 8.891603 -268.08151)
			(xy 8.883808 -268.100286) (xy 8.869422 -268.114651) (xy 8.850635 -268.122418) (xy 8.84047 -268.122908)
			(xy 7.44093 -268.122908) (xy 7.43078 -268.122343) (xy 7.41202 -268.114587) (xy 7.397655 -268.100244)
			(xy 7.389872 -268.081495) (xy 7.389368 -268.071346) (xy 2.509012 -268.071346) (xy 2.509012 -268.921484)
			(xy 11.489436 -268.921484) (xy 11.489436 -268.512544) (xy 11.489858 -268.502388) (xy 11.497646 -268.48363)
			(xy 11.512044 -268.469304) (xy 11.53084 -268.461609) (xy 11.540998 -268.461236) (xy 12.940538 -268.461236)
			(xy 12.950667 -268.461695) (xy 12.969388 -268.469435) (xy 12.983743 -268.483729) (xy 12.991561 -268.502418)
			(xy 12.9921 -268.512544) (xy 12.9921 -268.921484) (xy 19.033236 -268.921484) (xy 19.033236 -268.512544)
			(xy 19.033658 -268.502388) (xy 19.041446 -268.48363) (xy 19.055844 -268.469304) (xy 19.07464 -268.461609)
			(xy 19.084798 -268.461236) (xy 20.484338 -268.461236) (xy 20.494467 -268.461695) (xy 20.513188 -268.469435)
			(xy 20.527543 -268.483729) (xy 20.535361 -268.502418) (xy 20.5359 -268.512544) (xy 20.5359 -268.921484)
			(xy 26.577036 -268.921484) (xy 26.577036 -268.512544) (xy 26.577458 -268.502388) (xy 26.585246 -268.48363)
			(xy 26.599644 -268.469304) (xy 26.61844 -268.461609) (xy 26.628598 -268.461236) (xy 28.028138 -268.461236)
			(xy 28.038267 -268.461695) (xy 28.056988 -268.469435) (xy 28.071343 -268.483729) (xy 28.079161 -268.502418)
			(xy 28.0797 -268.512544) (xy 28.0797 -268.921484) (xy 34.120836 -268.921484) (xy 34.120836 -268.512544)
			(xy 34.121258 -268.502388) (xy 34.129046 -268.48363) (xy 34.143444 -268.469304) (xy 34.16224 -268.461609)
			(xy 34.172398 -268.461236) (xy 35.571938 -268.461236) (xy 35.582067 -268.461695) (xy 35.600788 -268.469435)
			(xy 35.615143 -268.483729) (xy 35.622961 -268.502418) (xy 35.6235 -268.512544) (xy 35.6235 -268.921484)
			(xy 41.664636 -268.921484) (xy 41.664636 -268.512544) (xy 41.665058 -268.502388) (xy 41.672846 -268.48363)
			(xy 41.687244 -268.469304) (xy 41.70604 -268.461609) (xy 41.716198 -268.461236) (xy 43.115738 -268.461236)
			(xy 43.125867 -268.461695) (xy 43.144588 -268.469435) (xy 43.158943 -268.483729) (xy 43.166761 -268.502418)
			(xy 43.1673 -268.512544) (xy 43.1673 -268.921484) (xy 49.208436 -268.921484) (xy 49.208436 -268.512544)
			(xy 49.208858 -268.502388) (xy 49.216646 -268.48363) (xy 49.231044 -268.469304) (xy 49.24984 -268.461609)
			(xy 49.259998 -268.461236) (xy 50.659538 -268.461236) (xy 50.669667 -268.461695) (xy 50.688388 -268.469435)
			(xy 50.702743 -268.483729) (xy 50.710561 -268.502418) (xy 50.7111 -268.512544) (xy 50.7111 -268.921484)
			(xy 56.752236 -268.921484) (xy 56.752236 -268.512544) (xy 56.752658 -268.502388) (xy 56.760446 -268.48363)
			(xy 56.774844 -268.469304) (xy 56.79364 -268.461609) (xy 56.803798 -268.461236) (xy 58.203338 -268.461236)
			(xy 58.213467 -268.461695) (xy 58.232188 -268.469435) (xy 58.246543 -268.483729) (xy 58.254361 -268.502418)
			(xy 58.2549 -268.512544) (xy 58.2549 -268.921484) (xy 64.296036 -268.921484) (xy 64.296036 -268.512544)
			(xy 64.296458 -268.502388) (xy 64.304246 -268.48363) (xy 64.318644 -268.469304) (xy 64.33744 -268.461609)
			(xy 64.347598 -268.461236) (xy 65.747138 -268.461236) (xy 65.757267 -268.461695) (xy 65.775988 -268.469435)
			(xy 65.790343 -268.483729) (xy 65.798161 -268.502418) (xy 65.7987 -268.512544) (xy 65.7987 -268.921484)
			(xy 162.162236 -268.921484) (xy 162.162236 -268.512544) (xy 162.162658 -268.502388) (xy 162.170446 -268.48363)
			(xy 162.184844 -268.469304) (xy 162.20364 -268.461609) (xy 162.213798 -268.461236) (xy 163.613338 -268.461236)
			(xy 163.623467 -268.461695) (xy 163.642188 -268.469435) (xy 163.656543 -268.483729) (xy 163.664361 -268.502418)
			(xy 163.6649 -268.512544) (xy 163.6649 -268.921484) (xy 169.706036 -268.921484) (xy 169.706036 -268.512544)
			(xy 169.706458 -268.502388) (xy 169.714246 -268.48363) (xy 169.728644 -268.469304) (xy 169.74744 -268.461609)
			(xy 169.757598 -268.461236) (xy 171.157138 -268.461236) (xy 171.167267 -268.461695) (xy 171.185988 -268.469435)
			(xy 171.200343 -268.483729) (xy 171.208161 -268.502418) (xy 171.2087 -268.512544) (xy 171.2087 -268.921484)
			(xy 177.249836 -268.921484) (xy 177.249836 -268.512544) (xy 177.250258 -268.502388) (xy 177.258046 -268.48363)
			(xy 177.272444 -268.469304) (xy 177.29124 -268.461609) (xy 177.301398 -268.461236) (xy 178.700938 -268.461236)
			(xy 178.711067 -268.461695) (xy 178.729788 -268.469435) (xy 178.744143 -268.483729) (xy 178.751961 -268.502418)
			(xy 178.7525 -268.512544) (xy 178.7525 -268.921484) (xy 184.793636 -268.921484) (xy 184.793636 -268.512544)
			(xy 184.794058 -268.502388) (xy 184.801846 -268.48363) (xy 184.816244 -268.469304) (xy 184.83504 -268.461609)
			(xy 184.845198 -268.461236) (xy 186.244738 -268.461236) (xy 186.254867 -268.461695) (xy 186.273588 -268.469435)
			(xy 186.287943 -268.483729) (xy 186.295761 -268.502418) (xy 186.2963 -268.512544) (xy 186.2963 -268.921484)
			(xy 192.337436 -268.921484) (xy 192.337436 -268.512544) (xy 192.337858 -268.502388) (xy 192.345646 -268.48363)
			(xy 192.360044 -268.469304) (xy 192.37884 -268.461609) (xy 192.388998 -268.461236) (xy 193.788538 -268.461236)
			(xy 193.798667 -268.461695) (xy 193.817388 -268.469435) (xy 193.831743 -268.483729) (xy 193.839561 -268.502418)
			(xy 193.8401 -268.512544) (xy 193.8401 -268.921484) (xy 199.881236 -268.921484) (xy 199.881236 -268.512544)
			(xy 199.881658 -268.502388) (xy 199.889446 -268.48363) (xy 199.903844 -268.469304) (xy 199.92264 -268.461609)
			(xy 199.932798 -268.461236) (xy 201.332338 -268.461236) (xy 201.342467 -268.461695) (xy 201.361188 -268.469435)
			(xy 201.375543 -268.483729) (xy 201.383361 -268.502418) (xy 201.3839 -268.512544) (xy 201.3839 -268.921484)
			(xy 207.425036 -268.921484) (xy 207.425036 -268.512544) (xy 207.425458 -268.502388) (xy 207.433246 -268.48363)
			(xy 207.447644 -268.469304) (xy 207.46644 -268.461609) (xy 207.476598 -268.461236) (xy 208.876138 -268.461236)
			(xy 208.886267 -268.461695) (xy 208.904988 -268.469435) (xy 208.919343 -268.483729) (xy 208.927161 -268.502418)
			(xy 208.9277 -268.512544) (xy 208.9277 -268.921484) (xy 214.968836 -268.921484) (xy 214.968836 -268.512544)
			(xy 214.969258 -268.502388) (xy 214.977046 -268.48363) (xy 214.991444 -268.469304) (xy 215.01024 -268.461609)
			(xy 215.020398 -268.461236) (xy 216.419938 -268.461236) (xy 216.430067 -268.461695) (xy 216.448788 -268.469435)
			(xy 216.463143 -268.483729) (xy 216.470961 -268.502418) (xy 216.4715 -268.512544) (xy 216.4715 -268.921484)
			(xy 259.429504 -268.921484) (xy 259.429504 -268.512544) (xy 259.429958 -268.502392) (xy 259.43774 -268.48364)
			(xy 259.452127 -268.469315) (xy 259.470913 -268.461615) (xy 259.481066 -268.461236) (xy 260.880606 -268.461236)
			(xy 260.890733 -268.461722) (xy 260.909453 -268.469451) (xy 260.923809 -268.483737) (xy 260.931629 -268.50242)
			(xy 260.932168 -268.512544) (xy 260.932168 -268.921484) (xy 266.973304 -268.921484) (xy 266.973304 -268.512544)
			(xy 266.973758 -268.502392) (xy 266.98154 -268.48364) (xy 266.995927 -268.469315) (xy 267.014713 -268.461615)
			(xy 267.024866 -268.461236) (xy 268.424406 -268.461236) (xy 268.434533 -268.461722) (xy 268.453253 -268.469451)
			(xy 268.467609 -268.483737) (xy 268.475429 -268.50242) (xy 268.475968 -268.512544) (xy 268.475968 -268.921484)
			(xy 274.517104 -268.921484) (xy 274.517104 -268.512544) (xy 274.517558 -268.502392) (xy 274.52534 -268.48364)
			(xy 274.539727 -268.469315) (xy 274.558513 -268.461615) (xy 274.568666 -268.461236) (xy 275.968206 -268.461236)
			(xy 275.978333 -268.461722) (xy 275.997053 -268.469451) (xy 276.011409 -268.483737) (xy 276.019229 -268.50242)
			(xy 276.019768 -268.512544) (xy 276.019768 -268.921484) (xy 282.060904 -268.921484) (xy 282.060904 -268.512544)
			(xy 282.061358 -268.502392) (xy 282.06914 -268.48364) (xy 282.083527 -268.469315) (xy 282.102313 -268.461615)
			(xy 282.112466 -268.461236) (xy 283.512006 -268.461236) (xy 283.522133 -268.461722) (xy 283.540853 -268.469451)
			(xy 283.555209 -268.483737) (xy 283.563029 -268.50242) (xy 283.563568 -268.512544) (xy 283.563568 -268.921484)
			(xy 289.604704 -268.921484) (xy 289.604704 -268.512544) (xy 289.605158 -268.502392) (xy 289.61294 -268.48364)
			(xy 289.627327 -268.469315) (xy 289.646113 -268.461615) (xy 289.656266 -268.461236) (xy 291.055806 -268.461236)
			(xy 291.065933 -268.461722) (xy 291.084653 -268.469451) (xy 291.099009 -268.483737) (xy 291.106829 -268.50242)
			(xy 291.107368 -268.512544) (xy 291.107368 -268.921484) (xy 297.148504 -268.921484) (xy 297.148504 -268.512544)
			(xy 297.148958 -268.502392) (xy 297.15674 -268.48364) (xy 297.171127 -268.469315) (xy 297.189913 -268.461615)
			(xy 297.200066 -268.461236) (xy 298.599606 -268.461236) (xy 298.609733 -268.461722) (xy 298.628453 -268.469451)
			(xy 298.642809 -268.483737) (xy 298.650629 -268.50242) (xy 298.651168 -268.512544) (xy 298.651168 -268.921484)
			(xy 304.692304 -268.921484) (xy 304.692304 -268.512544) (xy 304.692758 -268.502392) (xy 304.70054 -268.48364)
			(xy 304.714927 -268.469315) (xy 304.733713 -268.461615) (xy 304.743866 -268.461236) (xy 306.143406 -268.461236)
			(xy 306.153533 -268.461722) (xy 306.172253 -268.469451) (xy 306.186609 -268.483737) (xy 306.194429 -268.50242)
			(xy 306.194968 -268.512544) (xy 306.194968 -268.921484) (xy 312.236104 -268.921484) (xy 312.236104 -268.512544)
			(xy 312.236558 -268.502392) (xy 312.24434 -268.48364) (xy 312.258727 -268.469315) (xy 312.277513 -268.461615)
			(xy 312.287666 -268.461236) (xy 313.687206 -268.461236) (xy 313.697333 -268.461722) (xy 313.716053 -268.469451)
			(xy 313.730409 -268.483737) (xy 313.738229 -268.50242) (xy 313.738768 -268.512544) (xy 313.738768 -268.921484)
			(xy 410.102304 -268.921484) (xy 410.102304 -268.512544) (xy 410.102758 -268.502392) (xy 410.11054 -268.48364)
			(xy 410.124927 -268.469315) (xy 410.143713 -268.461615) (xy 410.153866 -268.461236) (xy 411.553406 -268.461236)
			(xy 411.563533 -268.461722) (xy 411.582253 -268.469451) (xy 411.596609 -268.483737) (xy 411.604429 -268.50242)
			(xy 411.604968 -268.512544) (xy 411.604968 -268.921484) (xy 417.646104 -268.921484) (xy 417.646104 -268.512544)
			(xy 417.646558 -268.502392) (xy 417.65434 -268.48364) (xy 417.668727 -268.469315) (xy 417.687513 -268.461615)
			(xy 417.697666 -268.461236) (xy 419.097206 -268.461236) (xy 419.107333 -268.461722) (xy 419.126053 -268.469451)
			(xy 419.140409 -268.483737) (xy 419.148229 -268.50242) (xy 419.148768 -268.512544) (xy 419.148768 -268.921484)
			(xy 425.189904 -268.921484) (xy 425.189904 -268.512544) (xy 425.190358 -268.502392) (xy 425.19814 -268.48364)
			(xy 425.212527 -268.469315) (xy 425.231313 -268.461615) (xy 425.241466 -268.461236) (xy 426.641006 -268.461236)
			(xy 426.651133 -268.461722) (xy 426.669853 -268.469451) (xy 426.684209 -268.483737) (xy 426.692029 -268.50242)
			(xy 426.692568 -268.512544) (xy 426.692568 -268.921484) (xy 432.733704 -268.921484) (xy 432.733704 -268.512544)
			(xy 432.734158 -268.502392) (xy 432.74194 -268.48364) (xy 432.756327 -268.469315) (xy 432.775113 -268.461615)
			(xy 432.785266 -268.461236) (xy 434.184806 -268.461236) (xy 434.194933 -268.461722) (xy 434.213653 -268.469451)
			(xy 434.228009 -268.483737) (xy 434.235829 -268.50242) (xy 434.236368 -268.512544) (xy 434.236368 -268.921484)
			(xy 440.277504 -268.921484) (xy 440.277504 -268.512544) (xy 440.277958 -268.502392) (xy 440.28574 -268.48364)
			(xy 440.300127 -268.469315) (xy 440.318913 -268.461615) (xy 440.329066 -268.461236) (xy 441.728606 -268.461236)
			(xy 441.738733 -268.461722) (xy 441.757453 -268.469451) (xy 441.771809 -268.483737) (xy 441.779629 -268.50242)
			(xy 441.780168 -268.512544) (xy 441.780168 -268.921484) (xy 447.821304 -268.921484) (xy 447.821304 -268.512544)
			(xy 447.821758 -268.502392) (xy 447.82954 -268.48364) (xy 447.843927 -268.469315) (xy 447.862713 -268.461615)
			(xy 447.872866 -268.461236) (xy 449.272406 -268.461236) (xy 449.282533 -268.461722) (xy 449.301253 -268.469451)
			(xy 449.315609 -268.483737) (xy 449.323429 -268.50242) (xy 449.323968 -268.512544) (xy 449.323968 -268.921484)
			(xy 455.365104 -268.921484) (xy 455.365104 -268.512544) (xy 455.365558 -268.502392) (xy 455.37334 -268.48364)
			(xy 455.387727 -268.469315) (xy 455.406513 -268.461615) (xy 455.416666 -268.461236) (xy 456.816206 -268.461236)
			(xy 456.826333 -268.461722) (xy 456.845053 -268.469451) (xy 456.859409 -268.483737) (xy 456.867229 -268.50242)
			(xy 456.867768 -268.512544) (xy 456.867768 -268.921484) (xy 462.908904 -268.921484) (xy 462.908904 -268.512544)
			(xy 462.909358 -268.502392) (xy 462.91714 -268.48364) (xy 462.931527 -268.469315) (xy 462.950313 -268.461615)
			(xy 462.960466 -268.461236) (xy 464.360006 -268.461236) (xy 464.370133 -268.461722) (xy 464.388853 -268.469451)
			(xy 464.403209 -268.483737) (xy 464.411029 -268.50242) (xy 464.411568 -268.512544) (xy 464.411568 -268.921484)
			(xy 464.411165 -268.931641) (xy 464.403368 -268.950399) (xy 464.388966 -268.964724) (xy 464.370165 -268.972419)
			(xy 464.360006 -268.972792) (xy 462.960466 -268.972792) (xy 462.950341 -268.972302) (xy 462.931625 -268.964569)
			(xy 462.917271 -268.950285) (xy 462.909448 -268.931606) (xy 462.908904 -268.921484) (xy 456.867768 -268.921484)
			(xy 456.867365 -268.931641) (xy 456.859568 -268.950399) (xy 456.845166 -268.964724) (xy 456.826365 -268.972419)
			(xy 456.816206 -268.972792) (xy 455.416666 -268.972792) (xy 455.406541 -268.972302) (xy 455.387825 -268.964569)
			(xy 455.373471 -268.950285) (xy 455.365648 -268.931606) (xy 455.365104 -268.921484) (xy 449.323968 -268.921484)
			(xy 449.323565 -268.931641) (xy 449.315768 -268.950399) (xy 449.301366 -268.964724) (xy 449.282565 -268.972419)
			(xy 449.272406 -268.972792) (xy 447.872866 -268.972792) (xy 447.862741 -268.972302) (xy 447.844025 -268.964569)
			(xy 447.829671 -268.950285) (xy 447.821848 -268.931606) (xy 447.821304 -268.921484) (xy 441.780168 -268.921484)
			(xy 441.779765 -268.931641) (xy 441.771968 -268.950399) (xy 441.757566 -268.964724) (xy 441.738765 -268.972419)
			(xy 441.728606 -268.972792) (xy 440.329066 -268.972792) (xy 440.318941 -268.972302) (xy 440.300225 -268.964569)
			(xy 440.285871 -268.950285) (xy 440.278048 -268.931606) (xy 440.277504 -268.921484) (xy 434.236368 -268.921484)
			(xy 434.235965 -268.931641) (xy 434.228168 -268.950399) (xy 434.213766 -268.964724) (xy 434.194965 -268.972419)
			(xy 434.184806 -268.972792) (xy 432.785266 -268.972792) (xy 432.775141 -268.972302) (xy 432.756425 -268.964569)
			(xy 432.742071 -268.950285) (xy 432.734248 -268.931606) (xy 432.733704 -268.921484) (xy 426.692568 -268.921484)
			(xy 426.692165 -268.931641) (xy 426.684368 -268.950399) (xy 426.669966 -268.964724) (xy 426.651165 -268.972419)
			(xy 426.641006 -268.972792) (xy 425.241466 -268.972792) (xy 425.231341 -268.972302) (xy 425.212625 -268.964569)
			(xy 425.198271 -268.950285) (xy 425.190448 -268.931606) (xy 425.189904 -268.921484) (xy 419.148768 -268.921484)
			(xy 419.148365 -268.931641) (xy 419.140568 -268.950399) (xy 419.126166 -268.964724) (xy 419.107365 -268.972419)
			(xy 419.097206 -268.972792) (xy 417.697666 -268.972792) (xy 417.687541 -268.972302) (xy 417.668825 -268.964569)
			(xy 417.654471 -268.950285) (xy 417.646648 -268.931606) (xy 417.646104 -268.921484) (xy 411.604968 -268.921484)
			(xy 411.604565 -268.931641) (xy 411.596768 -268.950399) (xy 411.582366 -268.964724) (xy 411.563565 -268.972419)
			(xy 411.553406 -268.972792) (xy 410.153866 -268.972792) (xy 410.143741 -268.972302) (xy 410.125025 -268.964569)
			(xy 410.110671 -268.950285) (xy 410.102848 -268.931606) (xy 410.102304 -268.921484) (xy 313.738768 -268.921484)
			(xy 313.738365 -268.931641) (xy 313.730568 -268.950399) (xy 313.716166 -268.964724) (xy 313.697365 -268.972419)
			(xy 313.687206 -268.972792) (xy 312.287666 -268.972792) (xy 312.277541 -268.972302) (xy 312.258825 -268.964569)
			(xy 312.244471 -268.950285) (xy 312.236648 -268.931606) (xy 312.236104 -268.921484) (xy 306.194968 -268.921484)
			(xy 306.194565 -268.931641) (xy 306.186768 -268.950399) (xy 306.172366 -268.964724) (xy 306.153565 -268.972419)
			(xy 306.143406 -268.972792) (xy 304.743866 -268.972792) (xy 304.733741 -268.972302) (xy 304.715025 -268.964569)
			(xy 304.700671 -268.950285) (xy 304.692848 -268.931606) (xy 304.692304 -268.921484) (xy 298.651168 -268.921484)
			(xy 298.650765 -268.931641) (xy 298.642968 -268.950399) (xy 298.628566 -268.964724) (xy 298.609765 -268.972419)
			(xy 298.599606 -268.972792) (xy 297.200066 -268.972792) (xy 297.189941 -268.972302) (xy 297.171225 -268.964569)
			(xy 297.156871 -268.950285) (xy 297.149048 -268.931606) (xy 297.148504 -268.921484) (xy 291.107368 -268.921484)
			(xy 291.106965 -268.931641) (xy 291.099168 -268.950399) (xy 291.084766 -268.964724) (xy 291.065965 -268.972419)
			(xy 291.055806 -268.972792) (xy 289.656266 -268.972792) (xy 289.646141 -268.972302) (xy 289.627425 -268.964569)
			(xy 289.613071 -268.950285) (xy 289.605248 -268.931606) (xy 289.604704 -268.921484) (xy 283.563568 -268.921484)
			(xy 283.563165 -268.931641) (xy 283.555368 -268.950399) (xy 283.540966 -268.964724) (xy 283.522165 -268.972419)
			(xy 283.512006 -268.972792) (xy 282.112466 -268.972792) (xy 282.102341 -268.972302) (xy 282.083625 -268.964569)
			(xy 282.069271 -268.950285) (xy 282.061448 -268.931606) (xy 282.060904 -268.921484) (xy 276.019768 -268.921484)
			(xy 276.019365 -268.931641) (xy 276.011568 -268.950399) (xy 275.997166 -268.964724) (xy 275.978365 -268.972419)
			(xy 275.968206 -268.972792) (xy 274.568666 -268.972792) (xy 274.558541 -268.972302) (xy 274.539825 -268.964569)
			(xy 274.525471 -268.950285) (xy 274.517648 -268.931606) (xy 274.517104 -268.921484) (xy 268.475968 -268.921484)
			(xy 268.475565 -268.931641) (xy 268.467768 -268.950399) (xy 268.453366 -268.964724) (xy 268.434565 -268.972419)
			(xy 268.424406 -268.972792) (xy 267.024866 -268.972792) (xy 267.014741 -268.972302) (xy 266.996025 -268.964569)
			(xy 266.981671 -268.950285) (xy 266.973848 -268.931606) (xy 266.973304 -268.921484) (xy 260.932168 -268.921484)
			(xy 260.931765 -268.931641) (xy 260.923968 -268.950399) (xy 260.909566 -268.964724) (xy 260.890765 -268.972419)
			(xy 260.880606 -268.972792) (xy 259.481066 -268.972792) (xy 259.470941 -268.972302) (xy 259.452225 -268.964569)
			(xy 259.437871 -268.950285) (xy 259.430048 -268.931606) (xy 259.429504 -268.921484) (xy 216.4715 -268.921484)
			(xy 216.471065 -268.931637) (xy 216.463275 -268.950389) (xy 216.448882 -268.964713) (xy 216.430093 -268.972413)
			(xy 216.419938 -268.972792) (xy 215.020398 -268.972792) (xy 215.010275 -268.972276) (xy 214.99156 -268.964553)
			(xy 214.977205 -268.950277) (xy 214.96938 -268.931604) (xy 214.968836 -268.921484) (xy 208.9277 -268.921484)
			(xy 208.927265 -268.931637) (xy 208.919475 -268.950389) (xy 208.905082 -268.964713) (xy 208.886293 -268.972413)
			(xy 208.876138 -268.972792) (xy 207.476598 -268.972792) (xy 207.466475 -268.972276) (xy 207.44776 -268.964553)
			(xy 207.433405 -268.950277) (xy 207.42558 -268.931604) (xy 207.425036 -268.921484) (xy 201.3839 -268.921484)
			(xy 201.383465 -268.931637) (xy 201.375675 -268.950389) (xy 201.361282 -268.964713) (xy 201.342493 -268.972413)
			(xy 201.332338 -268.972792) (xy 199.932798 -268.972792) (xy 199.922675 -268.972276) (xy 199.90396 -268.964553)
			(xy 199.889605 -268.950277) (xy 199.88178 -268.931604) (xy 199.881236 -268.921484) (xy 193.8401 -268.921484)
			(xy 193.839665 -268.931637) (xy 193.831875 -268.950389) (xy 193.817482 -268.964713) (xy 193.798693 -268.972413)
			(xy 193.788538 -268.972792) (xy 192.388998 -268.972792) (xy 192.378875 -268.972276) (xy 192.36016 -268.964553)
			(xy 192.345805 -268.950277) (xy 192.33798 -268.931604) (xy 192.337436 -268.921484) (xy 186.2963 -268.921484)
			(xy 186.295865 -268.931637) (xy 186.288075 -268.950389) (xy 186.273682 -268.964713) (xy 186.254893 -268.972413)
			(xy 186.244738 -268.972792) (xy 184.845198 -268.972792) (xy 184.835075 -268.972276) (xy 184.81636 -268.964553)
			(xy 184.802005 -268.950277) (xy 184.79418 -268.931604) (xy 184.793636 -268.921484) (xy 178.7525 -268.921484)
			(xy 178.752065 -268.931637) (xy 178.744275 -268.950389) (xy 178.729882 -268.964713) (xy 178.711093 -268.972413)
			(xy 178.700938 -268.972792) (xy 177.301398 -268.972792) (xy 177.291275 -268.972276) (xy 177.27256 -268.964553)
			(xy 177.258205 -268.950277) (xy 177.25038 -268.931604) (xy 177.249836 -268.921484) (xy 171.2087 -268.921484)
			(xy 171.208265 -268.931637) (xy 171.200475 -268.950389) (xy 171.186082 -268.964713) (xy 171.167293 -268.972413)
			(xy 171.157138 -268.972792) (xy 169.757598 -268.972792) (xy 169.747475 -268.972276) (xy 169.72876 -268.964553)
			(xy 169.714405 -268.950277) (xy 169.70658 -268.931604) (xy 169.706036 -268.921484) (xy 163.6649 -268.921484)
			(xy 163.664465 -268.931637) (xy 163.656675 -268.950389) (xy 163.642282 -268.964713) (xy 163.623493 -268.972413)
			(xy 163.613338 -268.972792) (xy 162.213798 -268.972792) (xy 162.203675 -268.972276) (xy 162.18496 -268.964553)
			(xy 162.170605 -268.950277) (xy 162.16278 -268.931604) (xy 162.162236 -268.921484) (xy 65.7987 -268.921484)
			(xy 65.798265 -268.931637) (xy 65.790475 -268.950389) (xy 65.776082 -268.964713) (xy 65.757293 -268.972413)
			(xy 65.747138 -268.972792) (xy 64.347598 -268.972792) (xy 64.337475 -268.972276) (xy 64.31876 -268.964553)
			(xy 64.304405 -268.950277) (xy 64.29658 -268.931604) (xy 64.296036 -268.921484) (xy 58.2549 -268.921484)
			(xy 58.254465 -268.931637) (xy 58.246675 -268.950389) (xy 58.232282 -268.964713) (xy 58.213493 -268.972413)
			(xy 58.203338 -268.972792) (xy 56.803798 -268.972792) (xy 56.793675 -268.972276) (xy 56.77496 -268.964553)
			(xy 56.760605 -268.950277) (xy 56.75278 -268.931604) (xy 56.752236 -268.921484) (xy 50.7111 -268.921484)
			(xy 50.710665 -268.931637) (xy 50.702875 -268.950389) (xy 50.688482 -268.964713) (xy 50.669693 -268.972413)
			(xy 50.659538 -268.972792) (xy 49.259998 -268.972792) (xy 49.249875 -268.972276) (xy 49.23116 -268.964553)
			(xy 49.216805 -268.950277) (xy 49.20898 -268.931604) (xy 49.208436 -268.921484) (xy 43.1673 -268.921484)
			(xy 43.166865 -268.931637) (xy 43.159075 -268.950389) (xy 43.144682 -268.964713) (xy 43.125893 -268.972413)
			(xy 43.115738 -268.972792) (xy 41.716198 -268.972792) (xy 41.706075 -268.972276) (xy 41.68736 -268.964553)
			(xy 41.673005 -268.950277) (xy 41.66518 -268.931604) (xy 41.664636 -268.921484) (xy 35.6235 -268.921484)
			(xy 35.623065 -268.931637) (xy 35.615275 -268.950389) (xy 35.600882 -268.964713) (xy 35.582093 -268.972413)
			(xy 35.571938 -268.972792) (xy 34.172398 -268.972792) (xy 34.162275 -268.972276) (xy 34.14356 -268.964553)
			(xy 34.129205 -268.950277) (xy 34.12138 -268.931604) (xy 34.120836 -268.921484) (xy 28.0797 -268.921484)
			(xy 28.079265 -268.931637) (xy 28.071475 -268.950389) (xy 28.057082 -268.964713) (xy 28.038293 -268.972413)
			(xy 28.028138 -268.972792) (xy 26.628598 -268.972792) (xy 26.618475 -268.972276) (xy 26.59976 -268.964553)
			(xy 26.585405 -268.950277) (xy 26.57758 -268.931604) (xy 26.577036 -268.921484) (xy 20.5359 -268.921484)
			(xy 20.535465 -268.931637) (xy 20.527675 -268.950389) (xy 20.513282 -268.964713) (xy 20.494493 -268.972413)
			(xy 20.484338 -268.972792) (xy 19.084798 -268.972792) (xy 19.074675 -268.972276) (xy 19.05596 -268.964553)
			(xy 19.041605 -268.950277) (xy 19.03378 -268.931604) (xy 19.033236 -268.921484) (xy 12.9921 -268.921484)
			(xy 12.991665 -268.931637) (xy 12.983875 -268.950389) (xy 12.969482 -268.964713) (xy 12.950693 -268.972413)
			(xy 12.940538 -268.972792) (xy 11.540998 -268.972792) (xy 11.530875 -268.972276) (xy 11.51216 -268.964553)
			(xy 11.497805 -268.950277) (xy 11.48998 -268.931604) (xy 11.489436 -268.921484) (xy 2.509012 -268.921484)
			(xy 2.509012 -269.771368) (xy 7.389368 -269.771368) (xy 7.389368 -269.362428) (xy 7.389844 -269.35228)
			(xy 7.397624 -269.333534) (xy 7.412004 -269.319211) (xy 7.43078 -269.311504) (xy 7.44093 -269.31112)
			(xy 8.84047 -269.31112) (xy 8.850592 -269.31165) (xy 8.869309 -269.319365) (xy 8.883666 -269.333637)
			(xy 8.89149 -269.352309) (xy 8.892032 -269.362428) (xy 8.892032 -269.771368) (xy 14.933168 -269.771368)
			(xy 14.933168 -269.362428) (xy 14.933644 -269.35228) (xy 14.941424 -269.333534) (xy 14.955804 -269.319211)
			(xy 14.97458 -269.311504) (xy 14.98473 -269.31112) (xy 16.38427 -269.31112) (xy 16.394392 -269.31165)
			(xy 16.413109 -269.319365) (xy 16.427466 -269.333637) (xy 16.43529 -269.352309) (xy 16.435832 -269.362428)
			(xy 16.435832 -269.771368) (xy 22.476968 -269.771368) (xy 22.476968 -269.362428) (xy 22.477444 -269.35228)
			(xy 22.485224 -269.333534) (xy 22.499604 -269.319211) (xy 22.51838 -269.311504) (xy 22.52853 -269.31112)
			(xy 23.92807 -269.31112) (xy 23.938192 -269.31165) (xy 23.956909 -269.319365) (xy 23.971266 -269.333637)
			(xy 23.97909 -269.352309) (xy 23.979632 -269.362428) (xy 23.979632 -269.771368) (xy 30.020768 -269.771368)
			(xy 30.020768 -269.362428) (xy 30.021244 -269.35228) (xy 30.029024 -269.333534) (xy 30.043404 -269.319211)
			(xy 30.06218 -269.311504) (xy 30.07233 -269.31112) (xy 31.47187 -269.31112) (xy 31.481992 -269.31165)
			(xy 31.500709 -269.319365) (xy 31.515066 -269.333637) (xy 31.52289 -269.352309) (xy 31.523432 -269.362428)
			(xy 31.523432 -269.771368) (xy 37.564568 -269.771368) (xy 37.564568 -269.362428) (xy 37.565044 -269.35228)
			(xy 37.572824 -269.333534) (xy 37.587204 -269.319211) (xy 37.60598 -269.311504) (xy 37.61613 -269.31112)
			(xy 39.01567 -269.31112) (xy 39.025792 -269.31165) (xy 39.044509 -269.319365) (xy 39.058866 -269.333637)
			(xy 39.06669 -269.352309) (xy 39.067232 -269.362428) (xy 39.067232 -269.771368) (xy 45.108368 -269.771368)
			(xy 45.108368 -269.362428) (xy 45.108844 -269.35228) (xy 45.116624 -269.333534) (xy 45.131004 -269.319211)
			(xy 45.14978 -269.311504) (xy 45.15993 -269.31112) (xy 46.55947 -269.31112) (xy 46.569592 -269.31165)
			(xy 46.588309 -269.319365) (xy 46.602666 -269.333637) (xy 46.61049 -269.352309) (xy 46.611032 -269.362428)
			(xy 46.611032 -269.771368) (xy 52.652168 -269.771368) (xy 52.652168 -269.362428) (xy 52.652644 -269.35228)
			(xy 52.660424 -269.333534) (xy 52.674804 -269.319211) (xy 52.69358 -269.311504) (xy 52.70373 -269.31112)
			(xy 54.10327 -269.31112) (xy 54.113392 -269.31165) (xy 54.132109 -269.319365) (xy 54.146466 -269.333637)
			(xy 54.15429 -269.352309) (xy 54.154832 -269.362428) (xy 54.154832 -269.771368) (xy 60.195968 -269.771368)
			(xy 60.195968 -269.362428) (xy 60.196444 -269.35228) (xy 60.204224 -269.333534) (xy 60.218604 -269.319211)
			(xy 60.23738 -269.311504) (xy 60.24753 -269.31112) (xy 61.64707 -269.31112) (xy 61.657192 -269.31165)
			(xy 61.675909 -269.319365) (xy 61.690266 -269.333637) (xy 61.69809 -269.352309) (xy 61.698632 -269.362428)
			(xy 61.698632 -269.771368) (xy 158.062168 -269.771368) (xy 158.062168 -269.362428) (xy 158.062644 -269.35228)
			(xy 158.070424 -269.333534) (xy 158.084804 -269.319211) (xy 158.10358 -269.311504) (xy 158.11373 -269.31112)
			(xy 159.51327 -269.31112) (xy 159.523392 -269.31165) (xy 159.542109 -269.319365) (xy 159.556466 -269.333637)
			(xy 159.56429 -269.352309) (xy 159.564832 -269.362428) (xy 159.564832 -269.771368) (xy 165.605968 -269.771368)
			(xy 165.605968 -269.362428) (xy 165.606444 -269.35228) (xy 165.614224 -269.333534) (xy 165.628604 -269.319211)
			(xy 165.64738 -269.311504) (xy 165.65753 -269.31112) (xy 167.05707 -269.31112) (xy 167.067192 -269.31165)
			(xy 167.085909 -269.319365) (xy 167.100266 -269.333637) (xy 167.10809 -269.352309) (xy 167.108632 -269.362428)
			(xy 167.108632 -269.771368) (xy 173.149768 -269.771368) (xy 173.149768 -269.362428) (xy 173.150244 -269.35228)
			(xy 173.158024 -269.333534) (xy 173.172404 -269.319211) (xy 173.19118 -269.311504) (xy 173.20133 -269.31112)
			(xy 174.60087 -269.31112) (xy 174.610992 -269.31165) (xy 174.629709 -269.319365) (xy 174.644066 -269.333637)
			(xy 174.65189 -269.352309) (xy 174.652432 -269.362428) (xy 174.652432 -269.771368) (xy 180.693568 -269.771368)
			(xy 180.693568 -269.362428) (xy 180.694044 -269.35228) (xy 180.701824 -269.333534) (xy 180.716204 -269.319211)
			(xy 180.73498 -269.311504) (xy 180.74513 -269.31112) (xy 182.14467 -269.31112) (xy 182.154792 -269.31165)
			(xy 182.173509 -269.319365) (xy 182.187866 -269.333637) (xy 182.19569 -269.352309) (xy 182.196232 -269.362428)
			(xy 182.196232 -269.771368) (xy 188.237368 -269.771368) (xy 188.237368 -269.362428) (xy 188.237844 -269.35228)
			(xy 188.245624 -269.333534) (xy 188.260004 -269.319211) (xy 188.27878 -269.311504) (xy 188.28893 -269.31112)
			(xy 189.68847 -269.31112) (xy 189.698592 -269.31165) (xy 189.717309 -269.319365) (xy 189.731666 -269.333637)
			(xy 189.73949 -269.352309) (xy 189.740032 -269.362428) (xy 189.740032 -269.771368) (xy 195.781168 -269.771368)
			(xy 195.781168 -269.362428) (xy 195.781644 -269.35228) (xy 195.789424 -269.333534) (xy 195.803804 -269.319211)
			(xy 195.82258 -269.311504) (xy 195.83273 -269.31112) (xy 197.23227 -269.31112) (xy 197.242392 -269.31165)
			(xy 197.261109 -269.319365) (xy 197.275466 -269.333637) (xy 197.28329 -269.352309) (xy 197.283832 -269.362428)
			(xy 197.283832 -269.771368) (xy 203.324968 -269.771368) (xy 203.324968 -269.362428) (xy 203.325444 -269.35228)
			(xy 203.333224 -269.333534) (xy 203.347604 -269.319211) (xy 203.36638 -269.311504) (xy 203.37653 -269.31112)
			(xy 204.77607 -269.31112) (xy 204.786192 -269.31165) (xy 204.804909 -269.319365) (xy 204.819266 -269.333637)
			(xy 204.82709 -269.352309) (xy 204.827632 -269.362428) (xy 204.827632 -269.771368) (xy 210.868768 -269.771368)
			(xy 210.868768 -269.362428) (xy 210.869244 -269.35228) (xy 210.877024 -269.333534) (xy 210.891404 -269.319211)
			(xy 210.91018 -269.311504) (xy 210.92033 -269.31112) (xy 212.31987 -269.31112) (xy 212.329992 -269.31165)
			(xy 212.348709 -269.319365) (xy 212.363066 -269.333637) (xy 212.37089 -269.352309) (xy 212.371432 -269.362428)
			(xy 212.371432 -269.771368) (xy 255.329436 -269.771368) (xy 255.329436 -269.362428) (xy 255.329845 -269.352271)
			(xy 255.337638 -269.333512) (xy 255.352039 -269.319187) (xy 255.370839 -269.311492) (xy 255.380998 -269.31112)
			(xy 256.780538 -269.31112) (xy 256.790665 -269.311595) (xy 256.809383 -269.319331) (xy 256.823737 -269.333621)
			(xy 256.831559 -269.352304) (xy 256.8321 -269.362428) (xy 256.8321 -269.771368) (xy 262.873236 -269.771368)
			(xy 262.873236 -269.362428) (xy 262.873645 -269.352271) (xy 262.881438 -269.333512) (xy 262.895839 -269.319187)
			(xy 262.914639 -269.311492) (xy 262.924798 -269.31112) (xy 264.324338 -269.31112) (xy 264.334465 -269.311595)
			(xy 264.353183 -269.319331) (xy 264.367537 -269.333621) (xy 264.375359 -269.352304) (xy 264.3759 -269.362428)
			(xy 264.3759 -269.771368) (xy 270.417036 -269.771368) (xy 270.417036 -269.362428) (xy 270.417445 -269.352271)
			(xy 270.425238 -269.333512) (xy 270.439639 -269.319187) (xy 270.458439 -269.311492) (xy 270.468598 -269.31112)
			(xy 271.868138 -269.31112) (xy 271.878265 -269.311595) (xy 271.896983 -269.319331) (xy 271.911337 -269.333621)
			(xy 271.919159 -269.352304) (xy 271.9197 -269.362428) (xy 271.9197 -269.771368) (xy 277.960836 -269.771368)
			(xy 277.960836 -269.362428) (xy 277.961245 -269.352271) (xy 277.969038 -269.333512) (xy 277.983439 -269.319187)
			(xy 278.002239 -269.311492) (xy 278.012398 -269.31112) (xy 279.411938 -269.31112) (xy 279.422065 -269.311595)
			(xy 279.440783 -269.319331) (xy 279.455137 -269.333621) (xy 279.462959 -269.352304) (xy 279.4635 -269.362428)
			(xy 279.4635 -269.771368) (xy 285.504636 -269.771368) (xy 285.504636 -269.362428) (xy 285.505045 -269.352271)
			(xy 285.512838 -269.333512) (xy 285.527239 -269.319187) (xy 285.546039 -269.311492) (xy 285.556198 -269.31112)
			(xy 286.955738 -269.31112) (xy 286.965865 -269.311595) (xy 286.984583 -269.319331) (xy 286.998937 -269.333621)
			(xy 287.006759 -269.352304) (xy 287.0073 -269.362428) (xy 287.0073 -269.771368) (xy 293.048436 -269.771368)
			(xy 293.048436 -269.362428) (xy 293.048845 -269.352271) (xy 293.056638 -269.333512) (xy 293.071039 -269.319187)
			(xy 293.089839 -269.311492) (xy 293.099998 -269.31112) (xy 294.499538 -269.31112) (xy 294.509665 -269.311595)
			(xy 294.528383 -269.319331) (xy 294.542737 -269.333621) (xy 294.550559 -269.352304) (xy 294.5511 -269.362428)
			(xy 294.5511 -269.771368) (xy 300.592236 -269.771368) (xy 300.592236 -269.362428) (xy 300.592645 -269.352271)
			(xy 300.600438 -269.333512) (xy 300.614839 -269.319187) (xy 300.633639 -269.311492) (xy 300.643798 -269.31112)
			(xy 302.043338 -269.31112) (xy 302.053465 -269.311595) (xy 302.072183 -269.319331) (xy 302.086537 -269.333621)
			(xy 302.094359 -269.352304) (xy 302.0949 -269.362428) (xy 302.0949 -269.771368) (xy 308.136036 -269.771368)
			(xy 308.136036 -269.362428) (xy 308.136445 -269.352271) (xy 308.144238 -269.333512) (xy 308.158639 -269.319187)
			(xy 308.177439 -269.311492) (xy 308.187598 -269.31112) (xy 309.587138 -269.31112) (xy 309.597265 -269.311595)
			(xy 309.615983 -269.319331) (xy 309.630337 -269.333621) (xy 309.638159 -269.352304) (xy 309.6387 -269.362428)
			(xy 309.6387 -269.771368) (xy 406.002236 -269.771368) (xy 406.002236 -269.362428) (xy 406.002645 -269.352271)
			(xy 406.010438 -269.333512) (xy 406.024839 -269.319187) (xy 406.043639 -269.311492) (xy 406.053798 -269.31112)
			(xy 407.453338 -269.31112) (xy 407.463465 -269.311595) (xy 407.482183 -269.319331) (xy 407.496537 -269.333621)
			(xy 407.504359 -269.352304) (xy 407.5049 -269.362428) (xy 407.5049 -269.771368) (xy 413.546036 -269.771368)
			(xy 413.546036 -269.362428) (xy 413.546445 -269.352271) (xy 413.554238 -269.333512) (xy 413.568639 -269.319187)
			(xy 413.587439 -269.311492) (xy 413.597598 -269.31112) (xy 414.997138 -269.31112) (xy 415.007265 -269.311595)
			(xy 415.025983 -269.319331) (xy 415.040337 -269.333621) (xy 415.048159 -269.352304) (xy 415.0487 -269.362428)
			(xy 415.0487 -269.771368) (xy 421.089836 -269.771368) (xy 421.089836 -269.362428) (xy 421.090245 -269.352271)
			(xy 421.098038 -269.333512) (xy 421.112439 -269.319187) (xy 421.131239 -269.311492) (xy 421.141398 -269.31112)
			(xy 422.540938 -269.31112) (xy 422.551065 -269.311595) (xy 422.569783 -269.319331) (xy 422.584137 -269.333621)
			(xy 422.591959 -269.352304) (xy 422.5925 -269.362428) (xy 422.5925 -269.771368) (xy 428.633636 -269.771368)
			(xy 428.633636 -269.362428) (xy 428.634045 -269.352271) (xy 428.641838 -269.333512) (xy 428.656239 -269.319187)
			(xy 428.675039 -269.311492) (xy 428.685198 -269.31112) (xy 430.084738 -269.31112) (xy 430.094865 -269.311595)
			(xy 430.113583 -269.319331) (xy 430.127937 -269.333621) (xy 430.135759 -269.352304) (xy 430.1363 -269.362428)
			(xy 430.1363 -269.771368) (xy 436.177436 -269.771368) (xy 436.177436 -269.362428) (xy 436.177845 -269.352271)
			(xy 436.185638 -269.333512) (xy 436.200039 -269.319187) (xy 436.218839 -269.311492) (xy 436.228998 -269.31112)
			(xy 437.628538 -269.31112) (xy 437.638665 -269.311595) (xy 437.657383 -269.319331) (xy 437.671737 -269.333621)
			(xy 437.679559 -269.352304) (xy 437.6801 -269.362428) (xy 437.6801 -269.771368) (xy 443.721236 -269.771368)
			(xy 443.721236 -269.362428) (xy 443.721645 -269.352271) (xy 443.729438 -269.333512) (xy 443.743839 -269.319187)
			(xy 443.762639 -269.311492) (xy 443.772798 -269.31112) (xy 445.172338 -269.31112) (xy 445.182465 -269.311595)
			(xy 445.201183 -269.319331) (xy 445.215537 -269.333621) (xy 445.223359 -269.352304) (xy 445.2239 -269.362428)
			(xy 445.2239 -269.771368) (xy 451.265036 -269.771368) (xy 451.265036 -269.362428) (xy 451.265445 -269.352271)
			(xy 451.273238 -269.333512) (xy 451.287639 -269.319187) (xy 451.306439 -269.311492) (xy 451.316598 -269.31112)
			(xy 452.716138 -269.31112) (xy 452.726265 -269.311595) (xy 452.744983 -269.319331) (xy 452.759337 -269.333621)
			(xy 452.767159 -269.352304) (xy 452.7677 -269.362428) (xy 452.7677 -269.771368) (xy 458.808836 -269.771368)
			(xy 458.808836 -269.362428) (xy 458.809245 -269.352271) (xy 458.817038 -269.333512) (xy 458.831439 -269.319187)
			(xy 458.850239 -269.311492) (xy 458.860398 -269.31112) (xy 460.259938 -269.31112) (xy 460.270065 -269.311595)
			(xy 460.288783 -269.319331) (xy 460.303137 -269.333621) (xy 460.310959 -269.352304) (xy 460.3115 -269.362428)
			(xy 460.3115 -269.771368) (xy 460.311052 -269.78152) (xy 460.303267 -269.800272) (xy 460.288878 -269.814596)
			(xy 460.270092 -269.822297) (xy 460.259938 -269.822676) (xy 458.860398 -269.822676) (xy 458.850273 -269.822175)
			(xy 458.831555 -269.81445) (xy 458.817199 -269.800168) (xy 458.809377 -269.78149) (xy 458.808836 -269.771368)
			(xy 452.7677 -269.771368) (xy 452.767252 -269.78152) (xy 452.759467 -269.800272) (xy 452.745078 -269.814596)
			(xy 452.726292 -269.822297) (xy 452.716138 -269.822676) (xy 451.316598 -269.822676) (xy 451.306473 -269.822175)
			(xy 451.287755 -269.81445) (xy 451.273399 -269.800168) (xy 451.265577 -269.78149) (xy 451.265036 -269.771368)
			(xy 445.2239 -269.771368) (xy 445.223452 -269.78152) (xy 445.215667 -269.800272) (xy 445.201278 -269.814596)
			(xy 445.182492 -269.822297) (xy 445.172338 -269.822676) (xy 443.772798 -269.822676) (xy 443.762673 -269.822175)
			(xy 443.743955 -269.81445) (xy 443.729599 -269.800168) (xy 443.721777 -269.78149) (xy 443.721236 -269.771368)
			(xy 437.6801 -269.771368) (xy 437.679652 -269.78152) (xy 437.671867 -269.800272) (xy 437.657478 -269.814596)
			(xy 437.638692 -269.822297) (xy 437.628538 -269.822676) (xy 436.228998 -269.822676) (xy 436.218873 -269.822175)
			(xy 436.200155 -269.81445) (xy 436.185799 -269.800168) (xy 436.177977 -269.78149) (xy 436.177436 -269.771368)
			(xy 430.1363 -269.771368) (xy 430.135852 -269.78152) (xy 430.128067 -269.800272) (xy 430.113678 -269.814596)
			(xy 430.094892 -269.822297) (xy 430.084738 -269.822676) (xy 428.685198 -269.822676) (xy 428.675073 -269.822175)
			(xy 428.656355 -269.81445) (xy 428.641999 -269.800168) (xy 428.634177 -269.78149) (xy 428.633636 -269.771368)
			(xy 422.5925 -269.771368) (xy 422.592052 -269.78152) (xy 422.584267 -269.800272) (xy 422.569878 -269.814596)
			(xy 422.551092 -269.822297) (xy 422.540938 -269.822676) (xy 421.141398 -269.822676) (xy 421.131273 -269.822175)
			(xy 421.112555 -269.81445) (xy 421.098199 -269.800168) (xy 421.090377 -269.78149) (xy 421.089836 -269.771368)
			(xy 415.0487 -269.771368) (xy 415.048252 -269.78152) (xy 415.040467 -269.800272) (xy 415.026078 -269.814596)
			(xy 415.007292 -269.822297) (xy 414.997138 -269.822676) (xy 413.597598 -269.822676) (xy 413.587473 -269.822175)
			(xy 413.568755 -269.81445) (xy 413.554399 -269.800168) (xy 413.546577 -269.78149) (xy 413.546036 -269.771368)
			(xy 407.5049 -269.771368) (xy 407.504452 -269.78152) (xy 407.496667 -269.800272) (xy 407.482278 -269.814596)
			(xy 407.463492 -269.822297) (xy 407.453338 -269.822676) (xy 406.053798 -269.822676) (xy 406.043673 -269.822175)
			(xy 406.024955 -269.81445) (xy 406.010599 -269.800168) (xy 406.002777 -269.78149) (xy 406.002236 -269.771368)
			(xy 309.6387 -269.771368) (xy 309.638252 -269.78152) (xy 309.630467 -269.800272) (xy 309.616078 -269.814596)
			(xy 309.597292 -269.822297) (xy 309.587138 -269.822676) (xy 308.187598 -269.822676) (xy 308.177473 -269.822175)
			(xy 308.158755 -269.81445) (xy 308.144399 -269.800168) (xy 308.136577 -269.78149) (xy 308.136036 -269.771368)
			(xy 302.0949 -269.771368) (xy 302.094452 -269.78152) (xy 302.086667 -269.800272) (xy 302.072278 -269.814596)
			(xy 302.053492 -269.822297) (xy 302.043338 -269.822676) (xy 300.643798 -269.822676) (xy 300.633673 -269.822175)
			(xy 300.614955 -269.81445) (xy 300.600599 -269.800168) (xy 300.592777 -269.78149) (xy 300.592236 -269.771368)
			(xy 294.5511 -269.771368) (xy 294.550652 -269.78152) (xy 294.542867 -269.800272) (xy 294.528478 -269.814596)
			(xy 294.509692 -269.822297) (xy 294.499538 -269.822676) (xy 293.099998 -269.822676) (xy 293.089873 -269.822175)
			(xy 293.071155 -269.81445) (xy 293.056799 -269.800168) (xy 293.048977 -269.78149) (xy 293.048436 -269.771368)
			(xy 287.0073 -269.771368) (xy 287.006852 -269.78152) (xy 286.999067 -269.800272) (xy 286.984678 -269.814596)
			(xy 286.965892 -269.822297) (xy 286.955738 -269.822676) (xy 285.556198 -269.822676) (xy 285.546073 -269.822175)
			(xy 285.527355 -269.81445) (xy 285.512999 -269.800168) (xy 285.505177 -269.78149) (xy 285.504636 -269.771368)
			(xy 279.4635 -269.771368) (xy 279.463052 -269.78152) (xy 279.455267 -269.800272) (xy 279.440878 -269.814596)
			(xy 279.422092 -269.822297) (xy 279.411938 -269.822676) (xy 278.012398 -269.822676) (xy 278.002273 -269.822175)
			(xy 277.983555 -269.81445) (xy 277.969199 -269.800168) (xy 277.961377 -269.78149) (xy 277.960836 -269.771368)
			(xy 271.9197 -269.771368) (xy 271.919252 -269.78152) (xy 271.911467 -269.800272) (xy 271.897078 -269.814596)
			(xy 271.878292 -269.822297) (xy 271.868138 -269.822676) (xy 270.468598 -269.822676) (xy 270.458473 -269.822175)
			(xy 270.439755 -269.81445) (xy 270.425399 -269.800168) (xy 270.417577 -269.78149) (xy 270.417036 -269.771368)
			(xy 264.3759 -269.771368) (xy 264.375452 -269.78152) (xy 264.367667 -269.800272) (xy 264.353278 -269.814596)
			(xy 264.334492 -269.822297) (xy 264.324338 -269.822676) (xy 262.924798 -269.822676) (xy 262.914673 -269.822175)
			(xy 262.895955 -269.81445) (xy 262.881599 -269.800168) (xy 262.873777 -269.78149) (xy 262.873236 -269.771368)
			(xy 256.8321 -269.771368) (xy 256.831652 -269.78152) (xy 256.823867 -269.800272) (xy 256.809478 -269.814596)
			(xy 256.790692 -269.822297) (xy 256.780538 -269.822676) (xy 255.380998 -269.822676) (xy 255.370873 -269.822175)
			(xy 255.352155 -269.81445) (xy 255.337799 -269.800168) (xy 255.329977 -269.78149) (xy 255.329436 -269.771368)
			(xy 212.371432 -269.771368) (xy 212.370953 -269.781516) (xy 212.363174 -269.800262) (xy 212.348795 -269.814585)
			(xy 212.33002 -269.822292) (xy 212.31987 -269.822676) (xy 210.92033 -269.822676) (xy 210.910207 -269.82215)
			(xy 210.89149 -269.814435) (xy 210.877133 -269.80016) (xy 210.86931 -269.781488) (xy 210.868768 -269.771368)
			(xy 204.827632 -269.771368) (xy 204.827153 -269.781516) (xy 204.819374 -269.800262) (xy 204.804995 -269.814585)
			(xy 204.78622 -269.822292) (xy 204.77607 -269.822676) (xy 203.37653 -269.822676) (xy 203.366407 -269.82215)
			(xy 203.34769 -269.814435) (xy 203.333333 -269.80016) (xy 203.32551 -269.781488) (xy 203.324968 -269.771368)
			(xy 197.283832 -269.771368) (xy 197.283353 -269.781516) (xy 197.275574 -269.800262) (xy 197.261195 -269.814585)
			(xy 197.24242 -269.822292) (xy 197.23227 -269.822676) (xy 195.83273 -269.822676) (xy 195.822607 -269.82215)
			(xy 195.80389 -269.814435) (xy 195.789533 -269.80016) (xy 195.78171 -269.781488) (xy 195.781168 -269.771368)
			(xy 189.740032 -269.771368) (xy 189.739553 -269.781516) (xy 189.731774 -269.800262) (xy 189.717395 -269.814585)
			(xy 189.69862 -269.822292) (xy 189.68847 -269.822676) (xy 188.28893 -269.822676) (xy 188.278807 -269.82215)
			(xy 188.26009 -269.814435) (xy 188.245733 -269.80016) (xy 188.23791 -269.781488) (xy 188.237368 -269.771368)
			(xy 182.196232 -269.771368) (xy 182.195753 -269.781516) (xy 182.187974 -269.800262) (xy 182.173595 -269.814585)
			(xy 182.15482 -269.822292) (xy 182.14467 -269.822676) (xy 180.74513 -269.822676) (xy 180.735007 -269.82215)
			(xy 180.71629 -269.814435) (xy 180.701933 -269.80016) (xy 180.69411 -269.781488) (xy 180.693568 -269.771368)
			(xy 174.652432 -269.771368) (xy 174.651953 -269.781516) (xy 174.644174 -269.800262) (xy 174.629795 -269.814585)
			(xy 174.61102 -269.822292) (xy 174.60087 -269.822676) (xy 173.20133 -269.822676) (xy 173.191207 -269.82215)
			(xy 173.17249 -269.814435) (xy 173.158133 -269.80016) (xy 173.15031 -269.781488) (xy 173.149768 -269.771368)
			(xy 167.108632 -269.771368) (xy 167.108153 -269.781516) (xy 167.100374 -269.800262) (xy 167.085995 -269.814585)
			(xy 167.06722 -269.822292) (xy 167.05707 -269.822676) (xy 165.65753 -269.822676) (xy 165.647407 -269.82215)
			(xy 165.62869 -269.814435) (xy 165.614333 -269.80016) (xy 165.60651 -269.781488) (xy 165.605968 -269.771368)
			(xy 159.564832 -269.771368) (xy 159.564353 -269.781516) (xy 159.556574 -269.800262) (xy 159.542195 -269.814585)
			(xy 159.52342 -269.822292) (xy 159.51327 -269.822676) (xy 158.11373 -269.822676) (xy 158.103607 -269.82215)
			(xy 158.08489 -269.814435) (xy 158.070533 -269.80016) (xy 158.06271 -269.781488) (xy 158.062168 -269.771368)
			(xy 61.698632 -269.771368) (xy 61.698153 -269.781516) (xy 61.690374 -269.800262) (xy 61.675995 -269.814585)
			(xy 61.65722 -269.822292) (xy 61.64707 -269.822676) (xy 60.24753 -269.822676) (xy 60.237407 -269.82215)
			(xy 60.21869 -269.814435) (xy 60.204333 -269.80016) (xy 60.19651 -269.781488) (xy 60.195968 -269.771368)
			(xy 54.154832 -269.771368) (xy 54.154353 -269.781516) (xy 54.146574 -269.800262) (xy 54.132195 -269.814585)
			(xy 54.11342 -269.822292) (xy 54.10327 -269.822676) (xy 52.70373 -269.822676) (xy 52.693607 -269.82215)
			(xy 52.67489 -269.814435) (xy 52.660533 -269.80016) (xy 52.65271 -269.781488) (xy 52.652168 -269.771368)
			(xy 46.611032 -269.771368) (xy 46.610553 -269.781516) (xy 46.602774 -269.800262) (xy 46.588395 -269.814585)
			(xy 46.56962 -269.822292) (xy 46.55947 -269.822676) (xy 45.15993 -269.822676) (xy 45.149807 -269.82215)
			(xy 45.13109 -269.814435) (xy 45.116733 -269.80016) (xy 45.10891 -269.781488) (xy 45.108368 -269.771368)
			(xy 39.067232 -269.771368) (xy 39.066753 -269.781516) (xy 39.058974 -269.800262) (xy 39.044595 -269.814585)
			(xy 39.02582 -269.822292) (xy 39.01567 -269.822676) (xy 37.61613 -269.822676) (xy 37.606007 -269.82215)
			(xy 37.58729 -269.814435) (xy 37.572933 -269.80016) (xy 37.56511 -269.781488) (xy 37.564568 -269.771368)
			(xy 31.523432 -269.771368) (xy 31.522953 -269.781516) (xy 31.515174 -269.800262) (xy 31.500795 -269.814585)
			(xy 31.48202 -269.822292) (xy 31.47187 -269.822676) (xy 30.07233 -269.822676) (xy 30.062207 -269.82215)
			(xy 30.04349 -269.814435) (xy 30.029133 -269.80016) (xy 30.02131 -269.781488) (xy 30.020768 -269.771368)
			(xy 23.979632 -269.771368) (xy 23.979153 -269.781516) (xy 23.971374 -269.800262) (xy 23.956995 -269.814585)
			(xy 23.93822 -269.822292) (xy 23.92807 -269.822676) (xy 22.52853 -269.822676) (xy 22.518407 -269.82215)
			(xy 22.49969 -269.814435) (xy 22.485333 -269.80016) (xy 22.47751 -269.781488) (xy 22.476968 -269.771368)
			(xy 16.435832 -269.771368) (xy 16.435353 -269.781516) (xy 16.427574 -269.800262) (xy 16.413195 -269.814585)
			(xy 16.39442 -269.822292) (xy 16.38427 -269.822676) (xy 14.98473 -269.822676) (xy 14.974607 -269.82215)
			(xy 14.95589 -269.814435) (xy 14.941533 -269.80016) (xy 14.93371 -269.781488) (xy 14.933168 -269.771368)
			(xy 8.892032 -269.771368) (xy 8.891553 -269.781516) (xy 8.883774 -269.800262) (xy 8.869395 -269.814585)
			(xy 8.85062 -269.822292) (xy 8.84047 -269.822676) (xy 7.44093 -269.822676) (xy 7.430807 -269.82215)
			(xy 7.41209 -269.814435) (xy 7.397733 -269.80016) (xy 7.38991 -269.781488) (xy 7.389368 -269.771368)
			(xy 2.509012 -269.771368) (xy 2.509012 -270.621506) (xy 11.489436 -270.621506) (xy 11.489436 -270.212566)
			(xy 11.489905 -270.202406) (xy 11.497691 -270.183637) (xy 11.512064 -270.169273) (xy 11.530838 -270.161499)
			(xy 11.540998 -270.161004) (xy 12.940538 -270.161004) (xy 12.950694 -270.161501) (xy 12.969458 -270.169282)
			(xy 12.98382 -270.183646) (xy 12.991599 -270.20241) (xy 12.9921 -270.212566) (xy 12.9921 -270.621506)
			(xy 19.033236 -270.621506) (xy 19.033236 -270.212566) (xy 19.033705 -270.202406) (xy 19.041491 -270.183637)
			(xy 19.055864 -270.169273) (xy 19.074638 -270.161499) (xy 19.084798 -270.161004) (xy 20.484338 -270.161004)
			(xy 20.494494 -270.161501) (xy 20.513258 -270.169282) (xy 20.52762 -270.183646) (xy 20.535399 -270.20241)
			(xy 20.5359 -270.212566) (xy 20.5359 -270.621506) (xy 26.577036 -270.621506) (xy 26.577036 -270.212566)
			(xy 26.577505 -270.202406) (xy 26.585291 -270.183637) (xy 26.599664 -270.169273) (xy 26.618438 -270.161499)
			(xy 26.628598 -270.161004) (xy 28.028138 -270.161004) (xy 28.038294 -270.161501) (xy 28.057058 -270.169282)
			(xy 28.07142 -270.183646) (xy 28.079199 -270.20241) (xy 28.0797 -270.212566) (xy 28.0797 -270.621506)
			(xy 34.120836 -270.621506) (xy 34.120836 -270.212566) (xy 34.121305 -270.202406) (xy 34.129091 -270.183637)
			(xy 34.143464 -270.169273) (xy 34.162238 -270.161499) (xy 34.172398 -270.161004) (xy 35.571938 -270.161004)
			(xy 35.582094 -270.161501) (xy 35.600858 -270.169282) (xy 35.61522 -270.183646) (xy 35.622999 -270.20241)
			(xy 35.6235 -270.212566) (xy 35.6235 -270.621506) (xy 41.664636 -270.621506) (xy 41.664636 -270.212566)
			(xy 41.665105 -270.202406) (xy 41.672891 -270.183637) (xy 41.687264 -270.169273) (xy 41.706038 -270.161499)
			(xy 41.716198 -270.161004) (xy 43.115738 -270.161004) (xy 43.125894 -270.161501) (xy 43.144658 -270.169282)
			(xy 43.15902 -270.183646) (xy 43.166799 -270.20241) (xy 43.1673 -270.212566) (xy 43.1673 -270.621506)
			(xy 49.208436 -270.621506) (xy 49.208436 -270.212566) (xy 49.208905 -270.202406) (xy 49.216691 -270.183637)
			(xy 49.231064 -270.169273) (xy 49.249838 -270.161499) (xy 49.259998 -270.161004) (xy 50.659538 -270.161004)
			(xy 50.669694 -270.161501) (xy 50.688458 -270.169282) (xy 50.70282 -270.183646) (xy 50.710599 -270.20241)
			(xy 50.7111 -270.212566) (xy 50.7111 -270.621506) (xy 56.752236 -270.621506) (xy 56.752236 -270.212566)
			(xy 56.752705 -270.202406) (xy 56.760491 -270.183637) (xy 56.774864 -270.169273) (xy 56.793638 -270.161499)
			(xy 56.803798 -270.161004) (xy 58.203338 -270.161004) (xy 58.213494 -270.161501) (xy 58.232258 -270.169282)
			(xy 58.24662 -270.183646) (xy 58.254399 -270.20241) (xy 58.2549 -270.212566) (xy 58.2549 -270.621506)
			(xy 64.296036 -270.621506) (xy 64.296036 -270.212566) (xy 64.296505 -270.202406) (xy 64.304291 -270.183637)
			(xy 64.318664 -270.169273) (xy 64.337438 -270.161499) (xy 64.347598 -270.161004) (xy 65.747138 -270.161004)
			(xy 65.757294 -270.161501) (xy 65.776058 -270.169282) (xy 65.79042 -270.183646) (xy 65.798199 -270.20241)
			(xy 65.7987 -270.212566) (xy 65.7987 -270.621506) (xy 162.162236 -270.621506) (xy 162.162236 -270.212566)
			(xy 162.162705 -270.202406) (xy 162.170491 -270.183637) (xy 162.184864 -270.169273) (xy 162.203638 -270.161499)
			(xy 162.213798 -270.161004) (xy 163.613338 -270.161004) (xy 163.623494 -270.161501) (xy 163.642258 -270.169282)
			(xy 163.65662 -270.183646) (xy 163.664399 -270.20241) (xy 163.6649 -270.212566) (xy 163.6649 -270.621506)
			(xy 169.706036 -270.621506) (xy 169.706036 -270.212566) (xy 169.706505 -270.202406) (xy 169.714291 -270.183637)
			(xy 169.728664 -270.169273) (xy 169.747438 -270.161499) (xy 169.757598 -270.161004) (xy 171.157138 -270.161004)
			(xy 171.167294 -270.161501) (xy 171.186058 -270.169282) (xy 171.20042 -270.183646) (xy 171.208199 -270.20241)
			(xy 171.2087 -270.212566) (xy 171.2087 -270.621506) (xy 177.249836 -270.621506) (xy 177.249836 -270.212566)
			(xy 177.250305 -270.202406) (xy 177.258091 -270.183637) (xy 177.272464 -270.169273) (xy 177.291238 -270.161499)
			(xy 177.301398 -270.161004) (xy 178.700938 -270.161004) (xy 178.711094 -270.161501) (xy 178.729858 -270.169282)
			(xy 178.74422 -270.183646) (xy 178.751999 -270.20241) (xy 178.7525 -270.212566) (xy 178.7525 -270.621506)
			(xy 184.793636 -270.621506) (xy 184.793636 -270.212566) (xy 184.794105 -270.202406) (xy 184.801891 -270.183637)
			(xy 184.816264 -270.169273) (xy 184.835038 -270.161499) (xy 184.845198 -270.161004) (xy 186.244738 -270.161004)
			(xy 186.254894 -270.161501) (xy 186.273658 -270.169282) (xy 186.28802 -270.183646) (xy 186.295799 -270.20241)
			(xy 186.2963 -270.212566) (xy 186.2963 -270.621506) (xy 192.337436 -270.621506) (xy 192.337436 -270.212566)
			(xy 192.337905 -270.202406) (xy 192.345691 -270.183637) (xy 192.360064 -270.169273) (xy 192.378838 -270.161499)
			(xy 192.388998 -270.161004) (xy 193.788538 -270.161004) (xy 193.798694 -270.161501) (xy 193.817458 -270.169282)
			(xy 193.83182 -270.183646) (xy 193.839599 -270.20241) (xy 193.8401 -270.212566) (xy 193.8401 -270.621506)
			(xy 199.881236 -270.621506) (xy 199.881236 -270.212566) (xy 199.881705 -270.202406) (xy 199.889491 -270.183637)
			(xy 199.903864 -270.169273) (xy 199.922638 -270.161499) (xy 199.932798 -270.161004) (xy 201.332338 -270.161004)
			(xy 201.342494 -270.161501) (xy 201.361258 -270.169282) (xy 201.37562 -270.183646) (xy 201.383399 -270.20241)
			(xy 201.3839 -270.212566) (xy 201.3839 -270.621506) (xy 207.425036 -270.621506) (xy 207.425036 -270.212566)
			(xy 207.425505 -270.202406) (xy 207.433291 -270.183637) (xy 207.447664 -270.169273) (xy 207.466438 -270.161499)
			(xy 207.476598 -270.161004) (xy 208.876138 -270.161004) (xy 208.886294 -270.161501) (xy 208.905058 -270.169282)
			(xy 208.91942 -270.183646) (xy 208.927199 -270.20241) (xy 208.9277 -270.212566) (xy 208.9277 -270.621506)
			(xy 214.968836 -270.621506) (xy 214.968836 -270.212566) (xy 214.969305 -270.202406) (xy 214.977091 -270.183637)
			(xy 214.991464 -270.169273) (xy 215.010238 -270.161499) (xy 215.020398 -270.161004) (xy 216.419938 -270.161004)
			(xy 216.430094 -270.161501) (xy 216.448858 -270.169282) (xy 216.46322 -270.183646) (xy 216.470999 -270.20241)
			(xy 216.4715 -270.212566) (xy 216.4715 -270.621506) (xy 259.429504 -270.621506) (xy 259.429504 -270.212566)
			(xy 259.430005 -270.20241) (xy 259.437784 -270.183647) (xy 259.452147 -270.169284) (xy 259.47091 -270.161505)
			(xy 259.481066 -270.161004) (xy 260.880606 -270.161004) (xy 260.89076 -270.161528) (xy 260.909523 -270.169298)
			(xy 260.923886 -270.183654) (xy 260.931667 -270.202412) (xy 260.932168 -270.212566) (xy 260.932168 -270.621506)
			(xy 266.973304 -270.621506) (xy 266.973304 -270.212566) (xy 266.973805 -270.20241) (xy 266.981584 -270.183647)
			(xy 266.995947 -270.169284) (xy 267.01471 -270.161505) (xy 267.024866 -270.161004) (xy 268.424406 -270.161004)
			(xy 268.43456 -270.161528) (xy 268.453323 -270.169298) (xy 268.467686 -270.183654) (xy 268.475467 -270.202412)
			(xy 268.475968 -270.212566) (xy 268.475968 -270.621506) (xy 274.517104 -270.621506) (xy 274.517104 -270.212566)
			(xy 274.517605 -270.20241) (xy 274.525384 -270.183647) (xy 274.539747 -270.169284) (xy 274.55851 -270.161505)
			(xy 274.568666 -270.161004) (xy 275.968206 -270.161004) (xy 275.97836 -270.161528) (xy 275.997123 -270.169298)
			(xy 276.011486 -270.183654) (xy 276.019267 -270.202412) (xy 276.019768 -270.212566) (xy 276.019768 -270.621506)
			(xy 282.060904 -270.621506) (xy 282.060904 -270.212566) (xy 282.061405 -270.20241) (xy 282.069184 -270.183647)
			(xy 282.083547 -270.169284) (xy 282.10231 -270.161505) (xy 282.112466 -270.161004) (xy 283.512006 -270.161004)
			(xy 283.52216 -270.161528) (xy 283.540923 -270.169298) (xy 283.555286 -270.183654) (xy 283.563067 -270.202412)
			(xy 283.563568 -270.212566) (xy 283.563568 -270.621506) (xy 289.604704 -270.621506) (xy 289.604704 -270.212566)
			(xy 289.605205 -270.20241) (xy 289.612984 -270.183647) (xy 289.627347 -270.169284) (xy 289.64611 -270.161505)
			(xy 289.656266 -270.161004) (xy 291.055806 -270.161004) (xy 291.06596 -270.161528) (xy 291.084723 -270.169298)
			(xy 291.099086 -270.183654) (xy 291.106867 -270.202412) (xy 291.107368 -270.212566) (xy 291.107368 -270.621506)
			(xy 297.148504 -270.621506) (xy 297.148504 -270.212566) (xy 297.149005 -270.20241) (xy 297.156784 -270.183647)
			(xy 297.171147 -270.169284) (xy 297.18991 -270.161505) (xy 297.200066 -270.161004) (xy 298.599606 -270.161004)
			(xy 298.60976 -270.161528) (xy 298.628523 -270.169298) (xy 298.642886 -270.183654) (xy 298.650667 -270.202412)
			(xy 298.651168 -270.212566) (xy 298.651168 -270.621506) (xy 304.692304 -270.621506) (xy 304.692304 -270.212566)
			(xy 304.692805 -270.20241) (xy 304.700584 -270.183647) (xy 304.714947 -270.169284) (xy 304.73371 -270.161505)
			(xy 304.743866 -270.161004) (xy 306.143406 -270.161004) (xy 306.15356 -270.161528) (xy 306.172323 -270.169298)
			(xy 306.186686 -270.183654) (xy 306.194467 -270.202412) (xy 306.194968 -270.212566) (xy 306.194968 -270.621506)
			(xy 312.236104 -270.621506) (xy 312.236104 -270.212566) (xy 312.236605 -270.20241) (xy 312.244384 -270.183647)
			(xy 312.258747 -270.169284) (xy 312.27751 -270.161505) (xy 312.287666 -270.161004) (xy 313.687206 -270.161004)
			(xy 313.69736 -270.161528) (xy 313.716123 -270.169298) (xy 313.730486 -270.183654) (xy 313.738267 -270.202412)
			(xy 313.738768 -270.212566) (xy 313.738768 -270.621506) (xy 410.102304 -270.621506) (xy 410.102304 -270.212566)
			(xy 410.102805 -270.20241) (xy 410.110584 -270.183647) (xy 410.124947 -270.169284) (xy 410.14371 -270.161505)
			(xy 410.153866 -270.161004) (xy 411.553406 -270.161004) (xy 411.56356 -270.161528) (xy 411.582323 -270.169298)
			(xy 411.596686 -270.183654) (xy 411.604467 -270.202412) (xy 411.604968 -270.212566) (xy 411.604968 -270.621506)
			(xy 417.646104 -270.621506) (xy 417.646104 -270.212566) (xy 417.646605 -270.20241) (xy 417.654384 -270.183647)
			(xy 417.668747 -270.169284) (xy 417.68751 -270.161505) (xy 417.697666 -270.161004) (xy 419.097206 -270.161004)
			(xy 419.10736 -270.161528) (xy 419.126123 -270.169298) (xy 419.140486 -270.183654) (xy 419.148267 -270.202412)
			(xy 419.148768 -270.212566) (xy 419.148768 -270.621506) (xy 425.189904 -270.621506) (xy 425.189904 -270.212566)
			(xy 425.190405 -270.20241) (xy 425.198184 -270.183647) (xy 425.212547 -270.169284) (xy 425.23131 -270.161505)
			(xy 425.241466 -270.161004) (xy 426.641006 -270.161004) (xy 426.65116 -270.161528) (xy 426.669923 -270.169298)
			(xy 426.684286 -270.183654) (xy 426.692067 -270.202412) (xy 426.692568 -270.212566) (xy 426.692568 -270.621506)
			(xy 432.733704 -270.621506) (xy 432.733704 -270.212566) (xy 432.734205 -270.20241) (xy 432.741984 -270.183647)
			(xy 432.756347 -270.169284) (xy 432.77511 -270.161505) (xy 432.785266 -270.161004) (xy 434.184806 -270.161004)
			(xy 434.19496 -270.161528) (xy 434.213723 -270.169298) (xy 434.228086 -270.183654) (xy 434.235867 -270.202412)
			(xy 434.236368 -270.212566) (xy 434.236368 -270.621506) (xy 440.277504 -270.621506) (xy 440.277504 -270.212566)
			(xy 440.278005 -270.20241) (xy 440.285784 -270.183647) (xy 440.300147 -270.169284) (xy 440.31891 -270.161505)
			(xy 440.329066 -270.161004) (xy 441.728606 -270.161004) (xy 441.73876 -270.161528) (xy 441.757523 -270.169298)
			(xy 441.771886 -270.183654) (xy 441.779667 -270.202412) (xy 441.780168 -270.212566) (xy 441.780168 -270.621506)
			(xy 447.821304 -270.621506) (xy 447.821304 -270.212566) (xy 447.821805 -270.20241) (xy 447.829584 -270.183647)
			(xy 447.843947 -270.169284) (xy 447.86271 -270.161505) (xy 447.872866 -270.161004) (xy 449.272406 -270.161004)
			(xy 449.28256 -270.161528) (xy 449.301323 -270.169298) (xy 449.315686 -270.183654) (xy 449.323467 -270.202412)
			(xy 449.323968 -270.212566) (xy 449.323968 -270.621506) (xy 455.365104 -270.621506) (xy 455.365104 -270.212566)
			(xy 455.365605 -270.20241) (xy 455.373384 -270.183647) (xy 455.387747 -270.169284) (xy 455.40651 -270.161505)
			(xy 455.416666 -270.161004) (xy 456.816206 -270.161004) (xy 456.82636 -270.161528) (xy 456.845123 -270.169298)
			(xy 456.859486 -270.183654) (xy 456.867267 -270.202412) (xy 456.867768 -270.212566) (xy 456.867768 -270.621506)
			(xy 462.908904 -270.621506) (xy 462.908904 -270.212566) (xy 462.909405 -270.20241) (xy 462.917184 -270.183647)
			(xy 462.931547 -270.169284) (xy 462.95031 -270.161505) (xy 462.960466 -270.161004) (xy 464.360006 -270.161004)
			(xy 464.37016 -270.161528) (xy 464.388923 -270.169298) (xy 464.403286 -270.183654) (xy 464.411067 -270.202412)
			(xy 464.411568 -270.212566) (xy 464.411568 -270.621506) (xy 464.411072 -270.631663) (xy 464.403296 -270.650431)
			(xy 464.388931 -270.664796) (xy 464.370163 -270.672572) (xy 464.360006 -270.673068) (xy 462.960466 -270.673068)
			(xy 462.950307 -270.672595) (xy 462.931538 -270.66481) (xy 462.917174 -270.650438) (xy 462.9094 -270.631665)
			(xy 462.908904 -270.621506) (xy 456.867768 -270.621506) (xy 456.867272 -270.631663) (xy 456.859496 -270.650431)
			(xy 456.845131 -270.664796) (xy 456.826363 -270.672572) (xy 456.816206 -270.673068) (xy 455.416666 -270.673068)
			(xy 455.406507 -270.672595) (xy 455.387738 -270.66481) (xy 455.373374 -270.650438) (xy 455.3656 -270.631665)
			(xy 455.365104 -270.621506) (xy 449.323968 -270.621506) (xy 449.323472 -270.631663) (xy 449.315696 -270.650431)
			(xy 449.301331 -270.664796) (xy 449.282563 -270.672572) (xy 449.272406 -270.673068) (xy 447.872866 -270.673068)
			(xy 447.862707 -270.672595) (xy 447.843938 -270.66481) (xy 447.829574 -270.650438) (xy 447.8218 -270.631665)
			(xy 447.821304 -270.621506) (xy 441.780168 -270.621506) (xy 441.779672 -270.631663) (xy 441.771896 -270.650431)
			(xy 441.757531 -270.664796) (xy 441.738763 -270.672572) (xy 441.728606 -270.673068) (xy 440.329066 -270.673068)
			(xy 440.318907 -270.672595) (xy 440.300138 -270.66481) (xy 440.285774 -270.650438) (xy 440.278 -270.631665)
			(xy 440.277504 -270.621506) (xy 434.236368 -270.621506) (xy 434.235872 -270.631663) (xy 434.228096 -270.650431)
			(xy 434.213731 -270.664796) (xy 434.194963 -270.672572) (xy 434.184806 -270.673068) (xy 432.785266 -270.673068)
			(xy 432.775107 -270.672595) (xy 432.756338 -270.66481) (xy 432.741974 -270.650438) (xy 432.7342 -270.631665)
			(xy 432.733704 -270.621506) (xy 426.692568 -270.621506) (xy 426.692072 -270.631663) (xy 426.684296 -270.650431)
			(xy 426.669931 -270.664796) (xy 426.651163 -270.672572) (xy 426.641006 -270.673068) (xy 425.241466 -270.673068)
			(xy 425.231307 -270.672595) (xy 425.212538 -270.66481) (xy 425.198174 -270.650438) (xy 425.1904 -270.631665)
			(xy 425.189904 -270.621506) (xy 419.148768 -270.621506) (xy 419.148272 -270.631663) (xy 419.140496 -270.650431)
			(xy 419.126131 -270.664796) (xy 419.107363 -270.672572) (xy 419.097206 -270.673068) (xy 417.697666 -270.673068)
			(xy 417.687507 -270.672595) (xy 417.668738 -270.66481) (xy 417.654374 -270.650438) (xy 417.6466 -270.631665)
			(xy 417.646104 -270.621506) (xy 411.604968 -270.621506) (xy 411.604472 -270.631663) (xy 411.596696 -270.650431)
			(xy 411.582331 -270.664796) (xy 411.563563 -270.672572) (xy 411.553406 -270.673068) (xy 410.153866 -270.673068)
			(xy 410.143707 -270.672595) (xy 410.124938 -270.66481) (xy 410.110574 -270.650438) (xy 410.1028 -270.631665)
			(xy 410.102304 -270.621506) (xy 313.738768 -270.621506) (xy 313.738272 -270.631663) (xy 313.730496 -270.650431)
			(xy 313.716131 -270.664796) (xy 313.697363 -270.672572) (xy 313.687206 -270.673068) (xy 312.287666 -270.673068)
			(xy 312.277507 -270.672595) (xy 312.258738 -270.66481) (xy 312.244374 -270.650438) (xy 312.2366 -270.631665)
			(xy 312.236104 -270.621506) (xy 306.194968 -270.621506) (xy 306.194472 -270.631663) (xy 306.186696 -270.650431)
			(xy 306.172331 -270.664796) (xy 306.153563 -270.672572) (xy 306.143406 -270.673068) (xy 304.743866 -270.673068)
			(xy 304.733707 -270.672595) (xy 304.714938 -270.66481) (xy 304.700574 -270.650438) (xy 304.6928 -270.631665)
			(xy 304.692304 -270.621506) (xy 298.651168 -270.621506) (xy 298.650672 -270.631663) (xy 298.642896 -270.650431)
			(xy 298.628531 -270.664796) (xy 298.609763 -270.672572) (xy 298.599606 -270.673068) (xy 297.200066 -270.673068)
			(xy 297.189907 -270.672595) (xy 297.171138 -270.66481) (xy 297.156774 -270.650438) (xy 297.149 -270.631665)
			(xy 297.148504 -270.621506) (xy 291.107368 -270.621506) (xy 291.106872 -270.631663) (xy 291.099096 -270.650431)
			(xy 291.084731 -270.664796) (xy 291.065963 -270.672572) (xy 291.055806 -270.673068) (xy 289.656266 -270.673068)
			(xy 289.646107 -270.672595) (xy 289.627338 -270.66481) (xy 289.612974 -270.650438) (xy 289.6052 -270.631665)
			(xy 289.604704 -270.621506) (xy 283.563568 -270.621506) (xy 283.563072 -270.631663) (xy 283.555296 -270.650431)
			(xy 283.540931 -270.664796) (xy 283.522163 -270.672572) (xy 283.512006 -270.673068) (xy 282.112466 -270.673068)
			(xy 282.102307 -270.672595) (xy 282.083538 -270.66481) (xy 282.069174 -270.650438) (xy 282.0614 -270.631665)
			(xy 282.060904 -270.621506) (xy 276.019768 -270.621506) (xy 276.019272 -270.631663) (xy 276.011496 -270.650431)
			(xy 275.997131 -270.664796) (xy 275.978363 -270.672572) (xy 275.968206 -270.673068) (xy 274.568666 -270.673068)
			(xy 274.558507 -270.672595) (xy 274.539738 -270.66481) (xy 274.525374 -270.650438) (xy 274.5176 -270.631665)
			(xy 274.517104 -270.621506) (xy 268.475968 -270.621506) (xy 268.475472 -270.631663) (xy 268.467696 -270.650431)
			(xy 268.453331 -270.664796) (xy 268.434563 -270.672572) (xy 268.424406 -270.673068) (xy 267.024866 -270.673068)
			(xy 267.014707 -270.672595) (xy 266.995938 -270.66481) (xy 266.981574 -270.650438) (xy 266.9738 -270.631665)
			(xy 266.973304 -270.621506) (xy 260.932168 -270.621506) (xy 260.931672 -270.631663) (xy 260.923896 -270.650431)
			(xy 260.909531 -270.664796) (xy 260.890763 -270.672572) (xy 260.880606 -270.673068) (xy 259.481066 -270.673068)
			(xy 259.470907 -270.672595) (xy 259.452138 -270.66481) (xy 259.437774 -270.650438) (xy 259.43 -270.631665)
			(xy 259.429504 -270.621506) (xy 216.4715 -270.621506) (xy 216.470972 -270.631659) (xy 216.463203 -270.650421)
			(xy 216.448848 -270.664785) (xy 216.430091 -270.672566) (xy 216.419938 -270.673068) (xy 215.020398 -270.673068)
			(xy 215.010241 -270.672568) (xy 214.991473 -270.664794) (xy 214.977108 -270.650431) (xy 214.969332 -270.631663)
			(xy 214.968836 -270.621506) (xy 208.9277 -270.621506) (xy 208.927172 -270.631659) (xy 208.919403 -270.650421)
			(xy 208.905048 -270.664785) (xy 208.886291 -270.672566) (xy 208.876138 -270.673068) (xy 207.476598 -270.673068)
			(xy 207.466441 -270.672568) (xy 207.447673 -270.664794) (xy 207.433308 -270.650431) (xy 207.425532 -270.631663)
			(xy 207.425036 -270.621506) (xy 201.3839 -270.621506) (xy 201.383372 -270.631659) (xy 201.375603 -270.650421)
			(xy 201.361248 -270.664785) (xy 201.342491 -270.672566) (xy 201.332338 -270.673068) (xy 199.932798 -270.673068)
			(xy 199.922641 -270.672568) (xy 199.903873 -270.664794) (xy 199.889508 -270.650431) (xy 199.881732 -270.631663)
			(xy 199.881236 -270.621506) (xy 193.8401 -270.621506) (xy 193.839572 -270.631659) (xy 193.831803 -270.650421)
			(xy 193.817448 -270.664785) (xy 193.798691 -270.672566) (xy 193.788538 -270.673068) (xy 192.388998 -270.673068)
			(xy 192.378841 -270.672568) (xy 192.360073 -270.664794) (xy 192.345708 -270.650431) (xy 192.337932 -270.631663)
			(xy 192.337436 -270.621506) (xy 186.2963 -270.621506) (xy 186.295772 -270.631659) (xy 186.288003 -270.650421)
			(xy 186.273648 -270.664785) (xy 186.254891 -270.672566) (xy 186.244738 -270.673068) (xy 184.845198 -270.673068)
			(xy 184.835041 -270.672568) (xy 184.816273 -270.664794) (xy 184.801908 -270.650431) (xy 184.794132 -270.631663)
			(xy 184.793636 -270.621506) (xy 178.7525 -270.621506) (xy 178.751972 -270.631659) (xy 178.744203 -270.650421)
			(xy 178.729848 -270.664785) (xy 178.711091 -270.672566) (xy 178.700938 -270.673068) (xy 177.301398 -270.673068)
			(xy 177.291241 -270.672568) (xy 177.272473 -270.664794) (xy 177.258108 -270.650431) (xy 177.250332 -270.631663)
			(xy 177.249836 -270.621506) (xy 171.2087 -270.621506) (xy 171.208172 -270.631659) (xy 171.200403 -270.650421)
			(xy 171.186048 -270.664785) (xy 171.167291 -270.672566) (xy 171.157138 -270.673068) (xy 169.757598 -270.673068)
			(xy 169.747441 -270.672568) (xy 169.728673 -270.664794) (xy 169.714308 -270.650431) (xy 169.706532 -270.631663)
			(xy 169.706036 -270.621506) (xy 163.6649 -270.621506) (xy 163.664372 -270.631659) (xy 163.656603 -270.650421)
			(xy 163.642248 -270.664785) (xy 163.623491 -270.672566) (xy 163.613338 -270.673068) (xy 162.213798 -270.673068)
			(xy 162.203641 -270.672568) (xy 162.184873 -270.664794) (xy 162.170508 -270.650431) (xy 162.162732 -270.631663)
			(xy 162.162236 -270.621506) (xy 65.7987 -270.621506) (xy 65.798172 -270.631659) (xy 65.790403 -270.650421)
			(xy 65.776048 -270.664785) (xy 65.757291 -270.672566) (xy 65.747138 -270.673068) (xy 64.347598 -270.673068)
			(xy 64.337441 -270.672568) (xy 64.318673 -270.664794) (xy 64.304308 -270.650431) (xy 64.296532 -270.631663)
			(xy 64.296036 -270.621506) (xy 58.2549 -270.621506) (xy 58.254372 -270.631659) (xy 58.246603 -270.650421)
			(xy 58.232248 -270.664785) (xy 58.213491 -270.672566) (xy 58.203338 -270.673068) (xy 56.803798 -270.673068)
			(xy 56.793641 -270.672568) (xy 56.774873 -270.664794) (xy 56.760508 -270.650431) (xy 56.752732 -270.631663)
			(xy 56.752236 -270.621506) (xy 50.7111 -270.621506) (xy 50.710572 -270.631659) (xy 50.702803 -270.650421)
			(xy 50.688448 -270.664785) (xy 50.669691 -270.672566) (xy 50.659538 -270.673068) (xy 49.259998 -270.673068)
			(xy 49.249841 -270.672568) (xy 49.231073 -270.664794) (xy 49.216708 -270.650431) (xy 49.208932 -270.631663)
			(xy 49.208436 -270.621506) (xy 43.1673 -270.621506) (xy 43.166772 -270.631659) (xy 43.159003 -270.650421)
			(xy 43.144648 -270.664785) (xy 43.125891 -270.672566) (xy 43.115738 -270.673068) (xy 41.716198 -270.673068)
			(xy 41.706041 -270.672568) (xy 41.687273 -270.664794) (xy 41.672908 -270.650431) (xy 41.665132 -270.631663)
			(xy 41.664636 -270.621506) (xy 35.6235 -270.621506) (xy 35.622972 -270.631659) (xy 35.615203 -270.650421)
			(xy 35.600848 -270.664785) (xy 35.582091 -270.672566) (xy 35.571938 -270.673068) (xy 34.172398 -270.673068)
			(xy 34.162241 -270.672568) (xy 34.143473 -270.664794) (xy 34.129108 -270.650431) (xy 34.121332 -270.631663)
			(xy 34.120836 -270.621506) (xy 28.0797 -270.621506) (xy 28.079172 -270.631659) (xy 28.071403 -270.650421)
			(xy 28.057048 -270.664785) (xy 28.038291 -270.672566) (xy 28.028138 -270.673068) (xy 26.628598 -270.673068)
			(xy 26.618441 -270.672568) (xy 26.599673 -270.664794) (xy 26.585308 -270.650431) (xy 26.577532 -270.631663)
			(xy 26.577036 -270.621506) (xy 20.5359 -270.621506) (xy 20.535372 -270.631659) (xy 20.527603 -270.650421)
			(xy 20.513248 -270.664785) (xy 20.494491 -270.672566) (xy 20.484338 -270.673068) (xy 19.084798 -270.673068)
			(xy 19.074641 -270.672568) (xy 19.055873 -270.664794) (xy 19.041508 -270.650431) (xy 19.033732 -270.631663)
			(xy 19.033236 -270.621506) (xy 12.9921 -270.621506) (xy 12.991572 -270.631659) (xy 12.983803 -270.650421)
			(xy 12.969448 -270.664785) (xy 12.950691 -270.672566) (xy 12.940538 -270.673068) (xy 11.540998 -270.673068)
			(xy 11.530841 -270.672568) (xy 11.512073 -270.664794) (xy 11.497708 -270.650431) (xy 11.489932 -270.631663)
			(xy 11.489436 -270.621506) (xy 2.509012 -270.621506) (xy 2.509012 -271.47139) (xy 7.389368 -271.47139)
			(xy 7.389368 -271.06245) (xy 7.389805 -271.052278) (xy 7.39758 -271.033479) (xy 7.411962 -271.019091)
			(xy 7.430758 -271.011309) (xy 7.44093 -271.010888) (xy 8.84047 -271.010888) (xy 8.850646 -271.01129)
			(xy 8.869449 -271.019074) (xy 8.883837 -271.033467) (xy 8.891614 -271.052274) (xy 8.892032 -271.06245)
			(xy 8.892032 -271.47139) (xy 14.933168 -271.47139) (xy 14.933168 -271.06245) (xy 14.933605 -271.052278)
			(xy 14.94138 -271.033479) (xy 14.955762 -271.019091) (xy 14.974558 -271.011309) (xy 14.98473 -271.010888)
			(xy 16.38427 -271.010888) (xy 16.394446 -271.01129) (xy 16.413249 -271.019074) (xy 16.427637 -271.033467)
			(xy 16.435414 -271.052274) (xy 16.435832 -271.06245) (xy 16.435832 -271.47139) (xy 22.476968 -271.47139)
			(xy 22.476968 -271.06245) (xy 22.477405 -271.052278) (xy 22.48518 -271.033479) (xy 22.499562 -271.019091)
			(xy 22.518358 -271.011309) (xy 22.52853 -271.010888) (xy 23.92807 -271.010888) (xy 23.938246 -271.01129)
			(xy 23.957049 -271.019074) (xy 23.971437 -271.033467) (xy 23.979214 -271.052274) (xy 23.979632 -271.06245)
			(xy 23.979632 -271.47139) (xy 30.020768 -271.47139) (xy 30.020768 -271.06245) (xy 30.021205 -271.052278)
			(xy 30.02898 -271.033479) (xy 30.043362 -271.019091) (xy 30.062158 -271.011309) (xy 30.07233 -271.010888)
			(xy 31.47187 -271.010888) (xy 31.482046 -271.01129) (xy 31.500849 -271.019074) (xy 31.515237 -271.033467)
			(xy 31.523014 -271.052274) (xy 31.523432 -271.06245) (xy 31.523432 -271.47139) (xy 37.564568 -271.47139)
			(xy 37.564568 -271.06245) (xy 37.565005 -271.052278) (xy 37.57278 -271.033479) (xy 37.587162 -271.019091)
			(xy 37.605958 -271.011309) (xy 37.61613 -271.010888) (xy 39.01567 -271.010888) (xy 39.025846 -271.01129)
			(xy 39.044649 -271.019074) (xy 39.059037 -271.033467) (xy 39.066814 -271.052274) (xy 39.067232 -271.06245)
			(xy 39.067232 -271.47139) (xy 45.108368 -271.47139) (xy 45.108368 -271.06245) (xy 45.108805 -271.052278)
			(xy 45.11658 -271.033479) (xy 45.130962 -271.019091) (xy 45.149758 -271.011309) (xy 45.15993 -271.010888)
			(xy 46.55947 -271.010888) (xy 46.569646 -271.01129) (xy 46.588449 -271.019074) (xy 46.602837 -271.033467)
			(xy 46.610614 -271.052274) (xy 46.611032 -271.06245) (xy 46.611032 -271.47139) (xy 52.652168 -271.47139)
			(xy 52.652168 -271.06245) (xy 52.652605 -271.052278) (xy 52.66038 -271.033479) (xy 52.674762 -271.019091)
			(xy 52.693558 -271.011309) (xy 52.70373 -271.010888) (xy 54.10327 -271.010888) (xy 54.113446 -271.01129)
			(xy 54.132249 -271.019074) (xy 54.146637 -271.033467) (xy 54.154414 -271.052274) (xy 54.154832 -271.06245)
			(xy 54.154832 -271.47139) (xy 60.195968 -271.47139) (xy 60.195968 -271.06245) (xy 60.196405 -271.052278)
			(xy 60.20418 -271.033479) (xy 60.218562 -271.019091) (xy 60.237358 -271.011309) (xy 60.24753 -271.010888)
			(xy 61.64707 -271.010888) (xy 61.657246 -271.01129) (xy 61.676049 -271.019074) (xy 61.690437 -271.033467)
			(xy 61.698214 -271.052274) (xy 61.698632 -271.06245) (xy 61.698632 -271.47139) (xy 158.062168 -271.47139)
			(xy 158.062168 -271.06245) (xy 158.062605 -271.052278) (xy 158.07038 -271.033479) (xy 158.084762 -271.019091)
			(xy 158.103558 -271.011309) (xy 158.11373 -271.010888) (xy 159.51327 -271.010888) (xy 159.523446 -271.01129)
			(xy 159.542249 -271.019074) (xy 159.556637 -271.033467) (xy 159.564414 -271.052274) (xy 159.564832 -271.06245)
			(xy 159.564832 -271.47139) (xy 165.605968 -271.47139) (xy 165.605968 -271.06245) (xy 165.606405 -271.052278)
			(xy 165.61418 -271.033479) (xy 165.628562 -271.019091) (xy 165.647358 -271.011309) (xy 165.65753 -271.010888)
			(xy 167.05707 -271.010888) (xy 167.067246 -271.01129) (xy 167.086049 -271.019074) (xy 167.100437 -271.033467)
			(xy 167.108214 -271.052274) (xy 167.108632 -271.06245) (xy 167.108632 -271.47139) (xy 173.149768 -271.47139)
			(xy 173.149768 -271.06245) (xy 173.150205 -271.052278) (xy 173.15798 -271.033479) (xy 173.172362 -271.019091)
			(xy 173.191158 -271.011309) (xy 173.20133 -271.010888) (xy 174.60087 -271.010888) (xy 174.611046 -271.01129)
			(xy 174.629849 -271.019074) (xy 174.644237 -271.033467) (xy 174.652014 -271.052274) (xy 174.652432 -271.06245)
			(xy 174.652432 -271.47139) (xy 180.693568 -271.47139) (xy 180.693568 -271.06245) (xy 180.694005 -271.052278)
			(xy 180.70178 -271.033479) (xy 180.716162 -271.019091) (xy 180.734958 -271.011309) (xy 180.74513 -271.010888)
			(xy 182.14467 -271.010888) (xy 182.154846 -271.01129) (xy 182.173649 -271.019074) (xy 182.188037 -271.033467)
			(xy 182.195814 -271.052274) (xy 182.196232 -271.06245) (xy 182.196232 -271.47139) (xy 188.237368 -271.47139)
			(xy 188.237368 -271.06245) (xy 188.237805 -271.052278) (xy 188.24558 -271.033479) (xy 188.259962 -271.019091)
			(xy 188.278758 -271.011309) (xy 188.28893 -271.010888) (xy 189.68847 -271.010888) (xy 189.698646 -271.01129)
			(xy 189.717449 -271.019074) (xy 189.731837 -271.033467) (xy 189.739614 -271.052274) (xy 189.740032 -271.06245)
			(xy 189.740032 -271.47139) (xy 195.781168 -271.47139) (xy 195.781168 -271.06245) (xy 195.781605 -271.052278)
			(xy 195.78938 -271.033479) (xy 195.803762 -271.019091) (xy 195.822558 -271.011309) (xy 195.83273 -271.010888)
			(xy 197.23227 -271.010888) (xy 197.242446 -271.01129) (xy 197.261249 -271.019074) (xy 197.275637 -271.033467)
			(xy 197.283414 -271.052274) (xy 197.283832 -271.06245) (xy 197.283832 -271.47139) (xy 203.324968 -271.47139)
			(xy 203.324968 -271.06245) (xy 203.325405 -271.052278) (xy 203.33318 -271.033479) (xy 203.347562 -271.019091)
			(xy 203.366358 -271.011309) (xy 203.37653 -271.010888) (xy 204.77607 -271.010888) (xy 204.786246 -271.01129)
			(xy 204.805049 -271.019074) (xy 204.819437 -271.033467) (xy 204.827214 -271.052274) (xy 204.827632 -271.06245)
			(xy 204.827632 -271.47139) (xy 210.868768 -271.47139) (xy 210.868768 -271.06245) (xy 210.869205 -271.052278)
			(xy 210.87698 -271.033479) (xy 210.891362 -271.019091) (xy 210.910158 -271.011309) (xy 210.92033 -271.010888)
			(xy 212.31987 -271.010888) (xy 212.330046 -271.01129) (xy 212.348849 -271.019074) (xy 212.363237 -271.033467)
			(xy 212.371014 -271.052274) (xy 212.371432 -271.06245) (xy 212.371432 -271.47139) (xy 255.329436 -271.47139)
			(xy 255.329436 -271.06245) (xy 255.329905 -271.052282) (xy 255.337673 -271.033489) (xy 255.352045 -271.019102)
			(xy 255.37083 -271.011315) (xy 255.380998 -271.010888) (xy 256.780538 -271.010888) (xy 256.790718 -271.011234)
			(xy 256.809523 -271.019041) (xy 256.823909 -271.033451) (xy 256.831684 -271.052269) (xy 256.8321 -271.06245)
			(xy 256.8321 -271.47139) (xy 262.873236 -271.47139) (xy 262.873236 -271.06245) (xy 262.873705 -271.052282)
			(xy 262.881473 -271.033489) (xy 262.895845 -271.019102) (xy 262.91463 -271.011315) (xy 262.924798 -271.010888)
			(xy 264.324338 -271.010888) (xy 264.334518 -271.011234) (xy 264.353323 -271.019041) (xy 264.367709 -271.033451)
			(xy 264.375484 -271.052269) (xy 264.3759 -271.06245) (xy 264.3759 -271.47139) (xy 270.417036 -271.47139)
			(xy 270.417036 -271.06245) (xy 270.417505 -271.052282) (xy 270.425273 -271.033489) (xy 270.439645 -271.019102)
			(xy 270.45843 -271.011315) (xy 270.468598 -271.010888) (xy 271.868138 -271.010888) (xy 271.878318 -271.011234)
			(xy 271.897123 -271.019041) (xy 271.911509 -271.033451) (xy 271.919284 -271.052269) (xy 271.9197 -271.06245)
			(xy 271.9197 -271.47139) (xy 277.960836 -271.47139) (xy 277.960836 -271.06245) (xy 277.961305 -271.052282)
			(xy 277.969073 -271.033489) (xy 277.983445 -271.019102) (xy 278.00223 -271.011315) (xy 278.012398 -271.010888)
			(xy 279.411938 -271.010888) (xy 279.422118 -271.011234) (xy 279.440923 -271.019041) (xy 279.455309 -271.033451)
			(xy 279.463084 -271.052269) (xy 279.4635 -271.06245) (xy 279.4635 -271.47139) (xy 285.504636 -271.47139)
			(xy 285.504636 -271.06245) (xy 285.505105 -271.052282) (xy 285.512873 -271.033489) (xy 285.527245 -271.019102)
			(xy 285.54603 -271.011315) (xy 285.556198 -271.010888) (xy 286.955738 -271.010888) (xy 286.965918 -271.011234)
			(xy 286.984723 -271.019041) (xy 286.999109 -271.033451) (xy 287.006884 -271.052269) (xy 287.0073 -271.06245)
			(xy 287.0073 -271.47139) (xy 293.048436 -271.47139) (xy 293.048436 -271.06245) (xy 293.048905 -271.052282)
			(xy 293.056673 -271.033489) (xy 293.071045 -271.019102) (xy 293.08983 -271.011315) (xy 293.099998 -271.010888)
			(xy 294.499538 -271.010888) (xy 294.509718 -271.011234) (xy 294.528523 -271.019041) (xy 294.542909 -271.033451)
			(xy 294.550684 -271.052269) (xy 294.5511 -271.06245) (xy 294.5511 -271.47139) (xy 300.592236 -271.47139)
			(xy 300.592236 -271.06245) (xy 300.592705 -271.052282) (xy 300.600473 -271.033489) (xy 300.614845 -271.019102)
			(xy 300.63363 -271.011315) (xy 300.643798 -271.010888) (xy 302.043338 -271.010888) (xy 302.053518 -271.011234)
			(xy 302.072323 -271.019041) (xy 302.086709 -271.033451) (xy 302.094484 -271.052269) (xy 302.0949 -271.06245)
			(xy 302.0949 -271.47139) (xy 308.136036 -271.47139) (xy 308.136036 -271.06245) (xy 308.136505 -271.052282)
			(xy 308.144273 -271.033489) (xy 308.158645 -271.019102) (xy 308.17743 -271.011315) (xy 308.187598 -271.010888)
			(xy 309.587138 -271.010888) (xy 309.597318 -271.011234) (xy 309.616123 -271.019041) (xy 309.630509 -271.033451)
			(xy 309.638284 -271.052269) (xy 309.6387 -271.06245) (xy 309.6387 -271.47139) (xy 406.002236 -271.47139)
			(xy 406.002236 -271.06245) (xy 406.002705 -271.052282) (xy 406.010473 -271.033489) (xy 406.024845 -271.019102)
			(xy 406.04363 -271.011315) (xy 406.053798 -271.010888) (xy 407.453338 -271.010888) (xy 407.463518 -271.011234)
			(xy 407.482323 -271.019041) (xy 407.496709 -271.033451) (xy 407.504484 -271.052269) (xy 407.5049 -271.06245)
			(xy 407.5049 -271.47139) (xy 413.546036 -271.47139) (xy 413.546036 -271.06245) (xy 413.546505 -271.052282)
			(xy 413.554273 -271.033489) (xy 413.568645 -271.019102) (xy 413.58743 -271.011315) (xy 413.597598 -271.010888)
			(xy 414.997138 -271.010888) (xy 415.007318 -271.011234) (xy 415.026123 -271.019041) (xy 415.040509 -271.033451)
			(xy 415.048284 -271.052269) (xy 415.0487 -271.06245) (xy 415.0487 -271.47139) (xy 421.089836 -271.47139)
			(xy 421.089836 -271.06245) (xy 421.090305 -271.052282) (xy 421.098073 -271.033489) (xy 421.112445 -271.019102)
			(xy 421.13123 -271.011315) (xy 421.141398 -271.010888) (xy 422.540938 -271.010888) (xy 422.551118 -271.011234)
			(xy 422.569923 -271.019041) (xy 422.584309 -271.033451) (xy 422.592084 -271.052269) (xy 422.5925 -271.06245)
			(xy 422.5925 -271.47139) (xy 428.633636 -271.47139) (xy 428.633636 -271.06245) (xy 428.634105 -271.052282)
			(xy 428.641873 -271.033489) (xy 428.656245 -271.019102) (xy 428.67503 -271.011315) (xy 428.685198 -271.010888)
			(xy 430.084738 -271.010888) (xy 430.094918 -271.011234) (xy 430.113723 -271.019041) (xy 430.128109 -271.033451)
			(xy 430.135884 -271.052269) (xy 430.1363 -271.06245) (xy 430.1363 -271.47139) (xy 436.177436 -271.47139)
			(xy 436.177436 -271.06245) (xy 436.177905 -271.052282) (xy 436.185673 -271.033489) (xy 436.200045 -271.019102)
			(xy 436.21883 -271.011315) (xy 436.228998 -271.010888) (xy 437.628538 -271.010888) (xy 437.638718 -271.011234)
			(xy 437.657523 -271.019041) (xy 437.671909 -271.033451) (xy 437.679684 -271.052269) (xy 437.6801 -271.06245)
			(xy 437.6801 -271.47139) (xy 443.721236 -271.47139) (xy 443.721236 -271.06245) (xy 443.721705 -271.052282)
			(xy 443.729473 -271.033489) (xy 443.743845 -271.019102) (xy 443.76263 -271.011315) (xy 443.772798 -271.010888)
			(xy 445.172338 -271.010888) (xy 445.182518 -271.011234) (xy 445.201323 -271.019041) (xy 445.215709 -271.033451)
			(xy 445.223484 -271.052269) (xy 445.2239 -271.06245) (xy 445.2239 -271.47139) (xy 451.265036 -271.47139)
			(xy 451.265036 -271.06245) (xy 451.265505 -271.052282) (xy 451.273273 -271.033489) (xy 451.287645 -271.019102)
			(xy 451.30643 -271.011315) (xy 451.316598 -271.010888) (xy 452.716138 -271.010888) (xy 452.726318 -271.011234)
			(xy 452.745123 -271.019041) (xy 452.759509 -271.033451) (xy 452.767284 -271.052269) (xy 452.7677 -271.06245)
			(xy 452.7677 -271.47139) (xy 458.808836 -271.47139) (xy 458.808836 -271.06245) (xy 458.809305 -271.052282)
			(xy 458.817073 -271.033489) (xy 458.831445 -271.019102) (xy 458.85023 -271.011315) (xy 458.860398 -271.010888)
			(xy 460.259938 -271.010888) (xy 460.270118 -271.011234) (xy 460.288923 -271.019041) (xy 460.303309 -271.033451)
			(xy 460.311084 -271.052269) (xy 460.3115 -271.06245) (xy 460.3115 -271.47139) (xy 460.310959 -271.481542)
			(xy 460.303195 -271.500304) (xy 460.288844 -271.514668) (xy 460.27009 -271.52245) (xy 460.259938 -271.522952)
			(xy 458.860398 -271.522952) (xy 458.850225 -271.522538) (xy 458.831428 -271.51475) (xy 458.817043 -271.500362)
			(xy 458.80926 -271.481563) (xy 458.808836 -271.47139) (xy 452.7677 -271.47139) (xy 452.767159 -271.481542)
			(xy 452.759395 -271.500304) (xy 452.745044 -271.514668) (xy 452.72629 -271.52245) (xy 452.716138 -271.522952)
			(xy 451.316598 -271.522952) (xy 451.306425 -271.522538) (xy 451.287628 -271.51475) (xy 451.273243 -271.500362)
			(xy 451.26546 -271.481563) (xy 451.265036 -271.47139) (xy 445.2239 -271.47139) (xy 445.223359 -271.481542)
			(xy 445.215595 -271.500304) (xy 445.201244 -271.514668) (xy 445.18249 -271.52245) (xy 445.172338 -271.522952)
			(xy 443.772798 -271.522952) (xy 443.762625 -271.522538) (xy 443.743828 -271.51475) (xy 443.729443 -271.500362)
			(xy 443.72166 -271.481563) (xy 443.721236 -271.47139) (xy 437.6801 -271.47139) (xy 437.679559 -271.481542)
			(xy 437.671795 -271.500304) (xy 437.657444 -271.514668) (xy 437.63869 -271.52245) (xy 437.628538 -271.522952)
			(xy 436.228998 -271.522952) (xy 436.218825 -271.522538) (xy 436.200028 -271.51475) (xy 436.185643 -271.500362)
			(xy 436.17786 -271.481563) (xy 436.177436 -271.47139) (xy 430.1363 -271.47139) (xy 430.135759 -271.481542)
			(xy 430.127995 -271.500304) (xy 430.113644 -271.514668) (xy 430.09489 -271.52245) (xy 430.084738 -271.522952)
			(xy 428.685198 -271.522952) (xy 428.675025 -271.522538) (xy 428.656228 -271.51475) (xy 428.641843 -271.500362)
			(xy 428.63406 -271.481563) (xy 428.633636 -271.47139) (xy 422.5925 -271.47139) (xy 422.591959 -271.481542)
			(xy 422.584195 -271.500304) (xy 422.569844 -271.514668) (xy 422.55109 -271.52245) (xy 422.540938 -271.522952)
			(xy 421.141398 -271.522952) (xy 421.131225 -271.522538) (xy 421.112428 -271.51475) (xy 421.098043 -271.500362)
			(xy 421.09026 -271.481563) (xy 421.089836 -271.47139) (xy 415.0487 -271.47139) (xy 415.048159 -271.481542)
			(xy 415.040395 -271.500304) (xy 415.026044 -271.514668) (xy 415.00729 -271.52245) (xy 414.997138 -271.522952)
			(xy 413.597598 -271.522952) (xy 413.587425 -271.522538) (xy 413.568628 -271.51475) (xy 413.554243 -271.500362)
			(xy 413.54646 -271.481563) (xy 413.546036 -271.47139) (xy 407.5049 -271.47139) (xy 407.504359 -271.481542)
			(xy 407.496595 -271.500304) (xy 407.482244 -271.514668) (xy 407.46349 -271.52245) (xy 407.453338 -271.522952)
			(xy 406.053798 -271.522952) (xy 406.043625 -271.522538) (xy 406.024828 -271.51475) (xy 406.010443 -271.500362)
			(xy 406.00266 -271.481563) (xy 406.002236 -271.47139) (xy 309.6387 -271.47139) (xy 309.638159 -271.481542)
			(xy 309.630395 -271.500304) (xy 309.616044 -271.514668) (xy 309.59729 -271.52245) (xy 309.587138 -271.522952)
			(xy 308.187598 -271.522952) (xy 308.177425 -271.522538) (xy 308.158628 -271.51475) (xy 308.144243 -271.500362)
			(xy 308.13646 -271.481563) (xy 308.136036 -271.47139) (xy 302.0949 -271.47139) (xy 302.094359 -271.481542)
			(xy 302.086595 -271.500304) (xy 302.072244 -271.514668) (xy 302.05349 -271.52245) (xy 302.043338 -271.522952)
			(xy 300.643798 -271.522952) (xy 300.633625 -271.522538) (xy 300.614828 -271.51475) (xy 300.600443 -271.500362)
			(xy 300.59266 -271.481563) (xy 300.592236 -271.47139) (xy 294.5511 -271.47139) (xy 294.550559 -271.481542)
			(xy 294.542795 -271.500304) (xy 294.528444 -271.514668) (xy 294.50969 -271.52245) (xy 294.499538 -271.522952)
			(xy 293.099998 -271.522952) (xy 293.089825 -271.522538) (xy 293.071028 -271.51475) (xy 293.056643 -271.500362)
			(xy 293.04886 -271.481563) (xy 293.048436 -271.47139) (xy 287.0073 -271.47139) (xy 287.006759 -271.481542)
			(xy 286.998995 -271.500304) (xy 286.984644 -271.514668) (xy 286.96589 -271.52245) (xy 286.955738 -271.522952)
			(xy 285.556198 -271.522952) (xy 285.546025 -271.522538) (xy 285.527228 -271.51475) (xy 285.512843 -271.500362)
			(xy 285.50506 -271.481563) (xy 285.504636 -271.47139) (xy 279.4635 -271.47139) (xy 279.462959 -271.481542)
			(xy 279.455195 -271.500304) (xy 279.440844 -271.514668) (xy 279.42209 -271.52245) (xy 279.411938 -271.522952)
			(xy 278.012398 -271.522952) (xy 278.002225 -271.522538) (xy 277.983428 -271.51475) (xy 277.969043 -271.500362)
			(xy 277.96126 -271.481563) (xy 277.960836 -271.47139) (xy 271.9197 -271.47139) (xy 271.919159 -271.481542)
			(xy 271.911395 -271.500304) (xy 271.897044 -271.514668) (xy 271.87829 -271.52245) (xy 271.868138 -271.522952)
			(xy 270.468598 -271.522952) (xy 270.458425 -271.522538) (xy 270.439628 -271.51475) (xy 270.425243 -271.500362)
			(xy 270.41746 -271.481563) (xy 270.417036 -271.47139) (xy 264.3759 -271.47139) (xy 264.375359 -271.481542)
			(xy 264.367595 -271.500304) (xy 264.353244 -271.514668) (xy 264.33449 -271.52245) (xy 264.324338 -271.522952)
			(xy 262.924798 -271.522952) (xy 262.914625 -271.522538) (xy 262.895828 -271.51475) (xy 262.881443 -271.500362)
			(xy 262.87366 -271.481563) (xy 262.873236 -271.47139) (xy 256.8321 -271.47139) (xy 256.831559 -271.481542)
			(xy 256.823795 -271.500304) (xy 256.809444 -271.514668) (xy 256.79069 -271.52245) (xy 256.780538 -271.522952)
			(xy 255.380998 -271.522952) (xy 255.370825 -271.522538) (xy 255.352028 -271.51475) (xy 255.337643 -271.500362)
			(xy 255.32986 -271.481563) (xy 255.329436 -271.47139) (xy 212.371432 -271.47139) (xy 212.371027 -271.481565)
			(xy 212.36324 -271.500365) (xy 212.348848 -271.514751) (xy 212.330045 -271.522531) (xy 212.31987 -271.522952)
			(xy 210.92033 -271.522952) (xy 210.910159 -271.522511) (xy 210.891363 -271.514734) (xy 210.876977 -271.500354)
			(xy 210.869193 -271.481561) (xy 210.868768 -271.47139) (xy 204.827632 -271.47139) (xy 204.827227 -271.481565)
			(xy 204.81944 -271.500365) (xy 204.805048 -271.514751) (xy 204.786245 -271.522531) (xy 204.77607 -271.522952)
			(xy 203.37653 -271.522952) (xy 203.366359 -271.522511) (xy 203.347563 -271.514734) (xy 203.333177 -271.500354)
			(xy 203.325393 -271.481561) (xy 203.324968 -271.47139) (xy 197.283832 -271.47139) (xy 197.283427 -271.481565)
			(xy 197.27564 -271.500365) (xy 197.261248 -271.514751) (xy 197.242445 -271.522531) (xy 197.23227 -271.522952)
			(xy 195.83273 -271.522952) (xy 195.822559 -271.522511) (xy 195.803763 -271.514734) (xy 195.789377 -271.500354)
			(xy 195.781593 -271.481561) (xy 195.781168 -271.47139) (xy 189.740032 -271.47139) (xy 189.739627 -271.481565)
			(xy 189.73184 -271.500365) (xy 189.717448 -271.514751) (xy 189.698645 -271.522531) (xy 189.68847 -271.522952)
			(xy 188.28893 -271.522952) (xy 188.278759 -271.522511) (xy 188.259963 -271.514734) (xy 188.245577 -271.500354)
			(xy 188.237793 -271.481561) (xy 188.237368 -271.47139) (xy 182.196232 -271.47139) (xy 182.195827 -271.481565)
			(xy 182.18804 -271.500365) (xy 182.173648 -271.514751) (xy 182.154845 -271.522531) (xy 182.14467 -271.522952)
			(xy 180.74513 -271.522952) (xy 180.734959 -271.522511) (xy 180.716163 -271.514734) (xy 180.701777 -271.500354)
			(xy 180.693993 -271.481561) (xy 180.693568 -271.47139) (xy 174.652432 -271.47139) (xy 174.652027 -271.481565)
			(xy 174.64424 -271.500365) (xy 174.629848 -271.514751) (xy 174.611045 -271.522531) (xy 174.60087 -271.522952)
			(xy 173.20133 -271.522952) (xy 173.191159 -271.522511) (xy 173.172363 -271.514734) (xy 173.157977 -271.500354)
			(xy 173.150193 -271.481561) (xy 173.149768 -271.47139) (xy 167.108632 -271.47139) (xy 167.108227 -271.481565)
			(xy 167.10044 -271.500365) (xy 167.086048 -271.514751) (xy 167.067245 -271.522531) (xy 167.05707 -271.522952)
			(xy 165.65753 -271.522952) (xy 165.647359 -271.522511) (xy 165.628563 -271.514734) (xy 165.614177 -271.500354)
			(xy 165.606393 -271.481561) (xy 165.605968 -271.47139) (xy 159.564832 -271.47139) (xy 159.564427 -271.481565)
			(xy 159.55664 -271.500365) (xy 159.542248 -271.514751) (xy 159.523445 -271.522531) (xy 159.51327 -271.522952)
			(xy 158.11373 -271.522952) (xy 158.103559 -271.522511) (xy 158.084763 -271.514734) (xy 158.070377 -271.500354)
			(xy 158.062593 -271.481561) (xy 158.062168 -271.47139) (xy 61.698632 -271.47139) (xy 61.698227 -271.481565)
			(xy 61.69044 -271.500365) (xy 61.676048 -271.514751) (xy 61.657245 -271.522531) (xy 61.64707 -271.522952)
			(xy 60.24753 -271.522952) (xy 60.237359 -271.522511) (xy 60.218563 -271.514734) (xy 60.204177 -271.500354)
			(xy 60.196393 -271.481561) (xy 60.195968 -271.47139) (xy 54.154832 -271.47139) (xy 54.154427 -271.481565)
			(xy 54.14664 -271.500365) (xy 54.132248 -271.514751) (xy 54.113445 -271.522531) (xy 54.10327 -271.522952)
			(xy 52.70373 -271.522952) (xy 52.693559 -271.522511) (xy 52.674763 -271.514734) (xy 52.660377 -271.500354)
			(xy 52.652593 -271.481561) (xy 52.652168 -271.47139) (xy 46.611032 -271.47139) (xy 46.610627 -271.481565)
			(xy 46.60284 -271.500365) (xy 46.588448 -271.514751) (xy 46.569645 -271.522531) (xy 46.55947 -271.522952)
			(xy 45.15993 -271.522952) (xy 45.149759 -271.522511) (xy 45.130963 -271.514734) (xy 45.116577 -271.500354)
			(xy 45.108793 -271.481561) (xy 45.108368 -271.47139) (xy 39.067232 -271.47139) (xy 39.066827 -271.481565)
			(xy 39.05904 -271.500365) (xy 39.044648 -271.514751) (xy 39.025845 -271.522531) (xy 39.01567 -271.522952)
			(xy 37.61613 -271.522952) (xy 37.605959 -271.522511) (xy 37.587163 -271.514734) (xy 37.572777 -271.500354)
			(xy 37.564993 -271.481561) (xy 37.564568 -271.47139) (xy 31.523432 -271.47139) (xy 31.523027 -271.481565)
			(xy 31.51524 -271.500365) (xy 31.500848 -271.514751) (xy 31.482045 -271.522531) (xy 31.47187 -271.522952)
			(xy 30.07233 -271.522952) (xy 30.062159 -271.522511) (xy 30.043363 -271.514734) (xy 30.028977 -271.500354)
			(xy 30.021193 -271.481561) (xy 30.020768 -271.47139) (xy 23.979632 -271.47139) (xy 23.979227 -271.481565)
			(xy 23.97144 -271.500365) (xy 23.957048 -271.514751) (xy 23.938245 -271.522531) (xy 23.92807 -271.522952)
			(xy 22.52853 -271.522952) (xy 22.518359 -271.522511) (xy 22.499563 -271.514734) (xy 22.485177 -271.500354)
			(xy 22.477393 -271.481561) (xy 22.476968 -271.47139) (xy 16.435832 -271.47139) (xy 16.435427 -271.481565)
			(xy 16.42764 -271.500365) (xy 16.413248 -271.514751) (xy 16.394445 -271.522531) (xy 16.38427 -271.522952)
			(xy 14.98473 -271.522952) (xy 14.974559 -271.522511) (xy 14.955763 -271.514734) (xy 14.941377 -271.500354)
			(xy 14.933593 -271.481561) (xy 14.933168 -271.47139) (xy 8.892032 -271.47139) (xy 8.891627 -271.481565)
			(xy 8.88384 -271.500365) (xy 8.869448 -271.514751) (xy 8.850645 -271.522531) (xy 8.84047 -271.522952)
			(xy 7.44093 -271.522952) (xy 7.430759 -271.522511) (xy 7.411963 -271.514734) (xy 7.397577 -271.500354)
			(xy 7.389793 -271.481561) (xy 7.389368 -271.47139) (xy 2.509012 -271.47139) (xy 2.509012 -272.321528)
			(xy 11.489436 -272.321528) (xy 11.489436 -271.912588) (xy 11.489812 -271.902429) (xy 11.497619 -271.883669)
			(xy 11.51203 -271.869345) (xy 11.530836 -271.861652) (xy 11.540998 -271.86128) (xy 12.940538 -271.86128)
			(xy 12.950672 -271.861697) (xy 12.969402 -271.869444) (xy 12.983758 -271.883752) (xy 12.991569 -271.902456)
			(xy 12.9921 -271.912588) (xy 12.9921 -272.321528) (xy 19.033236 -272.321528) (xy 19.033236 -271.912588)
			(xy 19.033612 -271.902429) (xy 19.041419 -271.883669) (xy 19.05583 -271.869345) (xy 19.074636 -271.861652)
			(xy 19.084798 -271.86128) (xy 20.484338 -271.86128) (xy 20.494472 -271.861697) (xy 20.513202 -271.869444)
			(xy 20.527558 -271.883752) (xy 20.535369 -271.902456) (xy 20.5359 -271.912588) (xy 20.5359 -272.321528)
			(xy 26.577036 -272.321528) (xy 26.577036 -271.912588) (xy 26.577412 -271.902429) (xy 26.585219 -271.883669)
			(xy 26.59963 -271.869345) (xy 26.618436 -271.861652) (xy 26.628598 -271.86128) (xy 28.028138 -271.86128)
			(xy 28.038272 -271.861697) (xy 28.057002 -271.869444) (xy 28.071358 -271.883752) (xy 28.079169 -271.902456)
			(xy 28.0797 -271.912588) (xy 28.0797 -272.321528) (xy 34.120836 -272.321528) (xy 34.120836 -271.912588)
			(xy 34.121212 -271.902429) (xy 34.129019 -271.883669) (xy 34.14343 -271.869345) (xy 34.162236 -271.861652)
			(xy 34.172398 -271.86128) (xy 35.571938 -271.86128) (xy 35.582072 -271.861697) (xy 35.600802 -271.869444)
			(xy 35.615158 -271.883752) (xy 35.622969 -271.902456) (xy 35.6235 -271.912588) (xy 35.6235 -272.321528)
			(xy 41.664636 -272.321528) (xy 41.664636 -271.912588) (xy 41.665012 -271.902429) (xy 41.672819 -271.883669)
			(xy 41.68723 -271.869345) (xy 41.706036 -271.861652) (xy 41.716198 -271.86128) (xy 43.115738 -271.86128)
			(xy 43.125872 -271.861697) (xy 43.144602 -271.869444) (xy 43.158958 -271.883752) (xy 43.166769 -271.902456)
			(xy 43.1673 -271.912588) (xy 43.1673 -272.321528) (xy 49.208436 -272.321528) (xy 49.208436 -271.912588)
			(xy 49.208812 -271.902429) (xy 49.216619 -271.883669) (xy 49.23103 -271.869345) (xy 49.249836 -271.861652)
			(xy 49.259998 -271.86128) (xy 50.659538 -271.86128) (xy 50.669672 -271.861697) (xy 50.688402 -271.869444)
			(xy 50.702758 -271.883752) (xy 50.710569 -271.902456) (xy 50.7111 -271.912588) (xy 50.7111 -272.321528)
			(xy 56.752236 -272.321528) (xy 56.752236 -271.912588) (xy 56.752612 -271.902429) (xy 56.760419 -271.883669)
			(xy 56.77483 -271.869345) (xy 56.793636 -271.861652) (xy 56.803798 -271.86128) (xy 58.203338 -271.86128)
			(xy 58.213472 -271.861697) (xy 58.232202 -271.869444) (xy 58.246558 -271.883752) (xy 58.254369 -271.902456)
			(xy 58.2549 -271.912588) (xy 58.2549 -272.321528) (xy 64.296036 -272.321528) (xy 64.296036 -271.912588)
			(xy 64.296412 -271.902429) (xy 64.304219 -271.883669) (xy 64.31863 -271.869345) (xy 64.337436 -271.861652)
			(xy 64.347598 -271.86128) (xy 65.747138 -271.86128) (xy 65.757272 -271.861697) (xy 65.776002 -271.869444)
			(xy 65.790358 -271.883752) (xy 65.798169 -271.902456) (xy 65.7987 -271.912588) (xy 65.7987 -272.321528)
			(xy 162.162236 -272.321528) (xy 162.162236 -271.912588) (xy 162.162612 -271.902429) (xy 162.170419 -271.883669)
			(xy 162.18483 -271.869345) (xy 162.203636 -271.861652) (xy 162.213798 -271.86128) (xy 163.613338 -271.86128)
			(xy 163.623472 -271.861697) (xy 163.642202 -271.869444) (xy 163.656558 -271.883752) (xy 163.664369 -271.902456)
			(xy 163.6649 -271.912588) (xy 163.6649 -272.321528) (xy 169.706036 -272.321528) (xy 169.706036 -271.912588)
			(xy 169.706412 -271.902429) (xy 169.714219 -271.883669) (xy 169.72863 -271.869345) (xy 169.747436 -271.861652)
			(xy 169.757598 -271.86128) (xy 171.157138 -271.86128) (xy 171.167272 -271.861697) (xy 171.186002 -271.869444)
			(xy 171.200358 -271.883752) (xy 171.208169 -271.902456) (xy 171.2087 -271.912588) (xy 171.2087 -272.321528)
			(xy 177.249836 -272.321528) (xy 177.249836 -271.912588) (xy 177.250212 -271.902429) (xy 177.258019 -271.883669)
			(xy 177.27243 -271.869345) (xy 177.291236 -271.861652) (xy 177.301398 -271.86128) (xy 178.700938 -271.86128)
			(xy 178.711072 -271.861697) (xy 178.729802 -271.869444) (xy 178.744158 -271.883752) (xy 178.751969 -271.902456)
			(xy 178.7525 -271.912588) (xy 178.7525 -272.321528) (xy 184.793636 -272.321528) (xy 184.793636 -271.912588)
			(xy 184.794012 -271.902429) (xy 184.801819 -271.883669) (xy 184.81623 -271.869345) (xy 184.835036 -271.861652)
			(xy 184.845198 -271.86128) (xy 186.244738 -271.86128) (xy 186.254872 -271.861697) (xy 186.273602 -271.869444)
			(xy 186.287958 -271.883752) (xy 186.295769 -271.902456) (xy 186.2963 -271.912588) (xy 186.2963 -272.321528)
			(xy 192.337436 -272.321528) (xy 192.337436 -271.912588) (xy 192.337812 -271.902429) (xy 192.345619 -271.883669)
			(xy 192.36003 -271.869345) (xy 192.378836 -271.861652) (xy 192.388998 -271.86128) (xy 193.788538 -271.86128)
			(xy 193.798672 -271.861697) (xy 193.817402 -271.869444) (xy 193.831758 -271.883752) (xy 193.839569 -271.902456)
			(xy 193.8401 -271.912588) (xy 193.8401 -272.321528) (xy 199.881236 -272.321528) (xy 199.881236 -271.912588)
			(xy 199.881612 -271.902429) (xy 199.889419 -271.883669) (xy 199.90383 -271.869345) (xy 199.922636 -271.861652)
			(xy 199.932798 -271.86128) (xy 201.332338 -271.86128) (xy 201.342472 -271.861697) (xy 201.361202 -271.869444)
			(xy 201.375558 -271.883752) (xy 201.383369 -271.902456) (xy 201.3839 -271.912588) (xy 201.3839 -272.321528)
			(xy 207.425036 -272.321528) (xy 207.425036 -271.912588) (xy 207.425412 -271.902429) (xy 207.433219 -271.883669)
			(xy 207.44763 -271.869345) (xy 207.466436 -271.861652) (xy 207.476598 -271.86128) (xy 208.876138 -271.86128)
			(xy 208.886272 -271.861697) (xy 208.905002 -271.869444) (xy 208.919358 -271.883752) (xy 208.927169 -271.902456)
			(xy 208.9277 -271.912588) (xy 208.9277 -272.321528) (xy 214.968836 -272.321528) (xy 214.968836 -271.912588)
			(xy 214.969212 -271.902429) (xy 214.977019 -271.883669) (xy 214.99143 -271.869345) (xy 215.010236 -271.861652)
			(xy 215.020398 -271.86128) (xy 216.419938 -271.86128) (xy 216.430072 -271.861697) (xy 216.448802 -271.869444)
			(xy 216.463158 -271.883752) (xy 216.470969 -271.902456) (xy 216.4715 -271.912588) (xy 216.4715 -272.321528)
			(xy 259.429504 -272.321528) (xy 259.429504 -271.912588) (xy 259.429912 -271.902433) (xy 259.437712 -271.883679)
			(xy 259.452113 -271.869356) (xy 259.470908 -271.861657) (xy 259.481066 -271.86128) (xy 260.880606 -271.86128)
			(xy 260.890738 -271.861723) (xy 260.909467 -271.86946) (xy 260.923824 -271.88376) (xy 260.931636 -271.902458)
			(xy 260.932168 -271.912588) (xy 260.932168 -272.321528) (xy 266.973304 -272.321528) (xy 266.973304 -271.912588)
			(xy 266.973712 -271.902433) (xy 266.981512 -271.883679) (xy 266.995913 -271.869356) (xy 267.014708 -271.861657)
			(xy 267.024866 -271.86128) (xy 268.424406 -271.86128) (xy 268.434538 -271.861723) (xy 268.453267 -271.86946)
			(xy 268.467624 -271.88376) (xy 268.475436 -271.902458) (xy 268.475968 -271.912588) (xy 268.475968 -272.321528)
			(xy 274.517104 -272.321528) (xy 274.517104 -271.912588) (xy 274.517512 -271.902433) (xy 274.525312 -271.883679)
			(xy 274.539713 -271.869356) (xy 274.558508 -271.861657) (xy 274.568666 -271.86128) (xy 275.968206 -271.86128)
			(xy 275.978338 -271.861723) (xy 275.997067 -271.86946) (xy 276.011424 -271.88376) (xy 276.019236 -271.902458)
			(xy 276.019768 -271.912588) (xy 276.019768 -272.321528) (xy 282.060904 -272.321528) (xy 282.060904 -271.912588)
			(xy 282.061312 -271.902433) (xy 282.069112 -271.883679) (xy 282.083513 -271.869356) (xy 282.102308 -271.861657)
			(xy 282.112466 -271.86128) (xy 283.512006 -271.86128) (xy 283.522138 -271.861723) (xy 283.540867 -271.86946)
			(xy 283.555224 -271.88376) (xy 283.563036 -271.902458) (xy 283.563568 -271.912588) (xy 283.563568 -272.321528)
			(xy 289.604704 -272.321528) (xy 289.604704 -271.912588) (xy 289.605112 -271.902433) (xy 289.612912 -271.883679)
			(xy 289.627313 -271.869356) (xy 289.646108 -271.861657) (xy 289.656266 -271.86128) (xy 291.055806 -271.86128)
			(xy 291.065938 -271.861723) (xy 291.084667 -271.86946) (xy 291.099024 -271.88376) (xy 291.106836 -271.902458)
			(xy 291.107368 -271.912588) (xy 291.107368 -272.321528) (xy 297.148504 -272.321528) (xy 297.148504 -271.912588)
			(xy 297.148912 -271.902433) (xy 297.156712 -271.883679) (xy 297.171113 -271.869356) (xy 297.189908 -271.861657)
			(xy 297.200066 -271.86128) (xy 298.599606 -271.86128) (xy 298.609738 -271.861723) (xy 298.628467 -271.86946)
			(xy 298.642824 -271.88376) (xy 298.650636 -271.902458) (xy 298.651168 -271.912588) (xy 298.651168 -272.321528)
			(xy 304.692304 -272.321528) (xy 304.692304 -271.912588) (xy 304.692712 -271.902433) (xy 304.700512 -271.883679)
			(xy 304.714913 -271.869356) (xy 304.733708 -271.861657) (xy 304.743866 -271.86128) (xy 306.143406 -271.86128)
			(xy 306.153538 -271.861723) (xy 306.172267 -271.86946) (xy 306.186624 -271.88376) (xy 306.194436 -271.902458)
			(xy 306.194968 -271.912588) (xy 306.194968 -272.321528) (xy 312.236104 -272.321528) (xy 312.236104 -271.912588)
			(xy 312.236512 -271.902433) (xy 312.244312 -271.883679) (xy 312.258713 -271.869356) (xy 312.277508 -271.861657)
			(xy 312.287666 -271.86128) (xy 313.687206 -271.86128) (xy 313.697338 -271.861723) (xy 313.716067 -271.86946)
			(xy 313.730424 -271.88376) (xy 313.738236 -271.902458) (xy 313.738768 -271.912588) (xy 313.738768 -272.321528)
			(xy 410.102304 -272.321528) (xy 410.102304 -271.912588) (xy 410.102712 -271.902433) (xy 410.110512 -271.883679)
			(xy 410.124913 -271.869356) (xy 410.143708 -271.861657) (xy 410.153866 -271.86128) (xy 411.553406 -271.86128)
			(xy 411.563538 -271.861723) (xy 411.582267 -271.86946) (xy 411.596624 -271.88376) (xy 411.604436 -271.902458)
			(xy 411.604968 -271.912588) (xy 411.604968 -272.321528) (xy 417.646104 -272.321528) (xy 417.646104 -271.912588)
			(xy 417.646512 -271.902433) (xy 417.654312 -271.883679) (xy 417.668713 -271.869356) (xy 417.687508 -271.861657)
			(xy 417.697666 -271.86128) (xy 419.097206 -271.86128) (xy 419.107338 -271.861723) (xy 419.126067 -271.86946)
			(xy 419.140424 -271.88376) (xy 419.148236 -271.902458) (xy 419.148768 -271.912588) (xy 419.148768 -272.321528)
			(xy 425.189904 -272.321528) (xy 425.189904 -271.912588) (xy 425.190312 -271.902433) (xy 425.198112 -271.883679)
			(xy 425.212513 -271.869356) (xy 425.231308 -271.861657) (xy 425.241466 -271.86128) (xy 426.641006 -271.86128)
			(xy 426.651138 -271.861723) (xy 426.669867 -271.86946) (xy 426.684224 -271.88376) (xy 426.692036 -271.902458)
			(xy 426.692568 -271.912588) (xy 426.692568 -272.321528) (xy 432.733704 -272.321528) (xy 432.733704 -271.912588)
			(xy 432.734112 -271.902433) (xy 432.741912 -271.883679) (xy 432.756313 -271.869356) (xy 432.775108 -271.861657)
			(xy 432.785266 -271.86128) (xy 434.184806 -271.86128) (xy 434.194938 -271.861723) (xy 434.213667 -271.86946)
			(xy 434.228024 -271.88376) (xy 434.235836 -271.902458) (xy 434.236368 -271.912588) (xy 434.236368 -272.321528)
			(xy 440.277504 -272.321528) (xy 440.277504 -271.912588) (xy 440.277912 -271.902433) (xy 440.285712 -271.883679)
			(xy 440.300113 -271.869356) (xy 440.318908 -271.861657) (xy 440.329066 -271.86128) (xy 441.728606 -271.86128)
			(xy 441.738738 -271.861723) (xy 441.757467 -271.86946) (xy 441.771824 -271.88376) (xy 441.779636 -271.902458)
			(xy 441.780168 -271.912588) (xy 441.780168 -272.321528) (xy 447.821304 -272.321528) (xy 447.821304 -271.912588)
			(xy 447.821712 -271.902433) (xy 447.829512 -271.883679) (xy 447.843913 -271.869356) (xy 447.862708 -271.861657)
			(xy 447.872866 -271.86128) (xy 449.272406 -271.86128) (xy 449.282538 -271.861723) (xy 449.301267 -271.86946)
			(xy 449.315624 -271.88376) (xy 449.323436 -271.902458) (xy 449.323968 -271.912588) (xy 449.323968 -272.321528)
			(xy 455.365104 -272.321528) (xy 455.365104 -271.912588) (xy 455.365512 -271.902433) (xy 455.373312 -271.883679)
			(xy 455.387713 -271.869356) (xy 455.406508 -271.861657) (xy 455.416666 -271.86128) (xy 456.816206 -271.86128)
			(xy 456.826338 -271.861723) (xy 456.845067 -271.86946) (xy 456.859424 -271.88376) (xy 456.867236 -271.902458)
			(xy 456.867768 -271.912588) (xy 456.867768 -272.321528) (xy 462.908904 -272.321528) (xy 462.908904 -271.912588)
			(xy 462.909312 -271.902433) (xy 462.917112 -271.883679) (xy 462.931513 -271.869356) (xy 462.950308 -271.861657)
			(xy 462.960466 -271.86128) (xy 464.360006 -271.86128) (xy 464.370138 -271.861723) (xy 464.388867 -271.86946)
			(xy 464.403224 -271.88376) (xy 464.411036 -271.902458) (xy 464.411568 -271.912588) (xy 464.411568 -272.321528)
			(xy 464.411201 -272.331688) (xy 464.40339 -272.350447) (xy 464.388976 -272.364771) (xy 464.370168 -272.372464)
			(xy 464.360006 -272.372836) (xy 462.960466 -272.372836) (xy 462.950334 -272.372401) (xy 462.931608 -272.364657)
			(xy 462.917252 -272.350355) (xy 462.909438 -272.331658) (xy 462.908904 -272.321528) (xy 456.867768 -272.321528)
			(xy 456.867401 -272.331688) (xy 456.85959 -272.350447) (xy 456.845176 -272.364771) (xy 456.826368 -272.372464)
			(xy 456.816206 -272.372836) (xy 455.416666 -272.372836) (xy 455.406534 -272.372401) (xy 455.387808 -272.364657)
			(xy 455.373452 -272.350355) (xy 455.365638 -272.331658) (xy 455.365104 -272.321528) (xy 449.323968 -272.321528)
			(xy 449.323601 -272.331688) (xy 449.31579 -272.350447) (xy 449.301376 -272.364771) (xy 449.282568 -272.372464)
			(xy 449.272406 -272.372836) (xy 447.872866 -272.372836) (xy 447.862734 -272.372401) (xy 447.844008 -272.364657)
			(xy 447.829652 -272.350355) (xy 447.821838 -272.331658) (xy 447.821304 -272.321528) (xy 441.780168 -272.321528)
			(xy 441.779801 -272.331688) (xy 441.77199 -272.350447) (xy 441.757576 -272.364771) (xy 441.738768 -272.372464)
			(xy 441.728606 -272.372836) (xy 440.329066 -272.372836) (xy 440.318934 -272.372401) (xy 440.300208 -272.364657)
			(xy 440.285852 -272.350355) (xy 440.278038 -272.331658) (xy 440.277504 -272.321528) (xy 434.236368 -272.321528)
			(xy 434.236001 -272.331688) (xy 434.22819 -272.350447) (xy 434.213776 -272.364771) (xy 434.194968 -272.372464)
			(xy 434.184806 -272.372836) (xy 432.785266 -272.372836) (xy 432.775134 -272.372401) (xy 432.756408 -272.364657)
			(xy 432.742052 -272.350355) (xy 432.734238 -272.331658) (xy 432.733704 -272.321528) (xy 426.692568 -272.321528)
			(xy 426.692201 -272.331688) (xy 426.68439 -272.350447) (xy 426.669976 -272.364771) (xy 426.651168 -272.372464)
			(xy 426.641006 -272.372836) (xy 425.241466 -272.372836) (xy 425.231334 -272.372401) (xy 425.212608 -272.364657)
			(xy 425.198252 -272.350355) (xy 425.190438 -272.331658) (xy 425.189904 -272.321528) (xy 419.148768 -272.321528)
			(xy 419.148401 -272.331688) (xy 419.14059 -272.350447) (xy 419.126176 -272.364771) (xy 419.107368 -272.372464)
			(xy 419.097206 -272.372836) (xy 417.697666 -272.372836) (xy 417.687534 -272.372401) (xy 417.668808 -272.364657)
			(xy 417.654452 -272.350355) (xy 417.646638 -272.331658) (xy 417.646104 -272.321528) (xy 411.604968 -272.321528)
			(xy 411.604601 -272.331688) (xy 411.59679 -272.350447) (xy 411.582376 -272.364771) (xy 411.563568 -272.372464)
			(xy 411.553406 -272.372836) (xy 410.153866 -272.372836) (xy 410.143734 -272.372401) (xy 410.125008 -272.364657)
			(xy 410.110652 -272.350355) (xy 410.102838 -272.331658) (xy 410.102304 -272.321528) (xy 313.738768 -272.321528)
			(xy 313.738401 -272.331688) (xy 313.73059 -272.350447) (xy 313.716176 -272.364771) (xy 313.697368 -272.372464)
			(xy 313.687206 -272.372836) (xy 312.287666 -272.372836) (xy 312.277534 -272.372401) (xy 312.258808 -272.364657)
			(xy 312.244452 -272.350355) (xy 312.236638 -272.331658) (xy 312.236104 -272.321528) (xy 306.194968 -272.321528)
			(xy 306.194601 -272.331688) (xy 306.18679 -272.350447) (xy 306.172376 -272.364771) (xy 306.153568 -272.372464)
			(xy 306.143406 -272.372836) (xy 304.743866 -272.372836) (xy 304.733734 -272.372401) (xy 304.715008 -272.364657)
			(xy 304.700652 -272.350355) (xy 304.692838 -272.331658) (xy 304.692304 -272.321528) (xy 298.651168 -272.321528)
			(xy 298.650801 -272.331688) (xy 298.64299 -272.350447) (xy 298.628576 -272.364771) (xy 298.609768 -272.372464)
			(xy 298.599606 -272.372836) (xy 297.200066 -272.372836) (xy 297.189934 -272.372401) (xy 297.171208 -272.364657)
			(xy 297.156852 -272.350355) (xy 297.149038 -272.331658) (xy 297.148504 -272.321528) (xy 291.107368 -272.321528)
			(xy 291.107001 -272.331688) (xy 291.09919 -272.350447) (xy 291.084776 -272.364771) (xy 291.065968 -272.372464)
			(xy 291.055806 -272.372836) (xy 289.656266 -272.372836) (xy 289.646134 -272.372401) (xy 289.627408 -272.364657)
			(xy 289.613052 -272.350355) (xy 289.605238 -272.331658) (xy 289.604704 -272.321528) (xy 283.563568 -272.321528)
			(xy 283.563201 -272.331688) (xy 283.55539 -272.350447) (xy 283.540976 -272.364771) (xy 283.522168 -272.372464)
			(xy 283.512006 -272.372836) (xy 282.112466 -272.372836) (xy 282.102334 -272.372401) (xy 282.083608 -272.364657)
			(xy 282.069252 -272.350355) (xy 282.061438 -272.331658) (xy 282.060904 -272.321528) (xy 276.019768 -272.321528)
			(xy 276.019401 -272.331688) (xy 276.01159 -272.350447) (xy 275.997176 -272.364771) (xy 275.978368 -272.372464)
			(xy 275.968206 -272.372836) (xy 274.568666 -272.372836) (xy 274.558534 -272.372401) (xy 274.539808 -272.364657)
			(xy 274.525452 -272.350355) (xy 274.517638 -272.331658) (xy 274.517104 -272.321528) (xy 268.475968 -272.321528)
			(xy 268.475601 -272.331688) (xy 268.46779 -272.350447) (xy 268.453376 -272.364771) (xy 268.434568 -272.372464)
			(xy 268.424406 -272.372836) (xy 267.024866 -272.372836) (xy 267.014734 -272.372401) (xy 266.996008 -272.364657)
			(xy 266.981652 -272.350355) (xy 266.973838 -272.331658) (xy 266.973304 -272.321528) (xy 260.932168 -272.321528)
			(xy 260.931801 -272.331688) (xy 260.92399 -272.350447) (xy 260.909576 -272.364771) (xy 260.890768 -272.372464)
			(xy 260.880606 -272.372836) (xy 259.481066 -272.372836) (xy 259.470934 -272.372401) (xy 259.452208 -272.364657)
			(xy 259.437852 -272.350355) (xy 259.430038 -272.331658) (xy 259.429504 -272.321528) (xy 216.4715 -272.321528)
			(xy 216.471101 -272.331684) (xy 216.463297 -272.350437) (xy 216.448893 -272.364759) (xy 216.430096 -272.372458)
			(xy 216.419938 -272.372836) (xy 215.020398 -272.372836) (xy 215.010268 -272.372374) (xy 214.991543 -272.364641)
			(xy 214.977185 -272.350347) (xy 214.969371 -272.331656) (xy 214.968836 -272.321528) (xy 208.9277 -272.321528)
			(xy 208.927301 -272.331684) (xy 208.919497 -272.350437) (xy 208.905093 -272.364759) (xy 208.886296 -272.372458)
			(xy 208.876138 -272.372836) (xy 207.476598 -272.372836) (xy 207.466468 -272.372374) (xy 207.447743 -272.364641)
			(xy 207.433385 -272.350347) (xy 207.425571 -272.331656) (xy 207.425036 -272.321528) (xy 201.3839 -272.321528)
			(xy 201.383501 -272.331684) (xy 201.375697 -272.350437) (xy 201.361293 -272.364759) (xy 201.342496 -272.372458)
			(xy 201.332338 -272.372836) (xy 199.932798 -272.372836) (xy 199.922668 -272.372374) (xy 199.903943 -272.364641)
			(xy 199.889585 -272.350347) (xy 199.881771 -272.331656) (xy 199.881236 -272.321528) (xy 193.8401 -272.321528)
			(xy 193.839701 -272.331684) (xy 193.831897 -272.350437) (xy 193.817493 -272.364759) (xy 193.798696 -272.372458)
			(xy 193.788538 -272.372836) (xy 192.388998 -272.372836) (xy 192.378868 -272.372374) (xy 192.360143 -272.364641)
			(xy 192.345785 -272.350347) (xy 192.337971 -272.331656) (xy 192.337436 -272.321528) (xy 186.2963 -272.321528)
			(xy 186.295901 -272.331684) (xy 186.288097 -272.350437) (xy 186.273693 -272.364759) (xy 186.254896 -272.372458)
			(xy 186.244738 -272.372836) (xy 184.845198 -272.372836) (xy 184.835068 -272.372374) (xy 184.816343 -272.364641)
			(xy 184.801985 -272.350347) (xy 184.794171 -272.331656) (xy 184.793636 -272.321528) (xy 178.7525 -272.321528)
			(xy 178.752101 -272.331684) (xy 178.744297 -272.350437) (xy 178.729893 -272.364759) (xy 178.711096 -272.372458)
			(xy 178.700938 -272.372836) (xy 177.301398 -272.372836) (xy 177.291268 -272.372374) (xy 177.272543 -272.364641)
			(xy 177.258185 -272.350347) (xy 177.250371 -272.331656) (xy 177.249836 -272.321528) (xy 171.2087 -272.321528)
			(xy 171.208301 -272.331684) (xy 171.200497 -272.350437) (xy 171.186093 -272.364759) (xy 171.167296 -272.372458)
			(xy 171.157138 -272.372836) (xy 169.757598 -272.372836) (xy 169.747468 -272.372374) (xy 169.728743 -272.364641)
			(xy 169.714385 -272.350347) (xy 169.706571 -272.331656) (xy 169.706036 -272.321528) (xy 163.6649 -272.321528)
			(xy 163.664501 -272.331684) (xy 163.656697 -272.350437) (xy 163.642293 -272.364759) (xy 163.623496 -272.372458)
			(xy 163.613338 -272.372836) (xy 162.213798 -272.372836) (xy 162.203668 -272.372374) (xy 162.184943 -272.364641)
			(xy 162.170585 -272.350347) (xy 162.162771 -272.331656) (xy 162.162236 -272.321528) (xy 65.7987 -272.321528)
			(xy 65.798301 -272.331684) (xy 65.790497 -272.350437) (xy 65.776093 -272.364759) (xy 65.757296 -272.372458)
			(xy 65.747138 -272.372836) (xy 64.347598 -272.372836) (xy 64.337468 -272.372374) (xy 64.318743 -272.364641)
			(xy 64.304385 -272.350347) (xy 64.296571 -272.331656) (xy 64.296036 -272.321528) (xy 58.2549 -272.321528)
			(xy 58.254501 -272.331684) (xy 58.246697 -272.350437) (xy 58.232293 -272.364759) (xy 58.213496 -272.372458)
			(xy 58.203338 -272.372836) (xy 56.803798 -272.372836) (xy 56.793668 -272.372374) (xy 56.774943 -272.364641)
			(xy 56.760585 -272.350347) (xy 56.752771 -272.331656) (xy 56.752236 -272.321528) (xy 50.7111 -272.321528)
			(xy 50.710701 -272.331684) (xy 50.702897 -272.350437) (xy 50.688493 -272.364759) (xy 50.669696 -272.372458)
			(xy 50.659538 -272.372836) (xy 49.259998 -272.372836) (xy 49.249868 -272.372374) (xy 49.231143 -272.364641)
			(xy 49.216785 -272.350347) (xy 49.208971 -272.331656) (xy 49.208436 -272.321528) (xy 43.1673 -272.321528)
			(xy 43.166901 -272.331684) (xy 43.159097 -272.350437) (xy 43.144693 -272.364759) (xy 43.125896 -272.372458)
			(xy 43.115738 -272.372836) (xy 41.716198 -272.372836) (xy 41.706068 -272.372374) (xy 41.687343 -272.364641)
			(xy 41.672985 -272.350347) (xy 41.665171 -272.331656) (xy 41.664636 -272.321528) (xy 35.6235 -272.321528)
			(xy 35.623101 -272.331684) (xy 35.615297 -272.350437) (xy 35.600893 -272.364759) (xy 35.582096 -272.372458)
			(xy 35.571938 -272.372836) (xy 34.172398 -272.372836) (xy 34.162268 -272.372374) (xy 34.143543 -272.364641)
			(xy 34.129185 -272.350347) (xy 34.121371 -272.331656) (xy 34.120836 -272.321528) (xy 28.0797 -272.321528)
			(xy 28.079301 -272.331684) (xy 28.071497 -272.350437) (xy 28.057093 -272.364759) (xy 28.038296 -272.372458)
			(xy 28.028138 -272.372836) (xy 26.628598 -272.372836) (xy 26.618468 -272.372374) (xy 26.599743 -272.364641)
			(xy 26.585385 -272.350347) (xy 26.577571 -272.331656) (xy 26.577036 -272.321528) (xy 20.5359 -272.321528)
			(xy 20.535501 -272.331684) (xy 20.527697 -272.350437) (xy 20.513293 -272.364759) (xy 20.494496 -272.372458)
			(xy 20.484338 -272.372836) (xy 19.084798 -272.372836) (xy 19.074668 -272.372374) (xy 19.055943 -272.364641)
			(xy 19.041585 -272.350347) (xy 19.033771 -272.331656) (xy 19.033236 -272.321528) (xy 12.9921 -272.321528)
			(xy 12.991701 -272.331684) (xy 12.983897 -272.350437) (xy 12.969493 -272.364759) (xy 12.950696 -272.372458)
			(xy 12.940538 -272.372836) (xy 11.540998 -272.372836) (xy 11.530868 -272.372374) (xy 11.512143 -272.364641)
			(xy 11.497785 -272.350347) (xy 11.489971 -272.331656) (xy 11.489436 -272.321528) (xy 2.509012 -272.321528)
			(xy 2.509012 -273.171412) (xy 7.389368 -273.171412) (xy 7.389368 -272.762472) (xy 7.389798 -272.75232)
			(xy 7.397597 -272.733573) (xy 7.41199 -272.719252) (xy 7.430776 -272.711547) (xy 7.44093 -272.711164)
			(xy 8.84047 -272.711164) (xy 8.850598 -272.711652) (xy 8.869323 -272.719374) (xy 8.883681 -272.733661)
			(xy 8.891497 -272.752347) (xy 8.892032 -272.762472) (xy 8.892032 -273.171412) (xy 14.933168 -273.171412)
			(xy 14.933168 -272.762472) (xy 14.933598 -272.75232) (xy 14.941397 -272.733573) (xy 14.95579 -272.719252)
			(xy 14.974576 -272.711547) (xy 14.98473 -272.711164) (xy 16.38427 -272.711164) (xy 16.394398 -272.711652)
			(xy 16.413123 -272.719374) (xy 16.427481 -272.733661) (xy 16.435297 -272.752347) (xy 16.435832 -272.762472)
			(xy 16.435832 -273.171412) (xy 22.476968 -273.171412) (xy 22.476968 -272.762472) (xy 22.477398 -272.75232)
			(xy 22.485197 -272.733573) (xy 22.49959 -272.719252) (xy 22.518376 -272.711547) (xy 22.52853 -272.711164)
			(xy 23.92807 -272.711164) (xy 23.938198 -272.711652) (xy 23.956923 -272.719374) (xy 23.971281 -272.733661)
			(xy 23.979097 -272.752347) (xy 23.979632 -272.762472) (xy 23.979632 -273.171412) (xy 30.020768 -273.171412)
			(xy 30.020768 -272.762472) (xy 30.021198 -272.75232) (xy 30.028997 -272.733573) (xy 30.04339 -272.719252)
			(xy 30.062176 -272.711547) (xy 30.07233 -272.711164) (xy 31.47187 -272.711164) (xy 31.481998 -272.711652)
			(xy 31.500723 -272.719374) (xy 31.515081 -272.733661) (xy 31.522897 -272.752347) (xy 31.523432 -272.762472)
			(xy 31.523432 -273.171412) (xy 37.564568 -273.171412) (xy 37.564568 -272.762472) (xy 37.564998 -272.75232)
			(xy 37.572797 -272.733573) (xy 37.58719 -272.719252) (xy 37.605976 -272.711547) (xy 37.61613 -272.711164)
			(xy 39.01567 -272.711164) (xy 39.025798 -272.711652) (xy 39.044523 -272.719374) (xy 39.058881 -272.733661)
			(xy 39.066697 -272.752347) (xy 39.067232 -272.762472) (xy 39.067232 -273.171412) (xy 45.108368 -273.171412)
			(xy 45.108368 -272.762472) (xy 45.108798 -272.75232) (xy 45.116597 -272.733573) (xy 45.13099 -272.719252)
			(xy 45.149776 -272.711547) (xy 45.15993 -272.711164) (xy 46.55947 -272.711164) (xy 46.569598 -272.711652)
			(xy 46.588323 -272.719374) (xy 46.602681 -272.733661) (xy 46.610497 -272.752347) (xy 46.611032 -272.762472)
			(xy 46.611032 -273.171412) (xy 52.652168 -273.171412) (xy 52.652168 -272.762472) (xy 52.652598 -272.75232)
			(xy 52.660397 -272.733573) (xy 52.67479 -272.719252) (xy 52.693576 -272.711547) (xy 52.70373 -272.711164)
			(xy 54.10327 -272.711164) (xy 54.113398 -272.711652) (xy 54.132123 -272.719374) (xy 54.146481 -272.733661)
			(xy 54.154297 -272.752347) (xy 54.154832 -272.762472) (xy 54.154832 -273.171412) (xy 60.195968 -273.171412)
			(xy 60.195968 -272.762472) (xy 60.196398 -272.75232) (xy 60.204197 -272.733573) (xy 60.21859 -272.719252)
			(xy 60.237376 -272.711547) (xy 60.24753 -272.711164) (xy 61.64707 -272.711164) (xy 61.657198 -272.711652)
			(xy 61.675923 -272.719374) (xy 61.690281 -272.733661) (xy 61.698097 -272.752347) (xy 61.698632 -272.762472)
			(xy 61.698632 -273.171412) (xy 61.698189 -273.181563) (xy 61.690396 -273.20031) (xy 61.676006 -273.214631)
			(xy 61.657223 -273.222336) (xy 61.64707 -273.22272) (xy 60.24753 -273.22272) (xy 60.2374 -273.222248)
			(xy 60.218672 -273.214523) (xy 60.204313 -273.200231) (xy 60.1965 -273.181539) (xy 60.195968 -273.171412)
			(xy 54.154832 -273.171412) (xy 54.154389 -273.181563) (xy 54.146596 -273.20031) (xy 54.132206 -273.214631)
			(xy 54.113423 -273.222336) (xy 54.10327 -273.22272) (xy 52.70373 -273.22272) (xy 52.6936 -273.222248)
			(xy 52.674872 -273.214523) (xy 52.660513 -273.200231) (xy 52.6527 -273.181539) (xy 52.652168 -273.171412)
			(xy 46.611032 -273.171412) (xy 46.610589 -273.181563) (xy 46.602796 -273.20031) (xy 46.588406 -273.214631)
			(xy 46.569623 -273.222336) (xy 46.55947 -273.22272) (xy 45.15993 -273.22272) (xy 45.1498 -273.222248)
			(xy 45.131072 -273.214523) (xy 45.116713 -273.200231) (xy 45.1089 -273.181539) (xy 45.108368 -273.171412)
			(xy 39.067232 -273.171412) (xy 39.066789 -273.181563) (xy 39.058996 -273.20031) (xy 39.044606 -273.214631)
			(xy 39.025823 -273.222336) (xy 39.01567 -273.22272) (xy 37.61613 -273.22272) (xy 37.606 -273.222248)
			(xy 37.587272 -273.214523) (xy 37.572913 -273.200231) (xy 37.5651 -273.181539) (xy 37.564568 -273.171412)
			(xy 31.523432 -273.171412) (xy 31.522989 -273.181563) (xy 31.515196 -273.20031) (xy 31.500806 -273.214631)
			(xy 31.482023 -273.222336) (xy 31.47187 -273.22272) (xy 30.07233 -273.22272) (xy 30.0622 -273.222248)
			(xy 30.043472 -273.214523) (xy 30.029113 -273.200231) (xy 30.0213 -273.181539) (xy 30.020768 -273.171412)
			(xy 23.979632 -273.171412) (xy 23.979189 -273.181563) (xy 23.971396 -273.20031) (xy 23.957006 -273.214631)
			(xy 23.938223 -273.222336) (xy 23.92807 -273.22272) (xy 22.52853 -273.22272) (xy 22.5184 -273.222248)
			(xy 22.499672 -273.214523) (xy 22.485313 -273.200231) (xy 22.4775 -273.181539) (xy 22.476968 -273.171412)
			(xy 16.435832 -273.171412) (xy 16.435389 -273.181563) (xy 16.427596 -273.20031) (xy 16.413206 -273.214631)
			(xy 16.394423 -273.222336) (xy 16.38427 -273.22272) (xy 14.98473 -273.22272) (xy 14.9746 -273.222248)
			(xy 14.955872 -273.214523) (xy 14.941513 -273.200231) (xy 14.9337 -273.181539) (xy 14.933168 -273.171412)
			(xy 8.892032 -273.171412) (xy 8.891589 -273.181563) (xy 8.883796 -273.20031) (xy 8.869406 -273.214631)
			(xy 8.850623 -273.222336) (xy 8.84047 -273.22272) (xy 7.44093 -273.22272) (xy 7.4308 -273.222248)
			(xy 7.412072 -273.214523) (xy 7.397713 -273.200231) (xy 7.3899 -273.181539) (xy 7.389368 -273.171412)
			(xy 2.509012 -273.171412) (xy 2.509012 -273.453098) (xy 108.601256 -273.453098) (xy 108.601764 -273.427211)
			(xy 108.609863 -273.376073) (xy 108.625862 -273.326833) (xy 108.649368 -273.280701) (xy 108.6798 -273.238814)
			(xy 108.71641 -273.202204) (xy 108.758297 -273.171772) (xy 108.804429 -273.148266) (xy 108.853669 -273.132267)
			(xy 108.904807 -273.124168) (xy 108.956581 -273.124168) (xy 109.007719 -273.132267) (xy 109.056959 -273.148266)
			(xy 109.102384 -273.171412) (xy 158.062168 -273.171412) (xy 158.062168 -272.762472) (xy 158.062598 -272.75232)
			(xy 158.070397 -272.733573) (xy 158.08479 -272.719252) (xy 158.103576 -272.711547) (xy 158.11373 -272.711164)
			(xy 159.51327 -272.711164) (xy 159.523398 -272.711652) (xy 159.542123 -272.719374) (xy 159.556481 -272.733661)
			(xy 159.564297 -272.752347) (xy 159.564832 -272.762472) (xy 159.564832 -273.171412) (xy 165.605968 -273.171412)
			(xy 165.605968 -272.762472) (xy 165.606398 -272.75232) (xy 165.614197 -272.733573) (xy 165.62859 -272.719252)
			(xy 165.647376 -272.711547) (xy 165.65753 -272.711164) (xy 167.05707 -272.711164) (xy 167.067198 -272.711652)
			(xy 167.085923 -272.719374) (xy 167.100281 -272.733661) (xy 167.108097 -272.752347) (xy 167.108632 -272.762472)
			(xy 167.108632 -273.171412) (xy 173.149768 -273.171412) (xy 173.149768 -272.762472) (xy 173.150198 -272.75232)
			(xy 173.157997 -272.733573) (xy 173.17239 -272.719252) (xy 173.191176 -272.711547) (xy 173.20133 -272.711164)
			(xy 174.60087 -272.711164) (xy 174.610998 -272.711652) (xy 174.629723 -272.719374) (xy 174.644081 -272.733661)
			(xy 174.651897 -272.752347) (xy 174.652432 -272.762472) (xy 174.652432 -273.171412) (xy 180.693568 -273.171412)
			(xy 180.693568 -272.762472) (xy 180.693998 -272.75232) (xy 180.701797 -272.733573) (xy 180.71619 -272.719252)
			(xy 180.734976 -272.711547) (xy 180.74513 -272.711164) (xy 182.14467 -272.711164) (xy 182.154798 -272.711652)
			(xy 182.173523 -272.719374) (xy 182.187881 -272.733661) (xy 182.195697 -272.752347) (xy 182.196232 -272.762472)
			(xy 182.196232 -273.171412) (xy 188.237368 -273.171412) (xy 188.237368 -272.762472) (xy 188.237798 -272.75232)
			(xy 188.245597 -272.733573) (xy 188.25999 -272.719252) (xy 188.278776 -272.711547) (xy 188.28893 -272.711164)
			(xy 189.68847 -272.711164) (xy 189.698598 -272.711652) (xy 189.717323 -272.719374) (xy 189.731681 -272.733661)
			(xy 189.739497 -272.752347) (xy 189.740032 -272.762472) (xy 189.740032 -273.171412) (xy 195.781168 -273.171412)
			(xy 195.781168 -272.762472) (xy 195.781598 -272.75232) (xy 195.789397 -272.733573) (xy 195.80379 -272.719252)
			(xy 195.822576 -272.711547) (xy 195.83273 -272.711164) (xy 197.23227 -272.711164) (xy 197.242398 -272.711652)
			(xy 197.261123 -272.719374) (xy 197.275481 -272.733661) (xy 197.283297 -272.752347) (xy 197.283832 -272.762472)
			(xy 197.283832 -273.171412) (xy 203.324968 -273.171412) (xy 203.324968 -272.762472) (xy 203.325398 -272.75232)
			(xy 203.333197 -272.733573) (xy 203.34759 -272.719252) (xy 203.366376 -272.711547) (xy 203.37653 -272.711164)
			(xy 204.77607 -272.711164) (xy 204.786198 -272.711652) (xy 204.804923 -272.719374) (xy 204.819281 -272.733661)
			(xy 204.827097 -272.752347) (xy 204.827632 -272.762472) (xy 204.827632 -273.171412) (xy 210.868768 -273.171412)
			(xy 210.868768 -272.762472) (xy 210.869198 -272.75232) (xy 210.876997 -272.733573) (xy 210.89139 -272.719252)
			(xy 210.910176 -272.711547) (xy 210.92033 -272.711164) (xy 212.31987 -272.711164) (xy 212.329998 -272.711652)
			(xy 212.348723 -272.719374) (xy 212.363081 -272.733661) (xy 212.370897 -272.752347) (xy 212.371432 -272.762472)
			(xy 212.371432 -273.171412) (xy 255.329436 -273.171412) (xy 255.329436 -272.762472) (xy 255.329799 -272.752312)
			(xy 255.337611 -272.733552) (xy 255.352026 -272.719228) (xy 255.370835 -272.711536) (xy 255.380998 -272.711164)
			(xy 256.780538 -272.711164) (xy 256.79067 -272.711596) (xy 256.809397 -272.719341) (xy 256.823752 -272.733644)
			(xy 256.831566 -272.752342) (xy 256.8321 -272.762472) (xy 256.8321 -273.171412) (xy 262.873236 -273.171412)
			(xy 262.873236 -272.762472) (xy 262.873599 -272.752312) (xy 262.881411 -272.733552) (xy 262.895826 -272.719228)
			(xy 262.914635 -272.711536) (xy 262.924798 -272.711164) (xy 264.324338 -272.711164) (xy 264.33447 -272.711596)
			(xy 264.353197 -272.719341) (xy 264.367552 -272.733644) (xy 264.375366 -272.752342) (xy 264.3759 -272.762472)
			(xy 264.3759 -273.171412) (xy 270.417036 -273.171412) (xy 270.417036 -272.762472) (xy 270.417399 -272.752312)
			(xy 270.425211 -272.733552) (xy 270.439626 -272.719228) (xy 270.458435 -272.711536) (xy 270.468598 -272.711164)
			(xy 271.868138 -272.711164) (xy 271.87827 -272.711596) (xy 271.896997 -272.719341) (xy 271.911352 -272.733644)
			(xy 271.919166 -272.752342) (xy 271.9197 -272.762472) (xy 271.9197 -273.171412) (xy 277.960836 -273.171412)
			(xy 277.960836 -272.762472) (xy 277.961199 -272.752312) (xy 277.969011 -272.733552) (xy 277.983426 -272.719228)
			(xy 278.002235 -272.711536) (xy 278.012398 -272.711164) (xy 279.411938 -272.711164) (xy 279.42207 -272.711596)
			(xy 279.440797 -272.719341) (xy 279.455152 -272.733644) (xy 279.462966 -272.752342) (xy 279.4635 -272.762472)
			(xy 279.4635 -273.171412) (xy 285.504636 -273.171412) (xy 285.504636 -272.762472) (xy 285.504999 -272.752312)
			(xy 285.512811 -272.733552) (xy 285.527226 -272.719228) (xy 285.546035 -272.711536) (xy 285.556198 -272.711164)
			(xy 286.955738 -272.711164) (xy 286.96587 -272.711596) (xy 286.984597 -272.719341) (xy 286.998952 -272.733644)
			(xy 287.006766 -272.752342) (xy 287.0073 -272.762472) (xy 287.0073 -273.171412) (xy 293.048436 -273.171412)
			(xy 293.048436 -272.762472) (xy 293.048799 -272.752312) (xy 293.056611 -272.733552) (xy 293.071026 -272.719228)
			(xy 293.089835 -272.711536) (xy 293.099998 -272.711164) (xy 294.499538 -272.711164) (xy 294.50967 -272.711596)
			(xy 294.528397 -272.719341) (xy 294.542752 -272.733644) (xy 294.550566 -272.752342) (xy 294.5511 -272.762472)
			(xy 294.5511 -273.171412) (xy 300.592236 -273.171412) (xy 300.592236 -272.762472) (xy 300.592599 -272.752312)
			(xy 300.600411 -272.733552) (xy 300.614826 -272.719228) (xy 300.633635 -272.711536) (xy 300.643798 -272.711164)
			(xy 302.043338 -272.711164) (xy 302.05347 -272.711596) (xy 302.072197 -272.719341) (xy 302.086552 -272.733644)
			(xy 302.094366 -272.752342) (xy 302.0949 -272.762472) (xy 302.0949 -273.171412) (xy 308.136036 -273.171412)
			(xy 308.136036 -272.762472) (xy 308.136399 -272.752312) (xy 308.144211 -272.733552) (xy 308.158626 -272.719228)
			(xy 308.177435 -272.711536) (xy 308.187598 -272.711164) (xy 309.587138 -272.711164) (xy 309.59727 -272.711596)
			(xy 309.615997 -272.719341) (xy 309.630352 -272.733644) (xy 309.638166 -272.752342) (xy 309.6387 -272.762472)
			(xy 309.6387 -273.171412) (xy 309.638288 -273.181567) (xy 309.630489 -273.20032) (xy 309.616089 -273.214643)
			(xy 309.597295 -273.222342) (xy 309.587138 -273.22272) (xy 308.187598 -273.22272) (xy 308.177466 -273.222274)
			(xy 308.158738 -273.214538) (xy 308.14438 -273.200239) (xy 308.136568 -273.181542) (xy 308.136036 -273.171412)
			(xy 302.0949 -273.171412) (xy 302.094488 -273.181567) (xy 302.086689 -273.20032) (xy 302.072289 -273.214643)
			(xy 302.053495 -273.222342) (xy 302.043338 -273.22272) (xy 300.643798 -273.22272) (xy 300.633666 -273.222274)
			(xy 300.614938 -273.214538) (xy 300.60058 -273.200239) (xy 300.592768 -273.181542) (xy 300.592236 -273.171412)
			(xy 294.5511 -273.171412) (xy 294.550688 -273.181567) (xy 294.542889 -273.20032) (xy 294.528489 -273.214643)
			(xy 294.509695 -273.222342) (xy 294.499538 -273.22272) (xy 293.099998 -273.22272) (xy 293.089866 -273.222274)
			(xy 293.071138 -273.214538) (xy 293.05678 -273.200239) (xy 293.048968 -273.181542) (xy 293.048436 -273.171412)
			(xy 287.0073 -273.171412) (xy 287.006888 -273.181567) (xy 286.999089 -273.20032) (xy 286.984689 -273.214643)
			(xy 286.965895 -273.222342) (xy 286.955738 -273.22272) (xy 285.556198 -273.22272) (xy 285.546066 -273.222274)
			(xy 285.527338 -273.214538) (xy 285.51298 -273.200239) (xy 285.505168 -273.181542) (xy 285.504636 -273.171412)
			(xy 279.4635 -273.171412) (xy 279.463088 -273.181567) (xy 279.455289 -273.20032) (xy 279.440889 -273.214643)
			(xy 279.422095 -273.222342) (xy 279.411938 -273.22272) (xy 278.012398 -273.22272) (xy 278.002266 -273.222274)
			(xy 277.983538 -273.214538) (xy 277.96918 -273.200239) (xy 277.961368 -273.181542) (xy 277.960836 -273.171412)
			(xy 271.9197 -273.171412) (xy 271.919288 -273.181567) (xy 271.911489 -273.20032) (xy 271.897089 -273.214643)
			(xy 271.878295 -273.222342) (xy 271.868138 -273.22272) (xy 270.468598 -273.22272) (xy 270.458466 -273.222274)
			(xy 270.439738 -273.214538) (xy 270.42538 -273.200239) (xy 270.417568 -273.181542) (xy 270.417036 -273.171412)
			(xy 264.3759 -273.171412) (xy 264.375488 -273.181567) (xy 264.367689 -273.20032) (xy 264.353289 -273.214643)
			(xy 264.334495 -273.222342) (xy 264.324338 -273.22272) (xy 262.924798 -273.22272) (xy 262.914666 -273.222274)
			(xy 262.895938 -273.214538) (xy 262.88158 -273.200239) (xy 262.873768 -273.181542) (xy 262.873236 -273.171412)
			(xy 256.8321 -273.171412) (xy 256.831688 -273.181567) (xy 256.823889 -273.20032) (xy 256.809489 -273.214643)
			(xy 256.790695 -273.222342) (xy 256.780538 -273.22272) (xy 255.380998 -273.22272) (xy 255.370866 -273.222274)
			(xy 255.352138 -273.214538) (xy 255.33778 -273.200239) (xy 255.329968 -273.181542) (xy 255.329436 -273.171412)
			(xy 212.371432 -273.171412) (xy 212.370989 -273.181563) (xy 212.363196 -273.20031) (xy 212.348806 -273.214631)
			(xy 212.330023 -273.222336) (xy 212.31987 -273.22272) (xy 210.92033 -273.22272) (xy 210.9102 -273.222248)
			(xy 210.891472 -273.214523) (xy 210.877113 -273.200231) (xy 210.8693 -273.181539) (xy 210.868768 -273.171412)
			(xy 204.827632 -273.171412) (xy 204.827189 -273.181563) (xy 204.819396 -273.20031) (xy 204.805006 -273.214631)
			(xy 204.786223 -273.222336) (xy 204.77607 -273.22272) (xy 203.37653 -273.22272) (xy 203.3664 -273.222248)
			(xy 203.347672 -273.214523) (xy 203.333313 -273.200231) (xy 203.3255 -273.181539) (xy 203.324968 -273.171412)
			(xy 197.283832 -273.171412) (xy 197.283389 -273.181563) (xy 197.275596 -273.20031) (xy 197.261206 -273.214631)
			(xy 197.242423 -273.222336) (xy 197.23227 -273.22272) (xy 195.83273 -273.22272) (xy 195.8226 -273.222248)
			(xy 195.803872 -273.214523) (xy 195.789513 -273.200231) (xy 195.7817 -273.181539) (xy 195.781168 -273.171412)
			(xy 189.740032 -273.171412) (xy 189.739589 -273.181563) (xy 189.731796 -273.20031) (xy 189.717406 -273.214631)
			(xy 189.698623 -273.222336) (xy 189.68847 -273.22272) (xy 188.28893 -273.22272) (xy 188.2788 -273.222248)
			(xy 188.260072 -273.214523) (xy 188.245713 -273.200231) (xy 188.2379 -273.181539) (xy 188.237368 -273.171412)
			(xy 182.196232 -273.171412) (xy 182.195789 -273.181563) (xy 182.187996 -273.20031) (xy 182.173606 -273.214631)
			(xy 182.154823 -273.222336) (xy 182.14467 -273.22272) (xy 180.74513 -273.22272) (xy 180.735 -273.222248)
			(xy 180.716272 -273.214523) (xy 180.701913 -273.200231) (xy 180.6941 -273.181539) (xy 180.693568 -273.171412)
			(xy 174.652432 -273.171412) (xy 174.651989 -273.181563) (xy 174.644196 -273.20031) (xy 174.629806 -273.214631)
			(xy 174.611023 -273.222336) (xy 174.60087 -273.22272) (xy 173.20133 -273.22272) (xy 173.1912 -273.222248)
			(xy 173.172472 -273.214523) (xy 173.158113 -273.200231) (xy 173.1503 -273.181539) (xy 173.149768 -273.171412)
			(xy 167.108632 -273.171412) (xy 167.108189 -273.181563) (xy 167.100396 -273.20031) (xy 167.086006 -273.214631)
			(xy 167.067223 -273.222336) (xy 167.05707 -273.22272) (xy 165.65753 -273.22272) (xy 165.6474 -273.222248)
			(xy 165.628672 -273.214523) (xy 165.614313 -273.200231) (xy 165.6065 -273.181539) (xy 165.605968 -273.171412)
			(xy 159.564832 -273.171412) (xy 159.564389 -273.181563) (xy 159.556596 -273.20031) (xy 159.542206 -273.214631)
			(xy 159.523423 -273.222336) (xy 159.51327 -273.22272) (xy 158.11373 -273.22272) (xy 158.1036 -273.222248)
			(xy 158.084872 -273.214523) (xy 158.070513 -273.200231) (xy 158.0627 -273.181539) (xy 158.062168 -273.171412)
			(xy 109.102384 -273.171412) (xy 109.103091 -273.171772) (xy 109.144978 -273.202204) (xy 109.181588 -273.238814)
			(xy 109.21202 -273.280701) (xy 109.235526 -273.326833) (xy 109.251525 -273.376073) (xy 109.259624 -273.427211)
			(xy 109.260132 -273.453098) (xy 356.541324 -273.453098) (xy 356.541832 -273.427211) (xy 356.549931 -273.376073)
			(xy 356.56593 -273.326833) (xy 356.589436 -273.280701) (xy 356.619868 -273.238814) (xy 356.656478 -273.202204)
			(xy 356.698365 -273.171772) (xy 356.744497 -273.148266) (xy 356.793737 -273.132267) (xy 356.844875 -273.124168)
			(xy 356.896649 -273.124168) (xy 356.947787 -273.132267) (xy 356.997027 -273.148266) (xy 357.042452 -273.171412)
			(xy 406.002236 -273.171412) (xy 406.002236 -272.762472) (xy 406.002599 -272.752312) (xy 406.010411 -272.733552)
			(xy 406.024826 -272.719228) (xy 406.043635 -272.711536) (xy 406.053798 -272.711164) (xy 407.453338 -272.711164)
			(xy 407.46347 -272.711596) (xy 407.482197 -272.719341) (xy 407.496552 -272.733644) (xy 407.504366 -272.752342)
			(xy 407.5049 -272.762472) (xy 407.5049 -273.171412) (xy 413.546036 -273.171412) (xy 413.546036 -272.762472)
			(xy 413.546399 -272.752312) (xy 413.554211 -272.733552) (xy 413.568626 -272.719228) (xy 413.587435 -272.711536)
			(xy 413.597598 -272.711164) (xy 414.997138 -272.711164) (xy 415.00727 -272.711596) (xy 415.025997 -272.719341)
			(xy 415.040352 -272.733644) (xy 415.048166 -272.752342) (xy 415.0487 -272.762472) (xy 415.0487 -273.171412)
			(xy 421.089836 -273.171412) (xy 421.089836 -272.762472) (xy 421.090199 -272.752312) (xy 421.098011 -272.733552)
			(xy 421.112426 -272.719228) (xy 421.131235 -272.711536) (xy 421.141398 -272.711164) (xy 422.540938 -272.711164)
			(xy 422.55107 -272.711596) (xy 422.569797 -272.719341) (xy 422.584152 -272.733644) (xy 422.591966 -272.752342)
			(xy 422.5925 -272.762472) (xy 422.5925 -273.171412) (xy 428.633636 -273.171412) (xy 428.633636 -272.762472)
			(xy 428.633999 -272.752312) (xy 428.641811 -272.733552) (xy 428.656226 -272.719228) (xy 428.675035 -272.711536)
			(xy 428.685198 -272.711164) (xy 430.084738 -272.711164) (xy 430.09487 -272.711596) (xy 430.113597 -272.719341)
			(xy 430.127952 -272.733644) (xy 430.135766 -272.752342) (xy 430.1363 -272.762472) (xy 430.1363 -273.171412)
			(xy 436.177436 -273.171412) (xy 436.177436 -272.762472) (xy 436.177799 -272.752312) (xy 436.185611 -272.733552)
			(xy 436.200026 -272.719228) (xy 436.218835 -272.711536) (xy 436.228998 -272.711164) (xy 437.628538 -272.711164)
			(xy 437.63867 -272.711596) (xy 437.657397 -272.719341) (xy 437.671752 -272.733644) (xy 437.679566 -272.752342)
			(xy 437.6801 -272.762472) (xy 437.6801 -273.171412) (xy 443.721236 -273.171412) (xy 443.721236 -272.762472)
			(xy 443.721599 -272.752312) (xy 443.729411 -272.733552) (xy 443.743826 -272.719228) (xy 443.762635 -272.711536)
			(xy 443.772798 -272.711164) (xy 445.172338 -272.711164) (xy 445.18247 -272.711596) (xy 445.201197 -272.719341)
			(xy 445.215552 -272.733644) (xy 445.223366 -272.752342) (xy 445.2239 -272.762472) (xy 445.2239 -273.171412)
			(xy 451.265036 -273.171412) (xy 451.265036 -272.762472) (xy 451.265399 -272.752312) (xy 451.273211 -272.733552)
			(xy 451.287626 -272.719228) (xy 451.306435 -272.711536) (xy 451.316598 -272.711164) (xy 452.716138 -272.711164)
			(xy 452.72627 -272.711596) (xy 452.744997 -272.719341) (xy 452.759352 -272.733644) (xy 452.767166 -272.752342)
			(xy 452.7677 -272.762472) (xy 452.7677 -273.171412) (xy 458.808836 -273.171412) (xy 458.808836 -272.762472)
			(xy 458.809199 -272.752312) (xy 458.817011 -272.733552) (xy 458.831426 -272.719228) (xy 458.850235 -272.711536)
			(xy 458.860398 -272.711164) (xy 460.259938 -272.711164) (xy 460.27007 -272.711596) (xy 460.288797 -272.719341)
			(xy 460.303152 -272.733644) (xy 460.310966 -272.752342) (xy 460.3115 -272.762472) (xy 460.3115 -273.171412)
			(xy 460.311088 -273.181567) (xy 460.303289 -273.20032) (xy 460.288889 -273.214643) (xy 460.270095 -273.222342)
			(xy 460.259938 -273.22272) (xy 458.860398 -273.22272) (xy 458.850266 -273.222274) (xy 458.831538 -273.214538)
			(xy 458.81718 -273.200239) (xy 458.809368 -273.181542) (xy 458.808836 -273.171412) (xy 452.7677 -273.171412)
			(xy 452.767288 -273.181567) (xy 452.759489 -273.20032) (xy 452.745089 -273.214643) (xy 452.726295 -273.222342)
			(xy 452.716138 -273.22272) (xy 451.316598 -273.22272) (xy 451.306466 -273.222274) (xy 451.287738 -273.214538)
			(xy 451.27338 -273.200239) (xy 451.265568 -273.181542) (xy 451.265036 -273.171412) (xy 445.2239 -273.171412)
			(xy 445.223488 -273.181567) (xy 445.215689 -273.20032) (xy 445.201289 -273.214643) (xy 445.182495 -273.222342)
			(xy 445.172338 -273.22272) (xy 443.772798 -273.22272) (xy 443.762666 -273.222274) (xy 443.743938 -273.214538)
			(xy 443.72958 -273.200239) (xy 443.721768 -273.181542) (xy 443.721236 -273.171412) (xy 437.6801 -273.171412)
			(xy 437.679688 -273.181567) (xy 437.671889 -273.20032) (xy 437.657489 -273.214643) (xy 437.638695 -273.222342)
			(xy 437.628538 -273.22272) (xy 436.228998 -273.22272) (xy 436.218866 -273.222274) (xy 436.200138 -273.214538)
			(xy 436.18578 -273.200239) (xy 436.177968 -273.181542) (xy 436.177436 -273.171412) (xy 430.1363 -273.171412)
			(xy 430.135888 -273.181567) (xy 430.128089 -273.20032) (xy 430.113689 -273.214643) (xy 430.094895 -273.222342)
			(xy 430.084738 -273.22272) (xy 428.685198 -273.22272) (xy 428.675066 -273.222274) (xy 428.656338 -273.214538)
			(xy 428.64198 -273.200239) (xy 428.634168 -273.181542) (xy 428.633636 -273.171412) (xy 422.5925 -273.171412)
			(xy 422.592088 -273.181567) (xy 422.584289 -273.20032) (xy 422.569889 -273.214643) (xy 422.551095 -273.222342)
			(xy 422.540938 -273.22272) (xy 421.141398 -273.22272) (xy 421.131266 -273.222274) (xy 421.112538 -273.214538)
			(xy 421.09818 -273.200239) (xy 421.090368 -273.181542) (xy 421.089836 -273.171412) (xy 415.0487 -273.171412)
			(xy 415.048288 -273.181567) (xy 415.040489 -273.20032) (xy 415.026089 -273.214643) (xy 415.007295 -273.222342)
			(xy 414.997138 -273.22272) (xy 413.597598 -273.22272) (xy 413.587466 -273.222274) (xy 413.568738 -273.214538)
			(xy 413.55438 -273.200239) (xy 413.546568 -273.181542) (xy 413.546036 -273.171412) (xy 407.5049 -273.171412)
			(xy 407.504488 -273.181567) (xy 407.496689 -273.20032) (xy 407.482289 -273.214643) (xy 407.463495 -273.222342)
			(xy 407.453338 -273.22272) (xy 406.053798 -273.22272) (xy 406.043666 -273.222274) (xy 406.024938 -273.214538)
			(xy 406.01058 -273.200239) (xy 406.002768 -273.181542) (xy 406.002236 -273.171412) (xy 357.042452 -273.171412)
			(xy 357.043159 -273.171772) (xy 357.085046 -273.202204) (xy 357.121656 -273.238814) (xy 357.152088 -273.280701)
			(xy 357.175594 -273.326833) (xy 357.191593 -273.376073) (xy 357.199692 -273.427211) (xy 357.2002 -273.453098)
			(xy 357.19967 -273.480806) (xy 357.190475 -273.535453) (xy 357.181912 -273.56181) (xy 357.174292 -273.583654)
			(xy 357.37927 -273.938746) (xy 357.40213 -273.943064) (xy 357.426938 -273.948232) (xy 357.474677 -273.965225)
			(xy 357.519254 -273.989322) (xy 357.559619 -274.019956) (xy 357.561158 -274.02155) (xy 410.102304 -274.02155)
			(xy 410.102304 -273.61261) (xy 410.102841 -273.602457) (xy 410.110606 -273.583695) (xy 410.124958 -273.56933)
			(xy 410.143713 -273.561549) (xy 410.153866 -273.561048) (xy 411.553406 -273.561048) (xy 411.563579 -273.561459)
			(xy 411.582376 -273.569248) (xy 411.596761 -273.583637) (xy 411.604544 -273.602437) (xy 411.604968 -273.61261)
			(xy 411.604968 -274.02155) (xy 417.646104 -274.02155) (xy 417.646104 -273.61261) (xy 417.646641 -273.602457)
			(xy 417.654406 -273.583695) (xy 417.668758 -273.56933) (xy 417.687513 -273.561549) (xy 417.697666 -273.561048)
			(xy 419.097206 -273.561048) (xy 419.107379 -273.561459) (xy 419.126176 -273.569248) (xy 419.140561 -273.583637)
			(xy 419.148344 -273.602437) (xy 419.148768 -273.61261) (xy 419.148768 -274.02155) (xy 425.189904 -274.02155)
			(xy 425.189904 -273.61261) (xy 425.190441 -273.602457) (xy 425.198206 -273.583695) (xy 425.212558 -273.56933)
			(xy 425.231313 -273.561549) (xy 425.241466 -273.561048) (xy 426.641006 -273.561048) (xy 426.651179 -273.561459)
			(xy 426.669976 -273.569248) (xy 426.684361 -273.583637) (xy 426.692144 -273.602437) (xy 426.692568 -273.61261)
			(xy 426.692568 -274.02155) (xy 432.733704 -274.02155) (xy 432.733704 -273.61261) (xy 432.734241 -273.602457)
			(xy 432.742006 -273.583695) (xy 432.756358 -273.56933) (xy 432.775113 -273.561549) (xy 432.785266 -273.561048)
			(xy 434.184806 -273.561048) (xy 434.194979 -273.561459) (xy 434.213776 -273.569248) (xy 434.228161 -273.583637)
			(xy 434.235944 -273.602437) (xy 434.236368 -273.61261) (xy 434.236368 -274.02155) (xy 440.277504 -274.02155)
			(xy 440.277504 -273.61261) (xy 440.278041 -273.602457) (xy 440.285806 -273.583695) (xy 440.300158 -273.56933)
			(xy 440.318913 -273.561549) (xy 440.329066 -273.561048) (xy 441.728606 -273.561048) (xy 441.738779 -273.561459)
			(xy 441.757576 -273.569248) (xy 441.771961 -273.583637) (xy 441.779744 -273.602437) (xy 441.780168 -273.61261)
			(xy 441.780168 -274.02155) (xy 447.821304 -274.02155) (xy 447.821304 -273.61261) (xy 447.821841 -273.602457)
			(xy 447.829606 -273.583695) (xy 447.843958 -273.56933) (xy 447.862713 -273.561549) (xy 447.872866 -273.561048)
			(xy 449.272406 -273.561048) (xy 449.282579 -273.561459) (xy 449.301376 -273.569248) (xy 449.315761 -273.583637)
			(xy 449.323544 -273.602437) (xy 449.323968 -273.61261) (xy 449.323968 -274.02155) (xy 455.365104 -274.02155)
			(xy 455.365104 -273.61261) (xy 455.365641 -273.602457) (xy 455.373406 -273.583695) (xy 455.387758 -273.56933)
			(xy 455.406513 -273.561549) (xy 455.416666 -273.561048) (xy 456.816206 -273.561048) (xy 456.826379 -273.561459)
			(xy 456.845176 -273.569248) (xy 456.859561 -273.583637) (xy 456.867344 -273.602437) (xy 456.867768 -273.61261)
			(xy 456.867768 -274.02155) (xy 462.908904 -274.02155) (xy 462.908904 -273.61261) (xy 462.909441 -273.602457)
			(xy 462.917206 -273.583695) (xy 462.931558 -273.56933) (xy 462.950313 -273.561549) (xy 462.960466 -273.561048)
			(xy 464.360006 -273.561048) (xy 464.370179 -273.561459) (xy 464.388976 -273.569248) (xy 464.403361 -273.583637)
			(xy 464.411144 -273.602437) (xy 464.411568 -273.61261) (xy 464.411568 -274.02155) (xy 464.411095 -274.031718)
			(xy 464.403328 -274.05051) (xy 464.388957 -274.064897) (xy 464.370173 -274.072684) (xy 464.360006 -274.073112)
			(xy 462.960466 -274.073112) (xy 462.950286 -274.072763) (xy 462.931481 -274.064957) (xy 462.917095 -274.050548)
			(xy 462.909321 -274.031731) (xy 462.908904 -274.02155) (xy 456.867768 -274.02155) (xy 456.867295 -274.031718)
			(xy 456.859528 -274.05051) (xy 456.845157 -274.064897) (xy 456.826373 -274.072684) (xy 456.816206 -274.073112)
			(xy 455.416666 -274.073112) (xy 455.406486 -274.072763) (xy 455.387681 -274.064957) (xy 455.373295 -274.050548)
			(xy 455.365521 -274.031731) (xy 455.365104 -274.02155) (xy 449.323968 -274.02155) (xy 449.323495 -274.031718)
			(xy 449.315728 -274.05051) (xy 449.301357 -274.064897) (xy 449.282573 -274.072684) (xy 449.272406 -274.073112)
			(xy 447.872866 -274.073112) (xy 447.862686 -274.072763) (xy 447.843881 -274.064957) (xy 447.829495 -274.050548)
			(xy 447.821721 -274.031731) (xy 447.821304 -274.02155) (xy 441.780168 -274.02155) (xy 441.779695 -274.031718)
			(xy 441.771928 -274.05051) (xy 441.757557 -274.064897) (xy 441.738773 -274.072684) (xy 441.728606 -274.073112)
			(xy 440.329066 -274.073112) (xy 440.318886 -274.072763) (xy 440.300081 -274.064957) (xy 440.285695 -274.050548)
			(xy 440.277921 -274.031731) (xy 440.277504 -274.02155) (xy 434.236368 -274.02155) (xy 434.235895 -274.031718)
			(xy 434.228128 -274.05051) (xy 434.213757 -274.064897) (xy 434.194973 -274.072684) (xy 434.184806 -274.073112)
			(xy 432.785266 -274.073112) (xy 432.775086 -274.072763) (xy 432.756281 -274.064957) (xy 432.741895 -274.050548)
			(xy 432.734121 -274.031731) (xy 432.733704 -274.02155) (xy 426.692568 -274.02155) (xy 426.692095 -274.031718)
			(xy 426.684328 -274.05051) (xy 426.669957 -274.064897) (xy 426.651173 -274.072684) (xy 426.641006 -274.073112)
			(xy 425.241466 -274.073112) (xy 425.231286 -274.072763) (xy 425.212481 -274.064957) (xy 425.198095 -274.050548)
			(xy 425.190321 -274.031731) (xy 425.189904 -274.02155) (xy 419.148768 -274.02155) (xy 419.148295 -274.031718)
			(xy 419.140528 -274.05051) (xy 419.126157 -274.064897) (xy 419.107373 -274.072684) (xy 419.097206 -274.073112)
			(xy 417.697666 -274.073112) (xy 417.687486 -274.072763) (xy 417.668681 -274.064957) (xy 417.654295 -274.050548)
			(xy 417.646521 -274.031731) (xy 417.646104 -274.02155) (xy 411.604968 -274.02155) (xy 411.604495 -274.031718)
			(xy 411.596728 -274.05051) (xy 411.582357 -274.064897) (xy 411.563573 -274.072684) (xy 411.553406 -274.073112)
			(xy 410.153866 -274.073112) (xy 410.143686 -274.072763) (xy 410.124881 -274.064957) (xy 410.110495 -274.050548)
			(xy 410.102721 -274.031731) (xy 410.102304 -274.02155) (xy 357.561158 -274.02155) (xy 357.594821 -274.056405)
			(xy 357.624032 -274.097811) (xy 357.646564 -274.143199) (xy 357.661886 -274.191501) (xy 357.669637 -274.241577)
			(xy 357.6701 -274.266914) (xy 357.669592 -274.292801) (xy 357.661493 -274.343939) (xy 357.645494 -274.393179)
			(xy 357.621988 -274.439311) (xy 357.591556 -274.481198) (xy 357.554946 -274.517808) (xy 357.513059 -274.54824)
			(xy 357.466927 -274.571746) (xy 357.417687 -274.587745) (xy 357.366549 -274.595844) (xy 357.314775 -274.595844)
			(xy 357.263637 -274.587745) (xy 357.214397 -274.571746) (xy 357.168265 -274.54824) (xy 357.126378 -274.517808)
			(xy 357.089768 -274.481198) (xy 357.059336 -274.439311) (xy 357.03583 -274.393179) (xy 357.019831 -274.343939)
			(xy 357.011732 -274.292801) (xy 357.011224 -274.266914) (xy 357.011756 -274.239206) (xy 357.020949 -274.184559)
			(xy 357.029512 -274.158202) (xy 357.037386 -274.136104) (xy 356.832408 -273.781266) (xy 356.809548 -273.776948)
			(xy 356.784736 -273.771741) (xy 356.73696 -273.75479) (xy 356.692344 -273.730722) (xy 356.651938 -273.700106)
			(xy 356.616698 -273.663665) (xy 356.587453 -273.622257) (xy 356.564893 -273.576859) (xy 356.549551 -273.528542)
			(xy 356.541789 -273.478445) (xy 356.541324 -273.453098) (xy 109.260132 -273.453098) (xy 109.259601 -273.480806)
			(xy 109.250407 -273.535453) (xy 109.241844 -273.56181) (xy 109.234224 -273.583654) (xy 109.439202 -273.938746)
			(xy 109.462062 -273.943064) (xy 109.486859 -273.948281) (xy 109.534598 -273.965264) (xy 109.579176 -273.989353)
			(xy 109.619543 -274.019979) (xy 109.621061 -274.02155) (xy 162.162236 -274.02155) (xy 162.162236 -273.61261)
			(xy 162.162672 -273.602439) (xy 162.170453 -273.583645) (xy 162.184835 -273.56926) (xy 162.203627 -273.561474)
			(xy 162.213798 -273.561048) (xy 163.613338 -273.561048) (xy 163.623499 -273.561503) (xy 163.642271 -273.569291)
			(xy 163.656636 -273.583669) (xy 163.664407 -273.602448) (xy 163.6649 -273.61261) (xy 163.6649 -274.02155)
			(xy 169.706036 -274.02155) (xy 169.706036 -273.61261) (xy 169.706472 -273.602439) (xy 169.714253 -273.583645)
			(xy 169.728635 -273.56926) (xy 169.747427 -273.561474) (xy 169.757598 -273.561048) (xy 171.157138 -273.561048)
			(xy 171.167299 -273.561503) (xy 171.186071 -273.569291) (xy 171.200436 -273.583669) (xy 171.208207 -273.602448)
			(xy 171.2087 -273.61261) (xy 171.2087 -274.02155) (xy 177.249836 -274.02155) (xy 177.249836 -273.61261)
			(xy 177.250272 -273.602439) (xy 177.258053 -273.583645) (xy 177.272435 -273.56926) (xy 177.291227 -273.561474)
			(xy 177.301398 -273.561048) (xy 178.700938 -273.561048) (xy 178.711099 -273.561503) (xy 178.729871 -273.569291)
			(xy 178.744236 -273.583669) (xy 178.752007 -273.602448) (xy 178.7525 -273.61261) (xy 178.7525 -274.02155)
			(xy 184.793636 -274.02155) (xy 184.793636 -273.61261) (xy 184.794072 -273.602439) (xy 184.801853 -273.583645)
			(xy 184.816235 -273.56926) (xy 184.835027 -273.561474) (xy 184.845198 -273.561048) (xy 186.244738 -273.561048)
			(xy 186.254899 -273.561503) (xy 186.273671 -273.569291) (xy 186.288036 -273.583669) (xy 186.295807 -273.602448)
			(xy 186.2963 -273.61261) (xy 186.2963 -274.02155) (xy 192.337436 -274.02155) (xy 192.337436 -273.61261)
			(xy 192.337872 -273.602439) (xy 192.345653 -273.583645) (xy 192.360035 -273.56926) (xy 192.378827 -273.561474)
			(xy 192.388998 -273.561048) (xy 193.788538 -273.561048) (xy 193.798699 -273.561503) (xy 193.817471 -273.569291)
			(xy 193.831836 -273.583669) (xy 193.839607 -273.602448) (xy 193.8401 -273.61261) (xy 193.8401 -274.02155)
			(xy 199.881236 -274.02155) (xy 199.881236 -273.61261) (xy 199.881672 -273.602439) (xy 199.889453 -273.583645)
			(xy 199.903835 -273.56926) (xy 199.922627 -273.561474) (xy 199.932798 -273.561048) (xy 201.332338 -273.561048)
			(xy 201.342499 -273.561503) (xy 201.361271 -273.569291) (xy 201.375636 -273.583669) (xy 201.383407 -273.602448)
			(xy 201.3839 -273.61261) (xy 201.3839 -274.02155) (xy 207.425036 -274.02155) (xy 207.425036 -273.61261)
			(xy 207.425472 -273.602439) (xy 207.433253 -273.583645) (xy 207.447635 -273.56926) (xy 207.466427 -273.561474)
			(xy 207.476598 -273.561048) (xy 208.876138 -273.561048) (xy 208.886299 -273.561503) (xy 208.905071 -273.569291)
			(xy 208.919436 -273.583669) (xy 208.927207 -273.602448) (xy 208.9277 -273.61261) (xy 208.9277 -274.02155)
			(xy 214.968836 -274.02155) (xy 214.968836 -273.61261) (xy 214.969272 -273.602439) (xy 214.977053 -273.583645)
			(xy 214.991435 -273.56926) (xy 215.010227 -273.561474) (xy 215.020398 -273.561048) (xy 216.419938 -273.561048)
			(xy 216.430099 -273.561503) (xy 216.448871 -273.569291) (xy 216.463236 -273.583669) (xy 216.471007 -273.602448)
			(xy 216.4715 -273.61261) (xy 216.4715 -274.02155) (xy 259.429504 -274.02155) (xy 259.429504 -273.61261)
			(xy 259.430041 -273.602457) (xy 259.437806 -273.583695) (xy 259.452158 -273.56933) (xy 259.470913 -273.561549)
			(xy 259.481066 -273.561048) (xy 260.880606 -273.561048) (xy 260.890779 -273.561459) (xy 260.909576 -273.569248)
			(xy 260.923961 -273.583637) (xy 260.931744 -273.602437) (xy 260.932168 -273.61261) (xy 260.932168 -274.02155)
			(xy 266.973304 -274.02155) (xy 266.973304 -273.61261) (xy 266.973841 -273.602457) (xy 266.981606 -273.583695)
			(xy 266.995958 -273.56933) (xy 267.014713 -273.561549) (xy 267.024866 -273.561048) (xy 268.424406 -273.561048)
			(xy 268.434579 -273.561459) (xy 268.453376 -273.569248) (xy 268.467761 -273.583637) (xy 268.475544 -273.602437)
			(xy 268.475968 -273.61261) (xy 268.475968 -274.02155) (xy 274.517104 -274.02155) (xy 274.517104 -273.61261)
			(xy 274.517641 -273.602457) (xy 274.525406 -273.583695) (xy 274.539758 -273.56933) (xy 274.558513 -273.561549)
			(xy 274.568666 -273.561048) (xy 275.968206 -273.561048) (xy 275.978379 -273.561459) (xy 275.997176 -273.569248)
			(xy 276.011561 -273.583637) (xy 276.019344 -273.602437) (xy 276.019768 -273.61261) (xy 276.019768 -274.02155)
			(xy 282.060904 -274.02155) (xy 282.060904 -273.61261) (xy 282.061441 -273.602457) (xy 282.069206 -273.583695)
			(xy 282.083558 -273.56933) (xy 282.102313 -273.561549) (xy 282.112466 -273.561048) (xy 283.512006 -273.561048)
			(xy 283.522179 -273.561459) (xy 283.540976 -273.569248) (xy 283.555361 -273.583637) (xy 283.563144 -273.602437)
			(xy 283.563568 -273.61261) (xy 283.563568 -274.02155) (xy 289.604704 -274.02155) (xy 289.604704 -273.61261)
			(xy 289.605241 -273.602457) (xy 289.613006 -273.583695) (xy 289.627358 -273.56933) (xy 289.646113 -273.561549)
			(xy 289.656266 -273.561048) (xy 291.055806 -273.561048) (xy 291.065979 -273.561459) (xy 291.084776 -273.569248)
			(xy 291.099161 -273.583637) (xy 291.106944 -273.602437) (xy 291.107368 -273.61261) (xy 291.107368 -274.02155)
			(xy 297.148504 -274.02155) (xy 297.148504 -273.61261) (xy 297.149041 -273.602457) (xy 297.156806 -273.583695)
			(xy 297.171158 -273.56933) (xy 297.189913 -273.561549) (xy 297.200066 -273.561048) (xy 298.599606 -273.561048)
			(xy 298.609779 -273.561459) (xy 298.628576 -273.569248) (xy 298.642961 -273.583637) (xy 298.650744 -273.602437)
			(xy 298.651168 -273.61261) (xy 298.651168 -274.02155) (xy 304.692304 -274.02155) (xy 304.692304 -273.61261)
			(xy 304.692841 -273.602457) (xy 304.700606 -273.583695) (xy 304.714958 -273.56933) (xy 304.733713 -273.561549)
			(xy 304.743866 -273.561048) (xy 306.143406 -273.561048) (xy 306.153579 -273.561459) (xy 306.172376 -273.569248)
			(xy 306.186761 -273.583637) (xy 306.194544 -273.602437) (xy 306.194968 -273.61261) (xy 306.194968 -274.02155)
			(xy 312.236104 -274.02155) (xy 312.236104 -273.61261) (xy 312.236641 -273.602457) (xy 312.244406 -273.583695)
			(xy 312.258758 -273.56933) (xy 312.277513 -273.561549) (xy 312.287666 -273.561048) (xy 313.687206 -273.561048)
			(xy 313.697379 -273.561459) (xy 313.716176 -273.569248) (xy 313.730561 -273.583637) (xy 313.738344 -273.602437)
			(xy 313.738768 -273.61261) (xy 313.738768 -274.02155) (xy 313.738295 -274.031718) (xy 313.730528 -274.05051)
			(xy 313.716157 -274.064897) (xy 313.697373 -274.072684) (xy 313.687206 -274.073112) (xy 312.287666 -274.073112)
			(xy 312.277486 -274.072763) (xy 312.258681 -274.064957) (xy 312.244295 -274.050548) (xy 312.236521 -274.031731)
			(xy 312.236104 -274.02155) (xy 306.194968 -274.02155) (xy 306.194495 -274.031718) (xy 306.186728 -274.05051)
			(xy 306.172357 -274.064897) (xy 306.153573 -274.072684) (xy 306.143406 -274.073112) (xy 304.743866 -274.073112)
			(xy 304.733686 -274.072763) (xy 304.714881 -274.064957) (xy 304.700495 -274.050548) (xy 304.692721 -274.031731)
			(xy 304.692304 -274.02155) (xy 298.651168 -274.02155) (xy 298.650695 -274.031718) (xy 298.642928 -274.05051)
			(xy 298.628557 -274.064897) (xy 298.609773 -274.072684) (xy 298.599606 -274.073112) (xy 297.200066 -274.073112)
			(xy 297.189886 -274.072763) (xy 297.171081 -274.064957) (xy 297.156695 -274.050548) (xy 297.148921 -274.031731)
			(xy 297.148504 -274.02155) (xy 291.107368 -274.02155) (xy 291.106895 -274.031718) (xy 291.099128 -274.05051)
			(xy 291.084757 -274.064897) (xy 291.065973 -274.072684) (xy 291.055806 -274.073112) (xy 289.656266 -274.073112)
			(xy 289.646086 -274.072763) (xy 289.627281 -274.064957) (xy 289.612895 -274.050548) (xy 289.605121 -274.031731)
			(xy 289.604704 -274.02155) (xy 283.563568 -274.02155) (xy 283.563095 -274.031718) (xy 283.555328 -274.05051)
			(xy 283.540957 -274.064897) (xy 283.522173 -274.072684) (xy 283.512006 -274.073112) (xy 282.112466 -274.073112)
			(xy 282.102286 -274.072763) (xy 282.083481 -274.064957) (xy 282.069095 -274.050548) (xy 282.061321 -274.031731)
			(xy 282.060904 -274.02155) (xy 276.019768 -274.02155) (xy 276.019295 -274.031718) (xy 276.011528 -274.05051)
			(xy 275.997157 -274.064897) (xy 275.978373 -274.072684) (xy 275.968206 -274.073112) (xy 274.568666 -274.073112)
			(xy 274.558486 -274.072763) (xy 274.539681 -274.064957) (xy 274.525295 -274.050548) (xy 274.517521 -274.031731)
			(xy 274.517104 -274.02155) (xy 268.475968 -274.02155) (xy 268.475495 -274.031718) (xy 268.467728 -274.05051)
			(xy 268.453357 -274.064897) (xy 268.434573 -274.072684) (xy 268.424406 -274.073112) (xy 267.024866 -274.073112)
			(xy 267.014686 -274.072763) (xy 266.995881 -274.064957) (xy 266.981495 -274.050548) (xy 266.973721 -274.031731)
			(xy 266.973304 -274.02155) (xy 260.932168 -274.02155) (xy 260.931695 -274.031718) (xy 260.923928 -274.05051)
			(xy 260.909557 -274.064897) (xy 260.890773 -274.072684) (xy 260.880606 -274.073112) (xy 259.481066 -274.073112)
			(xy 259.470886 -274.072763) (xy 259.452081 -274.064957) (xy 259.437695 -274.050548) (xy 259.429921 -274.031731)
			(xy 259.429504 -274.02155) (xy 216.4715 -274.02155) (xy 216.470996 -274.031714) (xy 216.463235 -274.0505)
			(xy 216.448874 -274.064885) (xy 216.430101 -274.072679) (xy 216.419938 -274.073112) (xy 215.020398 -274.073112)
			(xy 215.01022 -274.072737) (xy 214.991416 -274.064942) (xy 214.977029 -274.050541) (xy 214.969253 -274.031728)
			(xy 214.968836 -274.02155) (xy 208.9277 -274.02155) (xy 208.927196 -274.031714) (xy 208.919435 -274.0505)
			(xy 208.905074 -274.064885) (xy 208.886301 -274.072679) (xy 208.876138 -274.073112) (xy 207.476598 -274.073112)
			(xy 207.46642 -274.072737) (xy 207.447616 -274.064942) (xy 207.433229 -274.050541) (xy 207.425453 -274.031728)
			(xy 207.425036 -274.02155) (xy 201.3839 -274.02155) (xy 201.383396 -274.031714) (xy 201.375635 -274.0505)
			(xy 201.361274 -274.064885) (xy 201.342501 -274.072679) (xy 201.332338 -274.073112) (xy 199.932798 -274.073112)
			(xy 199.92262 -274.072737) (xy 199.903816 -274.064942) (xy 199.889429 -274.050541) (xy 199.881653 -274.031728)
			(xy 199.881236 -274.02155) (xy 193.8401 -274.02155) (xy 193.839596 -274.031714) (xy 193.831835 -274.0505)
			(xy 193.817474 -274.064885) (xy 193.798701 -274.072679) (xy 193.788538 -274.073112) (xy 192.388998 -274.073112)
			(xy 192.37882 -274.072737) (xy 192.360016 -274.064942) (xy 192.345629 -274.050541) (xy 192.337853 -274.031728)
			(xy 192.337436 -274.02155) (xy 186.2963 -274.02155) (xy 186.295796 -274.031714) (xy 186.288035 -274.0505)
			(xy 186.273674 -274.064885) (xy 186.254901 -274.072679) (xy 186.244738 -274.073112) (xy 184.845198 -274.073112)
			(xy 184.83502 -274.072737) (xy 184.816216 -274.064942) (xy 184.801829 -274.050541) (xy 184.794053 -274.031728)
			(xy 184.793636 -274.02155) (xy 178.7525 -274.02155) (xy 178.751996 -274.031714) (xy 178.744235 -274.0505)
			(xy 178.729874 -274.064885) (xy 178.711101 -274.072679) (xy 178.700938 -274.073112) (xy 177.301398 -274.073112)
			(xy 177.29122 -274.072737) (xy 177.272416 -274.064942) (xy 177.258029 -274.050541) (xy 177.250253 -274.031728)
			(xy 177.249836 -274.02155) (xy 171.2087 -274.02155) (xy 171.208196 -274.031714) (xy 171.200435 -274.0505)
			(xy 171.186074 -274.064885) (xy 171.167301 -274.072679) (xy 171.157138 -274.073112) (xy 169.757598 -274.073112)
			(xy 169.74742 -274.072737) (xy 169.728616 -274.064942) (xy 169.714229 -274.050541) (xy 169.706453 -274.031728)
			(xy 169.706036 -274.02155) (xy 163.6649 -274.02155) (xy 163.664396 -274.031714) (xy 163.656635 -274.0505)
			(xy 163.642274 -274.064885) (xy 163.623501 -274.072679) (xy 163.613338 -274.073112) (xy 162.213798 -274.073112)
			(xy 162.20362 -274.072737) (xy 162.184816 -274.064942) (xy 162.170429 -274.050541) (xy 162.162653 -274.031728)
			(xy 162.162236 -274.02155) (xy 109.621061 -274.02155) (xy 109.654747 -274.056422) (xy 109.683961 -274.097824)
			(xy 109.706494 -274.143208) (xy 109.721817 -274.191505) (xy 109.729569 -274.241579) (xy 109.730032 -274.266914)
			(xy 351.372424 -274.266914) (xy 351.372932 -274.241027) (xy 351.381031 -274.189889) (xy 351.39703 -274.140649)
			(xy 351.420536 -274.094517) (xy 351.450968 -274.05263) (xy 351.487578 -274.01602) (xy 351.529465 -273.985588)
			(xy 351.575597 -273.962082) (xy 351.624837 -273.946083) (xy 351.675975 -273.937984) (xy 351.727749 -273.937984)
			(xy 351.778887 -273.946083) (xy 351.828127 -273.962082) (xy 351.874259 -273.985588) (xy 351.916146 -274.01602)
			(xy 351.952756 -274.05263) (xy 351.983188 -274.094517) (xy 352.006694 -274.140649) (xy 352.022693 -274.189889)
			(xy 352.030792 -274.241027) (xy 352.0313 -274.266914) (xy 352.0313 -274.267422) (xy 352.030713 -274.294938)
			(xy 352.021525 -274.349199) (xy 352.013012 -274.375372) (xy 352.005392 -274.397216) (xy 352.210624 -274.752562)
			(xy 352.233484 -274.75688) (xy 352.258307 -274.762037) (xy 352.306085 -274.778995) (xy 352.350703 -274.80307)
			(xy 352.391108 -274.833692) (xy 352.426348 -274.87014) (xy 352.455591 -274.911554) (xy 352.478148 -274.956958)
			(xy 352.493487 -275.00528) (xy 352.501245 -275.055381) (xy 352.501708 -275.08073) (xy 352.5012 -275.106637)
			(xy 352.493094 -275.157814) (xy 352.477082 -275.207093) (xy 352.453559 -275.25326) (xy 352.423103 -275.295179)
			(xy 352.386465 -275.331817) (xy 352.344546 -275.362273) (xy 352.298379 -275.385796) (xy 352.2491 -275.401808)
			(xy 352.197923 -275.409914) (xy 352.146109 -275.409914) (xy 352.094932 -275.401808) (xy 352.045653 -275.385796)
			(xy 351.999486 -275.362273) (xy 351.957567 -275.331817) (xy 351.920929 -275.295179) (xy 351.890473 -275.25326)
			(xy 351.86695 -275.207093) (xy 351.850938 -275.157814) (xy 351.842832 -275.106637) (xy 351.842324 -275.08073)
			(xy 351.842924 -275.053013) (xy 351.852243 -274.998366) (xy 351.860866 -274.972018) (xy 351.86874 -274.94992)
			(xy 351.663762 -274.595082) (xy 351.640902 -274.590764) (xy 351.616074 -274.585582) (xy 351.568269 -274.568647)
			(xy 351.523622 -274.544591) (xy 351.483185 -274.513981) (xy 351.447913 -274.47754) (xy 351.418638 -274.436127)
			(xy 351.39605 -274.390718) (xy 351.380683 -274.342387) (xy 351.372898 -274.292272) (xy 351.372424 -274.266914)
			(xy 109.730032 -274.266914) (xy 109.729524 -274.292801) (xy 109.721425 -274.343939) (xy 109.705426 -274.393179)
			(xy 109.68192 -274.439311) (xy 109.651488 -274.481198) (xy 109.614878 -274.517808) (xy 109.572991 -274.54824)
			(xy 109.526859 -274.571746) (xy 109.477619 -274.587745) (xy 109.426481 -274.595844) (xy 109.374707 -274.595844)
			(xy 109.323569 -274.587745) (xy 109.274329 -274.571746) (xy 109.228197 -274.54824) (xy 109.18631 -274.517808)
			(xy 109.1497 -274.481198) (xy 109.119268 -274.439311) (xy 109.095762 -274.393179) (xy 109.079763 -274.343939)
			(xy 109.071664 -274.292801) (xy 109.071156 -274.266914) (xy 109.071691 -274.239206) (xy 109.080883 -274.184559)
			(xy 109.089444 -274.158202) (xy 109.097318 -274.136104) (xy 108.89234 -273.781266) (xy 108.86948 -273.776948)
			(xy 108.844673 -273.771718) (xy 108.796897 -273.754771) (xy 108.75228 -273.730708) (xy 108.711874 -273.700095)
			(xy 108.676632 -273.663656) (xy 108.647386 -273.622251) (xy 108.624826 -273.576855) (xy 108.609484 -273.528539)
			(xy 108.601721 -273.478444) (xy 108.601256 -273.453098) (xy 2.509012 -273.453098) (xy 2.509012 -274.02155)
			(xy 11.489436 -274.02155) (xy 11.489436 -273.61261) (xy 11.489872 -273.602439) (xy 11.497653 -273.583645)
			(xy 11.512035 -273.56926) (xy 11.530827 -273.561474) (xy 11.540998 -273.561048) (xy 12.940538 -273.561048)
			(xy 12.950699 -273.561503) (xy 12.969471 -273.569291) (xy 12.983836 -273.583669) (xy 12.991607 -273.602448)
			(xy 12.9921 -273.61261) (xy 12.9921 -274.02155) (xy 19.033236 -274.02155) (xy 19.033236 -273.61261)
			(xy 19.033672 -273.602439) (xy 19.041453 -273.583645) (xy 19.055835 -273.56926) (xy 19.074627 -273.561474)
			(xy 19.084798 -273.561048) (xy 20.484338 -273.561048) (xy 20.494499 -273.561503) (xy 20.513271 -273.569291)
			(xy 20.527636 -273.583669) (xy 20.535407 -273.602448) (xy 20.5359 -273.61261) (xy 20.5359 -274.02155)
			(xy 26.577036 -274.02155) (xy 26.577036 -273.61261) (xy 26.577472 -273.602439) (xy 26.585253 -273.583645)
			(xy 26.599635 -273.56926) (xy 26.618427 -273.561474) (xy 26.628598 -273.561048) (xy 28.028138 -273.561048)
			(xy 28.038299 -273.561503) (xy 28.057071 -273.569291) (xy 28.071436 -273.583669) (xy 28.079207 -273.602448)
			(xy 28.0797 -273.61261) (xy 28.0797 -274.02155) (xy 34.120836 -274.02155) (xy 34.120836 -273.61261)
			(xy 34.121272 -273.602439) (xy 34.129053 -273.583645) (xy 34.143435 -273.56926) (xy 34.162227 -273.561474)
			(xy 34.172398 -273.561048) (xy 35.571938 -273.561048) (xy 35.582099 -273.561503) (xy 35.600871 -273.569291)
			(xy 35.615236 -273.583669) (xy 35.623007 -273.602448) (xy 35.6235 -273.61261) (xy 35.6235 -274.02155)
			(xy 41.664636 -274.02155) (xy 41.664636 -273.61261) (xy 41.665072 -273.602439) (xy 41.672853 -273.583645)
			(xy 41.687235 -273.56926) (xy 41.706027 -273.561474) (xy 41.716198 -273.561048) (xy 43.115738 -273.561048)
			(xy 43.125899 -273.561503) (xy 43.144671 -273.569291) (xy 43.159036 -273.583669) (xy 43.166807 -273.602448)
			(xy 43.1673 -273.61261) (xy 43.1673 -274.02155) (xy 49.208436 -274.02155) (xy 49.208436 -273.61261)
			(xy 49.208872 -273.602439) (xy 49.216653 -273.583645) (xy 49.231035 -273.56926) (xy 49.249827 -273.561474)
			(xy 49.259998 -273.561048) (xy 50.659538 -273.561048) (xy 50.669699 -273.561503) (xy 50.688471 -273.569291)
			(xy 50.702836 -273.583669) (xy 50.710607 -273.602448) (xy 50.7111 -273.61261) (xy 50.7111 -274.02155)
			(xy 56.752236 -274.02155) (xy 56.752236 -273.61261) (xy 56.752672 -273.602439) (xy 56.760453 -273.583645)
			(xy 56.774835 -273.56926) (xy 56.793627 -273.561474) (xy 56.803798 -273.561048) (xy 58.203338 -273.561048)
			(xy 58.213499 -273.561503) (xy 58.232271 -273.569291) (xy 58.246636 -273.583669) (xy 58.254407 -273.602448)
			(xy 58.2549 -273.61261) (xy 58.2549 -274.02155) (xy 64.296036 -274.02155) (xy 64.296036 -273.61261)
			(xy 64.296472 -273.602439) (xy 64.304253 -273.583645) (xy 64.318635 -273.56926) (xy 64.337427 -273.561474)
			(xy 64.347598 -273.561048) (xy 65.747138 -273.561048) (xy 65.757299 -273.561503) (xy 65.776071 -273.569291)
			(xy 65.790436 -273.583669) (xy 65.798207 -273.602448) (xy 65.7987 -273.61261) (xy 65.7987 -274.02155)
			(xy 65.798196 -274.031714) (xy 65.790435 -274.0505) (xy 65.776074 -274.064885) (xy 65.757301 -274.072679)
			(xy 65.747138 -274.073112) (xy 64.347598 -274.073112) (xy 64.33742 -274.072737) (xy 64.318616 -274.064942)
			(xy 64.304229 -274.050541) (xy 64.296453 -274.031728) (xy 64.296036 -274.02155) (xy 58.2549 -274.02155)
			(xy 58.254396 -274.031714) (xy 58.246635 -274.0505) (xy 58.232274 -274.064885) (xy 58.213501 -274.072679)
			(xy 58.203338 -274.073112) (xy 56.803798 -274.073112) (xy 56.79362 -274.072737) (xy 56.774816 -274.064942)
			(xy 56.760429 -274.050541) (xy 56.752653 -274.031728) (xy 56.752236 -274.02155) (xy 50.7111 -274.02155)
			(xy 50.710596 -274.031714) (xy 50.702835 -274.0505) (xy 50.688474 -274.064885) (xy 50.669701 -274.072679)
			(xy 50.659538 -274.073112) (xy 49.259998 -274.073112) (xy 49.24982 -274.072737) (xy 49.231016 -274.064942)
			(xy 49.216629 -274.050541) (xy 49.208853 -274.031728) (xy 49.208436 -274.02155) (xy 43.1673 -274.02155)
			(xy 43.166796 -274.031714) (xy 43.159035 -274.0505) (xy 43.144674 -274.064885) (xy 43.125901 -274.072679)
			(xy 43.115738 -274.073112) (xy 41.716198 -274.073112) (xy 41.70602 -274.072737) (xy 41.687216 -274.064942)
			(xy 41.672829 -274.050541) (xy 41.665053 -274.031728) (xy 41.664636 -274.02155) (xy 35.6235 -274.02155)
			(xy 35.622996 -274.031714) (xy 35.615235 -274.0505) (xy 35.600874 -274.064885) (xy 35.582101 -274.072679)
			(xy 35.571938 -274.073112) (xy 34.172398 -274.073112) (xy 34.16222 -274.072737) (xy 34.143416 -274.064942)
			(xy 34.129029 -274.050541) (xy 34.121253 -274.031728) (xy 34.120836 -274.02155) (xy 28.0797 -274.02155)
			(xy 28.079196 -274.031714) (xy 28.071435 -274.0505) (xy 28.057074 -274.064885) (xy 28.038301 -274.072679)
			(xy 28.028138 -274.073112) (xy 26.628598 -274.073112) (xy 26.61842 -274.072737) (xy 26.599616 -274.064942)
			(xy 26.585229 -274.050541) (xy 26.577453 -274.031728) (xy 26.577036 -274.02155) (xy 20.5359 -274.02155)
			(xy 20.535396 -274.031714) (xy 20.527635 -274.0505) (xy 20.513274 -274.064885) (xy 20.494501 -274.072679)
			(xy 20.484338 -274.073112) (xy 19.084798 -274.073112) (xy 19.07462 -274.072737) (xy 19.055816 -274.064942)
			(xy 19.041429 -274.050541) (xy 19.033653 -274.031728) (xy 19.033236 -274.02155) (xy 12.9921 -274.02155)
			(xy 12.991596 -274.031714) (xy 12.983835 -274.0505) (xy 12.969474 -274.064885) (xy 12.950701 -274.072679)
			(xy 12.940538 -274.073112) (xy 11.540998 -274.073112) (xy 11.53082 -274.072737) (xy 11.512016 -274.064942)
			(xy 11.497629 -274.050541) (xy 11.489853 -274.031728) (xy 11.489436 -274.02155) (xy 2.509012 -274.02155)
			(xy 2.509012 -274.266914) (xy 103.432356 -274.266914) (xy 103.432864 -274.241027) (xy 103.440963 -274.189889)
			(xy 103.456962 -274.140649) (xy 103.480468 -274.094517) (xy 103.5109 -274.05263) (xy 103.54751 -274.01602)
			(xy 103.589397 -273.985588) (xy 103.635529 -273.962082) (xy 103.684769 -273.946083) (xy 103.735907 -273.937984)
			(xy 103.787681 -273.937984) (xy 103.838819 -273.946083) (xy 103.888059 -273.962082) (xy 103.934191 -273.985588)
			(xy 103.976078 -274.01602) (xy 104.012688 -274.05263) (xy 104.04312 -274.094517) (xy 104.066626 -274.140649)
			(xy 104.082625 -274.189889) (xy 104.090724 -274.241027) (xy 104.091232 -274.266914) (xy 104.091232 -274.267422)
			(xy 104.090643 -274.294938) (xy 104.081456 -274.349199) (xy 104.072944 -274.375372) (xy 104.065324 -274.397216)
			(xy 104.270556 -274.752562) (xy 104.293416 -274.75688) (xy 104.318228 -274.762086) (xy 104.366006 -274.779035)
			(xy 104.410625 -274.803101) (xy 104.451032 -274.833715) (xy 104.486274 -274.870157) (xy 104.515519 -274.911566)
			(xy 104.538078 -274.956966) (xy 104.553418 -275.005285) (xy 104.561177 -275.055382) (xy 104.56164 -275.08073)
			(xy 104.561132 -275.106637) (xy 104.553026 -275.157814) (xy 104.537014 -275.207093) (xy 104.513491 -275.25326)
			(xy 104.483035 -275.295179) (xy 104.446397 -275.331817) (xy 104.404478 -275.362273) (xy 104.358311 -275.385796)
			(xy 104.309032 -275.401808) (xy 104.257855 -275.409914) (xy 104.206041 -275.409914) (xy 104.154864 -275.401808)
			(xy 104.105585 -275.385796) (xy 104.059418 -275.362273) (xy 104.017499 -275.331817) (xy 103.980861 -275.295179)
			(xy 103.950405 -275.25326) (xy 103.926882 -275.207093) (xy 103.91087 -275.157814) (xy 103.902764 -275.106637)
			(xy 103.902256 -275.08073) (xy 103.902854 -275.053013) (xy 103.912174 -274.998366) (xy 103.920798 -274.972018)
			(xy 103.928672 -274.94992) (xy 103.723694 -274.595082) (xy 103.700834 -274.590764) (xy 103.676011 -274.585559)
			(xy 103.628206 -274.568629) (xy 103.583558 -274.544577) (xy 103.543121 -274.51397) (xy 103.507847 -274.477532)
			(xy 103.478571 -274.436121) (xy 103.455983 -274.390715) (xy 103.440615 -274.342385) (xy 103.43283 -274.292271)
			(xy 103.432356 -274.266914) (xy 2.509012 -274.266914) (xy 2.509012 -274.871434) (xy 7.389368 -274.871434)
			(xy 7.389368 -274.462494) (xy 7.38976 -274.452318) (xy 7.397552 -274.433518) (xy 7.411948 -274.419132)
			(xy 7.430754 -274.411353) (xy 7.44093 -274.410932) (xy 8.84047 -274.410932) (xy 8.850639 -274.411388)
			(xy 8.869432 -274.419162) (xy 8.883817 -274.433538) (xy 8.891604 -274.452325) (xy 8.892032 -274.462494)
			(xy 8.892032 -274.871434) (xy 11.489436 -274.871434) (xy 11.489436 -274.462494) (xy 11.489929 -274.452336)
			(xy 11.497705 -274.433567) (xy 11.512071 -274.419202) (xy 11.53084 -274.411428) (xy 11.540998 -274.410932)
			(xy 12.940538 -274.410932) (xy 12.950697 -274.411402) (xy 12.969466 -274.419188) (xy 12.98383 -274.433561)
			(xy 12.991604 -274.452334) (xy 12.9921 -274.462494) (xy 12.9921 -274.871434) (xy 14.933168 -274.871434)
			(xy 14.933168 -274.462494) (xy 14.93356 -274.452318) (xy 14.941352 -274.433518) (xy 14.955748 -274.419132)
			(xy 14.974554 -274.411353) (xy 14.98473 -274.410932) (xy 16.38427 -274.410932) (xy 16.394439 -274.411388)
			(xy 16.413232 -274.419162) (xy 16.427617 -274.433538) (xy 16.435404 -274.452325) (xy 16.435832 -274.462494)
			(xy 16.435832 -274.871434) (xy 19.033236 -274.871434) (xy 19.033236 -274.462494) (xy 19.033729 -274.452336)
			(xy 19.041505 -274.433567) (xy 19.055871 -274.419202) (xy 19.07464 -274.411428) (xy 19.084798 -274.410932)
			(xy 20.484338 -274.410932) (xy 20.494497 -274.411402) (xy 20.513266 -274.419188) (xy 20.52763 -274.433561)
			(xy 20.535404 -274.452334) (xy 20.5359 -274.462494) (xy 20.5359 -274.871434) (xy 22.476968 -274.871434)
			(xy 22.476968 -274.462494) (xy 22.47736 -274.452318) (xy 22.485152 -274.433518) (xy 22.499548 -274.419132)
			(xy 22.518354 -274.411353) (xy 22.52853 -274.410932) (xy 23.92807 -274.410932) (xy 23.938239 -274.411388)
			(xy 23.957032 -274.419162) (xy 23.971417 -274.433538) (xy 23.979204 -274.452325) (xy 23.979632 -274.462494)
			(xy 23.979632 -274.871434) (xy 26.577036 -274.871434) (xy 26.577036 -274.462494) (xy 26.577529 -274.452336)
			(xy 26.585305 -274.433567) (xy 26.599671 -274.419202) (xy 26.61844 -274.411428) (xy 26.628598 -274.410932)
			(xy 28.028138 -274.410932) (xy 28.038297 -274.411402) (xy 28.057066 -274.419188) (xy 28.07143 -274.433561)
			(xy 28.079204 -274.452334) (xy 28.0797 -274.462494) (xy 28.0797 -274.871434) (xy 30.020768 -274.871434)
			(xy 30.020768 -274.462494) (xy 30.02116 -274.452318) (xy 30.028952 -274.433518) (xy 30.043348 -274.419132)
			(xy 30.062154 -274.411353) (xy 30.07233 -274.410932) (xy 31.47187 -274.410932) (xy 31.482039 -274.411388)
			(xy 31.500832 -274.419162) (xy 31.515217 -274.433538) (xy 31.523004 -274.452325) (xy 31.523432 -274.462494)
			(xy 31.523432 -274.871434) (xy 34.120836 -274.871434) (xy 34.120836 -274.462494) (xy 34.121329 -274.452336)
			(xy 34.129105 -274.433567) (xy 34.143471 -274.419202) (xy 34.16224 -274.411428) (xy 34.172398 -274.410932)
			(xy 35.571938 -274.410932) (xy 35.582097 -274.411402) (xy 35.600866 -274.419188) (xy 35.61523 -274.433561)
			(xy 35.623004 -274.452334) (xy 35.6235 -274.462494) (xy 35.6235 -274.871434) (xy 37.564568 -274.871434)
			(xy 37.564568 -274.462494) (xy 37.56496 -274.452318) (xy 37.572752 -274.433518) (xy 37.587148 -274.419132)
			(xy 37.605954 -274.411353) (xy 37.61613 -274.410932) (xy 39.01567 -274.410932) (xy 39.025839 -274.411388)
			(xy 39.044632 -274.419162) (xy 39.059017 -274.433538) (xy 39.066804 -274.452325) (xy 39.067232 -274.462494)
			(xy 39.067232 -274.871434) (xy 41.664636 -274.871434) (xy 41.664636 -274.462494) (xy 41.665129 -274.452336)
			(xy 41.672905 -274.433567) (xy 41.687271 -274.419202) (xy 41.70604 -274.411428) (xy 41.716198 -274.410932)
			(xy 43.115738 -274.410932) (xy 43.125897 -274.411402) (xy 43.144666 -274.419188) (xy 43.15903 -274.433561)
			(xy 43.166804 -274.452334) (xy 43.1673 -274.462494) (xy 43.1673 -274.871434) (xy 45.108368 -274.871434)
			(xy 45.108368 -274.462494) (xy 45.10876 -274.452318) (xy 45.116552 -274.433518) (xy 45.130948 -274.419132)
			(xy 45.149754 -274.411353) (xy 45.15993 -274.410932) (xy 46.55947 -274.410932) (xy 46.569639 -274.411388)
			(xy 46.588432 -274.419162) (xy 46.602817 -274.433538) (xy 46.610604 -274.452325) (xy 46.611032 -274.462494)
			(xy 46.611032 -274.871434) (xy 49.208436 -274.871434) (xy 49.208436 -274.462494) (xy 49.208929 -274.452336)
			(xy 49.216705 -274.433567) (xy 49.231071 -274.419202) (xy 49.24984 -274.411428) (xy 49.259998 -274.410932)
			(xy 50.659538 -274.410932) (xy 50.669697 -274.411402) (xy 50.688466 -274.419188) (xy 50.70283 -274.433561)
			(xy 50.710604 -274.452334) (xy 50.7111 -274.462494) (xy 50.7111 -274.871434) (xy 52.652168 -274.871434)
			(xy 52.652168 -274.462494) (xy 52.65256 -274.452318) (xy 52.660352 -274.433518) (xy 52.674748 -274.419132)
			(xy 52.693554 -274.411353) (xy 52.70373 -274.410932) (xy 54.10327 -274.410932) (xy 54.113439 -274.411388)
			(xy 54.132232 -274.419162) (xy 54.146617 -274.433538) (xy 54.154404 -274.452325) (xy 54.154832 -274.462494)
			(xy 54.154832 -274.871434) (xy 56.752236 -274.871434) (xy 56.752236 -274.462494) (xy 56.752729 -274.452336)
			(xy 56.760505 -274.433567) (xy 56.774871 -274.419202) (xy 56.79364 -274.411428) (xy 56.803798 -274.410932)
			(xy 58.203338 -274.410932) (xy 58.213497 -274.411402) (xy 58.232266 -274.419188) (xy 58.24663 -274.433561)
			(xy 58.254404 -274.452334) (xy 58.2549 -274.462494) (xy 58.2549 -274.871434) (xy 60.195968 -274.871434)
			(xy 60.195968 -274.462494) (xy 60.19636 -274.452318) (xy 60.204152 -274.433518) (xy 60.218548 -274.419132)
			(xy 60.237354 -274.411353) (xy 60.24753 -274.410932) (xy 61.64707 -274.410932) (xy 61.657239 -274.411388)
			(xy 61.676032 -274.419162) (xy 61.690417 -274.433538) (xy 61.698204 -274.452325) (xy 61.698632 -274.462494)
			(xy 61.698632 -274.871434) (xy 64.296036 -274.871434) (xy 64.296036 -274.462494) (xy 64.296529 -274.452336)
			(xy 64.304305 -274.433567) (xy 64.318671 -274.419202) (xy 64.33744 -274.411428) (xy 64.347598 -274.410932)
			(xy 65.747138 -274.410932) (xy 65.757297 -274.411402) (xy 65.776066 -274.419188) (xy 65.79043 -274.433561)
			(xy 65.798204 -274.452334) (xy 65.7987 -274.462494) (xy 65.7987 -274.871434) (xy 65.798195 -274.881589)
			(xy 65.790417 -274.900352) (xy 65.776055 -274.914715) (xy 65.757293 -274.922495) (xy 65.747138 -274.922996)
			(xy 64.347598 -274.922996) (xy 64.337444 -274.922469) (xy 64.318682 -274.9147) (xy 64.304318 -274.900345)
			(xy 64.296537 -274.881587) (xy 64.296036 -274.871434) (xy 61.698632 -274.871434) (xy 61.698194 -274.881598)
			(xy 61.690403 -274.900373) (xy 61.67602 -274.914738) (xy 61.657234 -274.922506) (xy 61.64707 -274.922996)
			(xy 60.24753 -274.922996) (xy 60.237378 -274.922443) (xy 60.218616 -274.914685) (xy 60.204251 -274.900337)
			(xy 60.196469 -274.881585) (xy 60.195968 -274.871434) (xy 58.2549 -274.871434) (xy 58.254395 -274.881589)
			(xy 58.246617 -274.900352) (xy 58.232255 -274.914715) (xy 58.213493 -274.922495) (xy 58.203338 -274.922996)
			(xy 56.803798 -274.922996) (xy 56.793644 -274.922469) (xy 56.774882 -274.9147) (xy 56.760518 -274.900345)
			(xy 56.752737 -274.881587) (xy 56.752236 -274.871434) (xy 54.154832 -274.871434) (xy 54.154394 -274.881598)
			(xy 54.146603 -274.900373) (xy 54.13222 -274.914738) (xy 54.113434 -274.922506) (xy 54.10327 -274.922996)
			(xy 52.70373 -274.922996) (xy 52.693578 -274.922443) (xy 52.674816 -274.914685) (xy 52.660451 -274.900337)
			(xy 52.652669 -274.881585) (xy 52.652168 -274.871434) (xy 50.7111 -274.871434) (xy 50.710595 -274.881589)
			(xy 50.702817 -274.900352) (xy 50.688455 -274.914715) (xy 50.669693 -274.922495) (xy 50.659538 -274.922996)
			(xy 49.259998 -274.922996) (xy 49.249844 -274.922469) (xy 49.231082 -274.9147) (xy 49.216718 -274.900345)
			(xy 49.208937 -274.881587) (xy 49.208436 -274.871434) (xy 46.611032 -274.871434) (xy 46.610594 -274.881598)
			(xy 46.602803 -274.900373) (xy 46.58842 -274.914738) (xy 46.569634 -274.922506) (xy 46.55947 -274.922996)
			(xy 45.15993 -274.922996) (xy 45.149778 -274.922443) (xy 45.131016 -274.914685) (xy 45.116651 -274.900337)
			(xy 45.108869 -274.881585) (xy 45.108368 -274.871434) (xy 43.1673 -274.871434) (xy 43.166795 -274.881589)
			(xy 43.159017 -274.900352) (xy 43.144655 -274.914715) (xy 43.125893 -274.922495) (xy 43.115738 -274.922996)
			(xy 41.716198 -274.922996) (xy 41.706044 -274.922469) (xy 41.687282 -274.9147) (xy 41.672918 -274.900345)
			(xy 41.665137 -274.881587) (xy 41.664636 -274.871434) (xy 39.067232 -274.871434) (xy 39.066794 -274.881598)
			(xy 39.059003 -274.900373) (xy 39.04462 -274.914738) (xy 39.025834 -274.922506) (xy 39.01567 -274.922996)
			(xy 37.61613 -274.922996) (xy 37.605978 -274.922443) (xy 37.587216 -274.914685) (xy 37.572851 -274.900337)
			(xy 37.565069 -274.881585) (xy 37.564568 -274.871434) (xy 35.6235 -274.871434) (xy 35.622995 -274.881589)
			(xy 35.615217 -274.900352) (xy 35.600855 -274.914715) (xy 35.582093 -274.922495) (xy 35.571938 -274.922996)
			(xy 34.172398 -274.922996) (xy 34.162244 -274.922469) (xy 34.143482 -274.9147) (xy 34.129118 -274.900345)
			(xy 34.121337 -274.881587) (xy 34.120836 -274.871434) (xy 31.523432 -274.871434) (xy 31.522994 -274.881598)
			(xy 31.515203 -274.900373) (xy 31.50082 -274.914738) (xy 31.482034 -274.922506) (xy 31.47187 -274.922996)
			(xy 30.07233 -274.922996) (xy 30.062178 -274.922443) (xy 30.043416 -274.914685) (xy 30.029051 -274.900337)
			(xy 30.021269 -274.881585) (xy 30.020768 -274.871434) (xy 28.0797 -274.871434) (xy 28.079195 -274.881589)
			(xy 28.071417 -274.900352) (xy 28.057055 -274.914715) (xy 28.038293 -274.922495) (xy 28.028138 -274.922996)
			(xy 26.628598 -274.922996) (xy 26.618444 -274.922469) (xy 26.599682 -274.9147) (xy 26.585318 -274.900345)
			(xy 26.577537 -274.881587) (xy 26.577036 -274.871434) (xy 23.979632 -274.871434) (xy 23.979194 -274.881598)
			(xy 23.971403 -274.900373) (xy 23.95702 -274.914738) (xy 23.938234 -274.922506) (xy 23.92807 -274.922996)
			(xy 22.52853 -274.922996) (xy 22.518378 -274.922443) (xy 22.499616 -274.914685) (xy 22.485251 -274.900337)
			(xy 22.477469 -274.881585) (xy 22.476968 -274.871434) (xy 20.5359 -274.871434) (xy 20.535395 -274.881589)
			(xy 20.527617 -274.900352) (xy 20.513255 -274.914715) (xy 20.494493 -274.922495) (xy 20.484338 -274.922996)
			(xy 19.084798 -274.922996) (xy 19.074644 -274.922469) (xy 19.055882 -274.9147) (xy 19.041518 -274.900345)
			(xy 19.033737 -274.881587) (xy 19.033236 -274.871434) (xy 16.435832 -274.871434) (xy 16.435394 -274.881598)
			(xy 16.427603 -274.900373) (xy 16.41322 -274.914738) (xy 16.394434 -274.922506) (xy 16.38427 -274.922996)
			(xy 14.98473 -274.922996) (xy 14.974578 -274.922443) (xy 14.955816 -274.914685) (xy 14.941451 -274.900337)
			(xy 14.933669 -274.881585) (xy 14.933168 -274.871434) (xy 12.9921 -274.871434) (xy 12.991595 -274.881589)
			(xy 12.983817 -274.900352) (xy 12.969455 -274.914715) (xy 12.950693 -274.922495) (xy 12.940538 -274.922996)
			(xy 11.540998 -274.922996) (xy 11.530844 -274.922469) (xy 11.512082 -274.9147) (xy 11.497718 -274.900345)
			(xy 11.489937 -274.881587) (xy 11.489436 -274.871434) (xy 8.892032 -274.871434) (xy 8.891594 -274.881598)
			(xy 8.883803 -274.900373) (xy 8.86942 -274.914738) (xy 8.850634 -274.922506) (xy 8.84047 -274.922996)
			(xy 7.44093 -274.922996) (xy 7.430778 -274.922443) (xy 7.412016 -274.914685) (xy 7.397651 -274.900337)
			(xy 7.389869 -274.881585) (xy 7.389368 -274.871434) (xy 2.509012 -274.871434) (xy 2.509012 -275.10659)
			(xy 102.023373 -275.10659) (xy 102.023373 -275.05481) (xy 102.031474 -275.003669) (xy 102.047476 -274.954425)
			(xy 102.070985 -274.90829) (xy 102.101423 -274.866402) (xy 102.138039 -274.829791) (xy 102.179931 -274.79936)
			(xy 102.226069 -274.775858) (xy 102.275316 -274.759863) (xy 102.326458 -274.75177) (xy 102.352348 -274.751292)
			(xy 102.377861 -274.751741) (xy 102.428277 -274.759608) (xy 102.476879 -274.775148) (xy 102.522507 -274.79799)
			(xy 102.564072 -274.827588) (xy 102.600581 -274.863235) (xy 102.616254 -274.883372) (xy 103.028242 -274.883372)
			(xy 103.043883 -274.86321) (xy 103.0804 -274.827569) (xy 103.121973 -274.797979) (xy 103.167607 -274.775148)
			(xy 103.216215 -274.75962) (xy 103.266634 -274.751765) (xy 103.292148 -274.751292) (xy 103.318035 -274.751743)
			(xy 103.369171 -274.759849) (xy 103.41841 -274.775854) (xy 103.464539 -274.799364) (xy 103.506423 -274.8298)
			(xy 103.543031 -274.866413) (xy 103.573461 -274.908302) (xy 103.596964 -274.954434) (xy 103.612962 -275.003675)
			(xy 103.62106 -275.054813) (xy 103.62106 -275.106587) (xy 103.612962 -275.157725) (xy 103.596964 -275.206966)
			(xy 103.573461 -275.253098) (xy 103.543031 -275.294987) (xy 103.506423 -275.3316) (xy 103.464539 -275.362036)
			(xy 103.41841 -275.385546) (xy 103.369171 -275.401551) (xy 103.318035 -275.409657) (xy 103.292148 -275.410168)
			(xy 103.266637 -275.409665) (xy 103.216223 -275.401811) (xy 103.167621 -275.386283) (xy 103.121992 -275.363452)
			(xy 103.080426 -275.333862) (xy 103.043916 -275.298222) (xy 103.028242 -275.278088) (xy 102.616254 -275.278088)
			(xy 102.600546 -275.298195) (xy 102.564044 -275.333841) (xy 102.522486 -275.363438) (xy 102.476864 -275.386279)
			(xy 102.428268 -275.401819) (xy 102.377858 -275.409687) (xy 102.352348 -275.410168) (xy 102.326458 -275.40963)
			(xy 102.275316 -275.401537) (xy 102.226069 -275.385542) (xy 102.179931 -275.36204) (xy 102.138039 -275.331609)
			(xy 102.101423 -275.294998) (xy 102.070985 -275.25311) (xy 102.047476 -275.206975) (xy 102.031474 -275.157731)
			(xy 102.023373 -275.10659) (xy 2.509012 -275.10659) (xy 2.509012 -275.721318) (xy 7.389368 -275.721318)
			(xy 7.389368 -275.312378) (xy 7.389747 -275.302201) (xy 7.397545 -275.2834) (xy 7.411944 -275.269015)
			(xy 7.430753 -275.261237) (xy 7.44093 -275.260816) (xy 8.84047 -275.260816) (xy 8.850637 -275.261288)
			(xy 8.869427 -275.269059) (xy 8.883812 -275.28343) (xy 8.891602 -275.302212) (xy 8.892032 -275.312378)
			(xy 8.892032 -275.721318) (xy 14.933168 -275.721318) (xy 14.933168 -275.312378) (xy 14.933547 -275.302201)
			(xy 14.941345 -275.2834) (xy 14.955744 -275.269015) (xy 14.974553 -275.261237) (xy 14.98473 -275.260816)
			(xy 16.38427 -275.260816) (xy 16.394437 -275.261288) (xy 16.413227 -275.269059) (xy 16.427612 -275.28343)
			(xy 16.435402 -275.302212) (xy 16.435832 -275.312378) (xy 16.435832 -275.721318) (xy 22.476968 -275.721318)
			(xy 22.476968 -275.312378) (xy 22.477347 -275.302201) (xy 22.485145 -275.2834) (xy 22.499544 -275.269015)
			(xy 22.518353 -275.261237) (xy 22.52853 -275.260816) (xy 23.92807 -275.260816) (xy 23.938237 -275.261288)
			(xy 23.957027 -275.269059) (xy 23.971412 -275.28343) (xy 23.979202 -275.302212) (xy 23.979632 -275.312378)
			(xy 23.979632 -275.721318) (xy 30.020768 -275.721318) (xy 30.020768 -275.312378) (xy 30.021147 -275.302201)
			(xy 30.028945 -275.2834) (xy 30.043344 -275.269015) (xy 30.062153 -275.261237) (xy 30.07233 -275.260816)
			(xy 31.47187 -275.260816) (xy 31.482037 -275.261288) (xy 31.500827 -275.269059) (xy 31.515212 -275.28343)
			(xy 31.523002 -275.302212) (xy 31.523432 -275.312378) (xy 31.523432 -275.721318) (xy 37.564568 -275.721318)
			(xy 37.564568 -275.312378) (xy 37.564947 -275.302201) (xy 37.572745 -275.2834) (xy 37.587144 -275.269015)
			(xy 37.605953 -275.261237) (xy 37.61613 -275.260816) (xy 39.01567 -275.260816) (xy 39.025837 -275.261288)
			(xy 39.044627 -275.269059) (xy 39.059012 -275.28343) (xy 39.066802 -275.302212) (xy 39.067232 -275.312378)
			(xy 39.067232 -275.721318) (xy 45.108368 -275.721318) (xy 45.108368 -275.312378) (xy 45.108747 -275.302201)
			(xy 45.116545 -275.2834) (xy 45.130944 -275.269015) (xy 45.149753 -275.261237) (xy 45.15993 -275.260816)
			(xy 46.55947 -275.260816) (xy 46.569637 -275.261288) (xy 46.588427 -275.269059) (xy 46.602812 -275.28343)
			(xy 46.610602 -275.302212) (xy 46.611032 -275.312378) (xy 46.611032 -275.721318) (xy 52.652168 -275.721318)
			(xy 52.652168 -275.312378) (xy 52.652547 -275.302201) (xy 52.660345 -275.2834) (xy 52.674744 -275.269015)
			(xy 52.693553 -275.261237) (xy 52.70373 -275.260816) (xy 54.10327 -275.260816) (xy 54.113437 -275.261288)
			(xy 54.132227 -275.269059) (xy 54.146612 -275.28343) (xy 54.154402 -275.302212) (xy 54.154832 -275.312378)
			(xy 54.154832 -275.721318) (xy 60.195968 -275.721318) (xy 60.195968 -275.312378) (xy 60.196347 -275.302201)
			(xy 60.204145 -275.2834) (xy 60.218544 -275.269015) (xy 60.237353 -275.261237) (xy 60.24753 -275.260816)
			(xy 61.64707 -275.260816) (xy 61.657237 -275.261288) (xy 61.676027 -275.269059) (xy 61.690412 -275.28343)
			(xy 61.698202 -275.302212) (xy 61.698632 -275.312378) (xy 61.698632 -275.721318) (xy 61.69825 -275.731494)
			(xy 61.690453 -275.750295) (xy 61.676055 -275.76468) (xy 61.657247 -275.772459) (xy 61.64707 -275.77288)
			(xy 60.24753 -275.77288) (xy 60.237363 -275.772412) (xy 60.218572 -275.76464) (xy 60.204187 -275.750268)
			(xy 60.196398 -275.731485) (xy 60.195968 -275.721318) (xy 54.154832 -275.721318) (xy 54.15445 -275.731494)
			(xy 54.146653 -275.750295) (xy 54.132255 -275.76468) (xy 54.113447 -275.772459) (xy 54.10327 -275.77288)
			(xy 52.70373 -275.77288) (xy 52.693563 -275.772412) (xy 52.674772 -275.76464) (xy 52.660387 -275.750268)
			(xy 52.652598 -275.731485) (xy 52.652168 -275.721318) (xy 46.611032 -275.721318) (xy 46.61065 -275.731494)
			(xy 46.602853 -275.750295) (xy 46.588455 -275.76468) (xy 46.569647 -275.772459) (xy 46.55947 -275.77288)
			(xy 45.15993 -275.77288) (xy 45.149763 -275.772412) (xy 45.130972 -275.76464) (xy 45.116587 -275.750268)
			(xy 45.108798 -275.731485) (xy 45.108368 -275.721318) (xy 39.067232 -275.721318) (xy 39.06685 -275.731494)
			(xy 39.059053 -275.750295) (xy 39.044655 -275.76468) (xy 39.025847 -275.772459) (xy 39.01567 -275.77288)
			(xy 37.61613 -275.77288) (xy 37.605963 -275.772412) (xy 37.587172 -275.76464) (xy 37.572787 -275.750268)
			(xy 37.564998 -275.731485) (xy 37.564568 -275.721318) (xy 31.523432 -275.721318) (xy 31.52305 -275.731494)
			(xy 31.515253 -275.750295) (xy 31.500855 -275.76468) (xy 31.482047 -275.772459) (xy 31.47187 -275.77288)
			(xy 30.07233 -275.77288) (xy 30.062163 -275.772412) (xy 30.043372 -275.76464) (xy 30.028987 -275.750268)
			(xy 30.021198 -275.731485) (xy 30.020768 -275.721318) (xy 23.979632 -275.721318) (xy 23.97925 -275.731494)
			(xy 23.971453 -275.750295) (xy 23.957055 -275.76468) (xy 23.938247 -275.772459) (xy 23.92807 -275.77288)
			(xy 22.52853 -275.77288) (xy 22.518363 -275.772412) (xy 22.499572 -275.76464) (xy 22.485187 -275.750268)
			(xy 22.477398 -275.731485) (xy 22.476968 -275.721318) (xy 16.435832 -275.721318) (xy 16.43545 -275.731494)
			(xy 16.427653 -275.750295) (xy 16.413255 -275.76468) (xy 16.394447 -275.772459) (xy 16.38427 -275.77288)
			(xy 14.98473 -275.77288) (xy 14.974563 -275.772412) (xy 14.955772 -275.76464) (xy 14.941387 -275.750268)
			(xy 14.933598 -275.731485) (xy 14.933168 -275.721318) (xy 8.892032 -275.721318) (xy 8.89165 -275.731494)
			(xy 8.883853 -275.750295) (xy 8.869455 -275.76468) (xy 8.850647 -275.772459) (xy 8.84047 -275.77288)
			(xy 7.44093 -275.77288) (xy 7.430763 -275.772412) (xy 7.411972 -275.76464) (xy 7.397587 -275.750268)
			(xy 7.389798 -275.731485) (xy 7.389368 -275.721318) (xy 2.509012 -275.721318) (xy 2.509012 -276.571456)
			(xy 11.489436 -276.571456) (xy 11.489436 -276.162516) (xy 11.489835 -276.152358) (xy 11.497632 -276.133599)
			(xy 11.512037 -276.119274) (xy 11.530838 -276.11158) (xy 11.540998 -276.111208) (xy 12.940538 -276.111208)
			(xy 12.950663 -276.111694) (xy 12.969379 -276.119429) (xy 12.983733 -276.133714) (xy 12.991556 -276.152393)
			(xy 12.9921 -276.162516) (xy 12.9921 -276.571456) (xy 19.033236 -276.571456) (xy 19.033236 -276.162516)
			(xy 19.033635 -276.152358) (xy 19.041432 -276.133599) (xy 19.055837 -276.119274) (xy 19.074638 -276.11158)
			(xy 19.084798 -276.111208) (xy 20.484338 -276.111208) (xy 20.494463 -276.111694) (xy 20.513179 -276.119429)
			(xy 20.527533 -276.133714) (xy 20.535356 -276.152393) (xy 20.5359 -276.162516) (xy 20.5359 -276.571456)
			(xy 26.577036 -276.571456) (xy 26.577036 -276.162516) (xy 26.577435 -276.152358) (xy 26.585232 -276.133599)
			(xy 26.599637 -276.119274) (xy 26.618438 -276.11158) (xy 26.628598 -276.111208) (xy 28.028138 -276.111208)
			(xy 28.038263 -276.111694) (xy 28.056979 -276.119429) (xy 28.071333 -276.133714) (xy 28.079156 -276.152393)
			(xy 28.0797 -276.162516) (xy 28.0797 -276.571456) (xy 34.120836 -276.571456) (xy 34.120836 -276.162516)
			(xy 34.121235 -276.152358) (xy 34.129032 -276.133599) (xy 34.143437 -276.119274) (xy 34.162238 -276.11158)
			(xy 34.172398 -276.111208) (xy 35.571938 -276.111208) (xy 35.582063 -276.111694) (xy 35.600779 -276.119429)
			(xy 35.615133 -276.133714) (xy 35.622956 -276.152393) (xy 35.6235 -276.162516) (xy 35.6235 -276.571456)
			(xy 41.664636 -276.571456) (xy 41.664636 -276.162516) (xy 41.665035 -276.152358) (xy 41.672832 -276.133599)
			(xy 41.687237 -276.119274) (xy 41.706038 -276.11158) (xy 41.716198 -276.111208) (xy 43.115738 -276.111208)
			(xy 43.125863 -276.111694) (xy 43.144579 -276.119429) (xy 43.158933 -276.133714) (xy 43.166756 -276.152393)
			(xy 43.1673 -276.162516) (xy 43.1673 -276.571456) (xy 49.208436 -276.571456) (xy 49.208436 -276.162516)
			(xy 49.208835 -276.152358) (xy 49.216632 -276.133599) (xy 49.231037 -276.119274) (xy 49.249838 -276.11158)
			(xy 49.259998 -276.111208) (xy 50.659538 -276.111208) (xy 50.669663 -276.111694) (xy 50.688379 -276.119429)
			(xy 50.702733 -276.133714) (xy 50.710556 -276.152393) (xy 50.7111 -276.162516) (xy 50.7111 -276.571456)
			(xy 56.752236 -276.571456) (xy 56.752236 -276.162516) (xy 56.752635 -276.152358) (xy 56.760432 -276.133599)
			(xy 56.774837 -276.119274) (xy 56.793638 -276.11158) (xy 56.803798 -276.111208) (xy 58.203338 -276.111208)
			(xy 58.213463 -276.111694) (xy 58.232179 -276.119429) (xy 58.246533 -276.133714) (xy 58.254356 -276.152393)
			(xy 58.2549 -276.162516) (xy 58.2549 -276.571456) (xy 64.296036 -276.571456) (xy 64.296036 -276.162516)
			(xy 64.296435 -276.152358) (xy 64.304232 -276.133599) (xy 64.318637 -276.119274) (xy 64.337438 -276.11158)
			(xy 64.347598 -276.111208) (xy 65.747138 -276.111208) (xy 65.757263 -276.111694) (xy 65.775979 -276.119429)
			(xy 65.790333 -276.133714) (xy 65.798156 -276.152393) (xy 65.7987 -276.162516) (xy 65.7987 -276.571456)
			(xy 65.798242 -276.581607) (xy 65.790461 -276.600359) (xy 65.776075 -276.614684) (xy 65.757291 -276.622385)
			(xy 65.747138 -276.622764) (xy 64.347598 -276.622764) (xy 64.337472 -276.622275) (xy 64.318751 -276.614547)
			(xy 64.304395 -276.600262) (xy 64.296575 -276.58158) (xy 64.296036 -276.571456) (xy 58.2549 -276.571456)
			(xy 58.254442 -276.581607) (xy 58.246661 -276.600359) (xy 58.232275 -276.614684) (xy 58.213491 -276.622385)
			(xy 58.203338 -276.622764) (xy 56.803798 -276.622764) (xy 56.793672 -276.622275) (xy 56.774951 -276.614547)
			(xy 56.760595 -276.600262) (xy 56.752775 -276.58158) (xy 56.752236 -276.571456) (xy 50.7111 -276.571456)
			(xy 50.710642 -276.581607) (xy 50.702861 -276.600359) (xy 50.688475 -276.614684) (xy 50.669691 -276.622385)
			(xy 50.659538 -276.622764) (xy 49.259998 -276.622764) (xy 49.249872 -276.622275) (xy 49.231151 -276.614547)
			(xy 49.216795 -276.600262) (xy 49.208975 -276.58158) (xy 49.208436 -276.571456) (xy 43.1673 -276.571456)
			(xy 43.166842 -276.581607) (xy 43.159061 -276.600359) (xy 43.144675 -276.614684) (xy 43.125891 -276.622385)
			(xy 43.115738 -276.622764) (xy 41.716198 -276.622764) (xy 41.706072 -276.622275) (xy 41.687351 -276.614547)
			(xy 41.672995 -276.600262) (xy 41.665175 -276.58158) (xy 41.664636 -276.571456) (xy 35.6235 -276.571456)
			(xy 35.623042 -276.581607) (xy 35.615261 -276.600359) (xy 35.600875 -276.614684) (xy 35.582091 -276.622385)
			(xy 35.571938 -276.622764) (xy 34.172398 -276.622764) (xy 34.162272 -276.622275) (xy 34.143551 -276.614547)
			(xy 34.129195 -276.600262) (xy 34.121375 -276.58158) (xy 34.120836 -276.571456) (xy 28.0797 -276.571456)
			(xy 28.079242 -276.581607) (xy 28.071461 -276.600359) (xy 28.057075 -276.614684) (xy 28.038291 -276.622385)
			(xy 28.028138 -276.622764) (xy 26.628598 -276.622764) (xy 26.618472 -276.622275) (xy 26.599751 -276.614547)
			(xy 26.585395 -276.600262) (xy 26.577575 -276.58158) (xy 26.577036 -276.571456) (xy 20.5359 -276.571456)
			(xy 20.535442 -276.581607) (xy 20.527661 -276.600359) (xy 20.513275 -276.614684) (xy 20.494491 -276.622385)
			(xy 20.484338 -276.622764) (xy 19.084798 -276.622764) (xy 19.074672 -276.622275) (xy 19.055951 -276.614547)
			(xy 19.041595 -276.600262) (xy 19.033775 -276.58158) (xy 19.033236 -276.571456) (xy 12.9921 -276.571456)
			(xy 12.991642 -276.581607) (xy 12.983861 -276.600359) (xy 12.969475 -276.614684) (xy 12.950691 -276.622385)
			(xy 12.940538 -276.622764) (xy 11.540998 -276.622764) (xy 11.530872 -276.622275) (xy 11.512151 -276.614547)
			(xy 11.497795 -276.600262) (xy 11.489975 -276.58158) (xy 11.489436 -276.571456) (xy 2.509012 -276.571456)
			(xy 2.509012 -276.708616) (xy 102.022656 -276.708616) (xy 102.023189 -276.683284) (xy 102.030938 -276.633215)
			(xy 102.046256 -276.584922) (xy 102.068781 -276.53954) (xy 102.097985 -276.498139) (xy 102.133179 -276.461694)
			(xy 102.173534 -276.431062) (xy 102.218101 -276.406964) (xy 102.265829 -276.389968) (xy 102.290626 -276.384766)
			(xy 102.313486 -276.380448) (xy 102.518464 -276.025356) (xy 102.510844 -276.003512) (xy 102.502285 -275.977153)
			(xy 102.493085 -275.922508) (xy 102.492556 -275.8948) (xy 102.493064 -275.868913) (xy 102.501163 -275.817775)
			(xy 102.517162 -275.768535) (xy 102.540668 -275.722403) (xy 102.5711 -275.680516) (xy 102.60771 -275.643906)
			(xy 102.649597 -275.613474) (xy 102.695729 -275.589968) (xy 102.744969 -275.573969) (xy 102.796107 -275.56587)
			(xy 102.847881 -275.56587) (xy 102.899019 -275.573969) (xy 102.948259 -275.589968) (xy 102.994391 -275.613474)
			(xy 103.036278 -275.643906) (xy 103.072888 -275.680516) (xy 103.10332 -275.722403) (xy 103.126826 -275.768535)
			(xy 103.142825 -275.817775) (xy 103.150924 -275.868913) (xy 103.151432 -275.8948) (xy 104.372156 -275.8948)
			(xy 104.372675 -275.869467) (xy 104.380426 -275.819398) (xy 104.395746 -275.771105) (xy 104.418273 -275.725723)
			(xy 104.447479 -275.684322) (xy 104.482674 -275.647877) (xy 104.523031 -275.617245) (xy 104.567599 -275.593147)
			(xy 104.615329 -275.576152) (xy 104.640126 -275.57095) (xy 104.662986 -275.566632) (xy 104.868218 -275.211286)
			(xy 104.860598 -275.189188) (xy 104.851972 -275.162906) (xy 104.842659 -275.108385) (xy 104.842056 -275.08073)
			(xy 104.842564 -275.054823) (xy 104.85067 -275.003646) (xy 104.866682 -274.954367) (xy 104.890205 -274.9082)
			(xy 104.920661 -274.866281) (xy 104.957299 -274.829643) (xy 104.999218 -274.799187) (xy 105.045385 -274.775664)
			(xy 105.094664 -274.759652) (xy 105.145841 -274.751546) (xy 105.197655 -274.751546) (xy 105.248832 -274.759652)
			(xy 105.298111 -274.775664) (xy 105.344278 -274.799187) (xy 105.386197 -274.829643) (xy 105.422835 -274.866281)
			(xy 105.453291 -274.9082) (xy 105.476814 -274.954367) (xy 105.492826 -275.003646) (xy 105.500932 -275.054823)
			(xy 105.50144 -275.08073) (xy 107.661456 -275.08073) (xy 107.661964 -275.054823) (xy 107.67007 -275.003646)
			(xy 107.686082 -274.954367) (xy 107.709605 -274.9082) (xy 107.740061 -274.866281) (xy 107.776699 -274.829643)
			(xy 107.818618 -274.799187) (xy 107.864785 -274.775664) (xy 107.914064 -274.759652) (xy 107.965241 -274.751546)
			(xy 108.017055 -274.751546) (xy 108.068232 -274.759652) (xy 108.117511 -274.775664) (xy 108.163678 -274.799187)
			(xy 108.205597 -274.829643) (xy 108.242235 -274.866281) (xy 108.245979 -274.871434) (xy 158.062168 -274.871434)
			(xy 158.062168 -274.462494) (xy 158.06256 -274.452318) (xy 158.070352 -274.433518) (xy 158.084748 -274.419132)
			(xy 158.103554 -274.411353) (xy 158.11373 -274.410932) (xy 159.51327 -274.410932) (xy 159.523439 -274.411388)
			(xy 159.542232 -274.419162) (xy 159.556617 -274.433538) (xy 159.564404 -274.452325) (xy 159.564832 -274.462494)
			(xy 159.564832 -274.871434) (xy 162.162236 -274.871434) (xy 162.162236 -274.462494) (xy 162.162729 -274.452336)
			(xy 162.170505 -274.433567) (xy 162.184871 -274.419202) (xy 162.20364 -274.411428) (xy 162.213798 -274.410932)
			(xy 163.613338 -274.410932) (xy 163.623497 -274.411402) (xy 163.642266 -274.419188) (xy 163.65663 -274.433561)
			(xy 163.664404 -274.452334) (xy 163.6649 -274.462494) (xy 163.6649 -274.871434) (xy 165.605968 -274.871434)
			(xy 165.605968 -274.462494) (xy 165.60636 -274.452318) (xy 165.614152 -274.433518) (xy 165.628548 -274.419132)
			(xy 165.647354 -274.411353) (xy 165.65753 -274.410932) (xy 167.05707 -274.410932) (xy 167.067239 -274.411388)
			(xy 167.086032 -274.419162) (xy 167.100417 -274.433538) (xy 167.108204 -274.452325) (xy 167.108632 -274.462494)
			(xy 167.108632 -274.871434) (xy 169.706036 -274.871434) (xy 169.706036 -274.462494) (xy 169.706529 -274.452336)
			(xy 169.714305 -274.433567) (xy 169.728671 -274.419202) (xy 169.74744 -274.411428) (xy 169.757598 -274.410932)
			(xy 171.157138 -274.410932) (xy 171.167297 -274.411402) (xy 171.186066 -274.419188) (xy 171.20043 -274.433561)
			(xy 171.208204 -274.452334) (xy 171.2087 -274.462494) (xy 171.2087 -274.871434) (xy 173.149768 -274.871434)
			(xy 173.149768 -274.462494) (xy 173.15016 -274.452318) (xy 173.157952 -274.433518) (xy 173.172348 -274.419132)
			(xy 173.191154 -274.411353) (xy 173.20133 -274.410932) (xy 174.60087 -274.410932) (xy 174.611039 -274.411388)
			(xy 174.629832 -274.419162) (xy 174.644217 -274.433538) (xy 174.652004 -274.452325) (xy 174.652432 -274.462494)
			(xy 174.652432 -274.871434) (xy 177.249836 -274.871434) (xy 177.249836 -274.462494) (xy 177.250329 -274.452336)
			(xy 177.258105 -274.433567) (xy 177.272471 -274.419202) (xy 177.29124 -274.411428) (xy 177.301398 -274.410932)
			(xy 178.700938 -274.410932) (xy 178.711097 -274.411402) (xy 178.729866 -274.419188) (xy 178.74423 -274.433561)
			(xy 178.752004 -274.452334) (xy 178.7525 -274.462494) (xy 178.7525 -274.871434) (xy 180.693568 -274.871434)
			(xy 180.693568 -274.462494) (xy 180.69396 -274.452318) (xy 180.701752 -274.433518) (xy 180.716148 -274.419132)
			(xy 180.734954 -274.411353) (xy 180.74513 -274.410932) (xy 182.14467 -274.410932) (xy 182.154839 -274.411388)
			(xy 182.173632 -274.419162) (xy 182.188017 -274.433538) (xy 182.195804 -274.452325) (xy 182.196232 -274.462494)
			(xy 182.196232 -274.871434) (xy 184.793636 -274.871434) (xy 184.793636 -274.462494) (xy 184.794129 -274.452336)
			(xy 184.801905 -274.433567) (xy 184.816271 -274.419202) (xy 184.83504 -274.411428) (xy 184.845198 -274.410932)
			(xy 186.244738 -274.410932) (xy 186.254897 -274.411402) (xy 186.273666 -274.419188) (xy 186.28803 -274.433561)
			(xy 186.295804 -274.452334) (xy 186.2963 -274.462494) (xy 186.2963 -274.871434) (xy 188.237368 -274.871434)
			(xy 188.237368 -274.462494) (xy 188.23776 -274.452318) (xy 188.245552 -274.433518) (xy 188.259948 -274.419132)
			(xy 188.278754 -274.411353) (xy 188.28893 -274.410932) (xy 189.68847 -274.410932) (xy 189.698639 -274.411388)
			(xy 189.717432 -274.419162) (xy 189.731817 -274.433538) (xy 189.739604 -274.452325) (xy 189.740032 -274.462494)
			(xy 189.740032 -274.871434) (xy 192.337436 -274.871434) (xy 192.337436 -274.462494) (xy 192.337929 -274.452336)
			(xy 192.345705 -274.433567) (xy 192.360071 -274.419202) (xy 192.37884 -274.411428) (xy 192.388998 -274.410932)
			(xy 193.788538 -274.410932) (xy 193.798697 -274.411402) (xy 193.817466 -274.419188) (xy 193.83183 -274.433561)
			(xy 193.839604 -274.452334) (xy 193.8401 -274.462494) (xy 193.8401 -274.871434) (xy 195.781168 -274.871434)
			(xy 195.781168 -274.462494) (xy 195.78156 -274.452318) (xy 195.789352 -274.433518) (xy 195.803748 -274.419132)
			(xy 195.822554 -274.411353) (xy 195.83273 -274.410932) (xy 197.23227 -274.410932) (xy 197.242439 -274.411388)
			(xy 197.261232 -274.419162) (xy 197.275617 -274.433538) (xy 197.283404 -274.452325) (xy 197.283832 -274.462494)
			(xy 197.283832 -274.871434) (xy 199.881236 -274.871434) (xy 199.881236 -274.462494) (xy 199.881729 -274.452336)
			(xy 199.889505 -274.433567) (xy 199.903871 -274.419202) (xy 199.92264 -274.411428) (xy 199.932798 -274.410932)
			(xy 201.332338 -274.410932) (xy 201.342497 -274.411402) (xy 201.361266 -274.419188) (xy 201.37563 -274.433561)
			(xy 201.383404 -274.452334) (xy 201.3839 -274.462494) (xy 201.3839 -274.871434) (xy 203.324968 -274.871434)
			(xy 203.324968 -274.462494) (xy 203.32536 -274.452318) (xy 203.333152 -274.433518) (xy 203.347548 -274.419132)
			(xy 203.366354 -274.411353) (xy 203.37653 -274.410932) (xy 204.77607 -274.410932) (xy 204.786239 -274.411388)
			(xy 204.805032 -274.419162) (xy 204.819417 -274.433538) (xy 204.827204 -274.452325) (xy 204.827632 -274.462494)
			(xy 204.827632 -274.871434) (xy 207.425036 -274.871434) (xy 207.425036 -274.462494) (xy 207.425529 -274.452336)
			(xy 207.433305 -274.433567) (xy 207.447671 -274.419202) (xy 207.46644 -274.411428) (xy 207.476598 -274.410932)
			(xy 208.876138 -274.410932) (xy 208.886297 -274.411402) (xy 208.905066 -274.419188) (xy 208.91943 -274.433561)
			(xy 208.927204 -274.452334) (xy 208.9277 -274.462494) (xy 208.9277 -274.871434) (xy 210.868768 -274.871434)
			(xy 210.868768 -274.462494) (xy 210.86916 -274.452318) (xy 210.876952 -274.433518) (xy 210.891348 -274.419132)
			(xy 210.910154 -274.411353) (xy 210.92033 -274.410932) (xy 212.31987 -274.410932) (xy 212.330039 -274.411388)
			(xy 212.348832 -274.419162) (xy 212.363217 -274.433538) (xy 212.371004 -274.452325) (xy 212.371432 -274.462494)
			(xy 212.371432 -274.871434) (xy 214.968836 -274.871434) (xy 214.968836 -274.462494) (xy 214.969329 -274.452336)
			(xy 214.977105 -274.433567) (xy 214.991471 -274.419202) (xy 215.01024 -274.411428) (xy 215.020398 -274.410932)
			(xy 216.419938 -274.410932) (xy 216.430097 -274.411402) (xy 216.448866 -274.419188) (xy 216.46323 -274.433561)
			(xy 216.471004 -274.452334) (xy 216.4715 -274.462494) (xy 216.4715 -274.871434) (xy 255.329436 -274.871434)
			(xy 255.329436 -274.462494) (xy 255.329929 -274.452336) (xy 255.337705 -274.433567) (xy 255.352071 -274.419202)
			(xy 255.37084 -274.411428) (xy 255.380998 -274.410932) (xy 256.780538 -274.410932) (xy 256.790697 -274.411402)
			(xy 256.809466 -274.419188) (xy 256.82383 -274.433561) (xy 256.831604 -274.452334) (xy 256.8321 -274.462494)
			(xy 256.8321 -274.871434) (xy 259.429504 -274.871434) (xy 259.429504 -274.462494) (xy 259.430028 -274.45234)
			(xy 259.437798 -274.433577) (xy 259.452154 -274.419214) (xy 259.470912 -274.411433) (xy 259.481066 -274.410932)
			(xy 260.880606 -274.410932) (xy 260.890763 -274.411428) (xy 260.909531 -274.419204) (xy 260.923896 -274.433569)
			(xy 260.931672 -274.452337) (xy 260.932168 -274.462494) (xy 260.932168 -274.871434) (xy 262.873236 -274.871434)
			(xy 262.873236 -274.462494) (xy 262.873729 -274.452336) (xy 262.881505 -274.433567) (xy 262.895871 -274.419202)
			(xy 262.91464 -274.411428) (xy 262.924798 -274.410932) (xy 264.324338 -274.410932) (xy 264.334497 -274.411402)
			(xy 264.353266 -274.419188) (xy 264.36763 -274.433561) (xy 264.375404 -274.452334) (xy 264.3759 -274.462494)
			(xy 264.3759 -274.871434) (xy 266.973304 -274.871434) (xy 266.973304 -274.462494) (xy 266.973828 -274.45234)
			(xy 266.981598 -274.433577) (xy 266.995954 -274.419214) (xy 267.014712 -274.411433) (xy 267.024866 -274.410932)
			(xy 268.424406 -274.410932) (xy 268.434563 -274.411428) (xy 268.453331 -274.419204) (xy 268.467696 -274.433569)
			(xy 268.475472 -274.452337) (xy 268.475968 -274.462494) (xy 268.475968 -274.871434) (xy 270.417036 -274.871434)
			(xy 270.417036 -274.462494) (xy 270.417529 -274.452336) (xy 270.425305 -274.433567) (xy 270.439671 -274.419202)
			(xy 270.45844 -274.411428) (xy 270.468598 -274.410932) (xy 271.868138 -274.410932) (xy 271.878297 -274.411402)
			(xy 271.897066 -274.419188) (xy 271.91143 -274.433561) (xy 271.919204 -274.452334) (xy 271.9197 -274.462494)
			(xy 271.9197 -274.871434) (xy 274.517104 -274.871434) (xy 274.517104 -274.462494) (xy 274.517628 -274.45234)
			(xy 274.525398 -274.433577) (xy 274.539754 -274.419214) (xy 274.558512 -274.411433) (xy 274.568666 -274.410932)
			(xy 275.968206 -274.410932) (xy 275.978363 -274.411428) (xy 275.997131 -274.419204) (xy 276.011496 -274.433569)
			(xy 276.019272 -274.452337) (xy 276.019768 -274.462494) (xy 276.019768 -274.871434) (xy 277.960836 -274.871434)
			(xy 277.960836 -274.462494) (xy 277.961329 -274.452336) (xy 277.969105 -274.433567) (xy 277.983471 -274.419202)
			(xy 278.00224 -274.411428) (xy 278.012398 -274.410932) (xy 279.411938 -274.410932) (xy 279.422097 -274.411402)
			(xy 279.440866 -274.419188) (xy 279.45523 -274.433561) (xy 279.463004 -274.452334) (xy 279.4635 -274.462494)
			(xy 279.4635 -274.871434) (xy 282.060904 -274.871434) (xy 282.060904 -274.462494) (xy 282.061428 -274.45234)
			(xy 282.069198 -274.433577) (xy 282.083554 -274.419214) (xy 282.102312 -274.411433) (xy 282.112466 -274.410932)
			(xy 283.512006 -274.410932) (xy 283.522163 -274.411428) (xy 283.540931 -274.419204) (xy 283.555296 -274.433569)
			(xy 283.563072 -274.452337) (xy 283.563568 -274.462494) (xy 283.563568 -274.871434) (xy 285.504636 -274.871434)
			(xy 285.504636 -274.462494) (xy 285.505129 -274.452336) (xy 285.512905 -274.433567) (xy 285.527271 -274.419202)
			(xy 285.54604 -274.411428) (xy 285.556198 -274.410932) (xy 286.955738 -274.410932) (xy 286.965897 -274.411402)
			(xy 286.984666 -274.419188) (xy 286.99903 -274.433561) (xy 287.006804 -274.452334) (xy 287.0073 -274.462494)
			(xy 287.0073 -274.871434) (xy 289.604704 -274.871434) (xy 289.604704 -274.462494) (xy 289.605228 -274.45234)
			(xy 289.612998 -274.433577) (xy 289.627354 -274.419214) (xy 289.646112 -274.411433) (xy 289.656266 -274.410932)
			(xy 291.055806 -274.410932) (xy 291.065963 -274.411428) (xy 291.084731 -274.419204) (xy 291.099096 -274.433569)
			(xy 291.106872 -274.452337) (xy 291.107368 -274.462494) (xy 291.107368 -274.871434) (xy 293.048436 -274.871434)
			(xy 293.048436 -274.462494) (xy 293.048929 -274.452336) (xy 293.056705 -274.433567) (xy 293.071071 -274.419202)
			(xy 293.08984 -274.411428) (xy 293.099998 -274.410932) (xy 294.499538 -274.410932) (xy 294.509697 -274.411402)
			(xy 294.528466 -274.419188) (xy 294.54283 -274.433561) (xy 294.550604 -274.452334) (xy 294.5511 -274.462494)
			(xy 294.5511 -274.871434) (xy 297.148504 -274.871434) (xy 297.148504 -274.462494) (xy 297.149028 -274.45234)
			(xy 297.156798 -274.433577) (xy 297.171154 -274.419214) (xy 297.189912 -274.411433) (xy 297.200066 -274.410932)
			(xy 298.599606 -274.410932) (xy 298.609763 -274.411428) (xy 298.628531 -274.419204) (xy 298.642896 -274.433569)
			(xy 298.650672 -274.452337) (xy 298.651168 -274.462494) (xy 298.651168 -274.871434) (xy 300.592236 -274.871434)
			(xy 300.592236 -274.462494) (xy 300.592729 -274.452336) (xy 300.600505 -274.433567) (xy 300.614871 -274.419202)
			(xy 300.63364 -274.411428) (xy 300.643798 -274.410932) (xy 302.043338 -274.410932) (xy 302.053497 -274.411402)
			(xy 302.072266 -274.419188) (xy 302.08663 -274.433561) (xy 302.094404 -274.452334) (xy 302.0949 -274.462494)
			(xy 302.0949 -274.871434) (xy 304.692304 -274.871434) (xy 304.692304 -274.462494) (xy 304.692828 -274.45234)
			(xy 304.700598 -274.433577) (xy 304.714954 -274.419214) (xy 304.733712 -274.411433) (xy 304.743866 -274.410932)
			(xy 306.143406 -274.410932) (xy 306.153563 -274.411428) (xy 306.172331 -274.419204) (xy 306.186696 -274.433569)
			(xy 306.194472 -274.452337) (xy 306.194968 -274.462494) (xy 306.194968 -274.871434) (xy 308.136036 -274.871434)
			(xy 308.136036 -274.462494) (xy 308.136529 -274.452336) (xy 308.144305 -274.433567) (xy 308.158671 -274.419202)
			(xy 308.17744 -274.411428) (xy 308.187598 -274.410932) (xy 309.587138 -274.410932) (xy 309.597297 -274.411402)
			(xy 309.616066 -274.419188) (xy 309.63043 -274.433561) (xy 309.638204 -274.452334) (xy 309.6387 -274.462494)
			(xy 309.6387 -274.871434) (xy 312.236104 -274.871434) (xy 312.236104 -274.462494) (xy 312.236628 -274.45234)
			(xy 312.244398 -274.433577) (xy 312.258754 -274.419214) (xy 312.277512 -274.411433) (xy 312.287666 -274.410932)
			(xy 313.687206 -274.410932) (xy 313.697363 -274.411428) (xy 313.716131 -274.419204) (xy 313.730496 -274.433569)
			(xy 313.738272 -274.452337) (xy 313.738768 -274.462494) (xy 313.738768 -274.871434) (xy 313.738295 -274.881593)
			(xy 313.73051 -274.900362) (xy 313.716138 -274.914726) (xy 313.697365 -274.9225) (xy 313.687206 -274.922996)
			(xy 312.287666 -274.922996) (xy 312.27751 -274.922495) (xy 312.258747 -274.914716) (xy 312.244384 -274.900353)
			(xy 312.236605 -274.88159) (xy 312.236104 -274.871434) (xy 309.6387 -274.871434) (xy 309.638195 -274.881589)
			(xy 309.630417 -274.900352) (xy 309.616055 -274.914715) (xy 309.597293 -274.922495) (xy 309.587138 -274.922996)
			(xy 308.187598 -274.922996) (xy 308.177444 -274.922469) (xy 308.158682 -274.9147) (xy 308.144318 -274.900345)
			(xy 308.136537 -274.881587) (xy 308.136036 -274.871434) (xy 306.194968 -274.871434) (xy 306.194495 -274.881593)
			(xy 306.18671 -274.900362) (xy 306.172338 -274.914726) (xy 306.153565 -274.9225) (xy 306.143406 -274.922996)
			(xy 304.743866 -274.922996) (xy 304.73371 -274.922495) (xy 304.714947 -274.914716) (xy 304.700584 -274.900353)
			(xy 304.692805 -274.88159) (xy 304.692304 -274.871434) (xy 302.0949 -274.871434) (xy 302.094395 -274.881589)
			(xy 302.086617 -274.900352) (xy 302.072255 -274.914715) (xy 302.053493 -274.922495) (xy 302.043338 -274.922996)
			(xy 300.643798 -274.922996) (xy 300.633644 -274.922469) (xy 300.614882 -274.9147) (xy 300.600518 -274.900345)
			(xy 300.592737 -274.881587) (xy 300.592236 -274.871434) (xy 298.651168 -274.871434) (xy 298.650695 -274.881593)
			(xy 298.64291 -274.900362) (xy 298.628538 -274.914726) (xy 298.609765 -274.9225) (xy 298.599606 -274.922996)
			(xy 297.200066 -274.922996) (xy 297.18991 -274.922495) (xy 297.171147 -274.914716) (xy 297.156784 -274.900353)
			(xy 297.149005 -274.88159) (xy 297.148504 -274.871434) (xy 294.5511 -274.871434) (xy 294.550595 -274.881589)
			(xy 294.542817 -274.900352) (xy 294.528455 -274.914715) (xy 294.509693 -274.922495) (xy 294.499538 -274.922996)
			(xy 293.099998 -274.922996) (xy 293.089844 -274.922469) (xy 293.071082 -274.9147) (xy 293.056718 -274.900345)
			(xy 293.048937 -274.881587) (xy 293.048436 -274.871434) (xy 291.107368 -274.871434) (xy 291.106895 -274.881593)
			(xy 291.09911 -274.900362) (xy 291.084738 -274.914726) (xy 291.065965 -274.9225) (xy 291.055806 -274.922996)
			(xy 289.656266 -274.922996) (xy 289.64611 -274.922495) (xy 289.627347 -274.914716) (xy 289.612984 -274.900353)
			(xy 289.605205 -274.88159) (xy 289.604704 -274.871434) (xy 287.0073 -274.871434) (xy 287.006795 -274.881589)
			(xy 286.999017 -274.900352) (xy 286.984655 -274.914715) (xy 286.965893 -274.922495) (xy 286.955738 -274.922996)
			(xy 285.556198 -274.922996) (xy 285.546044 -274.922469) (xy 285.527282 -274.9147) (xy 285.512918 -274.900345)
			(xy 285.505137 -274.881587) (xy 285.504636 -274.871434) (xy 283.563568 -274.871434) (xy 283.563095 -274.881593)
			(xy 283.55531 -274.900362) (xy 283.540938 -274.914726) (xy 283.522165 -274.9225) (xy 283.512006 -274.922996)
			(xy 282.112466 -274.922996) (xy 282.10231 -274.922495) (xy 282.083547 -274.914716) (xy 282.069184 -274.900353)
			(xy 282.061405 -274.88159) (xy 282.060904 -274.871434) (xy 279.4635 -274.871434) (xy 279.462995 -274.881589)
			(xy 279.455217 -274.900352) (xy 279.440855 -274.914715) (xy 279.422093 -274.922495) (xy 279.411938 -274.922996)
			(xy 278.012398 -274.922996) (xy 278.002244 -274.922469) (xy 277.983482 -274.9147) (xy 277.969118 -274.900345)
			(xy 277.961337 -274.881587) (xy 277.960836 -274.871434) (xy 276.019768 -274.871434) (xy 276.019295 -274.881593)
			(xy 276.01151 -274.900362) (xy 275.997138 -274.914726) (xy 275.978365 -274.9225) (xy 275.968206 -274.922996)
			(xy 274.568666 -274.922996) (xy 274.55851 -274.922495) (xy 274.539747 -274.914716) (xy 274.525384 -274.900353)
			(xy 274.517605 -274.88159) (xy 274.517104 -274.871434) (xy 271.9197 -274.871434) (xy 271.919195 -274.881589)
			(xy 271.911417 -274.900352) (xy 271.897055 -274.914715) (xy 271.878293 -274.922495) (xy 271.868138 -274.922996)
			(xy 270.468598 -274.922996) (xy 270.458444 -274.922469) (xy 270.439682 -274.9147) (xy 270.425318 -274.900345)
			(xy 270.417537 -274.881587) (xy 270.417036 -274.871434) (xy 268.475968 -274.871434) (xy 268.475495 -274.881593)
			(xy 268.46771 -274.900362) (xy 268.453338 -274.914726) (xy 268.434565 -274.9225) (xy 268.424406 -274.922996)
			(xy 267.024866 -274.922996) (xy 267.01471 -274.922495) (xy 266.995947 -274.914716) (xy 266.981584 -274.900353)
			(xy 266.973805 -274.88159) (xy 266.973304 -274.871434) (xy 264.3759 -274.871434) (xy 264.375395 -274.881589)
			(xy 264.367617 -274.900352) (xy 264.353255 -274.914715) (xy 264.334493 -274.922495) (xy 264.324338 -274.922996)
			(xy 262.924798 -274.922996) (xy 262.914644 -274.922469) (xy 262.895882 -274.9147) (xy 262.881518 -274.900345)
			(xy 262.873737 -274.881587) (xy 262.873236 -274.871434) (xy 260.932168 -274.871434) (xy 260.931695 -274.881593)
			(xy 260.92391 -274.900362) (xy 260.909538 -274.914726) (xy 260.890765 -274.9225) (xy 260.880606 -274.922996)
			(xy 259.481066 -274.922996) (xy 259.47091 -274.922495) (xy 259.452147 -274.914716) (xy 259.437784 -274.900353)
			(xy 259.430005 -274.88159) (xy 259.429504 -274.871434) (xy 256.8321 -274.871434) (xy 256.831595 -274.881589)
			(xy 256.823817 -274.900352) (xy 256.809455 -274.914715) (xy 256.790693 -274.922495) (xy 256.780538 -274.922996)
			(xy 255.380998 -274.922996) (xy 255.370844 -274.922469) (xy 255.352082 -274.9147) (xy 255.337718 -274.900345)
			(xy 255.329937 -274.881587) (xy 255.329436 -274.871434) (xy 216.4715 -274.871434) (xy 216.470995 -274.881589)
			(xy 216.463217 -274.900352) (xy 216.448855 -274.914715) (xy 216.430093 -274.922495) (xy 216.419938 -274.922996)
			(xy 215.020398 -274.922996) (xy 215.010244 -274.922469) (xy 214.991482 -274.9147) (xy 214.977118 -274.900345)
			(xy 214.969337 -274.881587) (xy 214.968836 -274.871434) (xy 212.371432 -274.871434) (xy 212.370994 -274.881598)
			(xy 212.363203 -274.900373) (xy 212.34882 -274.914738) (xy 212.330034 -274.922506) (xy 212.31987 -274.922996)
			(xy 210.92033 -274.922996) (xy 210.910178 -274.922443) (xy 210.891416 -274.914685) (xy 210.877051 -274.900337)
			(xy 210.869269 -274.881585) (xy 210.868768 -274.871434) (xy 208.9277 -274.871434) (xy 208.927195 -274.881589)
			(xy 208.919417 -274.900352) (xy 208.905055 -274.914715) (xy 208.886293 -274.922495) (xy 208.876138 -274.922996)
			(xy 207.476598 -274.922996) (xy 207.466444 -274.922469) (xy 207.447682 -274.9147) (xy 207.433318 -274.900345)
			(xy 207.425537 -274.881587) (xy 207.425036 -274.871434) (xy 204.827632 -274.871434) (xy 204.827194 -274.881598)
			(xy 204.819403 -274.900373) (xy 204.80502 -274.914738) (xy 204.786234 -274.922506) (xy 204.77607 -274.922996)
			(xy 203.37653 -274.922996) (xy 203.366378 -274.922443) (xy 203.347616 -274.914685) (xy 203.333251 -274.900337)
			(xy 203.325469 -274.881585) (xy 203.324968 -274.871434) (xy 201.3839 -274.871434) (xy 201.383395 -274.881589)
			(xy 201.375617 -274.900352) (xy 201.361255 -274.914715) (xy 201.342493 -274.922495) (xy 201.332338 -274.922996)
			(xy 199.932798 -274.922996) (xy 199.922644 -274.922469) (xy 199.903882 -274.9147) (xy 199.889518 -274.900345)
			(xy 199.881737 -274.881587) (xy 199.881236 -274.871434) (xy 197.283832 -274.871434) (xy 197.283394 -274.881598)
			(xy 197.275603 -274.900373) (xy 197.26122 -274.914738) (xy 197.242434 -274.922506) (xy 197.23227 -274.922996)
			(xy 195.83273 -274.922996) (xy 195.822578 -274.922443) (xy 195.803816 -274.914685) (xy 195.789451 -274.900337)
			(xy 195.781669 -274.881585) (xy 195.781168 -274.871434) (xy 193.8401 -274.871434) (xy 193.839595 -274.881589)
			(xy 193.831817 -274.900352) (xy 193.817455 -274.914715) (xy 193.798693 -274.922495) (xy 193.788538 -274.922996)
			(xy 192.388998 -274.922996) (xy 192.378844 -274.922469) (xy 192.360082 -274.9147) (xy 192.345718 -274.900345)
			(xy 192.337937 -274.881587) (xy 192.337436 -274.871434) (xy 189.740032 -274.871434) (xy 189.739594 -274.881598)
			(xy 189.731803 -274.900373) (xy 189.71742 -274.914738) (xy 189.698634 -274.922506) (xy 189.68847 -274.922996)
			(xy 188.28893 -274.922996) (xy 188.278778 -274.922443) (xy 188.260016 -274.914685) (xy 188.245651 -274.900337)
			(xy 188.237869 -274.881585) (xy 188.237368 -274.871434) (xy 186.2963 -274.871434) (xy 186.295795 -274.881589)
			(xy 186.288017 -274.900352) (xy 186.273655 -274.914715) (xy 186.254893 -274.922495) (xy 186.244738 -274.922996)
			(xy 184.845198 -274.922996) (xy 184.835044 -274.922469) (xy 184.816282 -274.9147) (xy 184.801918 -274.900345)
			(xy 184.794137 -274.881587) (xy 184.793636 -274.871434) (xy 182.196232 -274.871434) (xy 182.195794 -274.881598)
			(xy 182.188003 -274.900373) (xy 182.17362 -274.914738) (xy 182.154834 -274.922506) (xy 182.14467 -274.922996)
			(xy 180.74513 -274.922996) (xy 180.734978 -274.922443) (xy 180.716216 -274.914685) (xy 180.701851 -274.900337)
			(xy 180.694069 -274.881585) (xy 180.693568 -274.871434) (xy 178.7525 -274.871434) (xy 178.751995 -274.881589)
			(xy 178.744217 -274.900352) (xy 178.729855 -274.914715) (xy 178.711093 -274.922495) (xy 178.700938 -274.922996)
			(xy 177.301398 -274.922996) (xy 177.291244 -274.922469) (xy 177.272482 -274.9147) (xy 177.258118 -274.900345)
			(xy 177.250337 -274.881587) (xy 177.249836 -274.871434) (xy 174.652432 -274.871434) (xy 174.651994 -274.881598)
			(xy 174.644203 -274.900373) (xy 174.62982 -274.914738) (xy 174.611034 -274.922506) (xy 174.60087 -274.922996)
			(xy 173.20133 -274.922996) (xy 173.191178 -274.922443) (xy 173.172416 -274.914685) (xy 173.158051 -274.900337)
			(xy 173.150269 -274.881585) (xy 173.149768 -274.871434) (xy 171.2087 -274.871434) (xy 171.208195 -274.881589)
			(xy 171.200417 -274.900352) (xy 171.186055 -274.914715) (xy 171.167293 -274.922495) (xy 171.157138 -274.922996)
			(xy 169.757598 -274.922996) (xy 169.747444 -274.922469) (xy 169.728682 -274.9147) (xy 169.714318 -274.900345)
			(xy 169.706537 -274.881587) (xy 169.706036 -274.871434) (xy 167.108632 -274.871434) (xy 167.108194 -274.881598)
			(xy 167.100403 -274.900373) (xy 167.08602 -274.914738) (xy 167.067234 -274.922506) (xy 167.05707 -274.922996)
			(xy 165.65753 -274.922996) (xy 165.647378 -274.922443) (xy 165.628616 -274.914685) (xy 165.614251 -274.900337)
			(xy 165.606469 -274.881585) (xy 165.605968 -274.871434) (xy 163.6649 -274.871434) (xy 163.664395 -274.881589)
			(xy 163.656617 -274.900352) (xy 163.642255 -274.914715) (xy 163.623493 -274.922495) (xy 163.613338 -274.922996)
			(xy 162.213798 -274.922996) (xy 162.203644 -274.922469) (xy 162.184882 -274.9147) (xy 162.170518 -274.900345)
			(xy 162.162737 -274.881587) (xy 162.162236 -274.871434) (xy 159.564832 -274.871434) (xy 159.564394 -274.881598)
			(xy 159.556603 -274.900373) (xy 159.54222 -274.914738) (xy 159.523434 -274.922506) (xy 159.51327 -274.922996)
			(xy 158.11373 -274.922996) (xy 158.103578 -274.922443) (xy 158.084816 -274.914685) (xy 158.070451 -274.900337)
			(xy 158.062669 -274.881585) (xy 158.062168 -274.871434) (xy 108.245979 -274.871434) (xy 108.272691 -274.9082)
			(xy 108.296214 -274.954367) (xy 108.312226 -275.003646) (xy 108.320332 -275.054823) (xy 108.32084 -275.08073)
			(xy 108.320273 -275.106588) (xy 349.963473 -275.106588) (xy 349.963473 -275.054812) (xy 349.971573 -275.003674)
			(xy 349.987573 -274.954432) (xy 350.011079 -274.9083) (xy 350.041513 -274.866413) (xy 350.078125 -274.829803)
			(xy 350.120014 -274.799371) (xy 350.166147 -274.775867) (xy 350.215389 -274.759869) (xy 350.266528 -274.751772)
			(xy 350.292416 -274.751292) (xy 350.317928 -274.751764) (xy 350.368343 -274.759627) (xy 350.416945 -274.775162)
			(xy 350.462573 -274.797999) (xy 350.504138 -274.827593) (xy 350.540648 -274.863237) (xy 350.556322 -274.883372)
			(xy 350.96831 -274.883372) (xy 350.98397 -274.863226) (xy 351.020483 -274.827584) (xy 351.062052 -274.797992)
			(xy 351.107683 -274.775158) (xy 351.156287 -274.759626) (xy 351.206703 -274.751768) (xy 351.232216 -274.751292)
			(xy 351.258105 -274.751741) (xy 351.309245 -274.759843) (xy 351.358488 -274.775845) (xy 351.404622 -274.799353)
			(xy 351.44651 -274.829789) (xy 351.483122 -274.866402) (xy 351.513555 -274.908292) (xy 351.537061 -274.954427)
			(xy 351.553061 -275.003671) (xy 351.56116 -275.054811) (xy 351.56116 -275.106589) (xy 351.553061 -275.157729)
			(xy 351.537061 -275.206973) (xy 351.513555 -275.253108) (xy 351.483122 -275.294998) (xy 351.44651 -275.331611)
			(xy 351.404622 -275.362047) (xy 351.358488 -275.385555) (xy 351.309245 -275.401557) (xy 351.258105 -275.409659)
			(xy 351.232216 -275.410168) (xy 351.206704 -275.409689) (xy 351.156289 -275.401829) (xy 351.107687 -275.386297)
			(xy 351.062058 -275.363461) (xy 351.020493 -275.333868) (xy 350.983983 -275.298224) (xy 350.96831 -275.278088)
			(xy 350.556322 -275.278088) (xy 350.540633 -275.29821) (xy 350.504126 -275.333856) (xy 350.462565 -275.363451)
			(xy 350.416939 -275.386289) (xy 350.36834 -275.401826) (xy 350.317927 -275.409689) (xy 350.292416 -275.410168)
			(xy 350.266528 -275.409628) (xy 350.215389 -275.401531) (xy 350.166147 -275.385533) (xy 350.120014 -275.362029)
			(xy 350.078125 -275.331597) (xy 350.041513 -275.294987) (xy 350.011079 -275.2531) (xy 349.987573 -275.206968)
			(xy 349.971573 -275.157726) (xy 349.963473 -275.106588) (xy 108.320273 -275.106588) (xy 108.320232 -275.108447)
			(xy 108.310918 -275.163093) (xy 108.302298 -275.189442) (xy 108.294424 -275.21154) (xy 108.499656 -275.566632)
			(xy 108.522516 -275.57095) (xy 108.547321 -275.576185) (xy 108.595097 -275.593131) (xy 108.639715 -275.617194)
			(xy 108.680121 -275.647805) (xy 108.715363 -275.684244) (xy 108.744609 -275.725649) (xy 108.767169 -275.771044)
			(xy 108.782512 -275.819359) (xy 108.790275 -275.869454) (xy 108.79074 -275.8948) (xy 108.790232 -275.920707)
			(xy 108.782126 -275.971884) (xy 108.766114 -276.021163) (xy 108.742591 -276.06733) (xy 108.712135 -276.109249)
			(xy 108.675497 -276.145887) (xy 108.633578 -276.176343) (xy 108.587411 -276.199866) (xy 108.538132 -276.215878)
			(xy 108.486955 -276.223984) (xy 108.435141 -276.223984) (xy 108.383964 -276.215878) (xy 108.334685 -276.199866)
			(xy 108.288518 -276.176343) (xy 108.246599 -276.145887) (xy 108.209961 -276.109249) (xy 108.179505 -276.06733)
			(xy 108.155982 -276.021163) (xy 108.13997 -275.971884) (xy 108.131864 -275.920707) (xy 108.131356 -275.8948)
			(xy 108.131947 -275.867082) (xy 108.141272 -275.812436) (xy 108.149898 -275.786088) (xy 108.157772 -275.76399)
			(xy 107.95254 -275.408898) (xy 107.92968 -275.40458) (xy 107.904858 -275.399414) (xy 107.857077 -275.382462)
			(xy 107.812456 -275.358392) (xy 107.772048 -275.327773) (xy 107.736806 -275.291325) (xy 107.707562 -275.249911)
			(xy 107.685006 -275.204506) (xy 107.66967 -275.156182) (xy 107.661916 -275.10608) (xy 107.661456 -275.08073)
			(xy 105.50144 -275.08073) (xy 105.500998 -275.106094) (xy 105.493245 -275.156227) (xy 105.477898 -275.204578)
			(xy 105.455318 -275.250004) (xy 105.42604 -275.291431) (xy 105.390756 -275.327878) (xy 105.350301 -275.358484)
			(xy 105.305631 -275.382526) (xy 105.257803 -275.399433) (xy 105.232962 -275.40458) (xy 105.209848 -275.408898)
			(xy 105.00487 -275.76399) (xy 105.012744 -275.786088) (xy 105.021303 -275.812447) (xy 105.030503 -275.867092)
			(xy 105.031032 -275.8948) (xy 105.030524 -275.920687) (xy 105.030521 -275.920707) (xy 106.252016 -275.920707)
			(xy 106.252016 -275.868893) (xy 106.260122 -275.817717) (xy 106.276133 -275.768439) (xy 106.299656 -275.722272)
			(xy 106.330111 -275.680353) (xy 106.366749 -275.643715) (xy 106.408667 -275.613259) (xy 106.454833 -275.589735)
			(xy 106.504111 -275.573723) (xy 106.555287 -275.565617) (xy 106.581194 -275.565108) (xy 106.606706 -275.56559)
			(xy 106.65712 -275.57345) (xy 106.705722 -275.588983) (xy 106.75135 -275.611818) (xy 106.792916 -275.64141)
			(xy 106.829426 -275.677053) (xy 106.8451 -275.697188) (xy 107.257088 -275.697188) (xy 107.272765 -275.677056)
			(xy 107.309275 -275.641412) (xy 107.350839 -275.611819) (xy 107.396467 -275.588982) (xy 107.445068 -275.573448)
			(xy 107.495482 -275.565586) (xy 107.520994 -275.565108) (xy 107.546904 -275.565589) (xy 107.598085 -275.573695)
			(xy 107.647369 -275.589707) (xy 107.693541 -275.613232) (xy 107.735464 -275.64369) (xy 107.772106 -275.680332)
			(xy 107.802565 -275.722254) (xy 107.826091 -275.768426) (xy 107.842104 -275.817709) (xy 107.85021 -275.86889)
			(xy 107.85021 -275.92071) (xy 107.842104 -275.971891) (xy 107.826091 -276.021174) (xy 107.802565 -276.067346)
			(xy 107.772106 -276.109268) (xy 107.735464 -276.14591) (xy 107.693541 -276.176368) (xy 107.647369 -276.199893)
			(xy 107.598085 -276.215905) (xy 107.546904 -276.224011) (xy 107.520994 -276.224492) (xy 107.495482 -276.224019)
			(xy 107.445067 -276.216157) (xy 107.396465 -276.200622) (xy 107.350837 -276.177785) (xy 107.309271 -276.148192)
			(xy 107.272762 -276.112547) (xy 107.257088 -276.092412) (xy 106.8451 -276.092412) (xy 106.82943 -276.11255)
			(xy 106.792919 -276.148193) (xy 106.751353 -276.177786) (xy 106.705724 -276.200622) (xy 106.657121 -276.216155)
			(xy 106.606706 -276.224015) (xy 106.581194 -276.224492) (xy 106.555287 -276.223983) (xy 106.504111 -276.215877)
			(xy 106.454833 -276.199865) (xy 106.408667 -276.176341) (xy 106.366749 -276.145885) (xy 106.330111 -276.109247)
			(xy 106.299656 -276.067328) (xy 106.276133 -276.021161) (xy 106.260122 -275.971883) (xy 106.252016 -275.920707)
			(xy 105.030521 -275.920707) (xy 105.022425 -275.971825) (xy 105.006426 -276.021065) (xy 104.98292 -276.067197)
			(xy 104.952488 -276.109084) (xy 104.915878 -276.145694) (xy 104.873991 -276.176126) (xy 104.827859 -276.199632)
			(xy 104.778619 -276.215631) (xy 104.727481 -276.22373) (xy 104.675707 -276.22373) (xy 104.624569 -276.215631)
			(xy 104.575329 -276.199632) (xy 104.529197 -276.176126) (xy 104.48731 -276.145694) (xy 104.4507 -276.109084)
			(xy 104.420268 -276.067197) (xy 104.396762 -276.021065) (xy 104.380763 -275.971825) (xy 104.372664 -275.920687)
			(xy 104.372156 -275.8948) (xy 103.151432 -275.8948) (xy 103.150966 -275.920146) (xy 103.143192 -275.97024)
			(xy 103.127843 -276.018553) (xy 103.105281 -276.063948) (xy 103.076038 -276.105356) (xy 103.040801 -276.1418)
			(xy 103.000402 -276.172421) (xy 102.955792 -276.196499) (xy 102.908023 -276.213466) (xy 102.883208 -276.21865)
			(xy 102.860348 -276.222968) (xy 102.65537 -276.577806) (xy 102.663244 -276.599904) (xy 102.671807 -276.626262)
			(xy 102.681004 -276.680908) (xy 102.681532 -276.708616) (xy 102.962456 -276.708616) (xy 102.962964 -276.682709)
			(xy 102.97107 -276.631532) (xy 102.987082 -276.582253) (xy 103.010605 -276.536086) (xy 103.041061 -276.494167)
			(xy 103.077699 -276.457529) (xy 103.119618 -276.427073) (xy 103.165785 -276.40355) (xy 103.215064 -276.387538)
			(xy 103.266241 -276.379432) (xy 103.318055 -276.379432) (xy 103.369232 -276.387538) (xy 103.418511 -276.40355)
			(xy 103.464678 -276.427073) (xy 103.506597 -276.457529) (xy 103.543235 -276.494167) (xy 103.573691 -276.536086)
			(xy 103.597214 -276.582253) (xy 103.613226 -276.631532) (xy 103.621332 -276.682709) (xy 103.62184 -276.708616)
			(xy 103.621308 -276.734511) (xy 103.902706 -276.734511) (xy 103.902706 -276.682689) (xy 103.910813 -276.631506)
			(xy 103.926828 -276.582222) (xy 103.950356 -276.53605) (xy 103.980818 -276.494128) (xy 104.017464 -276.457487)
			(xy 104.059391 -276.427031) (xy 104.105566 -276.40351) (xy 104.154853 -276.387502) (xy 104.206037 -276.379402)
			(xy 104.231948 -276.378924) (xy 104.257462 -276.37936) (xy 104.307879 -276.387228) (xy 104.356482 -276.40277)
			(xy 104.40211 -276.425614) (xy 104.443674 -276.455215) (xy 104.480182 -276.490865) (xy 104.495854 -276.511004)
			(xy 104.907842 -276.511004) (xy 104.923492 -276.490849) (xy 104.960006 -276.455206) (xy 105.001577 -276.425615)
			(xy 105.04721 -276.402782) (xy 105.095816 -276.387253) (xy 105.146235 -276.379398) (xy 105.171748 -276.378924)
			(xy 105.197654 -276.379404) (xy 105.248828 -276.387515) (xy 105.298102 -276.403532) (xy 105.344265 -276.427059)
			(xy 105.38618 -276.457517) (xy 105.422814 -276.494157) (xy 105.453266 -276.536076) (xy 105.476786 -276.582242)
			(xy 105.492796 -276.631519) (xy 105.5009 -276.682694) (xy 105.5009 -276.734506) (xy 105.492796 -276.785681)
			(xy 105.476786 -276.834958) (xy 105.453266 -276.881124) (xy 105.422814 -276.923043) (xy 105.38618 -276.959683)
			(xy 105.344265 -276.990141) (xy 105.298102 -277.013668) (xy 105.248828 -277.029685) (xy 105.197654 -277.037796)
			(xy 105.171748 -277.038308) (xy 105.146238 -277.037789) (xy 105.095825 -277.029936) (xy 105.047224 -277.01441)
			(xy 105.001596 -276.991582) (xy 104.960029 -276.961996) (xy 104.923517 -276.92636) (xy 104.907842 -276.906228)
			(xy 104.495854 -276.906228) (xy 104.480157 -276.926344) (xy 104.443651 -276.961988) (xy 104.40209 -276.991583)
			(xy 104.356467 -277.014422) (xy 104.307869 -277.029961) (xy 104.257458 -277.037827) (xy 104.231948 -277.038308)
			(xy 104.206037 -277.037798) (xy 104.154853 -277.029698) (xy 104.105566 -277.01369) (xy 104.059391 -276.990169)
			(xy 104.017464 -276.959713) (xy 103.980818 -276.923072) (xy 103.950356 -276.88115) (xy 103.926828 -276.834978)
			(xy 103.910813 -276.785694) (xy 103.902706 -276.734511) (xy 103.621308 -276.734511) (xy 103.621269 -276.736398)
			(xy 103.611945 -276.791174) (xy 103.603298 -276.817582) (xy 103.595424 -276.839426) (xy 103.800402 -277.194264)
			(xy 103.823262 -277.198582) (xy 103.848063 -277.203782) (xy 103.895803 -277.220766) (xy 103.940382 -277.244857)
			(xy 103.98075 -277.275485) (xy 104.015954 -277.311931) (xy 104.045167 -277.353334) (xy 104.067699 -277.398721)
			(xy 104.083021 -277.44702) (xy 104.09077 -277.497096) (xy 104.091232 -277.522432) (xy 106.251756 -277.522432)
			(xy 106.252213 -277.497097) (xy 106.259974 -277.447026) (xy 106.275303 -277.39873) (xy 106.297839 -277.353349)
			(xy 106.327053 -277.311948) (xy 106.362255 -277.275504) (xy 106.402618 -277.244873) (xy 106.447192 -277.220777)
			(xy 106.494926 -277.203783) (xy 106.519726 -277.198582) (xy 106.542586 -277.194264) (xy 106.747818 -276.838918)
			(xy 106.740198 -276.817074) (xy 106.731593 -276.790786) (xy 106.722266 -276.736269) (xy 106.721656 -276.708616)
			(xy 106.722164 -276.682709) (xy 106.73027 -276.631532) (xy 106.746282 -276.582253) (xy 106.769805 -276.536086)
			(xy 106.800261 -276.494167) (xy 106.836899 -276.457529) (xy 106.878818 -276.427073) (xy 106.924985 -276.40355)
			(xy 106.974264 -276.387538) (xy 107.025441 -276.379432) (xy 107.077255 -276.379432) (xy 107.128432 -276.387538)
			(xy 107.177711 -276.40355) (xy 107.223878 -276.427073) (xy 107.265797 -276.457529) (xy 107.302435 -276.494167)
			(xy 107.332891 -276.536086) (xy 107.356414 -276.582253) (xy 107.372426 -276.631532) (xy 107.380532 -276.682709)
			(xy 107.38104 -276.708616) (xy 108.601256 -276.708616) (xy 108.601789 -276.683284) (xy 108.609538 -276.633215)
			(xy 108.624856 -276.584922) (xy 108.647381 -276.53954) (xy 108.676585 -276.498139) (xy 108.711779 -276.461694)
			(xy 108.752134 -276.431062) (xy 108.796701 -276.406964) (xy 108.844429 -276.389968) (xy 108.869226 -276.384766)
			(xy 108.892086 -276.380448) (xy 109.097064 -276.02561) (xy 109.08919 -276.003766) (xy 109.080545 -275.977358)
			(xy 109.071224 -275.922582) (xy 109.070648 -275.8948) (xy 109.071156 -275.868893) (xy 109.079262 -275.817716)
			(xy 109.095274 -275.768437) (xy 109.118797 -275.72227) (xy 109.149253 -275.680351) (xy 109.185891 -275.643713)
			(xy 109.22781 -275.613257) (xy 109.273977 -275.589734) (xy 109.323256 -275.573722) (xy 109.374433 -275.565616)
			(xy 109.426247 -275.565616) (xy 109.477424 -275.573722) (xy 109.526703 -275.589734) (xy 109.57287 -275.613257)
			(xy 109.614789 -275.643713) (xy 109.651427 -275.680351) (xy 109.681191 -275.721318) (xy 158.062168 -275.721318)
			(xy 158.062168 -275.312378) (xy 158.062547 -275.302201) (xy 158.070345 -275.2834) (xy 158.084744 -275.269015)
			(xy 158.103553 -275.261237) (xy 158.11373 -275.260816) (xy 159.51327 -275.260816) (xy 159.523437 -275.261288)
			(xy 159.542227 -275.269059) (xy 159.556612 -275.28343) (xy 159.564402 -275.302212) (xy 159.564832 -275.312378)
			(xy 159.564832 -275.721318) (xy 165.605968 -275.721318) (xy 165.605968 -275.312378) (xy 165.606347 -275.302201)
			(xy 165.614145 -275.2834) (xy 165.628544 -275.269015) (xy 165.647353 -275.261237) (xy 165.65753 -275.260816)
			(xy 167.05707 -275.260816) (xy 167.067237 -275.261288) (xy 167.086027 -275.269059) (xy 167.100412 -275.28343)
			(xy 167.108202 -275.302212) (xy 167.108632 -275.312378) (xy 167.108632 -275.721318) (xy 173.149768 -275.721318)
			(xy 173.149768 -275.312378) (xy 173.150147 -275.302201) (xy 173.157945 -275.2834) (xy 173.172344 -275.269015)
			(xy 173.191153 -275.261237) (xy 173.20133 -275.260816) (xy 174.60087 -275.260816) (xy 174.611037 -275.261288)
			(xy 174.629827 -275.269059) (xy 174.644212 -275.28343) (xy 174.652002 -275.302212) (xy 174.652432 -275.312378)
			(xy 174.652432 -275.721318) (xy 180.693568 -275.721318) (xy 180.693568 -275.312378) (xy 180.693947 -275.302201)
			(xy 180.701745 -275.2834) (xy 180.716144 -275.269015) (xy 180.734953 -275.261237) (xy 180.74513 -275.260816)
			(xy 182.14467 -275.260816) (xy 182.154837 -275.261288) (xy 182.173627 -275.269059) (xy 182.188012 -275.28343)
			(xy 182.195802 -275.302212) (xy 182.196232 -275.312378) (xy 182.196232 -275.721318) (xy 188.237368 -275.721318)
			(xy 188.237368 -275.312378) (xy 188.237747 -275.302201) (xy 188.245545 -275.2834) (xy 188.259944 -275.269015)
			(xy 188.278753 -275.261237) (xy 188.28893 -275.260816) (xy 189.68847 -275.260816) (xy 189.698637 -275.261288)
			(xy 189.717427 -275.269059) (xy 189.731812 -275.28343) (xy 189.739602 -275.302212) (xy 189.740032 -275.312378)
			(xy 189.740032 -275.721318) (xy 195.781168 -275.721318) (xy 195.781168 -275.312378) (xy 195.781547 -275.302201)
			(xy 195.789345 -275.2834) (xy 195.803744 -275.269015) (xy 195.822553 -275.261237) (xy 195.83273 -275.260816)
			(xy 197.23227 -275.260816) (xy 197.242437 -275.261288) (xy 197.261227 -275.269059) (xy 197.275612 -275.28343)
			(xy 197.283402 -275.302212) (xy 197.283832 -275.312378) (xy 197.283832 -275.721318) (xy 203.324968 -275.721318)
			(xy 203.324968 -275.312378) (xy 203.325347 -275.302201) (xy 203.333145 -275.2834) (xy 203.347544 -275.269015)
			(xy 203.366353 -275.261237) (xy 203.37653 -275.260816) (xy 204.77607 -275.260816) (xy 204.786237 -275.261288)
			(xy 204.805027 -275.269059) (xy 204.819412 -275.28343) (xy 204.827202 -275.302212) (xy 204.827632 -275.312378)
			(xy 204.827632 -275.721318) (xy 210.868768 -275.721318) (xy 210.868768 -275.312378) (xy 210.869147 -275.302201)
			(xy 210.876945 -275.2834) (xy 210.891344 -275.269015) (xy 210.910153 -275.261237) (xy 210.92033 -275.260816)
			(xy 212.31987 -275.260816) (xy 212.330037 -275.261288) (xy 212.348827 -275.269059) (xy 212.363212 -275.28343)
			(xy 212.371002 -275.302212) (xy 212.371432 -275.312378) (xy 212.371432 -275.721318) (xy 255.329436 -275.721318)
			(xy 255.329436 -275.312378) (xy 255.329915 -275.302219) (xy 255.337696 -275.28345) (xy 255.352067 -275.269085)
			(xy 255.370839 -275.261311) (xy 255.380998 -275.260816) (xy 256.780538 -275.260816) (xy 256.790695 -275.261302)
			(xy 256.809461 -275.269085) (xy 256.823824 -275.283452) (xy 256.831601 -275.30222) (xy 256.8321 -275.312378)
			(xy 256.8321 -275.721318) (xy 262.873236 -275.721318) (xy 262.873236 -275.312378) (xy 262.873715 -275.302219)
			(xy 262.881496 -275.28345) (xy 262.895867 -275.269085) (xy 262.914639 -275.261311) (xy 262.924798 -275.260816)
			(xy 264.324338 -275.260816) (xy 264.334495 -275.261302) (xy 264.353261 -275.269085) (xy 264.367624 -275.283452)
			(xy 264.375401 -275.30222) (xy 264.3759 -275.312378) (xy 264.3759 -275.721318) (xy 270.417036 -275.721318)
			(xy 270.417036 -275.312378) (xy 270.417515 -275.302219) (xy 270.425296 -275.28345) (xy 270.439667 -275.269085)
			(xy 270.458439 -275.261311) (xy 270.468598 -275.260816) (xy 271.868138 -275.260816) (xy 271.878295 -275.261302)
			(xy 271.897061 -275.269085) (xy 271.911424 -275.283452) (xy 271.919201 -275.30222) (xy 271.9197 -275.312378)
			(xy 271.9197 -275.721318) (xy 277.960836 -275.721318) (xy 277.960836 -275.312378) (xy 277.961315 -275.302219)
			(xy 277.969096 -275.28345) (xy 277.983467 -275.269085) (xy 278.002239 -275.261311) (xy 278.012398 -275.260816)
			(xy 279.411938 -275.260816) (xy 279.422095 -275.261302) (xy 279.440861 -275.269085) (xy 279.455224 -275.283452)
			(xy 279.463001 -275.30222) (xy 279.4635 -275.312378) (xy 279.4635 -275.721318) (xy 285.504636 -275.721318)
			(xy 285.504636 -275.312378) (xy 285.505115 -275.302219) (xy 285.512896 -275.28345) (xy 285.527267 -275.269085)
			(xy 285.546039 -275.261311) (xy 285.556198 -275.260816) (xy 286.955738 -275.260816) (xy 286.965895 -275.261302)
			(xy 286.984661 -275.269085) (xy 286.999024 -275.283452) (xy 287.006801 -275.30222) (xy 287.0073 -275.312378)
			(xy 287.0073 -275.721318) (xy 293.048436 -275.721318) (xy 293.048436 -275.312378) (xy 293.048915 -275.302219)
			(xy 293.056696 -275.28345) (xy 293.071067 -275.269085) (xy 293.089839 -275.261311) (xy 293.099998 -275.260816)
			(xy 294.499538 -275.260816) (xy 294.509695 -275.261302) (xy 294.528461 -275.269085) (xy 294.542824 -275.283452)
			(xy 294.550601 -275.30222) (xy 294.5511 -275.312378) (xy 294.5511 -275.721318) (xy 300.592236 -275.721318)
			(xy 300.592236 -275.312378) (xy 300.592715 -275.302219) (xy 300.600496 -275.28345) (xy 300.614867 -275.269085)
			(xy 300.633639 -275.261311) (xy 300.643798 -275.260816) (xy 302.043338 -275.260816) (xy 302.053495 -275.261302)
			(xy 302.072261 -275.269085) (xy 302.086624 -275.283452) (xy 302.094401 -275.30222) (xy 302.0949 -275.312378)
			(xy 302.0949 -275.721318) (xy 308.136036 -275.721318) (xy 308.136036 -275.312378) (xy 308.136515 -275.302219)
			(xy 308.144296 -275.28345) (xy 308.158667 -275.269085) (xy 308.177439 -275.261311) (xy 308.187598 -275.260816)
			(xy 309.587138 -275.260816) (xy 309.597295 -275.261302) (xy 309.616061 -275.269085) (xy 309.630424 -275.283452)
			(xy 309.638201 -275.30222) (xy 309.6387 -275.312378) (xy 309.6387 -275.721318) (xy 309.638183 -275.731472)
			(xy 309.630409 -275.750235) (xy 309.616051 -275.764598) (xy 309.597292 -275.772379) (xy 309.587138 -275.77288)
			(xy 308.187598 -275.77288) (xy 308.177442 -275.772369) (xy 308.158677 -275.764597) (xy 308.144312 -275.750237)
			(xy 308.136535 -275.731474) (xy 308.136036 -275.721318) (xy 302.0949 -275.721318) (xy 302.094383 -275.731472)
			(xy 302.086609 -275.750235) (xy 302.072251 -275.764598) (xy 302.053492 -275.772379) (xy 302.043338 -275.77288)
			(xy 300.643798 -275.77288) (xy 300.633642 -275.772369) (xy 300.614877 -275.764597) (xy 300.600512 -275.750237)
			(xy 300.592735 -275.731474) (xy 300.592236 -275.721318) (xy 294.5511 -275.721318) (xy 294.550583 -275.731472)
			(xy 294.542809 -275.750235) (xy 294.528451 -275.764598) (xy 294.509692 -275.772379) (xy 294.499538 -275.77288)
			(xy 293.099998 -275.77288) (xy 293.089842 -275.772369) (xy 293.071077 -275.764597) (xy 293.056712 -275.750237)
			(xy 293.048935 -275.731474) (xy 293.048436 -275.721318) (xy 287.0073 -275.721318) (xy 287.006783 -275.731472)
			(xy 286.999009 -275.750235) (xy 286.984651 -275.764598) (xy 286.965892 -275.772379) (xy 286.955738 -275.77288)
			(xy 285.556198 -275.77288) (xy 285.546042 -275.772369) (xy 285.527277 -275.764597) (xy 285.512912 -275.750237)
			(xy 285.505135 -275.731474) (xy 285.504636 -275.721318) (xy 279.4635 -275.721318) (xy 279.462983 -275.731472)
			(xy 279.455209 -275.750235) (xy 279.440851 -275.764598) (xy 279.422092 -275.772379) (xy 279.411938 -275.77288)
			(xy 278.012398 -275.77288) (xy 278.002242 -275.772369) (xy 277.983477 -275.764597) (xy 277.969112 -275.750237)
			(xy 277.961335 -275.731474) (xy 277.960836 -275.721318) (xy 271.9197 -275.721318) (xy 271.919183 -275.731472)
			(xy 271.911409 -275.750235) (xy 271.897051 -275.764598) (xy 271.878292 -275.772379) (xy 271.868138 -275.77288)
			(xy 270.468598 -275.77288) (xy 270.458442 -275.772369) (xy 270.439677 -275.764597) (xy 270.425312 -275.750237)
			(xy 270.417535 -275.731474) (xy 270.417036 -275.721318) (xy 264.3759 -275.721318) (xy 264.375383 -275.731472)
			(xy 264.367609 -275.750235) (xy 264.353251 -275.764598) (xy 264.334492 -275.772379) (xy 264.324338 -275.77288)
			(xy 262.924798 -275.77288) (xy 262.914642 -275.772369) (xy 262.895877 -275.764597) (xy 262.881512 -275.750237)
			(xy 262.873735 -275.731474) (xy 262.873236 -275.721318) (xy 256.8321 -275.721318) (xy 256.831583 -275.731472)
			(xy 256.823809 -275.750235) (xy 256.809451 -275.764598) (xy 256.790692 -275.772379) (xy 256.780538 -275.77288)
			(xy 255.380998 -275.77288) (xy 255.370842 -275.772369) (xy 255.352077 -275.764597) (xy 255.337712 -275.750237)
			(xy 255.329935 -275.731474) (xy 255.329436 -275.721318) (xy 212.371432 -275.721318) (xy 212.37105 -275.731494)
			(xy 212.363253 -275.750295) (xy 212.348855 -275.76468) (xy 212.330047 -275.772459) (xy 212.31987 -275.77288)
			(xy 210.92033 -275.77288) (xy 210.910163 -275.772412) (xy 210.891372 -275.76464) (xy 210.876987 -275.750268)
			(xy 210.869198 -275.731485) (xy 210.868768 -275.721318) (xy 204.827632 -275.721318) (xy 204.82725 -275.731494)
			(xy 204.819453 -275.750295) (xy 204.805055 -275.76468) (xy 204.786247 -275.772459) (xy 204.77607 -275.77288)
			(xy 203.37653 -275.77288) (xy 203.366363 -275.772412) (xy 203.347572 -275.76464) (xy 203.333187 -275.750268)
			(xy 203.325398 -275.731485) (xy 203.324968 -275.721318) (xy 197.283832 -275.721318) (xy 197.28345 -275.731494)
			(xy 197.275653 -275.750295) (xy 197.261255 -275.76468) (xy 197.242447 -275.772459) (xy 197.23227 -275.77288)
			(xy 195.83273 -275.77288) (xy 195.822563 -275.772412) (xy 195.803772 -275.76464) (xy 195.789387 -275.750268)
			(xy 195.781598 -275.731485) (xy 195.781168 -275.721318) (xy 189.740032 -275.721318) (xy 189.73965 -275.731494)
			(xy 189.731853 -275.750295) (xy 189.717455 -275.76468) (xy 189.698647 -275.772459) (xy 189.68847 -275.77288)
			(xy 188.28893 -275.77288) (xy 188.278763 -275.772412) (xy 188.259972 -275.76464) (xy 188.245587 -275.750268)
			(xy 188.237798 -275.731485) (xy 188.237368 -275.721318) (xy 182.196232 -275.721318) (xy 182.19585 -275.731494)
			(xy 182.188053 -275.750295) (xy 182.173655 -275.76468) (xy 182.154847 -275.772459) (xy 182.14467 -275.77288)
			(xy 180.74513 -275.77288) (xy 180.734963 -275.772412) (xy 180.716172 -275.76464) (xy 180.701787 -275.750268)
			(xy 180.693998 -275.731485) (xy 180.693568 -275.721318) (xy 174.652432 -275.721318) (xy 174.65205 -275.731494)
			(xy 174.644253 -275.750295) (xy 174.629855 -275.76468) (xy 174.611047 -275.772459) (xy 174.60087 -275.77288)
			(xy 173.20133 -275.77288) (xy 173.191163 -275.772412) (xy 173.172372 -275.76464) (xy 173.157987 -275.750268)
			(xy 173.150198 -275.731485) (xy 173.149768 -275.721318) (xy 167.108632 -275.721318) (xy 167.10825 -275.731494)
			(xy 167.100453 -275.750295) (xy 167.086055 -275.76468) (xy 167.067247 -275.772459) (xy 167.05707 -275.77288)
			(xy 165.65753 -275.77288) (xy 165.647363 -275.772412) (xy 165.628572 -275.76464) (xy 165.614187 -275.750268)
			(xy 165.606398 -275.731485) (xy 165.605968 -275.721318) (xy 159.564832 -275.721318) (xy 159.56445 -275.731494)
			(xy 159.556653 -275.750295) (xy 159.542255 -275.76468) (xy 159.523447 -275.772459) (xy 159.51327 -275.77288)
			(xy 158.11373 -275.77288) (xy 158.103563 -275.772412) (xy 158.084772 -275.76464) (xy 158.070387 -275.750268)
			(xy 158.062598 -275.731485) (xy 158.062168 -275.721318) (xy 109.681191 -275.721318) (xy 109.681883 -275.72227)
			(xy 109.705406 -275.768437) (xy 109.721418 -275.817716) (xy 109.729524 -275.868893) (xy 109.730032 -275.8948)
			(xy 109.729566 -275.920146) (xy 109.721792 -275.97024) (xy 109.706443 -276.018553) (xy 109.683881 -276.063948)
			(xy 109.654638 -276.105356) (xy 109.619401 -276.1418) (xy 109.579002 -276.172421) (xy 109.534392 -276.196499)
			(xy 109.486623 -276.213466) (xy 109.461808 -276.21865) (xy 109.438948 -276.222968) (xy 109.237638 -276.571456)
			(xy 162.162236 -276.571456) (xy 162.162236 -276.162516) (xy 162.162635 -276.152358) (xy 162.170432 -276.133599)
			(xy 162.184837 -276.119274) (xy 162.203638 -276.11158) (xy 162.213798 -276.111208) (xy 163.613338 -276.111208)
			(xy 163.623463 -276.111694) (xy 163.642179 -276.119429) (xy 163.656533 -276.133714) (xy 163.664356 -276.152393)
			(xy 163.6649 -276.162516) (xy 163.6649 -276.571456) (xy 169.706036 -276.571456) (xy 169.706036 -276.162516)
			(xy 169.706435 -276.152358) (xy 169.714232 -276.133599) (xy 169.728637 -276.119274) (xy 169.747438 -276.11158)
			(xy 169.757598 -276.111208) (xy 171.157138 -276.111208) (xy 171.167263 -276.111694) (xy 171.185979 -276.119429)
			(xy 171.200333 -276.133714) (xy 171.208156 -276.152393) (xy 171.2087 -276.162516) (xy 171.2087 -276.571456)
			(xy 177.249836 -276.571456) (xy 177.249836 -276.162516) (xy 177.250235 -276.152358) (xy 177.258032 -276.133599)
			(xy 177.272437 -276.119274) (xy 177.291238 -276.11158) (xy 177.301398 -276.111208) (xy 178.700938 -276.111208)
			(xy 178.711063 -276.111694) (xy 178.729779 -276.119429) (xy 178.744133 -276.133714) (xy 178.751956 -276.152393)
			(xy 178.7525 -276.162516) (xy 178.7525 -276.571456) (xy 184.793636 -276.571456) (xy 184.793636 -276.162516)
			(xy 184.794035 -276.152358) (xy 184.801832 -276.133599) (xy 184.816237 -276.119274) (xy 184.835038 -276.11158)
			(xy 184.845198 -276.111208) (xy 186.244738 -276.111208) (xy 186.254863 -276.111694) (xy 186.273579 -276.119429)
			(xy 186.287933 -276.133714) (xy 186.295756 -276.152393) (xy 186.2963 -276.162516) (xy 186.2963 -276.571456)
			(xy 192.337436 -276.571456) (xy 192.337436 -276.162516) (xy 192.337835 -276.152358) (xy 192.345632 -276.133599)
			(xy 192.360037 -276.119274) (xy 192.378838 -276.11158) (xy 192.388998 -276.111208) (xy 193.788538 -276.111208)
			(xy 193.798663 -276.111694) (xy 193.817379 -276.119429) (xy 193.831733 -276.133714) (xy 193.839556 -276.152393)
			(xy 193.8401 -276.162516) (xy 193.8401 -276.571456) (xy 199.881236 -276.571456) (xy 199.881236 -276.162516)
			(xy 199.881635 -276.152358) (xy 199.889432 -276.133599) (xy 199.903837 -276.119274) (xy 199.922638 -276.11158)
			(xy 199.932798 -276.111208) (xy 201.332338 -276.111208) (xy 201.342463 -276.111694) (xy 201.361179 -276.119429)
			(xy 201.375533 -276.133714) (xy 201.383356 -276.152393) (xy 201.3839 -276.162516) (xy 201.3839 -276.571456)
			(xy 207.425036 -276.571456) (xy 207.425036 -276.162516) (xy 207.425435 -276.152358) (xy 207.433232 -276.133599)
			(xy 207.447637 -276.119274) (xy 207.466438 -276.11158) (xy 207.476598 -276.111208) (xy 208.876138 -276.111208)
			(xy 208.886263 -276.111694) (xy 208.904979 -276.119429) (xy 208.919333 -276.133714) (xy 208.927156 -276.152393)
			(xy 208.9277 -276.162516) (xy 208.9277 -276.571456) (xy 214.968836 -276.571456) (xy 214.968836 -276.162516)
			(xy 214.969235 -276.152358) (xy 214.977032 -276.133599) (xy 214.991437 -276.119274) (xy 215.010238 -276.11158)
			(xy 215.020398 -276.111208) (xy 216.419938 -276.111208) (xy 216.430063 -276.111694) (xy 216.448779 -276.119429)
			(xy 216.463133 -276.133714) (xy 216.470956 -276.152393) (xy 216.4715 -276.162516) (xy 216.4715 -276.571456)
			(xy 259.429504 -276.571456) (xy 259.429504 -276.162516) (xy 259.429935 -276.152362) (xy 259.437726 -276.13361)
			(xy 259.45212 -276.119285) (xy 259.47091 -276.111586) (xy 259.481066 -276.111208) (xy 260.880606 -276.111208)
			(xy 260.890729 -276.111721) (xy 260.909444 -276.119445) (xy 260.923799 -276.133722) (xy 260.931624 -276.152396)
			(xy 260.932168 -276.162516) (xy 260.932168 -276.571456) (xy 266.973304 -276.571456) (xy 266.973304 -276.162516)
			(xy 266.973735 -276.152362) (xy 266.981526 -276.13361) (xy 266.99592 -276.119285) (xy 267.01471 -276.111586)
			(xy 267.024866 -276.111208) (xy 268.424406 -276.111208) (xy 268.434529 -276.111721) (xy 268.453244 -276.119445)
			(xy 268.467599 -276.133722) (xy 268.475424 -276.152396) (xy 268.475968 -276.162516) (xy 268.475968 -276.571456)
			(xy 274.517104 -276.571456) (xy 274.517104 -276.162516) (xy 274.517535 -276.152362) (xy 274.525326 -276.13361)
			(xy 274.53972 -276.119285) (xy 274.55851 -276.111586) (xy 274.568666 -276.111208) (xy 275.968206 -276.111208)
			(xy 275.978329 -276.111721) (xy 275.997044 -276.119445) (xy 276.011399 -276.133722) (xy 276.019224 -276.152396)
			(xy 276.019768 -276.162516) (xy 276.019768 -276.571456) (xy 282.060904 -276.571456) (xy 282.060904 -276.162516)
			(xy 282.061335 -276.152362) (xy 282.069126 -276.13361) (xy 282.08352 -276.119285) (xy 282.10231 -276.111586)
			(xy 282.112466 -276.111208) (xy 283.512006 -276.111208) (xy 283.522129 -276.111721) (xy 283.540844 -276.119445)
			(xy 283.555199 -276.133722) (xy 283.563024 -276.152396) (xy 283.563568 -276.162516) (xy 283.563568 -276.571456)
			(xy 289.604704 -276.571456) (xy 289.604704 -276.162516) (xy 289.605135 -276.152362) (xy 289.612926 -276.13361)
			(xy 289.62732 -276.119285) (xy 289.64611 -276.111586) (xy 289.656266 -276.111208) (xy 291.055806 -276.111208)
			(xy 291.065929 -276.111721) (xy 291.084644 -276.119445) (xy 291.098999 -276.133722) (xy 291.106824 -276.152396)
			(xy 291.107368 -276.162516) (xy 291.107368 -276.571456) (xy 297.148504 -276.571456) (xy 297.148504 -276.162516)
			(xy 297.148935 -276.152362) (xy 297.156726 -276.13361) (xy 297.17112 -276.119285) (xy 297.18991 -276.111586)
			(xy 297.200066 -276.111208) (xy 298.599606 -276.111208) (xy 298.609729 -276.111721) (xy 298.628444 -276.119445)
			(xy 298.642799 -276.133722) (xy 298.650624 -276.152396) (xy 298.651168 -276.162516) (xy 298.651168 -276.571456)
			(xy 304.692304 -276.571456) (xy 304.692304 -276.162516) (xy 304.692735 -276.152362) (xy 304.700526 -276.13361)
			(xy 304.71492 -276.119285) (xy 304.73371 -276.111586) (xy 304.743866 -276.111208) (xy 306.143406 -276.111208)
			(xy 306.153529 -276.111721) (xy 306.172244 -276.119445) (xy 306.186599 -276.133722) (xy 306.194424 -276.152396)
			(xy 306.194968 -276.162516) (xy 306.194968 -276.571456) (xy 312.236104 -276.571456) (xy 312.236104 -276.162516)
			(xy 312.236535 -276.152362) (xy 312.244326 -276.13361) (xy 312.25872 -276.119285) (xy 312.27751 -276.111586)
			(xy 312.287666 -276.111208) (xy 313.687206 -276.111208) (xy 313.697329 -276.111721) (xy 313.716044 -276.119445)
			(xy 313.730399 -276.133722) (xy 313.738224 -276.152396) (xy 313.738768 -276.162516) (xy 313.738768 -276.571456)
			(xy 313.738342 -276.581611) (xy 313.730555 -276.600369) (xy 313.716159 -276.614695) (xy 313.697363 -276.62239)
			(xy 313.687206 -276.622764) (xy 312.287666 -276.622764) (xy 312.277538 -276.622301) (xy 312.258816 -276.614563)
			(xy 312.244461 -276.60027) (xy 312.236643 -276.581582) (xy 312.236104 -276.571456) (xy 306.194968 -276.571456)
			(xy 306.194542 -276.581611) (xy 306.186755 -276.600369) (xy 306.172359 -276.614695) (xy 306.153563 -276.62239)
			(xy 306.143406 -276.622764) (xy 304.743866 -276.622764) (xy 304.733738 -276.622301) (xy 304.715016 -276.614563)
			(xy 304.700661 -276.60027) (xy 304.692843 -276.581582) (xy 304.692304 -276.571456) (xy 298.651168 -276.571456)
			(xy 298.650742 -276.581611) (xy 298.642955 -276.600369) (xy 298.628559 -276.614695) (xy 298.609763 -276.62239)
			(xy 298.599606 -276.622764) (xy 297.200066 -276.622764) (xy 297.189938 -276.622301) (xy 297.171216 -276.614563)
			(xy 297.156861 -276.60027) (xy 297.149043 -276.581582) (xy 297.148504 -276.571456) (xy 291.107368 -276.571456)
			(xy 291.106942 -276.581611) (xy 291.099155 -276.600369) (xy 291.084759 -276.614695) (xy 291.065963 -276.62239)
			(xy 291.055806 -276.622764) (xy 289.656266 -276.622764) (xy 289.646138 -276.622301) (xy 289.627416 -276.614563)
			(xy 289.613061 -276.60027) (xy 289.605243 -276.581582) (xy 289.604704 -276.571456) (xy 283.563568 -276.571456)
			(xy 283.563142 -276.581611) (xy 283.555355 -276.600369) (xy 283.540959 -276.614695) (xy 283.522163 -276.62239)
			(xy 283.512006 -276.622764) (xy 282.112466 -276.622764) (xy 282.102338 -276.622301) (xy 282.083616 -276.614563)
			(xy 282.069261 -276.60027) (xy 282.061443 -276.581582) (xy 282.060904 -276.571456) (xy 276.019768 -276.571456)
			(xy 276.019342 -276.581611) (xy 276.011555 -276.600369) (xy 275.997159 -276.614695) (xy 275.978363 -276.62239)
			(xy 275.968206 -276.622764) (xy 274.568666 -276.622764) (xy 274.558538 -276.622301) (xy 274.539816 -276.614563)
			(xy 274.525461 -276.60027) (xy 274.517643 -276.581582) (xy 274.517104 -276.571456) (xy 268.475968 -276.571456)
			(xy 268.475542 -276.581611) (xy 268.467755 -276.600369) (xy 268.453359 -276.614695) (xy 268.434563 -276.62239)
			(xy 268.424406 -276.622764) (xy 267.024866 -276.622764) (xy 267.014738 -276.622301) (xy 266.996016 -276.614563)
			(xy 266.981661 -276.60027) (xy 266.973843 -276.581582) (xy 266.973304 -276.571456) (xy 260.932168 -276.571456)
			(xy 260.931742 -276.581611) (xy 260.923955 -276.600369) (xy 260.909559 -276.614695) (xy 260.890763 -276.62239)
			(xy 260.880606 -276.622764) (xy 259.481066 -276.622764) (xy 259.470938 -276.622301) (xy 259.452216 -276.614563)
			(xy 259.437861 -276.60027) (xy 259.430043 -276.581582) (xy 259.429504 -276.571456) (xy 216.4715 -276.571456)
			(xy 216.471042 -276.581607) (xy 216.463261 -276.600359) (xy 216.448875 -276.614684) (xy 216.430091 -276.622385)
			(xy 216.419938 -276.622764) (xy 215.020398 -276.622764) (xy 215.010272 -276.622275) (xy 214.991551 -276.614547)
			(xy 214.977195 -276.600262) (xy 214.969375 -276.58158) (xy 214.968836 -276.571456) (xy 208.9277 -276.571456)
			(xy 208.927242 -276.581607) (xy 208.919461 -276.600359) (xy 208.905075 -276.614684) (xy 208.886291 -276.622385)
			(xy 208.876138 -276.622764) (xy 207.476598 -276.622764) (xy 207.466472 -276.622275) (xy 207.447751 -276.614547)
			(xy 207.433395 -276.600262) (xy 207.425575 -276.58158) (xy 207.425036 -276.571456) (xy 201.3839 -276.571456)
			(xy 201.383442 -276.581607) (xy 201.375661 -276.600359) (xy 201.361275 -276.614684) (xy 201.342491 -276.622385)
			(xy 201.332338 -276.622764) (xy 199.932798 -276.622764) (xy 199.922672 -276.622275) (xy 199.903951 -276.614547)
			(xy 199.889595 -276.600262) (xy 199.881775 -276.58158) (xy 199.881236 -276.571456) (xy 193.8401 -276.571456)
			(xy 193.839642 -276.581607) (xy 193.831861 -276.600359) (xy 193.817475 -276.614684) (xy 193.798691 -276.622385)
			(xy 193.788538 -276.622764) (xy 192.388998 -276.622764) (xy 192.378872 -276.622275) (xy 192.360151 -276.614547)
			(xy 192.345795 -276.600262) (xy 192.337975 -276.58158) (xy 192.337436 -276.571456) (xy 186.2963 -276.571456)
			(xy 186.295842 -276.581607) (xy 186.288061 -276.600359) (xy 186.273675 -276.614684) (xy 186.254891 -276.622385)
			(xy 186.244738 -276.622764) (xy 184.845198 -276.622764) (xy 184.835072 -276.622275) (xy 184.816351 -276.614547)
			(xy 184.801995 -276.600262) (xy 184.794175 -276.58158) (xy 184.793636 -276.571456) (xy 178.7525 -276.571456)
			(xy 178.752042 -276.581607) (xy 178.744261 -276.600359) (xy 178.729875 -276.614684) (xy 178.711091 -276.622385)
			(xy 178.700938 -276.622764) (xy 177.301398 -276.622764) (xy 177.291272 -276.622275) (xy 177.272551 -276.614547)
			(xy 177.258195 -276.600262) (xy 177.250375 -276.58158) (xy 177.249836 -276.571456) (xy 171.2087 -276.571456)
			(xy 171.208242 -276.581607) (xy 171.200461 -276.600359) (xy 171.186075 -276.614684) (xy 171.167291 -276.622385)
			(xy 171.157138 -276.622764) (xy 169.757598 -276.622764) (xy 169.747472 -276.622275) (xy 169.728751 -276.614547)
			(xy 169.714395 -276.600262) (xy 169.706575 -276.58158) (xy 169.706036 -276.571456) (xy 163.6649 -276.571456)
			(xy 163.664442 -276.581607) (xy 163.656661 -276.600359) (xy 163.642275 -276.614684) (xy 163.623491 -276.622385)
			(xy 163.613338 -276.622764) (xy 162.213798 -276.622764) (xy 162.203672 -276.622275) (xy 162.184951 -276.614547)
			(xy 162.170595 -276.600262) (xy 162.162775 -276.58158) (xy 162.162236 -276.571456) (xy 109.237638 -276.571456)
			(xy 109.23397 -276.577806) (xy 109.241844 -276.599904) (xy 109.250407 -276.626262) (xy 109.259604 -276.680908)
			(xy 109.260132 -276.708616) (xy 349.962724 -276.708616) (xy 349.963202 -276.683281) (xy 349.970953 -276.633207)
			(xy 349.986274 -276.584909) (xy 350.008806 -276.539525) (xy 350.038016 -276.498122) (xy 350.073218 -276.461676)
			(xy 350.113581 -276.431046) (xy 350.158157 -276.406953) (xy 350.205894 -276.389964) (xy 350.230694 -276.384766)
			(xy 350.253554 -276.380448) (xy 350.458532 -276.025356) (xy 350.450912 -276.003512) (xy 350.442352 -275.977154)
			(xy 350.433153 -275.922508) (xy 350.432624 -275.8948) (xy 350.433132 -275.868913) (xy 350.441231 -275.817775)
			(xy 350.45723 -275.768535) (xy 350.480736 -275.722403) (xy 350.511168 -275.680516) (xy 350.547778 -275.643906)
			(xy 350.589665 -275.613474) (xy 350.635797 -275.589968) (xy 350.685037 -275.573969) (xy 350.736175 -275.56587)
			(xy 350.787949 -275.56587) (xy 350.839087 -275.573969) (xy 350.888327 -275.589968) (xy 350.934459 -275.613474)
			(xy 350.976346 -275.643906) (xy 351.012956 -275.680516) (xy 351.043388 -275.722403) (xy 351.066894 -275.768535)
			(xy 351.082893 -275.817775) (xy 351.090992 -275.868913) (xy 351.0915 -275.8948) (xy 352.312224 -275.8948)
			(xy 352.312688 -275.869465) (xy 352.320441 -275.81939) (xy 352.335764 -275.771092) (xy 352.358298 -275.725707)
			(xy 352.38751 -275.684304) (xy 352.422713 -275.647859) (xy 352.463078 -275.617229) (xy 352.507655 -275.593136)
			(xy 352.555393 -275.576148) (xy 352.580194 -275.57095) (xy 352.603054 -275.566632) (xy 352.808286 -275.211286)
			(xy 352.800666 -275.189188) (xy 352.792042 -275.162906) (xy 352.782727 -275.108385) (xy 352.782124 -275.08073)
			(xy 352.782632 -275.054823) (xy 352.790738 -275.003646) (xy 352.80675 -274.954367) (xy 352.830273 -274.9082)
			(xy 352.860729 -274.866281) (xy 352.897367 -274.829643) (xy 352.939286 -274.799187) (xy 352.985453 -274.775664)
			(xy 353.034732 -274.759652) (xy 353.085909 -274.751546) (xy 353.137723 -274.751546) (xy 353.1889 -274.759652)
			(xy 353.238179 -274.775664) (xy 353.284346 -274.799187) (xy 353.326265 -274.829643) (xy 353.362903 -274.866281)
			(xy 353.393359 -274.9082) (xy 353.416882 -274.954367) (xy 353.432894 -275.003646) (xy 353.441 -275.054823)
			(xy 353.441508 -275.08073) (xy 355.601524 -275.08073) (xy 355.602032 -275.054823) (xy 355.610138 -275.003646)
			(xy 355.62615 -274.954367) (xy 355.649673 -274.9082) (xy 355.680129 -274.866281) (xy 355.716767 -274.829643)
			(xy 355.758686 -274.799187) (xy 355.804853 -274.775664) (xy 355.854132 -274.759652) (xy 355.905309 -274.751546)
			(xy 355.957123 -274.751546) (xy 356.0083 -274.759652) (xy 356.057579 -274.775664) (xy 356.103746 -274.799187)
			(xy 356.145665 -274.829643) (xy 356.182303 -274.866281) (xy 356.186047 -274.871434) (xy 406.002236 -274.871434)
			(xy 406.002236 -274.462494) (xy 406.002729 -274.452336) (xy 406.010505 -274.433567) (xy 406.024871 -274.419202)
			(xy 406.04364 -274.411428) (xy 406.053798 -274.410932) (xy 407.453338 -274.410932) (xy 407.463497 -274.411402)
			(xy 407.482266 -274.419188) (xy 407.49663 -274.433561) (xy 407.504404 -274.452334) (xy 407.5049 -274.462494)
			(xy 407.5049 -274.871434) (xy 410.102304 -274.871434) (xy 410.102304 -274.462494) (xy 410.102828 -274.45234)
			(xy 410.110598 -274.433577) (xy 410.124954 -274.419214) (xy 410.143712 -274.411433) (xy 410.153866 -274.410932)
			(xy 411.553406 -274.410932) (xy 411.563563 -274.411428) (xy 411.582331 -274.419204) (xy 411.596696 -274.433569)
			(xy 411.604472 -274.452337) (xy 411.604968 -274.462494) (xy 411.604968 -274.871434) (xy 413.546036 -274.871434)
			(xy 413.546036 -274.462494) (xy 413.546529 -274.452336) (xy 413.554305 -274.433567) (xy 413.568671 -274.419202)
			(xy 413.58744 -274.411428) (xy 413.597598 -274.410932) (xy 414.997138 -274.410932) (xy 415.007297 -274.411402)
			(xy 415.026066 -274.419188) (xy 415.04043 -274.433561) (xy 415.048204 -274.452334) (xy 415.0487 -274.462494)
			(xy 415.0487 -274.871434) (xy 417.646104 -274.871434) (xy 417.646104 -274.462494) (xy 417.646628 -274.45234)
			(xy 417.654398 -274.433577) (xy 417.668754 -274.419214) (xy 417.687512 -274.411433) (xy 417.697666 -274.410932)
			(xy 419.097206 -274.410932) (xy 419.107363 -274.411428) (xy 419.126131 -274.419204) (xy 419.140496 -274.433569)
			(xy 419.148272 -274.452337) (xy 419.148768 -274.462494) (xy 419.148768 -274.871434) (xy 421.089836 -274.871434)
			(xy 421.089836 -274.462494) (xy 421.090329 -274.452336) (xy 421.098105 -274.433567) (xy 421.112471 -274.419202)
			(xy 421.13124 -274.411428) (xy 421.141398 -274.410932) (xy 422.540938 -274.410932) (xy 422.551097 -274.411402)
			(xy 422.569866 -274.419188) (xy 422.58423 -274.433561) (xy 422.592004 -274.452334) (xy 422.5925 -274.462494)
			(xy 422.5925 -274.871434) (xy 425.189904 -274.871434) (xy 425.189904 -274.462494) (xy 425.190428 -274.45234)
			(xy 425.198198 -274.433577) (xy 425.212554 -274.419214) (xy 425.231312 -274.411433) (xy 425.241466 -274.410932)
			(xy 426.641006 -274.410932) (xy 426.651163 -274.411428) (xy 426.669931 -274.419204) (xy 426.684296 -274.433569)
			(xy 426.692072 -274.452337) (xy 426.692568 -274.462494) (xy 426.692568 -274.871434) (xy 428.633636 -274.871434)
			(xy 428.633636 -274.462494) (xy 428.634129 -274.452336) (xy 428.641905 -274.433567) (xy 428.656271 -274.419202)
			(xy 428.67504 -274.411428) (xy 428.685198 -274.410932) (xy 430.084738 -274.410932) (xy 430.094897 -274.411402)
			(xy 430.113666 -274.419188) (xy 430.12803 -274.433561) (xy 430.135804 -274.452334) (xy 430.1363 -274.462494)
			(xy 430.1363 -274.871434) (xy 432.733704 -274.871434) (xy 432.733704 -274.462494) (xy 432.734228 -274.45234)
			(xy 432.741998 -274.433577) (xy 432.756354 -274.419214) (xy 432.775112 -274.411433) (xy 432.785266 -274.410932)
			(xy 434.184806 -274.410932) (xy 434.194963 -274.411428) (xy 434.213731 -274.419204) (xy 434.228096 -274.433569)
			(xy 434.235872 -274.452337) (xy 434.236368 -274.462494) (xy 434.236368 -274.871434) (xy 436.177436 -274.871434)
			(xy 436.177436 -274.462494) (xy 436.177929 -274.452336) (xy 436.185705 -274.433567) (xy 436.200071 -274.419202)
			(xy 436.21884 -274.411428) (xy 436.228998 -274.410932) (xy 437.628538 -274.410932) (xy 437.638697 -274.411402)
			(xy 437.657466 -274.419188) (xy 437.67183 -274.433561) (xy 437.679604 -274.452334) (xy 437.6801 -274.462494)
			(xy 437.6801 -274.871434) (xy 440.277504 -274.871434) (xy 440.277504 -274.462494) (xy 440.278028 -274.45234)
			(xy 440.285798 -274.433577) (xy 440.300154 -274.419214) (xy 440.318912 -274.411433) (xy 440.329066 -274.410932)
			(xy 441.728606 -274.410932) (xy 441.738763 -274.411428) (xy 441.757531 -274.419204) (xy 441.771896 -274.433569)
			(xy 441.779672 -274.452337) (xy 441.780168 -274.462494) (xy 441.780168 -274.871434) (xy 443.721236 -274.871434)
			(xy 443.721236 -274.462494) (xy 443.721729 -274.452336) (xy 443.729505 -274.433567) (xy 443.743871 -274.419202)
			(xy 443.76264 -274.411428) (xy 443.772798 -274.410932) (xy 445.172338 -274.410932) (xy 445.182497 -274.411402)
			(xy 445.201266 -274.419188) (xy 445.21563 -274.433561) (xy 445.223404 -274.452334) (xy 445.2239 -274.462494)
			(xy 445.2239 -274.871434) (xy 447.821304 -274.871434) (xy 447.821304 -274.462494) (xy 447.821828 -274.45234)
			(xy 447.829598 -274.433577) (xy 447.843954 -274.419214) (xy 447.862712 -274.411433) (xy 447.872866 -274.410932)
			(xy 449.272406 -274.410932) (xy 449.282563 -274.411428) (xy 449.301331 -274.419204) (xy 449.315696 -274.433569)
			(xy 449.323472 -274.452337) (xy 449.323968 -274.462494) (xy 449.323968 -274.871434) (xy 451.265036 -274.871434)
			(xy 451.265036 -274.462494) (xy 451.265529 -274.452336) (xy 451.273305 -274.433567) (xy 451.287671 -274.419202)
			(xy 451.30644 -274.411428) (xy 451.316598 -274.410932) (xy 452.716138 -274.410932) (xy 452.726297 -274.411402)
			(xy 452.745066 -274.419188) (xy 452.75943 -274.433561) (xy 452.767204 -274.452334) (xy 452.7677 -274.462494)
			(xy 452.7677 -274.871434) (xy 455.365104 -274.871434) (xy 455.365104 -274.462494) (xy 455.365628 -274.45234)
			(xy 455.373398 -274.433577) (xy 455.387754 -274.419214) (xy 455.406512 -274.411433) (xy 455.416666 -274.410932)
			(xy 456.816206 -274.410932) (xy 456.826363 -274.411428) (xy 456.845131 -274.419204) (xy 456.859496 -274.433569)
			(xy 456.867272 -274.452337) (xy 456.867768 -274.462494) (xy 456.867768 -274.871434) (xy 458.808836 -274.871434)
			(xy 458.808836 -274.462494) (xy 458.809329 -274.452336) (xy 458.817105 -274.433567) (xy 458.831471 -274.419202)
			(xy 458.85024 -274.411428) (xy 458.860398 -274.410932) (xy 460.259938 -274.410932) (xy 460.270097 -274.411402)
			(xy 460.288866 -274.419188) (xy 460.30323 -274.433561) (xy 460.311004 -274.452334) (xy 460.3115 -274.462494)
			(xy 460.3115 -274.871434) (xy 462.908904 -274.871434) (xy 462.908904 -274.462494) (xy 462.909428 -274.45234)
			(xy 462.917198 -274.433577) (xy 462.931554 -274.419214) (xy 462.950312 -274.411433) (xy 462.960466 -274.410932)
			(xy 464.360006 -274.410932) (xy 464.370163 -274.411428) (xy 464.388931 -274.419204) (xy 464.403296 -274.433569)
			(xy 464.411072 -274.452337) (xy 464.411568 -274.462494) (xy 464.411568 -274.871434) (xy 464.411095 -274.881593)
			(xy 464.40331 -274.900362) (xy 464.388938 -274.914726) (xy 464.370165 -274.9225) (xy 464.360006 -274.922996)
			(xy 462.960466 -274.922996) (xy 462.95031 -274.922495) (xy 462.931547 -274.914716) (xy 462.917184 -274.900353)
			(xy 462.909405 -274.88159) (xy 462.908904 -274.871434) (xy 460.3115 -274.871434) (xy 460.310995 -274.881589)
			(xy 460.303217 -274.900352) (xy 460.288855 -274.914715) (xy 460.270093 -274.922495) (xy 460.259938 -274.922996)
			(xy 458.860398 -274.922996) (xy 458.850244 -274.922469) (xy 458.831482 -274.9147) (xy 458.817118 -274.900345)
			(xy 458.809337 -274.881587) (xy 458.808836 -274.871434) (xy 456.867768 -274.871434) (xy 456.867295 -274.881593)
			(xy 456.85951 -274.900362) (xy 456.845138 -274.914726) (xy 456.826365 -274.9225) (xy 456.816206 -274.922996)
			(xy 455.416666 -274.922996) (xy 455.40651 -274.922495) (xy 455.387747 -274.914716) (xy 455.373384 -274.900353)
			(xy 455.365605 -274.88159) (xy 455.365104 -274.871434) (xy 452.7677 -274.871434) (xy 452.767195 -274.881589)
			(xy 452.759417 -274.900352) (xy 452.745055 -274.914715) (xy 452.726293 -274.922495) (xy 452.716138 -274.922996)
			(xy 451.316598 -274.922996) (xy 451.306444 -274.922469) (xy 451.287682 -274.9147) (xy 451.273318 -274.900345)
			(xy 451.265537 -274.881587) (xy 451.265036 -274.871434) (xy 449.323968 -274.871434) (xy 449.323495 -274.881593)
			(xy 449.31571 -274.900362) (xy 449.301338 -274.914726) (xy 449.282565 -274.9225) (xy 449.272406 -274.922996)
			(xy 447.872866 -274.922996) (xy 447.86271 -274.922495) (xy 447.843947 -274.914716) (xy 447.829584 -274.900353)
			(xy 447.821805 -274.88159) (xy 447.821304 -274.871434) (xy 445.2239 -274.871434) (xy 445.223395 -274.881589)
			(xy 445.215617 -274.900352) (xy 445.201255 -274.914715) (xy 445.182493 -274.922495) (xy 445.172338 -274.922996)
			(xy 443.772798 -274.922996) (xy 443.762644 -274.922469) (xy 443.743882 -274.9147) (xy 443.729518 -274.900345)
			(xy 443.721737 -274.881587) (xy 443.721236 -274.871434) (xy 441.780168 -274.871434) (xy 441.779695 -274.881593)
			(xy 441.77191 -274.900362) (xy 441.757538 -274.914726) (xy 441.738765 -274.9225) (xy 441.728606 -274.922996)
			(xy 440.329066 -274.922996) (xy 440.31891 -274.922495) (xy 440.300147 -274.914716) (xy 440.285784 -274.900353)
			(xy 440.278005 -274.88159) (xy 440.277504 -274.871434) (xy 437.6801 -274.871434) (xy 437.679595 -274.881589)
			(xy 437.671817 -274.900352) (xy 437.657455 -274.914715) (xy 437.638693 -274.922495) (xy 437.628538 -274.922996)
			(xy 436.228998 -274.922996) (xy 436.218844 -274.922469) (xy 436.200082 -274.9147) (xy 436.185718 -274.900345)
			(xy 436.177937 -274.881587) (xy 436.177436 -274.871434) (xy 434.236368 -274.871434) (xy 434.235895 -274.881593)
			(xy 434.22811 -274.900362) (xy 434.213738 -274.914726) (xy 434.194965 -274.9225) (xy 434.184806 -274.922996)
			(xy 432.785266 -274.922996) (xy 432.77511 -274.922495) (xy 432.756347 -274.914716) (xy 432.741984 -274.900353)
			(xy 432.734205 -274.88159) (xy 432.733704 -274.871434) (xy 430.1363 -274.871434) (xy 430.135795 -274.881589)
			(xy 430.128017 -274.900352) (xy 430.113655 -274.914715) (xy 430.094893 -274.922495) (xy 430.084738 -274.922996)
			(xy 428.685198 -274.922996) (xy 428.675044 -274.922469) (xy 428.656282 -274.9147) (xy 428.641918 -274.900345)
			(xy 428.634137 -274.881587) (xy 428.633636 -274.871434) (xy 426.692568 -274.871434) (xy 426.692095 -274.881593)
			(xy 426.68431 -274.900362) (xy 426.669938 -274.914726) (xy 426.651165 -274.9225) (xy 426.641006 -274.922996)
			(xy 425.241466 -274.922996) (xy 425.23131 -274.922495) (xy 425.212547 -274.914716) (xy 425.198184 -274.900353)
			(xy 425.190405 -274.88159) (xy 425.189904 -274.871434) (xy 422.5925 -274.871434) (xy 422.591995 -274.881589)
			(xy 422.584217 -274.900352) (xy 422.569855 -274.914715) (xy 422.551093 -274.922495) (xy 422.540938 -274.922996)
			(xy 421.141398 -274.922996) (xy 421.131244 -274.922469) (xy 421.112482 -274.9147) (xy 421.098118 -274.900345)
			(xy 421.090337 -274.881587) (xy 421.089836 -274.871434) (xy 419.148768 -274.871434) (xy 419.148295 -274.881593)
			(xy 419.14051 -274.900362) (xy 419.126138 -274.914726) (xy 419.107365 -274.9225) (xy 419.097206 -274.922996)
			(xy 417.697666 -274.922996) (xy 417.68751 -274.922495) (xy 417.668747 -274.914716) (xy 417.654384 -274.900353)
			(xy 417.646605 -274.88159) (xy 417.646104 -274.871434) (xy 415.0487 -274.871434) (xy 415.048195 -274.881589)
			(xy 415.040417 -274.900352) (xy 415.026055 -274.914715) (xy 415.007293 -274.922495) (xy 414.997138 -274.922996)
			(xy 413.597598 -274.922996) (xy 413.587444 -274.922469) (xy 413.568682 -274.9147) (xy 413.554318 -274.900345)
			(xy 413.546537 -274.881587) (xy 413.546036 -274.871434) (xy 411.604968 -274.871434) (xy 411.604495 -274.881593)
			(xy 411.59671 -274.900362) (xy 411.582338 -274.914726) (xy 411.563565 -274.9225) (xy 411.553406 -274.922996)
			(xy 410.153866 -274.922996) (xy 410.14371 -274.922495) (xy 410.124947 -274.914716) (xy 410.110584 -274.900353)
			(xy 410.102805 -274.88159) (xy 410.102304 -274.871434) (xy 407.5049 -274.871434) (xy 407.504395 -274.881589)
			(xy 407.496617 -274.900352) (xy 407.482255 -274.914715) (xy 407.463493 -274.922495) (xy 407.453338 -274.922996)
			(xy 406.053798 -274.922996) (xy 406.043644 -274.922469) (xy 406.024882 -274.9147) (xy 406.010518 -274.900345)
			(xy 406.002737 -274.881587) (xy 406.002236 -274.871434) (xy 356.186047 -274.871434) (xy 356.212759 -274.9082)
			(xy 356.236282 -274.954367) (xy 356.252294 -275.003646) (xy 356.2604 -275.054823) (xy 356.260908 -275.08073)
			(xy 356.260296 -275.108446) (xy 356.250985 -275.163093) (xy 356.242366 -275.189442) (xy 356.234492 -275.21154)
			(xy 356.439724 -275.566632) (xy 356.462584 -275.57095) (xy 356.4874 -275.576135) (xy 356.535176 -275.593092)
			(xy 356.579792 -275.617163) (xy 356.620197 -275.647782) (xy 356.655436 -275.684226) (xy 356.684681 -275.725636)
			(xy 356.707239 -275.771036) (xy 356.722581 -275.819355) (xy 356.730343 -275.869452) (xy 356.730808 -275.8948)
			(xy 356.7303 -275.920707) (xy 356.722194 -275.971884) (xy 356.706182 -276.021163) (xy 356.682659 -276.06733)
			(xy 356.652203 -276.109249) (xy 356.615565 -276.145887) (xy 356.573646 -276.176343) (xy 356.527479 -276.199866)
			(xy 356.4782 -276.215878) (xy 356.427023 -276.223984) (xy 356.375209 -276.223984) (xy 356.324032 -276.215878)
			(xy 356.274753 -276.199866) (xy 356.228586 -276.176343) (xy 356.186667 -276.145887) (xy 356.150029 -276.109249)
			(xy 356.119573 -276.06733) (xy 356.09605 -276.021163) (xy 356.080038 -275.971884) (xy 356.071932 -275.920707)
			(xy 356.071424 -275.8948) (xy 356.072017 -275.867083) (xy 356.081341 -275.812436) (xy 356.089966 -275.786088)
			(xy 356.09784 -275.76399) (xy 355.892608 -275.408898) (xy 355.869748 -275.40458) (xy 355.844921 -275.399437)
			(xy 355.79714 -275.382481) (xy 355.75252 -275.358407) (xy 355.712113 -275.327784) (xy 355.676872 -275.291334)
			(xy 355.647629 -275.249917) (xy 355.625073 -275.20451) (xy 355.609738 -275.156184) (xy 355.601984 -275.10608)
			(xy 355.601524 -275.08073) (xy 353.441508 -275.08073) (xy 353.441092 -275.106096) (xy 353.433338 -275.156231)
			(xy 353.417989 -275.204584) (xy 353.395406 -275.250011) (xy 353.366125 -275.291439) (xy 353.330837 -275.327886)
			(xy 353.290378 -275.358492) (xy 353.245704 -275.382531) (xy 353.197873 -275.399435) (xy 353.17303 -275.40458)
			(xy 353.149916 -275.408898) (xy 352.944938 -275.76399) (xy 352.952812 -275.786088) (xy 352.96137 -275.812447)
			(xy 352.97057 -275.867092) (xy 352.9711 -275.8948) (xy 352.970592 -275.920687) (xy 352.970589 -275.920705)
			(xy 354.192116 -275.920705) (xy 354.192116 -275.868895) (xy 354.200221 -275.817722) (xy 354.21623 -275.768446)
			(xy 354.23975 -275.722282) (xy 354.270202 -275.680364) (xy 354.306835 -275.643726) (xy 354.348749 -275.61327)
			(xy 354.394911 -275.589745) (xy 354.444185 -275.57373) (xy 354.495357 -275.565619) (xy 354.521262 -275.565108)
			(xy 354.546773 -275.565613) (xy 354.597186 -275.573468) (xy 354.645788 -275.588996) (xy 354.691416 -275.611827)
			(xy 354.732982 -275.641416) (xy 354.769494 -275.677055) (xy 354.785168 -275.697188) (xy 355.197156 -275.697188)
			(xy 355.212852 -275.677071) (xy 355.249357 -275.641427) (xy 355.290918 -275.611831) (xy 355.336542 -275.588992)
			(xy 355.38514 -275.573454) (xy 355.435551 -275.565588) (xy 355.461062 -275.565108) (xy 355.486973 -275.565587)
			(xy 355.538159 -275.573688) (xy 355.587447 -275.589698) (xy 355.633623 -275.613221) (xy 355.67555 -275.643679)
			(xy 355.712197 -275.680321) (xy 355.742659 -275.722245) (xy 355.766188 -275.768418) (xy 355.782203 -275.817704)
			(xy 355.79031 -275.868889) (xy 355.79031 -275.920711) (xy 355.782203 -275.971896) (xy 355.766188 -276.021182)
			(xy 355.742659 -276.067355) (xy 355.712197 -276.109279) (xy 355.67555 -276.145921) (xy 355.633623 -276.176379)
			(xy 355.587447 -276.199902) (xy 355.538159 -276.215912) (xy 355.486973 -276.224013) (xy 355.461062 -276.224492)
			(xy 355.435549 -276.224043) (xy 355.385133 -276.216176) (xy 355.336531 -276.200636) (xy 355.290902 -276.177795)
			(xy 355.249337 -276.148197) (xy 355.212829 -276.112549) (xy 355.197156 -276.092412) (xy 354.785168 -276.092412)
			(xy 354.769516 -276.112565) (xy 354.733002 -276.148208) (xy 354.691432 -276.177799) (xy 354.645799 -276.200632)
			(xy 354.597193 -276.216162) (xy 354.546775 -276.224017) (xy 354.521262 -276.224492) (xy 354.495357 -276.223981)
			(xy 354.444185 -276.21587) (xy 354.394911 -276.199855) (xy 354.348749 -276.17633) (xy 354.306835 -276.145874)
			(xy 354.270202 -276.109236) (xy 354.23975 -276.067318) (xy 354.21623 -276.021154) (xy 354.200221 -275.971878)
			(xy 354.192116 -275.920705) (xy 352.970589 -275.920705) (xy 352.962493 -275.971825) (xy 352.946494 -276.021065)
			(xy 352.922988 -276.067197) (xy 352.892556 -276.109084) (xy 352.855946 -276.145694) (xy 352.814059 -276.176126)
			(xy 352.767927 -276.199632) (xy 352.718687 -276.215631) (xy 352.667549 -276.22373) (xy 352.615775 -276.22373)
			(xy 352.564637 -276.215631) (xy 352.515397 -276.199632) (xy 352.469265 -276.176126) (xy 352.427378 -276.145694)
			(xy 352.390768 -276.109084) (xy 352.360336 -276.067197) (xy 352.33683 -276.021065) (xy 352.320831 -275.971825)
			(xy 352.312732 -275.920687) (xy 352.312224 -275.8948) (xy 351.0915 -275.8948) (xy 351.090979 -275.920144)
			(xy 351.083207 -275.970232) (xy 351.067862 -276.018541) (xy 351.045306 -276.063932) (xy 351.016069 -276.105338)
			(xy 350.98084 -276.141782) (xy 350.940449 -276.172406) (xy 350.895848 -276.196488) (xy 350.848087 -276.213462)
			(xy 350.823276 -276.21865) (xy 350.800416 -276.222968) (xy 350.595438 -276.577806) (xy 350.603312 -276.599904)
			(xy 350.611874 -276.626262) (xy 350.621072 -276.680908) (xy 350.6216 -276.708616) (xy 350.902524 -276.708616)
			(xy 350.903032 -276.682709) (xy 350.911138 -276.631532) (xy 350.92715 -276.582253) (xy 350.950673 -276.536086)
			(xy 350.981129 -276.494167) (xy 351.017767 -276.457529) (xy 351.059686 -276.427073) (xy 351.105853 -276.40355)
			(xy 351.155132 -276.387538) (xy 351.206309 -276.379432) (xy 351.258123 -276.379432) (xy 351.3093 -276.387538)
			(xy 351.358579 -276.40355) (xy 351.404746 -276.427073) (xy 351.446665 -276.457529) (xy 351.483303 -276.494167)
			(xy 351.513759 -276.536086) (xy 351.537282 -276.582253) (xy 351.553294 -276.631532) (xy 351.5614 -276.682709)
			(xy 351.561908 -276.708616) (xy 351.561377 -276.734509) (xy 351.842805 -276.734509) (xy 351.842805 -276.682691)
			(xy 351.850912 -276.631511) (xy 351.866925 -276.582229) (xy 351.89045 -276.53606) (xy 351.920909 -276.494139)
			(xy 351.957551 -276.457499) (xy 351.999473 -276.427042) (xy 352.045644 -276.403519) (xy 352.094927 -276.387508)
			(xy 352.146107 -276.379404) (xy 352.172016 -276.378924) (xy 352.197529 -276.379383) (xy 352.247945 -276.387247)
			(xy 352.296547 -276.402784) (xy 352.342175 -276.425624) (xy 352.38374 -276.45522) (xy 352.420249 -276.490867)
			(xy 352.435922 -276.511004) (xy 352.84791 -276.511004) (xy 352.863579 -276.490865) (xy 352.900089 -276.455221)
			(xy 352.941656 -276.425628) (xy 352.987285 -276.402792) (xy 353.035888 -276.387259) (xy 353.086304 -276.3794)
			(xy 353.111816 -276.378924) (xy 353.137724 -276.379401) (xy 353.188901 -276.387509) (xy 353.23818 -276.403523)
			(xy 353.284347 -276.427048) (xy 353.326266 -276.457506) (xy 353.362904 -276.494146) (xy 353.39336 -276.536066)
			(xy 353.416883 -276.582235) (xy 353.432895 -276.631514) (xy 353.441 -276.682692) (xy 353.441 -276.734508)
			(xy 353.432895 -276.785686) (xy 353.416883 -276.834965) (xy 353.39336 -276.881134) (xy 353.362904 -276.923054)
			(xy 353.326266 -276.959694) (xy 353.284347 -276.990152) (xy 353.23818 -277.013677) (xy 353.188901 -277.029691)
			(xy 353.137724 -277.037799) (xy 353.111816 -277.038308) (xy 353.086305 -277.037813) (xy 353.035891 -277.029955)
			(xy 352.98729 -277.014424) (xy 352.941662 -276.991591) (xy 352.900096 -276.962001) (xy 352.863585 -276.926361)
			(xy 352.84791 -276.906228) (xy 352.435922 -276.906228) (xy 352.420244 -276.926359) (xy 352.383734 -276.962002)
			(xy 352.342169 -276.991595) (xy 352.296542 -277.014432) (xy 352.247941 -277.029967) (xy 352.197528 -277.03783)
			(xy 352.172016 -277.038308) (xy 352.146107 -277.037796) (xy 352.094927 -277.029692) (xy 352.045644 -277.013681)
			(xy 351.999473 -276.990158) (xy 351.957551 -276.959701) (xy 351.920909 -276.923061) (xy 351.89045 -276.88114)
			(xy 351.866925 -276.834971) (xy 351.850912 -276.785689) (xy 351.842805 -276.734509) (xy 351.561377 -276.734509)
			(xy 351.561338 -276.736398) (xy 351.552014 -276.791174) (xy 351.543366 -276.817582) (xy 351.535492 -276.839426)
			(xy 351.74047 -277.194264) (xy 351.76333 -277.198582) (xy 351.788142 -277.203733) (xy 351.835882 -277.220727)
			(xy 351.88046 -277.244826) (xy 351.920825 -277.275462) (xy 351.956028 -277.311913) (xy 351.985239 -277.353322)
			(xy 352.007769 -277.398712) (xy 352.02309 -277.447016) (xy 352.030838 -277.497095) (xy 352.0313 -277.522432)
			(xy 354.191824 -277.522432) (xy 354.192226 -277.497095) (xy 354.199989 -277.447018) (xy 354.215322 -277.398718)
			(xy 354.237864 -277.353333) (xy 354.267084 -277.31193) (xy 354.302294 -277.275486) (xy 354.342666 -277.244857)
			(xy 354.387248 -277.220766) (xy 354.434991 -277.203779) (xy 354.459794 -277.198582) (xy 354.482654 -277.194264)
			(xy 354.687886 -276.838918) (xy 354.680266 -276.817074) (xy 354.671663 -276.790785) (xy 354.662334 -276.736269)
			(xy 354.661724 -276.708616) (xy 354.662232 -276.682709) (xy 354.670338 -276.631532) (xy 354.68635 -276.582253)
			(xy 354.709873 -276.536086) (xy 354.740329 -276.494167) (xy 354.776967 -276.457529) (xy 354.818886 -276.427073)
			(xy 354.865053 -276.40355) (xy 354.914332 -276.387538) (xy 354.965509 -276.379432) (xy 355.017323 -276.379432)
			(xy 355.0685 -276.387538) (xy 355.117779 -276.40355) (xy 355.163946 -276.427073) (xy 355.205865 -276.457529)
			(xy 355.242503 -276.494167) (xy 355.272959 -276.536086) (xy 355.296482 -276.582253) (xy 355.312494 -276.631532)
			(xy 355.3206 -276.682709) (xy 355.321108 -276.708616) (xy 356.541324 -276.708616) (xy 356.541802 -276.683281)
			(xy 356.549553 -276.633207) (xy 356.564874 -276.584909) (xy 356.587406 -276.539525) (xy 356.616616 -276.498122)
			(xy 356.651818 -276.461676) (xy 356.692181 -276.431046) (xy 356.736757 -276.406953) (xy 356.784494 -276.389964)
			(xy 356.809294 -276.384766) (xy 356.832154 -276.380448) (xy 357.037132 -276.02561) (xy 357.029258 -276.003766)
			(xy 357.020612 -275.977358) (xy 357.011292 -275.922582) (xy 357.010716 -275.8948) (xy 357.011224 -275.868893)
			(xy 357.01933 -275.817716) (xy 357.035342 -275.768437) (xy 357.058865 -275.72227) (xy 357.089321 -275.680351)
			(xy 357.125959 -275.643713) (xy 357.167878 -275.613257) (xy 357.214045 -275.589734) (xy 357.263324 -275.573722)
			(xy 357.314501 -275.565616) (xy 357.366315 -275.565616) (xy 357.417492 -275.573722) (xy 357.466771 -275.589734)
			(xy 357.512938 -275.613257) (xy 357.554857 -275.643713) (xy 357.591495 -275.680351) (xy 357.621259 -275.721318)
			(xy 406.002236 -275.721318) (xy 406.002236 -275.312378) (xy 406.002715 -275.302219) (xy 406.010496 -275.28345)
			(xy 406.024867 -275.269085) (xy 406.043639 -275.261311) (xy 406.053798 -275.260816) (xy 407.453338 -275.260816)
			(xy 407.463495 -275.261302) (xy 407.482261 -275.269085) (xy 407.496624 -275.283452) (xy 407.504401 -275.30222)
			(xy 407.5049 -275.312378) (xy 407.5049 -275.721318) (xy 413.546036 -275.721318) (xy 413.546036 -275.312378)
			(xy 413.546515 -275.302219) (xy 413.554296 -275.28345) (xy 413.568667 -275.269085) (xy 413.587439 -275.261311)
			(xy 413.597598 -275.260816) (xy 414.997138 -275.260816) (xy 415.007295 -275.261302) (xy 415.026061 -275.269085)
			(xy 415.040424 -275.283452) (xy 415.048201 -275.30222) (xy 415.0487 -275.312378) (xy 415.0487 -275.721318)
			(xy 421.089836 -275.721318) (xy 421.089836 -275.312378) (xy 421.090315 -275.302219) (xy 421.098096 -275.28345)
			(xy 421.112467 -275.269085) (xy 421.131239 -275.261311) (xy 421.141398 -275.260816) (xy 422.540938 -275.260816)
			(xy 422.551095 -275.261302) (xy 422.569861 -275.269085) (xy 422.584224 -275.283452) (xy 422.592001 -275.30222)
			(xy 422.5925 -275.312378) (xy 422.5925 -275.721318) (xy 428.633636 -275.721318) (xy 428.633636 -275.312378)
			(xy 428.634115 -275.302219) (xy 428.641896 -275.28345) (xy 428.656267 -275.269085) (xy 428.675039 -275.261311)
			(xy 428.685198 -275.260816) (xy 430.084738 -275.260816) (xy 430.094895 -275.261302) (xy 430.113661 -275.269085)
			(xy 430.128024 -275.283452) (xy 430.135801 -275.30222) (xy 430.1363 -275.312378) (xy 430.1363 -275.721318)
			(xy 436.177436 -275.721318) (xy 436.177436 -275.312378) (xy 436.177915 -275.302219) (xy 436.185696 -275.28345)
			(xy 436.200067 -275.269085) (xy 436.218839 -275.261311) (xy 436.228998 -275.260816) (xy 437.628538 -275.260816)
			(xy 437.638695 -275.261302) (xy 437.657461 -275.269085) (xy 437.671824 -275.283452) (xy 437.679601 -275.30222)
			(xy 437.6801 -275.312378) (xy 437.6801 -275.721318) (xy 443.721236 -275.721318) (xy 443.721236 -275.312378)
			(xy 443.721715 -275.302219) (xy 443.729496 -275.28345) (xy 443.743867 -275.269085) (xy 443.762639 -275.261311)
			(xy 443.772798 -275.260816) (xy 445.172338 -275.260816) (xy 445.182495 -275.261302) (xy 445.201261 -275.269085)
			(xy 445.215624 -275.283452) (xy 445.223401 -275.30222) (xy 445.2239 -275.312378) (xy 445.2239 -275.721318)
			(xy 451.265036 -275.721318) (xy 451.265036 -275.312378) (xy 451.265515 -275.302219) (xy 451.273296 -275.28345)
			(xy 451.287667 -275.269085) (xy 451.306439 -275.261311) (xy 451.316598 -275.260816) (xy 452.716138 -275.260816)
			(xy 452.726295 -275.261302) (xy 452.745061 -275.269085) (xy 452.759424 -275.283452) (xy 452.767201 -275.30222)
			(xy 452.7677 -275.312378) (xy 452.7677 -275.721318) (xy 458.808836 -275.721318) (xy 458.808836 -275.312378)
			(xy 458.809315 -275.302219) (xy 458.817096 -275.28345) (xy 458.831467 -275.269085) (xy 458.850239 -275.261311)
			(xy 458.860398 -275.260816) (xy 460.259938 -275.260816) (xy 460.270095 -275.261302) (xy 460.288861 -275.269085)
			(xy 460.303224 -275.283452) (xy 460.311001 -275.30222) (xy 460.3115 -275.312378) (xy 460.3115 -275.721318)
			(xy 460.310983 -275.731472) (xy 460.303209 -275.750235) (xy 460.288851 -275.764598) (xy 460.270092 -275.772379)
			(xy 460.259938 -275.77288) (xy 458.860398 -275.77288) (xy 458.850242 -275.772369) (xy 458.831477 -275.764597)
			(xy 458.817112 -275.750237) (xy 458.809335 -275.731474) (xy 458.808836 -275.721318) (xy 452.7677 -275.721318)
			(xy 452.767183 -275.731472) (xy 452.759409 -275.750235) (xy 452.745051 -275.764598) (xy 452.726292 -275.772379)
			(xy 452.716138 -275.77288) (xy 451.316598 -275.77288) (xy 451.306442 -275.772369) (xy 451.287677 -275.764597)
			(xy 451.273312 -275.750237) (xy 451.265535 -275.731474) (xy 451.265036 -275.721318) (xy 445.2239 -275.721318)
			(xy 445.223383 -275.731472) (xy 445.215609 -275.750235) (xy 445.201251 -275.764598) (xy 445.182492 -275.772379)
			(xy 445.172338 -275.77288) (xy 443.772798 -275.77288) (xy 443.762642 -275.772369) (xy 443.743877 -275.764597)
			(xy 443.729512 -275.750237) (xy 443.721735 -275.731474) (xy 443.721236 -275.721318) (xy 437.6801 -275.721318)
			(xy 437.679583 -275.731472) (xy 437.671809 -275.750235) (xy 437.657451 -275.764598) (xy 437.638692 -275.772379)
			(xy 437.628538 -275.77288) (xy 436.228998 -275.77288) (xy 436.218842 -275.772369) (xy 436.200077 -275.764597)
			(xy 436.185712 -275.750237) (xy 436.177935 -275.731474) (xy 436.177436 -275.721318) (xy 430.1363 -275.721318)
			(xy 430.135783 -275.731472) (xy 430.128009 -275.750235) (xy 430.113651 -275.764598) (xy 430.094892 -275.772379)
			(xy 430.084738 -275.77288) (xy 428.685198 -275.77288) (xy 428.675042 -275.772369) (xy 428.656277 -275.764597)
			(xy 428.641912 -275.750237) (xy 428.634135 -275.731474) (xy 428.633636 -275.721318) (xy 422.5925 -275.721318)
			(xy 422.591983 -275.731472) (xy 422.584209 -275.750235) (xy 422.569851 -275.764598) (xy 422.551092 -275.772379)
			(xy 422.540938 -275.77288) (xy 421.141398 -275.77288) (xy 421.131242 -275.772369) (xy 421.112477 -275.764597)
			(xy 421.098112 -275.750237) (xy 421.090335 -275.731474) (xy 421.089836 -275.721318) (xy 415.0487 -275.721318)
			(xy 415.048183 -275.731472) (xy 415.040409 -275.750235) (xy 415.026051 -275.764598) (xy 415.007292 -275.772379)
			(xy 414.997138 -275.77288) (xy 413.597598 -275.77288) (xy 413.587442 -275.772369) (xy 413.568677 -275.764597)
			(xy 413.554312 -275.750237) (xy 413.546535 -275.731474) (xy 413.546036 -275.721318) (xy 407.5049 -275.721318)
			(xy 407.504383 -275.731472) (xy 407.496609 -275.750235) (xy 407.482251 -275.764598) (xy 407.463492 -275.772379)
			(xy 407.453338 -275.77288) (xy 406.053798 -275.77288) (xy 406.043642 -275.772369) (xy 406.024877 -275.764597)
			(xy 406.010512 -275.750237) (xy 406.002735 -275.731474) (xy 406.002236 -275.721318) (xy 357.621259 -275.721318)
			(xy 357.621951 -275.72227) (xy 357.645474 -275.768437) (xy 357.661486 -275.817716) (xy 357.669592 -275.868893)
			(xy 357.6701 -275.8948) (xy 357.669579 -275.920144) (xy 357.661807 -275.970232) (xy 357.646462 -276.018541)
			(xy 357.623906 -276.063932) (xy 357.594669 -276.105338) (xy 357.55944 -276.141782) (xy 357.519049 -276.172406)
			(xy 357.474448 -276.196488) (xy 357.426687 -276.213462) (xy 357.401876 -276.21865) (xy 357.379016 -276.222968)
			(xy 357.177706 -276.571456) (xy 410.102304 -276.571456) (xy 410.102304 -276.162516) (xy 410.102735 -276.152362)
			(xy 410.110526 -276.13361) (xy 410.12492 -276.119285) (xy 410.14371 -276.111586) (xy 410.153866 -276.111208)
			(xy 411.553406 -276.111208) (xy 411.563529 -276.111721) (xy 411.582244 -276.119445) (xy 411.596599 -276.133722)
			(xy 411.604424 -276.152396) (xy 411.604968 -276.162516) (xy 411.604968 -276.571456) (xy 417.646104 -276.571456)
			(xy 417.646104 -276.162516) (xy 417.646535 -276.152362) (xy 417.654326 -276.13361) (xy 417.66872 -276.119285)
			(xy 417.68751 -276.111586) (xy 417.697666 -276.111208) (xy 419.097206 -276.111208) (xy 419.107329 -276.111721)
			(xy 419.126044 -276.119445) (xy 419.140399 -276.133722) (xy 419.148224 -276.152396) (xy 419.148768 -276.162516)
			(xy 419.148768 -276.571456) (xy 425.189904 -276.571456) (xy 425.189904 -276.162516) (xy 425.190335 -276.152362)
			(xy 425.198126 -276.13361) (xy 425.21252 -276.119285) (xy 425.23131 -276.111586) (xy 425.241466 -276.111208)
			(xy 426.641006 -276.111208) (xy 426.651129 -276.111721) (xy 426.669844 -276.119445) (xy 426.684199 -276.133722)
			(xy 426.692024 -276.152396) (xy 426.692568 -276.162516) (xy 426.692568 -276.571456) (xy 432.733704 -276.571456)
			(xy 432.733704 -276.162516) (xy 432.734135 -276.152362) (xy 432.741926 -276.13361) (xy 432.75632 -276.119285)
			(xy 432.77511 -276.111586) (xy 432.785266 -276.111208) (xy 434.184806 -276.111208) (xy 434.194929 -276.111721)
			(xy 434.213644 -276.119445) (xy 434.227999 -276.133722) (xy 434.235824 -276.152396) (xy 434.236368 -276.162516)
			(xy 434.236368 -276.571456) (xy 440.277504 -276.571456) (xy 440.277504 -276.162516) (xy 440.277935 -276.152362)
			(xy 440.285726 -276.13361) (xy 440.30012 -276.119285) (xy 440.31891 -276.111586) (xy 440.329066 -276.111208)
			(xy 441.728606 -276.111208) (xy 441.738729 -276.111721) (xy 441.757444 -276.119445) (xy 441.771799 -276.133722)
			(xy 441.779624 -276.152396) (xy 441.780168 -276.162516) (xy 441.780168 -276.571456) (xy 447.821304 -276.571456)
			(xy 447.821304 -276.162516) (xy 447.821735 -276.152362) (xy 447.829526 -276.13361) (xy 447.84392 -276.119285)
			(xy 447.86271 -276.111586) (xy 447.872866 -276.111208) (xy 449.272406 -276.111208) (xy 449.282529 -276.111721)
			(xy 449.301244 -276.119445) (xy 449.315599 -276.133722) (xy 449.323424 -276.152396) (xy 449.323968 -276.162516)
			(xy 449.323968 -276.571456) (xy 455.365104 -276.571456) (xy 455.365104 -276.162516) (xy 455.365535 -276.152362)
			(xy 455.373326 -276.13361) (xy 455.38772 -276.119285) (xy 455.40651 -276.111586) (xy 455.416666 -276.111208)
			(xy 456.816206 -276.111208) (xy 456.826329 -276.111721) (xy 456.845044 -276.119445) (xy 456.859399 -276.133722)
			(xy 456.867224 -276.152396) (xy 456.867768 -276.162516) (xy 456.867768 -276.571456) (xy 462.908904 -276.571456)
			(xy 462.908904 -276.162516) (xy 462.909335 -276.152362) (xy 462.917126 -276.13361) (xy 462.93152 -276.119285)
			(xy 462.95031 -276.111586) (xy 462.960466 -276.111208) (xy 464.360006 -276.111208) (xy 464.370129 -276.111721)
			(xy 464.388844 -276.119445) (xy 464.403199 -276.133722) (xy 464.411024 -276.152396) (xy 464.411568 -276.162516)
			(xy 464.411568 -276.571456) (xy 464.411142 -276.581611) (xy 464.403355 -276.600369) (xy 464.388959 -276.614695)
			(xy 464.370163 -276.62239) (xy 464.360006 -276.622764) (xy 462.960466 -276.622764) (xy 462.950338 -276.622301)
			(xy 462.931616 -276.614563) (xy 462.917261 -276.60027) (xy 462.909443 -276.581582) (xy 462.908904 -276.571456)
			(xy 456.867768 -276.571456) (xy 456.867342 -276.581611) (xy 456.859555 -276.600369) (xy 456.845159 -276.614695)
			(xy 456.826363 -276.62239) (xy 456.816206 -276.622764) (xy 455.416666 -276.622764) (xy 455.406538 -276.622301)
			(xy 455.387816 -276.614563) (xy 455.373461 -276.60027) (xy 455.365643 -276.581582) (xy 455.365104 -276.571456)
			(xy 449.323968 -276.571456) (xy 449.323542 -276.581611) (xy 449.315755 -276.600369) (xy 449.301359 -276.614695)
			(xy 449.282563 -276.62239) (xy 449.272406 -276.622764) (xy 447.872866 -276.622764) (xy 447.862738 -276.622301)
			(xy 447.844016 -276.614563) (xy 447.829661 -276.60027) (xy 447.821843 -276.581582) (xy 447.821304 -276.571456)
			(xy 441.780168 -276.571456) (xy 441.779742 -276.581611) (xy 441.771955 -276.600369) (xy 441.757559 -276.614695)
			(xy 441.738763 -276.62239) (xy 441.728606 -276.622764) (xy 440.329066 -276.622764) (xy 440.318938 -276.622301)
			(xy 440.300216 -276.614563) (xy 440.285861 -276.60027) (xy 440.278043 -276.581582) (xy 440.277504 -276.571456)
			(xy 434.236368 -276.571456) (xy 434.235942 -276.581611) (xy 434.228155 -276.600369) (xy 434.213759 -276.614695)
			(xy 434.194963 -276.62239) (xy 434.184806 -276.622764) (xy 432.785266 -276.622764) (xy 432.775138 -276.622301)
			(xy 432.756416 -276.614563) (xy 432.742061 -276.60027) (xy 432.734243 -276.581582) (xy 432.733704 -276.571456)
			(xy 426.692568 -276.571456) (xy 426.692142 -276.581611) (xy 426.684355 -276.600369) (xy 426.669959 -276.614695)
			(xy 426.651163 -276.62239) (xy 426.641006 -276.622764) (xy 425.241466 -276.622764) (xy 425.231338 -276.622301)
			(xy 425.212616 -276.614563) (xy 425.198261 -276.60027) (xy 425.190443 -276.581582) (xy 425.189904 -276.571456)
			(xy 419.148768 -276.571456) (xy 419.148342 -276.581611) (xy 419.140555 -276.600369) (xy 419.126159 -276.614695)
			(xy 419.107363 -276.62239) (xy 419.097206 -276.622764) (xy 417.697666 -276.622764) (xy 417.687538 -276.622301)
			(xy 417.668816 -276.614563) (xy 417.654461 -276.60027) (xy 417.646643 -276.581582) (xy 417.646104 -276.571456)
			(xy 411.604968 -276.571456) (xy 411.604542 -276.581611) (xy 411.596755 -276.600369) (xy 411.582359 -276.614695)
			(xy 411.563563 -276.62239) (xy 411.553406 -276.622764) (xy 410.153866 -276.622764) (xy 410.143738 -276.622301)
			(xy 410.125016 -276.614563) (xy 410.110661 -276.60027) (xy 410.102843 -276.581582) (xy 410.102304 -276.571456)
			(xy 357.177706 -276.571456) (xy 357.174038 -276.577806) (xy 357.181912 -276.599904) (xy 357.190474 -276.626262)
			(xy 357.199672 -276.680908) (xy 357.2002 -276.708616) (xy 357.199692 -276.734503) (xy 357.191593 -276.785641)
			(xy 357.175594 -276.834881) (xy 357.152088 -276.881013) (xy 357.121656 -276.9229) (xy 357.085046 -276.95951)
			(xy 357.043159 -276.989942) (xy 356.997027 -277.013448) (xy 356.947787 -277.029447) (xy 356.896649 -277.037546)
			(xy 356.844875 -277.037546) (xy 356.793737 -277.029447) (xy 356.744497 -277.013448) (xy 356.698365 -276.989942)
			(xy 356.656478 -276.95951) (xy 356.619868 -276.9229) (xy 356.589436 -276.881013) (xy 356.56593 -276.834881)
			(xy 356.549931 -276.785641) (xy 356.541832 -276.734503) (xy 356.541324 -276.708616) (xy 355.321108 -276.708616)
			(xy 355.320641 -276.73399) (xy 355.312871 -276.784141) (xy 355.297501 -276.832506) (xy 355.274895 -276.877942)
			(xy 355.245588 -276.919373) (xy 355.210273 -276.955819) (xy 355.169787 -276.986418) (xy 355.125087 -277.010445)
			(xy 355.07723 -277.027332) (xy 355.052376 -277.032466) (xy 355.029516 -277.036784) (xy 354.824538 -277.391622)
			(xy 354.832412 -277.41372) (xy 354.840977 -277.440077) (xy 354.850173 -277.494724) (xy 354.8507 -277.522432)
			(xy 355.131624 -277.522432) (xy 355.132132 -277.496545) (xy 355.140231 -277.445407) (xy 355.15623 -277.396167)
			(xy 355.179736 -277.350035) (xy 355.210168 -277.308148) (xy 355.246778 -277.271538) (xy 355.288665 -277.241106)
			(xy 355.334797 -277.2176) (xy 355.384037 -277.201601) (xy 355.435175 -277.193502) (xy 355.486949 -277.193502)
			(xy 355.538087 -277.201601) (xy 355.587327 -277.2176) (xy 355.633459 -277.241106) (xy 355.675346 -277.271538)
			(xy 355.711956 -277.308148) (xy 355.742388 -277.350035) (xy 355.765894 -277.396167) (xy 355.781893 -277.445407)
			(xy 355.789992 -277.496545) (xy 355.7905 -277.522432) (xy 355.7905 -277.52294) (xy 355.789963 -277.548303)
			(xy 356.071748 -277.548303) (xy 356.071748 -277.496497) (xy 356.079852 -277.445329) (xy 356.09586 -277.396058)
			(xy 356.119377 -277.349898) (xy 356.149826 -277.307985) (xy 356.186456 -277.271351) (xy 356.228366 -277.240897)
			(xy 356.274523 -277.217374) (xy 356.323792 -277.201361) (xy 356.374959 -277.193251) (xy 356.400862 -277.19274)
			(xy 356.426374 -277.193232) (xy 356.476788 -277.201088) (xy 356.52539 -277.216618) (xy 356.571019 -277.239452)
			(xy 356.612585 -277.269043) (xy 356.649095 -277.304685) (xy 356.664768 -277.32482) (xy 357.076756 -277.32482)
			(xy 357.09246 -277.30471) (xy 357.128963 -277.269063) (xy 357.170522 -277.239467) (xy 357.216144 -277.216626)
			(xy 357.264741 -277.201087) (xy 357.315152 -277.19322) (xy 357.340662 -277.19274) (xy 357.366576 -277.193155)
			(xy 357.417766 -277.201257) (xy 357.467059 -277.217268) (xy 357.51324 -277.240794) (xy 357.555171 -277.271254)
			(xy 357.591821 -277.3079) (xy 357.622286 -277.349828) (xy 357.645817 -277.396006) (xy 357.654049 -277.42134)
			(xy 406.002236 -277.42134) (xy 406.002236 -277.0124) (xy 406.002622 -277.002241) (xy 406.010425 -276.983482)
			(xy 406.024833 -276.969157) (xy 406.043637 -276.961464) (xy 406.053798 -276.961092) (xy 407.453338 -276.961092)
			(xy 407.463461 -276.961594) (xy 407.482174 -276.969325) (xy 407.496527 -276.983606) (xy 407.504354 -277.002279)
			(xy 407.5049 -277.0124) (xy 407.5049 -277.42134) (xy 413.546036 -277.42134) (xy 413.546036 -277.0124)
			(xy 413.546422 -277.002241) (xy 413.554225 -276.983482) (xy 413.568633 -276.969157) (xy 413.587437 -276.961464)
			(xy 413.597598 -276.961092) (xy 414.997138 -276.961092) (xy 415.007261 -276.961594) (xy 415.025974 -276.969325)
			(xy 415.040327 -276.983606) (xy 415.048154 -277.002279) (xy 415.0487 -277.0124) (xy 415.0487 -277.42134)
			(xy 421.089836 -277.42134) (xy 421.089836 -277.0124) (xy 421.090222 -277.002241) (xy 421.098025 -276.983482)
			(xy 421.112433 -276.969157) (xy 421.131237 -276.961464) (xy 421.141398 -276.961092) (xy 422.540938 -276.961092)
			(xy 422.551061 -276.961594) (xy 422.569774 -276.969325) (xy 422.584127 -276.983606) (xy 422.591954 -277.002279)
			(xy 422.5925 -277.0124) (xy 422.5925 -277.42134) (xy 428.633636 -277.42134) (xy 428.633636 -277.0124)
			(xy 428.634022 -277.002241) (xy 428.641825 -276.983482) (xy 428.656233 -276.969157) (xy 428.675037 -276.961464)
			(xy 428.685198 -276.961092) (xy 430.084738 -276.961092) (xy 430.094861 -276.961594) (xy 430.113574 -276.969325)
			(xy 430.127927 -276.983606) (xy 430.135754 -277.002279) (xy 430.1363 -277.0124) (xy 430.1363 -277.42134)
			(xy 436.177436 -277.42134) (xy 436.177436 -277.0124) (xy 436.177822 -277.002241) (xy 436.185625 -276.983482)
			(xy 436.200033 -276.969157) (xy 436.218837 -276.961464) (xy 436.228998 -276.961092) (xy 437.628538 -276.961092)
			(xy 437.638661 -276.961594) (xy 437.657374 -276.969325) (xy 437.671727 -276.983606) (xy 437.679554 -277.002279)
			(xy 437.6801 -277.0124) (xy 437.6801 -277.42134) (xy 443.721236 -277.42134) (xy 443.721236 -277.0124)
			(xy 443.721622 -277.002241) (xy 443.729425 -276.983482) (xy 443.743833 -276.969157) (xy 443.762637 -276.961464)
			(xy 443.772798 -276.961092) (xy 445.172338 -276.961092) (xy 445.182461 -276.961594) (xy 445.201174 -276.969325)
			(xy 445.215527 -276.983606) (xy 445.223354 -277.002279) (xy 445.2239 -277.0124) (xy 445.2239 -277.42134)
			(xy 451.265036 -277.42134) (xy 451.265036 -277.0124) (xy 451.265422 -277.002241) (xy 451.273225 -276.983482)
			(xy 451.287633 -276.969157) (xy 451.306437 -276.961464) (xy 451.316598 -276.961092) (xy 452.716138 -276.961092)
			(xy 452.726261 -276.961594) (xy 452.744974 -276.969325) (xy 452.759327 -276.983606) (xy 452.767154 -277.002279)
			(xy 452.7677 -277.0124) (xy 452.7677 -277.42134) (xy 458.808836 -277.42134) (xy 458.808836 -277.0124)
			(xy 458.809222 -277.002241) (xy 458.817025 -276.983482) (xy 458.831433 -276.969157) (xy 458.850237 -276.961464)
			(xy 458.860398 -276.961092) (xy 460.259938 -276.961092) (xy 460.270061 -276.961594) (xy 460.288774 -276.969325)
			(xy 460.303127 -276.983606) (xy 460.310954 -277.002279) (xy 460.3115 -277.0124) (xy 460.3115 -277.42134)
			(xy 460.311111 -277.431497) (xy 460.303302 -277.45025) (xy 460.288896 -277.464572) (xy 460.270097 -277.47227)
			(xy 460.259938 -277.472648) (xy 458.860398 -277.472648) (xy 458.85027 -277.472175) (xy 458.831546 -277.464444)
			(xy 458.81719 -277.450153) (xy 458.809373 -277.431466) (xy 458.808836 -277.42134) (xy 452.7677 -277.42134)
			(xy 452.767311 -277.431497) (xy 452.759502 -277.45025) (xy 452.745096 -277.464572) (xy 452.726297 -277.47227)
			(xy 452.716138 -277.472648) (xy 451.316598 -277.472648) (xy 451.30647 -277.472175) (xy 451.287746 -277.464444)
			(xy 451.27339 -277.450153) (xy 451.265573 -277.431466) (xy 451.265036 -277.42134) (xy 445.2239 -277.42134)
			(xy 445.223511 -277.431497) (xy 445.215702 -277.45025) (xy 445.201296 -277.464572) (xy 445.182497 -277.47227)
			(xy 445.172338 -277.472648) (xy 443.772798 -277.472648) (xy 443.76267 -277.472175) (xy 443.743946 -277.464444)
			(xy 443.72959 -277.450153) (xy 443.721773 -277.431466) (xy 443.721236 -277.42134) (xy 437.6801 -277.42134)
			(xy 437.679711 -277.431497) (xy 437.671902 -277.45025) (xy 437.657496 -277.464572) (xy 437.638697 -277.47227)
			(xy 437.628538 -277.472648) (xy 436.228998 -277.472648) (xy 436.21887 -277.472175) (xy 436.200146 -277.464444)
			(xy 436.18579 -277.450153) (xy 436.177973 -277.431466) (xy 436.177436 -277.42134) (xy 430.1363 -277.42134)
			(xy 430.135911 -277.431497) (xy 430.128102 -277.45025) (xy 430.113696 -277.464572) (xy 430.094897 -277.47227)
			(xy 430.084738 -277.472648) (xy 428.685198 -277.472648) (xy 428.67507 -277.472175) (xy 428.656346 -277.464444)
			(xy 428.64199 -277.450153) (xy 428.634173 -277.431466) (xy 428.633636 -277.42134) (xy 422.5925 -277.42134)
			(xy 422.592111 -277.431497) (xy 422.584302 -277.45025) (xy 422.569896 -277.464572) (xy 422.551097 -277.47227)
			(xy 422.540938 -277.472648) (xy 421.141398 -277.472648) (xy 421.13127 -277.472175) (xy 421.112546 -277.464444)
			(xy 421.09819 -277.450153) (xy 421.090373 -277.431466) (xy 421.089836 -277.42134) (xy 415.0487 -277.42134)
			(xy 415.048311 -277.431497) (xy 415.040502 -277.45025) (xy 415.026096 -277.464572) (xy 415.007297 -277.47227)
			(xy 414.997138 -277.472648) (xy 413.597598 -277.472648) (xy 413.58747 -277.472175) (xy 413.568746 -277.464444)
			(xy 413.55439 -277.450153) (xy 413.546573 -277.431466) (xy 413.546036 -277.42134) (xy 407.5049 -277.42134)
			(xy 407.504511 -277.431497) (xy 407.496702 -277.45025) (xy 407.482296 -277.464572) (xy 407.463497 -277.47227)
			(xy 407.453338 -277.472648) (xy 406.053798 -277.472648) (xy 406.04367 -277.472175) (xy 406.024946 -277.464444)
			(xy 406.01059 -277.450153) (xy 406.002773 -277.431466) (xy 406.002236 -277.42134) (xy 357.654049 -277.42134)
			(xy 357.661834 -277.445297) (xy 357.669942 -277.496486) (xy 357.669942 -277.548314) (xy 357.661834 -277.599503)
			(xy 357.645817 -277.648794) (xy 357.622286 -277.694972) (xy 357.591821 -277.7369) (xy 357.555171 -277.773546)
			(xy 357.51324 -277.804006) (xy 357.467059 -277.827532) (xy 357.417766 -277.843543) (xy 357.366576 -277.851645)
			(xy 357.340662 -277.852124) (xy 357.31515 -277.851662) (xy 357.264735 -277.843796) (xy 357.216133 -277.828258)
			(xy 357.170505 -277.805419) (xy 357.12894 -277.775824) (xy 357.09243 -277.74018) (xy 357.076756 -277.720044)
			(xy 356.664768 -277.720044) (xy 356.649125 -277.740204) (xy 356.612608 -277.775845) (xy 356.571036 -277.805434)
			(xy 356.525401 -277.828266) (xy 356.476795 -277.843795) (xy 356.426376 -277.85165) (xy 356.400862 -277.852124)
			(xy 356.374959 -277.851549) (xy 356.323792 -277.843439) (xy 356.274523 -277.827426) (xy 356.228366 -277.803903)
			(xy 356.186456 -277.773449) (xy 356.149826 -277.736815) (xy 356.119377 -277.694902) (xy 356.09586 -277.648742)
			(xy 356.079852 -277.599471) (xy 356.071748 -277.548303) (xy 355.789963 -277.548303) (xy 355.789917 -277.550456)
			(xy 355.780726 -277.604717) (xy 355.772212 -277.63089) (xy 355.764592 -277.652988) (xy 355.969824 -278.008334)
			(xy 355.992684 -278.012652) (xy 356.017501 -278.017836) (xy 356.065277 -278.034792) (xy 356.109893 -278.058863)
			(xy 356.150297 -278.089482) (xy 356.185537 -278.125927) (xy 356.214781 -278.167338) (xy 356.23734 -278.212738)
			(xy 356.252681 -278.261056) (xy 356.254296 -278.271478) (xy 410.102304 -278.271478) (xy 410.102304 -277.862538)
			(xy 410.102794 -277.852373) (xy 410.11056 -277.833586) (xy 410.124925 -277.819201) (xy 410.143702 -277.811408)
			(xy 410.153866 -277.810976) (xy 411.553406 -277.810976) (xy 411.563583 -277.81136) (xy 411.582385 -277.819154)
			(xy 411.596771 -277.833552) (xy 411.604549 -277.852361) (xy 411.604968 -277.862538) (xy 411.604968 -278.271478)
			(xy 417.646104 -278.271478) (xy 417.646104 -277.862538) (xy 417.646594 -277.852373) (xy 417.65436 -277.833586)
			(xy 417.668725 -277.819201) (xy 417.687502 -277.811408) (xy 417.697666 -277.810976) (xy 419.097206 -277.810976)
			(xy 419.107383 -277.81136) (xy 419.126185 -277.819154) (xy 419.140571 -277.833552) (xy 419.148349 -277.852361)
			(xy 419.148768 -277.862538) (xy 419.148768 -278.271478) (xy 425.189904 -278.271478) (xy 425.189904 -277.862538)
			(xy 425.190394 -277.852373) (xy 425.19816 -277.833586) (xy 425.212525 -277.819201) (xy 425.231302 -277.811408)
			(xy 425.241466 -277.810976) (xy 426.641006 -277.810976) (xy 426.651183 -277.81136) (xy 426.669985 -277.819154)
			(xy 426.684371 -277.833552) (xy 426.692149 -277.852361) (xy 426.692568 -277.862538) (xy 426.692568 -278.271478)
			(xy 432.733704 -278.271478) (xy 432.733704 -277.862538) (xy 432.734194 -277.852373) (xy 432.74196 -277.833586)
			(xy 432.756325 -277.819201) (xy 432.775102 -277.811408) (xy 432.785266 -277.810976) (xy 434.184806 -277.810976)
			(xy 434.194983 -277.81136) (xy 434.213785 -277.819154) (xy 434.228171 -277.833552) (xy 434.235949 -277.852361)
			(xy 434.236368 -277.862538) (xy 434.236368 -278.271478) (xy 440.277504 -278.271478) (xy 440.277504 -277.862538)
			(xy 440.277994 -277.852373) (xy 440.28576 -277.833586) (xy 440.300125 -277.819201) (xy 440.318902 -277.811408)
			(xy 440.329066 -277.810976) (xy 441.728606 -277.810976) (xy 441.738783 -277.81136) (xy 441.757585 -277.819154)
			(xy 441.771971 -277.833552) (xy 441.779749 -277.852361) (xy 441.780168 -277.862538) (xy 441.780168 -278.271478)
			(xy 447.821304 -278.271478) (xy 447.821304 -277.862538) (xy 447.821794 -277.852373) (xy 447.82956 -277.833586)
			(xy 447.843925 -277.819201) (xy 447.862702 -277.811408) (xy 447.872866 -277.810976) (xy 449.272406 -277.810976)
			(xy 449.282583 -277.81136) (xy 449.301385 -277.819154) (xy 449.315771 -277.833552) (xy 449.323549 -277.852361)
			(xy 449.323968 -277.862538) (xy 449.323968 -278.271478) (xy 455.365104 -278.271478) (xy 455.365104 -277.862538)
			(xy 455.365594 -277.852373) (xy 455.37336 -277.833586) (xy 455.387725 -277.819201) (xy 455.406502 -277.811408)
			(xy 455.416666 -277.810976) (xy 456.816206 -277.810976) (xy 456.826383 -277.81136) (xy 456.845185 -277.819154)
			(xy 456.859571 -277.833552) (xy 456.867349 -277.852361) (xy 456.867768 -277.862538) (xy 456.867768 -278.271478)
			(xy 462.908904 -278.271478) (xy 462.908904 -277.862538) (xy 462.909394 -277.852373) (xy 462.91716 -277.833586)
			(xy 462.931525 -277.819201) (xy 462.950302 -277.811408) (xy 462.960466 -277.810976) (xy 464.360006 -277.810976)
			(xy 464.370183 -277.81136) (xy 464.388985 -277.819154) (xy 464.403371 -277.833552) (xy 464.411149 -277.852361)
			(xy 464.411568 -277.862538) (xy 464.411568 -278.271478) (xy 464.411118 -278.281647) (xy 464.403341 -278.30044)
			(xy 464.388964 -278.314826) (xy 464.370175 -278.322613) (xy 464.360006 -278.32304) (xy 462.960466 -278.32304)
			(xy 462.950303 -278.322594) (xy 462.931529 -278.314804) (xy 462.917164 -278.300424) (xy 462.909395 -278.281641)
			(xy 462.908904 -278.271478) (xy 456.867768 -278.271478) (xy 456.867318 -278.281647) (xy 456.859541 -278.30044)
			(xy 456.845164 -278.314826) (xy 456.826375 -278.322613) (xy 456.816206 -278.32304) (xy 455.416666 -278.32304)
			(xy 455.406503 -278.322594) (xy 455.387729 -278.314804) (xy 455.373364 -278.300424) (xy 455.365595 -278.281641)
			(xy 455.365104 -278.271478) (xy 449.323968 -278.271478) (xy 449.323518 -278.281647) (xy 449.315741 -278.30044)
			(xy 449.301364 -278.314826) (xy 449.282575 -278.322613) (xy 449.272406 -278.32304) (xy 447.872866 -278.32304)
			(xy 447.862703 -278.322594) (xy 447.843929 -278.314804) (xy 447.829564 -278.300424) (xy 447.821795 -278.281641)
			(xy 447.821304 -278.271478) (xy 441.780168 -278.271478) (xy 441.779718 -278.281647) (xy 441.771941 -278.30044)
			(xy 441.757564 -278.314826) (xy 441.738775 -278.322613) (xy 441.728606 -278.32304) (xy 440.329066 -278.32304)
			(xy 440.318903 -278.322594) (xy 440.300129 -278.314804) (xy 440.285764 -278.300424) (xy 440.277995 -278.281641)
			(xy 440.277504 -278.271478) (xy 434.236368 -278.271478) (xy 434.235918 -278.281647) (xy 434.228141 -278.30044)
			(xy 434.213764 -278.314826) (xy 434.194975 -278.322613) (xy 434.184806 -278.32304) (xy 432.785266 -278.32304)
			(xy 432.775103 -278.322594) (xy 432.756329 -278.314804) (xy 432.741964 -278.300424) (xy 432.734195 -278.281641)
			(xy 432.733704 -278.271478) (xy 426.692568 -278.271478) (xy 426.692118 -278.281647) (xy 426.684341 -278.30044)
			(xy 426.669964 -278.314826) (xy 426.651175 -278.322613) (xy 426.641006 -278.32304) (xy 425.241466 -278.32304)
			(xy 425.231303 -278.322594) (xy 425.212529 -278.314804) (xy 425.198164 -278.300424) (xy 425.190395 -278.281641)
			(xy 425.189904 -278.271478) (xy 419.148768 -278.271478) (xy 419.148318 -278.281647) (xy 419.140541 -278.30044)
			(xy 419.126164 -278.314826) (xy 419.107375 -278.322613) (xy 419.097206 -278.32304) (xy 417.697666 -278.32304)
			(xy 417.687503 -278.322594) (xy 417.668729 -278.314804) (xy 417.654364 -278.300424) (xy 417.646595 -278.281641)
			(xy 417.646104 -278.271478) (xy 411.604968 -278.271478) (xy 411.604518 -278.281647) (xy 411.596741 -278.30044)
			(xy 411.582364 -278.314826) (xy 411.563575 -278.322613) (xy 411.553406 -278.32304) (xy 410.153866 -278.32304)
			(xy 410.143703 -278.322594) (xy 410.124929 -278.314804) (xy 410.110564 -278.300424) (xy 410.102795 -278.281641)
			(xy 410.102304 -278.271478) (xy 356.254296 -278.271478) (xy 356.260443 -278.311154) (xy 356.260908 -278.336502)
			(xy 356.2604 -278.362409) (xy 356.252294 -278.413586) (xy 356.236282 -278.462865) (xy 356.212759 -278.509032)
			(xy 356.182303 -278.550951) (xy 356.145665 -278.587589) (xy 356.103746 -278.618045) (xy 356.057579 -278.641568)
			(xy 356.0083 -278.65758) (xy 355.957123 -278.665686) (xy 355.905309 -278.665686) (xy 355.854132 -278.65758)
			(xy 355.804853 -278.641568) (xy 355.758686 -278.618045) (xy 355.716767 -278.587589) (xy 355.680129 -278.550951)
			(xy 355.649673 -278.509032) (xy 355.62615 -278.462865) (xy 355.610138 -278.413586) (xy 355.602032 -278.362409)
			(xy 355.601524 -278.336502) (xy 355.602117 -278.308785) (xy 355.611441 -278.254138) (xy 355.620066 -278.22779)
			(xy 355.62794 -278.205692) (xy 355.422962 -277.8506) (xy 355.399848 -277.846282) (xy 355.375022 -277.841137)
			(xy 355.327241 -277.824181) (xy 355.282621 -277.800107) (xy 355.242213 -277.769484) (xy 355.206972 -277.733035)
			(xy 355.177729 -277.691618) (xy 355.155174 -277.646211) (xy 355.139838 -277.597886) (xy 355.132084 -277.547782)
			(xy 355.131624 -277.522432) (xy 354.8507 -277.522432) (xy 354.850192 -277.548319) (xy 354.842093 -277.599457)
			(xy 354.826094 -277.648697) (xy 354.802588 -277.694829) (xy 354.772156 -277.736716) (xy 354.735546 -277.773326)
			(xy 354.693659 -277.803758) (xy 354.647527 -277.827264) (xy 354.598287 -277.843263) (xy 354.547149 -277.851362)
			(xy 354.495375 -277.851362) (xy 354.444237 -277.843263) (xy 354.394997 -277.827264) (xy 354.348865 -277.803758)
			(xy 354.306978 -277.773326) (xy 354.270368 -277.736716) (xy 354.239936 -277.694829) (xy 354.21643 -277.648697)
			(xy 354.200431 -277.599457) (xy 354.192332 -277.548319) (xy 354.191824 -277.522432) (xy 352.0313 -277.522432)
			(xy 352.030792 -277.548319) (xy 352.022693 -277.599457) (xy 352.006694 -277.648697) (xy 351.983188 -277.694829)
			(xy 351.952756 -277.736716) (xy 351.916146 -277.773326) (xy 351.874259 -277.803758) (xy 351.828127 -277.827264)
			(xy 351.778887 -277.843263) (xy 351.727749 -277.851362) (xy 351.675975 -277.851362) (xy 351.624837 -277.843263)
			(xy 351.575597 -277.827264) (xy 351.529465 -277.803758) (xy 351.487578 -277.773326) (xy 351.450968 -277.736716)
			(xy 351.420536 -277.694829) (xy 351.39703 -277.648697) (xy 351.381031 -277.599457) (xy 351.372932 -277.548319)
			(xy 351.372424 -277.522432) (xy 351.37296 -277.494724) (xy 351.382151 -277.440077) (xy 351.390712 -277.41372)
			(xy 351.398586 -277.391622) (xy 351.193608 -277.036784) (xy 351.170748 -277.032466) (xy 351.145918 -277.027336)
			(xy 351.098136 -277.010379) (xy 351.053515 -276.986304) (xy 351.013107 -276.955679) (xy 350.977866 -276.919227)
			(xy 350.948624 -276.877808) (xy 350.926069 -276.8324) (xy 350.910735 -276.784072) (xy 350.902983 -276.733967)
			(xy 350.902524 -276.708616) (xy 350.6216 -276.708616) (xy 350.621092 -276.734503) (xy 350.612993 -276.785641)
			(xy 350.596994 -276.834881) (xy 350.573488 -276.881013) (xy 350.543056 -276.9229) (xy 350.506446 -276.95951)
			(xy 350.464559 -276.989942) (xy 350.418427 -277.013448) (xy 350.369187 -277.029447) (xy 350.318049 -277.037546)
			(xy 350.266275 -277.037546) (xy 350.215137 -277.029447) (xy 350.165897 -277.013448) (xy 350.119765 -276.989942)
			(xy 350.077878 -276.95951) (xy 350.041268 -276.9229) (xy 350.010836 -276.881013) (xy 349.98733 -276.834881)
			(xy 349.971331 -276.785641) (xy 349.963232 -276.734503) (xy 349.962724 -276.708616) (xy 109.260132 -276.708616)
			(xy 109.259624 -276.734503) (xy 109.251525 -276.785641) (xy 109.235526 -276.834881) (xy 109.21202 -276.881013)
			(xy 109.181588 -276.9229) (xy 109.144978 -276.95951) (xy 109.103091 -276.989942) (xy 109.056959 -277.013448)
			(xy 109.007719 -277.029447) (xy 108.956581 -277.037546) (xy 108.904807 -277.037546) (xy 108.853669 -277.029447)
			(xy 108.804429 -277.013448) (xy 108.758297 -276.989942) (xy 108.71641 -276.95951) (xy 108.6798 -276.9229)
			(xy 108.649368 -276.881013) (xy 108.625862 -276.834881) (xy 108.609863 -276.785641) (xy 108.601764 -276.734503)
			(xy 108.601256 -276.708616) (xy 107.38104 -276.708616) (xy 107.380628 -276.733993) (xy 107.372856 -276.784149)
			(xy 107.357482 -276.832518) (xy 107.334871 -276.877958) (xy 107.305557 -276.91939) (xy 107.270234 -276.955836)
			(xy 107.229739 -276.986433) (xy 107.18503 -277.010456) (xy 107.137166 -277.027337) (xy 107.112308 -277.032466)
			(xy 107.089448 -277.036784) (xy 106.88447 -277.391622) (xy 106.892344 -277.41372) (xy 106.90091 -277.440076)
			(xy 106.910105 -277.494723) (xy 106.910632 -277.522432) (xy 107.191556 -277.522432) (xy 107.192064 -277.496545)
			(xy 107.200163 -277.445407) (xy 107.216162 -277.396167) (xy 107.239668 -277.350035) (xy 107.2701 -277.308148)
			(xy 107.30671 -277.271538) (xy 107.348597 -277.241106) (xy 107.394729 -277.2176) (xy 107.443969 -277.201601)
			(xy 107.495107 -277.193502) (xy 107.546881 -277.193502) (xy 107.598019 -277.201601) (xy 107.647259 -277.2176)
			(xy 107.693391 -277.241106) (xy 107.735278 -277.271538) (xy 107.771888 -277.308148) (xy 107.80232 -277.350035)
			(xy 107.825826 -277.396167) (xy 107.841825 -277.445407) (xy 107.849924 -277.496545) (xy 107.850432 -277.522432)
			(xy 107.850432 -277.52294) (xy 107.849894 -277.548305) (xy 108.131648 -277.548305) (xy 108.131648 -277.496495)
			(xy 108.139753 -277.445324) (xy 108.155763 -277.396051) (xy 108.179283 -277.349889) (xy 108.209735 -277.307974)
			(xy 108.24637 -277.271339) (xy 108.288284 -277.240886) (xy 108.334445 -277.217365) (xy 108.383718 -277.201354)
			(xy 108.43489 -277.193249) (xy 108.460794 -277.19274) (xy 108.486306 -277.193209) (xy 108.536722 -277.20107)
			(xy 108.585325 -277.216605) (xy 108.630953 -277.239442) (xy 108.672518 -277.269037) (xy 108.709027 -277.304684)
			(xy 108.7247 -277.32482) (xy 109.136688 -277.32482) (xy 109.152374 -277.304695) (xy 109.18888 -277.269049)
			(xy 109.230443 -277.239454) (xy 109.276069 -277.216616) (xy 109.324669 -277.20108) (xy 109.375083 -277.193218)
			(xy 109.400594 -277.19274) (xy 109.426506 -277.193157) (xy 109.477693 -277.201263) (xy 109.526981 -277.217277)
			(xy 109.573157 -277.240805) (xy 109.615085 -277.271266) (xy 109.65173 -277.307911) (xy 109.682192 -277.349838)
			(xy 109.70572 -277.396013) (xy 109.713949 -277.42134) (xy 158.062168 -277.42134) (xy 158.062168 -277.0124)
			(xy 158.062621 -277.00225) (xy 158.070411 -276.983504) (xy 158.084797 -276.969182) (xy 158.103578 -276.961476)
			(xy 158.11373 -276.961092) (xy 159.51327 -276.961092) (xy 159.523389 -276.96165) (xy 159.5421 -276.969359)
			(xy 159.556456 -276.983623) (xy 159.564285 -277.002284) (xy 159.564832 -277.0124) (xy 159.564832 -277.42134)
			(xy 165.605968 -277.42134) (xy 165.605968 -277.0124) (xy 165.606421 -277.00225) (xy 165.614211 -276.983504)
			(xy 165.628597 -276.969182) (xy 165.647378 -276.961476) (xy 165.65753 -276.961092) (xy 167.05707 -276.961092)
			(xy 167.067189 -276.96165) (xy 167.0859 -276.969359) (xy 167.100256 -276.983623) (xy 167.108085 -277.002284)
			(xy 167.108632 -277.0124) (xy 167.108632 -277.42134) (xy 173.149768 -277.42134) (xy 173.149768 -277.0124)
			(xy 173.150221 -277.00225) (xy 173.158011 -276.983504) (xy 173.172397 -276.969182) (xy 173.191178 -276.961476)
			(xy 173.20133 -276.961092) (xy 174.60087 -276.961092) (xy 174.610989 -276.96165) (xy 174.6297 -276.969359)
			(xy 174.644056 -276.983623) (xy 174.651885 -277.002284) (xy 174.652432 -277.0124) (xy 174.652432 -277.42134)
			(xy 180.693568 -277.42134) (xy 180.693568 -277.0124) (xy 180.694021 -277.00225) (xy 180.701811 -276.983504)
			(xy 180.716197 -276.969182) (xy 180.734978 -276.961476) (xy 180.74513 -276.961092) (xy 182.14467 -276.961092)
			(xy 182.154789 -276.96165) (xy 182.1735 -276.969359) (xy 182.187856 -276.983623) (xy 182.195685 -277.002284)
			(xy 182.196232 -277.0124) (xy 182.196232 -277.42134) (xy 188.237368 -277.42134) (xy 188.237368 -277.0124)
			(xy 188.237821 -277.00225) (xy 188.245611 -276.983504) (xy 188.259997 -276.969182) (xy 188.278778 -276.961476)
			(xy 188.28893 -276.961092) (xy 189.68847 -276.961092) (xy 189.698589 -276.96165) (xy 189.7173 -276.969359)
			(xy 189.731656 -276.983623) (xy 189.739485 -277.002284) (xy 189.740032 -277.0124) (xy 189.740032 -277.42134)
			(xy 195.781168 -277.42134) (xy 195.781168 -277.0124) (xy 195.781621 -277.00225) (xy 195.789411 -276.983504)
			(xy 195.803797 -276.969182) (xy 195.822578 -276.961476) (xy 195.83273 -276.961092) (xy 197.23227 -276.961092)
			(xy 197.242389 -276.96165) (xy 197.2611 -276.969359) (xy 197.275456 -276.983623) (xy 197.283285 -277.002284)
			(xy 197.283832 -277.0124) (xy 197.283832 -277.42134) (xy 203.324968 -277.42134) (xy 203.324968 -277.0124)
			(xy 203.325421 -277.00225) (xy 203.333211 -276.983504) (xy 203.347597 -276.969182) (xy 203.366378 -276.961476)
			(xy 203.37653 -276.961092) (xy 204.77607 -276.961092) (xy 204.786189 -276.96165) (xy 204.8049 -276.969359)
			(xy 204.819256 -276.983623) (xy 204.827085 -277.002284) (xy 204.827632 -277.0124) (xy 204.827632 -277.42134)
			(xy 210.868768 -277.42134) (xy 210.868768 -277.0124) (xy 210.869221 -277.00225) (xy 210.877011 -276.983504)
			(xy 210.891397 -276.969182) (xy 210.910178 -276.961476) (xy 210.92033 -276.961092) (xy 212.31987 -276.961092)
			(xy 212.329989 -276.96165) (xy 212.3487 -276.969359) (xy 212.363056 -276.983623) (xy 212.370885 -277.002284)
			(xy 212.371432 -277.0124) (xy 212.371432 -277.42134) (xy 255.329436 -277.42134) (xy 255.329436 -277.0124)
			(xy 255.329822 -277.002241) (xy 255.337625 -276.983482) (xy 255.352033 -276.969157) (xy 255.370837 -276.961464)
			(xy 255.380998 -276.961092) (xy 256.780538 -276.961092) (xy 256.790661 -276.961594) (xy 256.809374 -276.969325)
			(xy 256.823727 -276.983606) (xy 256.831554 -277.002279) (xy 256.8321 -277.0124) (xy 256.8321 -277.42134)
			(xy 262.873236 -277.42134) (xy 262.873236 -277.0124) (xy 262.873622 -277.002241) (xy 262.881425 -276.983482)
			(xy 262.895833 -276.969157) (xy 262.914637 -276.961464) (xy 262.924798 -276.961092) (xy 264.324338 -276.961092)
			(xy 264.334461 -276.961594) (xy 264.353174 -276.969325) (xy 264.367527 -276.983606) (xy 264.375354 -277.002279)
			(xy 264.3759 -277.0124) (xy 264.3759 -277.42134) (xy 270.417036 -277.42134) (xy 270.417036 -277.0124)
			(xy 270.417422 -277.002241) (xy 270.425225 -276.983482) (xy 270.439633 -276.969157) (xy 270.458437 -276.961464)
			(xy 270.468598 -276.961092) (xy 271.868138 -276.961092) (xy 271.878261 -276.961594) (xy 271.896974 -276.969325)
			(xy 271.911327 -276.983606) (xy 271.919154 -277.002279) (xy 271.9197 -277.0124) (xy 271.9197 -277.42134)
			(xy 277.960836 -277.42134) (xy 277.960836 -277.0124) (xy 277.961222 -277.002241) (xy 277.969025 -276.983482)
			(xy 277.983433 -276.969157) (xy 278.002237 -276.961464) (xy 278.012398 -276.961092) (xy 279.411938 -276.961092)
			(xy 279.422061 -276.961594) (xy 279.440774 -276.969325) (xy 279.455127 -276.983606) (xy 279.462954 -277.002279)
			(xy 279.4635 -277.0124) (xy 279.4635 -277.42134) (xy 285.504636 -277.42134) (xy 285.504636 -277.0124)
			(xy 285.505022 -277.002241) (xy 285.512825 -276.983482) (xy 285.527233 -276.969157) (xy 285.546037 -276.961464)
			(xy 285.556198 -276.961092) (xy 286.955738 -276.961092) (xy 286.965861 -276.961594) (xy 286.984574 -276.969325)
			(xy 286.998927 -276.983606) (xy 287.006754 -277.002279) (xy 287.0073 -277.0124) (xy 287.0073 -277.42134)
			(xy 293.048436 -277.42134) (xy 293.048436 -277.0124) (xy 293.048822 -277.002241) (xy 293.056625 -276.983482)
			(xy 293.071033 -276.969157) (xy 293.089837 -276.961464) (xy 293.099998 -276.961092) (xy 294.499538 -276.961092)
			(xy 294.509661 -276.961594) (xy 294.528374 -276.969325) (xy 294.542727 -276.983606) (xy 294.550554 -277.002279)
			(xy 294.5511 -277.0124) (xy 294.5511 -277.42134) (xy 300.592236 -277.42134) (xy 300.592236 -277.0124)
			(xy 300.592622 -277.002241) (xy 300.600425 -276.983482) (xy 300.614833 -276.969157) (xy 300.633637 -276.961464)
			(xy 300.643798 -276.961092) (xy 302.043338 -276.961092) (xy 302.053461 -276.961594) (xy 302.072174 -276.969325)
			(xy 302.086527 -276.983606) (xy 302.094354 -277.002279) (xy 302.0949 -277.0124) (xy 302.0949 -277.42134)
			(xy 308.136036 -277.42134) (xy 308.136036 -277.0124) (xy 308.136422 -277.002241) (xy 308.144225 -276.983482)
			(xy 308.158633 -276.969157) (xy 308.177437 -276.961464) (xy 308.187598 -276.961092) (xy 309.587138 -276.961092)
			(xy 309.597261 -276.961594) (xy 309.615974 -276.969325) (xy 309.630327 -276.983606) (xy 309.638154 -277.002279)
			(xy 309.6387 -277.0124) (xy 309.6387 -277.42134) (xy 309.638311 -277.431497) (xy 309.630502 -277.45025)
			(xy 309.616096 -277.464572) (xy 309.597297 -277.47227) (xy 309.587138 -277.472648) (xy 308.187598 -277.472648)
			(xy 308.17747 -277.472175) (xy 308.158746 -277.464444) (xy 308.14439 -277.450153) (xy 308.136573 -277.431466)
			(xy 308.136036 -277.42134) (xy 302.0949 -277.42134) (xy 302.094511 -277.431497) (xy 302.086702 -277.45025)
			(xy 302.072296 -277.464572) (xy 302.053497 -277.47227) (xy 302.043338 -277.472648) (xy 300.643798 -277.472648)
			(xy 300.63367 -277.472175) (xy 300.614946 -277.464444) (xy 300.60059 -277.450153) (xy 300.592773 -277.431466)
			(xy 300.592236 -277.42134) (xy 294.5511 -277.42134) (xy 294.550711 -277.431497) (xy 294.542902 -277.45025)
			(xy 294.528496 -277.464572) (xy 294.509697 -277.47227) (xy 294.499538 -277.472648) (xy 293.099998 -277.472648)
			(xy 293.08987 -277.472175) (xy 293.071146 -277.464444) (xy 293.05679 -277.450153) (xy 293.048973 -277.431466)
			(xy 293.048436 -277.42134) (xy 287.0073 -277.42134) (xy 287.006911 -277.431497) (xy 286.999102 -277.45025)
			(xy 286.984696 -277.464572) (xy 286.965897 -277.47227) (xy 286.955738 -277.472648) (xy 285.556198 -277.472648)
			(xy 285.54607 -277.472175) (xy 285.527346 -277.464444) (xy 285.51299 -277.450153) (xy 285.505173 -277.431466)
			(xy 285.504636 -277.42134) (xy 279.4635 -277.42134) (xy 279.463111 -277.431497) (xy 279.455302 -277.45025)
			(xy 279.440896 -277.464572) (xy 279.422097 -277.47227) (xy 279.411938 -277.472648) (xy 278.012398 -277.472648)
			(xy 278.00227 -277.472175) (xy 277.983546 -277.464444) (xy 277.96919 -277.450153) (xy 277.961373 -277.431466)
			(xy 277.960836 -277.42134) (xy 271.9197 -277.42134) (xy 271.919311 -277.431497) (xy 271.911502 -277.45025)
			(xy 271.897096 -277.464572) (xy 271.878297 -277.47227) (xy 271.868138 -277.472648) (xy 270.468598 -277.472648)
			(xy 270.45847 -277.472175) (xy 270.439746 -277.464444) (xy 270.42539 -277.450153) (xy 270.417573 -277.431466)
			(xy 270.417036 -277.42134) (xy 264.3759 -277.42134) (xy 264.375511 -277.431497) (xy 264.367702 -277.45025)
			(xy 264.353296 -277.464572) (xy 264.334497 -277.47227) (xy 264.324338 -277.472648) (xy 262.924798 -277.472648)
			(xy 262.91467 -277.472175) (xy 262.895946 -277.464444) (xy 262.88159 -277.450153) (xy 262.873773 -277.431466)
			(xy 262.873236 -277.42134) (xy 256.8321 -277.42134) (xy 256.831711 -277.431497) (xy 256.823902 -277.45025)
			(xy 256.809496 -277.464572) (xy 256.790697 -277.47227) (xy 256.780538 -277.472648) (xy 255.380998 -277.472648)
			(xy 255.37087 -277.472175) (xy 255.352146 -277.464444) (xy 255.33779 -277.450153) (xy 255.329973 -277.431466)
			(xy 255.329436 -277.42134) (xy 212.371432 -277.42134) (xy 212.371012 -277.431493) (xy 212.363209 -277.45024)
			(xy 212.348813 -277.464561) (xy 212.330025 -277.472265) (xy 212.31987 -277.472648) (xy 210.92033 -277.472648)
			(xy 210.910204 -277.472149) (xy 210.891481 -277.464429) (xy 210.877123 -277.450146) (xy 210.869305 -277.431464)
			(xy 210.868768 -277.42134) (xy 204.827632 -277.42134) (xy 204.827212 -277.431493) (xy 204.819409 -277.45024)
			(xy 204.805013 -277.464561) (xy 204.786225 -277.472265) (xy 204.77607 -277.472648) (xy 203.37653 -277.472648)
			(xy 203.366404 -277.472149) (xy 203.347681 -277.464429) (xy 203.333323 -277.450146) (xy 203.325505 -277.431464)
			(xy 203.324968 -277.42134) (xy 197.283832 -277.42134) (xy 197.283412 -277.431493) (xy 197.275609 -277.45024)
			(xy 197.261213 -277.464561) (xy 197.242425 -277.472265) (xy 197.23227 -277.472648) (xy 195.83273 -277.472648)
			(xy 195.822604 -277.472149) (xy 195.803881 -277.464429) (xy 195.789523 -277.450146) (xy 195.781705 -277.431464)
			(xy 195.781168 -277.42134) (xy 189.740032 -277.42134) (xy 189.739612 -277.431493) (xy 189.731809 -277.45024)
			(xy 189.717413 -277.464561) (xy 189.698625 -277.472265) (xy 189.68847 -277.472648) (xy 188.28893 -277.472648)
			(xy 188.278804 -277.472149) (xy 188.260081 -277.464429) (xy 188.245723 -277.450146) (xy 188.237905 -277.431464)
			(xy 188.237368 -277.42134) (xy 182.196232 -277.42134) (xy 182.195812 -277.431493) (xy 182.188009 -277.45024)
			(xy 182.173613 -277.464561) (xy 182.154825 -277.472265) (xy 182.14467 -277.472648) (xy 180.74513 -277.472648)
			(xy 180.735004 -277.472149) (xy 180.716281 -277.464429) (xy 180.701923 -277.450146) (xy 180.694105 -277.431464)
			(xy 180.693568 -277.42134) (xy 174.652432 -277.42134) (xy 174.652012 -277.431493) (xy 174.644209 -277.45024)
			(xy 174.629813 -277.464561) (xy 174.611025 -277.472265) (xy 174.60087 -277.472648) (xy 173.20133 -277.472648)
			(xy 173.191204 -277.472149) (xy 173.172481 -277.464429) (xy 173.158123 -277.450146) (xy 173.150305 -277.431464)
			(xy 173.149768 -277.42134) (xy 167.108632 -277.42134) (xy 167.108212 -277.431493) (xy 167.100409 -277.45024)
			(xy 167.086013 -277.464561) (xy 167.067225 -277.472265) (xy 167.05707 -277.472648) (xy 165.65753 -277.472648)
			(xy 165.647404 -277.472149) (xy 165.628681 -277.464429) (xy 165.614323 -277.450146) (xy 165.606505 -277.431464)
			(xy 165.605968 -277.42134) (xy 159.564832 -277.42134) (xy 159.564412 -277.431493) (xy 159.556609 -277.45024)
			(xy 159.542213 -277.464561) (xy 159.523425 -277.472265) (xy 159.51327 -277.472648) (xy 158.11373 -277.472648)
			(xy 158.103604 -277.472149) (xy 158.084881 -277.464429) (xy 158.070523 -277.450146) (xy 158.062705 -277.431464)
			(xy 158.062168 -277.42134) (xy 109.713949 -277.42134) (xy 109.721735 -277.445301) (xy 109.729842 -277.496488)
			(xy 109.729842 -277.548312) (xy 109.721735 -277.599499) (xy 109.70572 -277.648787) (xy 109.682192 -277.694962)
			(xy 109.65173 -277.736889) (xy 109.615085 -277.773534) (xy 109.573157 -277.803995) (xy 109.526981 -277.827523)
			(xy 109.477693 -277.843537) (xy 109.426506 -277.851643) (xy 109.400594 -277.852124) (xy 109.375083 -277.851639)
			(xy 109.324669 -277.843778) (xy 109.276068 -277.828245) (xy 109.230439 -277.80541) (xy 109.188874 -277.775819)
			(xy 109.152362 -277.740178) (xy 109.136688 -277.720044) (xy 108.7247 -277.720044) (xy 108.709039 -277.740189)
			(xy 108.672525 -277.77583) (xy 108.630957 -277.805422) (xy 108.585326 -277.828256) (xy 108.536723 -277.843788)
			(xy 108.486307 -277.851647) (xy 108.460794 -277.852124) (xy 108.43489 -277.851551) (xy 108.383718 -277.843446)
			(xy 108.334445 -277.827435) (xy 108.288284 -277.803914) (xy 108.24637 -277.773461) (xy 108.209735 -277.736826)
			(xy 108.179283 -277.694911) (xy 108.155763 -277.648749) (xy 108.139753 -277.599476) (xy 108.131648 -277.548305)
			(xy 107.849894 -277.548305) (xy 107.849848 -277.550456) (xy 107.840658 -277.604717) (xy 107.832144 -277.63089)
			(xy 107.824524 -277.652988) (xy 108.029756 -278.008334) (xy 108.052616 -278.012652) (xy 108.077422 -278.017885)
			(xy 108.125198 -278.034831) (xy 108.169815 -278.058894) (xy 108.210222 -278.089506) (xy 108.245463 -278.125945)
			(xy 108.27471 -278.16735) (xy 108.29727 -278.212746) (xy 108.312612 -278.261061) (xy 108.314226 -278.271478)
			(xy 162.162236 -278.271478) (xy 162.162236 -277.862538) (xy 162.162695 -277.852369) (xy 162.170467 -277.833576)
			(xy 162.184842 -277.81919) (xy 162.203629 -277.811403) (xy 162.213798 -277.810976) (xy 163.613338 -277.810976)
			(xy 163.623503 -277.811403) (xy 163.64228 -277.819197) (xy 163.656645 -277.833584) (xy 163.664412 -277.852372)
			(xy 163.6649 -277.862538) (xy 163.6649 -278.271478) (xy 169.706036 -278.271478) (xy 169.706036 -277.862538)
			(xy 169.706495 -277.852369) (xy 169.714267 -277.833576) (xy 169.728642 -277.81919) (xy 169.747429 -277.811403)
			(xy 169.757598 -277.810976) (xy 171.157138 -277.810976) (xy 171.167303 -277.811403) (xy 171.18608 -277.819197)
			(xy 171.200445 -277.833584) (xy 171.208212 -277.852372) (xy 171.2087 -277.862538) (xy 171.2087 -278.271478)
			(xy 177.249836 -278.271478) (xy 177.249836 -277.862538) (xy 177.250295 -277.852369) (xy 177.258067 -277.833576)
			(xy 177.272442 -277.81919) (xy 177.291229 -277.811403) (xy 177.301398 -277.810976) (xy 178.700938 -277.810976)
			(xy 178.711103 -277.811403) (xy 178.72988 -277.819197) (xy 178.744245 -277.833584) (xy 178.752012 -277.852372)
			(xy 178.7525 -277.862538) (xy 178.7525 -278.271478) (xy 184.793636 -278.271478) (xy 184.793636 -277.862538)
			(xy 184.794095 -277.852369) (xy 184.801867 -277.833576) (xy 184.816242 -277.81919) (xy 184.835029 -277.811403)
			(xy 184.845198 -277.810976) (xy 186.244738 -277.810976) (xy 186.254903 -277.811403) (xy 186.27368 -277.819197)
			(xy 186.288045 -277.833584) (xy 186.295812 -277.852372) (xy 186.2963 -277.862538) (xy 186.2963 -278.271478)
			(xy 192.337436 -278.271478) (xy 192.337436 -277.862538) (xy 192.337895 -277.852369) (xy 192.345667 -277.833576)
			(xy 192.360042 -277.81919) (xy 192.378829 -277.811403) (xy 192.388998 -277.810976) (xy 193.788538 -277.810976)
			(xy 193.798703 -277.811403) (xy 193.81748 -277.819197) (xy 193.831845 -277.833584) (xy 193.839612 -277.852372)
			(xy 193.8401 -277.862538) (xy 193.8401 -278.271478) (xy 199.881236 -278.271478) (xy 199.881236 -277.862538)
			(xy 199.881695 -277.852369) (xy 199.889467 -277.833576) (xy 199.903842 -277.81919) (xy 199.922629 -277.811403)
			(xy 199.932798 -277.810976) (xy 201.332338 -277.810976) (xy 201.342503 -277.811403) (xy 201.36128 -277.819197)
			(xy 201.375645 -277.833584) (xy 201.383412 -277.852372) (xy 201.3839 -277.862538) (xy 201.3839 -278.271478)
			(xy 207.425036 -278.271478) (xy 207.425036 -277.862538) (xy 207.425495 -277.852369) (xy 207.433267 -277.833576)
			(xy 207.447642 -277.81919) (xy 207.466429 -277.811403) (xy 207.476598 -277.810976) (xy 208.876138 -277.810976)
			(xy 208.886303 -277.811403) (xy 208.90508 -277.819197) (xy 208.919445 -277.833584) (xy 208.927212 -277.852372)
			(xy 208.9277 -277.862538) (xy 208.9277 -278.271478) (xy 214.968836 -278.271478) (xy 214.968836 -277.862538)
			(xy 214.969295 -277.852369) (xy 214.977067 -277.833576) (xy 214.991442 -277.81919) (xy 215.010229 -277.811403)
			(xy 215.020398 -277.810976) (xy 216.419938 -277.810976) (xy 216.430103 -277.811403) (xy 216.44888 -277.819197)
			(xy 216.463245 -277.833584) (xy 216.471012 -277.852372) (xy 216.4715 -277.862538) (xy 216.4715 -278.271478)
			(xy 259.429504 -278.271478) (xy 259.429504 -277.862538) (xy 259.429994 -277.852373) (xy 259.43776 -277.833586)
			(xy 259.452125 -277.819201) (xy 259.470902 -277.811408) (xy 259.481066 -277.810976) (xy 260.880606 -277.810976)
			(xy 260.890783 -277.81136) (xy 260.909585 -277.819154) (xy 260.923971 -277.833552) (xy 260.931749 -277.852361)
			(xy 260.932168 -277.862538) (xy 260.932168 -278.271478) (xy 266.973304 -278.271478) (xy 266.973304 -277.862538)
			(xy 266.973794 -277.852373) (xy 266.98156 -277.833586) (xy 266.995925 -277.819201) (xy 267.014702 -277.811408)
			(xy 267.024866 -277.810976) (xy 268.424406 -277.810976) (xy 268.434583 -277.81136) (xy 268.453385 -277.819154)
			(xy 268.467771 -277.833552) (xy 268.475549 -277.852361) (xy 268.475968 -277.862538) (xy 268.475968 -278.271478)
			(xy 274.517104 -278.271478) (xy 274.517104 -277.862538) (xy 274.517594 -277.852373) (xy 274.52536 -277.833586)
			(xy 274.539725 -277.819201) (xy 274.558502 -277.811408) (xy 274.568666 -277.810976) (xy 275.968206 -277.810976)
			(xy 275.978383 -277.81136) (xy 275.997185 -277.819154) (xy 276.011571 -277.833552) (xy 276.019349 -277.852361)
			(xy 276.019768 -277.862538) (xy 276.019768 -278.271478) (xy 282.060904 -278.271478) (xy 282.060904 -277.862538)
			(xy 282.061394 -277.852373) (xy 282.06916 -277.833586) (xy 282.083525 -277.819201) (xy 282.102302 -277.811408)
			(xy 282.112466 -277.810976) (xy 283.512006 -277.810976) (xy 283.522183 -277.81136) (xy 283.540985 -277.819154)
			(xy 283.555371 -277.833552) (xy 283.563149 -277.852361) (xy 283.563568 -277.862538) (xy 283.563568 -278.271478)
			(xy 289.604704 -278.271478) (xy 289.604704 -277.862538) (xy 289.605194 -277.852373) (xy 289.61296 -277.833586)
			(xy 289.627325 -277.819201) (xy 289.646102 -277.811408) (xy 289.656266 -277.810976) (xy 291.055806 -277.810976)
			(xy 291.065983 -277.81136) (xy 291.084785 -277.819154) (xy 291.099171 -277.833552) (xy 291.106949 -277.852361)
			(xy 291.107368 -277.862538) (xy 291.107368 -278.271478) (xy 297.148504 -278.271478) (xy 297.148504 -277.862538)
			(xy 297.148994 -277.852373) (xy 297.15676 -277.833586) (xy 297.171125 -277.819201) (xy 297.189902 -277.811408)
			(xy 297.200066 -277.810976) (xy 298.599606 -277.810976) (xy 298.609783 -277.81136) (xy 298.628585 -277.819154)
			(xy 298.642971 -277.833552) (xy 298.650749 -277.852361) (xy 298.651168 -277.862538) (xy 298.651168 -278.271478)
			(xy 304.692304 -278.271478) (xy 304.692304 -277.862538) (xy 304.692794 -277.852373) (xy 304.70056 -277.833586)
			(xy 304.714925 -277.819201) (xy 304.733702 -277.811408) (xy 304.743866 -277.810976) (xy 306.143406 -277.810976)
			(xy 306.153583 -277.81136) (xy 306.172385 -277.819154) (xy 306.186771 -277.833552) (xy 306.194549 -277.852361)
			(xy 306.194968 -277.862538) (xy 306.194968 -278.271478) (xy 312.236104 -278.271478) (xy 312.236104 -277.862538)
			(xy 312.236594 -277.852373) (xy 312.24436 -277.833586) (xy 312.258725 -277.819201) (xy 312.277502 -277.811408)
			(xy 312.287666 -277.810976) (xy 313.687206 -277.810976) (xy 313.697383 -277.81136) (xy 313.716185 -277.819154)
			(xy 313.730571 -277.833552) (xy 313.738349 -277.852361) (xy 313.738768 -277.862538) (xy 313.738768 -278.271478)
			(xy 313.738318 -278.281647) (xy 313.730541 -278.30044) (xy 313.716164 -278.314826) (xy 313.697375 -278.322613)
			(xy 313.687206 -278.32304) (xy 312.287666 -278.32304) (xy 312.277503 -278.322594) (xy 312.258729 -278.314804)
			(xy 312.244364 -278.300424) (xy 312.236595 -278.281641) (xy 312.236104 -278.271478) (xy 306.194968 -278.271478)
			(xy 306.194518 -278.281647) (xy 306.186741 -278.30044) (xy 306.172364 -278.314826) (xy 306.153575 -278.322613)
			(xy 306.143406 -278.32304) (xy 304.743866 -278.32304) (xy 304.733703 -278.322594) (xy 304.714929 -278.314804)
			(xy 304.700564 -278.300424) (xy 304.692795 -278.281641) (xy 304.692304 -278.271478) (xy 298.651168 -278.271478)
			(xy 298.650718 -278.281647) (xy 298.642941 -278.30044) (xy 298.628564 -278.314826) (xy 298.609775 -278.322613)
			(xy 298.599606 -278.32304) (xy 297.200066 -278.32304) (xy 297.189903 -278.322594) (xy 297.171129 -278.314804)
			(xy 297.156764 -278.300424) (xy 297.148995 -278.281641) (xy 297.148504 -278.271478) (xy 291.107368 -278.271478)
			(xy 291.106918 -278.281647) (xy 291.099141 -278.30044) (xy 291.084764 -278.314826) (xy 291.065975 -278.322613)
			(xy 291.055806 -278.32304) (xy 289.656266 -278.32304) (xy 289.646103 -278.322594) (xy 289.627329 -278.314804)
			(xy 289.612964 -278.300424) (xy 289.605195 -278.281641) (xy 289.604704 -278.271478) (xy 283.563568 -278.271478)
			(xy 283.563118 -278.281647) (xy 283.555341 -278.30044) (xy 283.540964 -278.314826) (xy 283.522175 -278.322613)
			(xy 283.512006 -278.32304) (xy 282.112466 -278.32304) (xy 282.102303 -278.322594) (xy 282.083529 -278.314804)
			(xy 282.069164 -278.300424) (xy 282.061395 -278.281641) (xy 282.060904 -278.271478) (xy 276.019768 -278.271478)
			(xy 276.019318 -278.281647) (xy 276.011541 -278.30044) (xy 275.997164 -278.314826) (xy 275.978375 -278.322613)
			(xy 275.968206 -278.32304) (xy 274.568666 -278.32304) (xy 274.558503 -278.322594) (xy 274.539729 -278.314804)
			(xy 274.525364 -278.300424) (xy 274.517595 -278.281641) (xy 274.517104 -278.271478) (xy 268.475968 -278.271478)
			(xy 268.475518 -278.281647) (xy 268.467741 -278.30044) (xy 268.453364 -278.314826) (xy 268.434575 -278.322613)
			(xy 268.424406 -278.32304) (xy 267.024866 -278.32304) (xy 267.014703 -278.322594) (xy 266.995929 -278.314804)
			(xy 266.981564 -278.300424) (xy 266.973795 -278.281641) (xy 266.973304 -278.271478) (xy 260.932168 -278.271478)
			(xy 260.931718 -278.281647) (xy 260.923941 -278.30044) (xy 260.909564 -278.314826) (xy 260.890775 -278.322613)
			(xy 260.880606 -278.32304) (xy 259.481066 -278.32304) (xy 259.470903 -278.322594) (xy 259.452129 -278.314804)
			(xy 259.437764 -278.300424) (xy 259.429995 -278.281641) (xy 259.429504 -278.271478) (xy 216.4715 -278.271478)
			(xy 216.47095 -278.28163) (xy 216.46319 -278.300391) (xy 216.448842 -278.314756) (xy 216.430089 -278.322538)
			(xy 216.419938 -278.32304) (xy 215.020398 -278.32304) (xy 215.010224 -278.322637) (xy 214.991425 -278.314847)
			(xy 214.977039 -278.300455) (xy 214.969258 -278.281653) (xy 214.968836 -278.271478) (xy 208.9277 -278.271478)
			(xy 208.92715 -278.28163) (xy 208.91939 -278.300391) (xy 208.905042 -278.314756) (xy 208.886289 -278.322538)
			(xy 208.876138 -278.32304) (xy 207.476598 -278.32304) (xy 207.466424 -278.322637) (xy 207.447625 -278.314847)
			(xy 207.433239 -278.300455) (xy 207.425458 -278.281653) (xy 207.425036 -278.271478) (xy 201.3839 -278.271478)
			(xy 201.38335 -278.28163) (xy 201.37559 -278.300391) (xy 201.361242 -278.314756) (xy 201.342489 -278.322538)
			(xy 201.332338 -278.32304) (xy 199.932798 -278.32304) (xy 199.922624 -278.322637) (xy 199.903825 -278.314847)
			(xy 199.889439 -278.300455) (xy 199.881658 -278.281653) (xy 199.881236 -278.271478) (xy 193.8401 -278.271478)
			(xy 193.83955 -278.28163) (xy 193.83179 -278.300391) (xy 193.817442 -278.314756) (xy 193.798689 -278.322538)
			(xy 193.788538 -278.32304) (xy 192.388998 -278.32304) (xy 192.378824 -278.322637) (xy 192.360025 -278.314847)
			(xy 192.345639 -278.300455) (xy 192.337858 -278.281653) (xy 192.337436 -278.271478) (xy 186.2963 -278.271478)
			(xy 186.29575 -278.28163) (xy 186.28799 -278.300391) (xy 186.273642 -278.314756) (xy 186.254889 -278.322538)
			(xy 186.244738 -278.32304) (xy 184.845198 -278.32304) (xy 184.835024 -278.322637) (xy 184.816225 -278.314847)
			(xy 184.801839 -278.300455) (xy 184.794058 -278.281653) (xy 184.793636 -278.271478) (xy 178.7525 -278.271478)
			(xy 178.75195 -278.28163) (xy 178.74419 -278.300391) (xy 178.729842 -278.314756) (xy 178.711089 -278.322538)
			(xy 178.700938 -278.32304) (xy 177.301398 -278.32304) (xy 177.291224 -278.322637) (xy 177.272425 -278.314847)
			(xy 177.258039 -278.300455) (xy 177.250258 -278.281653) (xy 177.249836 -278.271478) (xy 171.2087 -278.271478)
			(xy 171.20815 -278.28163) (xy 171.20039 -278.300391) (xy 171.186042 -278.314756) (xy 171.167289 -278.322538)
			(xy 171.157138 -278.32304) (xy 169.757598 -278.32304) (xy 169.747424 -278.322637) (xy 169.728625 -278.314847)
			(xy 169.714239 -278.300455) (xy 169.706458 -278.281653) (xy 169.706036 -278.271478) (xy 163.6649 -278.271478)
			(xy 163.66435 -278.28163) (xy 163.65659 -278.300391) (xy 163.642242 -278.314756) (xy 163.623489 -278.322538)
			(xy 163.613338 -278.32304) (xy 162.213798 -278.32304) (xy 162.203624 -278.322637) (xy 162.184825 -278.314847)
			(xy 162.170439 -278.300455) (xy 162.162658 -278.281653) (xy 162.162236 -278.271478) (xy 108.314226 -278.271478)
			(xy 108.320375 -278.311156) (xy 108.32084 -278.336502) (xy 108.320332 -278.362409) (xy 108.312226 -278.413586)
			(xy 108.296214 -278.462865) (xy 108.272691 -278.509032) (xy 108.242235 -278.550951) (xy 108.205597 -278.587589)
			(xy 108.163678 -278.618045) (xy 108.117511 -278.641568) (xy 108.068232 -278.65758) (xy 108.017055 -278.665686)
			(xy 107.965241 -278.665686) (xy 107.914064 -278.65758) (xy 107.864785 -278.641568) (xy 107.818618 -278.618045)
			(xy 107.776699 -278.587589) (xy 107.740061 -278.550951) (xy 107.709605 -278.509032) (xy 107.686082 -278.462865)
			(xy 107.67007 -278.413586) (xy 107.661964 -278.362409) (xy 107.661456 -278.336502) (xy 107.662047 -278.308784)
			(xy 107.671372 -278.254138) (xy 107.679998 -278.22779) (xy 107.687872 -278.205692) (xy 107.482894 -277.8506)
			(xy 107.45978 -277.846282) (xy 107.434959 -277.841114) (xy 107.387178 -277.824162) (xy 107.342557 -277.800093)
			(xy 107.302149 -277.769473) (xy 107.266907 -277.733026) (xy 107.237663 -277.691612) (xy 107.215107 -277.646207)
			(xy 107.199771 -277.597884) (xy 107.192016 -277.547781) (xy 107.191556 -277.522432) (xy 106.910632 -277.522432)
			(xy 106.910124 -277.548319) (xy 106.902025 -277.599457) (xy 106.886026 -277.648697) (xy 106.86252 -277.694829)
			(xy 106.832088 -277.736716) (xy 106.795478 -277.773326) (xy 106.753591 -277.803758) (xy 106.707459 -277.827264)
			(xy 106.658219 -277.843263) (xy 106.607081 -277.851362) (xy 106.555307 -277.851362) (xy 106.504169 -277.843263)
			(xy 106.454929 -277.827264) (xy 106.408797 -277.803758) (xy 106.36691 -277.773326) (xy 106.3303 -277.736716)
			(xy 106.299868 -277.694829) (xy 106.276362 -277.648697) (xy 106.260363 -277.599457) (xy 106.252264 -277.548319)
			(xy 106.251756 -277.522432) (xy 104.091232 -277.522432) (xy 104.090724 -277.548319) (xy 104.082625 -277.599457)
			(xy 104.066626 -277.648697) (xy 104.04312 -277.694829) (xy 104.012688 -277.736716) (xy 103.976078 -277.773326)
			(xy 103.934191 -277.803758) (xy 103.888059 -277.827264) (xy 103.838819 -277.843263) (xy 103.787681 -277.851362)
			(xy 103.735907 -277.851362) (xy 103.684769 -277.843263) (xy 103.635529 -277.827264) (xy 103.589397 -277.803758)
			(xy 103.54751 -277.773326) (xy 103.5109 -277.736716) (xy 103.480468 -277.694829) (xy 103.456962 -277.648697)
			(xy 103.440963 -277.599457) (xy 103.432864 -277.548319) (xy 103.432356 -277.522432) (xy 103.432895 -277.494724)
			(xy 103.442084 -277.440078) (xy 103.450644 -277.41372) (xy 103.458518 -277.391622) (xy 103.25354 -277.036784)
			(xy 103.23068 -277.032466) (xy 103.205855 -277.027313) (xy 103.158073 -277.01036) (xy 103.113452 -276.986289)
			(xy 103.073043 -276.955668) (xy 103.037801 -276.919219) (xy 103.008557 -276.877803) (xy 102.986002 -276.832396)
			(xy 102.970667 -276.78407) (xy 102.962915 -276.733966) (xy 102.962456 -276.708616) (xy 102.681532 -276.708616)
			(xy 102.681024 -276.734503) (xy 102.672925 -276.785641) (xy 102.656926 -276.834881) (xy 102.63342 -276.881013)
			(xy 102.602988 -276.9229) (xy 102.566378 -276.95951) (xy 102.524491 -276.989942) (xy 102.478359 -277.013448)
			(xy 102.429119 -277.029447) (xy 102.377981 -277.037546) (xy 102.326207 -277.037546) (xy 102.275069 -277.029447)
			(xy 102.225829 -277.013448) (xy 102.179697 -276.989942) (xy 102.13781 -276.95951) (xy 102.1012 -276.9229)
			(xy 102.070768 -276.881013) (xy 102.047262 -276.834881) (xy 102.031263 -276.785641) (xy 102.023164 -276.734503)
			(xy 102.022656 -276.708616) (xy 2.509012 -276.708616) (xy 2.509012 -277.42134) (xy 7.389368 -277.42134)
			(xy 7.389368 -277.0124) (xy 7.389821 -277.00225) (xy 7.397611 -276.983504) (xy 7.411997 -276.969182)
			(xy 7.430778 -276.961476) (xy 7.44093 -276.961092) (xy 8.84047 -276.961092) (xy 8.850589 -276.96165)
			(xy 8.8693 -276.969359) (xy 8.883656 -276.983623) (xy 8.891485 -277.002284) (xy 8.892032 -277.0124)
			(xy 8.892032 -277.42134) (xy 14.933168 -277.42134) (xy 14.933168 -277.0124) (xy 14.933621 -277.00225)
			(xy 14.941411 -276.983504) (xy 14.955797 -276.969182) (xy 14.974578 -276.961476) (xy 14.98473 -276.961092)
			(xy 16.38427 -276.961092) (xy 16.394389 -276.96165) (xy 16.4131 -276.969359) (xy 16.427456 -276.983623)
			(xy 16.435285 -277.002284) (xy 16.435832 -277.0124) (xy 16.435832 -277.42134) (xy 22.476968 -277.42134)
			(xy 22.476968 -277.0124) (xy 22.477421 -277.00225) (xy 22.485211 -276.983504) (xy 22.499597 -276.969182)
			(xy 22.518378 -276.961476) (xy 22.52853 -276.961092) (xy 23.92807 -276.961092) (xy 23.938189 -276.96165)
			(xy 23.9569 -276.969359) (xy 23.971256 -276.983623) (xy 23.979085 -277.002284) (xy 23.979632 -277.0124)
			(xy 23.979632 -277.42134) (xy 30.020768 -277.42134) (xy 30.020768 -277.0124) (xy 30.021221 -277.00225)
			(xy 30.029011 -276.983504) (xy 30.043397 -276.969182) (xy 30.062178 -276.961476) (xy 30.07233 -276.961092)
			(xy 31.47187 -276.961092) (xy 31.481989 -276.96165) (xy 31.5007 -276.969359) (xy 31.515056 -276.983623)
			(xy 31.522885 -277.002284) (xy 31.523432 -277.0124) (xy 31.523432 -277.42134) (xy 37.564568 -277.42134)
			(xy 37.564568 -277.0124) (xy 37.565021 -277.00225) (xy 37.572811 -276.983504) (xy 37.587197 -276.969182)
			(xy 37.605978 -276.961476) (xy 37.61613 -276.961092) (xy 39.01567 -276.961092) (xy 39.025789 -276.96165)
			(xy 39.0445 -276.969359) (xy 39.058856 -276.983623) (xy 39.066685 -277.002284) (xy 39.067232 -277.0124)
			(xy 39.067232 -277.42134) (xy 45.108368 -277.42134) (xy 45.108368 -277.0124) (xy 45.108821 -277.00225)
			(xy 45.116611 -276.983504) (xy 45.130997 -276.969182) (xy 45.149778 -276.961476) (xy 45.15993 -276.961092)
			(xy 46.55947 -276.961092) (xy 46.569589 -276.96165) (xy 46.5883 -276.969359) (xy 46.602656 -276.983623)
			(xy 46.610485 -277.002284) (xy 46.611032 -277.0124) (xy 46.611032 -277.42134) (xy 52.652168 -277.42134)
			(xy 52.652168 -277.0124) (xy 52.652621 -277.00225) (xy 52.660411 -276.983504) (xy 52.674797 -276.969182)
			(xy 52.693578 -276.961476) (xy 52.70373 -276.961092) (xy 54.10327 -276.961092) (xy 54.113389 -276.96165)
			(xy 54.1321 -276.969359) (xy 54.146456 -276.983623) (xy 54.154285 -277.002284) (xy 54.154832 -277.0124)
			(xy 54.154832 -277.42134) (xy 60.195968 -277.42134) (xy 60.195968 -277.0124) (xy 60.196421 -277.00225)
			(xy 60.204211 -276.983504) (xy 60.218597 -276.969182) (xy 60.237378 -276.961476) (xy 60.24753 -276.961092)
			(xy 61.64707 -276.961092) (xy 61.657189 -276.96165) (xy 61.6759 -276.969359) (xy 61.690256 -276.983623)
			(xy 61.698085 -277.002284) (xy 61.698632 -277.0124) (xy 61.698632 -277.42134) (xy 61.698212 -277.431493)
			(xy 61.690409 -277.45024) (xy 61.676013 -277.464561) (xy 61.657225 -277.472265) (xy 61.64707 -277.472648)
			(xy 60.24753 -277.472648) (xy 60.237404 -277.472149) (xy 60.218681 -277.464429) (xy 60.204323 -277.450146)
			(xy 60.196505 -277.431464) (xy 60.195968 -277.42134) (xy 54.154832 -277.42134) (xy 54.154412 -277.431493)
			(xy 54.146609 -277.45024) (xy 54.132213 -277.464561) (xy 54.113425 -277.472265) (xy 54.10327 -277.472648)
			(xy 52.70373 -277.472648) (xy 52.693604 -277.472149) (xy 52.674881 -277.464429) (xy 52.660523 -277.450146)
			(xy 52.652705 -277.431464) (xy 52.652168 -277.42134) (xy 46.611032 -277.42134) (xy 46.610612 -277.431493)
			(xy 46.602809 -277.45024) (xy 46.588413 -277.464561) (xy 46.569625 -277.472265) (xy 46.55947 -277.472648)
			(xy 45.15993 -277.472648) (xy 45.149804 -277.472149) (xy 45.131081 -277.464429) (xy 45.116723 -277.450146)
			(xy 45.108905 -277.431464) (xy 45.108368 -277.42134) (xy 39.067232 -277.42134) (xy 39.066812 -277.431493)
			(xy 39.059009 -277.45024) (xy 39.044613 -277.464561) (xy 39.025825 -277.472265) (xy 39.01567 -277.472648)
			(xy 37.61613 -277.472648) (xy 37.606004 -277.472149) (xy 37.587281 -277.464429) (xy 37.572923 -277.450146)
			(xy 37.565105 -277.431464) (xy 37.564568 -277.42134) (xy 31.523432 -277.42134) (xy 31.523012 -277.431493)
			(xy 31.515209 -277.45024) (xy 31.500813 -277.464561) (xy 31.482025 -277.472265) (xy 31.47187 -277.472648)
			(xy 30.07233 -277.472648) (xy 30.062204 -277.472149) (xy 30.043481 -277.464429) (xy 30.029123 -277.450146)
			(xy 30.021305 -277.431464) (xy 30.020768 -277.42134) (xy 23.979632 -277.42134) (xy 23.979212 -277.431493)
			(xy 23.971409 -277.45024) (xy 23.957013 -277.464561) (xy 23.938225 -277.472265) (xy 23.92807 -277.472648)
			(xy 22.52853 -277.472648) (xy 22.518404 -277.472149) (xy 22.499681 -277.464429) (xy 22.485323 -277.450146)
			(xy 22.477505 -277.431464) (xy 22.476968 -277.42134) (xy 16.435832 -277.42134) (xy 16.435412 -277.431493)
			(xy 16.427609 -277.45024) (xy 16.413213 -277.464561) (xy 16.394425 -277.472265) (xy 16.38427 -277.472648)
			(xy 14.98473 -277.472648) (xy 14.974604 -277.472149) (xy 14.955881 -277.464429) (xy 14.941523 -277.450146)
			(xy 14.933705 -277.431464) (xy 14.933168 -277.42134) (xy 8.892032 -277.42134) (xy 8.891612 -277.431493)
			(xy 8.883809 -277.45024) (xy 8.869413 -277.464561) (xy 8.850625 -277.472265) (xy 8.84047 -277.472648)
			(xy 7.44093 -277.472648) (xy 7.430804 -277.472149) (xy 7.412081 -277.464429) (xy 7.397723 -277.450146)
			(xy 7.389905 -277.431464) (xy 7.389368 -277.42134) (xy 2.509012 -277.42134) (xy 2.509012 -278.271478)
			(xy 11.489436 -278.271478) (xy 11.489436 -277.862538) (xy 11.489895 -277.852369) (xy 11.497667 -277.833576)
			(xy 11.512042 -277.81919) (xy 11.530829 -277.811403) (xy 11.540998 -277.810976) (xy 12.940538 -277.810976)
			(xy 12.950703 -277.811403) (xy 12.96948 -277.819197) (xy 12.983845 -277.833584) (xy 12.991612 -277.852372)
			(xy 12.9921 -277.862538) (xy 12.9921 -278.271478) (xy 19.033236 -278.271478) (xy 19.033236 -277.862538)
			(xy 19.033695 -277.852369) (xy 19.041467 -277.833576) (xy 19.055842 -277.81919) (xy 19.074629 -277.811403)
			(xy 19.084798 -277.810976) (xy 20.484338 -277.810976) (xy 20.494503 -277.811403) (xy 20.51328 -277.819197)
			(xy 20.527645 -277.833584) (xy 20.535412 -277.852372) (xy 20.5359 -277.862538) (xy 20.5359 -278.271478)
			(xy 26.577036 -278.271478) (xy 26.577036 -277.862538) (xy 26.577495 -277.852369) (xy 26.585267 -277.833576)
			(xy 26.599642 -277.81919) (xy 26.618429 -277.811403) (xy 26.628598 -277.810976) (xy 28.028138 -277.810976)
			(xy 28.038303 -277.811403) (xy 28.05708 -277.819197) (xy 28.071445 -277.833584) (xy 28.079212 -277.852372)
			(xy 28.0797 -277.862538) (xy 28.0797 -278.271478) (xy 34.120836 -278.271478) (xy 34.120836 -277.862538)
			(xy 34.121295 -277.852369) (xy 34.129067 -277.833576) (xy 34.143442 -277.81919) (xy 34.162229 -277.811403)
			(xy 34.172398 -277.810976) (xy 35.571938 -277.810976) (xy 35.582103 -277.811403) (xy 35.60088 -277.819197)
			(xy 35.615245 -277.833584) (xy 35.623012 -277.852372) (xy 35.6235 -277.862538) (xy 35.6235 -278.271478)
			(xy 41.664636 -278.271478) (xy 41.664636 -277.862538) (xy 41.665095 -277.852369) (xy 41.672867 -277.833576)
			(xy 41.687242 -277.81919) (xy 41.706029 -277.811403) (xy 41.716198 -277.810976) (xy 43.115738 -277.810976)
			(xy 43.125903 -277.811403) (xy 43.14468 -277.819197) (xy 43.159045 -277.833584) (xy 43.166812 -277.852372)
			(xy 43.1673 -277.862538) (xy 43.1673 -278.271478) (xy 49.208436 -278.271478) (xy 49.208436 -277.862538)
			(xy 49.208895 -277.852369) (xy 49.216667 -277.833576) (xy 49.231042 -277.81919) (xy 49.249829 -277.811403)
			(xy 49.259998 -277.810976) (xy 50.659538 -277.810976) (xy 50.669703 -277.811403) (xy 50.68848 -277.819197)
			(xy 50.702845 -277.833584) (xy 50.710612 -277.852372) (xy 50.7111 -277.862538) (xy 50.7111 -278.271478)
			(xy 56.752236 -278.271478) (xy 56.752236 -277.862538) (xy 56.752695 -277.852369) (xy 56.760467 -277.833576)
			(xy 56.774842 -277.81919) (xy 56.793629 -277.811403) (xy 56.803798 -277.810976) (xy 58.203338 -277.810976)
			(xy 58.213503 -277.811403) (xy 58.23228 -277.819197) (xy 58.246645 -277.833584) (xy 58.254412 -277.852372)
			(xy 58.2549 -277.862538) (xy 58.2549 -278.271478) (xy 64.296036 -278.271478) (xy 64.296036 -277.862538)
			(xy 64.296495 -277.852369) (xy 64.304267 -277.833576) (xy 64.318642 -277.81919) (xy 64.337429 -277.811403)
			(xy 64.347598 -277.810976) (xy 65.747138 -277.810976) (xy 65.757303 -277.811403) (xy 65.77608 -277.819197)
			(xy 65.790445 -277.833584) (xy 65.798212 -277.852372) (xy 65.7987 -277.862538) (xy 65.7987 -278.271478)
			(xy 65.79815 -278.28163) (xy 65.79039 -278.300391) (xy 65.776042 -278.314756) (xy 65.757289 -278.322538)
			(xy 65.747138 -278.32304) (xy 64.347598 -278.32304) (xy 64.337424 -278.322637) (xy 64.318625 -278.314847)
			(xy 64.304239 -278.300455) (xy 64.296458 -278.281653) (xy 64.296036 -278.271478) (xy 58.2549 -278.271478)
			(xy 58.25435 -278.28163) (xy 58.24659 -278.300391) (xy 58.232242 -278.314756) (xy 58.213489 -278.322538)
			(xy 58.203338 -278.32304) (xy 56.803798 -278.32304) (xy 56.793624 -278.322637) (xy 56.774825 -278.314847)
			(xy 56.760439 -278.300455) (xy 56.752658 -278.281653) (xy 56.752236 -278.271478) (xy 50.7111 -278.271478)
			(xy 50.71055 -278.28163) (xy 50.70279 -278.300391) (xy 50.688442 -278.314756) (xy 50.669689 -278.322538)
			(xy 50.659538 -278.32304) (xy 49.259998 -278.32304) (xy 49.249824 -278.322637) (xy 49.231025 -278.314847)
			(xy 49.216639 -278.300455) (xy 49.208858 -278.281653) (xy 49.208436 -278.271478) (xy 43.1673 -278.271478)
			(xy 43.16675 -278.28163) (xy 43.15899 -278.300391) (xy 43.144642 -278.314756) (xy 43.125889 -278.322538)
			(xy 43.115738 -278.32304) (xy 41.716198 -278.32304) (xy 41.706024 -278.322637) (xy 41.687225 -278.314847)
			(xy 41.672839 -278.300455) (xy 41.665058 -278.281653) (xy 41.664636 -278.271478) (xy 35.6235 -278.271478)
			(xy 35.62295 -278.28163) (xy 35.61519 -278.300391) (xy 35.600842 -278.314756) (xy 35.582089 -278.322538)
			(xy 35.571938 -278.32304) (xy 34.172398 -278.32304) (xy 34.162224 -278.322637) (xy 34.143425 -278.314847)
			(xy 34.129039 -278.300455) (xy 34.121258 -278.281653) (xy 34.120836 -278.271478) (xy 28.0797 -278.271478)
			(xy 28.07915 -278.28163) (xy 28.07139 -278.300391) (xy 28.057042 -278.314756) (xy 28.038289 -278.322538)
			(xy 28.028138 -278.32304) (xy 26.628598 -278.32304) (xy 26.618424 -278.322637) (xy 26.599625 -278.314847)
			(xy 26.585239 -278.300455) (xy 26.577458 -278.281653) (xy 26.577036 -278.271478) (xy 20.5359 -278.271478)
			(xy 20.53535 -278.28163) (xy 20.52759 -278.300391) (xy 20.513242 -278.314756) (xy 20.494489 -278.322538)
			(xy 20.484338 -278.32304) (xy 19.084798 -278.32304) (xy 19.074624 -278.322637) (xy 19.055825 -278.314847)
			(xy 19.041439 -278.300455) (xy 19.033658 -278.281653) (xy 19.033236 -278.271478) (xy 12.9921 -278.271478)
			(xy 12.99155 -278.28163) (xy 12.98379 -278.300391) (xy 12.969442 -278.314756) (xy 12.950689 -278.322538)
			(xy 12.940538 -278.32304) (xy 11.540998 -278.32304) (xy 11.530824 -278.322637) (xy 11.512025 -278.314847)
			(xy 11.497639 -278.300455) (xy 11.489858 -278.281653) (xy 11.489436 -278.271478) (xy 2.509012 -278.271478)
			(xy 2.509012 -279.121362) (xy 7.389368 -279.121362) (xy 7.389368 -278.712422) (xy 7.389783 -278.702248)
			(xy 7.397566 -278.683448) (xy 7.411955 -278.669062) (xy 7.430756 -278.661281) (xy 7.44093 -278.66086)
			(xy 8.84047 -278.66086) (xy 8.850642 -278.661289) (xy 8.869441 -278.669068) (xy 8.883827 -278.683453)
			(xy 8.891609 -278.70225) (xy 8.892032 -278.712422) (xy 8.892032 -279.121362) (xy 14.933168 -279.121362)
			(xy 14.933168 -278.712422) (xy 14.933583 -278.702248) (xy 14.941366 -278.683448) (xy 14.955755 -278.669062)
			(xy 14.974556 -278.661281) (xy 14.98473 -278.66086) (xy 16.38427 -278.66086) (xy 16.394442 -278.661289)
			(xy 16.413241 -278.669068) (xy 16.427627 -278.683453) (xy 16.435409 -278.70225) (xy 16.435832 -278.712422)
			(xy 16.435832 -279.121362) (xy 22.476968 -279.121362) (xy 22.476968 -278.712422) (xy 22.477383 -278.702248)
			(xy 22.485166 -278.683448) (xy 22.499555 -278.669062) (xy 22.518356 -278.661281) (xy 22.52853 -278.66086)
			(xy 23.92807 -278.66086) (xy 23.938242 -278.661289) (xy 23.957041 -278.669068) (xy 23.971427 -278.683453)
			(xy 23.979209 -278.70225) (xy 23.979632 -278.712422) (xy 23.979632 -279.121362) (xy 30.020768 -279.121362)
			(xy 30.020768 -278.712422) (xy 30.021183 -278.702248) (xy 30.028966 -278.683448) (xy 30.043355 -278.669062)
			(xy 30.062156 -278.661281) (xy 30.07233 -278.66086) (xy 31.47187 -278.66086) (xy 31.482042 -278.661289)
			(xy 31.500841 -278.669068) (xy 31.515227 -278.683453) (xy 31.523009 -278.70225) (xy 31.523432 -278.712422)
			(xy 31.523432 -279.121362) (xy 37.564568 -279.121362) (xy 37.564568 -278.712422) (xy 37.564983 -278.702248)
			(xy 37.572766 -278.683448) (xy 37.587155 -278.669062) (xy 37.605956 -278.661281) (xy 37.61613 -278.66086)
			(xy 39.01567 -278.66086) (xy 39.025842 -278.661289) (xy 39.044641 -278.669068) (xy 39.059027 -278.683453)
			(xy 39.066809 -278.70225) (xy 39.067232 -278.712422) (xy 39.067232 -279.121362) (xy 45.108368 -279.121362)
			(xy 45.108368 -278.712422) (xy 45.108783 -278.702248) (xy 45.116566 -278.683448) (xy 45.130955 -278.669062)
			(xy 45.149756 -278.661281) (xy 45.15993 -278.66086) (xy 46.55947 -278.66086) (xy 46.569642 -278.661289)
			(xy 46.588441 -278.669068) (xy 46.602827 -278.683453) (xy 46.610609 -278.70225) (xy 46.611032 -278.712422)
			(xy 46.611032 -279.121362) (xy 52.652168 -279.121362) (xy 52.652168 -278.712422) (xy 52.652583 -278.702248)
			(xy 52.660366 -278.683448) (xy 52.674755 -278.669062) (xy 52.693556 -278.661281) (xy 52.70373 -278.66086)
			(xy 54.10327 -278.66086) (xy 54.113442 -278.661289) (xy 54.132241 -278.669068) (xy 54.146627 -278.683453)
			(xy 54.154409 -278.70225) (xy 54.154832 -278.712422) (xy 54.154832 -279.121362) (xy 60.195968 -279.121362)
			(xy 60.195968 -278.712422) (xy 60.196383 -278.702248) (xy 60.204166 -278.683448) (xy 60.218555 -278.669062)
			(xy 60.237356 -278.661281) (xy 60.24753 -278.66086) (xy 61.64707 -278.66086) (xy 61.657242 -278.661289)
			(xy 61.676041 -278.669068) (xy 61.690427 -278.683453) (xy 61.698209 -278.70225) (xy 61.698632 -278.712422)
			(xy 61.698632 -279.121362) (xy 61.698204 -279.131535) (xy 61.690433 -279.150318) (xy 101.552756 -279.150318)
			(xy 101.553264 -279.124431) (xy 101.561363 -279.073293) (xy 101.577362 -279.024053) (xy 101.600868 -278.977921)
			(xy 101.6313 -278.936034) (xy 101.66791 -278.899424) (xy 101.709797 -278.868992) (xy 101.755929 -278.845486)
			(xy 101.805169 -278.829487) (xy 101.856307 -278.821388) (xy 101.908081 -278.821388) (xy 101.959219 -278.829487)
			(xy 102.008459 -278.845486) (xy 102.054591 -278.868992) (xy 102.096478 -278.899424) (xy 102.133088 -278.936034)
			(xy 102.16352 -278.977921) (xy 102.187026 -279.024053) (xy 102.203025 -279.073293) (xy 102.211124 -279.124431)
			(xy 102.211632 -279.150318) (xy 102.211632 -279.150826) (xy 102.21109 -279.176186) (xy 102.493088 -279.176186)
			(xy 102.493088 -279.124414) (xy 102.501186 -279.07328) (xy 102.517184 -279.024043) (xy 102.540688 -278.977914)
			(xy 102.571118 -278.93603) (xy 102.607725 -278.899422) (xy 102.649609 -278.868991) (xy 102.695737 -278.845487)
			(xy 102.744975 -278.829488) (xy 102.796108 -278.821388) (xy 102.821994 -278.82088) (xy 102.847505 -278.821372)
			(xy 102.897919 -278.829232) (xy 102.94652 -278.844763) (xy 102.992148 -278.867597) (xy 103.033714 -278.897186)
			(xy 103.070226 -278.932826) (xy 103.0859 -278.95296) (xy 103.497888 -278.95296) (xy 103.513557 -278.932822)
			(xy 103.550069 -278.89718) (xy 103.591636 -278.867588) (xy 103.637265 -278.844752) (xy 103.685867 -278.829219)
			(xy 103.736282 -278.821357) (xy 103.761794 -278.82088) (xy 103.787685 -278.821325) (xy 103.83883 -278.829425)
			(xy 103.888078 -278.845425) (xy 103.934217 -278.868934) (xy 103.97611 -278.89937) (xy 104.012726 -278.935985)
			(xy 104.043163 -278.977878) (xy 104.066672 -279.024016) (xy 104.082674 -279.073264) (xy 104.090292 -279.121362)
			(xy 158.062168 -279.121362) (xy 158.062168 -278.712422) (xy 158.062583 -278.702248) (xy 158.070366 -278.683448)
			(xy 158.084755 -278.669062) (xy 158.103556 -278.661281) (xy 158.11373 -278.66086) (xy 159.51327 -278.66086)
			(xy 159.523442 -278.661289) (xy 159.542241 -278.669068) (xy 159.556627 -278.683453) (xy 159.564409 -278.70225)
			(xy 159.564832 -278.712422) (xy 159.564832 -279.121362) (xy 165.605968 -279.121362) (xy 165.605968 -278.712422)
			(xy 165.606383 -278.702248) (xy 165.614166 -278.683448) (xy 165.628555 -278.669062) (xy 165.647356 -278.661281)
			(xy 165.65753 -278.66086) (xy 167.05707 -278.66086) (xy 167.067242 -278.661289) (xy 167.086041 -278.669068)
			(xy 167.100427 -278.683453) (xy 167.108209 -278.70225) (xy 167.108632 -278.712422) (xy 167.108632 -279.121362)
			(xy 173.149768 -279.121362) (xy 173.149768 -278.712422) (xy 173.150183 -278.702248) (xy 173.157966 -278.683448)
			(xy 173.172355 -278.669062) (xy 173.191156 -278.661281) (xy 173.20133 -278.66086) (xy 174.60087 -278.66086)
			(xy 174.611042 -278.661289) (xy 174.629841 -278.669068) (xy 174.644227 -278.683453) (xy 174.652009 -278.70225)
			(xy 174.652432 -278.712422) (xy 174.652432 -279.121362) (xy 180.693568 -279.121362) (xy 180.693568 -278.712422)
			(xy 180.693983 -278.702248) (xy 180.701766 -278.683448) (xy 180.716155 -278.669062) (xy 180.734956 -278.661281)
			(xy 180.74513 -278.66086) (xy 182.14467 -278.66086) (xy 182.154842 -278.661289) (xy 182.173641 -278.669068)
			(xy 182.188027 -278.683453) (xy 182.195809 -278.70225) (xy 182.196232 -278.712422) (xy 182.196232 -279.121362)
			(xy 188.237368 -279.121362) (xy 188.237368 -278.712422) (xy 188.237783 -278.702248) (xy 188.245566 -278.683448)
			(xy 188.259955 -278.669062) (xy 188.278756 -278.661281) (xy 188.28893 -278.66086) (xy 189.68847 -278.66086)
			(xy 189.698642 -278.661289) (xy 189.717441 -278.669068) (xy 189.731827 -278.683453) (xy 189.739609 -278.70225)
			(xy 189.740032 -278.712422) (xy 189.740032 -279.121362) (xy 195.781168 -279.121362) (xy 195.781168 -278.712422)
			(xy 195.781583 -278.702248) (xy 195.789366 -278.683448) (xy 195.803755 -278.669062) (xy 195.822556 -278.661281)
			(xy 195.83273 -278.66086) (xy 197.23227 -278.66086) (xy 197.242442 -278.661289) (xy 197.261241 -278.669068)
			(xy 197.275627 -278.683453) (xy 197.283409 -278.70225) (xy 197.283832 -278.712422) (xy 197.283832 -279.121362)
			(xy 203.324968 -279.121362) (xy 203.324968 -278.712422) (xy 203.325383 -278.702248) (xy 203.333166 -278.683448)
			(xy 203.347555 -278.669062) (xy 203.366356 -278.661281) (xy 203.37653 -278.66086) (xy 204.77607 -278.66086)
			(xy 204.786242 -278.661289) (xy 204.805041 -278.669068) (xy 204.819427 -278.683453) (xy 204.827209 -278.70225)
			(xy 204.827632 -278.712422) (xy 204.827632 -279.121362) (xy 210.868768 -279.121362) (xy 210.868768 -278.712422)
			(xy 210.869183 -278.702248) (xy 210.876966 -278.683448) (xy 210.891355 -278.669062) (xy 210.910156 -278.661281)
			(xy 210.92033 -278.66086) (xy 212.31987 -278.66086) (xy 212.330042 -278.661289) (xy 212.348841 -278.669068)
			(xy 212.363227 -278.683453) (xy 212.371009 -278.70225) (xy 212.371432 -278.712422) (xy 212.371432 -279.121362)
			(xy 255.329436 -279.121362) (xy 255.329436 -278.712422) (xy 255.329882 -278.702252) (xy 255.337659 -278.683458)
			(xy 255.352038 -278.669073) (xy 255.370828 -278.661287) (xy 255.380998 -278.66086) (xy 256.780538 -278.66086)
			(xy 256.790701 -278.661303) (xy 256.809475 -278.669094) (xy 256.82384 -278.683475) (xy 256.831609 -278.702258)
			(xy 256.8321 -278.712422) (xy 256.8321 -279.121362) (xy 262.873236 -279.121362) (xy 262.873236 -278.712422)
			(xy 262.873682 -278.702252) (xy 262.881459 -278.683458) (xy 262.895838 -278.669073) (xy 262.914628 -278.661287)
			(xy 262.924798 -278.66086) (xy 264.324338 -278.66086) (xy 264.334501 -278.661303) (xy 264.353275 -278.669094)
			(xy 264.36764 -278.683475) (xy 264.375409 -278.702258) (xy 264.3759 -278.712422) (xy 264.3759 -279.121362)
			(xy 270.417036 -279.121362) (xy 270.417036 -278.712422) (xy 270.417482 -278.702252) (xy 270.425259 -278.683458)
			(xy 270.439638 -278.669073) (xy 270.458428 -278.661287) (xy 270.468598 -278.66086) (xy 271.868138 -278.66086)
			(xy 271.878301 -278.661303) (xy 271.897075 -278.669094) (xy 271.91144 -278.683475) (xy 271.919209 -278.702258)
			(xy 271.9197 -278.712422) (xy 271.9197 -279.121362) (xy 277.960836 -279.121362) (xy 277.960836 -278.712422)
			(xy 277.961282 -278.702252) (xy 277.969059 -278.683458) (xy 277.983438 -278.669073) (xy 278.002228 -278.661287)
			(xy 278.012398 -278.66086) (xy 279.411938 -278.66086) (xy 279.422101 -278.661303) (xy 279.440875 -278.669094)
			(xy 279.45524 -278.683475) (xy 279.463009 -278.702258) (xy 279.4635 -278.712422) (xy 279.4635 -279.121362)
			(xy 285.504636 -279.121362) (xy 285.504636 -278.712422) (xy 285.505082 -278.702252) (xy 285.512859 -278.683458)
			(xy 285.527238 -278.669073) (xy 285.546028 -278.661287) (xy 285.556198 -278.66086) (xy 286.955738 -278.66086)
			(xy 286.965901 -278.661303) (xy 286.984675 -278.669094) (xy 286.99904 -278.683475) (xy 287.006809 -278.702258)
			(xy 287.0073 -278.712422) (xy 287.0073 -279.121362) (xy 293.048436 -279.121362) (xy 293.048436 -278.712422)
			(xy 293.048882 -278.702252) (xy 293.056659 -278.683458) (xy 293.071038 -278.669073) (xy 293.089828 -278.661287)
			(xy 293.099998 -278.66086) (xy 294.499538 -278.66086) (xy 294.509701 -278.661303) (xy 294.528475 -278.669094)
			(xy 294.54284 -278.683475) (xy 294.550609 -278.702258) (xy 294.5511 -278.712422) (xy 294.5511 -279.121362)
			(xy 300.592236 -279.121362) (xy 300.592236 -278.712422) (xy 300.592682 -278.702252) (xy 300.600459 -278.683458)
			(xy 300.614838 -278.669073) (xy 300.633628 -278.661287) (xy 300.643798 -278.66086) (xy 302.043338 -278.66086)
			(xy 302.053501 -278.661303) (xy 302.072275 -278.669094) (xy 302.08664 -278.683475) (xy 302.094409 -278.702258)
			(xy 302.0949 -278.712422) (xy 302.0949 -279.121362) (xy 308.136036 -279.121362) (xy 308.136036 -278.712422)
			(xy 308.136482 -278.702252) (xy 308.144259 -278.683458) (xy 308.158638 -278.669073) (xy 308.177428 -278.661287)
			(xy 308.187598 -278.66086) (xy 309.587138 -278.66086) (xy 309.597301 -278.661303) (xy 309.616075 -278.669094)
			(xy 309.63044 -278.683475) (xy 309.638209 -278.702258) (xy 309.6387 -278.712422) (xy 309.6387 -279.121362)
			(xy 309.638136 -279.131513) (xy 309.630381 -279.150274) (xy 309.630337 -279.150318) (xy 349.492824 -279.150318)
			(xy 349.493332 -279.124431) (xy 349.501431 -279.073293) (xy 349.51743 -279.024053) (xy 349.540936 -278.977921)
			(xy 349.571368 -278.936034) (xy 349.607978 -278.899424) (xy 349.649865 -278.868992) (xy 349.695997 -278.845486)
			(xy 349.745237 -278.829487) (xy 349.796375 -278.821388) (xy 349.848149 -278.821388) (xy 349.899287 -278.829487)
			(xy 349.948527 -278.845486) (xy 349.994659 -278.868992) (xy 350.036546 -278.899424) (xy 350.073156 -278.936034)
			(xy 350.103588 -278.977921) (xy 350.127094 -279.024053) (xy 350.143093 -279.073293) (xy 350.151192 -279.124431)
			(xy 350.1517 -279.150318) (xy 350.1517 -279.150826) (xy 350.15116 -279.176184) (xy 350.433187 -279.176184)
			(xy 350.433187 -279.124416) (xy 350.441285 -279.073285) (xy 350.457281 -279.02405) (xy 350.480782 -278.977924)
			(xy 350.511209 -278.936041) (xy 350.547812 -278.899433) (xy 350.589691 -278.869002) (xy 350.635815 -278.845496)
			(xy 350.685048 -278.829494) (xy 350.736178 -278.82139) (xy 350.762062 -278.82088) (xy 350.787572 -278.821396)
			(xy 350.837985 -278.82925) (xy 350.886585 -278.844777) (xy 350.932214 -278.867606) (xy 350.97378 -278.897192)
			(xy 351.010293 -278.932828) (xy 351.025968 -278.95296) (xy 351.437956 -278.95296) (xy 351.453644 -278.932837)
			(xy 351.490152 -278.897194) (xy 351.531715 -278.8676) (xy 351.57734 -278.844762) (xy 351.625939 -278.829225)
			(xy 351.676351 -278.82136) (xy 351.701862 -278.82088) (xy 351.727755 -278.821322) (xy 351.778904 -278.829418)
			(xy 351.828156 -278.845416) (xy 351.874299 -278.868923) (xy 351.916197 -278.899359) (xy 351.952817 -278.935974)
			(xy 351.983257 -278.977868) (xy 352.006769 -279.024009) (xy 352.022773 -279.073259) (xy 352.030393 -279.121362)
			(xy 406.002236 -279.121362) (xy 406.002236 -278.712422) (xy 406.002682 -278.702252) (xy 406.010459 -278.683458)
			(xy 406.024838 -278.669073) (xy 406.043628 -278.661287) (xy 406.053798 -278.66086) (xy 407.453338 -278.66086)
			(xy 407.463501 -278.661303) (xy 407.482275 -278.669094) (xy 407.49664 -278.683475) (xy 407.504409 -278.702258)
			(xy 407.5049 -278.712422) (xy 407.5049 -279.121362) (xy 413.546036 -279.121362) (xy 413.546036 -278.712422)
			(xy 413.546482 -278.702252) (xy 413.554259 -278.683458) (xy 413.568638 -278.669073) (xy 413.587428 -278.661287)
			(xy 413.597598 -278.66086) (xy 414.997138 -278.66086) (xy 415.007301 -278.661303) (xy 415.026075 -278.669094)
			(xy 415.04044 -278.683475) (xy 415.048209 -278.702258) (xy 415.0487 -278.712422) (xy 415.0487 -279.121362)
			(xy 421.089836 -279.121362) (xy 421.089836 -278.712422) (xy 421.090282 -278.702252) (xy 421.098059 -278.683458)
			(xy 421.112438 -278.669073) (xy 421.131228 -278.661287) (xy 421.141398 -278.66086) (xy 422.540938 -278.66086)
			(xy 422.551101 -278.661303) (xy 422.569875 -278.669094) (xy 422.58424 -278.683475) (xy 422.592009 -278.702258)
			(xy 422.5925 -278.712422) (xy 422.5925 -279.121362) (xy 428.633636 -279.121362) (xy 428.633636 -278.712422)
			(xy 428.634082 -278.702252) (xy 428.641859 -278.683458) (xy 428.656238 -278.669073) (xy 428.675028 -278.661287)
			(xy 428.685198 -278.66086) (xy 430.084738 -278.66086) (xy 430.094901 -278.661303) (xy 430.113675 -278.669094)
			(xy 430.12804 -278.683475) (xy 430.135809 -278.702258) (xy 430.1363 -278.712422) (xy 430.1363 -279.121362)
			(xy 436.177436 -279.121362) (xy 436.177436 -278.712422) (xy 436.177882 -278.702252) (xy 436.185659 -278.683458)
			(xy 436.200038 -278.669073) (xy 436.218828 -278.661287) (xy 436.228998 -278.66086) (xy 437.628538 -278.66086)
			(xy 437.638701 -278.661303) (xy 437.657475 -278.669094) (xy 437.67184 -278.683475) (xy 437.679609 -278.702258)
			(xy 437.6801 -278.712422) (xy 437.6801 -279.121362) (xy 443.721236 -279.121362) (xy 443.721236 -278.712422)
			(xy 443.721682 -278.702252) (xy 443.729459 -278.683458) (xy 443.743838 -278.669073) (xy 443.762628 -278.661287)
			(xy 443.772798 -278.66086) (xy 445.172338 -278.66086) (xy 445.182501 -278.661303) (xy 445.201275 -278.669094)
			(xy 445.21564 -278.683475) (xy 445.223409 -278.702258) (xy 445.2239 -278.712422) (xy 445.2239 -279.121362)
			(xy 451.265036 -279.121362) (xy 451.265036 -278.712422) (xy 451.265482 -278.702252) (xy 451.273259 -278.683458)
			(xy 451.287638 -278.669073) (xy 451.306428 -278.661287) (xy 451.316598 -278.66086) (xy 452.716138 -278.66086)
			(xy 452.726301 -278.661303) (xy 452.745075 -278.669094) (xy 452.75944 -278.683475) (xy 452.767209 -278.702258)
			(xy 452.7677 -278.712422) (xy 452.7677 -279.121362) (xy 458.808836 -279.121362) (xy 458.808836 -278.712422)
			(xy 458.809282 -278.702252) (xy 458.817059 -278.683458) (xy 458.831438 -278.669073) (xy 458.850228 -278.661287)
			(xy 458.860398 -278.66086) (xy 460.259938 -278.66086) (xy 460.270101 -278.661303) (xy 460.288875 -278.669094)
			(xy 460.30324 -278.683475) (xy 460.311009 -278.702258) (xy 460.3115 -278.712422) (xy 460.3115 -279.121362)
			(xy 460.310936 -279.131513) (xy 460.303181 -279.150274) (xy 460.288837 -279.164639) (xy 460.270088 -279.172421)
			(xy 460.259938 -279.172924) (xy 458.860398 -279.172924) (xy 458.850222 -279.172537) (xy 458.83142 -279.164744)
			(xy 458.817033 -279.150347) (xy 458.809255 -279.131539) (xy 458.808836 -279.121362) (xy 452.7677 -279.121362)
			(xy 452.767136 -279.131513) (xy 452.759381 -279.150274) (xy 452.745037 -279.164639) (xy 452.726288 -279.172421)
			(xy 452.716138 -279.172924) (xy 451.316598 -279.172924) (xy 451.306422 -279.172537) (xy 451.28762 -279.164744)
			(xy 451.273233 -279.150347) (xy 451.265455 -279.131539) (xy 451.265036 -279.121362) (xy 445.2239 -279.121362)
			(xy 445.223336 -279.131513) (xy 445.215581 -279.150274) (xy 445.201237 -279.164639) (xy 445.182488 -279.172421)
			(xy 445.172338 -279.172924) (xy 443.772798 -279.172924) (xy 443.762622 -279.172537) (xy 443.74382 -279.164744)
			(xy 443.729433 -279.150347) (xy 443.721655 -279.131539) (xy 443.721236 -279.121362) (xy 437.6801 -279.121362)
			(xy 437.679536 -279.131513) (xy 437.671781 -279.150274) (xy 437.657437 -279.164639) (xy 437.638688 -279.172421)
			(xy 437.628538 -279.172924) (xy 436.228998 -279.172924) (xy 436.218822 -279.172537) (xy 436.20002 -279.164744)
			(xy 436.185633 -279.150347) (xy 436.177855 -279.131539) (xy 436.177436 -279.121362) (xy 430.1363 -279.121362)
			(xy 430.135736 -279.131513) (xy 430.127981 -279.150274) (xy 430.113637 -279.164639) (xy 430.094888 -279.172421)
			(xy 430.084738 -279.172924) (xy 428.685198 -279.172924) (xy 428.675022 -279.172537) (xy 428.65622 -279.164744)
			(xy 428.641833 -279.150347) (xy 428.634055 -279.131539) (xy 428.633636 -279.121362) (xy 422.5925 -279.121362)
			(xy 422.591936 -279.131513) (xy 422.584181 -279.150274) (xy 422.569837 -279.164639) (xy 422.551088 -279.172421)
			(xy 422.540938 -279.172924) (xy 421.141398 -279.172924) (xy 421.131222 -279.172537) (xy 421.11242 -279.164744)
			(xy 421.098033 -279.150347) (xy 421.090255 -279.131539) (xy 421.089836 -279.121362) (xy 415.0487 -279.121362)
			(xy 415.048136 -279.131513) (xy 415.040381 -279.150274) (xy 415.026037 -279.164639) (xy 415.007288 -279.172421)
			(xy 414.997138 -279.172924) (xy 413.597598 -279.172924) (xy 413.587422 -279.172537) (xy 413.56862 -279.164744)
			(xy 413.554233 -279.150347) (xy 413.546455 -279.131539) (xy 413.546036 -279.121362) (xy 407.5049 -279.121362)
			(xy 407.504336 -279.131513) (xy 407.496581 -279.150274) (xy 407.482237 -279.164639) (xy 407.463488 -279.172421)
			(xy 407.453338 -279.172924) (xy 406.053798 -279.172924) (xy 406.043622 -279.172537) (xy 406.02482 -279.164744)
			(xy 406.010433 -279.150347) (xy 406.002655 -279.131539) (xy 406.002236 -279.121362) (xy 352.030393 -279.121362)
			(xy 352.030875 -279.124407) (xy 352.030875 -279.176193) (xy 352.022773 -279.227341) (xy 352.006769 -279.276591)
			(xy 351.983257 -279.322732) (xy 351.952817 -279.364626) (xy 351.916197 -279.401241) (xy 351.874299 -279.431677)
			(xy 351.828156 -279.455184) (xy 351.778904 -279.471182) (xy 351.727755 -279.479278) (xy 351.701862 -279.479756)
			(xy 351.676348 -279.47932) (xy 351.625931 -279.471453) (xy 351.577328 -279.455912) (xy 351.531699 -279.433068)
			(xy 351.490135 -279.403466) (xy 351.453628 -279.367815) (xy 351.437956 -279.347676) (xy 351.025968 -279.347676)
			(xy 351.010307 -279.367822) (xy 350.973795 -279.403466) (xy 350.932228 -279.433059) (xy 350.886597 -279.455894)
			(xy 350.837992 -279.471425) (xy 350.787575 -279.479281) (xy 350.762062 -279.479756) (xy 350.736178 -279.47921)
			(xy 350.685048 -279.471106) (xy 350.635815 -279.455104) (xy 350.589691 -279.431598) (xy 350.547812 -279.401167)
			(xy 350.511209 -279.364559) (xy 350.480782 -279.322676) (xy 350.457281 -279.27655) (xy 350.441285 -279.227315)
			(xy 350.433187 -279.176184) (xy 350.15116 -279.176184) (xy 350.151114 -279.178342) (xy 350.141925 -279.232603)
			(xy 350.133412 -279.258776) (xy 350.125792 -279.28062) (xy 350.331024 -279.635966) (xy 350.353884 -279.640284)
			(xy 350.378708 -279.645438) (xy 350.426486 -279.662396) (xy 350.471104 -279.68647) (xy 350.511509 -279.717093)
			(xy 350.546749 -279.753542) (xy 350.575992 -279.794956) (xy 350.598549 -279.84036) (xy 350.613887 -279.888683)
			(xy 350.621645 -279.938785) (xy 350.622108 -279.964134) (xy 350.6216 -279.990041) (xy 350.613494 -280.041218)
			(xy 350.597482 -280.090497) (xy 350.573959 -280.136664) (xy 350.543503 -280.178583) (xy 350.506865 -280.215221)
			(xy 350.464946 -280.245677) (xy 350.418779 -280.2692) (xy 350.3695 -280.285212) (xy 350.318323 -280.293318)
			(xy 350.266509 -280.293318) (xy 350.215332 -280.285212) (xy 350.166053 -280.2692) (xy 350.119886 -280.245677)
			(xy 350.077967 -280.215221) (xy 350.041329 -280.178583) (xy 350.010873 -280.136664) (xy 349.98735 -280.090497)
			(xy 349.971338 -280.041218) (xy 349.963232 -279.990041) (xy 349.962724 -279.964134) (xy 349.963325 -279.936417)
			(xy 349.972644 -279.88177) (xy 349.981266 -279.855422) (xy 349.98914 -279.833324) (xy 349.784162 -279.478486)
			(xy 349.761302 -279.474168) (xy 349.736475 -279.468982) (xy 349.688671 -279.452048) (xy 349.644023 -279.427992)
			(xy 349.603586 -279.397383) (xy 349.568314 -279.360942) (xy 349.539039 -279.319529) (xy 349.516451 -279.274121)
			(xy 349.501083 -279.22579) (xy 349.493299 -279.175676) (xy 349.492824 -279.150318) (xy 309.630337 -279.150318)
			(xy 309.616037 -279.164639) (xy 309.597288 -279.172421) (xy 309.587138 -279.172924) (xy 308.187598 -279.172924)
			(xy 308.177422 -279.172537) (xy 308.15862 -279.164744) (xy 308.144233 -279.150347) (xy 308.136455 -279.131539)
			(xy 308.136036 -279.121362) (xy 302.0949 -279.121362) (xy 302.094336 -279.131513) (xy 302.086581 -279.150274)
			(xy 302.072237 -279.164639) (xy 302.053488 -279.172421) (xy 302.043338 -279.172924) (xy 300.643798 -279.172924)
			(xy 300.633622 -279.172537) (xy 300.61482 -279.164744) (xy 300.600433 -279.150347) (xy 300.592655 -279.131539)
			(xy 300.592236 -279.121362) (xy 294.5511 -279.121362) (xy 294.550536 -279.131513) (xy 294.542781 -279.150274)
			(xy 294.528437 -279.164639) (xy 294.509688 -279.172421) (xy 294.499538 -279.172924) (xy 293.099998 -279.172924)
			(xy 293.089822 -279.172537) (xy 293.07102 -279.164744) (xy 293.056633 -279.150347) (xy 293.048855 -279.131539)
			(xy 293.048436 -279.121362) (xy 287.0073 -279.121362) (xy 287.006736 -279.131513) (xy 286.998981 -279.150274)
			(xy 286.984637 -279.164639) (xy 286.965888 -279.172421) (xy 286.955738 -279.172924) (xy 285.556198 -279.172924)
			(xy 285.546022 -279.172537) (xy 285.52722 -279.164744) (xy 285.512833 -279.150347) (xy 285.505055 -279.131539)
			(xy 285.504636 -279.121362) (xy 279.4635 -279.121362) (xy 279.462936 -279.131513) (xy 279.455181 -279.150274)
			(xy 279.440837 -279.164639) (xy 279.422088 -279.172421) (xy 279.411938 -279.172924) (xy 278.012398 -279.172924)
			(xy 278.002222 -279.172537) (xy 277.98342 -279.164744) (xy 277.969033 -279.150347) (xy 277.961255 -279.131539)
			(xy 277.960836 -279.121362) (xy 271.9197 -279.121362) (xy 271.919136 -279.131513) (xy 271.911381 -279.150274)
			(xy 271.897037 -279.164639) (xy 271.878288 -279.172421) (xy 271.868138 -279.172924) (xy 270.468598 -279.172924)
			(xy 270.458422 -279.172537) (xy 270.43962 -279.164744) (xy 270.425233 -279.150347) (xy 270.417455 -279.131539)
			(xy 270.417036 -279.121362) (xy 264.3759 -279.121362) (xy 264.375336 -279.131513) (xy 264.367581 -279.150274)
			(xy 264.353237 -279.164639) (xy 264.334488 -279.172421) (xy 264.324338 -279.172924) (xy 262.924798 -279.172924)
			(xy 262.914622 -279.172537) (xy 262.89582 -279.164744) (xy 262.881433 -279.150347) (xy 262.873655 -279.131539)
			(xy 262.873236 -279.121362) (xy 256.8321 -279.121362) (xy 256.831536 -279.131513) (xy 256.823781 -279.150274)
			(xy 256.809437 -279.164639) (xy 256.790688 -279.172421) (xy 256.780538 -279.172924) (xy 255.380998 -279.172924)
			(xy 255.370822 -279.172537) (xy 255.35202 -279.164744) (xy 255.337633 -279.150347) (xy 255.329855 -279.131539)
			(xy 255.329436 -279.121362) (xy 212.371432 -279.121362) (xy 212.371004 -279.131535) (xy 212.363226 -279.150334)
			(xy 212.348841 -279.164722) (xy 212.330043 -279.172503) (xy 212.31987 -279.172924) (xy 210.92033 -279.172924)
			(xy 210.910156 -279.172511) (xy 210.891354 -279.164728) (xy 210.876967 -279.150339) (xy 210.869188 -279.131536)
			(xy 210.868768 -279.121362) (xy 204.827632 -279.121362) (xy 204.827204 -279.131535) (xy 204.819426 -279.150334)
			(xy 204.805041 -279.164722) (xy 204.786243 -279.172503) (xy 204.77607 -279.172924) (xy 203.37653 -279.172924)
			(xy 203.366356 -279.172511) (xy 203.347554 -279.164728) (xy 203.333167 -279.150339) (xy 203.325388 -279.131536)
			(xy 203.324968 -279.121362) (xy 197.283832 -279.121362) (xy 197.283404 -279.131535) (xy 197.275626 -279.150334)
			(xy 197.261241 -279.164722) (xy 197.242443 -279.172503) (xy 197.23227 -279.172924) (xy 195.83273 -279.172924)
			(xy 195.822556 -279.172511) (xy 195.803754 -279.164728) (xy 195.789367 -279.150339) (xy 195.781588 -279.131536)
			(xy 195.781168 -279.121362) (xy 189.740032 -279.121362) (xy 189.739604 -279.131535) (xy 189.731826 -279.150334)
			(xy 189.717441 -279.164722) (xy 189.698643 -279.172503) (xy 189.68847 -279.172924) (xy 188.28893 -279.172924)
			(xy 188.278756 -279.172511) (xy 188.259954 -279.164728) (xy 188.245567 -279.150339) (xy 188.237788 -279.131536)
			(xy 188.237368 -279.121362) (xy 182.196232 -279.121362) (xy 182.195804 -279.131535) (xy 182.188026 -279.150334)
			(xy 182.173641 -279.164722) (xy 182.154843 -279.172503) (xy 182.14467 -279.172924) (xy 180.74513 -279.172924)
			(xy 180.734956 -279.172511) (xy 180.716154 -279.164728) (xy 180.701767 -279.150339) (xy 180.693988 -279.131536)
			(xy 180.693568 -279.121362) (xy 174.652432 -279.121362) (xy 174.652004 -279.131535) (xy 174.644226 -279.150334)
			(xy 174.629841 -279.164722) (xy 174.611043 -279.172503) (xy 174.60087 -279.172924) (xy 173.20133 -279.172924)
			(xy 173.191156 -279.172511) (xy 173.172354 -279.164728) (xy 173.157967 -279.150339) (xy 173.150188 -279.131536)
			(xy 173.149768 -279.121362) (xy 167.108632 -279.121362) (xy 167.108204 -279.131535) (xy 167.100426 -279.150334)
			(xy 167.086041 -279.164722) (xy 167.067243 -279.172503) (xy 167.05707 -279.172924) (xy 165.65753 -279.172924)
			(xy 165.647356 -279.172511) (xy 165.628554 -279.164728) (xy 165.614167 -279.150339) (xy 165.606388 -279.131536)
			(xy 165.605968 -279.121362) (xy 159.564832 -279.121362) (xy 159.564404 -279.131535) (xy 159.556626 -279.150334)
			(xy 159.542241 -279.164722) (xy 159.523443 -279.172503) (xy 159.51327 -279.172924) (xy 158.11373 -279.172924)
			(xy 158.103556 -279.172511) (xy 158.084754 -279.164728) (xy 158.070367 -279.150339) (xy 158.062588 -279.131536)
			(xy 158.062168 -279.121362) (xy 104.090292 -279.121362) (xy 104.090775 -279.124409) (xy 104.090775 -279.176191)
			(xy 104.082674 -279.227336) (xy 104.066672 -279.276584) (xy 104.043163 -279.322722) (xy 104.012726 -279.364615)
			(xy 103.97611 -279.40123) (xy 103.934217 -279.431666) (xy 103.888078 -279.455175) (xy 103.83883 -279.471175)
			(xy 103.787685 -279.479275) (xy 103.761794 -279.479756) (xy 103.736281 -279.479297) (xy 103.685865 -279.471435)
			(xy 103.637262 -279.455898) (xy 103.591633 -279.433058) (xy 103.550069 -279.403461) (xy 103.51356 -279.367813)
			(xy 103.497888 -279.347676) (xy 103.0859 -279.347676) (xy 103.07022 -279.367806) (xy 103.033713 -279.403452)
			(xy 102.992149 -279.433046) (xy 102.946521 -279.455884) (xy 102.89792 -279.471418) (xy 102.847506 -279.479279)
			(xy 102.821994 -279.479756) (xy 102.796108 -279.479212) (xy 102.744975 -279.471112) (xy 102.695737 -279.455113)
			(xy 102.649609 -279.431609) (xy 102.607725 -279.401178) (xy 102.571118 -279.36457) (xy 102.540688 -279.322686)
			(xy 102.517184 -279.276557) (xy 102.501186 -279.22732) (xy 102.493088 -279.176186) (xy 102.21109 -279.176186)
			(xy 102.211044 -279.178342) (xy 102.201856 -279.232603) (xy 102.193344 -279.258776) (xy 102.185724 -279.28062)
			(xy 102.390956 -279.635966) (xy 102.413816 -279.640284) (xy 102.438629 -279.645487) (xy 102.486407 -279.662435)
			(xy 102.531027 -279.686501) (xy 102.571434 -279.717117) (xy 102.606676 -279.753559) (xy 102.635921 -279.794969)
			(xy 102.658479 -279.840369) (xy 102.673819 -279.888688) (xy 102.681577 -279.938786) (xy 102.68204 -279.964134)
			(xy 102.681532 -279.990041) (xy 102.673426 -280.041218) (xy 102.657414 -280.090497) (xy 102.633891 -280.136664)
			(xy 102.603435 -280.178583) (xy 102.566797 -280.215221) (xy 102.524878 -280.245677) (xy 102.478711 -280.2692)
			(xy 102.429432 -280.285212) (xy 102.378255 -280.293318) (xy 102.326441 -280.293318) (xy 102.275264 -280.285212)
			(xy 102.225985 -280.2692) (xy 102.179818 -280.245677) (xy 102.137899 -280.215221) (xy 102.101261 -280.178583)
			(xy 102.070805 -280.136664) (xy 102.047282 -280.090497) (xy 102.03127 -280.041218) (xy 102.023164 -279.990041)
			(xy 102.022656 -279.964134) (xy 102.023255 -279.936417) (xy 102.032575 -279.88177) (xy 102.041198 -279.855422)
			(xy 102.049072 -279.833324) (xy 101.844094 -279.478486) (xy 101.821234 -279.474168) (xy 101.796412 -279.468959)
			(xy 101.748608 -279.452029) (xy 101.70396 -279.427978) (xy 101.663522 -279.397372) (xy 101.628249 -279.360934)
			(xy 101.598973 -279.319523) (xy 101.576384 -279.274117) (xy 101.561016 -279.225788) (xy 101.553231 -279.175675)
			(xy 101.552756 -279.150318) (xy 61.690433 -279.150318) (xy 61.690426 -279.150334) (xy 61.676041 -279.164722)
			(xy 61.657243 -279.172503) (xy 61.64707 -279.172924) (xy 60.24753 -279.172924) (xy 60.237356 -279.172511)
			(xy 60.218554 -279.164728) (xy 60.204167 -279.150339) (xy 60.196388 -279.131536) (xy 60.195968 -279.121362)
			(xy 54.154832 -279.121362) (xy 54.154404 -279.131535) (xy 54.146626 -279.150334) (xy 54.132241 -279.164722)
			(xy 54.113443 -279.172503) (xy 54.10327 -279.172924) (xy 52.70373 -279.172924) (xy 52.693556 -279.172511)
			(xy 52.674754 -279.164728) (xy 52.660367 -279.150339) (xy 52.652588 -279.131536) (xy 52.652168 -279.121362)
			(xy 46.611032 -279.121362) (xy 46.610604 -279.131535) (xy 46.602826 -279.150334) (xy 46.588441 -279.164722)
			(xy 46.569643 -279.172503) (xy 46.55947 -279.172924) (xy 45.15993 -279.172924) (xy 45.149756 -279.172511)
			(xy 45.130954 -279.164728) (xy 45.116567 -279.150339) (xy 45.108788 -279.131536) (xy 45.108368 -279.121362)
			(xy 39.067232 -279.121362) (xy 39.066804 -279.131535) (xy 39.059026 -279.150334) (xy 39.044641 -279.164722)
			(xy 39.025843 -279.172503) (xy 39.01567 -279.172924) (xy 37.61613 -279.172924) (xy 37.605956 -279.172511)
			(xy 37.587154 -279.164728) (xy 37.572767 -279.150339) (xy 37.564988 -279.131536) (xy 37.564568 -279.121362)
			(xy 31.523432 -279.121362) (xy 31.523004 -279.131535) (xy 31.515226 -279.150334) (xy 31.500841 -279.164722)
			(xy 31.482043 -279.172503) (xy 31.47187 -279.172924) (xy 30.07233 -279.172924) (xy 30.062156 -279.172511)
			(xy 30.043354 -279.164728) (xy 30.028967 -279.150339) (xy 30.021188 -279.131536) (xy 30.020768 -279.121362)
			(xy 23.979632 -279.121362) (xy 23.979204 -279.131535) (xy 23.971426 -279.150334) (xy 23.957041 -279.164722)
			(xy 23.938243 -279.172503) (xy 23.92807 -279.172924) (xy 22.52853 -279.172924) (xy 22.518356 -279.172511)
			(xy 22.499554 -279.164728) (xy 22.485167 -279.150339) (xy 22.477388 -279.131536) (xy 22.476968 -279.121362)
			(xy 16.435832 -279.121362) (xy 16.435404 -279.131535) (xy 16.427626 -279.150334) (xy 16.413241 -279.164722)
			(xy 16.394443 -279.172503) (xy 16.38427 -279.172924) (xy 14.98473 -279.172924) (xy 14.974556 -279.172511)
			(xy 14.955754 -279.164728) (xy 14.941367 -279.150339) (xy 14.933588 -279.131536) (xy 14.933168 -279.121362)
			(xy 8.892032 -279.121362) (xy 8.891604 -279.131535) (xy 8.883826 -279.150334) (xy 8.869441 -279.164722)
			(xy 8.850643 -279.172503) (xy 8.84047 -279.172924) (xy 7.44093 -279.172924) (xy 7.430756 -279.172511)
			(xy 7.411954 -279.164728) (xy 7.397567 -279.150339) (xy 7.389788 -279.131536) (xy 7.389368 -279.121362)
			(xy 2.509012 -279.121362) (xy 2.509012 -279.9715) (xy 11.489436 -279.9715) (xy 11.489436 -279.56256)
			(xy 11.48979 -279.552399) (xy 11.497605 -279.533639) (xy 11.512023 -279.519315) (xy 11.530834 -279.511624)
			(xy 11.540998 -279.511252) (xy 12.940538 -279.511252) (xy 12.950669 -279.511696) (xy 12.969393 -279.519438)
			(xy 12.983748 -279.533738) (xy 12.991564 -279.552431) (xy 12.9921 -279.56256) (xy 12.9921 -279.9715)
			(xy 19.033236 -279.9715) (xy 19.033236 -279.56256) (xy 19.03359 -279.552399) (xy 19.041405 -279.533639)
			(xy 19.055823 -279.519315) (xy 19.074634 -279.511624) (xy 19.084798 -279.511252) (xy 20.484338 -279.511252)
			(xy 20.494469 -279.511696) (xy 20.513193 -279.519438) (xy 20.527548 -279.533738) (xy 20.535364 -279.552431)
			(xy 20.5359 -279.56256) (xy 20.5359 -279.9715) (xy 26.577036 -279.9715) (xy 26.577036 -279.56256)
			(xy 26.57739 -279.552399) (xy 26.585205 -279.533639) (xy 26.599623 -279.519315) (xy 26.618434 -279.511624)
			(xy 26.628598 -279.511252) (xy 28.028138 -279.511252) (xy 28.038269 -279.511696) (xy 28.056993 -279.519438)
			(xy 28.071348 -279.533738) (xy 28.079164 -279.552431) (xy 28.0797 -279.56256) (xy 28.0797 -279.9715)
			(xy 34.120836 -279.9715) (xy 34.120836 -279.56256) (xy 34.12119 -279.552399) (xy 34.129005 -279.533639)
			(xy 34.143423 -279.519315) (xy 34.162234 -279.511624) (xy 34.172398 -279.511252) (xy 35.571938 -279.511252)
			(xy 35.582069 -279.511696) (xy 35.600793 -279.519438) (xy 35.615148 -279.533738) (xy 35.622964 -279.552431)
			(xy 35.6235 -279.56256) (xy 35.6235 -279.9715) (xy 41.664636 -279.9715) (xy 41.664636 -279.56256)
			(xy 41.66499 -279.552399) (xy 41.672805 -279.533639) (xy 41.687223 -279.519315) (xy 41.706034 -279.511624)
			(xy 41.716198 -279.511252) (xy 43.115738 -279.511252) (xy 43.125869 -279.511696) (xy 43.144593 -279.519438)
			(xy 43.158948 -279.533738) (xy 43.166764 -279.552431) (xy 43.1673 -279.56256) (xy 43.1673 -279.9715)
			(xy 49.208436 -279.9715) (xy 49.208436 -279.56256) (xy 49.20879 -279.552399) (xy 49.216605 -279.533639)
			(xy 49.231023 -279.519315) (xy 49.249834 -279.511624) (xy 49.259998 -279.511252) (xy 50.659538 -279.511252)
			(xy 50.669669 -279.511696) (xy 50.688393 -279.519438) (xy 50.702748 -279.533738) (xy 50.710564 -279.552431)
			(xy 50.7111 -279.56256) (xy 50.7111 -279.9715) (xy 56.752236 -279.9715) (xy 56.752236 -279.56256)
			(xy 56.75259 -279.552399) (xy 56.760405 -279.533639) (xy 56.774823 -279.519315) (xy 56.793634 -279.511624)
			(xy 56.803798 -279.511252) (xy 58.203338 -279.511252) (xy 58.213469 -279.511696) (xy 58.232193 -279.519438)
			(xy 58.246548 -279.533738) (xy 58.254364 -279.552431) (xy 58.2549 -279.56256) (xy 58.2549 -279.9715)
			(xy 64.296036 -279.9715) (xy 64.296036 -279.56256) (xy 64.29639 -279.552399) (xy 64.304205 -279.533639)
			(xy 64.318623 -279.519315) (xy 64.337434 -279.511624) (xy 64.347598 -279.511252) (xy 65.747138 -279.511252)
			(xy 65.757269 -279.511696) (xy 65.775993 -279.519438) (xy 65.790348 -279.533738) (xy 65.798164 -279.552431)
			(xy 65.7987 -279.56256) (xy 65.7987 -279.9715) (xy 65.798278 -279.981654) (xy 65.794815 -279.989984)
			(xy 88.866003 -279.989984) (xy 88.866003 -279.938216) (xy 88.874102 -279.887084) (xy 88.890099 -279.837849)
			(xy 88.913601 -279.791722) (xy 88.94403 -279.74984) (xy 88.980636 -279.713234) (xy 89.022517 -279.682805)
			(xy 89.068643 -279.659301) (xy 89.117878 -279.643303) (xy 89.16901 -279.635204) (xy 89.194894 -279.634696)
			(xy 89.220406 -279.635183) (xy 89.27082 -279.643042) (xy 89.319421 -279.658575) (xy 89.365049 -279.681409)
			(xy 89.406615 -279.711) (xy 89.443126 -279.746642) (xy 89.4588 -279.766776) (xy 89.870788 -279.766776)
			(xy 89.886462 -279.746641) (xy 89.922972 -279.710998) (xy 89.964538 -279.681405) (xy 90.010166 -279.658569)
			(xy 90.058768 -279.643035) (xy 90.109182 -279.635173) (xy 90.134694 -279.634696) (xy 90.160586 -279.635109)
			(xy 90.211734 -279.643209) (xy 90.260984 -279.659211) (xy 90.307125 -279.68272) (xy 90.349021 -279.713158)
			(xy 90.385638 -279.749775) (xy 90.416077 -279.791669) (xy 90.439587 -279.83781) (xy 90.45559 -279.88706)
			(xy 90.463691 -279.938208) (xy 90.463691 -279.964134) (xy 96.383856 -279.964134) (xy 96.384364 -279.938227)
			(xy 96.39247 -279.88705) (xy 96.408482 -279.837771) (xy 96.432005 -279.791604) (xy 96.462461 -279.749685)
			(xy 96.499099 -279.713047) (xy 96.541018 -279.682591) (xy 96.587185 -279.659068) (xy 96.636464 -279.643056)
			(xy 96.687641 -279.63495) (xy 96.739455 -279.63495) (xy 96.790632 -279.643056) (xy 96.839911 -279.659068)
			(xy 96.886078 -279.682591) (xy 96.927997 -279.713047) (xy 96.964635 -279.749685) (xy 96.995091 -279.791604)
			(xy 97.018614 -279.837771) (xy 97.034626 -279.88705) (xy 97.042732 -279.938227) (xy 97.04324 -279.964134)
			(xy 97.042606 -279.991926) (xy 97.033158 -280.046702) (xy 97.024444 -280.0731) (xy 97.016824 -280.095198)
			(xy 97.221802 -280.450036) (xy 97.244662 -280.454354) (xy 97.269457 -280.45958) (xy 97.317195 -280.476563)
			(xy 97.361773 -280.50065) (xy 97.402139 -280.531276) (xy 97.437344 -280.567718) (xy 97.466557 -280.609118)
			(xy 97.489091 -280.6545) (xy 97.504415 -280.702797) (xy 97.512168 -280.752869) (xy 97.512632 -280.778204)
			(xy 97.512124 -280.804091) (xy 97.504025 -280.855229) (xy 97.488026 -280.904469) (xy 97.46452 -280.950601)
			(xy 97.434088 -280.992488) (xy 97.397478 -281.029098) (xy 97.355591 -281.05953) (xy 97.309459 -281.083036)
			(xy 97.260219 -281.099035) (xy 97.209081 -281.107134) (xy 97.157307 -281.107134) (xy 97.106169 -281.099035)
			(xy 97.056929 -281.083036) (xy 97.010797 -281.05953) (xy 96.96891 -281.029098) (xy 96.9323 -280.992488)
			(xy 96.901868 -280.950601) (xy 96.878362 -280.904469) (xy 96.862363 -280.855229) (xy 96.854264 -280.804091)
			(xy 96.853756 -280.778204) (xy 96.854288 -280.750496) (xy 96.863482 -280.695849) (xy 96.872044 -280.669492)
			(xy 96.879918 -280.647394) (xy 96.674686 -280.292302) (xy 96.651826 -280.287984) (xy 96.627038 -280.282731)
			(xy 96.579302 -280.265749) (xy 96.534727 -280.241664) (xy 96.494362 -280.211041) (xy 96.459158 -280.174603)
			(xy 96.429944 -280.133207) (xy 96.407407 -280.087828) (xy 96.39208 -280.039536) (xy 96.384322 -279.989467)
			(xy 96.383856 -279.964134) (xy 90.463691 -279.964134) (xy 90.463691 -279.989992) (xy 90.45559 -280.04114)
			(xy 90.439587 -280.09039) (xy 90.416077 -280.13653) (xy 90.385638 -280.178425) (xy 90.349021 -280.215042)
			(xy 90.307125 -280.24548) (xy 90.260984 -280.268989) (xy 90.211734 -280.284991) (xy 90.160586 -280.293091)
			(xy 90.134694 -280.293572) (xy 90.109181 -280.293107) (xy 90.058766 -280.285245) (xy 90.010163 -280.269709)
			(xy 89.964535 -280.24687) (xy 89.92297 -280.217275) (xy 89.886461 -280.181628) (xy 89.870788 -280.161492)
			(xy 89.4588 -280.161492) (xy 89.443124 -280.181626) (xy 89.406615 -280.21727) (xy 89.365051 -280.246864)
			(xy 89.319422 -280.269701) (xy 89.270821 -280.285235) (xy 89.220406 -280.293095) (xy 89.194894 -280.293572)
			(xy 89.16901 -280.292996) (xy 89.117878 -280.284897) (xy 89.068643 -280.268899) (xy 89.022517 -280.245395)
			(xy 88.980636 -280.214966) (xy 88.94403 -280.17836) (xy 88.913601 -280.136478) (xy 88.890099 -280.090351)
			(xy 88.874102 -280.041116) (xy 88.866003 -279.989984) (xy 65.794815 -279.989984) (xy 65.790483 -280.000406)
			(xy 65.776086 -280.01473) (xy 65.757294 -280.022429) (xy 65.747138 -280.022808) (xy 64.347598 -280.022808)
			(xy 64.337477 -280.022276) (xy 64.318765 -280.014557) (xy 64.304411 -280.000285) (xy 64.296583 -279.981618)
			(xy 64.296036 -279.9715) (xy 58.2549 -279.9715) (xy 58.254478 -279.981654) (xy 58.246683 -280.000406)
			(xy 58.232286 -280.01473) (xy 58.213494 -280.022429) (xy 58.203338 -280.022808) (xy 56.803798 -280.022808)
			(xy 56.793677 -280.022276) (xy 56.774965 -280.014557) (xy 56.760611 -280.000285) (xy 56.752783 -279.981618)
			(xy 56.752236 -279.9715) (xy 50.7111 -279.9715) (xy 50.710678 -279.981654) (xy 50.702883 -280.000406)
			(xy 50.688486 -280.01473) (xy 50.669694 -280.022429) (xy 50.659538 -280.022808) (xy 49.259998 -280.022808)
			(xy 49.249877 -280.022276) (xy 49.231165 -280.014557) (xy 49.216811 -280.000285) (xy 49.208983 -279.981618)
			(xy 49.208436 -279.9715) (xy 43.1673 -279.9715) (xy 43.166878 -279.981654) (xy 43.159083 -280.000406)
			(xy 43.144686 -280.01473) (xy 43.125894 -280.022429) (xy 43.115738 -280.022808) (xy 41.716198 -280.022808)
			(xy 41.706077 -280.022276) (xy 41.687365 -280.014557) (xy 41.673011 -280.000285) (xy 41.665183 -279.981618)
			(xy 41.664636 -279.9715) (xy 35.6235 -279.9715) (xy 35.623078 -279.981654) (xy 35.615283 -280.000406)
			(xy 35.600886 -280.01473) (xy 35.582094 -280.022429) (xy 35.571938 -280.022808) (xy 34.172398 -280.022808)
			(xy 34.162277 -280.022276) (xy 34.143565 -280.014557) (xy 34.129211 -280.000285) (xy 34.121383 -279.981618)
			(xy 34.120836 -279.9715) (xy 28.0797 -279.9715) (xy 28.079278 -279.981654) (xy 28.071483 -280.000406)
			(xy 28.057086 -280.01473) (xy 28.038294 -280.022429) (xy 28.028138 -280.022808) (xy 26.628598 -280.022808)
			(xy 26.618477 -280.022276) (xy 26.599765 -280.014557) (xy 26.585411 -280.000285) (xy 26.577583 -279.981618)
			(xy 26.577036 -279.9715) (xy 20.5359 -279.9715) (xy 20.535478 -279.981654) (xy 20.527683 -280.000406)
			(xy 20.513286 -280.01473) (xy 20.494494 -280.022429) (xy 20.484338 -280.022808) (xy 19.084798 -280.022808)
			(xy 19.074677 -280.022276) (xy 19.055965 -280.014557) (xy 19.041611 -280.000285) (xy 19.033783 -279.981618)
			(xy 19.033236 -279.9715) (xy 12.9921 -279.9715) (xy 12.991678 -279.981654) (xy 12.983883 -280.000406)
			(xy 12.969486 -280.01473) (xy 12.950694 -280.022429) (xy 12.940538 -280.022808) (xy 11.540998 -280.022808)
			(xy 11.530877 -280.022276) (xy 11.512165 -280.014557) (xy 11.497811 -280.000285) (xy 11.489983 -279.981618)
			(xy 11.489436 -279.9715) (xy 2.509012 -279.9715) (xy 2.509012 -280.821384) (xy 7.389368 -280.821384)
			(xy 7.389368 -280.412444) (xy 7.389857 -280.402297) (xy 7.397632 -280.383551) (xy 7.412008 -280.369228)
			(xy 7.430781 -280.361521) (xy 7.44093 -280.361136) (xy 8.84047 -280.361136) (xy 8.850594 -280.361651)
			(xy 8.869314 -280.369368) (xy 8.883671 -280.383646) (xy 8.891492 -280.402322) (xy 8.892032 -280.412444)
			(xy 8.892032 -280.821384) (xy 14.933168 -280.821384) (xy 14.933168 -280.412444) (xy 14.933657 -280.402297)
			(xy 14.941432 -280.383551) (xy 14.955808 -280.369228) (xy 14.974581 -280.361521) (xy 14.98473 -280.361136)
			(xy 16.38427 -280.361136) (xy 16.394394 -280.361651) (xy 16.413114 -280.369368) (xy 16.427471 -280.383646)
			(xy 16.435292 -280.402322) (xy 16.435832 -280.412444) (xy 16.435832 -280.821384) (xy 22.476968 -280.821384)
			(xy 22.476968 -280.412444) (xy 22.477457 -280.402297) (xy 22.485232 -280.383551) (xy 22.499608 -280.369228)
			(xy 22.518381 -280.361521) (xy 22.52853 -280.361136) (xy 23.92807 -280.361136) (xy 23.938194 -280.361651)
			(xy 23.956914 -280.369368) (xy 23.971271 -280.383646) (xy 23.979092 -280.402322) (xy 23.979632 -280.412444)
			(xy 23.979632 -280.821384) (xy 30.020768 -280.821384) (xy 30.020768 -280.412444) (xy 30.021257 -280.402297)
			(xy 30.029032 -280.383551) (xy 30.043408 -280.369228) (xy 30.062181 -280.361521) (xy 30.07233 -280.361136)
			(xy 31.47187 -280.361136) (xy 31.481994 -280.361651) (xy 31.500714 -280.369368) (xy 31.515071 -280.383646)
			(xy 31.522892 -280.402322) (xy 31.523432 -280.412444) (xy 31.523432 -280.821384) (xy 37.564568 -280.821384)
			(xy 37.564568 -280.412444) (xy 37.565057 -280.402297) (xy 37.572832 -280.383551) (xy 37.587208 -280.369228)
			(xy 37.605981 -280.361521) (xy 37.61613 -280.361136) (xy 39.01567 -280.361136) (xy 39.025794 -280.361651)
			(xy 39.044514 -280.369368) (xy 39.058871 -280.383646) (xy 39.066692 -280.402322) (xy 39.067232 -280.412444)
			(xy 39.067232 -280.821384) (xy 45.108368 -280.821384) (xy 45.108368 -280.412444) (xy 45.108857 -280.402297)
			(xy 45.116632 -280.383551) (xy 45.131008 -280.369228) (xy 45.149781 -280.361521) (xy 45.15993 -280.361136)
			(xy 46.55947 -280.361136) (xy 46.569594 -280.361651) (xy 46.588314 -280.369368) (xy 46.602671 -280.383646)
			(xy 46.610492 -280.402322) (xy 46.611032 -280.412444) (xy 46.611032 -280.821384) (xy 52.652168 -280.821384)
			(xy 52.652168 -280.412444) (xy 52.652657 -280.402297) (xy 52.660432 -280.383551) (xy 52.674808 -280.369228)
			(xy 52.693581 -280.361521) (xy 52.70373 -280.361136) (xy 54.10327 -280.361136) (xy 54.113394 -280.361651)
			(xy 54.132114 -280.369368) (xy 54.146471 -280.383646) (xy 54.154292 -280.402322) (xy 54.154832 -280.412444)
			(xy 54.154832 -280.821384) (xy 60.195968 -280.821384) (xy 60.195968 -280.412444) (xy 60.196457 -280.402297)
			(xy 60.204232 -280.383551) (xy 60.218608 -280.369228) (xy 60.237381 -280.361521) (xy 60.24753 -280.361136)
			(xy 61.64707 -280.361136) (xy 61.657194 -280.361651) (xy 61.675914 -280.369368) (xy 61.690271 -280.383646)
			(xy 61.698092 -280.402322) (xy 61.698632 -280.412444) (xy 61.698632 -280.821384) (xy 61.698166 -280.831533)
			(xy 61.690382 -280.850279) (xy 61.675999 -280.864602) (xy 61.657221 -280.872308) (xy 61.64707 -280.872692)
			(xy 60.24753 -280.872692) (xy 60.237409 -280.87215) (xy 60.218695 -280.864438) (xy 60.204338 -280.850169)
			(xy 60.196512 -280.831502) (xy 60.195968 -280.821384) (xy 54.154832 -280.821384) (xy 54.154366 -280.831533)
			(xy 54.146582 -280.850279) (xy 54.132199 -280.864602) (xy 54.113421 -280.872308) (xy 54.10327 -280.872692)
			(xy 52.70373 -280.872692) (xy 52.693609 -280.87215) (xy 52.674895 -280.864438) (xy 52.660538 -280.850169)
			(xy 52.652712 -280.831502) (xy 52.652168 -280.821384) (xy 46.611032 -280.821384) (xy 46.610566 -280.831533)
			(xy 46.602782 -280.850279) (xy 46.588399 -280.864602) (xy 46.569621 -280.872308) (xy 46.55947 -280.872692)
			(xy 45.15993 -280.872692) (xy 45.149809 -280.87215) (xy 45.131095 -280.864438) (xy 45.116738 -280.850169)
			(xy 45.108912 -280.831502) (xy 45.108368 -280.821384) (xy 39.067232 -280.821384) (xy 39.066766 -280.831533)
			(xy 39.058982 -280.850279) (xy 39.044599 -280.864602) (xy 39.025821 -280.872308) (xy 39.01567 -280.872692)
			(xy 37.61613 -280.872692) (xy 37.606009 -280.87215) (xy 37.587295 -280.864438) (xy 37.572938 -280.850169)
			(xy 37.565112 -280.831502) (xy 37.564568 -280.821384) (xy 31.523432 -280.821384) (xy 31.522966 -280.831533)
			(xy 31.515182 -280.850279) (xy 31.500799 -280.864602) (xy 31.482021 -280.872308) (xy 31.47187 -280.872692)
			(xy 30.07233 -280.872692) (xy 30.062209 -280.87215) (xy 30.043495 -280.864438) (xy 30.029138 -280.850169)
			(xy 30.021312 -280.831502) (xy 30.020768 -280.821384) (xy 23.979632 -280.821384) (xy 23.979166 -280.831533)
			(xy 23.971382 -280.850279) (xy 23.956999 -280.864602) (xy 23.938221 -280.872308) (xy 23.92807 -280.872692)
			(xy 22.52853 -280.872692) (xy 22.518409 -280.87215) (xy 22.499695 -280.864438) (xy 22.485338 -280.850169)
			(xy 22.477512 -280.831502) (xy 22.476968 -280.821384) (xy 16.435832 -280.821384) (xy 16.435366 -280.831533)
			(xy 16.427582 -280.850279) (xy 16.413199 -280.864602) (xy 16.394421 -280.872308) (xy 16.38427 -280.872692)
			(xy 14.98473 -280.872692) (xy 14.974609 -280.87215) (xy 14.955895 -280.864438) (xy 14.941538 -280.850169)
			(xy 14.933712 -280.831502) (xy 14.933168 -280.821384) (xy 8.892032 -280.821384) (xy 8.891566 -280.831533)
			(xy 8.883782 -280.850279) (xy 8.869399 -280.864602) (xy 8.850621 -280.872308) (xy 8.84047 -280.872692)
			(xy 7.44093 -280.872692) (xy 7.430809 -280.87215) (xy 7.412095 -280.864438) (xy 7.397738 -280.850169)
			(xy 7.389912 -280.831502) (xy 7.389368 -280.821384) (xy 2.509012 -280.821384) (xy 2.509012 -281.671522)
			(xy 11.489436 -281.671522) (xy 11.489436 -281.262582) (xy 11.489918 -281.252423) (xy 11.497698 -281.233654)
			(xy 11.512067 -281.219289) (xy 11.530839 -281.211515) (xy 11.540998 -281.21102) (xy 12.940538 -281.21102)
			(xy 12.950696 -281.211502) (xy 12.969463 -281.219285) (xy 12.983826 -281.233654) (xy 12.991602 -281.252424)
			(xy 12.9921 -281.262582) (xy 12.9921 -281.671522) (xy 19.033236 -281.671522) (xy 19.033236 -281.262582)
			(xy 19.033718 -281.252423) (xy 19.041498 -281.233654) (xy 19.055867 -281.219289) (xy 19.074639 -281.211515)
			(xy 19.084798 -281.21102) (xy 20.484338 -281.21102) (xy 20.494496 -281.211502) (xy 20.513263 -281.219285)
			(xy 20.527626 -281.233654) (xy 20.535402 -281.252424) (xy 20.5359 -281.262582) (xy 20.5359 -281.671522)
			(xy 26.577036 -281.671522) (xy 26.577036 -281.262582) (xy 26.577518 -281.252423) (xy 26.585298 -281.233654)
			(xy 26.599667 -281.219289) (xy 26.618439 -281.211515) (xy 26.628598 -281.21102) (xy 28.028138 -281.21102)
			(xy 28.038296 -281.211502) (xy 28.057063 -281.219285) (xy 28.071426 -281.233654) (xy 28.079202 -281.252424)
			(xy 28.0797 -281.262582) (xy 28.0797 -281.671522) (xy 34.120836 -281.671522) (xy 34.120836 -281.262582)
			(xy 34.121318 -281.252423) (xy 34.129098 -281.233654) (xy 34.143467 -281.219289) (xy 34.162239 -281.211515)
			(xy 34.172398 -281.21102) (xy 35.571938 -281.21102) (xy 35.582096 -281.211502) (xy 35.600863 -281.219285)
			(xy 35.615226 -281.233654) (xy 35.623002 -281.252424) (xy 35.6235 -281.262582) (xy 35.6235 -281.671522)
			(xy 41.664636 -281.671522) (xy 41.664636 -281.262582) (xy 41.665118 -281.252423) (xy 41.672898 -281.233654)
			(xy 41.687267 -281.219289) (xy 41.706039 -281.211515) (xy 41.716198 -281.21102) (xy 43.115738 -281.21102)
			(xy 43.125896 -281.211502) (xy 43.144663 -281.219285) (xy 43.159026 -281.233654) (xy 43.166802 -281.252424)
			(xy 43.1673 -281.262582) (xy 43.1673 -281.671522) (xy 49.208436 -281.671522) (xy 49.208436 -281.262582)
			(xy 49.208918 -281.252423) (xy 49.216698 -281.233654) (xy 49.231067 -281.219289) (xy 49.249839 -281.211515)
			(xy 49.259998 -281.21102) (xy 50.659538 -281.21102) (xy 50.669696 -281.211502) (xy 50.688463 -281.219285)
			(xy 50.702826 -281.233654) (xy 50.710602 -281.252424) (xy 50.7111 -281.262582) (xy 50.7111 -281.671522)
			(xy 56.752236 -281.671522) (xy 56.752236 -281.262582) (xy 56.752718 -281.252423) (xy 56.760498 -281.233654)
			(xy 56.774867 -281.219289) (xy 56.793639 -281.211515) (xy 56.803798 -281.21102) (xy 58.203338 -281.21102)
			(xy 58.213496 -281.211502) (xy 58.232263 -281.219285) (xy 58.246626 -281.233654) (xy 58.254402 -281.252424)
			(xy 58.2549 -281.262582) (xy 58.2549 -281.671522) (xy 64.296036 -281.671522) (xy 64.296036 -281.262582)
			(xy 64.296518 -281.252423) (xy 64.304298 -281.233654) (xy 64.318667 -281.219289) (xy 64.337439 -281.211515)
			(xy 64.347598 -281.21102) (xy 65.747138 -281.21102) (xy 65.757296 -281.211502) (xy 65.776063 -281.219285)
			(xy 65.790426 -281.233654) (xy 65.798202 -281.252424) (xy 65.7987 -281.262582) (xy 65.7987 -281.59202)
			(xy 88.865456 -281.59202) (xy 88.86595 -281.566675) (xy 88.87372 -281.516583) (xy 88.889066 -281.468271)
			(xy 88.911624 -281.422876) (xy 88.940864 -281.381469) (xy 88.976098 -281.345025) (xy 89.016493 -281.314403)
			(xy 89.0611 -281.290323) (xy 89.108866 -281.273355) (xy 89.13368 -281.26817) (xy 89.15654 -281.263852)
			(xy 89.361518 -280.909014) (xy 89.353898 -280.88717) (xy 89.345254 -280.860761) (xy 89.335932 -280.805986)
			(xy 89.335356 -280.778204) (xy 89.335819 -280.752307) (xy 89.343918 -280.70115) (xy 89.359916 -280.651889)
			(xy 89.383421 -280.605736) (xy 89.413854 -280.563826) (xy 89.450466 -280.527191) (xy 89.492357 -280.496731)
			(xy 89.538495 -280.473197) (xy 89.587746 -280.457167) (xy 89.638897 -280.449036) (xy 89.664794 -280.448512)
			(xy 89.690671 -280.448974) (xy 89.741789 -280.457066) (xy 89.791012 -280.473052) (xy 89.83713 -280.496539)
			(xy 89.879007 -280.526949) (xy 89.915615 -280.563533) (xy 89.946051 -280.605391) (xy 89.969567 -280.651494)
			(xy 89.985584 -280.700707) (xy 89.993709 -280.751819) (xy 89.994232 -280.777696) (xy 89.994232 -280.778204)
			(xy 92.154756 -280.778204) (xy 92.155193 -280.752292) (xy 92.163301 -280.701107) (xy 92.179316 -280.65182)
			(xy 92.202845 -280.605646) (xy 92.233308 -280.563722) (xy 92.269955 -280.527079) (xy 92.311884 -280.496622)
			(xy 92.358061 -280.473099) (xy 92.40735 -280.45709) (xy 92.458536 -280.44899) (xy 92.484448 -280.448512)
			(xy 92.510327 -280.448924) (xy 92.561446 -280.457025) (xy 92.61067 -280.473018) (xy 92.656788 -280.496511)
			(xy 92.698665 -280.526927) (xy 92.735272 -280.563516) (xy 92.765707 -280.605379) (xy 92.789222 -280.651486)
			(xy 92.805239 -280.700702) (xy 92.813363 -280.751818) (xy 92.813886 -280.777696) (xy 92.813886 -280.778204)
			(xy 92.813354 -280.804107) (xy 94.97442 -280.804107) (xy 94.97442 -280.752293) (xy 94.982526 -280.701118)
			(xy 94.998537 -280.65184) (xy 95.022059 -280.605674) (xy 95.052514 -280.563756) (xy 95.089151 -280.527118)
			(xy 95.131069 -280.496662) (xy 95.177235 -280.473139) (xy 95.226512 -280.457127) (xy 95.277687 -280.449021)
			(xy 95.303594 -280.448512) (xy 95.329106 -280.448992) (xy 95.379521 -280.456852) (xy 95.428122 -280.472385)
			(xy 95.473751 -280.495221) (xy 95.515316 -280.524814) (xy 95.551826 -280.560457) (xy 95.5675 -280.580592)
			(xy 95.979742 -280.580592) (xy 95.995389 -280.560435) (xy 96.031904 -280.524793) (xy 96.073475 -280.495202)
			(xy 96.119109 -280.472369) (xy 96.167716 -280.45684) (xy 96.218134 -280.448986) (xy 96.243648 -280.448512)
			(xy 96.269553 -280.449016) (xy 96.320725 -280.457128) (xy 96.369997 -280.473144) (xy 96.416159 -280.49667)
			(xy 96.458071 -280.527127) (xy 96.494704 -280.563765) (xy 96.525155 -280.605682) (xy 96.548675 -280.651847)
			(xy 96.564684 -280.701122) (xy 96.572788 -280.752295) (xy 96.572788 -280.804105) (xy 96.564684 -280.855278)
			(xy 96.548675 -280.904553) (xy 96.525155 -280.950718) (xy 96.494704 -280.992635) (xy 96.458071 -281.029273)
			(xy 96.416159 -281.05973) (xy 96.369997 -281.083256) (xy 96.320725 -281.099272) (xy 96.269553 -281.107384)
			(xy 96.243648 -281.107896) (xy 96.218137 -281.107382) (xy 96.167724 -281.099529) (xy 96.119123 -281.084002)
			(xy 96.073495 -281.061173) (xy 96.031928 -281.031586) (xy 95.995417 -280.995948) (xy 95.979742 -280.975816)
			(xy 95.5675 -280.975816) (xy 95.551831 -280.995955) (xy 95.51532 -281.031598) (xy 95.473753 -281.06119)
			(xy 95.428124 -281.084026) (xy 95.379522 -281.099559) (xy 95.329106 -281.107419) (xy 95.303594 -281.107896)
			(xy 95.277687 -281.107379) (xy 95.226512 -281.099273) (xy 95.177235 -281.083261) (xy 95.131069 -281.059738)
			(xy 95.089151 -281.029282) (xy 95.052514 -280.992644) (xy 95.022059 -280.950726) (xy 94.998537 -280.90456)
			(xy 94.982526 -280.855282) (xy 94.97442 -280.804107) (xy 92.813354 -280.804107) (xy 92.813315 -280.805986)
			(xy 92.803991 -280.860762) (xy 92.795344 -280.88717) (xy 92.787724 -280.909014) (xy 92.992702 -281.263852)
			(xy 93.015562 -281.26817) (xy 93.04036 -281.273381) (xy 93.0881 -281.290365) (xy 93.132678 -281.314454)
			(xy 93.173045 -281.345081) (xy 93.20825 -281.381525) (xy 93.237463 -281.422927) (xy 93.259996 -281.468312)
			(xy 93.275318 -281.51661) (xy 93.283069 -281.566685) (xy 93.283532 -281.59202) (xy 93.283024 -281.617907)
			(xy 93.274925 -281.669045) (xy 93.258926 -281.718285) (xy 93.23542 -281.764417) (xy 93.204988 -281.806304)
			(xy 93.168378 -281.842914) (xy 93.126491 -281.873346) (xy 93.080359 -281.896852) (xy 93.031119 -281.912851)
			(xy 92.979981 -281.92095) (xy 92.928207 -281.92095) (xy 92.877069 -281.912851) (xy 92.827829 -281.896852)
			(xy 92.781697 -281.873346) (xy 92.73981 -281.842914) (xy 92.7032 -281.806304) (xy 92.672768 -281.764417)
			(xy 92.649262 -281.718285) (xy 92.633263 -281.669045) (xy 92.625164 -281.617907) (xy 92.624656 -281.59202)
			(xy 92.625203 -281.564313) (xy 92.634391 -281.509667) (xy 92.642944 -281.483308) (xy 92.650564 -281.461464)
			(xy 92.445586 -281.106372) (xy 92.422726 -281.102054) (xy 92.397931 -281.096829) (xy 92.350193 -281.079845)
			(xy 92.305616 -281.055757) (xy 92.265251 -281.025131) (xy 92.230046 -280.988689) (xy 92.200833 -280.947289)
			(xy 92.178299 -280.901907) (xy 92.162974 -280.853611) (xy 92.15522 -280.803539) (xy 92.154756 -280.778204)
			(xy 89.994232 -280.778204) (xy 89.993765 -280.803528) (xy 89.986033 -280.853583) (xy 89.970734 -280.901865)
			(xy 89.94823 -280.947239) (xy 89.91905 -280.988637) (xy 89.883881 -281.025084) (xy 89.843551 -281.055722)
			(xy 89.799008 -281.079831) (xy 89.751302 -281.096842) (xy 89.726516 -281.102054) (xy 89.703656 -281.106372)
			(xy 89.498678 -281.46121) (xy 89.506298 -281.483054) (xy 89.51491 -281.50934) (xy 89.524233 -281.563858)
			(xy 89.52484 -281.591512) (xy 89.52484 -281.59202) (xy 89.524332 -281.617905) (xy 90.745336 -281.617905)
			(xy 90.745336 -281.566095) (xy 90.753441 -281.514922) (xy 90.769451 -281.465646) (xy 90.792973 -281.419482)
			(xy 90.823426 -281.377566) (xy 90.860062 -281.34093) (xy 90.901977 -281.310476) (xy 90.948141 -281.286954)
			(xy 90.997416 -281.270943) (xy 91.048589 -281.262837) (xy 91.074494 -281.262328) (xy 91.100006 -281.262802)
			(xy 91.150421 -281.270662) (xy 91.199024 -281.286196) (xy 91.244652 -281.309033) (xy 91.286218 -281.338627)
			(xy 91.322727 -281.374272) (xy 91.3384 -281.394408) (xy 91.750388 -281.394408) (xy 91.766071 -281.37428)
			(xy 91.802578 -281.338635) (xy 91.844142 -281.309041) (xy 91.889768 -281.286203) (xy 91.938369 -281.270668)
			(xy 91.988782 -281.262806) (xy 92.014294 -281.262328) (xy 92.040205 -281.262769) (xy 92.09139 -281.270875)
			(xy 92.140676 -281.286888) (xy 92.186851 -281.310415) (xy 92.228777 -281.340875) (xy 92.265421 -281.377519)
			(xy 92.295882 -281.419444) (xy 92.319409 -281.465618) (xy 92.335423 -281.514904) (xy 92.34353 -281.566089)
			(xy 92.34353 -281.617911) (xy 92.335423 -281.669096) (xy 92.319409 -281.718382) (xy 92.295882 -281.764556)
			(xy 92.265421 -281.806481) (xy 92.228777 -281.843125) (xy 92.186851 -281.873585) (xy 92.140676 -281.897112)
			(xy 92.09139 -281.913125) (xy 92.040205 -281.921231) (xy 92.014294 -281.921712) (xy 91.988782 -281.921231)
			(xy 91.938368 -281.91337) (xy 91.889767 -281.897836) (xy 91.844138 -281.875001) (xy 91.802573 -281.845409)
			(xy 91.766062 -281.809767) (xy 91.750388 -281.789632) (xy 91.3384 -281.789632) (xy 91.322735 -281.809774)
			(xy 91.286223 -281.845417) (xy 91.244655 -281.875008) (xy 91.199025 -281.897843) (xy 91.150422 -281.913376)
			(xy 91.100006 -281.921235) (xy 91.074494 -281.921712) (xy 91.048589 -281.921163) (xy 90.997416 -281.913057)
			(xy 90.948141 -281.897046) (xy 90.901977 -281.873524) (xy 90.860062 -281.84307) (xy 90.823426 -281.806434)
			(xy 90.792973 -281.764518) (xy 90.769451 -281.718354) (xy 90.753441 -281.669078) (xy 90.745336 -281.617905)
			(xy 89.524332 -281.617905) (xy 89.524332 -281.617927) (xy 89.516226 -281.669104) (xy 89.500214 -281.718383)
			(xy 89.476691 -281.76455) (xy 89.446235 -281.806469) (xy 89.409597 -281.843107) (xy 89.367678 -281.873563)
			(xy 89.321511 -281.897086) (xy 89.272232 -281.913098) (xy 89.221055 -281.921204) (xy 89.169241 -281.921204)
			(xy 89.118064 -281.913098) (xy 89.068785 -281.897086) (xy 89.022618 -281.873563) (xy 88.980699 -281.843107)
			(xy 88.944061 -281.806469) (xy 88.913605 -281.76455) (xy 88.890082 -281.718383) (xy 88.87407 -281.669104)
			(xy 88.865964 -281.617927) (xy 88.865456 -281.59202) (xy 65.7987 -281.59202) (xy 65.7987 -281.671522)
			(xy 65.798186 -281.681677) (xy 65.790411 -281.700439) (xy 65.776052 -281.714802) (xy 65.757292 -281.722583)
			(xy 65.747138 -281.723084) (xy 64.347598 -281.723084) (xy 64.337443 -281.722569) (xy 64.318678 -281.714798)
			(xy 64.304313 -281.700439) (xy 64.296535 -281.681677) (xy 64.296036 -281.671522) (xy 58.2549 -281.671522)
			(xy 58.254386 -281.681677) (xy 58.246611 -281.700439) (xy 58.232252 -281.714802) (xy 58.213492 -281.722583)
			(xy 58.203338 -281.723084) (xy 56.803798 -281.723084) (xy 56.793643 -281.722569) (xy 56.774878 -281.714798)
			(xy 56.760513 -281.700439) (xy 56.752735 -281.681677) (xy 56.752236 -281.671522) (xy 50.7111 -281.671522)
			(xy 50.710586 -281.681677) (xy 50.702811 -281.700439) (xy 50.688452 -281.714802) (xy 50.669692 -281.722583)
			(xy 50.659538 -281.723084) (xy 49.259998 -281.723084) (xy 49.249843 -281.722569) (xy 49.231078 -281.714798)
			(xy 49.216713 -281.700439) (xy 49.208935 -281.681677) (xy 49.208436 -281.671522) (xy 43.1673 -281.671522)
			(xy 43.166786 -281.681677) (xy 43.159011 -281.700439) (xy 43.144652 -281.714802) (xy 43.125892 -281.722583)
			(xy 43.115738 -281.723084) (xy 41.716198 -281.723084) (xy 41.706043 -281.722569) (xy 41.687278 -281.714798)
			(xy 41.672913 -281.700439) (xy 41.665135 -281.681677) (xy 41.664636 -281.671522) (xy 35.6235 -281.671522)
			(xy 35.622986 -281.681677) (xy 35.615211 -281.700439) (xy 35.600852 -281.714802) (xy 35.582092 -281.722583)
			(xy 35.571938 -281.723084) (xy 34.172398 -281.723084) (xy 34.162243 -281.722569) (xy 34.143478 -281.714798)
			(xy 34.129113 -281.700439) (xy 34.121335 -281.681677) (xy 34.120836 -281.671522) (xy 28.0797 -281.671522)
			(xy 28.079186 -281.681677) (xy 28.071411 -281.700439) (xy 28.057052 -281.714802) (xy 28.038292 -281.722583)
			(xy 28.028138 -281.723084) (xy 26.628598 -281.723084) (xy 26.618443 -281.722569) (xy 26.599678 -281.714798)
			(xy 26.585313 -281.700439) (xy 26.577535 -281.681677) (xy 26.577036 -281.671522) (xy 20.5359 -281.671522)
			(xy 20.535386 -281.681677) (xy 20.527611 -281.700439) (xy 20.513252 -281.714802) (xy 20.494492 -281.722583)
			(xy 20.484338 -281.723084) (xy 19.084798 -281.723084) (xy 19.074643 -281.722569) (xy 19.055878 -281.714798)
			(xy 19.041513 -281.700439) (xy 19.033735 -281.681677) (xy 19.033236 -281.671522) (xy 12.9921 -281.671522)
			(xy 12.991586 -281.681677) (xy 12.983811 -281.700439) (xy 12.969452 -281.714802) (xy 12.950692 -281.722583)
			(xy 12.940538 -281.723084) (xy 11.540998 -281.723084) (xy 11.530843 -281.722569) (xy 11.512078 -281.714798)
			(xy 11.497713 -281.700439) (xy 11.489935 -281.681677) (xy 11.489436 -281.671522) (xy 2.509012 -281.671522)
			(xy 2.509012 -282.521406) (xy 7.389368 -282.521406) (xy 7.389368 -282.112466) (xy 7.389806 -282.102302)
			(xy 7.397597 -282.083527) (xy 7.41198 -282.069162) (xy 7.430766 -282.061394) (xy 7.44093 -282.060904)
			(xy 8.84047 -282.060904) (xy 8.850622 -282.061457) (xy 8.869384 -282.069215) (xy 8.883749 -282.083563)
			(xy 8.891531 -282.102315) (xy 8.892032 -282.112466) (xy 8.892032 -282.521406) (xy 14.933168 -282.521406)
			(xy 14.933168 -282.112466) (xy 14.933606 -282.102302) (xy 14.941397 -282.083527) (xy 14.95578 -282.069162)
			(xy 14.974566 -282.061394) (xy 14.98473 -282.060904) (xy 16.38427 -282.060904) (xy 16.394422 -282.061457)
			(xy 16.413184 -282.069215) (xy 16.427549 -282.083563) (xy 16.435331 -282.102315) (xy 16.435832 -282.112466)
			(xy 16.435832 -282.521406) (xy 22.476968 -282.521406) (xy 22.476968 -282.112466) (xy 22.477406 -282.102302)
			(xy 22.485197 -282.083527) (xy 22.49958 -282.069162) (xy 22.518366 -282.061394) (xy 22.52853 -282.060904)
			(xy 23.92807 -282.060904) (xy 23.938222 -282.061457) (xy 23.956984 -282.069215) (xy 23.971349 -282.083563)
			(xy 23.979131 -282.102315) (xy 23.979632 -282.112466) (xy 23.979632 -282.521406) (xy 30.020768 -282.521406)
			(xy 30.020768 -282.112466) (xy 30.021206 -282.102302) (xy 30.028997 -282.083527) (xy 30.04338 -282.069162)
			(xy 30.062166 -282.061394) (xy 30.07233 -282.060904) (xy 31.47187 -282.060904) (xy 31.482022 -282.061457)
			(xy 31.500784 -282.069215) (xy 31.515149 -282.083563) (xy 31.522931 -282.102315) (xy 31.523432 -282.112466)
			(xy 31.523432 -282.521406) (xy 37.564568 -282.521406) (xy 37.564568 -282.112466) (xy 37.565006 -282.102302)
			(xy 37.572797 -282.083527) (xy 37.58718 -282.069162) (xy 37.605966 -282.061394) (xy 37.61613 -282.060904)
			(xy 39.01567 -282.060904) (xy 39.025822 -282.061457) (xy 39.044584 -282.069215) (xy 39.058949 -282.083563)
			(xy 39.066731 -282.102315) (xy 39.067232 -282.112466) (xy 39.067232 -282.521406) (xy 45.108368 -282.521406)
			(xy 45.108368 -282.112466) (xy 45.108806 -282.102302) (xy 45.116597 -282.083527) (xy 45.13098 -282.069162)
			(xy 45.149766 -282.061394) (xy 45.15993 -282.060904) (xy 46.55947 -282.060904) (xy 46.569622 -282.061457)
			(xy 46.588384 -282.069215) (xy 46.602749 -282.083563) (xy 46.610531 -282.102315) (xy 46.611032 -282.112466)
			(xy 46.611032 -282.521406) (xy 52.652168 -282.521406) (xy 52.652168 -282.112466) (xy 52.652606 -282.102302)
			(xy 52.660397 -282.083527) (xy 52.67478 -282.069162) (xy 52.693566 -282.061394) (xy 52.70373 -282.060904)
			(xy 54.10327 -282.060904) (xy 54.113422 -282.061457) (xy 54.132184 -282.069215) (xy 54.146549 -282.083563)
			(xy 54.154331 -282.102315) (xy 54.154832 -282.112466) (xy 54.154832 -282.521406) (xy 60.195968 -282.521406)
			(xy 60.195968 -282.112466) (xy 60.196406 -282.102302) (xy 60.204197 -282.083527) (xy 60.21858 -282.069162)
			(xy 60.237366 -282.061394) (xy 60.24753 -282.060904) (xy 61.64707 -282.060904) (xy 61.657222 -282.061457)
			(xy 61.675984 -282.069215) (xy 61.690349 -282.083563) (xy 61.698131 -282.102315) (xy 61.698632 -282.112466)
			(xy 61.698632 -282.405836) (xy 87.455756 -282.405836) (xy 87.456264 -282.379949) (xy 87.464363 -282.328811)
			(xy 87.480362 -282.279571) (xy 87.503868 -282.233439) (xy 87.5343 -282.191552) (xy 87.57091 -282.154942)
			(xy 87.612797 -282.12451) (xy 87.658929 -282.101004) (xy 87.708169 -282.085005) (xy 87.759307 -282.076906)
			(xy 87.811081 -282.076906) (xy 87.862219 -282.085005) (xy 87.911459 -282.101004) (xy 87.957591 -282.12451)
			(xy 87.999478 -282.154942) (xy 88.036088 -282.191552) (xy 88.06652 -282.233439) (xy 88.090026 -282.279571)
			(xy 88.106025 -282.328811) (xy 88.114124 -282.379949) (xy 88.114632 -282.405836) (xy 88.114145 -282.431709)
			(xy 88.396026 -282.431709) (xy 88.396026 -282.379891) (xy 88.404133 -282.328711) (xy 88.420147 -282.27943)
			(xy 88.443674 -282.233261) (xy 88.474134 -282.191341) (xy 88.510778 -282.154703) (xy 88.552702 -282.124249)
			(xy 88.598874 -282.100729) (xy 88.648158 -282.084722) (xy 88.699339 -282.076622) (xy 88.725248 -282.076144)
			(xy 88.750741 -282.076648) (xy 88.801118 -282.084503) (xy 88.849682 -282.100032) (xy 88.895269 -282.122865)
			(xy 88.936791 -282.152454) (xy 88.973252 -282.188093) (xy 88.9889 -282.208224) (xy 89.401396 -282.208224)
			(xy 89.417024 -282.188075) (xy 89.453488 -282.152433) (xy 89.495013 -282.122841) (xy 89.540604 -282.100006)
			(xy 89.589171 -282.084474) (xy 89.639553 -282.076619) (xy 89.665048 -282.076144) (xy 89.690956 -282.076584)
			(xy 89.742132 -282.084696) (xy 89.79141 -282.100714) (xy 89.837576 -282.124242) (xy 89.879493 -282.154702)
			(xy 89.916129 -282.191344) (xy 89.946583 -282.233265) (xy 89.970105 -282.279434) (xy 89.986115 -282.328714)
			(xy 89.99422 -282.379892) (xy 89.99422 -282.431708) (xy 89.986115 -282.482886) (xy 89.970105 -282.532166)
			(xy 89.946583 -282.578335) (xy 89.916129 -282.620256) (xy 89.879493 -282.656898) (xy 89.837576 -282.687358)
			(xy 89.79141 -282.710886) (xy 89.742132 -282.726904) (xy 89.690956 -282.735016) (xy 89.665048 -282.735528)
			(xy 89.639556 -282.734998) (xy 89.589182 -282.727145) (xy 89.54062 -282.711619) (xy 89.495033 -282.688791)
			(xy 89.453511 -282.659207) (xy 89.417046 -282.623576) (xy 89.401396 -282.603448) (xy 88.9889 -282.603448)
			(xy 88.973236 -282.623567) (xy 88.936776 -282.659207) (xy 88.895259 -282.6888) (xy 88.849675 -282.71164)
			(xy 88.801115 -282.727179) (xy 88.750741 -282.735046) (xy 88.725248 -282.735528) (xy 88.699339 -282.734978)
			(xy 88.648158 -282.726878) (xy 88.598874 -282.710871) (xy 88.552702 -282.687351) (xy 88.510778 -282.656897)
			(xy 88.474134 -282.620259) (xy 88.443674 -282.578339) (xy 88.420147 -282.53217) (xy 88.404133 -282.482889)
			(xy 88.396026 -282.431709) (xy 88.114145 -282.431709) (xy 88.11411 -282.433545) (xy 88.10491 -282.488191)
			(xy 88.096344 -282.514548) (xy 88.08847 -282.536646) (xy 88.293702 -282.891738) (xy 88.316562 -282.896056)
			(xy 88.341357 -282.90128) (xy 88.389096 -282.918263) (xy 88.433673 -282.942351) (xy 88.47404 -282.972977)
			(xy 88.509244 -283.009419) (xy 88.538458 -283.050819) (xy 88.560992 -283.096202) (xy 88.576316 -283.144498)
			(xy 88.584068 -283.194571) (xy 88.584532 -283.219906) (xy 90.745056 -283.219906) (xy 90.74558 -283.194573)
			(xy 90.75333 -283.144505) (xy 90.768649 -283.096211) (xy 90.791176 -283.05083) (xy 90.820381 -283.009429)
			(xy 90.855576 -282.972983) (xy 90.895932 -282.942351) (xy 90.9405 -282.918254) (xy 90.988229 -282.901258)
			(xy 91.013026 -282.896056) (xy 91.035886 -282.891738) (xy 91.241118 -282.536392) (xy 91.233498 -282.514548)
			(xy 91.224857 -282.488204) (xy 91.215541 -282.433555) (xy 91.214956 -282.405836) (xy 91.215464 -282.379929)
			(xy 91.22357 -282.328752) (xy 91.239582 -282.279473) (xy 91.263105 -282.233306) (xy 91.293561 -282.191387)
			(xy 91.330199 -282.154749) (xy 91.372118 -282.124293) (xy 91.418285 -282.10077) (xy 91.467564 -282.084758)
			(xy 91.518741 -282.076652) (xy 91.570555 -282.076652) (xy 91.621732 -282.084758) (xy 91.671011 -282.10077)
			(xy 91.717178 -282.124293) (xy 91.759097 -282.154749) (xy 91.795735 -282.191387) (xy 91.826191 -282.233306)
			(xy 91.849714 -282.279473) (xy 91.865726 -282.328752) (xy 91.873832 -282.379929) (xy 91.87434 -282.405836)
			(xy 93.094556 -282.405836) (xy 93.094974 -282.380488) (xy 93.102757 -282.330393) (xy 93.118114 -282.282079)
			(xy 93.140683 -282.236685) (xy 93.169933 -282.195278) (xy 93.205175 -282.158835) (xy 93.245578 -282.128214)
			(xy 93.290191 -282.104137) (xy 93.337964 -282.08717) (xy 93.36278 -282.081986) (xy 93.38564 -282.077668)
			(xy 93.590618 -281.72283) (xy 93.582744 -281.700986) (xy 93.574162 -281.674568) (xy 93.564967 -281.619792)
			(xy 93.564456 -281.59202) (xy 93.564964 -281.566133) (xy 93.573063 -281.514995) (xy 93.589062 -281.465755)
			(xy 93.612568 -281.419623) (xy 93.643 -281.377736) (xy 93.67961 -281.341126) (xy 93.721497 -281.310694)
			(xy 93.767629 -281.287188) (xy 93.816869 -281.271189) (xy 93.868007 -281.26309) (xy 93.919781 -281.26309)
			(xy 93.970919 -281.271189) (xy 94.020159 -281.287188) (xy 94.066291 -281.310694) (xy 94.108178 -281.341126)
			(xy 94.144788 -281.377736) (xy 94.17522 -281.419623) (xy 94.198726 -281.465755) (xy 94.214725 -281.514995)
			(xy 94.222824 -281.566133) (xy 94.223332 -281.59202) (xy 94.222842 -281.617354) (xy 94.215087 -281.667425)
			(xy 94.199764 -281.71572) (xy 94.177233 -281.761102) (xy 94.148024 -281.802503) (xy 94.112825 -281.838948)
			(xy 94.072465 -281.869579) (xy 94.027893 -281.893676) (xy 93.980161 -281.910669) (xy 93.955362 -281.91587)
			(xy 93.932502 -281.920188) (xy 93.727524 -282.275026) (xy 93.735398 -282.297124) (xy 93.744018 -282.323474)
			(xy 93.753346 -282.378119) (xy 93.75394 -282.405836) (xy 94.974156 -282.405836) (xy 94.974616 -282.380501)
			(xy 94.982377 -282.33043) (xy 94.997705 -282.282135) (xy 95.020241 -282.236753) (xy 95.049454 -282.195352)
			(xy 95.084656 -282.158908) (xy 95.125019 -282.128277) (xy 95.169592 -282.104181) (xy 95.217327 -282.087187)
			(xy 95.242126 -282.081986) (xy 95.264986 -282.077668) (xy 95.470218 -281.722322) (xy 95.462598 -281.700478)
			(xy 95.45397 -281.674197) (xy 95.444658 -281.619675) (xy 95.444056 -281.59202) (xy 95.444564 -281.566113)
			(xy 95.45267 -281.514936) (xy 95.468682 -281.465657) (xy 95.492205 -281.41949) (xy 95.522661 -281.377571)
			(xy 95.559299 -281.340933) (xy 95.601218 -281.310477) (xy 95.647385 -281.286954) (xy 95.696664 -281.270942)
			(xy 95.747841 -281.262836) (xy 95.799655 -281.262836) (xy 95.850832 -281.270942) (xy 95.900111 -281.286954)
			(xy 95.946278 -281.310477) (xy 95.988197 -281.340933) (xy 96.024835 -281.377571) (xy 96.055291 -281.41949)
			(xy 96.078814 -281.465657) (xy 96.094826 -281.514936) (xy 96.102932 -281.566113) (xy 96.10344 -281.59202)
			(xy 97.323656 -281.59202) (xy 97.32415 -281.566675) (xy 97.33192 -281.516583) (xy 97.347266 -281.468271)
			(xy 97.369824 -281.422876) (xy 97.399064 -281.381469) (xy 97.434298 -281.345025) (xy 97.474693 -281.314403)
			(xy 97.5193 -281.290323) (xy 97.567066 -281.273355) (xy 97.59188 -281.26817) (xy 97.61474 -281.263852)
			(xy 97.819718 -280.909014) (xy 97.811844 -280.88717) (xy 97.803259 -280.860753) (xy 97.794066 -280.805977)
			(xy 97.793556 -280.778204) (xy 97.794064 -280.752317) (xy 97.802163 -280.701179) (xy 97.818162 -280.651939)
			(xy 97.841668 -280.605807) (xy 97.8721 -280.56392) (xy 97.90871 -280.52731) (xy 97.950597 -280.496878)
			(xy 97.996729 -280.473372) (xy 98.045969 -280.457373) (xy 98.097107 -280.449274) (xy 98.148881 -280.449274)
			(xy 98.200019 -280.457373) (xy 98.249259 -280.473372) (xy 98.295391 -280.496878) (xy 98.337278 -280.52731)
			(xy 98.373888 -280.56392) (xy 98.40432 -280.605807) (xy 98.427826 -280.651939) (xy 98.443825 -280.701179)
			(xy 98.451924 -280.752317) (xy 98.452432 -280.778204) (xy 100.612956 -280.778204) (xy 100.613464 -280.752317)
			(xy 100.621563 -280.701179) (xy 100.637562 -280.651939) (xy 100.661068 -280.605807) (xy 100.6915 -280.56392)
			(xy 100.72811 -280.52731) (xy 100.769997 -280.496878) (xy 100.816129 -280.473372) (xy 100.865369 -280.457373)
			(xy 100.916507 -280.449274) (xy 100.968281 -280.449274) (xy 101.019419 -280.457373) (xy 101.068659 -280.473372)
			(xy 101.114791 -280.496878) (xy 101.156678 -280.52731) (xy 101.193288 -280.56392) (xy 101.22372 -280.605807)
			(xy 101.247226 -280.651939) (xy 101.263225 -280.701179) (xy 101.271324 -280.752317) (xy 101.271832 -280.778204)
			(xy 103.432356 -280.778204) (xy 103.432864 -280.752317) (xy 103.440963 -280.701179) (xy 103.456962 -280.651939)
			(xy 103.480468 -280.605807) (xy 103.5109 -280.56392) (xy 103.54751 -280.52731) (xy 103.589397 -280.496878)
			(xy 103.635529 -280.473372) (xy 103.684769 -280.457373) (xy 103.735907 -280.449274) (xy 103.787681 -280.449274)
			(xy 103.838819 -280.457373) (xy 103.888059 -280.473372) (xy 103.934191 -280.496878) (xy 103.976078 -280.52731)
			(xy 104.012688 -280.56392) (xy 104.04312 -280.605807) (xy 104.066626 -280.651939) (xy 104.082625 -280.701179)
			(xy 104.090724 -280.752317) (xy 104.091232 -280.778204) (xy 104.372156 -280.778204) (xy 104.372678 -280.752871)
			(xy 104.380429 -280.702803) (xy 104.395748 -280.654509) (xy 104.418275 -280.609127) (xy 104.44748 -280.567726)
			(xy 104.482675 -280.531281) (xy 104.523032 -280.500649) (xy 104.567599 -280.476552) (xy 104.615329 -280.459556)
			(xy 104.640126 -280.454354) (xy 104.662986 -280.450036) (xy 104.868218 -280.09469) (xy 104.860598 -280.072592)
			(xy 104.851973 -280.04631) (xy 104.842659 -279.991789) (xy 104.842056 -279.964134) (xy 104.842564 -279.938227)
			(xy 104.85067 -279.88705) (xy 104.866682 -279.837771) (xy 104.890205 -279.791604) (xy 104.920661 -279.749685)
			(xy 104.957299 -279.713047) (xy 104.999218 -279.682591) (xy 105.045385 -279.659068) (xy 105.094664 -279.643056)
			(xy 105.145841 -279.63495) (xy 105.197655 -279.63495) (xy 105.248832 -279.643056) (xy 105.298111 -279.659068)
			(xy 105.344278 -279.682591) (xy 105.386197 -279.713047) (xy 105.422835 -279.749685) (xy 105.453291 -279.791604)
			(xy 105.476814 -279.837771) (xy 105.492826 -279.88705) (xy 105.500932 -279.938227) (xy 105.50144 -279.964134)
			(xy 105.501313 -279.9715) (xy 162.162236 -279.9715) (xy 162.162236 -279.56256) (xy 162.16259 -279.552399)
			(xy 162.170405 -279.533639) (xy 162.184823 -279.519315) (xy 162.203634 -279.511624) (xy 162.213798 -279.511252)
			(xy 163.613338 -279.511252) (xy 163.623469 -279.511696) (xy 163.642193 -279.519438) (xy 163.656548 -279.533738)
			(xy 163.664364 -279.552431) (xy 163.6649 -279.56256) (xy 163.6649 -279.9715) (xy 169.706036 -279.9715)
			(xy 169.706036 -279.56256) (xy 169.70639 -279.552399) (xy 169.714205 -279.533639) (xy 169.728623 -279.519315)
			(xy 169.747434 -279.511624) (xy 169.757598 -279.511252) (xy 171.157138 -279.511252) (xy 171.167269 -279.511696)
			(xy 171.185993 -279.519438) (xy 171.200348 -279.533738) (xy 171.208164 -279.552431) (xy 171.2087 -279.56256)
			(xy 171.2087 -279.9715) (xy 177.249836 -279.9715) (xy 177.249836 -279.56256) (xy 177.25019 -279.552399)
			(xy 177.258005 -279.533639) (xy 177.272423 -279.519315) (xy 177.291234 -279.511624) (xy 177.301398 -279.511252)
			(xy 178.700938 -279.511252) (xy 178.711069 -279.511696) (xy 178.729793 -279.519438) (xy 178.744148 -279.533738)
			(xy 178.751964 -279.552431) (xy 178.7525 -279.56256) (xy 178.7525 -279.9715) (xy 184.793636 -279.9715)
			(xy 184.793636 -279.56256) (xy 184.79399 -279.552399) (xy 184.801805 -279.533639) (xy 184.816223 -279.519315)
			(xy 184.835034 -279.511624) (xy 184.845198 -279.511252) (xy 186.244738 -279.511252) (xy 186.254869 -279.511696)
			(xy 186.273593 -279.519438) (xy 186.287948 -279.533738) (xy 186.295764 -279.552431) (xy 186.2963 -279.56256)
			(xy 186.2963 -279.9715) (xy 192.337436 -279.9715) (xy 192.337436 -279.56256) (xy 192.33779 -279.552399)
			(xy 192.345605 -279.533639) (xy 192.360023 -279.519315) (xy 192.378834 -279.511624) (xy 192.388998 -279.511252)
			(xy 193.788538 -279.511252) (xy 193.798669 -279.511696) (xy 193.817393 -279.519438) (xy 193.831748 -279.533738)
			(xy 193.839564 -279.552431) (xy 193.8401 -279.56256) (xy 193.8401 -279.9715) (xy 199.881236 -279.9715)
			(xy 199.881236 -279.56256) (xy 199.88159 -279.552399) (xy 199.889405 -279.533639) (xy 199.903823 -279.519315)
			(xy 199.922634 -279.511624) (xy 199.932798 -279.511252) (xy 201.332338 -279.511252) (xy 201.342469 -279.511696)
			(xy 201.361193 -279.519438) (xy 201.375548 -279.533738) (xy 201.383364 -279.552431) (xy 201.3839 -279.56256)
			(xy 201.3839 -279.9715) (xy 207.425036 -279.9715) (xy 207.425036 -279.56256) (xy 207.42539 -279.552399)
			(xy 207.433205 -279.533639) (xy 207.447623 -279.519315) (xy 207.466434 -279.511624) (xy 207.476598 -279.511252)
			(xy 208.876138 -279.511252) (xy 208.886269 -279.511696) (xy 208.904993 -279.519438) (xy 208.919348 -279.533738)
			(xy 208.927164 -279.552431) (xy 208.9277 -279.56256) (xy 208.9277 -279.9715) (xy 214.968836 -279.9715)
			(xy 214.968836 -279.56256) (xy 214.96919 -279.552399) (xy 214.977005 -279.533639) (xy 214.991423 -279.519315)
			(xy 215.010234 -279.511624) (xy 215.020398 -279.511252) (xy 216.419938 -279.511252) (xy 216.430069 -279.511696)
			(xy 216.448793 -279.519438) (xy 216.463148 -279.533738) (xy 216.470964 -279.552431) (xy 216.4715 -279.56256)
			(xy 216.4715 -279.9715) (xy 259.429504 -279.9715) (xy 259.429504 -279.56256) (xy 259.429889 -279.552403)
			(xy 259.437699 -279.533649) (xy 259.452106 -279.519327) (xy 259.470906 -279.511629) (xy 259.481066 -279.511252)
			(xy 260.880606 -279.511252) (xy 260.890735 -279.511722) (xy 260.909458 -279.519454) (xy 260.923815 -279.533746)
			(xy 260.931631 -279.552434) (xy 260.932168 -279.56256) (xy 260.932168 -279.9715) (xy 266.973304 -279.9715)
			(xy 266.973304 -279.56256) (xy 266.973689 -279.552403) (xy 266.981499 -279.533649) (xy 266.995906 -279.519327)
			(xy 267.014706 -279.511629) (xy 267.024866 -279.511252) (xy 268.424406 -279.511252) (xy 268.434535 -279.511722)
			(xy 268.453258 -279.519454) (xy 268.467615 -279.533746) (xy 268.475431 -279.552434) (xy 268.475968 -279.56256)
			(xy 268.475968 -279.9715) (xy 274.517104 -279.9715) (xy 274.517104 -279.56256) (xy 274.517489 -279.552403)
			(xy 274.525299 -279.533649) (xy 274.539706 -279.519327) (xy 274.558506 -279.511629) (xy 274.568666 -279.511252)
			(xy 275.968206 -279.511252) (xy 275.978335 -279.511722) (xy 275.997058 -279.519454) (xy 276.011415 -279.533746)
			(xy 276.019231 -279.552434) (xy 276.019768 -279.56256) (xy 276.019768 -279.9715) (xy 282.060904 -279.9715)
			(xy 282.060904 -279.56256) (xy 282.061289 -279.552403) (xy 282.069099 -279.533649) (xy 282.083506 -279.519327)
			(xy 282.102306 -279.511629) (xy 282.112466 -279.511252) (xy 283.512006 -279.511252) (xy 283.522135 -279.511722)
			(xy 283.540858 -279.519454) (xy 283.555215 -279.533746) (xy 283.563031 -279.552434) (xy 283.563568 -279.56256)
			(xy 283.563568 -279.9715) (xy 289.604704 -279.9715) (xy 289.604704 -279.56256) (xy 289.605089 -279.552403)
			(xy 289.612899 -279.533649) (xy 289.627306 -279.519327) (xy 289.646106 -279.511629) (xy 289.656266 -279.511252)
			(xy 291.055806 -279.511252) (xy 291.065935 -279.511722) (xy 291.084658 -279.519454) (xy 291.099015 -279.533746)
			(xy 291.106831 -279.552434) (xy 291.107368 -279.56256) (xy 291.107368 -279.9715) (xy 297.148504 -279.9715)
			(xy 297.148504 -279.56256) (xy 297.148889 -279.552403) (xy 297.156699 -279.533649) (xy 297.171106 -279.519327)
			(xy 297.189906 -279.511629) (xy 297.200066 -279.511252) (xy 298.599606 -279.511252) (xy 298.609735 -279.511722)
			(xy 298.628458 -279.519454) (xy 298.642815 -279.533746) (xy 298.650631 -279.552434) (xy 298.651168 -279.56256)
			(xy 298.651168 -279.9715) (xy 304.692304 -279.9715) (xy 304.692304 -279.56256) (xy 304.692689 -279.552403)
			(xy 304.700499 -279.533649) (xy 304.714906 -279.519327) (xy 304.733706 -279.511629) (xy 304.743866 -279.511252)
			(xy 306.143406 -279.511252) (xy 306.153535 -279.511722) (xy 306.172258 -279.519454) (xy 306.186615 -279.533746)
			(xy 306.194431 -279.552434) (xy 306.194968 -279.56256) (xy 306.194968 -279.9715) (xy 312.236104 -279.9715)
			(xy 312.236104 -279.56256) (xy 312.236489 -279.552403) (xy 312.244299 -279.533649) (xy 312.258706 -279.519327)
			(xy 312.277506 -279.511629) (xy 312.287666 -279.511252) (xy 313.687206 -279.511252) (xy 313.697335 -279.511722)
			(xy 313.716058 -279.519454) (xy 313.730415 -279.533746) (xy 313.738231 -279.552434) (xy 313.738768 -279.56256)
			(xy 313.738768 -279.9715) (xy 313.738378 -279.981658) (xy 313.734916 -279.989983) (xy 336.806103 -279.989983)
			(xy 336.806103 -279.938217) (xy 336.814201 -279.887089) (xy 336.830196 -279.837856) (xy 336.853696 -279.791732)
			(xy 336.884121 -279.749851) (xy 336.920722 -279.713245) (xy 336.9626 -279.682815) (xy 337.008721 -279.659311)
			(xy 337.057952 -279.64331) (xy 337.109079 -279.635206) (xy 337.134962 -279.634696) (xy 337.160473 -279.635206)
			(xy 337.210886 -279.64306) (xy 337.259487 -279.658588) (xy 337.305115 -279.681418) (xy 337.346681 -279.711006)
			(xy 337.383193 -279.746643) (xy 337.398868 -279.766776) (xy 337.810856 -279.766776) (xy 337.826548 -279.746656)
			(xy 337.863055 -279.711012) (xy 337.904617 -279.681418) (xy 337.950241 -279.658579) (xy 337.998839 -279.643041)
			(xy 338.049251 -279.635176) (xy 338.074762 -279.634696) (xy 338.100656 -279.635106) (xy 338.151807 -279.643203)
			(xy 338.201062 -279.659201) (xy 338.247208 -279.682709) (xy 338.289107 -279.713146) (xy 338.325729 -279.749764)
			(xy 338.356171 -279.79166) (xy 338.379684 -279.837803) (xy 338.395689 -279.887056) (xy 338.403791 -279.938206)
			(xy 338.403791 -279.964134) (xy 344.323924 -279.964134) (xy 344.324432 -279.938227) (xy 344.332538 -279.88705)
			(xy 344.34855 -279.837771) (xy 344.372073 -279.791604) (xy 344.402529 -279.749685) (xy 344.439167 -279.713047)
			(xy 344.481086 -279.682591) (xy 344.527253 -279.659068) (xy 344.576532 -279.643056) (xy 344.627709 -279.63495)
			(xy 344.679523 -279.63495) (xy 344.7307 -279.643056) (xy 344.779979 -279.659068) (xy 344.826146 -279.682591)
			(xy 344.868065 -279.713047) (xy 344.904703 -279.749685) (xy 344.935159 -279.791604) (xy 344.958682 -279.837771)
			(xy 344.974694 -279.88705) (xy 344.9828 -279.938227) (xy 344.983308 -279.964134) (xy 344.982671 -279.991925)
			(xy 344.973225 -280.046702) (xy 344.964512 -280.0731) (xy 344.956892 -280.095198) (xy 345.16187 -280.450036)
			(xy 345.18473 -280.454354) (xy 345.209535 -280.459531) (xy 345.257274 -280.476523) (xy 345.30185 -280.500619)
			(xy 345.342215 -280.531252) (xy 345.377417 -280.5677) (xy 345.406629 -280.609105) (xy 345.429161 -280.654492)
			(xy 345.444484 -280.702792) (xy 345.452236 -280.752868) (xy 345.4527 -280.778204) (xy 345.452192 -280.804091)
			(xy 345.444093 -280.855229) (xy 345.428094 -280.904469) (xy 345.404588 -280.950601) (xy 345.374156 -280.992488)
			(xy 345.337546 -281.029098) (xy 345.295659 -281.05953) (xy 345.249527 -281.083036) (xy 345.200287 -281.099035)
			(xy 345.149149 -281.107134) (xy 345.097375 -281.107134) (xy 345.046237 -281.099035) (xy 344.996997 -281.083036)
			(xy 344.950865 -281.05953) (xy 344.908978 -281.029098) (xy 344.872368 -280.992488) (xy 344.841936 -280.950601)
			(xy 344.81843 -280.904469) (xy 344.802431 -280.855229) (xy 344.794332 -280.804091) (xy 344.793824 -280.778204)
			(xy 344.794353 -280.750496) (xy 344.803549 -280.695849) (xy 344.812112 -280.669492) (xy 344.819986 -280.647394)
			(xy 344.614754 -280.292302) (xy 344.591894 -280.287984) (xy 344.567101 -280.282754) (xy 344.519365 -280.265768)
			(xy 344.47479 -280.241678) (xy 344.434426 -280.211052) (xy 344.399223 -280.174611) (xy 344.37001 -280.133213)
			(xy 344.347475 -280.087832) (xy 344.332148 -280.039538) (xy 344.32439 -279.989468) (xy 344.323924 -279.964134)
			(xy 338.403791 -279.964134) (xy 338.403791 -279.989994) (xy 338.395689 -280.041144) (xy 338.379684 -280.090397)
			(xy 338.356171 -280.13654) (xy 338.325729 -280.178436) (xy 338.289107 -280.215054) (xy 338.247208 -280.245491)
			(xy 338.201062 -280.268999) (xy 338.151807 -280.284997) (xy 338.100656 -280.293094) (xy 338.074762 -280.293572)
			(xy 338.049249 -280.293131) (xy 337.998832 -280.285263) (xy 337.950229 -280.269723) (xy 337.9046 -280.24688)
			(xy 337.863036 -280.21728) (xy 337.826528 -280.18163) (xy 337.810856 -280.161492) (xy 337.398868 -280.161492)
			(xy 337.383211 -280.181641) (xy 337.346698 -280.217284) (xy 337.305129 -280.246877) (xy 337.259498 -280.269711)
			(xy 337.210893 -280.285241) (xy 337.160475 -280.293097) (xy 337.134962 -280.293572) (xy 337.109079 -280.292994)
			(xy 337.057952 -280.28489) (xy 337.008721 -280.268889) (xy 336.9626 -280.245385) (xy 336.920722 -280.214955)
			(xy 336.884121 -280.178349) (xy 336.853696 -280.136468) (xy 336.830196 -280.090344) (xy 336.814201 -280.041111)
			(xy 336.806103 -279.989983) (xy 313.734916 -279.989983) (xy 313.730576 -280.000417) (xy 313.716169 -280.014741)
			(xy 313.697366 -280.022435) (xy 313.687206 -280.022808) (xy 312.287666 -280.022808) (xy 312.277543 -280.022303)
			(xy 312.25883 -280.014573) (xy 312.244477 -280.000293) (xy 312.23665 -279.98162) (xy 312.236104 -279.9715)
			(xy 306.194968 -279.9715) (xy 306.194578 -279.981658) (xy 306.186776 -280.000417) (xy 306.172369 -280.014741)
			(xy 306.153566 -280.022435) (xy 306.143406 -280.022808) (xy 304.743866 -280.022808) (xy 304.733743 -280.022303)
			(xy 304.71503 -280.014573) (xy 304.700677 -280.000293) (xy 304.69285 -279.98162) (xy 304.692304 -279.9715)
			(xy 298.651168 -279.9715) (xy 298.650778 -279.981658) (xy 298.642976 -280.000417) (xy 298.628569 -280.014741)
			(xy 298.609766 -280.022435) (xy 298.599606 -280.022808) (xy 297.200066 -280.022808) (xy 297.189943 -280.022303)
			(xy 297.17123 -280.014573) (xy 297.156877 -280.000293) (xy 297.14905 -279.98162) (xy 297.148504 -279.9715)
			(xy 291.107368 -279.9715) (xy 291.106978 -279.981658) (xy 291.099176 -280.000417) (xy 291.084769 -280.014741)
			(xy 291.065966 -280.022435) (xy 291.055806 -280.022808) (xy 289.656266 -280.022808) (xy 289.646143 -280.022303)
			(xy 289.62743 -280.014573) (xy 289.613077 -280.000293) (xy 289.60525 -279.98162) (xy 289.604704 -279.9715)
			(xy 283.563568 -279.9715) (xy 283.563178 -279.981658) (xy 283.555376 -280.000417) (xy 283.540969 -280.014741)
			(xy 283.522166 -280.022435) (xy 283.512006 -280.022808) (xy 282.112466 -280.022808) (xy 282.102343 -280.022303)
			(xy 282.08363 -280.014573) (xy 282.069277 -280.000293) (xy 282.06145 -279.98162) (xy 282.060904 -279.9715)
			(xy 276.019768 -279.9715) (xy 276.019378 -279.981658) (xy 276.011576 -280.000417) (xy 275.997169 -280.014741)
			(xy 275.978366 -280.022435) (xy 275.968206 -280.022808) (xy 274.568666 -280.022808) (xy 274.558543 -280.022303)
			(xy 274.53983 -280.014573) (xy 274.525477 -280.000293) (xy 274.51765 -279.98162) (xy 274.517104 -279.9715)
			(xy 268.475968 -279.9715) (xy 268.475578 -279.981658) (xy 268.467776 -280.000417) (xy 268.453369 -280.014741)
			(xy 268.434566 -280.022435) (xy 268.424406 -280.022808) (xy 267.024866 -280.022808) (xy 267.014743 -280.022303)
			(xy 266.99603 -280.014573) (xy 266.981677 -280.000293) (xy 266.97385 -279.98162) (xy 266.973304 -279.9715)
			(xy 260.932168 -279.9715) (xy 260.931778 -279.981658) (xy 260.923976 -280.000417) (xy 260.909569 -280.014741)
			(xy 260.890766 -280.022435) (xy 260.880606 -280.022808) (xy 259.481066 -280.022808) (xy 259.470943 -280.022303)
			(xy 259.45223 -280.014573) (xy 259.437877 -280.000293) (xy 259.43005 -279.98162) (xy 259.429504 -279.9715)
			(xy 216.4715 -279.9715) (xy 216.471078 -279.981654) (xy 216.463283 -280.000406) (xy 216.448886 -280.01473)
			(xy 216.430094 -280.022429) (xy 216.419938 -280.022808) (xy 215.020398 -280.022808) (xy 215.010277 -280.022276)
			(xy 214.991565 -280.014557) (xy 214.977211 -280.000285) (xy 214.969383 -279.981618) (xy 214.968836 -279.9715)
			(xy 208.9277 -279.9715) (xy 208.927278 -279.981654) (xy 208.919483 -280.000406) (xy 208.905086 -280.01473)
			(xy 208.886294 -280.022429) (xy 208.876138 -280.022808) (xy 207.476598 -280.022808) (xy 207.466477 -280.022276)
			(xy 207.447765 -280.014557) (xy 207.433411 -280.000285) (xy 207.425583 -279.981618) (xy 207.425036 -279.9715)
			(xy 201.3839 -279.9715) (xy 201.383478 -279.981654) (xy 201.375683 -280.000406) (xy 201.361286 -280.01473)
			(xy 201.342494 -280.022429) (xy 201.332338 -280.022808) (xy 199.932798 -280.022808) (xy 199.922677 -280.022276)
			(xy 199.903965 -280.014557) (xy 199.889611 -280.000285) (xy 199.881783 -279.981618) (xy 199.881236 -279.9715)
			(xy 193.8401 -279.9715) (xy 193.839678 -279.981654) (xy 193.831883 -280.000406) (xy 193.817486 -280.01473)
			(xy 193.798694 -280.022429) (xy 193.788538 -280.022808) (xy 192.388998 -280.022808) (xy 192.378877 -280.022276)
			(xy 192.360165 -280.014557) (xy 192.345811 -280.000285) (xy 192.337983 -279.981618) (xy 192.337436 -279.9715)
			(xy 186.2963 -279.9715) (xy 186.295878 -279.981654) (xy 186.288083 -280.000406) (xy 186.273686 -280.01473)
			(xy 186.254894 -280.022429) (xy 186.244738 -280.022808) (xy 184.845198 -280.022808) (xy 184.835077 -280.022276)
			(xy 184.816365 -280.014557) (xy 184.802011 -280.000285) (xy 184.794183 -279.981618) (xy 184.793636 -279.9715)
			(xy 178.7525 -279.9715) (xy 178.752078 -279.981654) (xy 178.744283 -280.000406) (xy 178.729886 -280.01473)
			(xy 178.711094 -280.022429) (xy 178.700938 -280.022808) (xy 177.301398 -280.022808) (xy 177.291277 -280.022276)
			(xy 177.272565 -280.014557) (xy 177.258211 -280.000285) (xy 177.250383 -279.981618) (xy 177.249836 -279.9715)
			(xy 171.2087 -279.9715) (xy 171.208278 -279.981654) (xy 171.200483 -280.000406) (xy 171.186086 -280.01473)
			(xy 171.167294 -280.022429) (xy 171.157138 -280.022808) (xy 169.757598 -280.022808) (xy 169.747477 -280.022276)
			(xy 169.728765 -280.014557) (xy 169.714411 -280.000285) (xy 169.706583 -279.981618) (xy 169.706036 -279.9715)
			(xy 163.6649 -279.9715) (xy 163.664478 -279.981654) (xy 163.656683 -280.000406) (xy 163.642286 -280.01473)
			(xy 163.623494 -280.022429) (xy 163.613338 -280.022808) (xy 162.213798 -280.022808) (xy 162.203677 -280.022276)
			(xy 162.184965 -280.014557) (xy 162.170611 -280.000285) (xy 162.162783 -279.981618) (xy 162.162236 -279.9715)
			(xy 105.501313 -279.9715) (xy 105.501001 -279.989499) (xy 105.493248 -280.039631) (xy 105.4779 -280.087982)
			(xy 105.45532 -280.133408) (xy 105.426041 -280.174835) (xy 105.390757 -280.211282) (xy 105.350301 -280.241888)
			(xy 105.305631 -280.26593) (xy 105.257803 -280.282837) (xy 105.232962 -280.287984) (xy 105.209848 -280.292302)
			(xy 105.00487 -280.647394) (xy 105.012744 -280.669492) (xy 105.021304 -280.69585) (xy 105.030503 -280.750496)
			(xy 105.031032 -280.778204) (xy 105.030524 -280.804091) (xy 105.030521 -280.804107) (xy 105.31222 -280.804107)
			(xy 105.31222 -280.752293) (xy 105.320326 -280.701118) (xy 105.336337 -280.65184) (xy 105.359859 -280.605674)
			(xy 105.390314 -280.563756) (xy 105.426951 -280.527118) (xy 105.468869 -280.496662) (xy 105.515035 -280.473139)
			(xy 105.564312 -280.457127) (xy 105.615487 -280.449021) (xy 105.641394 -280.448512) (xy 105.666906 -280.448992)
			(xy 105.717321 -280.456852) (xy 105.765922 -280.472385) (xy 105.811551 -280.495221) (xy 105.853116 -280.524814)
			(xy 105.889626 -280.560457) (xy 105.9053 -280.580592) (xy 106.317288 -280.580592) (xy 106.332966 -280.560461)
			(xy 106.369475 -280.524817) (xy 106.41104 -280.495223) (xy 106.456667 -280.472386) (xy 106.505268 -280.456852)
			(xy 106.555682 -280.44899) (xy 106.581194 -280.448512) (xy 106.607104 -280.448985) (xy 106.658286 -280.457091)
			(xy 106.70757 -280.473103) (xy 106.753743 -280.496628) (xy 106.795666 -280.527087) (xy 106.832309 -280.563729)
			(xy 106.862768 -280.605652) (xy 106.886294 -280.651824) (xy 106.902308 -280.701108) (xy 106.910414 -280.75229)
			(xy 106.910414 -280.80411) (xy 106.907678 -280.821384) (xy 158.062168 -280.821384) (xy 158.062168 -280.412444)
			(xy 158.062657 -280.402297) (xy 158.070432 -280.383551) (xy 158.084808 -280.369228) (xy 158.103581 -280.361521)
			(xy 158.11373 -280.361136) (xy 159.51327 -280.361136) (xy 159.523394 -280.361651) (xy 159.542114 -280.369368)
			(xy 159.556471 -280.383646) (xy 159.564292 -280.402322) (xy 159.564832 -280.412444) (xy 159.564832 -280.821384)
			(xy 165.605968 -280.821384) (xy 165.605968 -280.412444) (xy 165.606457 -280.402297) (xy 165.614232 -280.383551)
			(xy 165.628608 -280.369228) (xy 165.647381 -280.361521) (xy 165.65753 -280.361136) (xy 167.05707 -280.361136)
			(xy 167.067194 -280.361651) (xy 167.085914 -280.369368) (xy 167.100271 -280.383646) (xy 167.108092 -280.402322)
			(xy 167.108632 -280.412444) (xy 167.108632 -280.821384) (xy 173.149768 -280.821384) (xy 173.149768 -280.412444)
			(xy 173.150257 -280.402297) (xy 173.158032 -280.383551) (xy 173.172408 -280.369228) (xy 173.191181 -280.361521)
			(xy 173.20133 -280.361136) (xy 174.60087 -280.361136) (xy 174.610994 -280.361651) (xy 174.629714 -280.369368)
			(xy 174.644071 -280.383646) (xy 174.651892 -280.402322) (xy 174.652432 -280.412444) (xy 174.652432 -280.821384)
			(xy 180.693568 -280.821384) (xy 180.693568 -280.412444) (xy 180.694057 -280.402297) (xy 180.701832 -280.383551)
			(xy 180.716208 -280.369228) (xy 180.734981 -280.361521) (xy 180.74513 -280.361136) (xy 182.14467 -280.361136)
			(xy 182.154794 -280.361651) (xy 182.173514 -280.369368) (xy 182.187871 -280.383646) (xy 182.195692 -280.402322)
			(xy 182.196232 -280.412444) (xy 182.196232 -280.821384) (xy 188.237368 -280.821384) (xy 188.237368 -280.412444)
			(xy 188.237857 -280.402297) (xy 188.245632 -280.383551) (xy 188.260008 -280.369228) (xy 188.278781 -280.361521)
			(xy 188.28893 -280.361136) (xy 189.68847 -280.361136) (xy 189.698594 -280.361651) (xy 189.717314 -280.369368)
			(xy 189.731671 -280.383646) (xy 189.739492 -280.402322) (xy 189.740032 -280.412444) (xy 189.740032 -280.821384)
			(xy 195.781168 -280.821384) (xy 195.781168 -280.412444) (xy 195.781657 -280.402297) (xy 195.789432 -280.383551)
			(xy 195.803808 -280.369228) (xy 195.822581 -280.361521) (xy 195.83273 -280.361136) (xy 197.23227 -280.361136)
			(xy 197.242394 -280.361651) (xy 197.261114 -280.369368) (xy 197.275471 -280.383646) (xy 197.283292 -280.402322)
			(xy 197.283832 -280.412444) (xy 197.283832 -280.821384) (xy 203.324968 -280.821384) (xy 203.324968 -280.412444)
			(xy 203.325457 -280.402297) (xy 203.333232 -280.383551) (xy 203.347608 -280.369228) (xy 203.366381 -280.361521)
			(xy 203.37653 -280.361136) (xy 204.77607 -280.361136) (xy 204.786194 -280.361651) (xy 204.804914 -280.369368)
			(xy 204.819271 -280.383646) (xy 204.827092 -280.402322) (xy 204.827632 -280.412444) (xy 204.827632 -280.821384)
			(xy 210.868768 -280.821384) (xy 210.868768 -280.412444) (xy 210.869257 -280.402297) (xy 210.877032 -280.383551)
			(xy 210.891408 -280.369228) (xy 210.910181 -280.361521) (xy 210.92033 -280.361136) (xy 212.31987 -280.361136)
			(xy 212.329994 -280.361651) (xy 212.348714 -280.369368) (xy 212.363071 -280.383646) (xy 212.370892 -280.402322)
			(xy 212.371432 -280.412444) (xy 212.371432 -280.821384) (xy 255.329436 -280.821384) (xy 255.329436 -280.412444)
			(xy 255.329858 -280.402288) (xy 255.337646 -280.38353) (xy 255.352044 -280.369204) (xy 255.37084 -280.361509)
			(xy 255.380998 -280.361136) (xy 256.780538 -280.361136) (xy 256.790667 -280.361595) (xy 256.809388 -280.369335)
			(xy 256.823743 -280.383629) (xy 256.831561 -280.402318) (xy 256.8321 -280.412444) (xy 256.8321 -280.821384)
			(xy 262.873236 -280.821384) (xy 262.873236 -280.412444) (xy 262.873658 -280.402288) (xy 262.881446 -280.38353)
			(xy 262.895844 -280.369204) (xy 262.91464 -280.361509) (xy 262.924798 -280.361136) (xy 264.324338 -280.361136)
			(xy 264.334467 -280.361595) (xy 264.353188 -280.369335) (xy 264.367543 -280.383629) (xy 264.375361 -280.402318)
			(xy 264.3759 -280.412444) (xy 264.3759 -280.821384) (xy 270.417036 -280.821384) (xy 270.417036 -280.412444)
			(xy 270.417458 -280.402288) (xy 270.425246 -280.38353) (xy 270.439644 -280.369204) (xy 270.45844 -280.361509)
			(xy 270.468598 -280.361136) (xy 271.868138 -280.361136) (xy 271.878267 -280.361595) (xy 271.896988 -280.369335)
			(xy 271.911343 -280.383629) (xy 271.919161 -280.402318) (xy 271.9197 -280.412444) (xy 271.9197 -280.821384)
			(xy 277.960836 -280.821384) (xy 277.960836 -280.412444) (xy 277.961258 -280.402288) (xy 277.969046 -280.38353)
			(xy 277.983444 -280.369204) (xy 278.00224 -280.361509) (xy 278.012398 -280.361136) (xy 279.411938 -280.361136)
			(xy 279.422067 -280.361595) (xy 279.440788 -280.369335) (xy 279.455143 -280.383629) (xy 279.462961 -280.402318)
			(xy 279.4635 -280.412444) (xy 279.4635 -280.821384) (xy 285.504636 -280.821384) (xy 285.504636 -280.412444)
			(xy 285.505058 -280.402288) (xy 285.512846 -280.38353) (xy 285.527244 -280.369204) (xy 285.54604 -280.361509)
			(xy 285.556198 -280.361136) (xy 286.955738 -280.361136) (xy 286.965867 -280.361595) (xy 286.984588 -280.369335)
			(xy 286.998943 -280.383629) (xy 287.006761 -280.402318) (xy 287.0073 -280.412444) (xy 287.0073 -280.821384)
			(xy 293.048436 -280.821384) (xy 293.048436 -280.412444) (xy 293.048858 -280.402288) (xy 293.056646 -280.38353)
			(xy 293.071044 -280.369204) (xy 293.08984 -280.361509) (xy 293.099998 -280.361136) (xy 294.499538 -280.361136)
			(xy 294.509667 -280.361595) (xy 294.528388 -280.369335) (xy 294.542743 -280.383629) (xy 294.550561 -280.402318)
			(xy 294.5511 -280.412444) (xy 294.5511 -280.821384) (xy 300.592236 -280.821384) (xy 300.592236 -280.412444)
			(xy 300.592658 -280.402288) (xy 300.600446 -280.38353) (xy 300.614844 -280.369204) (xy 300.63364 -280.361509)
			(xy 300.643798 -280.361136) (xy 302.043338 -280.361136) (xy 302.053467 -280.361595) (xy 302.072188 -280.369335)
			(xy 302.086543 -280.383629) (xy 302.094361 -280.402318) (xy 302.0949 -280.412444) (xy 302.0949 -280.821384)
			(xy 308.136036 -280.821384) (xy 308.136036 -280.412444) (xy 308.136458 -280.402288) (xy 308.144246 -280.38353)
			(xy 308.158644 -280.369204) (xy 308.17744 -280.361509) (xy 308.187598 -280.361136) (xy 309.587138 -280.361136)
			(xy 309.597267 -280.361595) (xy 309.615988 -280.369335) (xy 309.630343 -280.383629) (xy 309.638161 -280.402318)
			(xy 309.6387 -280.412444) (xy 309.6387 -280.821384) (xy 309.638265 -280.831537) (xy 309.630475 -280.850289)
			(xy 309.616082 -280.864613) (xy 309.597293 -280.872313) (xy 309.587138 -280.872692) (xy 308.187598 -280.872692)
			(xy 308.177475 -280.872176) (xy 308.15876 -280.864453) (xy 308.144405 -280.850177) (xy 308.13658 -280.831504)
			(xy 308.136036 -280.821384) (xy 302.0949 -280.821384) (xy 302.094465 -280.831537) (xy 302.086675 -280.850289)
			(xy 302.072282 -280.864613) (xy 302.053493 -280.872313) (xy 302.043338 -280.872692) (xy 300.643798 -280.872692)
			(xy 300.633675 -280.872176) (xy 300.61496 -280.864453) (xy 300.600605 -280.850177) (xy 300.59278 -280.831504)
			(xy 300.592236 -280.821384) (xy 294.5511 -280.821384) (xy 294.550665 -280.831537) (xy 294.542875 -280.850289)
			(xy 294.528482 -280.864613) (xy 294.509693 -280.872313) (xy 294.499538 -280.872692) (xy 293.099998 -280.872692)
			(xy 293.089875 -280.872176) (xy 293.07116 -280.864453) (xy 293.056805 -280.850177) (xy 293.04898 -280.831504)
			(xy 293.048436 -280.821384) (xy 287.0073 -280.821384) (xy 287.006865 -280.831537) (xy 286.999075 -280.850289)
			(xy 286.984682 -280.864613) (xy 286.965893 -280.872313) (xy 286.955738 -280.872692) (xy 285.556198 -280.872692)
			(xy 285.546075 -280.872176) (xy 285.52736 -280.864453) (xy 285.513005 -280.850177) (xy 285.50518 -280.831504)
			(xy 285.504636 -280.821384) (xy 279.4635 -280.821384) (xy 279.463065 -280.831537) (xy 279.455275 -280.850289)
			(xy 279.440882 -280.864613) (xy 279.422093 -280.872313) (xy 279.411938 -280.872692) (xy 278.012398 -280.872692)
			(xy 278.002275 -280.872176) (xy 277.98356 -280.864453) (xy 277.969205 -280.850177) (xy 277.96138 -280.831504)
			(xy 277.960836 -280.821384) (xy 271.9197 -280.821384) (xy 271.919265 -280.831537) (xy 271.911475 -280.850289)
			(xy 271.897082 -280.864613) (xy 271.878293 -280.872313) (xy 271.868138 -280.872692) (xy 270.468598 -280.872692)
			(xy 270.458475 -280.872176) (xy 270.43976 -280.864453) (xy 270.425405 -280.850177) (xy 270.41758 -280.831504)
			(xy 270.417036 -280.821384) (xy 264.3759 -280.821384) (xy 264.375465 -280.831537) (xy 264.367675 -280.850289)
			(xy 264.353282 -280.864613) (xy 264.334493 -280.872313) (xy 264.324338 -280.872692) (xy 262.924798 -280.872692)
			(xy 262.914675 -280.872176) (xy 262.89596 -280.864453) (xy 262.881605 -280.850177) (xy 262.87378 -280.831504)
			(xy 262.873236 -280.821384) (xy 256.8321 -280.821384) (xy 256.831665 -280.831537) (xy 256.823875 -280.850289)
			(xy 256.809482 -280.864613) (xy 256.790693 -280.872313) (xy 256.780538 -280.872692) (xy 255.380998 -280.872692)
			(xy 255.370875 -280.872176) (xy 255.35216 -280.864453) (xy 255.337805 -280.850177) (xy 255.32998 -280.831504)
			(xy 255.329436 -280.821384) (xy 212.371432 -280.821384) (xy 212.370966 -280.831533) (xy 212.363182 -280.850279)
			(xy 212.348799 -280.864602) (xy 212.330021 -280.872308) (xy 212.31987 -280.872692) (xy 210.92033 -280.872692)
			(xy 210.910209 -280.87215) (xy 210.891495 -280.864438) (xy 210.877138 -280.850169) (xy 210.869312 -280.831502)
			(xy 210.868768 -280.821384) (xy 204.827632 -280.821384) (xy 204.827166 -280.831533) (xy 204.819382 -280.850279)
			(xy 204.804999 -280.864602) (xy 204.786221 -280.872308) (xy 204.77607 -280.872692) (xy 203.37653 -280.872692)
			(xy 203.366409 -280.87215) (xy 203.347695 -280.864438) (xy 203.333338 -280.850169) (xy 203.325512 -280.831502)
			(xy 203.324968 -280.821384) (xy 197.283832 -280.821384) (xy 197.283366 -280.831533) (xy 197.275582 -280.850279)
			(xy 197.261199 -280.864602) (xy 197.242421 -280.872308) (xy 197.23227 -280.872692) (xy 195.83273 -280.872692)
			(xy 195.822609 -280.87215) (xy 195.803895 -280.864438) (xy 195.789538 -280.850169) (xy 195.781712 -280.831502)
			(xy 195.781168 -280.821384) (xy 189.740032 -280.821384) (xy 189.739566 -280.831533) (xy 189.731782 -280.850279)
			(xy 189.717399 -280.864602) (xy 189.698621 -280.872308) (xy 189.68847 -280.872692) (xy 188.28893 -280.872692)
			(xy 188.278809 -280.87215) (xy 188.260095 -280.864438) (xy 188.245738 -280.850169) (xy 188.237912 -280.831502)
			(xy 188.237368 -280.821384) (xy 182.196232 -280.821384) (xy 182.195766 -280.831533) (xy 182.187982 -280.850279)
			(xy 182.173599 -280.864602) (xy 182.154821 -280.872308) (xy 182.14467 -280.872692) (xy 180.74513 -280.872692)
			(xy 180.735009 -280.87215) (xy 180.716295 -280.864438) (xy 180.701938 -280.850169) (xy 180.694112 -280.831502)
			(xy 180.693568 -280.821384) (xy 174.652432 -280.821384) (xy 174.651966 -280.831533) (xy 174.644182 -280.850279)
			(xy 174.629799 -280.864602) (xy 174.611021 -280.872308) (xy 174.60087 -280.872692) (xy 173.20133 -280.872692)
			(xy 173.191209 -280.87215) (xy 173.172495 -280.864438) (xy 173.158138 -280.850169) (xy 173.150312 -280.831502)
			(xy 173.149768 -280.821384) (xy 167.108632 -280.821384) (xy 167.108166 -280.831533) (xy 167.100382 -280.850279)
			(xy 167.085999 -280.864602) (xy 167.067221 -280.872308) (xy 167.05707 -280.872692) (xy 165.65753 -280.872692)
			(xy 165.647409 -280.87215) (xy 165.628695 -280.864438) (xy 165.614338 -280.850169) (xy 165.606512 -280.831502)
			(xy 165.605968 -280.821384) (xy 159.564832 -280.821384) (xy 159.564366 -280.831533) (xy 159.556582 -280.850279)
			(xy 159.542199 -280.864602) (xy 159.523421 -280.872308) (xy 159.51327 -280.872692) (xy 158.11373 -280.872692)
			(xy 158.103609 -280.87215) (xy 158.084895 -280.864438) (xy 158.070538 -280.850169) (xy 158.062712 -280.831502)
			(xy 158.062168 -280.821384) (xy 106.907678 -280.821384) (xy 106.902308 -280.855292) (xy 106.886294 -280.904576)
			(xy 106.862768 -280.950748) (xy 106.832309 -280.992671) (xy 106.795666 -281.029313) (xy 106.753743 -281.059772)
			(xy 106.70757 -281.083297) (xy 106.658286 -281.099309) (xy 106.607104 -281.107415) (xy 106.581194 -281.107896)
			(xy 106.555682 -281.107421) (xy 106.505267 -281.09956) (xy 106.456665 -281.084025) (xy 106.411037 -281.061188)
			(xy 106.369472 -281.031595) (xy 106.332962 -280.995951) (xy 106.317288 -280.975816) (xy 105.9053 -280.975816)
			(xy 105.889631 -280.995955) (xy 105.85312 -281.031598) (xy 105.811553 -281.06119) (xy 105.765924 -281.084026)
			(xy 105.717322 -281.099559) (xy 105.666906 -281.107419) (xy 105.641394 -281.107896) (xy 105.615487 -281.107379)
			(xy 105.564312 -281.099273) (xy 105.515035 -281.083261) (xy 105.468869 -281.059738) (xy 105.426951 -281.029282)
			(xy 105.390314 -280.992644) (xy 105.359859 -280.950726) (xy 105.336337 -280.90456) (xy 105.320326 -280.855282)
			(xy 105.31222 -280.804107) (xy 105.030521 -280.804107) (xy 105.022425 -280.855229) (xy 105.006426 -280.904469)
			(xy 104.98292 -280.950601) (xy 104.952488 -280.992488) (xy 104.915878 -281.029098) (xy 104.873991 -281.05953)
			(xy 104.827859 -281.083036) (xy 104.778619 -281.099035) (xy 104.727481 -281.107134) (xy 104.675707 -281.107134)
			(xy 104.624569 -281.099035) (xy 104.575329 -281.083036) (xy 104.529197 -281.05953) (xy 104.48731 -281.029098)
			(xy 104.4507 -280.992488) (xy 104.420268 -280.950601) (xy 104.396762 -280.904469) (xy 104.380763 -280.855229)
			(xy 104.372664 -280.804091) (xy 104.372156 -280.778204) (xy 104.091232 -280.778204) (xy 104.091232 -280.778712)
			(xy 104.090641 -280.806228) (xy 104.081455 -280.860489) (xy 104.072944 -280.886662) (xy 104.065324 -280.908506)
			(xy 104.270556 -281.263852) (xy 104.293416 -281.26817) (xy 104.318226 -281.273386) (xy 104.366003 -281.290334)
			(xy 104.410622 -281.314398) (xy 104.451028 -281.345012) (xy 104.48627 -281.381453) (xy 104.515516 -281.422861)
			(xy 104.538075 -281.468259) (xy 104.553416 -281.516576) (xy 104.561176 -281.566673) (xy 104.56164 -281.59202)
			(xy 105.781856 -281.59202) (xy 105.782364 -281.566113) (xy 105.79047 -281.514936) (xy 105.806482 -281.465657)
			(xy 105.830005 -281.41949) (xy 105.860461 -281.377571) (xy 105.897099 -281.340933) (xy 105.939018 -281.310477)
			(xy 105.985185 -281.286954) (xy 106.034464 -281.270942) (xy 106.085641 -281.262836) (xy 106.137455 -281.262836)
			(xy 106.188632 -281.270942) (xy 106.237911 -281.286954) (xy 106.284078 -281.310477) (xy 106.325997 -281.340933)
			(xy 106.362635 -281.377571) (xy 106.393091 -281.41949) (xy 106.416614 -281.465657) (xy 106.432626 -281.514936)
			(xy 106.440732 -281.566113) (xy 106.44124 -281.59202) (xy 106.44067 -281.619802) (xy 106.431865 -281.671522)
			(xy 162.162236 -281.671522) (xy 162.162236 -281.262582) (xy 162.162718 -281.252423) (xy 162.170498 -281.233654)
			(xy 162.184867 -281.219289) (xy 162.203639 -281.211515) (xy 162.213798 -281.21102) (xy 163.613338 -281.21102)
			(xy 163.623496 -281.211502) (xy 163.642263 -281.219285) (xy 163.656626 -281.233654) (xy 163.664402 -281.252424)
			(xy 163.6649 -281.262582) (xy 163.6649 -281.671522) (xy 169.706036 -281.671522) (xy 169.706036 -281.262582)
			(xy 169.706518 -281.252423) (xy 169.714298 -281.233654) (xy 169.728667 -281.219289) (xy 169.747439 -281.211515)
			(xy 169.757598 -281.21102) (xy 171.157138 -281.21102) (xy 171.167296 -281.211502) (xy 171.186063 -281.219285)
			(xy 171.200426 -281.233654) (xy 171.208202 -281.252424) (xy 171.2087 -281.262582) (xy 171.2087 -281.671522)
			(xy 177.249836 -281.671522) (xy 177.249836 -281.262582) (xy 177.250318 -281.252423) (xy 177.258098 -281.233654)
			(xy 177.272467 -281.219289) (xy 177.291239 -281.211515) (xy 177.301398 -281.21102) (xy 178.700938 -281.21102)
			(xy 178.711096 -281.211502) (xy 178.729863 -281.219285) (xy 178.744226 -281.233654) (xy 178.752002 -281.252424)
			(xy 178.7525 -281.262582) (xy 178.7525 -281.671522) (xy 184.793636 -281.671522) (xy 184.793636 -281.262582)
			(xy 184.794118 -281.252423) (xy 184.801898 -281.233654) (xy 184.816267 -281.219289) (xy 184.835039 -281.211515)
			(xy 184.845198 -281.21102) (xy 186.244738 -281.21102) (xy 186.254896 -281.211502) (xy 186.273663 -281.219285)
			(xy 186.288026 -281.233654) (xy 186.295802 -281.252424) (xy 186.2963 -281.262582) (xy 186.2963 -281.671522)
			(xy 192.337436 -281.671522) (xy 192.337436 -281.262582) (xy 192.337918 -281.252423) (xy 192.345698 -281.233654)
			(xy 192.360067 -281.219289) (xy 192.378839 -281.211515) (xy 192.388998 -281.21102) (xy 193.788538 -281.21102)
			(xy 193.798696 -281.211502) (xy 193.817463 -281.219285) (xy 193.831826 -281.233654) (xy 193.839602 -281.252424)
			(xy 193.8401 -281.262582) (xy 193.8401 -281.671522) (xy 199.881236 -281.671522) (xy 199.881236 -281.262582)
			(xy 199.881718 -281.252423) (xy 199.889498 -281.233654) (xy 199.903867 -281.219289) (xy 199.922639 -281.211515)
			(xy 199.932798 -281.21102) (xy 201.332338 -281.21102) (xy 201.342496 -281.211502) (xy 201.361263 -281.219285)
			(xy 201.375626 -281.233654) (xy 201.383402 -281.252424) (xy 201.3839 -281.262582) (xy 201.3839 -281.671522)
			(xy 207.425036 -281.671522) (xy 207.425036 -281.262582) (xy 207.425518 -281.252423) (xy 207.433298 -281.233654)
			(xy 207.447667 -281.219289) (xy 207.466439 -281.211515) (xy 207.476598 -281.21102) (xy 208.876138 -281.21102)
			(xy 208.886296 -281.211502) (xy 208.905063 -281.219285) (xy 208.919426 -281.233654) (xy 208.927202 -281.252424)
			(xy 208.9277 -281.262582) (xy 208.9277 -281.671522) (xy 214.968836 -281.671522) (xy 214.968836 -281.262582)
			(xy 214.969318 -281.252423) (xy 214.977098 -281.233654) (xy 214.991467 -281.219289) (xy 215.010239 -281.211515)
			(xy 215.020398 -281.21102) (xy 216.419938 -281.21102) (xy 216.430096 -281.211502) (xy 216.448863 -281.219285)
			(xy 216.463226 -281.233654) (xy 216.471002 -281.252424) (xy 216.4715 -281.262582) (xy 216.4715 -281.671522)
			(xy 259.429504 -281.671522) (xy 259.429504 -281.262582) (xy 259.430018 -281.252427) (xy 259.437792 -281.233664)
			(xy 259.452151 -281.219301) (xy 259.470911 -281.211521) (xy 259.481066 -281.21102) (xy 260.880606 -281.21102)
			(xy 260.890762 -281.211528) (xy 260.909528 -281.219301) (xy 260.923892 -281.233662) (xy 260.931669 -281.252426)
			(xy 260.932168 -281.262582) (xy 260.932168 -281.671522) (xy 266.973304 -281.671522) (xy 266.973304 -281.262582)
			(xy 266.973818 -281.252427) (xy 266.981592 -281.233664) (xy 266.995951 -281.219301) (xy 267.014711 -281.211521)
			(xy 267.024866 -281.21102) (xy 268.424406 -281.21102) (xy 268.434562 -281.211528) (xy 268.453328 -281.219301)
			(xy 268.467692 -281.233662) (xy 268.475469 -281.252426) (xy 268.475968 -281.262582) (xy 268.475968 -281.671522)
			(xy 274.517104 -281.671522) (xy 274.517104 -281.262582) (xy 274.517618 -281.252427) (xy 274.525392 -281.233664)
			(xy 274.539751 -281.219301) (xy 274.558511 -281.211521) (xy 274.568666 -281.21102) (xy 275.968206 -281.21102)
			(xy 275.978362 -281.211528) (xy 275.997128 -281.219301) (xy 276.011492 -281.233662) (xy 276.019269 -281.252426)
			(xy 276.019768 -281.262582) (xy 276.019768 -281.671522) (xy 282.060904 -281.671522) (xy 282.060904 -281.262582)
			(xy 282.061418 -281.252427) (xy 282.069192 -281.233664) (xy 282.083551 -281.219301) (xy 282.102311 -281.211521)
			(xy 282.112466 -281.21102) (xy 283.512006 -281.21102) (xy 283.522162 -281.211528) (xy 283.540928 -281.219301)
			(xy 283.555292 -281.233662) (xy 283.563069 -281.252426) (xy 283.563568 -281.262582) (xy 283.563568 -281.671522)
			(xy 289.604704 -281.671522) (xy 289.604704 -281.262582) (xy 289.605218 -281.252427) (xy 289.612992 -281.233664)
			(xy 289.627351 -281.219301) (xy 289.646111 -281.211521) (xy 289.656266 -281.21102) (xy 291.055806 -281.21102)
			(xy 291.065962 -281.211528) (xy 291.084728 -281.219301) (xy 291.099092 -281.233662) (xy 291.106869 -281.252426)
			(xy 291.107368 -281.262582) (xy 291.107368 -281.671522) (xy 297.148504 -281.671522) (xy 297.148504 -281.262582)
			(xy 297.149018 -281.252427) (xy 297.156792 -281.233664) (xy 297.171151 -281.219301) (xy 297.189911 -281.211521)
			(xy 297.200066 -281.21102) (xy 298.599606 -281.21102) (xy 298.609762 -281.211528) (xy 298.628528 -281.219301)
			(xy 298.642892 -281.233662) (xy 298.650669 -281.252426) (xy 298.651168 -281.262582) (xy 298.651168 -281.671522)
			(xy 304.692304 -281.671522) (xy 304.692304 -281.262582) (xy 304.692818 -281.252427) (xy 304.700592 -281.233664)
			(xy 304.714951 -281.219301) (xy 304.733711 -281.211521) (xy 304.743866 -281.21102) (xy 306.143406 -281.21102)
			(xy 306.153562 -281.211528) (xy 306.172328 -281.219301) (xy 306.186692 -281.233662) (xy 306.194469 -281.252426)
			(xy 306.194968 -281.262582) (xy 306.194968 -281.671522) (xy 312.236104 -281.671522) (xy 312.236104 -281.262582)
			(xy 312.236618 -281.252427) (xy 312.244392 -281.233664) (xy 312.258751 -281.219301) (xy 312.277511 -281.211521)
			(xy 312.287666 -281.21102) (xy 313.687206 -281.21102) (xy 313.697362 -281.211528) (xy 313.716128 -281.219301)
			(xy 313.730492 -281.233662) (xy 313.738269 -281.252426) (xy 313.738768 -281.262582) (xy 313.738768 -281.59202)
			(xy 336.805524 -281.59202) (xy 336.806044 -281.566676) (xy 336.813813 -281.516587) (xy 336.829157 -281.468277)
			(xy 336.851713 -281.422884) (xy 336.88095 -281.381477) (xy 336.916179 -281.345033) (xy 336.956571 -281.31441)
			(xy 337.001174 -281.290329) (xy 337.048936 -281.273357) (xy 337.073748 -281.26817) (xy 337.096608 -281.263852)
			(xy 337.301586 -280.909014) (xy 337.293966 -280.88717) (xy 337.285321 -280.860761) (xy 337.276 -280.805986)
			(xy 337.275424 -280.778204) (xy 337.275919 -280.752309) (xy 337.284017 -280.701155) (xy 337.300013 -280.651897)
			(xy 337.323515 -280.605746) (xy 337.353945 -280.563837) (xy 337.390553 -280.527202) (xy 337.432439 -280.496742)
			(xy 337.478573 -280.473206) (xy 337.527819 -280.457173) (xy 337.578967 -280.449038) (xy 337.604862 -280.448512)
			(xy 337.630738 -280.449004) (xy 337.681855 -280.457091) (xy 337.731077 -280.473073) (xy 337.777195 -280.496556)
			(xy 337.819073 -280.526962) (xy 337.855681 -280.563542) (xy 337.886118 -280.605398) (xy 337.909634 -280.651499)
			(xy 337.925652 -280.70071) (xy 337.933777 -280.75182) (xy 337.9343 -280.777696) (xy 337.9343 -280.778204)
			(xy 340.094824 -280.778204) (xy 340.095293 -280.752294) (xy 340.103399 -280.701112) (xy 340.119413 -280.651828)
			(xy 340.142939 -280.605656) (xy 340.173399 -280.563733) (xy 340.210042 -280.527091) (xy 340.251966 -280.496633)
			(xy 340.298139 -280.473108) (xy 340.347423 -280.457097) (xy 340.398606 -280.448992) (xy 340.424516 -280.448512)
			(xy 340.450394 -280.448954) (xy 340.501512 -280.457049) (xy 340.550736 -280.473038) (xy 340.596853 -280.496528)
			(xy 340.638731 -280.52694) (xy 340.675338 -280.563526) (xy 340.705774 -280.605386) (xy 340.729289 -280.651491)
			(xy 340.745307 -280.700705) (xy 340.753431 -280.751819) (xy 340.753954 -280.777696) (xy 340.753954 -280.778204)
			(xy 340.753418 -280.804105) (xy 342.91452 -280.804105) (xy 342.91452 -280.752295) (xy 342.922625 -280.701122)
			(xy 342.938634 -280.651848) (xy 342.962153 -280.605684) (xy 342.992605 -280.563767) (xy 343.029238 -280.527129)
			(xy 343.071151 -280.496673) (xy 343.117313 -280.473148) (xy 343.166585 -280.457133) (xy 343.217757 -280.449023)
			(xy 343.243662 -280.448512) (xy 343.269173 -280.449015) (xy 343.319587 -280.45687) (xy 343.368188 -280.472399)
			(xy 343.413817 -280.49523) (xy 343.455383 -280.524819) (xy 343.491894 -280.560459) (xy 343.507568 -280.580592)
			(xy 343.91981 -280.580592) (xy 343.935476 -280.56045) (xy 343.971987 -280.524807) (xy 344.013554 -280.495214)
			(xy 344.059184 -280.472379) (xy 344.107788 -280.456847) (xy 344.158204 -280.448988) (xy 344.183716 -280.448512)
			(xy 344.209623 -280.449014) (xy 344.260798 -280.457121) (xy 344.310075 -280.473134) (xy 344.356241 -280.496659)
			(xy 344.398158 -280.527115) (xy 344.434795 -280.563754) (xy 344.465249 -280.605673) (xy 344.488772 -280.65184)
			(xy 344.504782 -280.701117) (xy 344.512888 -280.752293) (xy 344.512888 -280.804107) (xy 344.504782 -280.855283)
			(xy 344.488772 -280.90456) (xy 344.465249 -280.950727) (xy 344.434795 -280.992646) (xy 344.398158 -281.029285)
			(xy 344.356241 -281.059741) (xy 344.310075 -281.083266) (xy 344.260798 -281.099279) (xy 344.209623 -281.107386)
			(xy 344.183716 -281.107896) (xy 344.158205 -281.107405) (xy 344.107791 -281.099547) (xy 344.059189 -281.084016)
			(xy 344.013561 -281.061182) (xy 343.971995 -281.031591) (xy 343.935484 -280.99595) (xy 343.91981 -280.975816)
			(xy 343.507568 -280.975816) (xy 343.491917 -280.99597) (xy 343.455403 -281.031612) (xy 343.413832 -281.061203)
			(xy 343.368199 -281.084036) (xy 343.319593 -281.099566) (xy 343.269175 -281.107421) (xy 343.243662 -281.107896)
			(xy 343.217757 -281.107377) (xy 343.166585 -281.099267) (xy 343.117313 -281.083252) (xy 343.071151 -281.059727)
			(xy 343.029238 -281.029271) (xy 342.992605 -280.992633) (xy 342.962153 -280.950716) (xy 342.938634 -280.904552)
			(xy 342.922625 -280.855278) (xy 342.91452 -280.804105) (xy 340.753418 -280.804105) (xy 340.753379 -280.805986)
			(xy 340.744058 -280.860762) (xy 340.735412 -280.88717) (xy 340.727792 -280.909014) (xy 340.93277 -281.263852)
			(xy 340.95563 -281.26817) (xy 340.980439 -281.273332) (xy 341.028178 -281.290325) (xy 341.072756 -281.314423)
			(xy 341.113121 -281.345058) (xy 341.148323 -281.381508) (xy 341.177534 -281.422915) (xy 341.200066 -281.468304)
			(xy 341.215387 -281.516606) (xy 341.223138 -281.566683) (xy 341.2236 -281.59202) (xy 341.223092 -281.617907)
			(xy 341.214993 -281.669045) (xy 341.198994 -281.718285) (xy 341.175488 -281.764417) (xy 341.145056 -281.806304)
			(xy 341.108446 -281.842914) (xy 341.066559 -281.873346) (xy 341.020427 -281.896852) (xy 340.971187 -281.912851)
			(xy 340.920049 -281.92095) (xy 340.868275 -281.92095) (xy 340.817137 -281.912851) (xy 340.767897 -281.896852)
			(xy 340.721765 -281.873346) (xy 340.679878 -281.842914) (xy 340.643268 -281.806304) (xy 340.612836 -281.764417)
			(xy 340.58933 -281.718285) (xy 340.573331 -281.669045) (xy 340.565232 -281.617907) (xy 340.564724 -281.59202)
			(xy 340.565273 -281.564313) (xy 340.574459 -281.509667) (xy 340.583012 -281.483308) (xy 340.590632 -281.461464)
			(xy 340.385654 -281.106372) (xy 340.362794 -281.102054) (xy 340.337994 -281.096852) (xy 340.290256 -281.079864)
			(xy 340.24568 -281.055771) (xy 340.205315 -281.025142) (xy 340.170112 -280.988697) (xy 340.140899 -280.947295)
			(xy 340.118366 -280.901911) (xy 340.103042 -280.853613) (xy 340.095288 -280.803539) (xy 340.094824 -280.778204)
			(xy 337.9343 -280.778204) (xy 337.933779 -280.803526) (xy 337.926048 -280.853575) (xy 337.910753 -280.901853)
			(xy 337.888254 -280.947223) (xy 337.859081 -280.988619) (xy 337.82392 -281.025066) (xy 337.783598 -281.055707)
			(xy 337.739064 -281.07982) (xy 337.691367 -281.096838) (xy 337.666584 -281.102054) (xy 337.643724 -281.106372)
			(xy 337.438746 -281.46121) (xy 337.446366 -281.483054) (xy 337.454977 -281.50934) (xy 337.464301 -281.563858)
			(xy 337.464908 -281.591512) (xy 337.464908 -281.59202) (xy 337.4644 -281.617904) (xy 338.685436 -281.617904)
			(xy 338.685436 -281.566096) (xy 338.69354 -281.514926) (xy 338.709548 -281.465654) (xy 338.733067 -281.419492)
			(xy 338.763517 -281.377577) (xy 338.800148 -281.340942) (xy 338.84206 -281.310487) (xy 338.888219 -281.286963)
			(xy 338.937489 -281.270949) (xy 338.988658 -281.262839) (xy 339.014562 -281.262328) (xy 339.040073 -281.262825)
			(xy 339.090487 -281.270681) (xy 339.139089 -281.28621) (xy 339.184718 -281.309042) (xy 339.226284 -281.338633)
			(xy 339.262794 -281.374274) (xy 339.278468 -281.394408) (xy 339.690456 -281.394408) (xy 339.706157 -281.374295)
			(xy 339.742661 -281.33865) (xy 339.784221 -281.309053) (xy 339.829844 -281.286213) (xy 339.878441 -281.270675)
			(xy 339.928852 -281.262808) (xy 339.954362 -281.262328) (xy 339.980275 -281.262767) (xy 340.031464 -281.270869)
			(xy 340.080754 -281.286879) (xy 340.126933 -281.310404) (xy 340.168863 -281.340863) (xy 340.205512 -281.377508)
			(xy 340.235976 -281.419434) (xy 340.259506 -281.465611) (xy 340.275522 -281.514899) (xy 340.28363 -281.566087)
			(xy 340.28363 -281.617913) (xy 340.275522 -281.669101) (xy 340.259506 -281.718389) (xy 340.235976 -281.764566)
			(xy 340.205512 -281.806492) (xy 340.168863 -281.843137) (xy 340.126933 -281.873596) (xy 340.080754 -281.897121)
			(xy 340.031464 -281.913131) (xy 339.980275 -281.921233) (xy 339.954362 -281.921712) (xy 339.928849 -281.921255)
			(xy 339.878434 -281.913389) (xy 339.829832 -281.89785) (xy 339.784204 -281.87501) (xy 339.742639 -281.845414)
			(xy 339.706129 -281.809768) (xy 339.690456 -281.789632) (xy 339.278468 -281.789632) (xy 339.262822 -281.80979)
			(xy 339.226306 -281.845431) (xy 339.184734 -281.875021) (xy 339.139101 -281.897853) (xy 339.090494 -281.913382)
			(xy 339.040076 -281.921238) (xy 339.014562 -281.921712) (xy 338.988658 -281.921161) (xy 338.937489 -281.913051)
			(xy 338.888219 -281.897037) (xy 338.84206 -281.873513) (xy 338.800148 -281.843058) (xy 338.763517 -281.806423)
			(xy 338.733067 -281.764508) (xy 338.709548 -281.718346) (xy 338.69354 -281.669074) (xy 338.685436 -281.617904)
			(xy 337.4644 -281.617904) (xy 337.4644 -281.617927) (xy 337.456294 -281.669104) (xy 337.440282 -281.718383)
			(xy 337.416759 -281.76455) (xy 337.386303 -281.806469) (xy 337.349665 -281.843107) (xy 337.307746 -281.873563)
			(xy 337.261579 -281.897086) (xy 337.2123 -281.913098) (xy 337.161123 -281.921204) (xy 337.109309 -281.921204)
			(xy 337.058132 -281.913098) (xy 337.008853 -281.897086) (xy 336.962686 -281.873563) (xy 336.920767 -281.843107)
			(xy 336.884129 -281.806469) (xy 336.853673 -281.76455) (xy 336.83015 -281.718383) (xy 336.814138 -281.669104)
			(xy 336.806032 -281.617927) (xy 336.805524 -281.59202) (xy 313.738768 -281.59202) (xy 313.738768 -281.671522)
			(xy 313.738285 -281.68168) (xy 313.730504 -281.700449) (xy 313.716136 -281.714813) (xy 313.697365 -281.722588)
			(xy 313.687206 -281.723084) (xy 312.287666 -281.723084) (xy 312.277509 -281.722595) (xy 312.258743 -281.714814)
			(xy 312.24438 -281.700447) (xy 312.236603 -281.681679) (xy 312.236104 -281.671522) (xy 306.194968 -281.671522)
			(xy 306.194485 -281.68168) (xy 306.186704 -281.700449) (xy 306.172336 -281.714813) (xy 306.153565 -281.722588)
			(xy 306.143406 -281.723084) (xy 304.743866 -281.723084) (xy 304.733709 -281.722595) (xy 304.714943 -281.714814)
			(xy 304.70058 -281.700447) (xy 304.692803 -281.681679) (xy 304.692304 -281.671522) (xy 298.651168 -281.671522)
			(xy 298.650685 -281.68168) (xy 298.642904 -281.700449) (xy 298.628536 -281.714813) (xy 298.609765 -281.722588)
			(xy 298.599606 -281.723084) (xy 297.200066 -281.723084) (xy 297.189909 -281.722595) (xy 297.171143 -281.714814)
			(xy 297.15678 -281.700447) (xy 297.149003 -281.681679) (xy 297.148504 -281.671522) (xy 291.107368 -281.671522)
			(xy 291.106885 -281.68168) (xy 291.099104 -281.700449) (xy 291.084736 -281.714813) (xy 291.065965 -281.722588)
			(xy 291.055806 -281.723084) (xy 289.656266 -281.723084) (xy 289.646109 -281.722595) (xy 289.627343 -281.714814)
			(xy 289.61298 -281.700447) (xy 289.605203 -281.681679) (xy 289.604704 -281.671522) (xy 283.563568 -281.671522)
			(xy 283.563085 -281.68168) (xy 283.555304 -281.700449) (xy 283.540936 -281.714813) (xy 283.522165 -281.722588)
			(xy 283.512006 -281.723084) (xy 282.112466 -281.723084) (xy 282.102309 -281.722595) (xy 282.083543 -281.714814)
			(xy 282.06918 -281.700447) (xy 282.061403 -281.681679) (xy 282.060904 -281.671522) (xy 276.019768 -281.671522)
			(xy 276.019285 -281.68168) (xy 276.011504 -281.700449) (xy 275.997136 -281.714813) (xy 275.978365 -281.722588)
			(xy 275.968206 -281.723084) (xy 274.568666 -281.723084) (xy 274.558509 -281.722595) (xy 274.539743 -281.714814)
			(xy 274.52538 -281.700447) (xy 274.517603 -281.681679) (xy 274.517104 -281.671522) (xy 268.475968 -281.671522)
			(xy 268.475485 -281.68168) (xy 268.467704 -281.700449) (xy 268.453336 -281.714813) (xy 268.434565 -281.722588)
			(xy 268.424406 -281.723084) (xy 267.024866 -281.723084) (xy 267.014709 -281.722595) (xy 266.995943 -281.714814)
			(xy 266.98158 -281.700447) (xy 266.973803 -281.681679) (xy 266.973304 -281.671522) (xy 260.932168 -281.671522)
			(xy 260.931685 -281.68168) (xy 260.923904 -281.700449) (xy 260.909536 -281.714813) (xy 260.890765 -281.722588)
			(xy 260.880606 -281.723084) (xy 259.481066 -281.723084) (xy 259.470909 -281.722595) (xy 259.452143 -281.714814)
			(xy 259.43778 -281.700447) (xy 259.430003 -281.681679) (xy 259.429504 -281.671522) (xy 216.4715 -281.671522)
			(xy 216.470986 -281.681677) (xy 216.463211 -281.700439) (xy 216.448852 -281.714802) (xy 216.430092 -281.722583)
			(xy 216.419938 -281.723084) (xy 215.020398 -281.723084) (xy 215.010243 -281.722569) (xy 214.991478 -281.714798)
			(xy 214.977113 -281.700439) (xy 214.969335 -281.681677) (xy 214.968836 -281.671522) (xy 208.9277 -281.671522)
			(xy 208.927186 -281.681677) (xy 208.919411 -281.700439) (xy 208.905052 -281.714802) (xy 208.886292 -281.722583)
			(xy 208.876138 -281.723084) (xy 207.476598 -281.723084) (xy 207.466443 -281.722569) (xy 207.447678 -281.714798)
			(xy 207.433313 -281.700439) (xy 207.425535 -281.681677) (xy 207.425036 -281.671522) (xy 201.3839 -281.671522)
			(xy 201.383386 -281.681677) (xy 201.375611 -281.700439) (xy 201.361252 -281.714802) (xy 201.342492 -281.722583)
			(xy 201.332338 -281.723084) (xy 199.932798 -281.723084) (xy 199.922643 -281.722569) (xy 199.903878 -281.714798)
			(xy 199.889513 -281.700439) (xy 199.881735 -281.681677) (xy 199.881236 -281.671522) (xy 193.8401 -281.671522)
			(xy 193.839586 -281.681677) (xy 193.831811 -281.700439) (xy 193.817452 -281.714802) (xy 193.798692 -281.722583)
			(xy 193.788538 -281.723084) (xy 192.388998 -281.723084) (xy 192.378843 -281.722569) (xy 192.360078 -281.714798)
			(xy 192.345713 -281.700439) (xy 192.337935 -281.681677) (xy 192.337436 -281.671522) (xy 186.2963 -281.671522)
			(xy 186.295786 -281.681677) (xy 186.288011 -281.700439) (xy 186.273652 -281.714802) (xy 186.254892 -281.722583)
			(xy 186.244738 -281.723084) (xy 184.845198 -281.723084) (xy 184.835043 -281.722569) (xy 184.816278 -281.714798)
			(xy 184.801913 -281.700439) (xy 184.794135 -281.681677) (xy 184.793636 -281.671522) (xy 178.7525 -281.671522)
			(xy 178.751986 -281.681677) (xy 178.744211 -281.700439) (xy 178.729852 -281.714802) (xy 178.711092 -281.722583)
			(xy 178.700938 -281.723084) (xy 177.301398 -281.723084) (xy 177.291243 -281.722569) (xy 177.272478 -281.714798)
			(xy 177.258113 -281.700439) (xy 177.250335 -281.681677) (xy 177.249836 -281.671522) (xy 171.2087 -281.671522)
			(xy 171.208186 -281.681677) (xy 171.200411 -281.700439) (xy 171.186052 -281.714802) (xy 171.167292 -281.722583)
			(xy 171.157138 -281.723084) (xy 169.757598 -281.723084) (xy 169.747443 -281.722569) (xy 169.728678 -281.714798)
			(xy 169.714313 -281.700439) (xy 169.706535 -281.681677) (xy 169.706036 -281.671522) (xy 163.6649 -281.671522)
			(xy 163.664386 -281.681677) (xy 163.656611 -281.700439) (xy 163.642252 -281.714802) (xy 163.623492 -281.722583)
			(xy 163.613338 -281.723084) (xy 162.213798 -281.723084) (xy 162.203643 -281.722569) (xy 162.184878 -281.714798)
			(xy 162.170513 -281.700439) (xy 162.162735 -281.681677) (xy 162.162236 -281.671522) (xy 106.431865 -281.671522)
			(xy 106.431345 -281.674578) (xy 106.422698 -281.700986) (xy 106.414824 -281.72283) (xy 106.619802 -282.077668)
			(xy 106.642662 -282.081986) (xy 106.667464 -282.087182) (xy 106.715205 -282.104167) (xy 106.759784 -282.128258)
			(xy 106.800151 -282.158887) (xy 106.835356 -282.195333) (xy 106.864568 -282.236737) (xy 106.8871 -282.282123)
			(xy 106.902422 -282.330424) (xy 106.910171 -282.3805) (xy 106.910632 -282.405836) (xy 106.910124 -282.431723)
			(xy 106.902025 -282.482861) (xy 106.889501 -282.521406) (xy 158.062168 -282.521406) (xy 158.062168 -282.112466)
			(xy 158.062606 -282.102302) (xy 158.070397 -282.083527) (xy 158.08478 -282.069162) (xy 158.103566 -282.061394)
			(xy 158.11373 -282.060904) (xy 159.51327 -282.060904) (xy 159.523422 -282.061457) (xy 159.542184 -282.069215)
			(xy 159.556549 -282.083563) (xy 159.564331 -282.102315) (xy 159.564832 -282.112466) (xy 159.564832 -282.521406)
			(xy 165.605968 -282.521406) (xy 165.605968 -282.112466) (xy 165.606406 -282.102302) (xy 165.614197 -282.083527)
			(xy 165.62858 -282.069162) (xy 165.647366 -282.061394) (xy 165.65753 -282.060904) (xy 167.05707 -282.060904)
			(xy 167.067222 -282.061457) (xy 167.085984 -282.069215) (xy 167.100349 -282.083563) (xy 167.108131 -282.102315)
			(xy 167.108632 -282.112466) (xy 167.108632 -282.521406) (xy 173.149768 -282.521406) (xy 173.149768 -282.112466)
			(xy 173.150206 -282.102302) (xy 173.157997 -282.083527) (xy 173.17238 -282.069162) (xy 173.191166 -282.061394)
			(xy 173.20133 -282.060904) (xy 174.60087 -282.060904) (xy 174.611022 -282.061457) (xy 174.629784 -282.069215)
			(xy 174.644149 -282.083563) (xy 174.651931 -282.102315) (xy 174.652432 -282.112466) (xy 174.652432 -282.521406)
			(xy 180.693568 -282.521406) (xy 180.693568 -282.112466) (xy 180.694006 -282.102302) (xy 180.701797 -282.083527)
			(xy 180.71618 -282.069162) (xy 180.734966 -282.061394) (xy 180.74513 -282.060904) (xy 182.14467 -282.060904)
			(xy 182.154822 -282.061457) (xy 182.173584 -282.069215) (xy 182.187949 -282.083563) (xy 182.195731 -282.102315)
			(xy 182.196232 -282.112466) (xy 182.196232 -282.521406) (xy 188.237368 -282.521406) (xy 188.237368 -282.112466)
			(xy 188.237806 -282.102302) (xy 188.245597 -282.083527) (xy 188.25998 -282.069162) (xy 188.278766 -282.061394)
			(xy 188.28893 -282.060904) (xy 189.68847 -282.060904) (xy 189.698622 -282.061457) (xy 189.717384 -282.069215)
			(xy 189.731749 -282.083563) (xy 189.739531 -282.102315) (xy 189.740032 -282.112466) (xy 189.740032 -282.521406)
			(xy 195.781168 -282.521406) (xy 195.781168 -282.112466) (xy 195.781606 -282.102302) (xy 195.789397 -282.083527)
			(xy 195.80378 -282.069162) (xy 195.822566 -282.061394) (xy 195.83273 -282.060904) (xy 197.23227 -282.060904)
			(xy 197.242422 -282.061457) (xy 197.261184 -282.069215) (xy 197.275549 -282.083563) (xy 197.283331 -282.102315)
			(xy 197.283832 -282.112466) (xy 197.283832 -282.521406) (xy 203.324968 -282.521406) (xy 203.324968 -282.112466)
			(xy 203.325406 -282.102302) (xy 203.333197 -282.083527) (xy 203.34758 -282.069162) (xy 203.366366 -282.061394)
			(xy 203.37653 -282.060904) (xy 204.77607 -282.060904) (xy 204.786222 -282.061457) (xy 204.804984 -282.069215)
			(xy 204.819349 -282.083563) (xy 204.827131 -282.102315) (xy 204.827632 -282.112466) (xy 204.827632 -282.521406)
			(xy 210.868768 -282.521406) (xy 210.868768 -282.112466) (xy 210.869206 -282.102302) (xy 210.876997 -282.083527)
			(xy 210.89138 -282.069162) (xy 210.910166 -282.061394) (xy 210.92033 -282.060904) (xy 212.31987 -282.060904)
			(xy 212.330022 -282.061457) (xy 212.348784 -282.069215) (xy 212.363149 -282.083563) (xy 212.370931 -282.102315)
			(xy 212.371432 -282.112466) (xy 212.371432 -282.521406) (xy 255.329436 -282.521406) (xy 255.329436 -282.112466)
			(xy 255.329905 -282.102306) (xy 255.337691 -282.083537) (xy 255.352064 -282.069173) (xy 255.370838 -282.061399)
			(xy 255.380998 -282.060904) (xy 256.780538 -282.060904) (xy 256.790694 -282.061401) (xy 256.809458 -282.069182)
			(xy 256.82382 -282.083546) (xy 256.831599 -282.10231) (xy 256.8321 -282.112466) (xy 256.8321 -282.521406)
			(xy 262.873236 -282.521406) (xy 262.873236 -282.112466) (xy 262.873705 -282.102306) (xy 262.881491 -282.083537)
			(xy 262.895864 -282.069173) (xy 262.914638 -282.061399) (xy 262.924798 -282.060904) (xy 264.324338 -282.060904)
			(xy 264.334494 -282.061401) (xy 264.353258 -282.069182) (xy 264.36762 -282.083546) (xy 264.375399 -282.10231)
			(xy 264.3759 -282.112466) (xy 264.3759 -282.521406) (xy 270.417036 -282.521406) (xy 270.417036 -282.112466)
			(xy 270.417505 -282.102306) (xy 270.425291 -282.083537) (xy 270.439664 -282.069173) (xy 270.458438 -282.061399)
			(xy 270.468598 -282.060904) (xy 271.868138 -282.060904) (xy 271.878294 -282.061401) (xy 271.897058 -282.069182)
			(xy 271.91142 -282.083546) (xy 271.919199 -282.10231) (xy 271.9197 -282.112466) (xy 271.9197 -282.521406)
			(xy 277.960836 -282.521406) (xy 277.960836 -282.112466) (xy 277.961305 -282.102306) (xy 277.969091 -282.083537)
			(xy 277.983464 -282.069173) (xy 278.002238 -282.061399) (xy 278.012398 -282.060904) (xy 279.411938 -282.060904)
			(xy 279.422094 -282.061401) (xy 279.440858 -282.069182) (xy 279.45522 -282.083546) (xy 279.462999 -282.10231)
			(xy 279.4635 -282.112466) (xy 279.4635 -282.521406) (xy 285.504636 -282.521406) (xy 285.504636 -282.112466)
			(xy 285.505105 -282.102306) (xy 285.512891 -282.083537) (xy 285.527264 -282.069173) (xy 285.546038 -282.061399)
			(xy 285.556198 -282.060904) (xy 286.955738 -282.060904) (xy 286.965894 -282.061401) (xy 286.984658 -282.069182)
			(xy 286.99902 -282.083546) (xy 287.006799 -282.10231) (xy 287.0073 -282.112466) (xy 287.0073 -282.521406)
			(xy 293.048436 -282.521406) (xy 293.048436 -282.112466) (xy 293.048905 -282.102306) (xy 293.056691 -282.083537)
			(xy 293.071064 -282.069173) (xy 293.089838 -282.061399) (xy 293.099998 -282.060904) (xy 294.499538 -282.060904)
			(xy 294.509694 -282.061401) (xy 294.528458 -282.069182) (xy 294.54282 -282.083546) (xy 294.550599 -282.10231)
			(xy 294.5511 -282.112466) (xy 294.5511 -282.521406) (xy 300.592236 -282.521406) (xy 300.592236 -282.112466)
			(xy 300.592705 -282.102306) (xy 300.600491 -282.083537) (xy 300.614864 -282.069173) (xy 300.633638 -282.061399)
			(xy 300.643798 -282.060904) (xy 302.043338 -282.060904) (xy 302.053494 -282.061401) (xy 302.072258 -282.069182)
			(xy 302.08662 -282.083546) (xy 302.094399 -282.10231) (xy 302.0949 -282.112466) (xy 302.0949 -282.521406)
			(xy 308.136036 -282.521406) (xy 308.136036 -282.112466) (xy 308.136505 -282.102306) (xy 308.144291 -282.083537)
			(xy 308.158664 -282.069173) (xy 308.177438 -282.061399) (xy 308.187598 -282.060904) (xy 309.587138 -282.060904)
			(xy 309.597294 -282.061401) (xy 309.616058 -282.069182) (xy 309.63042 -282.083546) (xy 309.638199 -282.10231)
			(xy 309.6387 -282.112466) (xy 309.6387 -282.405836) (xy 335.395824 -282.405836) (xy 335.396332 -282.379949)
			(xy 335.404431 -282.328811) (xy 335.42043 -282.279571) (xy 335.443936 -282.233439) (xy 335.474368 -282.191552)
			(xy 335.510978 -282.154942) (xy 335.552865 -282.12451) (xy 335.598997 -282.101004) (xy 335.648237 -282.085005)
			(xy 335.699375 -282.076906) (xy 335.751149 -282.076906) (xy 335.802287 -282.085005) (xy 335.851527 -282.101004)
			(xy 335.897659 -282.12451) (xy 335.939546 -282.154942) (xy 335.976156 -282.191552) (xy 336.006588 -282.233439)
			(xy 336.030094 -282.279571) (xy 336.046093 -282.328811) (xy 336.054192 -282.379949) (xy 336.0547 -282.405836)
			(xy 336.054214 -282.431707) (xy 336.336126 -282.431707) (xy 336.336126 -282.379893) (xy 336.344232 -282.328716)
			(xy 336.360244 -282.279437) (xy 336.383768 -282.23327) (xy 336.414225 -282.191352) (xy 336.450864 -282.154714)
			(xy 336.492784 -282.12426) (xy 336.538952 -282.100738) (xy 336.588231 -282.084728) (xy 336.639409 -282.076625)
			(xy 336.665316 -282.076144) (xy 336.690811 -282.076599) (xy 336.74119 -282.084464) (xy 336.789755 -282.100003)
			(xy 336.835342 -282.122845) (xy 336.876862 -282.152443) (xy 336.913321 -282.188089) (xy 336.928968 -282.208224)
			(xy 337.341464 -282.208224) (xy 337.35711 -282.18809) (xy 337.393571 -282.152447) (xy 337.435092 -282.122853)
			(xy 337.480679 -282.100016) (xy 337.529243 -282.084481) (xy 337.579622 -282.076621) (xy 337.605116 -282.076144)
			(xy 337.631025 -282.076581) (xy 337.682206 -282.08469) (xy 337.731488 -282.100704) (xy 337.777658 -282.124231)
			(xy 337.819579 -282.154691) (xy 337.85622 -282.191333) (xy 337.886677 -282.233256) (xy 337.910202 -282.279427)
			(xy 337.926214 -282.32871) (xy 337.93432 -282.379891) (xy 337.93432 -282.431709) (xy 337.926214 -282.48289)
			(xy 337.910202 -282.532173) (xy 337.886677 -282.578344) (xy 337.85622 -282.620267) (xy 337.819579 -282.656909)
			(xy 337.777658 -282.687369) (xy 337.731488 -282.710896) (xy 337.682206 -282.72691) (xy 337.631025 -282.735019)
			(xy 337.605116 -282.735528) (xy 337.579623 -282.735021) (xy 337.529248 -282.727163) (xy 337.480686 -282.711632)
			(xy 337.435099 -282.6888) (xy 337.393577 -282.659213) (xy 337.357114 -282.623577) (xy 337.341464 -282.603448)
			(xy 336.928968 -282.603448) (xy 336.913322 -282.623582) (xy 336.876859 -282.659221) (xy 336.835338 -282.688813)
			(xy 336.78975 -282.71165) (xy 336.741187 -282.727186) (xy 336.69081 -282.735049) (xy 336.665316 -282.735528)
			(xy 336.639409 -282.734975) (xy 336.588231 -282.726872) (xy 336.538952 -282.710862) (xy 336.492784 -282.68734)
			(xy 336.450864 -282.656886) (xy 336.414225 -282.620248) (xy 336.383768 -282.57833) (xy 336.360244 -282.532163)
			(xy 336.344232 -282.482884) (xy 336.336126 -282.431707) (xy 336.054214 -282.431707) (xy 336.054179 -282.433545)
			(xy 336.044978 -282.488191) (xy 336.036412 -282.514548) (xy 336.028538 -282.536646) (xy 336.23377 -282.891738)
			(xy 336.25663 -282.896056) (xy 336.281436 -282.901231) (xy 336.329174 -282.918223) (xy 336.373751 -282.94232)
			(xy 336.414116 -282.972953) (xy 336.449318 -283.009401) (xy 336.478529 -283.050806) (xy 336.501062 -283.096194)
			(xy 336.516384 -283.144494) (xy 336.524137 -283.19457) (xy 336.5246 -283.219906) (xy 338.685124 -283.219906)
			(xy 338.685593 -283.194571) (xy 338.693345 -283.144497) (xy 338.708668 -283.096199) (xy 338.731201 -283.050814)
			(xy 338.760412 -283.009411) (xy 338.795615 -282.972966) (xy 338.83598 -282.942336) (xy 338.880556 -282.918243)
			(xy 338.928293 -282.901254) (xy 338.953094 -282.896056) (xy 338.975954 -282.891738) (xy 339.181186 -282.536392)
			(xy 339.173566 -282.514548) (xy 339.164924 -282.488205) (xy 339.155609 -282.433555) (xy 339.155024 -282.405836)
			(xy 339.155532 -282.379929) (xy 339.163638 -282.328752) (xy 339.17965 -282.279473) (xy 339.203173 -282.233306)
			(xy 339.233629 -282.191387) (xy 339.270267 -282.154749) (xy 339.312186 -282.124293) (xy 339.358353 -282.10077)
			(xy 339.407632 -282.084758) (xy 339.458809 -282.076652) (xy 339.510623 -282.076652) (xy 339.5618 -282.084758)
			(xy 339.611079 -282.10077) (xy 339.657246 -282.124293) (xy 339.699165 -282.154749) (xy 339.735803 -282.191387)
			(xy 339.766259 -282.233306) (xy 339.789782 -282.279473) (xy 339.805794 -282.328752) (xy 339.8139 -282.379929)
			(xy 339.814408 -282.405836) (xy 341.034624 -282.405836) (xy 341.035068 -282.38049) (xy 341.04285 -282.330397)
			(xy 341.058205 -282.282085) (xy 341.080771 -282.236692) (xy 341.110018 -282.195286) (xy 341.145256 -282.158843)
			(xy 341.185656 -282.128222) (xy 341.230265 -282.104142) (xy 341.278033 -282.087172) (xy 341.302848 -282.081986)
			(xy 341.325708 -282.077668) (xy 341.530686 -281.72283) (xy 341.522812 -281.700986) (xy 341.514229 -281.674568)
			(xy 341.505035 -281.619792) (xy 341.504524 -281.59202) (xy 341.505032 -281.566133) (xy 341.513131 -281.514995)
			(xy 341.52913 -281.465755) (xy 341.552636 -281.419623) (xy 341.583068 -281.377736) (xy 341.619678 -281.341126)
			(xy 341.661565 -281.310694) (xy 341.707697 -281.287188) (xy 341.756937 -281.271189) (xy 341.808075 -281.26309)
			(xy 341.859849 -281.26309) (xy 341.910987 -281.271189) (xy 341.960227 -281.287188) (xy 342.006359 -281.310694)
			(xy 342.048246 -281.341126) (xy 342.084856 -281.377736) (xy 342.115288 -281.419623) (xy 342.138794 -281.465755)
			(xy 342.154793 -281.514995) (xy 342.162892 -281.566133) (xy 342.1634 -281.59202) (xy 342.162935 -281.617355)
			(xy 342.15518 -281.667428) (xy 342.139855 -281.715725) (xy 342.117321 -281.761109) (xy 342.088109 -281.802511)
			(xy 342.052906 -281.838956) (xy 342.012542 -281.869586) (xy 341.967967 -281.89368) (xy 341.92023 -281.910671)
			(xy 341.89543 -281.91587) (xy 341.87257 -281.920188) (xy 341.667592 -282.275026) (xy 341.675466 -282.297124)
			(xy 341.684085 -282.323474) (xy 341.693414 -282.378119) (xy 341.694008 -282.405836) (xy 342.914224 -282.405836)
			(xy 342.914629 -282.380499) (xy 342.922392 -282.330422) (xy 342.937724 -282.282122) (xy 342.960266 -282.236737)
			(xy 342.989485 -282.195335) (xy 343.024695 -282.15889) (xy 343.065066 -282.128262) (xy 343.109648 -282.10417)
			(xy 343.157391 -282.087183) (xy 343.182194 -282.081986) (xy 343.205054 -282.077668) (xy 343.410286 -281.722322)
			(xy 343.402666 -281.700478) (xy 343.39404 -281.674196) (xy 343.384726 -281.619675) (xy 343.384124 -281.59202)
			(xy 343.384632 -281.566113) (xy 343.392738 -281.514936) (xy 343.40875 -281.465657) (xy 343.432273 -281.41949)
			(xy 343.462729 -281.377571) (xy 343.499367 -281.340933) (xy 343.541286 -281.310477) (xy 343.587453 -281.286954)
			(xy 343.636732 -281.270942) (xy 343.687909 -281.262836) (xy 343.739723 -281.262836) (xy 343.7909 -281.270942)
			(xy 343.840179 -281.286954) (xy 343.886346 -281.310477) (xy 343.928265 -281.340933) (xy 343.964903 -281.377571)
			(xy 343.995359 -281.41949) (xy 344.018882 -281.465657) (xy 344.034894 -281.514936) (xy 344.043 -281.566113)
			(xy 344.043508 -281.59202) (xy 345.263724 -281.59202) (xy 345.264244 -281.566676) (xy 345.272013 -281.516587)
			(xy 345.287357 -281.468277) (xy 345.309913 -281.422884) (xy 345.33915 -281.381477) (xy 345.374379 -281.345033)
			(xy 345.414771 -281.31441) (xy 345.459374 -281.290329) (xy 345.507136 -281.273357) (xy 345.531948 -281.26817)
			(xy 345.554808 -281.263852) (xy 345.759786 -280.909014) (xy 345.751912 -280.88717) (xy 345.743326 -280.860753)
			(xy 345.734134 -280.805977) (xy 345.733624 -280.778204) (xy 345.734132 -280.752317) (xy 345.742231 -280.701179)
			(xy 345.75823 -280.651939) (xy 345.781736 -280.605807) (xy 345.812168 -280.56392) (xy 345.848778 -280.52731)
			(xy 345.890665 -280.496878) (xy 345.936797 -280.473372) (xy 345.986037 -280.457373) (xy 346.037175 -280.449274)
			(xy 346.088949 -280.449274) (xy 346.140087 -280.457373) (xy 346.189327 -280.473372) (xy 346.235459 -280.496878)
			(xy 346.277346 -280.52731) (xy 346.313956 -280.56392) (xy 346.344388 -280.605807) (xy 346.367894 -280.651939)
			(xy 346.383893 -280.701179) (xy 346.391992 -280.752317) (xy 346.3925 -280.778204) (xy 348.553024 -280.778204)
			(xy 348.553532 -280.752317) (xy 348.561631 -280.701179) (xy 348.57763 -280.651939) (xy 348.601136 -280.605807)
			(xy 348.631568 -280.56392) (xy 348.668178 -280.52731) (xy 348.710065 -280.496878) (xy 348.756197 -280.473372)
			(xy 348.805437 -280.457373) (xy 348.856575 -280.449274) (xy 348.908349 -280.449274) (xy 348.959487 -280.457373)
			(xy 349.008727 -280.473372) (xy 349.054859 -280.496878) (xy 349.096746 -280.52731) (xy 349.133356 -280.56392)
			(xy 349.163788 -280.605807) (xy 349.187294 -280.651939) (xy 349.203293 -280.701179) (xy 349.211392 -280.752317)
			(xy 349.2119 -280.778204) (xy 351.372424 -280.778204) (xy 351.372932 -280.752317) (xy 351.381031 -280.701179)
			(xy 351.39703 -280.651939) (xy 351.420536 -280.605807) (xy 351.450968 -280.56392) (xy 351.487578 -280.52731)
			(xy 351.529465 -280.496878) (xy 351.575597 -280.473372) (xy 351.624837 -280.457373) (xy 351.675975 -280.449274)
			(xy 351.727749 -280.449274) (xy 351.778887 -280.457373) (xy 351.828127 -280.473372) (xy 351.874259 -280.496878)
			(xy 351.916146 -280.52731) (xy 351.952756 -280.56392) (xy 351.983188 -280.605807) (xy 352.006694 -280.651939)
			(xy 352.022693 -280.701179) (xy 352.030792 -280.752317) (xy 352.0313 -280.778204) (xy 352.312224 -280.778204)
			(xy 352.312691 -280.752869) (xy 352.320444 -280.702795) (xy 352.335767 -280.654496) (xy 352.3583 -280.609112)
			(xy 352.387511 -280.567709) (xy 352.422714 -280.531263) (xy 352.463079 -280.500633) (xy 352.507655 -280.47654)
			(xy 352.555393 -280.459552) (xy 352.580194 -280.454354) (xy 352.603054 -280.450036) (xy 352.808286 -280.09469)
			(xy 352.800666 -280.072592) (xy 352.792043 -280.046309) (xy 352.782727 -279.991789) (xy 352.782124 -279.964134)
			(xy 352.782632 -279.938227) (xy 352.790738 -279.88705) (xy 352.80675 -279.837771) (xy 352.830273 -279.791604)
			(xy 352.860729 -279.749685) (xy 352.897367 -279.713047) (xy 352.939286 -279.682591) (xy 352.985453 -279.659068)
			(xy 353.034732 -279.643056) (xy 353.085909 -279.63495) (xy 353.137723 -279.63495) (xy 353.1889 -279.643056)
			(xy 353.238179 -279.659068) (xy 353.284346 -279.682591) (xy 353.326265 -279.713047) (xy 353.362903 -279.749685)
			(xy 353.393359 -279.791604) (xy 353.416882 -279.837771) (xy 353.432894 -279.88705) (xy 353.441 -279.938227)
			(xy 353.441508 -279.964134) (xy 353.441388 -279.9715) (xy 410.102304 -279.9715) (xy 410.102304 -279.56256)
			(xy 410.102689 -279.552403) (xy 410.110499 -279.533649) (xy 410.124906 -279.519327) (xy 410.143706 -279.511629)
			(xy 410.153866 -279.511252) (xy 411.553406 -279.511252) (xy 411.563535 -279.511722) (xy 411.582258 -279.519454)
			(xy 411.596615 -279.533746) (xy 411.604431 -279.552434) (xy 411.604968 -279.56256) (xy 411.604968 -279.9715)
			(xy 417.646104 -279.9715) (xy 417.646104 -279.56256) (xy 417.646489 -279.552403) (xy 417.654299 -279.533649)
			(xy 417.668706 -279.519327) (xy 417.687506 -279.511629) (xy 417.697666 -279.511252) (xy 419.097206 -279.511252)
			(xy 419.107335 -279.511722) (xy 419.126058 -279.519454) (xy 419.140415 -279.533746) (xy 419.148231 -279.552434)
			(xy 419.148768 -279.56256) (xy 419.148768 -279.9715) (xy 425.189904 -279.9715) (xy 425.189904 -279.56256)
			(xy 425.190289 -279.552403) (xy 425.198099 -279.533649) (xy 425.212506 -279.519327) (xy 425.231306 -279.511629)
			(xy 425.241466 -279.511252) (xy 426.641006 -279.511252) (xy 426.651135 -279.511722) (xy 426.669858 -279.519454)
			(xy 426.684215 -279.533746) (xy 426.692031 -279.552434) (xy 426.692568 -279.56256) (xy 426.692568 -279.9715)
			(xy 432.733704 -279.9715) (xy 432.733704 -279.56256) (xy 432.734089 -279.552403) (xy 432.741899 -279.533649)
			(xy 432.756306 -279.519327) (xy 432.775106 -279.511629) (xy 432.785266 -279.511252) (xy 434.184806 -279.511252)
			(xy 434.194935 -279.511722) (xy 434.213658 -279.519454) (xy 434.228015 -279.533746) (xy 434.235831 -279.552434)
			(xy 434.236368 -279.56256) (xy 434.236368 -279.9715) (xy 440.277504 -279.9715) (xy 440.277504 -279.56256)
			(xy 440.277889 -279.552403) (xy 440.285699 -279.533649) (xy 440.300106 -279.519327) (xy 440.318906 -279.511629)
			(xy 440.329066 -279.511252) (xy 441.728606 -279.511252) (xy 441.738735 -279.511722) (xy 441.757458 -279.519454)
			(xy 441.771815 -279.533746) (xy 441.779631 -279.552434) (xy 441.780168 -279.56256) (xy 441.780168 -279.9715)
			(xy 447.821304 -279.9715) (xy 447.821304 -279.56256) (xy 447.821689 -279.552403) (xy 447.829499 -279.533649)
			(xy 447.843906 -279.519327) (xy 447.862706 -279.511629) (xy 447.872866 -279.511252) (xy 449.272406 -279.511252)
			(xy 449.282535 -279.511722) (xy 449.301258 -279.519454) (xy 449.315615 -279.533746) (xy 449.323431 -279.552434)
			(xy 449.323968 -279.56256) (xy 449.323968 -279.9715) (xy 455.365104 -279.9715) (xy 455.365104 -279.56256)
			(xy 455.365489 -279.552403) (xy 455.373299 -279.533649) (xy 455.387706 -279.519327) (xy 455.406506 -279.511629)
			(xy 455.416666 -279.511252) (xy 456.816206 -279.511252) (xy 456.826335 -279.511722) (xy 456.845058 -279.519454)
			(xy 456.859415 -279.533746) (xy 456.867231 -279.552434) (xy 456.867768 -279.56256) (xy 456.867768 -279.9715)
			(xy 462.908904 -279.9715) (xy 462.908904 -279.56256) (xy 462.909289 -279.552403) (xy 462.917099 -279.533649)
			(xy 462.931506 -279.519327) (xy 462.950306 -279.511629) (xy 462.960466 -279.511252) (xy 464.360006 -279.511252)
			(xy 464.370135 -279.511722) (xy 464.388858 -279.519454) (xy 464.403215 -279.533746) (xy 464.411031 -279.552434)
			(xy 464.411568 -279.56256) (xy 464.411568 -279.9715) (xy 464.411178 -279.981658) (xy 464.403376 -280.000417)
			(xy 464.388969 -280.014741) (xy 464.370166 -280.022435) (xy 464.360006 -280.022808) (xy 462.960466 -280.022808)
			(xy 462.950343 -280.022303) (xy 462.93163 -280.014573) (xy 462.917277 -280.000293) (xy 462.90945 -279.98162)
			(xy 462.908904 -279.9715) (xy 456.867768 -279.9715) (xy 456.867378 -279.981658) (xy 456.859576 -280.000417)
			(xy 456.845169 -280.014741) (xy 456.826366 -280.022435) (xy 456.816206 -280.022808) (xy 455.416666 -280.022808)
			(xy 455.406543 -280.022303) (xy 455.38783 -280.014573) (xy 455.373477 -280.000293) (xy 455.36565 -279.98162)
			(xy 455.365104 -279.9715) (xy 449.323968 -279.9715) (xy 449.323578 -279.981658) (xy 449.315776 -280.000417)
			(xy 449.301369 -280.014741) (xy 449.282566 -280.022435) (xy 449.272406 -280.022808) (xy 447.872866 -280.022808)
			(xy 447.862743 -280.022303) (xy 447.84403 -280.014573) (xy 447.829677 -280.000293) (xy 447.82185 -279.98162)
			(xy 447.821304 -279.9715) (xy 441.780168 -279.9715) (xy 441.779778 -279.981658) (xy 441.771976 -280.000417)
			(xy 441.757569 -280.014741) (xy 441.738766 -280.022435) (xy 441.728606 -280.022808) (xy 440.329066 -280.022808)
			(xy 440.318943 -280.022303) (xy 440.30023 -280.014573) (xy 440.285877 -280.000293) (xy 440.27805 -279.98162)
			(xy 440.277504 -279.9715) (xy 434.236368 -279.9715) (xy 434.235978 -279.981658) (xy 434.228176 -280.000417)
			(xy 434.213769 -280.014741) (xy 434.194966 -280.022435) (xy 434.184806 -280.022808) (xy 432.785266 -280.022808)
			(xy 432.775143 -280.022303) (xy 432.75643 -280.014573) (xy 432.742077 -280.000293) (xy 432.73425 -279.98162)
			(xy 432.733704 -279.9715) (xy 426.692568 -279.9715) (xy 426.692178 -279.981658) (xy 426.684376 -280.000417)
			(xy 426.669969 -280.014741) (xy 426.651166 -280.022435) (xy 426.641006 -280.022808) (xy 425.241466 -280.022808)
			(xy 425.231343 -280.022303) (xy 425.21263 -280.014573) (xy 425.198277 -280.000293) (xy 425.19045 -279.98162)
			(xy 425.189904 -279.9715) (xy 419.148768 -279.9715) (xy 419.148378 -279.981658) (xy 419.140576 -280.000417)
			(xy 419.126169 -280.014741) (xy 419.107366 -280.022435) (xy 419.097206 -280.022808) (xy 417.697666 -280.022808)
			(xy 417.687543 -280.022303) (xy 417.66883 -280.014573) (xy 417.654477 -280.000293) (xy 417.64665 -279.98162)
			(xy 417.646104 -279.9715) (xy 411.604968 -279.9715) (xy 411.604578 -279.981658) (xy 411.596776 -280.000417)
			(xy 411.582369 -280.014741) (xy 411.563566 -280.022435) (xy 411.553406 -280.022808) (xy 410.153866 -280.022808)
			(xy 410.143743 -280.022303) (xy 410.12503 -280.014573) (xy 410.110677 -280.000293) (xy 410.10285 -279.98162)
			(xy 410.102304 -279.9715) (xy 353.441388 -279.9715) (xy 353.441095 -279.9895) (xy 353.433341 -280.039635)
			(xy 353.417991 -280.087988) (xy 353.395408 -280.133416) (xy 353.366127 -280.174843) (xy 353.330839 -280.211291)
			(xy 353.290379 -280.241896) (xy 353.245705 -280.265935) (xy 353.197873 -280.282839) (xy 353.17303 -280.287984)
			(xy 353.149916 -280.292302) (xy 352.944938 -280.647394) (xy 352.952812 -280.669492) (xy 352.961371 -280.695851)
			(xy 352.970571 -280.750496) (xy 352.9711 -280.778204) (xy 352.970592 -280.804091) (xy 352.97059 -280.804105)
			(xy 353.25232 -280.804105) (xy 353.25232 -280.752295) (xy 353.260425 -280.701122) (xy 353.276434 -280.651848)
			(xy 353.299953 -280.605684) (xy 353.330405 -280.563767) (xy 353.367038 -280.527129) (xy 353.408951 -280.496673)
			(xy 353.455113 -280.473148) (xy 353.504385 -280.457133) (xy 353.555557 -280.449023) (xy 353.581462 -280.448512)
			(xy 353.606973 -280.449015) (xy 353.657387 -280.45687) (xy 353.705988 -280.472399) (xy 353.751617 -280.49523)
			(xy 353.793183 -280.524819) (xy 353.829694 -280.560459) (xy 353.845368 -280.580592) (xy 354.257356 -280.580592)
			(xy 354.273053 -280.560476) (xy 354.309558 -280.524831) (xy 354.351119 -280.495236) (xy 354.396742 -280.472396)
			(xy 354.44534 -280.456858) (xy 354.495751 -280.448992) (xy 354.521262 -280.448512) (xy 354.547174 -280.448983)
			(xy 354.59836 -280.457084) (xy 354.647648 -280.473094) (xy 354.693825 -280.496618) (xy 354.735753 -280.527076)
			(xy 354.7724 -280.563718) (xy 354.802863 -280.605643) (xy 354.826391 -280.651817) (xy 354.842407 -280.701103)
			(xy 354.850514 -280.752288) (xy 354.850514 -280.804112) (xy 354.847778 -280.821384) (xy 406.002236 -280.821384)
			(xy 406.002236 -280.412444) (xy 406.002658 -280.402288) (xy 406.010446 -280.38353) (xy 406.024844 -280.369204)
			(xy 406.04364 -280.361509) (xy 406.053798 -280.361136) (xy 407.453338 -280.361136) (xy 407.463467 -280.361595)
			(xy 407.482188 -280.369335) (xy 407.496543 -280.383629) (xy 407.504361 -280.402318) (xy 407.5049 -280.412444)
			(xy 407.5049 -280.821384) (xy 413.546036 -280.821384) (xy 413.546036 -280.412444) (xy 413.546458 -280.402288)
			(xy 413.554246 -280.38353) (xy 413.568644 -280.369204) (xy 413.58744 -280.361509) (xy 413.597598 -280.361136)
			(xy 414.997138 -280.361136) (xy 415.007267 -280.361595) (xy 415.025988 -280.369335) (xy 415.040343 -280.383629)
			(xy 415.048161 -280.402318) (xy 415.0487 -280.412444) (xy 415.0487 -280.821384) (xy 421.089836 -280.821384)
			(xy 421.089836 -280.412444) (xy 421.090258 -280.402288) (xy 421.098046 -280.38353) (xy 421.112444 -280.369204)
			(xy 421.13124 -280.361509) (xy 421.141398 -280.361136) (xy 422.540938 -280.361136) (xy 422.551067 -280.361595)
			(xy 422.569788 -280.369335) (xy 422.584143 -280.383629) (xy 422.591961 -280.402318) (xy 422.5925 -280.412444)
			(xy 422.5925 -280.821384) (xy 428.633636 -280.821384) (xy 428.633636 -280.412444) (xy 428.634058 -280.402288)
			(xy 428.641846 -280.38353) (xy 428.656244 -280.369204) (xy 428.67504 -280.361509) (xy 428.685198 -280.361136)
			(xy 430.084738 -280.361136) (xy 430.094867 -280.361595) (xy 430.113588 -280.369335) (xy 430.127943 -280.383629)
			(xy 430.135761 -280.402318) (xy 430.1363 -280.412444) (xy 430.1363 -280.821384) (xy 436.177436 -280.821384)
			(xy 436.177436 -280.412444) (xy 436.177858 -280.402288) (xy 436.185646 -280.38353) (xy 436.200044 -280.369204)
			(xy 436.21884 -280.361509) (xy 436.228998 -280.361136) (xy 437.628538 -280.361136) (xy 437.638667 -280.361595)
			(xy 437.657388 -280.369335) (xy 437.671743 -280.383629) (xy 437.679561 -280.402318) (xy 437.6801 -280.412444)
			(xy 437.6801 -280.821384) (xy 443.721236 -280.821384) (xy 443.721236 -280.412444) (xy 443.721658 -280.402288)
			(xy 443.729446 -280.38353) (xy 443.743844 -280.369204) (xy 443.76264 -280.361509) (xy 443.772798 -280.361136)
			(xy 445.172338 -280.361136) (xy 445.182467 -280.361595) (xy 445.201188 -280.369335) (xy 445.215543 -280.383629)
			(xy 445.223361 -280.402318) (xy 445.2239 -280.412444) (xy 445.2239 -280.821384) (xy 451.265036 -280.821384)
			(xy 451.265036 -280.412444) (xy 451.265458 -280.402288) (xy 451.273246 -280.38353) (xy 451.287644 -280.369204)
			(xy 451.30644 -280.361509) (xy 451.316598 -280.361136) (xy 452.716138 -280.361136) (xy 452.726267 -280.361595)
			(xy 452.744988 -280.369335) (xy 452.759343 -280.383629) (xy 452.767161 -280.402318) (xy 452.7677 -280.412444)
			(xy 452.7677 -280.821384) (xy 458.808836 -280.821384) (xy 458.808836 -280.412444) (xy 458.809258 -280.402288)
			(xy 458.817046 -280.38353) (xy 458.831444 -280.369204) (xy 458.85024 -280.361509) (xy 458.860398 -280.361136)
			(xy 460.259938 -280.361136) (xy 460.270067 -280.361595) (xy 460.288788 -280.369335) (xy 460.303143 -280.383629)
			(xy 460.310961 -280.402318) (xy 460.3115 -280.412444) (xy 460.3115 -280.821384) (xy 460.311065 -280.831537)
			(xy 460.303275 -280.850289) (xy 460.288882 -280.864613) (xy 460.270093 -280.872313) (xy 460.259938 -280.872692)
			(xy 458.860398 -280.872692) (xy 458.850275 -280.872176) (xy 458.83156 -280.864453) (xy 458.817205 -280.850177)
			(xy 458.80938 -280.831504) (xy 458.808836 -280.821384) (xy 452.7677 -280.821384) (xy 452.767265 -280.831537)
			(xy 452.759475 -280.850289) (xy 452.745082 -280.864613) (xy 452.726293 -280.872313) (xy 452.716138 -280.872692)
			(xy 451.316598 -280.872692) (xy 451.306475 -280.872176) (xy 451.28776 -280.864453) (xy 451.273405 -280.850177)
			(xy 451.26558 -280.831504) (xy 451.265036 -280.821384) (xy 445.2239 -280.821384) (xy 445.223465 -280.831537)
			(xy 445.215675 -280.850289) (xy 445.201282 -280.864613) (xy 445.182493 -280.872313) (xy 445.172338 -280.872692)
			(xy 443.772798 -280.872692) (xy 443.762675 -280.872176) (xy 443.74396 -280.864453) (xy 443.729605 -280.850177)
			(xy 443.72178 -280.831504) (xy 443.721236 -280.821384) (xy 437.6801 -280.821384) (xy 437.679665 -280.831537)
			(xy 437.671875 -280.850289) (xy 437.657482 -280.864613) (xy 437.638693 -280.872313) (xy 437.628538 -280.872692)
			(xy 436.228998 -280.872692) (xy 436.218875 -280.872176) (xy 436.20016 -280.864453) (xy 436.185805 -280.850177)
			(xy 436.17798 -280.831504) (xy 436.177436 -280.821384) (xy 430.1363 -280.821384) (xy 430.135865 -280.831537)
			(xy 430.128075 -280.850289) (xy 430.113682 -280.864613) (xy 430.094893 -280.872313) (xy 430.084738 -280.872692)
			(xy 428.685198 -280.872692) (xy 428.675075 -280.872176) (xy 428.65636 -280.864453) (xy 428.642005 -280.850177)
			(xy 428.63418 -280.831504) (xy 428.633636 -280.821384) (xy 422.5925 -280.821384) (xy 422.592065 -280.831537)
			(xy 422.584275 -280.850289) (xy 422.569882 -280.864613) (xy 422.551093 -280.872313) (xy 422.540938 -280.872692)
			(xy 421.141398 -280.872692) (xy 421.131275 -280.872176) (xy 421.11256 -280.864453) (xy 421.098205 -280.850177)
			(xy 421.09038 -280.831504) (xy 421.089836 -280.821384) (xy 415.0487 -280.821384) (xy 415.048265 -280.831537)
			(xy 415.040475 -280.850289) (xy 415.026082 -280.864613) (xy 415.007293 -280.872313) (xy 414.997138 -280.872692)
			(xy 413.597598 -280.872692) (xy 413.587475 -280.872176) (xy 413.56876 -280.864453) (xy 413.554405 -280.850177)
			(xy 413.54658 -280.831504) (xy 413.546036 -280.821384) (xy 407.5049 -280.821384) (xy 407.504465 -280.831537)
			(xy 407.496675 -280.850289) (xy 407.482282 -280.864613) (xy 407.463493 -280.872313) (xy 407.453338 -280.872692)
			(xy 406.053798 -280.872692) (xy 406.043675 -280.872176) (xy 406.02496 -280.864453) (xy 406.010605 -280.850177)
			(xy 406.00278 -280.831504) (xy 406.002236 -280.821384) (xy 354.847778 -280.821384) (xy 354.842407 -280.855297)
			(xy 354.826391 -280.904583) (xy 354.802863 -280.950757) (xy 354.7724 -280.992682) (xy 354.735753 -281.029324)
			(xy 354.693825 -281.059782) (xy 354.647648 -281.083306) (xy 354.59836 -281.099316) (xy 354.547174 -281.107417)
			(xy 354.521262 -281.107896) (xy 354.495749 -281.107445) (xy 354.445333 -281.099578) (xy 354.396731 -281.084039)
			(xy 354.351103 -281.061198) (xy 354.309538 -281.031601) (xy 354.273029 -280.995953) (xy 354.257356 -280.975816)
			(xy 353.845368 -280.975816) (xy 353.829717 -280.99597) (xy 353.793203 -281.031612) (xy 353.751632 -281.061203)
			(xy 353.705999 -281.084036) (xy 353.657393 -281.099566) (xy 353.606975 -281.107421) (xy 353.581462 -281.107896)
			(xy 353.555557 -281.107377) (xy 353.504385 -281.099267) (xy 353.455113 -281.083252) (xy 353.408951 -281.059727)
			(xy 353.367038 -281.029271) (xy 353.330405 -280.992633) (xy 353.299953 -280.950716) (xy 353.276434 -280.904552)
			(xy 353.260425 -280.855278) (xy 353.25232 -280.804105) (xy 352.97059 -280.804105) (xy 352.962493 -280.855229)
			(xy 352.946494 -280.904469) (xy 352.922988 -280.950601) (xy 352.892556 -280.992488) (xy 352.855946 -281.029098)
			(xy 352.814059 -281.05953) (xy 352.767927 -281.083036) (xy 352.718687 -281.099035) (xy 352.667549 -281.107134)
			(xy 352.615775 -281.107134) (xy 352.564637 -281.099035) (xy 352.515397 -281.083036) (xy 352.469265 -281.05953)
			(xy 352.427378 -281.029098) (xy 352.390768 -280.992488) (xy 352.360336 -280.950601) (xy 352.33683 -280.904469)
			(xy 352.320831 -280.855229) (xy 352.312732 -280.804091) (xy 352.312224 -280.778204) (xy 352.0313 -280.778204)
			(xy 352.0313 -280.778712) (xy 352.03071 -280.806228) (xy 352.021524 -280.860489) (xy 352.013012 -280.886662)
			(xy 352.005392 -280.908506) (xy 352.210624 -281.263852) (xy 352.233484 -281.26817) (xy 352.258305 -281.273337)
			(xy 352.306082 -281.290294) (xy 352.350699 -281.314367) (xy 352.391104 -281.344988) (xy 352.426344 -281.381435)
			(xy 352.455588 -281.422848) (xy 352.478145 -281.46825) (xy 352.493485 -281.516571) (xy 352.501244 -281.566671)
			(xy 352.501708 -281.59202) (xy 353.721924 -281.59202) (xy 353.722432 -281.566113) (xy 353.730538 -281.514936)
			(xy 353.74655 -281.465657) (xy 353.770073 -281.41949) (xy 353.800529 -281.377571) (xy 353.837167 -281.340933)
			(xy 353.879086 -281.310477) (xy 353.925253 -281.286954) (xy 353.974532 -281.270942) (xy 354.025709 -281.262836)
			(xy 354.077523 -281.262836) (xy 354.1287 -281.270942) (xy 354.177979 -281.286954) (xy 354.224146 -281.310477)
			(xy 354.266065 -281.340933) (xy 354.302703 -281.377571) (xy 354.333159 -281.41949) (xy 354.356682 -281.465657)
			(xy 354.372694 -281.514936) (xy 354.3808 -281.566113) (xy 354.381308 -281.59202) (xy 354.380739 -281.619802)
			(xy 354.371934 -281.671522) (xy 410.102304 -281.671522) (xy 410.102304 -281.262582) (xy 410.102818 -281.252427)
			(xy 410.110592 -281.233664) (xy 410.124951 -281.219301) (xy 410.143711 -281.211521) (xy 410.153866 -281.21102)
			(xy 411.553406 -281.21102) (xy 411.563562 -281.211528) (xy 411.582328 -281.219301) (xy 411.596692 -281.233662)
			(xy 411.604469 -281.252426) (xy 411.604968 -281.262582) (xy 411.604968 -281.671522) (xy 417.646104 -281.671522)
			(xy 417.646104 -281.262582) (xy 417.646618 -281.252427) (xy 417.654392 -281.233664) (xy 417.668751 -281.219301)
			(xy 417.687511 -281.211521) (xy 417.697666 -281.21102) (xy 419.097206 -281.21102) (xy 419.107362 -281.211528)
			(xy 419.126128 -281.219301) (xy 419.140492 -281.233662) (xy 419.148269 -281.252426) (xy 419.148768 -281.262582)
			(xy 419.148768 -281.671522) (xy 425.189904 -281.671522) (xy 425.189904 -281.262582) (xy 425.190418 -281.252427)
			(xy 425.198192 -281.233664) (xy 425.212551 -281.219301) (xy 425.231311 -281.211521) (xy 425.241466 -281.21102)
			(xy 426.641006 -281.21102) (xy 426.651162 -281.211528) (xy 426.669928 -281.219301) (xy 426.684292 -281.233662)
			(xy 426.692069 -281.252426) (xy 426.692568 -281.262582) (xy 426.692568 -281.671522) (xy 432.733704 -281.671522)
			(xy 432.733704 -281.262582) (xy 432.734218 -281.252427) (xy 432.741992 -281.233664) (xy 432.756351 -281.219301)
			(xy 432.775111 -281.211521) (xy 432.785266 -281.21102) (xy 434.184806 -281.21102) (xy 434.194962 -281.211528)
			(xy 434.213728 -281.219301) (xy 434.228092 -281.233662) (xy 434.235869 -281.252426) (xy 434.236368 -281.262582)
			(xy 434.236368 -281.671522) (xy 440.277504 -281.671522) (xy 440.277504 -281.262582) (xy 440.278018 -281.252427)
			(xy 440.285792 -281.233664) (xy 440.300151 -281.219301) (xy 440.318911 -281.211521) (xy 440.329066 -281.21102)
			(xy 441.728606 -281.21102) (xy 441.738762 -281.211528) (xy 441.757528 -281.219301) (xy 441.771892 -281.233662)
			(xy 441.779669 -281.252426) (xy 441.780168 -281.262582) (xy 441.780168 -281.671522) (xy 447.821304 -281.671522)
			(xy 447.821304 -281.262582) (xy 447.821818 -281.252427) (xy 447.829592 -281.233664) (xy 447.843951 -281.219301)
			(xy 447.862711 -281.211521) (xy 447.872866 -281.21102) (xy 449.272406 -281.21102) (xy 449.282562 -281.211528)
			(xy 449.301328 -281.219301) (xy 449.315692 -281.233662) (xy 449.323469 -281.252426) (xy 449.323968 -281.262582)
			(xy 449.323968 -281.671522) (xy 455.365104 -281.671522) (xy 455.365104 -281.262582) (xy 455.365618 -281.252427)
			(xy 455.373392 -281.233664) (xy 455.387751 -281.219301) (xy 455.406511 -281.211521) (xy 455.416666 -281.21102)
			(xy 456.816206 -281.21102) (xy 456.826362 -281.211528) (xy 456.845128 -281.219301) (xy 456.859492 -281.233662)
			(xy 456.867269 -281.252426) (xy 456.867768 -281.262582) (xy 456.867768 -281.671522) (xy 462.908904 -281.671522)
			(xy 462.908904 -281.262582) (xy 462.909418 -281.252427) (xy 462.917192 -281.233664) (xy 462.931551 -281.219301)
			(xy 462.950311 -281.211521) (xy 462.960466 -281.21102) (xy 464.360006 -281.21102) (xy 464.370162 -281.211528)
			(xy 464.388928 -281.219301) (xy 464.403292 -281.233662) (xy 464.411069 -281.252426) (xy 464.411568 -281.262582)
			(xy 464.411568 -281.671522) (xy 464.411085 -281.68168) (xy 464.403304 -281.700449) (xy 464.388936 -281.714813)
			(xy 464.370165 -281.722588) (xy 464.360006 -281.723084) (xy 462.960466 -281.723084) (xy 462.950309 -281.722595)
			(xy 462.931543 -281.714814) (xy 462.91718 -281.700447) (xy 462.909403 -281.681679) (xy 462.908904 -281.671522)
			(xy 456.867768 -281.671522) (xy 456.867285 -281.68168) (xy 456.859504 -281.700449) (xy 456.845136 -281.714813)
			(xy 456.826365 -281.722588) (xy 456.816206 -281.723084) (xy 455.416666 -281.723084) (xy 455.406509 -281.722595)
			(xy 455.387743 -281.714814) (xy 455.37338 -281.700447) (xy 455.365603 -281.681679) (xy 455.365104 -281.671522)
			(xy 449.323968 -281.671522) (xy 449.323485 -281.68168) (xy 449.315704 -281.700449) (xy 449.301336 -281.714813)
			(xy 449.282565 -281.722588) (xy 449.272406 -281.723084) (xy 447.872866 -281.723084) (xy 447.862709 -281.722595)
			(xy 447.843943 -281.714814) (xy 447.82958 -281.700447) (xy 447.821803 -281.681679) (xy 447.821304 -281.671522)
			(xy 441.780168 -281.671522) (xy 441.779685 -281.68168) (xy 441.771904 -281.700449) (xy 441.757536 -281.714813)
			(xy 441.738765 -281.722588) (xy 441.728606 -281.723084) (xy 440.329066 -281.723084) (xy 440.318909 -281.722595)
			(xy 440.300143 -281.714814) (xy 440.28578 -281.700447) (xy 440.278003 -281.681679) (xy 440.277504 -281.671522)
			(xy 434.236368 -281.671522) (xy 434.235885 -281.68168) (xy 434.228104 -281.700449) (xy 434.213736 -281.714813)
			(xy 434.194965 -281.722588) (xy 434.184806 -281.723084) (xy 432.785266 -281.723084) (xy 432.775109 -281.722595)
			(xy 432.756343 -281.714814) (xy 432.74198 -281.700447) (xy 432.734203 -281.681679) (xy 432.733704 -281.671522)
			(xy 426.692568 -281.671522) (xy 426.692085 -281.68168) (xy 426.684304 -281.700449) (xy 426.669936 -281.714813)
			(xy 426.651165 -281.722588) (xy 426.641006 -281.723084) (xy 425.241466 -281.723084) (xy 425.231309 -281.722595)
			(xy 425.212543 -281.714814) (xy 425.19818 -281.700447) (xy 425.190403 -281.681679) (xy 425.189904 -281.671522)
			(xy 419.148768 -281.671522) (xy 419.148285 -281.68168) (xy 419.140504 -281.700449) (xy 419.126136 -281.714813)
			(xy 419.107365 -281.722588) (xy 419.097206 -281.723084) (xy 417.697666 -281.723084) (xy 417.687509 -281.722595)
			(xy 417.668743 -281.714814) (xy 417.65438 -281.700447) (xy 417.646603 -281.681679) (xy 417.646104 -281.671522)
			(xy 411.604968 -281.671522) (xy 411.604485 -281.68168) (xy 411.596704 -281.700449) (xy 411.582336 -281.714813)
			(xy 411.563565 -281.722588) (xy 411.553406 -281.723084) (xy 410.153866 -281.723084) (xy 410.143709 -281.722595)
			(xy 410.124943 -281.714814) (xy 410.11058 -281.700447) (xy 410.102803 -281.681679) (xy 410.102304 -281.671522)
			(xy 354.371934 -281.671522) (xy 354.371414 -281.674578) (xy 354.362766 -281.700986) (xy 354.354892 -281.72283)
			(xy 354.55987 -282.077668) (xy 354.58273 -282.081986) (xy 354.607543 -282.087133) (xy 354.655283 -282.104127)
			(xy 354.699861 -282.128227) (xy 354.740227 -282.158863) (xy 354.775429 -282.195315) (xy 354.80464 -282.236724)
			(xy 354.82717 -282.282115) (xy 354.84249 -282.330419) (xy 354.850239 -282.380498) (xy 354.8507 -282.405836)
			(xy 354.850192 -282.431723) (xy 354.842093 -282.482861) (xy 354.829569 -282.521406) (xy 406.002236 -282.521406)
			(xy 406.002236 -282.112466) (xy 406.002705 -282.102306) (xy 406.010491 -282.083537) (xy 406.024864 -282.069173)
			(xy 406.043638 -282.061399) (xy 406.053798 -282.060904) (xy 407.453338 -282.060904) (xy 407.463494 -282.061401)
			(xy 407.482258 -282.069182) (xy 407.49662 -282.083546) (xy 407.504399 -282.10231) (xy 407.5049 -282.112466)
			(xy 407.5049 -282.521406) (xy 413.546036 -282.521406) (xy 413.546036 -282.112466) (xy 413.546505 -282.102306)
			(xy 413.554291 -282.083537) (xy 413.568664 -282.069173) (xy 413.587438 -282.061399) (xy 413.597598 -282.060904)
			(xy 414.997138 -282.060904) (xy 415.007294 -282.061401) (xy 415.026058 -282.069182) (xy 415.04042 -282.083546)
			(xy 415.048199 -282.10231) (xy 415.0487 -282.112466) (xy 415.0487 -282.521406) (xy 421.089836 -282.521406)
			(xy 421.089836 -282.112466) (xy 421.090305 -282.102306) (xy 421.098091 -282.083537) (xy 421.112464 -282.069173)
			(xy 421.131238 -282.061399) (xy 421.141398 -282.060904) (xy 422.540938 -282.060904) (xy 422.551094 -282.061401)
			(xy 422.569858 -282.069182) (xy 422.58422 -282.083546) (xy 422.591999 -282.10231) (xy 422.5925 -282.112466)
			(xy 422.5925 -282.521406) (xy 428.633636 -282.521406) (xy 428.633636 -282.112466) (xy 428.634105 -282.102306)
			(xy 428.641891 -282.083537) (xy 428.656264 -282.069173) (xy 428.675038 -282.061399) (xy 428.685198 -282.060904)
			(xy 430.084738 -282.060904) (xy 430.094894 -282.061401) (xy 430.113658 -282.069182) (xy 430.12802 -282.083546)
			(xy 430.135799 -282.10231) (xy 430.1363 -282.112466) (xy 430.1363 -282.521406) (xy 436.177436 -282.521406)
			(xy 436.177436 -282.112466) (xy 436.177905 -282.102306) (xy 436.185691 -282.083537) (xy 436.200064 -282.069173)
			(xy 436.218838 -282.061399) (xy 436.228998 -282.060904) (xy 437.628538 -282.060904) (xy 437.638694 -282.061401)
			(xy 437.657458 -282.069182) (xy 437.67182 -282.083546) (xy 437.679599 -282.10231) (xy 437.6801 -282.112466)
			(xy 437.6801 -282.521406) (xy 443.721236 -282.521406) (xy 443.721236 -282.112466) (xy 443.721705 -282.102306)
			(xy 443.729491 -282.083537) (xy 443.743864 -282.069173) (xy 443.762638 -282.061399) (xy 443.772798 -282.060904)
			(xy 445.172338 -282.060904) (xy 445.182494 -282.061401) (xy 445.201258 -282.069182) (xy 445.21562 -282.083546)
			(xy 445.223399 -282.10231) (xy 445.2239 -282.112466) (xy 445.2239 -282.521406) (xy 451.265036 -282.521406)
			(xy 451.265036 -282.112466) (xy 451.265505 -282.102306) (xy 451.273291 -282.083537) (xy 451.287664 -282.069173)
			(xy 451.306438 -282.061399) (xy 451.316598 -282.060904) (xy 452.716138 -282.060904) (xy 452.726294 -282.061401)
			(xy 452.745058 -282.069182) (xy 452.75942 -282.083546) (xy 452.767199 -282.10231) (xy 452.7677 -282.112466)
			(xy 452.7677 -282.521406) (xy 458.808836 -282.521406) (xy 458.808836 -282.112466) (xy 458.809305 -282.102306)
			(xy 458.817091 -282.083537) (xy 458.831464 -282.069173) (xy 458.850238 -282.061399) (xy 458.860398 -282.060904)
			(xy 460.259938 -282.060904) (xy 460.270094 -282.061401) (xy 460.288858 -282.069182) (xy 460.30322 -282.083546)
			(xy 460.310999 -282.10231) (xy 460.3115 -282.112466) (xy 460.3115 -282.521406) (xy 460.310972 -282.531559)
			(xy 460.303203 -282.550321) (xy 460.288848 -282.564685) (xy 460.270091 -282.572466) (xy 460.259938 -282.572968)
			(xy 458.860398 -282.572968) (xy 458.850241 -282.572468) (xy 458.831473 -282.564694) (xy 458.817108 -282.550331)
			(xy 458.809332 -282.531563) (xy 458.808836 -282.521406) (xy 452.7677 -282.521406) (xy 452.767172 -282.531559)
			(xy 452.759403 -282.550321) (xy 452.745048 -282.564685) (xy 452.726291 -282.572466) (xy 452.716138 -282.572968)
			(xy 451.316598 -282.572968) (xy 451.306441 -282.572468) (xy 451.287673 -282.564694) (xy 451.273308 -282.550331)
			(xy 451.265532 -282.531563) (xy 451.265036 -282.521406) (xy 445.2239 -282.521406) (xy 445.223372 -282.531559)
			(xy 445.215603 -282.550321) (xy 445.201248 -282.564685) (xy 445.182491 -282.572466) (xy 445.172338 -282.572968)
			(xy 443.772798 -282.572968) (xy 443.762641 -282.572468) (xy 443.743873 -282.564694) (xy 443.729508 -282.550331)
			(xy 443.721732 -282.531563) (xy 443.721236 -282.521406) (xy 437.6801 -282.521406) (xy 437.679572 -282.531559)
			(xy 437.671803 -282.550321) (xy 437.657448 -282.564685) (xy 437.638691 -282.572466) (xy 437.628538 -282.572968)
			(xy 436.228998 -282.572968) (xy 436.218841 -282.572468) (xy 436.200073 -282.564694) (xy 436.185708 -282.550331)
			(xy 436.177932 -282.531563) (xy 436.177436 -282.521406) (xy 430.1363 -282.521406) (xy 430.135772 -282.531559)
			(xy 430.128003 -282.550321) (xy 430.113648 -282.564685) (xy 430.094891 -282.572466) (xy 430.084738 -282.572968)
			(xy 428.685198 -282.572968) (xy 428.675041 -282.572468) (xy 428.656273 -282.564694) (xy 428.641908 -282.550331)
			(xy 428.634132 -282.531563) (xy 428.633636 -282.521406) (xy 422.5925 -282.521406) (xy 422.591972 -282.531559)
			(xy 422.584203 -282.550321) (xy 422.569848 -282.564685) (xy 422.551091 -282.572466) (xy 422.540938 -282.572968)
			(xy 421.141398 -282.572968) (xy 421.131241 -282.572468) (xy 421.112473 -282.564694) (xy 421.098108 -282.550331)
			(xy 421.090332 -282.531563) (xy 421.089836 -282.521406) (xy 415.0487 -282.521406) (xy 415.048172 -282.531559)
			(xy 415.040403 -282.550321) (xy 415.026048 -282.564685) (xy 415.007291 -282.572466) (xy 414.997138 -282.572968)
			(xy 413.597598 -282.572968) (xy 413.587441 -282.572468) (xy 413.568673 -282.564694) (xy 413.554308 -282.550331)
			(xy 413.546532 -282.531563) (xy 413.546036 -282.521406) (xy 407.5049 -282.521406) (xy 407.504372 -282.531559)
			(xy 407.496603 -282.550321) (xy 407.482248 -282.564685) (xy 407.463491 -282.572466) (xy 407.453338 -282.572968)
			(xy 406.053798 -282.572968) (xy 406.043641 -282.572468) (xy 406.024873 -282.564694) (xy 406.010508 -282.550331)
			(xy 406.002732 -282.531563) (xy 406.002236 -282.521406) (xy 354.829569 -282.521406) (xy 354.826094 -282.532101)
			(xy 354.802588 -282.578233) (xy 354.772156 -282.62012) (xy 354.735546 -282.65673) (xy 354.693659 -282.687162)
			(xy 354.647527 -282.710668) (xy 354.598287 -282.726667) (xy 354.547149 -282.734766) (xy 354.495375 -282.734766)
			(xy 354.444237 -282.726667) (xy 354.394997 -282.710668) (xy 354.348865 -282.687162) (xy 354.306978 -282.65673)
			(xy 354.270368 -282.62012) (xy 354.239936 -282.578233) (xy 354.21643 -282.532101) (xy 354.200431 -282.482861)
			(xy 354.192332 -282.431723) (xy 354.191824 -282.405836) (xy 354.192361 -282.378128) (xy 354.201551 -282.323481)
			(xy 354.210112 -282.297124) (xy 354.217986 -282.275026) (xy 354.013008 -281.920188) (xy 353.990148 -281.91587)
			(xy 353.965319 -281.910737) (xy 353.917537 -281.893779) (xy 353.872916 -281.869705) (xy 353.832509 -281.83908)
			(xy 353.797268 -281.802629) (xy 353.768025 -281.761211) (xy 353.74547 -281.715803) (xy 353.730136 -281.667476)
			(xy 353.722383 -281.617371) (xy 353.721924 -281.59202) (xy 352.501708 -281.59202) (xy 352.5012 -281.617927)
			(xy 352.493094 -281.669104) (xy 352.477082 -281.718383) (xy 352.453559 -281.76455) (xy 352.423103 -281.806469)
			(xy 352.386465 -281.843107) (xy 352.344546 -281.873563) (xy 352.298379 -281.897086) (xy 352.2491 -281.913098)
			(xy 352.197923 -281.921204) (xy 352.146109 -281.921204) (xy 352.094932 -281.913098) (xy 352.045653 -281.897086)
			(xy 351.999486 -281.873563) (xy 351.957567 -281.843107) (xy 351.920929 -281.806469) (xy 351.890473 -281.76455)
			(xy 351.86695 -281.718383) (xy 351.850938 -281.669104) (xy 351.842832 -281.617927) (xy 351.842324 -281.59202)
			(xy 351.842922 -281.564303) (xy 351.852242 -281.509656) (xy 351.860866 -281.483308) (xy 351.86874 -281.46121)
			(xy 351.663762 -281.106372) (xy 351.640902 -281.102054) (xy 351.616072 -281.096882) (xy 351.568266 -281.079946)
			(xy 351.523618 -281.055889) (xy 351.483181 -281.025278) (xy 351.447909 -280.988835) (xy 351.418634 -280.947421)
			(xy 351.396047 -280.902011) (xy 351.380681 -280.853678) (xy 351.372898 -280.803562) (xy 351.372424 -280.778204)
			(xy 349.2119 -280.778204) (xy 349.2119 -280.778712) (xy 349.21131 -280.806228) (xy 349.202124 -280.860489)
			(xy 349.193612 -280.886662) (xy 349.185992 -280.908506) (xy 349.391224 -281.263852) (xy 349.414084 -281.26817)
			(xy 349.438905 -281.273337) (xy 349.486682 -281.290294) (xy 349.531299 -281.314367) (xy 349.571704 -281.344988)
			(xy 349.606944 -281.381435) (xy 349.636188 -281.422848) (xy 349.658745 -281.46825) (xy 349.674085 -281.516571)
			(xy 349.681844 -281.566671) (xy 349.682308 -281.59202) (xy 349.6818 -281.617927) (xy 349.673694 -281.669104)
			(xy 349.657682 -281.718383) (xy 349.634159 -281.76455) (xy 349.603703 -281.806469) (xy 349.567065 -281.843107)
			(xy 349.525146 -281.873563) (xy 349.478979 -281.897086) (xy 349.4297 -281.913098) (xy 349.378523 -281.921204)
			(xy 349.326709 -281.921204) (xy 349.275532 -281.913098) (xy 349.226253 -281.897086) (xy 349.180086 -281.873563)
			(xy 349.138167 -281.843107) (xy 349.101529 -281.806469) (xy 349.071073 -281.76455) (xy 349.04755 -281.718383)
			(xy 349.031538 -281.669104) (xy 349.023432 -281.617927) (xy 349.022924 -281.59202) (xy 349.023522 -281.564303)
			(xy 349.032842 -281.509656) (xy 349.041466 -281.483308) (xy 349.04934 -281.46121) (xy 348.844362 -281.106372)
			(xy 348.821502 -281.102054) (xy 348.796672 -281.096882) (xy 348.748866 -281.079946) (xy 348.704218 -281.055889)
			(xy 348.663781 -281.025278) (xy 348.628509 -280.988835) (xy 348.599234 -280.947421) (xy 348.576647 -280.902011)
			(xy 348.561281 -280.853678) (xy 348.553498 -280.803562) (xy 348.553024 -280.778204) (xy 346.3925 -280.778204)
			(xy 346.392021 -280.803539) (xy 346.384268 -280.853611) (xy 346.368945 -280.901908) (xy 346.346413 -280.947292)
			(xy 346.317203 -280.988694) (xy 346.282002 -281.025139) (xy 346.241639 -281.055769) (xy 346.197065 -281.079864)
			(xy 346.14933 -281.096855) (xy 346.12453 -281.102054) (xy 346.10167 -281.106372) (xy 345.896692 -281.46121)
			(xy 345.904566 -281.483308) (xy 345.913205 -281.509652) (xy 345.922521 -281.564301) (xy 345.923108 -281.59202)
			(xy 345.9226 -281.617909) (xy 347.143809 -281.617909) (xy 347.143809 -281.566091) (xy 347.151916 -281.514912)
			(xy 347.167929 -281.465631) (xy 347.191454 -281.419462) (xy 347.221912 -281.377541) (xy 347.258553 -281.340902)
			(xy 347.300475 -281.310446) (xy 347.346646 -281.286923) (xy 347.395928 -281.270912) (xy 347.447107 -281.262808)
			(xy 347.473016 -281.262328) (xy 347.498529 -281.262786) (xy 347.548945 -281.27065) (xy 347.597547 -281.286187)
			(xy 347.643176 -281.309027) (xy 347.684741 -281.338624) (xy 347.721249 -281.374271) (xy 347.736922 -281.394408)
			(xy 348.14891 -281.394408) (xy 348.16458 -281.37427) (xy 348.20109 -281.338625) (xy 348.242656 -281.309032)
			(xy 348.288285 -281.286196) (xy 348.336888 -281.270663) (xy 348.387304 -281.262804) (xy 348.412816 -281.262328)
			(xy 348.438724 -281.262797) (xy 348.489902 -281.270905) (xy 348.539182 -281.286919) (xy 348.585349 -281.310445)
			(xy 348.627269 -281.340903) (xy 348.663907 -281.377543) (xy 348.694363 -281.419464) (xy 348.717887 -281.465633)
			(xy 348.733899 -281.514914) (xy 348.742004 -281.566092) (xy 348.742004 -281.617908) (xy 348.733899 -281.669086)
			(xy 348.717887 -281.718367) (xy 348.694363 -281.764536) (xy 348.663907 -281.806457) (xy 348.627269 -281.843097)
			(xy 348.585349 -281.873555) (xy 348.539182 -281.897081) (xy 348.489902 -281.913095) (xy 348.438724 -281.921203)
			(xy 348.412816 -281.921712) (xy 348.387305 -281.921215) (xy 348.336891 -281.913357) (xy 348.28829 -281.897827)
			(xy 348.242662 -281.874994) (xy 348.201096 -281.845405) (xy 348.164585 -281.809765) (xy 348.14891 -281.789632)
			(xy 347.736922 -281.789632) (xy 347.721245 -281.809764) (xy 347.684735 -281.845407) (xy 347.64317 -281.875)
			(xy 347.597542 -281.897836) (xy 347.548942 -281.913371) (xy 347.498528 -281.921234) (xy 347.473016 -281.921712)
			(xy 347.447107 -281.921192) (xy 347.395928 -281.913088) (xy 347.346646 -281.897077) (xy 347.300475 -281.873554)
			(xy 347.258553 -281.843098) (xy 347.221912 -281.806459) (xy 347.191454 -281.764538) (xy 347.167929 -281.718369)
			(xy 347.151916 -281.669088) (xy 347.143809 -281.617909) (xy 345.9226 -281.617909) (xy 345.9226 -281.617927)
			(xy 345.914494 -281.669104) (xy 345.898482 -281.718383) (xy 345.874959 -281.76455) (xy 345.844503 -281.806469)
			(xy 345.807865 -281.843107) (xy 345.765946 -281.873563) (xy 345.719779 -281.897086) (xy 345.6705 -281.913098)
			(xy 345.619323 -281.921204) (xy 345.567509 -281.921204) (xy 345.516332 -281.913098) (xy 345.467053 -281.897086)
			(xy 345.420886 -281.873563) (xy 345.378967 -281.843107) (xy 345.342329 -281.806469) (xy 345.311873 -281.76455)
			(xy 345.28835 -281.718383) (xy 345.272338 -281.669104) (xy 345.264232 -281.617927) (xy 345.263724 -281.59202)
			(xy 344.043508 -281.59202) (xy 344.043045 -281.617395) (xy 344.035274 -281.667545) (xy 344.019903 -281.71591)
			(xy 343.997297 -281.761346) (xy 343.967989 -281.802777) (xy 343.932674 -281.839223) (xy 343.892188 -281.869822)
			(xy 343.847487 -281.893849) (xy 343.79963 -281.910736) (xy 343.774776 -281.91587) (xy 343.751916 -281.920188)
			(xy 343.546938 -282.275026) (xy 343.554812 -282.297124) (xy 343.563378 -282.32348) (xy 343.572573 -282.378127)
			(xy 343.5731 -282.405836) (xy 343.854024 -282.405836) (xy 343.854532 -282.379949) (xy 343.862631 -282.328811)
			(xy 343.87863 -282.279571) (xy 343.902136 -282.233439) (xy 343.932568 -282.191552) (xy 343.969178 -282.154942)
			(xy 344.011065 -282.12451) (xy 344.057197 -282.101004) (xy 344.106437 -282.085005) (xy 344.157575 -282.076906)
			(xy 344.209349 -282.076906) (xy 344.260487 -282.085005) (xy 344.309727 -282.101004) (xy 344.355859 -282.12451)
			(xy 344.397746 -282.154942) (xy 344.434356 -282.191552) (xy 344.464788 -282.233439) (xy 344.488294 -282.279571)
			(xy 344.504293 -282.328811) (xy 344.512392 -282.379949) (xy 344.5129 -282.405836) (xy 344.5129 -282.406344)
			(xy 344.512364 -282.431703) (xy 344.794152 -282.431703) (xy 344.794152 -282.379897) (xy 344.802256 -282.32873)
			(xy 344.818263 -282.27946) (xy 344.841781 -282.2333) (xy 344.872229 -282.191388) (xy 344.908859 -282.154754)
			(xy 344.950768 -282.124301) (xy 344.996925 -282.100778) (xy 345.046193 -282.084765) (xy 345.097359 -282.076655)
			(xy 345.123262 -282.076144) (xy 345.148774 -282.076635) (xy 345.199188 -282.084491) (xy 345.247791 -282.100021)
			(xy 345.293419 -282.122855) (xy 345.334985 -282.152446) (xy 345.371495 -282.188089) (xy 345.387168 -282.208224)
			(xy 345.799156 -282.208224) (xy 345.814861 -282.188115) (xy 345.851364 -282.152468) (xy 345.892922 -282.122871)
			(xy 345.938545 -282.10003) (xy 345.987141 -282.084491) (xy 346.037552 -282.076624) (xy 346.063062 -282.076144)
			(xy 346.088976 -282.076551) (xy 346.140167 -282.084653) (xy 346.18946 -282.100664) (xy 346.235642 -282.12419)
			(xy 346.277574 -282.154651) (xy 346.314224 -282.191297) (xy 346.34469 -282.233226) (xy 346.368221 -282.279404)
			(xy 346.384238 -282.328696) (xy 346.392346 -282.379886) (xy 346.392346 -282.431714) (xy 346.384238 -282.482904)
			(xy 346.368221 -282.532196) (xy 346.34469 -282.578374) (xy 346.314224 -282.620303) (xy 346.277574 -282.656949)
			(xy 346.235642 -282.68741) (xy 346.18946 -282.710936) (xy 346.140167 -282.726947) (xy 346.088976 -282.735049)
			(xy 346.063062 -282.735528) (xy 346.03755 -282.735064) (xy 345.987135 -282.727199) (xy 345.938534 -282.711661)
			(xy 345.892906 -282.688822) (xy 345.85134 -282.659228) (xy 345.81483 -282.623584) (xy 345.799156 -282.603448)
			(xy 345.387168 -282.603448) (xy 345.371526 -282.623609) (xy 345.335009 -282.659249) (xy 345.293436 -282.688839)
			(xy 345.247802 -282.71167) (xy 345.199195 -282.727199) (xy 345.148776 -282.735054) (xy 345.123262 -282.735528)
			(xy 345.097359 -282.734945) (xy 345.046193 -282.726835) (xy 344.996925 -282.710822) (xy 344.950768 -282.687299)
			(xy 344.908859 -282.656846) (xy 344.872229 -282.620212) (xy 344.841781 -282.5783) (xy 344.818263 -282.53214)
			(xy 344.802256 -282.48287) (xy 344.794152 -282.431703) (xy 344.512364 -282.431703) (xy 344.512318 -282.43386)
			(xy 344.503126 -282.488122) (xy 344.494612 -282.514294) (xy 344.486992 -282.536392) (xy 344.692224 -282.891738)
			(xy 344.715084 -282.896056) (xy 344.739902 -282.901236) (xy 344.787678 -282.918192) (xy 344.832294 -282.942264)
			(xy 344.872699 -282.972884) (xy 344.907939 -283.009329) (xy 344.937183 -283.05074) (xy 344.959741 -283.09614)
			(xy 344.975082 -283.14446) (xy 344.982843 -283.194558) (xy 344.983308 -283.219906) (xy 347.143324 -283.219906)
			(xy 347.143831 -283.194562) (xy 347.151603 -283.144472) (xy 347.166948 -283.096161) (xy 347.189506 -283.050768)
			(xy 347.218745 -283.009362) (xy 347.253975 -282.972918) (xy 347.294368 -282.942295) (xy 347.338972 -282.918214)
			(xy 347.386736 -282.901243) (xy 347.411548 -282.896056) (xy 347.434408 -282.891738) (xy 347.639386 -282.5369)
			(xy 347.631766 -282.514802) (xy 347.623129 -282.488391) (xy 347.613803 -282.433617) (xy 347.613224 -282.405836)
			(xy 347.613732 -282.379949) (xy 347.621831 -282.328811) (xy 347.63783 -282.279571) (xy 347.661336 -282.233439)
			(xy 347.691768 -282.191552) (xy 347.728378 -282.154942) (xy 347.770265 -282.12451) (xy 347.816397 -282.101004)
			(xy 347.865637 -282.085005) (xy 347.916775 -282.076906) (xy 347.968549 -282.076906) (xy 348.019687 -282.085005)
			(xy 348.068927 -282.101004) (xy 348.115059 -282.12451) (xy 348.156946 -282.154942) (xy 348.193556 -282.191552)
			(xy 348.223988 -282.233439) (xy 348.247494 -282.279571) (xy 348.263493 -282.328811) (xy 348.271592 -282.379949)
			(xy 348.2721 -282.405836) (xy 349.492824 -282.405836) (xy 349.493229 -282.380499) (xy 349.500992 -282.330422)
			(xy 349.516324 -282.282122) (xy 349.538866 -282.236737) (xy 349.568085 -282.195335) (xy 349.603295 -282.15889)
			(xy 349.643666 -282.128262) (xy 349.688248 -282.10417) (xy 349.735991 -282.087183) (xy 349.760794 -282.081986)
			(xy 349.783654 -282.077668) (xy 349.988886 -281.722322) (xy 349.981266 -281.700478) (xy 349.97264 -281.674196)
			(xy 349.963326 -281.619675) (xy 349.962724 -281.59202) (xy 349.963232 -281.566113) (xy 349.971338 -281.514936)
			(xy 349.98735 -281.465657) (xy 350.010873 -281.41949) (xy 350.041329 -281.377571) (xy 350.077967 -281.340933)
			(xy 350.119886 -281.310477) (xy 350.166053 -281.286954) (xy 350.215332 -281.270942) (xy 350.266509 -281.262836)
			(xy 350.318323 -281.262836) (xy 350.3695 -281.270942) (xy 350.418779 -281.286954) (xy 350.464946 -281.310477)
			(xy 350.506865 -281.340933) (xy 350.543503 -281.377571) (xy 350.573959 -281.41949) (xy 350.597482 -281.465657)
			(xy 350.613494 -281.514936) (xy 350.6216 -281.566113) (xy 350.622108 -281.59202) (xy 350.621645 -281.617395)
			(xy 350.613874 -281.667545) (xy 350.598503 -281.71591) (xy 350.575897 -281.761346) (xy 350.546589 -281.802777)
			(xy 350.511274 -281.839223) (xy 350.470788 -281.869822) (xy 350.426087 -281.893849) (xy 350.37823 -281.910736)
			(xy 350.353376 -281.91587) (xy 350.330516 -281.920188) (xy 350.125538 -282.275026) (xy 350.133412 -282.297124)
			(xy 350.141978 -282.32348) (xy 350.151173 -282.378127) (xy 350.1517 -282.405836) (xy 350.151192 -282.431703)
			(xy 351.372752 -282.431703) (xy 351.372752 -282.379897) (xy 351.380856 -282.32873) (xy 351.396863 -282.27946)
			(xy 351.420381 -282.2333) (xy 351.450829 -282.191388) (xy 351.487459 -282.154754) (xy 351.529368 -282.124301)
			(xy 351.575525 -282.100778) (xy 351.624793 -282.084765) (xy 351.675959 -282.076655) (xy 351.701862 -282.076144)
			(xy 351.727374 -282.076635) (xy 351.777788 -282.084491) (xy 351.826391 -282.100021) (xy 351.872019 -282.122855)
			(xy 351.913585 -282.152446) (xy 351.950095 -282.188089) (xy 351.965768 -282.208224) (xy 352.377756 -282.208224)
			(xy 352.393461 -282.188115) (xy 352.429964 -282.152468) (xy 352.471522 -282.122871) (xy 352.517145 -282.10003)
			(xy 352.565741 -282.084491) (xy 352.616152 -282.076624) (xy 352.641662 -282.076144) (xy 352.667576 -282.076551)
			(xy 352.718767 -282.084653) (xy 352.76806 -282.100664) (xy 352.814242 -282.12419) (xy 352.856174 -282.154651)
			(xy 352.892824 -282.191297) (xy 352.92329 -282.233226) (xy 352.946821 -282.279404) (xy 352.962838 -282.328696)
			(xy 352.970946 -282.379886) (xy 352.970946 -282.431714) (xy 352.962838 -282.482904) (xy 352.946821 -282.532196)
			(xy 352.92329 -282.578374) (xy 352.892824 -282.620303) (xy 352.856174 -282.656949) (xy 352.814242 -282.68741)
			(xy 352.76806 -282.710936) (xy 352.718767 -282.726947) (xy 352.667576 -282.735049) (xy 352.641662 -282.735528)
			(xy 352.61615 -282.735064) (xy 352.565735 -282.727199) (xy 352.517134 -282.711661) (xy 352.471506 -282.688822)
			(xy 352.42994 -282.659228) (xy 352.39343 -282.623584) (xy 352.377756 -282.603448) (xy 351.965768 -282.603448)
			(xy 351.950126 -282.623609) (xy 351.913609 -282.659249) (xy 351.872036 -282.688839) (xy 351.826402 -282.71167)
			(xy 351.777795 -282.727199) (xy 351.727376 -282.735054) (xy 351.701862 -282.735528) (xy 351.675959 -282.734945)
			(xy 351.624793 -282.726835) (xy 351.575525 -282.710822) (xy 351.529368 -282.687299) (xy 351.487459 -282.656846)
			(xy 351.450829 -282.620212) (xy 351.420381 -282.5783) (xy 351.396863 -282.53214) (xy 351.380856 -282.48287)
			(xy 351.372752 -282.431703) (xy 350.151192 -282.431703) (xy 350.151192 -282.431723) (xy 350.143093 -282.482861)
			(xy 350.127094 -282.532101) (xy 350.103588 -282.578233) (xy 350.073156 -282.62012) (xy 350.036546 -282.65673)
			(xy 349.994659 -282.687162) (xy 349.948527 -282.710668) (xy 349.899287 -282.726667) (xy 349.848149 -282.734766)
			(xy 349.796375 -282.734766) (xy 349.745237 -282.726667) (xy 349.695997 -282.710668) (xy 349.649865 -282.687162)
			(xy 349.607978 -282.65673) (xy 349.571368 -282.62012) (xy 349.540936 -282.578233) (xy 349.51743 -282.532101)
			(xy 349.501431 -282.482861) (xy 349.493332 -282.431723) (xy 349.492824 -282.405836) (xy 348.2721 -282.405836)
			(xy 348.271608 -282.431158) (xy 348.263872 -282.481209) (xy 348.248573 -282.529487) (xy 348.22607 -282.574858)
			(xy 348.196893 -282.616254) (xy 348.161729 -282.6527) (xy 348.121404 -282.68334) (xy 348.076868 -282.707453)
			(xy 348.029168 -282.72447) (xy 348.004384 -282.729686) (xy 347.981524 -282.734004) (xy 347.776292 -283.089096)
			(xy 347.784166 -283.111194) (xy 347.792802 -283.137539) (xy 347.80212 -283.192188) (xy 347.802708 -283.219906)
			(xy 347.8022 -283.24579) (xy 349.023649 -283.24579) (xy 349.023649 -283.19401) (xy 349.03175 -283.142868)
			(xy 349.047751 -283.093623) (xy 349.071259 -283.047487) (xy 349.101695 -283.005597) (xy 349.13831 -282.968985)
			(xy 349.180201 -282.938551) (xy 349.226338 -282.915045) (xy 349.275584 -282.899046) (xy 349.326726 -282.890948)
			(xy 349.352616 -282.890468) (xy 349.378128 -282.890949) (xy 349.428541 -282.898811) (xy 349.477143 -282.914346)
			(xy 349.522771 -282.937181) (xy 349.564336 -282.966773) (xy 349.600848 -283.002414) (xy 349.616522 -283.022548)
			(xy 350.02851 -283.022548) (xy 350.044163 -283.002397) (xy 350.080679 -282.966756) (xy 350.122249 -282.937166)
			(xy 350.167881 -282.914333) (xy 350.216486 -282.898802) (xy 350.266903 -282.890944) (xy 350.292416 -282.890468)
			(xy 350.318303 -282.890965) (xy 350.369439 -282.899066) (xy 350.418679 -282.915067) (xy 350.464809 -282.938574)
			(xy 350.506694 -282.969007) (xy 350.543303 -283.005618) (xy 350.573735 -283.047505) (xy 350.597239 -283.093636)
			(xy 350.613237 -283.142876) (xy 350.621336 -283.194013) (xy 350.621336 -283.219906) (xy 352.782124 -283.219906)
			(xy 352.782631 -283.194562) (xy 352.790403 -283.144472) (xy 352.805748 -283.096161) (xy 352.828306 -283.050768)
			(xy 352.857545 -283.009362) (xy 352.892775 -282.972918) (xy 352.933168 -282.942295) (xy 352.977772 -282.918214)
			(xy 353.025536 -282.901243) (xy 353.050348 -282.896056) (xy 353.073208 -282.891738) (xy 353.278186 -282.5369)
			(xy 353.270566 -282.514802) (xy 353.261929 -282.488391) (xy 353.252603 -282.433617) (xy 353.252024 -282.405836)
			(xy 353.252532 -282.379949) (xy 353.260631 -282.328811) (xy 353.27663 -282.279571) (xy 353.300136 -282.233439)
			(xy 353.330568 -282.191552) (xy 353.367178 -282.154942) (xy 353.409065 -282.12451) (xy 353.455197 -282.101004)
			(xy 353.504437 -282.085005) (xy 353.555575 -282.076906) (xy 353.607349 -282.076906) (xy 353.658487 -282.085005)
			(xy 353.707727 -282.101004) (xy 353.753859 -282.12451) (xy 353.795746 -282.154942) (xy 353.832356 -282.191552)
			(xy 353.862788 -282.233439) (xy 353.886294 -282.279571) (xy 353.902293 -282.328811) (xy 353.910392 -282.379949)
			(xy 353.9109 -282.405836) (xy 353.910408 -282.431158) (xy 353.902672 -282.481209) (xy 353.887373 -282.529487)
			(xy 353.86487 -282.574858) (xy 353.835693 -282.616254) (xy 353.800529 -282.6527) (xy 353.760204 -282.68334)
			(xy 353.715668 -282.707453) (xy 353.667968 -282.72447) (xy 353.643184 -282.729686) (xy 353.620324 -282.734004)
			(xy 353.415092 -283.089096) (xy 353.422966 -283.111194) (xy 353.431602 -283.137539) (xy 353.44092 -283.192188)
			(xy 353.441508 -283.219906) (xy 353.441 -283.245813) (xy 353.432894 -283.29699) (xy 353.416882 -283.346269)
			(xy 353.404004 -283.371544) (xy 410.102304 -283.371544) (xy 410.102304 -282.962604) (xy 410.102725 -282.95245)
			(xy 410.11052 -282.933697) (xy 410.124917 -282.919373) (xy 410.14371 -282.911674) (xy 410.153866 -282.911296)
			(xy 411.553406 -282.911296) (xy 411.563528 -282.91182) (xy 411.582241 -282.919542) (xy 411.596595 -282.933816)
			(xy 411.604422 -282.952485) (xy 411.604968 -282.962604) (xy 411.604968 -283.371544) (xy 417.646104 -283.371544)
			(xy 417.646104 -282.962604) (xy 417.646525 -282.95245) (xy 417.65432 -282.933697) (xy 417.668717 -282.919373)
			(xy 417.68751 -282.911674) (xy 417.697666 -282.911296) (xy 419.097206 -282.911296) (xy 419.107328 -282.91182)
			(xy 419.126041 -282.919542) (xy 419.140395 -282.933816) (xy 419.148222 -282.952485) (xy 419.148768 -282.962604)
			(xy 419.148768 -283.371544) (xy 425.189904 -283.371544) (xy 425.189904 -282.962604) (xy 425.190325 -282.95245)
			(xy 425.19812 -282.933697) (xy 425.212517 -282.919373) (xy 425.23131 -282.911674) (xy 425.241466 -282.911296)
			(xy 426.641006 -282.911296) (xy 426.651128 -282.91182) (xy 426.669841 -282.919542) (xy 426.684195 -282.933816)
			(xy 426.692022 -282.952485) (xy 426.692568 -282.962604) (xy 426.692568 -283.371544) (xy 432.733704 -283.371544)
			(xy 432.733704 -282.962604) (xy 432.734125 -282.95245) (xy 432.74192 -282.933697) (xy 432.756317 -282.919373)
			(xy 432.77511 -282.911674) (xy 432.785266 -282.911296) (xy 434.184806 -282.911296) (xy 434.194928 -282.91182)
			(xy 434.213641 -282.919542) (xy 434.227995 -282.933816) (xy 434.235822 -282.952485) (xy 434.236368 -282.962604)
			(xy 434.236368 -283.371544) (xy 440.277504 -283.371544) (xy 440.277504 -282.962604) (xy 440.277925 -282.95245)
			(xy 440.28572 -282.933697) (xy 440.300117 -282.919373) (xy 440.31891 -282.911674) (xy 440.329066 -282.911296)
			(xy 441.728606 -282.911296) (xy 441.738728 -282.91182) (xy 441.757441 -282.919542) (xy 441.771795 -282.933816)
			(xy 441.779622 -282.952485) (xy 441.780168 -282.962604) (xy 441.780168 -283.371544) (xy 447.821304 -283.371544)
			(xy 447.821304 -282.962604) (xy 447.821725 -282.95245) (xy 447.82952 -282.933697) (xy 447.843917 -282.919373)
			(xy 447.86271 -282.911674) (xy 447.872866 -282.911296) (xy 449.272406 -282.911296) (xy 449.282528 -282.91182)
			(xy 449.301241 -282.919542) (xy 449.315595 -282.933816) (xy 449.323422 -282.952485) (xy 449.323968 -282.962604)
			(xy 449.323968 -283.371544) (xy 455.365104 -283.371544) (xy 455.365104 -282.962604) (xy 455.365525 -282.95245)
			(xy 455.37332 -282.933697) (xy 455.387717 -282.919373) (xy 455.40651 -282.911674) (xy 455.416666 -282.911296)
			(xy 456.816206 -282.911296) (xy 456.826328 -282.91182) (xy 456.845041 -282.919542) (xy 456.859395 -282.933816)
			(xy 456.867222 -282.952485) (xy 456.867768 -282.962604) (xy 456.867768 -283.371544) (xy 462.908904 -283.371544)
			(xy 462.908904 -282.962604) (xy 462.909325 -282.95245) (xy 462.91712 -282.933697) (xy 462.931517 -282.919373)
			(xy 462.95031 -282.911674) (xy 462.960466 -282.911296) (xy 464.360006 -282.911296) (xy 464.370128 -282.91182)
			(xy 464.388841 -282.919542) (xy 464.403195 -282.933816) (xy 464.411022 -282.952485) (xy 464.411568 -282.962604)
			(xy 464.411568 -283.371544) (xy 464.411214 -283.381705) (xy 464.403398 -283.400464) (xy 464.38898 -283.414787)
			(xy 464.37017 -283.42248) (xy 464.360006 -283.422852) (xy 462.960466 -283.422852) (xy 462.950336 -283.422401)
			(xy 462.931613 -283.414661) (xy 462.917257 -283.400364) (xy 462.909441 -283.381672) (xy 462.908904 -283.371544)
			(xy 456.867768 -283.371544) (xy 456.867414 -283.381705) (xy 456.859598 -283.400464) (xy 456.84518 -283.414787)
			(xy 456.82637 -283.42248) (xy 456.816206 -283.422852) (xy 455.416666 -283.422852) (xy 455.406536 -283.422401)
			(xy 455.387813 -283.414661) (xy 455.373457 -283.400364) (xy 455.365641 -283.381672) (xy 455.365104 -283.371544)
			(xy 449.323968 -283.371544) (xy 449.323614 -283.381705) (xy 449.315798 -283.400464) (xy 449.30138 -283.414787)
			(xy 449.28257 -283.42248) (xy 449.272406 -283.422852) (xy 447.872866 -283.422852) (xy 447.862736 -283.422401)
			(xy 447.844013 -283.414661) (xy 447.829657 -283.400364) (xy 447.821841 -283.381672) (xy 447.821304 -283.371544)
			(xy 441.780168 -283.371544) (xy 441.779814 -283.381705) (xy 441.771998 -283.400464) (xy 441.75758 -283.414787)
			(xy 441.73877 -283.42248) (xy 441.728606 -283.422852) (xy 440.329066 -283.422852) (xy 440.318936 -283.422401)
			(xy 440.300213 -283.414661) (xy 440.285857 -283.400364) (xy 440.278041 -283.381672) (xy 440.277504 -283.371544)
			(xy 434.236368 -283.371544) (xy 434.236014 -283.381705) (xy 434.228198 -283.400464) (xy 434.21378 -283.414787)
			(xy 434.19497 -283.42248) (xy 434.184806 -283.422852) (xy 432.785266 -283.422852) (xy 432.775136 -283.422401)
			(xy 432.756413 -283.414661) (xy 432.742057 -283.400364) (xy 432.734241 -283.381672) (xy 432.733704 -283.371544)
			(xy 426.692568 -283.371544) (xy 426.692214 -283.381705) (xy 426.684398 -283.400464) (xy 426.66998 -283.414787)
			(xy 426.65117 -283.42248) (xy 426.641006 -283.422852) (xy 425.241466 -283.422852) (xy 425.231336 -283.422401)
			(xy 425.212613 -283.414661) (xy 425.198257 -283.400364) (xy 425.190441 -283.381672) (xy 425.189904 -283.371544)
			(xy 419.148768 -283.371544) (xy 419.148414 -283.381705) (xy 419.140598 -283.400464) (xy 419.12618 -283.414787)
			(xy 419.10737 -283.42248) (xy 419.097206 -283.422852) (xy 417.697666 -283.422852) (xy 417.687536 -283.422401)
			(xy 417.668813 -283.414661) (xy 417.654457 -283.400364) (xy 417.646641 -283.381672) (xy 417.646104 -283.371544)
			(xy 411.604968 -283.371544) (xy 411.604614 -283.381705) (xy 411.596798 -283.400464) (xy 411.58238 -283.414787)
			(xy 411.56357 -283.42248) (xy 411.553406 -283.422852) (xy 410.153866 -283.422852) (xy 410.143736 -283.422401)
			(xy 410.125013 -283.414661) (xy 410.110657 -283.400364) (xy 410.102841 -283.381672) (xy 410.102304 -283.371544)
			(xy 353.404004 -283.371544) (xy 353.393359 -283.392436) (xy 353.362903 -283.434355) (xy 353.326265 -283.470993)
			(xy 353.284346 -283.501449) (xy 353.238179 -283.524972) (xy 353.1889 -283.540984) (xy 353.137723 -283.54909)
			(xy 353.085909 -283.54909) (xy 353.034732 -283.540984) (xy 352.985453 -283.524972) (xy 352.939286 -283.501449)
			(xy 352.897367 -283.470993) (xy 352.860729 -283.434355) (xy 352.830273 -283.392436) (xy 352.80675 -283.346269)
			(xy 352.790738 -283.29699) (xy 352.782632 -283.245813) (xy 352.782124 -283.219906) (xy 350.621336 -283.219906)
			(xy 350.621336 -283.245787) (xy 350.613237 -283.296924) (xy 350.597239 -283.346164) (xy 350.573735 -283.392295)
			(xy 350.543303 -283.434182) (xy 350.506694 -283.470793) (xy 350.464809 -283.501226) (xy 350.418679 -283.524733)
			(xy 350.369439 -283.540734) (xy 350.318303 -283.548835) (xy 350.292416 -283.549344) (xy 350.266904 -283.548874)
			(xy 350.216488 -283.541014) (xy 350.167885 -283.52548) (xy 350.122256 -283.502643) (xy 350.080691 -283.473047)
			(xy 350.044182 -283.437401) (xy 350.02851 -283.417264) (xy 349.616522 -283.417264) (xy 349.600826 -283.437381)
			(xy 349.564322 -283.473028) (xy 349.522762 -283.502625) (xy 349.477138 -283.525464) (xy 349.428539 -283.541001)
			(xy 349.378127 -283.548865) (xy 349.352616 -283.549344) (xy 349.326726 -283.548852) (xy 349.275584 -283.540754)
			(xy 349.226338 -283.524755) (xy 349.180201 -283.501249) (xy 349.13831 -283.470815) (xy 349.101695 -283.434203)
			(xy 349.071259 -283.392313) (xy 349.047751 -283.346177) (xy 349.03175 -283.296932) (xy 349.023649 -283.24579)
			(xy 347.8022 -283.24579) (xy 347.8022 -283.245813) (xy 347.794094 -283.29699) (xy 347.778082 -283.346269)
			(xy 347.754559 -283.392436) (xy 347.724103 -283.434355) (xy 347.687465 -283.470993) (xy 347.645546 -283.501449)
			(xy 347.599379 -283.524972) (xy 347.5501 -283.540984) (xy 347.498923 -283.54909) (xy 347.447109 -283.54909)
			(xy 347.395932 -283.540984) (xy 347.346653 -283.524972) (xy 347.300486 -283.501449) (xy 347.258567 -283.470993)
			(xy 347.221929 -283.434355) (xy 347.191473 -283.392436) (xy 347.16795 -283.346269) (xy 347.151938 -283.29699)
			(xy 347.143832 -283.245813) (xy 347.143324 -283.219906) (xy 344.983308 -283.219906) (xy 344.9828 -283.245813)
			(xy 344.974694 -283.29699) (xy 344.958682 -283.346269) (xy 344.935159 -283.392436) (xy 344.904703 -283.434355)
			(xy 344.868065 -283.470993) (xy 344.826146 -283.501449) (xy 344.779979 -283.524972) (xy 344.7307 -283.540984)
			(xy 344.679523 -283.54909) (xy 344.627709 -283.54909) (xy 344.576532 -283.540984) (xy 344.527253 -283.524972)
			(xy 344.481086 -283.501449) (xy 344.439167 -283.470993) (xy 344.402529 -283.434355) (xy 344.372073 -283.392436)
			(xy 344.34855 -283.346269) (xy 344.332538 -283.29699) (xy 344.324432 -283.245813) (xy 344.323924 -283.219906)
			(xy 344.324518 -283.192189) (xy 344.333841 -283.137542) (xy 344.342466 -283.111194) (xy 344.35034 -283.089096)
			(xy 344.145362 -282.734004) (xy 344.122248 -282.729686) (xy 344.097423 -282.724538) (xy 344.049642 -282.707582)
			(xy 344.005022 -282.683508) (xy 343.964615 -282.652886) (xy 343.929374 -282.616436) (xy 343.900131 -282.57502)
			(xy 343.877575 -282.529614) (xy 343.862239 -282.481289) (xy 343.854484 -282.431186) (xy 343.854024 -282.405836)
			(xy 343.5731 -282.405836) (xy 343.572592 -282.431723) (xy 343.564493 -282.482861) (xy 343.548494 -282.532101)
			(xy 343.524988 -282.578233) (xy 343.494556 -282.62012) (xy 343.457946 -282.65673) (xy 343.416059 -282.687162)
			(xy 343.369927 -282.710668) (xy 343.320687 -282.726667) (xy 343.269549 -282.734766) (xy 343.217775 -282.734766)
			(xy 343.166637 -282.726667) (xy 343.117397 -282.710668) (xy 343.071265 -282.687162) (xy 343.029378 -282.65673)
			(xy 342.992768 -282.62012) (xy 342.962336 -282.578233) (xy 342.93883 -282.532101) (xy 342.922831 -282.482861)
			(xy 342.914732 -282.431723) (xy 342.914224 -282.405836) (xy 341.694008 -282.405836) (xy 341.6935 -282.431743)
			(xy 341.685394 -282.48292) (xy 341.669382 -282.532199) (xy 341.645859 -282.578366) (xy 341.615403 -282.620285)
			(xy 341.578765 -282.656923) (xy 341.536846 -282.687379) (xy 341.490679 -282.710902) (xy 341.4414 -282.726914)
			(xy 341.390223 -282.73502) (xy 341.338409 -282.73502) (xy 341.287232 -282.726914) (xy 341.237953 -282.710902)
			(xy 341.191786 -282.687379) (xy 341.149867 -282.656923) (xy 341.113229 -282.620285) (xy 341.082773 -282.578366)
			(xy 341.05925 -282.532199) (xy 341.043238 -282.48292) (xy 341.035132 -282.431743) (xy 341.034624 -282.405836)
			(xy 339.814408 -282.405836) (xy 339.813997 -282.431202) (xy 339.806243 -282.481337) (xy 339.790893 -282.52969)
			(xy 339.768309 -282.575118) (xy 339.739027 -282.616545) (xy 339.703739 -282.652993) (xy 339.663279 -282.683598)
			(xy 339.618605 -282.707637) (xy 339.570773 -282.724541) (xy 339.54593 -282.729686) (xy 339.52307 -282.734004)
			(xy 339.318092 -283.089096) (xy 339.325712 -283.11094) (xy 339.33426 -283.137236) (xy 339.343458 -283.191753)
			(xy 339.344 -283.219398) (xy 339.344 -283.219906) (xy 339.343492 -283.245785) (xy 340.565275 -283.245785)
			(xy 340.565275 -283.194015) (xy 340.573373 -283.142882) (xy 340.58937 -283.093646) (xy 340.612872 -283.047517)
			(xy 340.643299 -283.005633) (xy 340.679904 -282.969024) (xy 340.721785 -282.938592) (xy 340.76791 -282.915085)
			(xy 340.817145 -282.899082) (xy 340.868277 -282.890978) (xy 340.894162 -282.890468) (xy 340.919672 -282.890989)
			(xy 340.970084 -282.898843) (xy 341.018684 -282.914369) (xy 341.064312 -282.937197) (xy 341.105879 -282.966782)
			(xy 341.142392 -283.002417) (xy 341.158068 -283.022548) (xy 341.570056 -283.022548) (xy 341.585741 -283.002422)
			(xy 341.62225 -282.96678) (xy 341.663813 -282.937187) (xy 341.709439 -282.91435) (xy 341.758039 -282.898813)
			(xy 341.808451 -282.890948) (xy 341.833962 -282.890468) (xy 341.859854 -282.890934) (xy 341.911001 -282.89903)
			(xy 341.960252 -282.915027) (xy 342.006393 -282.938533) (xy 342.048289 -282.968968) (xy 342.084908 -283.005582)
			(xy 342.115347 -283.047475) (xy 342.138858 -283.093613) (xy 342.154861 -283.142862) (xy 342.162963 -283.194008)
			(xy 342.162963 -283.245792) (xy 342.154861 -283.296938) (xy 342.138858 -283.346187) (xy 342.115347 -283.392325)
			(xy 342.084908 -283.434218) (xy 342.048289 -283.470832) (xy 342.006393 -283.501267) (xy 341.960252 -283.524773)
			(xy 341.911001 -283.54077) (xy 341.859854 -283.548866) (xy 341.833962 -283.549344) (xy 341.808448 -283.548913)
			(xy 341.75803 -283.541045) (xy 341.709427 -283.525503) (xy 341.663798 -283.502658) (xy 341.622234 -283.473056)
			(xy 341.585727 -283.437404) (xy 341.570056 -283.417264) (xy 341.158068 -283.417264) (xy 341.142404 -283.437407)
			(xy 341.105893 -283.473052) (xy 341.064326 -283.502646) (xy 341.018696 -283.525481) (xy 340.970092 -283.541013)
			(xy 340.919675 -283.548869) (xy 340.894162 -283.549344) (xy 340.868277 -283.548822) (xy 340.817145 -283.540718)
			(xy 340.76791 -283.524715) (xy 340.721785 -283.501208) (xy 340.679904 -283.470776) (xy 340.643299 -283.434167)
			(xy 340.612872 -283.392283) (xy 340.58937 -283.346154) (xy 340.573373 -283.296918) (xy 340.565275 -283.245785)
			(xy 339.343492 -283.245785) (xy 339.343492 -283.245793) (xy 339.335393 -283.296931) (xy 339.319394 -283.346171)
			(xy 339.295888 -283.392303) (xy 339.265456 -283.43419) (xy 339.228846 -283.4708) (xy 339.186959 -283.501232)
			(xy 339.140827 -283.524738) (xy 339.091587 -283.540737) (xy 339.040449 -283.548836) (xy 338.988675 -283.548836)
			(xy 338.937537 -283.540737) (xy 338.888297 -283.524738) (xy 338.842165 -283.501232) (xy 338.800278 -283.4708)
			(xy 338.763668 -283.43419) (xy 338.733236 -283.392303) (xy 338.70973 -283.346171) (xy 338.693731 -283.296931)
			(xy 338.685632 -283.245793) (xy 338.685124 -283.219906) (xy 336.5246 -283.219906) (xy 336.524092 -283.245793)
			(xy 336.515993 -283.296931) (xy 336.499994 -283.346171) (xy 336.476488 -283.392303) (xy 336.446056 -283.43419)
			(xy 336.409446 -283.4708) (xy 336.367559 -283.501232) (xy 336.321427 -283.524738) (xy 336.272187 -283.540737)
			(xy 336.221049 -283.548836) (xy 336.169275 -283.548836) (xy 336.118137 -283.540737) (xy 336.068897 -283.524738)
			(xy 336.022765 -283.501232) (xy 335.980878 -283.4708) (xy 335.944268 -283.43419) (xy 335.913836 -283.392303)
			(xy 335.89033 -283.346171) (xy 335.874331 -283.296931) (xy 335.866232 -283.245793) (xy 335.865724 -283.219906)
			(xy 335.866254 -283.192198) (xy 335.875449 -283.137551) (xy 335.884012 -283.111194) (xy 335.891886 -283.089096)
			(xy 335.686654 -282.734004) (xy 335.663794 -282.729686) (xy 335.639001 -282.724454) (xy 335.591266 -282.707468)
			(xy 335.546691 -282.683379) (xy 335.506327 -282.652753) (xy 335.471124 -282.616312) (xy 335.441911 -282.574914)
			(xy 335.419375 -282.529534) (xy 335.404048 -282.48124) (xy 335.396291 -282.43117) (xy 335.395824 -282.405836)
			(xy 309.6387 -282.405836) (xy 309.6387 -282.521406) (xy 309.638172 -282.531559) (xy 309.630403 -282.550321)
			(xy 309.616048 -282.564685) (xy 309.597291 -282.572466) (xy 309.587138 -282.572968) (xy 308.187598 -282.572968)
			(xy 308.177441 -282.572468) (xy 308.158673 -282.564694) (xy 308.144308 -282.550331) (xy 308.136532 -282.531563)
			(xy 308.136036 -282.521406) (xy 302.0949 -282.521406) (xy 302.094372 -282.531559) (xy 302.086603 -282.550321)
			(xy 302.072248 -282.564685) (xy 302.053491 -282.572466) (xy 302.043338 -282.572968) (xy 300.643798 -282.572968)
			(xy 300.633641 -282.572468) (xy 300.614873 -282.564694) (xy 300.600508 -282.550331) (xy 300.592732 -282.531563)
			(xy 300.592236 -282.521406) (xy 294.5511 -282.521406) (xy 294.550572 -282.531559) (xy 294.542803 -282.550321)
			(xy 294.528448 -282.564685) (xy 294.509691 -282.572466) (xy 294.499538 -282.572968) (xy 293.099998 -282.572968)
			(xy 293.089841 -282.572468) (xy 293.071073 -282.564694) (xy 293.056708 -282.550331) (xy 293.048932 -282.531563)
			(xy 293.048436 -282.521406) (xy 287.0073 -282.521406) (xy 287.006772 -282.531559) (xy 286.999003 -282.550321)
			(xy 286.984648 -282.564685) (xy 286.965891 -282.572466) (xy 286.955738 -282.572968) (xy 285.556198 -282.572968)
			(xy 285.546041 -282.572468) (xy 285.527273 -282.564694) (xy 285.512908 -282.550331) (xy 285.505132 -282.531563)
			(xy 285.504636 -282.521406) (xy 279.4635 -282.521406) (xy 279.462972 -282.531559) (xy 279.455203 -282.550321)
			(xy 279.440848 -282.564685) (xy 279.422091 -282.572466) (xy 279.411938 -282.572968) (xy 278.012398 -282.572968)
			(xy 278.002241 -282.572468) (xy 277.983473 -282.564694) (xy 277.969108 -282.550331) (xy 277.961332 -282.531563)
			(xy 277.960836 -282.521406) (xy 271.9197 -282.521406) (xy 271.919172 -282.531559) (xy 271.911403 -282.550321)
			(xy 271.897048 -282.564685) (xy 271.878291 -282.572466) (xy 271.868138 -282.572968) (xy 270.468598 -282.572968)
			(xy 270.458441 -282.572468) (xy 270.439673 -282.564694) (xy 270.425308 -282.550331) (xy 270.417532 -282.531563)
			(xy 270.417036 -282.521406) (xy 264.3759 -282.521406) (xy 264.375372 -282.531559) (xy 264.367603 -282.550321)
			(xy 264.353248 -282.564685) (xy 264.334491 -282.572466) (xy 264.324338 -282.572968) (xy 262.924798 -282.572968)
			(xy 262.914641 -282.572468) (xy 262.895873 -282.564694) (xy 262.881508 -282.550331) (xy 262.873732 -282.531563)
			(xy 262.873236 -282.521406) (xy 256.8321 -282.521406) (xy 256.831572 -282.531559) (xy 256.823803 -282.550321)
			(xy 256.809448 -282.564685) (xy 256.790691 -282.572466) (xy 256.780538 -282.572968) (xy 255.380998 -282.572968)
			(xy 255.370841 -282.572468) (xy 255.352073 -282.564694) (xy 255.337708 -282.550331) (xy 255.329932 -282.531563)
			(xy 255.329436 -282.521406) (xy 212.371432 -282.521406) (xy 212.37104 -282.531582) (xy 212.363248 -282.550382)
			(xy 212.348852 -282.564768) (xy 212.330046 -282.572547) (xy 212.31987 -282.572968) (xy 210.92033 -282.572968)
			(xy 210.910161 -282.572512) (xy 210.891368 -282.564738) (xy 210.876983 -282.550362) (xy 210.869196 -282.531575)
			(xy 210.868768 -282.521406) (xy 204.827632 -282.521406) (xy 204.82724 -282.531582) (xy 204.819448 -282.550382)
			(xy 204.805052 -282.564768) (xy 204.786246 -282.572547) (xy 204.77607 -282.572968) (xy 203.37653 -282.572968)
			(xy 203.366361 -282.572512) (xy 203.347568 -282.564738) (xy 203.333183 -282.550362) (xy 203.325396 -282.531575)
			(xy 203.324968 -282.521406) (xy 197.283832 -282.521406) (xy 197.28344 -282.531582) (xy 197.275648 -282.550382)
			(xy 197.261252 -282.564768) (xy 197.242446 -282.572547) (xy 197.23227 -282.572968) (xy 195.83273 -282.572968)
			(xy 195.822561 -282.572512) (xy 195.803768 -282.564738) (xy 195.789383 -282.550362) (xy 195.781596 -282.531575)
			(xy 195.781168 -282.521406) (xy 189.740032 -282.521406) (xy 189.73964 -282.531582) (xy 189.731848 -282.550382)
			(xy 189.717452 -282.564768) (xy 189.698646 -282.572547) (xy 189.68847 -282.572968) (xy 188.28893 -282.572968)
			(xy 188.278761 -282.572512) (xy 188.259968 -282.564738) (xy 188.245583 -282.550362) (xy 188.237796 -282.531575)
			(xy 188.237368 -282.521406) (xy 182.196232 -282.521406) (xy 182.19584 -282.531582) (xy 182.188048 -282.550382)
			(xy 182.173652 -282.564768) (xy 182.154846 -282.572547) (xy 182.14467 -282.572968) (xy 180.74513 -282.572968)
			(xy 180.734961 -282.572512) (xy 180.716168 -282.564738) (xy 180.701783 -282.550362) (xy 180.693996 -282.531575)
			(xy 180.693568 -282.521406) (xy 174.652432 -282.521406) (xy 174.65204 -282.531582) (xy 174.644248 -282.550382)
			(xy 174.629852 -282.564768) (xy 174.611046 -282.572547) (xy 174.60087 -282.572968) (xy 173.20133 -282.572968)
			(xy 173.191161 -282.572512) (xy 173.172368 -282.564738) (xy 173.157983 -282.550362) (xy 173.150196 -282.531575)
			(xy 173.149768 -282.521406) (xy 167.108632 -282.521406) (xy 167.10824 -282.531582) (xy 167.100448 -282.550382)
			(xy 167.086052 -282.564768) (xy 167.067246 -282.572547) (xy 167.05707 -282.572968) (xy 165.65753 -282.572968)
			(xy 165.647361 -282.572512) (xy 165.628568 -282.564738) (xy 165.614183 -282.550362) (xy 165.606396 -282.531575)
			(xy 165.605968 -282.521406) (xy 159.564832 -282.521406) (xy 159.56444 -282.531582) (xy 159.556648 -282.550382)
			(xy 159.542252 -282.564768) (xy 159.523446 -282.572547) (xy 159.51327 -282.572968) (xy 158.11373 -282.572968)
			(xy 158.103561 -282.572512) (xy 158.084768 -282.564738) (xy 158.070383 -282.550362) (xy 158.062596 -282.531575)
			(xy 158.062168 -282.521406) (xy 106.889501 -282.521406) (xy 106.886026 -282.532101) (xy 106.86252 -282.578233)
			(xy 106.832088 -282.62012) (xy 106.795478 -282.65673) (xy 106.753591 -282.687162) (xy 106.707459 -282.710668)
			(xy 106.658219 -282.726667) (xy 106.607081 -282.734766) (xy 106.555307 -282.734766) (xy 106.504169 -282.726667)
			(xy 106.454929 -282.710668) (xy 106.408797 -282.687162) (xy 106.36691 -282.65673) (xy 106.3303 -282.62012)
			(xy 106.299868 -282.578233) (xy 106.276362 -282.532101) (xy 106.260363 -282.482861) (xy 106.252264 -282.431723)
			(xy 106.251756 -282.405836) (xy 106.252296 -282.378128) (xy 106.261484 -282.323482) (xy 106.270044 -282.297124)
			(xy 106.277918 -282.275026) (xy 106.07294 -281.920188) (xy 106.05008 -281.91587) (xy 106.025256 -281.910713)
			(xy 105.977474 -281.893761) (xy 105.932853 -281.86969) (xy 105.892445 -281.839069) (xy 105.857203 -281.802621)
			(xy 105.827959 -281.761205) (xy 105.805403 -281.715799) (xy 105.790068 -281.667474) (xy 105.782315 -281.61737)
			(xy 105.781856 -281.59202) (xy 104.56164 -281.59202) (xy 104.561132 -281.617927) (xy 104.553026 -281.669104)
			(xy 104.537014 -281.718383) (xy 104.513491 -281.76455) (xy 104.483035 -281.806469) (xy 104.446397 -281.843107)
			(xy 104.404478 -281.873563) (xy 104.358311 -281.897086) (xy 104.309032 -281.913098) (xy 104.257855 -281.921204)
			(xy 104.206041 -281.921204) (xy 104.154864 -281.913098) (xy 104.105585 -281.897086) (xy 104.059418 -281.873563)
			(xy 104.017499 -281.843107) (xy 103.980861 -281.806469) (xy 103.950405 -281.76455) (xy 103.926882 -281.718383)
			(xy 103.91087 -281.669104) (xy 103.902764 -281.617927) (xy 103.902256 -281.59202) (xy 103.902852 -281.564303)
			(xy 103.912174 -281.509656) (xy 103.920798 -281.483308) (xy 103.928672 -281.46121) (xy 103.723694 -281.106372)
			(xy 103.700834 -281.102054) (xy 103.676009 -281.096858) (xy 103.628203 -281.079927) (xy 103.583555 -281.055874)
			(xy 103.543117 -281.025267) (xy 103.507844 -280.988827) (xy 103.478568 -280.947415) (xy 103.45598 -280.902007)
			(xy 103.440613 -280.853676) (xy 103.43283 -280.803562) (xy 103.432356 -280.778204) (xy 101.271832 -280.778204)
			(xy 101.271832 -280.778712) (xy 101.271241 -280.806228) (xy 101.262055 -280.860489) (xy 101.253544 -280.886662)
			(xy 101.245924 -280.908506) (xy 101.451156 -281.263852) (xy 101.474016 -281.26817) (xy 101.498826 -281.273386)
			(xy 101.546603 -281.290334) (xy 101.591222 -281.314398) (xy 101.631628 -281.345012) (xy 101.66687 -281.381453)
			(xy 101.696116 -281.422861) (xy 101.718675 -281.468259) (xy 101.734016 -281.516576) (xy 101.741776 -281.566673)
			(xy 101.74224 -281.59202) (xy 101.741732 -281.617927) (xy 101.733626 -281.669104) (xy 101.717614 -281.718383)
			(xy 101.694091 -281.76455) (xy 101.663635 -281.806469) (xy 101.626997 -281.843107) (xy 101.585078 -281.873563)
			(xy 101.538911 -281.897086) (xy 101.489632 -281.913098) (xy 101.438455 -281.921204) (xy 101.386641 -281.921204)
			(xy 101.335464 -281.913098) (xy 101.286185 -281.897086) (xy 101.240018 -281.873563) (xy 101.198099 -281.843107)
			(xy 101.161461 -281.806469) (xy 101.131005 -281.76455) (xy 101.107482 -281.718383) (xy 101.09147 -281.669104)
			(xy 101.083364 -281.617927) (xy 101.082856 -281.59202) (xy 101.083452 -281.564303) (xy 101.092774 -281.509656)
			(xy 101.101398 -281.483308) (xy 101.109272 -281.46121) (xy 100.904294 -281.106372) (xy 100.881434 -281.102054)
			(xy 100.856609 -281.096858) (xy 100.808803 -281.079927) (xy 100.764155 -281.055874) (xy 100.723717 -281.025267)
			(xy 100.688444 -280.988827) (xy 100.659168 -280.947415) (xy 100.63658 -280.902007) (xy 100.621213 -280.853676)
			(xy 100.61343 -280.803562) (xy 100.612956 -280.778204) (xy 98.452432 -280.778204) (xy 98.451927 -280.803537)
			(xy 98.444175 -280.853607) (xy 98.428854 -280.901902) (xy 98.406324 -280.947284) (xy 98.377117 -280.988685)
			(xy 98.34192 -281.025131) (xy 98.301561 -281.055762) (xy 98.256992 -281.079859) (xy 98.20926 -281.096853)
			(xy 98.184462 -281.102054) (xy 98.161602 -281.106372) (xy 97.956624 -281.46121) (xy 97.964498 -281.483308)
			(xy 97.973138 -281.509652) (xy 97.982453 -281.564301) (xy 97.98304 -281.59202) (xy 97.982532 -281.61791)
			(xy 99.20371 -281.61791) (xy 99.20371 -281.56609) (xy 99.211817 -281.514907) (xy 99.227832 -281.465624)
			(xy 99.25136 -281.419452) (xy 99.281822 -281.37753) (xy 99.318467 -281.34089) (xy 99.360393 -281.310435)
			(xy 99.406568 -281.286913) (xy 99.455854 -281.270906) (xy 99.507038 -281.262806) (xy 99.532948 -281.262328)
			(xy 99.558462 -281.262762) (xy 99.608879 -281.270631) (xy 99.657482 -281.286173) (xy 99.70311 -281.309017)
			(xy 99.744675 -281.338618) (xy 99.781182 -281.374269) (xy 99.796854 -281.394408) (xy 100.208842 -281.394408)
			(xy 100.224493 -281.374254) (xy 100.261007 -281.338611) (xy 100.302577 -281.309019) (xy 100.34821 -281.286186)
			(xy 100.396816 -281.270657) (xy 100.447235 -281.262802) (xy 100.472748 -281.262328) (xy 100.498654 -281.2628)
			(xy 100.549829 -281.270912) (xy 100.599104 -281.286928) (xy 100.645267 -281.310456) (xy 100.687182 -281.340914)
			(xy 100.723817 -281.377554) (xy 100.754269 -281.419474) (xy 100.77779 -281.465641) (xy 100.7938 -281.514918)
			(xy 100.801904 -281.566093) (xy 100.801904 -281.617907) (xy 100.7938 -281.669082) (xy 100.77779 -281.718359)
			(xy 100.754269 -281.764526) (xy 100.723817 -281.806446) (xy 100.687182 -281.843086) (xy 100.645267 -281.873544)
			(xy 100.599104 -281.897072) (xy 100.549829 -281.913088) (xy 100.498654 -281.9212) (xy 100.472748 -281.921712)
			(xy 100.447238 -281.921192) (xy 100.396825 -281.913339) (xy 100.348225 -281.897813) (xy 100.302596 -281.874985)
			(xy 100.26103 -281.8454) (xy 100.224517 -281.809764) (xy 100.208842 -281.789632) (xy 99.796854 -281.789632)
			(xy 99.781158 -281.809749) (xy 99.744652 -281.845392) (xy 99.703091 -281.874987) (xy 99.657467 -281.897826)
			(xy 99.60887 -281.913365) (xy 99.558459 -281.921231) (xy 99.532948 -281.921712) (xy 99.507038 -281.921194)
			(xy 99.455854 -281.913094) (xy 99.406568 -281.897087) (xy 99.360393 -281.873565) (xy 99.318467 -281.84311)
			(xy 99.281822 -281.80647) (xy 99.25136 -281.764548) (xy 99.227832 -281.718376) (xy 99.211817 -281.669093)
			(xy 99.20371 -281.61791) (xy 97.982532 -281.61791) (xy 97.982532 -281.617927) (xy 97.974426 -281.669104)
			(xy 97.958414 -281.718383) (xy 97.934891 -281.76455) (xy 97.904435 -281.806469) (xy 97.867797 -281.843107)
			(xy 97.825878 -281.873563) (xy 97.779711 -281.897086) (xy 97.730432 -281.913098) (xy 97.679255 -281.921204)
			(xy 97.627441 -281.921204) (xy 97.576264 -281.913098) (xy 97.526985 -281.897086) (xy 97.480818 -281.873563)
			(xy 97.438899 -281.843107) (xy 97.402261 -281.806469) (xy 97.371805 -281.76455) (xy 97.348282 -281.718383)
			(xy 97.33227 -281.669104) (xy 97.324164 -281.617927) (xy 97.323656 -281.59202) (xy 96.10344 -281.59202)
			(xy 96.103032 -281.617397) (xy 96.095259 -281.667553) (xy 96.079885 -281.715923) (xy 96.057273 -281.761362)
			(xy 96.027958 -281.802795) (xy 95.992635 -281.839241) (xy 95.95214 -281.869837) (xy 95.907431 -281.89386)
			(xy 95.859566 -281.910741) (xy 95.834708 -281.91587) (xy 95.811848 -281.920188) (xy 95.60687 -282.275026)
			(xy 95.614744 -282.297124) (xy 95.623311 -282.32348) (xy 95.632506 -282.378127) (xy 95.633032 -282.405836)
			(xy 95.913956 -282.405836) (xy 95.914464 -282.379949) (xy 95.922563 -282.328811) (xy 95.938562 -282.279571)
			(xy 95.962068 -282.233439) (xy 95.9925 -282.191552) (xy 96.02911 -282.154942) (xy 96.070997 -282.12451)
			(xy 96.117129 -282.101004) (xy 96.166369 -282.085005) (xy 96.217507 -282.076906) (xy 96.269281 -282.076906)
			(xy 96.320419 -282.085005) (xy 96.369659 -282.101004) (xy 96.415791 -282.12451) (xy 96.457678 -282.154942)
			(xy 96.494288 -282.191552) (xy 96.52472 -282.233439) (xy 96.548226 -282.279571) (xy 96.564225 -282.328811)
			(xy 96.572324 -282.379949) (xy 96.572832 -282.405836) (xy 96.572832 -282.406344) (xy 96.572295 -282.431704)
			(xy 96.854052 -282.431704) (xy 96.854052 -282.379896) (xy 96.862157 -282.328725) (xy 96.878166 -282.279453)
			(xy 96.901687 -282.233291) (xy 96.932138 -282.191377) (xy 96.968772 -282.154742) (xy 97.010686 -282.12429)
			(xy 97.056847 -282.100769) (xy 97.106119 -282.084758) (xy 97.15729 -282.076653) (xy 97.183194 -282.076144)
			(xy 97.208707 -282.076611) (xy 97.259122 -282.084472) (xy 97.307725 -282.100007) (xy 97.353354 -282.122845)
			(xy 97.394919 -282.152441) (xy 97.431427 -282.188087) (xy 97.4471 -282.208224) (xy 97.859088 -282.208224)
			(xy 97.874775 -282.188099) (xy 97.911281 -282.152454) (xy 97.952843 -282.122858) (xy 97.998469 -282.10002)
			(xy 98.047069 -282.084484) (xy 98.097483 -282.076622) (xy 98.122994 -282.076144) (xy 98.148907 -282.076553)
			(xy 98.200094 -282.08466) (xy 98.249383 -282.100674) (xy 98.295559 -282.124201) (xy 98.337487 -282.154663)
			(xy 98.374133 -282.191308) (xy 98.404596 -282.233235) (xy 98.428124 -282.279412) (xy 98.444139 -282.3287)
			(xy 98.452246 -282.379887) (xy 98.452246 -282.431713) (xy 98.444139 -282.4829) (xy 98.428124 -282.532188)
			(xy 98.404596 -282.578365) (xy 98.374133 -282.620292) (xy 98.337487 -282.656937) (xy 98.295559 -282.687399)
			(xy 98.249383 -282.710926) (xy 98.200094 -282.72694) (xy 98.148907 -282.735047) (xy 98.122994 -282.735528)
			(xy 98.097483 -282.735041) (xy 98.047069 -282.72718) (xy 97.998468 -282.711647) (xy 97.95284 -282.688813)
			(xy 97.911274 -282.659222) (xy 97.874762 -282.623582) (xy 97.859088 -282.603448) (xy 97.4471 -282.603448)
			(xy 97.43144 -282.623594) (xy 97.394926 -282.659235) (xy 97.353357 -282.688826) (xy 97.307726 -282.71166)
			(xy 97.259123 -282.727192) (xy 97.208707 -282.735052) (xy 97.183194 -282.735528) (xy 97.15729 -282.734947)
			(xy 97.106119 -282.726842) (xy 97.056847 -282.710831) (xy 97.010686 -282.68731) (xy 96.968772 -282.656858)
			(xy 96.932138 -282.620223) (xy 96.901687 -282.578309) (xy 96.878166 -282.532147) (xy 96.862157 -282.482875)
			(xy 96.854052 -282.431704) (xy 96.572295 -282.431704) (xy 96.572249 -282.43386) (xy 96.563058 -282.488121)
			(xy 96.554544 -282.514294) (xy 96.546924 -282.536392) (xy 96.752156 -282.891738) (xy 96.775016 -282.896056)
			(xy 96.799823 -282.901285) (xy 96.847599 -282.918232) (xy 96.892217 -282.942295) (xy 96.932623 -282.972907)
			(xy 96.967865 -283.009346) (xy 96.997111 -283.050752) (xy 97.019671 -283.096149) (xy 97.035013 -283.144464)
			(xy 97.042775 -283.194559) (xy 97.04324 -283.219906) (xy 99.203256 -283.219906) (xy 99.203737 -283.19456)
			(xy 99.21151 -283.144468) (xy 99.226857 -283.096156) (xy 99.249417 -283.050761) (xy 99.278659 -283.009354)
			(xy 99.313894 -282.97291) (xy 99.354291 -282.942288) (xy 99.398899 -282.918209) (xy 99.446666 -282.901241)
			(xy 99.47148 -282.896056) (xy 99.49434 -282.891738) (xy 99.699318 -282.5369) (xy 99.691698 -282.514802)
			(xy 99.683062 -282.488391) (xy 99.673735 -282.433617) (xy 99.673156 -282.405836) (xy 99.673664 -282.379949)
			(xy 99.681763 -282.328811) (xy 99.697762 -282.279571) (xy 99.721268 -282.233439) (xy 99.7517 -282.191552)
			(xy 99.78831 -282.154942) (xy 99.830197 -282.12451) (xy 99.876329 -282.101004) (xy 99.925569 -282.085005)
			(xy 99.976707 -282.076906) (xy 100.028481 -282.076906) (xy 100.079619 -282.085005) (xy 100.128859 -282.101004)
			(xy 100.174991 -282.12451) (xy 100.216878 -282.154942) (xy 100.253488 -282.191552) (xy 100.28392 -282.233439)
			(xy 100.307426 -282.279571) (xy 100.323425 -282.328811) (xy 100.331524 -282.379949) (xy 100.332032 -282.405836)
			(xy 101.552756 -282.405836) (xy 101.553216 -282.380501) (xy 101.560977 -282.33043) (xy 101.576305 -282.282135)
			(xy 101.598841 -282.236753) (xy 101.628054 -282.195352) (xy 101.663256 -282.158908) (xy 101.703619 -282.128277)
			(xy 101.748192 -282.104181) (xy 101.795927 -282.087187) (xy 101.820726 -282.081986) (xy 101.843586 -282.077668)
			(xy 102.048818 -281.722322) (xy 102.041198 -281.700478) (xy 102.03257 -281.674197) (xy 102.023258 -281.619675)
			(xy 102.022656 -281.59202) (xy 102.023164 -281.566113) (xy 102.03127 -281.514936) (xy 102.047282 -281.465657)
			(xy 102.070805 -281.41949) (xy 102.101261 -281.377571) (xy 102.137899 -281.340933) (xy 102.179818 -281.310477)
			(xy 102.225985 -281.286954) (xy 102.275264 -281.270942) (xy 102.326441 -281.262836) (xy 102.378255 -281.262836)
			(xy 102.429432 -281.270942) (xy 102.478711 -281.286954) (xy 102.524878 -281.310477) (xy 102.566797 -281.340933)
			(xy 102.603435 -281.377571) (xy 102.633891 -281.41949) (xy 102.657414 -281.465657) (xy 102.673426 -281.514936)
			(xy 102.681532 -281.566113) (xy 102.68204 -281.59202) (xy 102.681632 -281.617397) (xy 102.673859 -281.667553)
			(xy 102.658485 -281.715923) (xy 102.635873 -281.761362) (xy 102.606558 -281.802795) (xy 102.571235 -281.839241)
			(xy 102.53074 -281.869837) (xy 102.486031 -281.89386) (xy 102.438166 -281.910741) (xy 102.413308 -281.91587)
			(xy 102.390448 -281.920188) (xy 102.18547 -282.275026) (xy 102.193344 -282.297124) (xy 102.201911 -282.32348)
			(xy 102.211106 -282.378127) (xy 102.211632 -282.405836) (xy 102.211124 -282.431704) (xy 103.432652 -282.431704)
			(xy 103.432652 -282.379896) (xy 103.440757 -282.328725) (xy 103.456766 -282.279453) (xy 103.480287 -282.233291)
			(xy 103.510738 -282.191377) (xy 103.547372 -282.154742) (xy 103.589286 -282.12429) (xy 103.635447 -282.100769)
			(xy 103.684719 -282.084758) (xy 103.73589 -282.076653) (xy 103.761794 -282.076144) (xy 103.787307 -282.076611)
			(xy 103.837722 -282.084472) (xy 103.886325 -282.100007) (xy 103.931954 -282.122845) (xy 103.973519 -282.152441)
			(xy 104.010027 -282.188087) (xy 104.0257 -282.208224) (xy 104.437688 -282.208224) (xy 104.453375 -282.188099)
			(xy 104.489881 -282.152454) (xy 104.531443 -282.122858) (xy 104.577069 -282.10002) (xy 104.625669 -282.084484)
			(xy 104.676083 -282.076622) (xy 104.701594 -282.076144) (xy 104.727507 -282.076553) (xy 104.778694 -282.08466)
			(xy 104.827983 -282.100674) (xy 104.874159 -282.124201) (xy 104.916087 -282.154663) (xy 104.952733 -282.191308)
			(xy 104.983196 -282.233235) (xy 105.006724 -282.279412) (xy 105.022739 -282.3287) (xy 105.030846 -282.379887)
			(xy 105.030846 -282.431713) (xy 105.022739 -282.4829) (xy 105.006724 -282.532188) (xy 104.983196 -282.578365)
			(xy 104.952733 -282.620292) (xy 104.916087 -282.656937) (xy 104.874159 -282.687399) (xy 104.827983 -282.710926)
			(xy 104.778694 -282.72694) (xy 104.727507 -282.735047) (xy 104.701594 -282.735528) (xy 104.676083 -282.735041)
			(xy 104.625669 -282.72718) (xy 104.577068 -282.711647) (xy 104.53144 -282.688813) (xy 104.489874 -282.659222)
			(xy 104.453362 -282.623582) (xy 104.437688 -282.603448) (xy 104.0257 -282.603448) (xy 104.01004 -282.623594)
			(xy 103.973526 -282.659235) (xy 103.931957 -282.688826) (xy 103.886326 -282.71166) (xy 103.837723 -282.727192)
			(xy 103.787307 -282.735052) (xy 103.761794 -282.735528) (xy 103.73589 -282.734947) (xy 103.684719 -282.726842)
			(xy 103.635447 -282.710831) (xy 103.589286 -282.68731) (xy 103.547372 -282.656858) (xy 103.510738 -282.620223)
			(xy 103.480287 -282.578309) (xy 103.456766 -282.532147) (xy 103.440757 -282.482875) (xy 103.432652 -282.431704)
			(xy 102.211124 -282.431704) (xy 102.211124 -282.431723) (xy 102.203025 -282.482861) (xy 102.187026 -282.532101)
			(xy 102.16352 -282.578233) (xy 102.133088 -282.62012) (xy 102.096478 -282.65673) (xy 102.054591 -282.687162)
			(xy 102.008459 -282.710668) (xy 101.959219 -282.726667) (xy 101.908081 -282.734766) (xy 101.856307 -282.734766)
			(xy 101.805169 -282.726667) (xy 101.755929 -282.710668) (xy 101.709797 -282.687162) (xy 101.66791 -282.65673)
			(xy 101.6313 -282.62012) (xy 101.600868 -282.578233) (xy 101.577362 -282.532101) (xy 101.561363 -282.482861)
			(xy 101.553264 -282.431723) (xy 101.552756 -282.405836) (xy 100.332032 -282.405836) (xy 100.331594 -282.431161)
			(xy 100.323857 -282.481217) (xy 100.308554 -282.5295) (xy 100.286046 -282.574874) (xy 100.256862 -282.616272)
			(xy 100.22169 -282.652718) (xy 100.181356 -282.683356) (xy 100.136812 -282.707464) (xy 100.089103 -282.724474)
			(xy 100.064316 -282.729686) (xy 100.041456 -282.734004) (xy 99.836224 -283.089096) (xy 99.844098 -283.111194)
			(xy 99.852735 -283.137539) (xy 99.862052 -283.192188) (xy 99.86264 -283.219906) (xy 99.862132 -283.245791)
			(xy 101.083549 -283.245791) (xy 101.083549 -283.194009) (xy 101.091651 -283.142863) (xy 101.107654 -283.093616)
			(xy 101.131165 -283.047478) (xy 101.161604 -283.005586) (xy 101.198223 -282.968973) (xy 101.240119 -282.93854)
			(xy 101.28626 -282.915036) (xy 101.33551 -282.89904) (xy 101.386657 -282.890946) (xy 101.412548 -282.890468)
			(xy 101.43806 -282.890926) (xy 101.488475 -282.898793) (xy 101.537077 -282.914332) (xy 101.582705 -282.937172)
			(xy 101.62427 -282.966767) (xy 101.66078 -283.002412) (xy 101.676454 -283.022548) (xy 102.088442 -283.022548)
			(xy 102.104077 -283.002381) (xy 102.140596 -282.966741) (xy 102.18217 -282.937153) (xy 102.227806 -282.914323)
			(xy 102.276414 -282.898795) (xy 102.326834 -282.890941) (xy 102.352348 -282.890468) (xy 102.378233 -282.890967)
			(xy 102.429366 -282.899073) (xy 102.478601 -282.915077) (xy 102.524727 -282.938585) (xy 102.566608 -282.969019)
			(xy 102.603213 -283.005629) (xy 102.63364 -283.047514) (xy 102.657142 -283.093643) (xy 102.673139 -283.142881)
			(xy 102.681237 -283.194015) (xy 102.681237 -283.219906) (xy 104.842056 -283.219906) (xy 104.842537 -283.19456)
			(xy 104.85031 -283.144468) (xy 104.865657 -283.096156) (xy 104.888217 -283.050761) (xy 104.917459 -283.009354)
			(xy 104.952694 -282.97291) (xy 104.993091 -282.942288) (xy 105.037699 -282.918209) (xy 105.085466 -282.901241)
			(xy 105.11028 -282.896056) (xy 105.13314 -282.891738) (xy 105.338118 -282.5369) (xy 105.330498 -282.514802)
			(xy 105.321862 -282.488391) (xy 105.312535 -282.433617) (xy 105.311956 -282.405836) (xy 105.312464 -282.379949)
			(xy 105.320563 -282.328811) (xy 105.336562 -282.279571) (xy 105.360068 -282.233439) (xy 105.3905 -282.191552)
			(xy 105.42711 -282.154942) (xy 105.468997 -282.12451) (xy 105.515129 -282.101004) (xy 105.564369 -282.085005)
			(xy 105.615507 -282.076906) (xy 105.667281 -282.076906) (xy 105.718419 -282.085005) (xy 105.767659 -282.101004)
			(xy 105.813791 -282.12451) (xy 105.855678 -282.154942) (xy 105.892288 -282.191552) (xy 105.92272 -282.233439)
			(xy 105.946226 -282.279571) (xy 105.962225 -282.328811) (xy 105.970324 -282.379949) (xy 105.970832 -282.405836)
			(xy 105.970394 -282.431161) (xy 105.962657 -282.481217) (xy 105.947354 -282.5295) (xy 105.924846 -282.574874)
			(xy 105.895662 -282.616272) (xy 105.86049 -282.652718) (xy 105.820156 -282.683356) (xy 105.775612 -282.707464)
			(xy 105.727903 -282.724474) (xy 105.703116 -282.729686) (xy 105.680256 -282.734004) (xy 105.475024 -283.089096)
			(xy 105.482898 -283.111194) (xy 105.491535 -283.137539) (xy 105.500852 -283.192188) (xy 105.50144 -283.219906)
			(xy 105.500932 -283.245813) (xy 105.492826 -283.29699) (xy 105.476814 -283.346269) (xy 105.463936 -283.371544)
			(xy 162.162236 -283.371544) (xy 162.162236 -282.962604) (xy 162.162626 -282.952446) (xy 162.170427 -282.933686)
			(xy 162.184834 -282.919362) (xy 162.203637 -282.911668) (xy 162.213798 -282.911296) (xy 163.613338 -282.911296)
			(xy 163.623462 -282.911794) (xy 163.642175 -282.919526) (xy 163.656529 -282.933808) (xy 163.664354 -282.952483)
			(xy 163.6649 -282.962604) (xy 163.6649 -283.371544) (xy 169.706036 -283.371544) (xy 169.706036 -282.962604)
			(xy 169.706426 -282.952446) (xy 169.714227 -282.933686) (xy 169.728634 -282.919362) (xy 169.747437 -282.911668)
			(xy 169.757598 -282.911296) (xy 171.157138 -282.911296) (xy 171.167262 -282.911794) (xy 171.185975 -282.919526)
			(xy 171.200329 -282.933808) (xy 171.208154 -282.952483) (xy 171.2087 -282.962604) (xy 171.2087 -283.371544)
			(xy 177.249836 -283.371544) (xy 177.249836 -282.962604) (xy 177.250226 -282.952446) (xy 177.258027 -282.933686)
			(xy 177.272434 -282.919362) (xy 177.291237 -282.911668) (xy 177.301398 -282.911296) (xy 178.700938 -282.911296)
			(xy 178.711062 -282.911794) (xy 178.729775 -282.919526) (xy 178.744129 -282.933808) (xy 178.751954 -282.952483)
			(xy 178.7525 -282.962604) (xy 178.7525 -283.371544) (xy 184.793636 -283.371544) (xy 184.793636 -282.962604)
			(xy 184.794026 -282.952446) (xy 184.801827 -282.933686) (xy 184.816234 -282.919362) (xy 184.835037 -282.911668)
			(xy 184.845198 -282.911296) (xy 186.244738 -282.911296) (xy 186.254862 -282.911794) (xy 186.273575 -282.919526)
			(xy 186.287929 -282.933808) (xy 186.295754 -282.952483) (xy 186.2963 -282.962604) (xy 186.2963 -283.371544)
			(xy 192.337436 -283.371544) (xy 192.337436 -282.962604) (xy 192.337826 -282.952446) (xy 192.345627 -282.933686)
			(xy 192.360034 -282.919362) (xy 192.378837 -282.911668) (xy 192.388998 -282.911296) (xy 193.788538 -282.911296)
			(xy 193.798662 -282.911794) (xy 193.817375 -282.919526) (xy 193.831729 -282.933808) (xy 193.839554 -282.952483)
			(xy 193.8401 -282.962604) (xy 193.8401 -283.371544) (xy 199.881236 -283.371544) (xy 199.881236 -282.962604)
			(xy 199.881626 -282.952446) (xy 199.889427 -282.933686) (xy 199.903834 -282.919362) (xy 199.922637 -282.911668)
			(xy 199.932798 -282.911296) (xy 201.332338 -282.911296) (xy 201.342462 -282.911794) (xy 201.361175 -282.919526)
			(xy 201.375529 -282.933808) (xy 201.383354 -282.952483) (xy 201.3839 -282.962604) (xy 201.3839 -283.371544)
			(xy 207.425036 -283.371544) (xy 207.425036 -282.962604) (xy 207.425426 -282.952446) (xy 207.433227 -282.933686)
			(xy 207.447634 -282.919362) (xy 207.466437 -282.911668) (xy 207.476598 -282.911296) (xy 208.876138 -282.911296)
			(xy 208.886262 -282.911794) (xy 208.904975 -282.919526) (xy 208.919329 -282.933808) (xy 208.927154 -282.952483)
			(xy 208.9277 -282.962604) (xy 208.9277 -283.371544) (xy 214.968836 -283.371544) (xy 214.968836 -282.962604)
			(xy 214.969226 -282.952446) (xy 214.977027 -282.933686) (xy 214.991434 -282.919362) (xy 215.010237 -282.911668)
			(xy 215.020398 -282.911296) (xy 216.419938 -282.911296) (xy 216.430062 -282.911794) (xy 216.448775 -282.919526)
			(xy 216.463129 -282.933808) (xy 216.470954 -282.952483) (xy 216.4715 -282.962604) (xy 216.4715 -283.371544)
			(xy 259.429504 -283.371544) (xy 259.429504 -282.962604) (xy 259.429925 -282.95245) (xy 259.43772 -282.933697)
			(xy 259.452117 -282.919373) (xy 259.47091 -282.911674) (xy 259.481066 -282.911296) (xy 260.880606 -282.911296)
			(xy 260.890728 -282.91182) (xy 260.909441 -282.919542) (xy 260.923795 -282.933816) (xy 260.931622 -282.952485)
			(xy 260.932168 -282.962604) (xy 260.932168 -283.371544) (xy 266.973304 -283.371544) (xy 266.973304 -282.962604)
			(xy 266.973725 -282.95245) (xy 266.98152 -282.933697) (xy 266.995917 -282.919373) (xy 267.01471 -282.911674)
			(xy 267.024866 -282.911296) (xy 268.424406 -282.911296) (xy 268.434528 -282.91182) (xy 268.453241 -282.919542)
			(xy 268.467595 -282.933816) (xy 268.475422 -282.952485) (xy 268.475968 -282.962604) (xy 268.475968 -283.371544)
			(xy 274.517104 -283.371544) (xy 274.517104 -282.962604) (xy 274.517525 -282.95245) (xy 274.52532 -282.933697)
			(xy 274.539717 -282.919373) (xy 274.55851 -282.911674) (xy 274.568666 -282.911296) (xy 275.968206 -282.911296)
			(xy 275.978328 -282.91182) (xy 275.997041 -282.919542) (xy 276.011395 -282.933816) (xy 276.019222 -282.952485)
			(xy 276.019768 -282.962604) (xy 276.019768 -283.371544) (xy 282.060904 -283.371544) (xy 282.060904 -282.962604)
			(xy 282.061325 -282.95245) (xy 282.06912 -282.933697) (xy 282.083517 -282.919373) (xy 282.10231 -282.911674)
			(xy 282.112466 -282.911296) (xy 283.512006 -282.911296) (xy 283.522128 -282.91182) (xy 283.540841 -282.919542)
			(xy 283.555195 -282.933816) (xy 283.563022 -282.952485) (xy 283.563568 -282.962604) (xy 283.563568 -283.371544)
			(xy 289.604704 -283.371544) (xy 289.604704 -282.962604) (xy 289.605125 -282.95245) (xy 289.61292 -282.933697)
			(xy 289.627317 -282.919373) (xy 289.64611 -282.911674) (xy 289.656266 -282.911296) (xy 291.055806 -282.911296)
			(xy 291.065928 -282.91182) (xy 291.084641 -282.919542) (xy 291.098995 -282.933816) (xy 291.106822 -282.952485)
			(xy 291.107368 -282.962604) (xy 291.107368 -283.371544) (xy 297.148504 -283.371544) (xy 297.148504 -282.962604)
			(xy 297.148925 -282.95245) (xy 297.15672 -282.933697) (xy 297.171117 -282.919373) (xy 297.18991 -282.911674)
			(xy 297.200066 -282.911296) (xy 298.599606 -282.911296) (xy 298.609728 -282.91182) (xy 298.628441 -282.919542)
			(xy 298.642795 -282.933816) (xy 298.650622 -282.952485) (xy 298.651168 -282.962604) (xy 298.651168 -283.371544)
			(xy 304.692304 -283.371544) (xy 304.692304 -282.962604) (xy 304.692725 -282.95245) (xy 304.70052 -282.933697)
			(xy 304.714917 -282.919373) (xy 304.73371 -282.911674) (xy 304.743866 -282.911296) (xy 306.143406 -282.911296)
			(xy 306.153528 -282.91182) (xy 306.172241 -282.919542) (xy 306.186595 -282.933816) (xy 306.194422 -282.952485)
			(xy 306.194968 -282.962604) (xy 306.194968 -283.371544) (xy 312.236104 -283.371544) (xy 312.236104 -282.962604)
			(xy 312.236525 -282.95245) (xy 312.24432 -282.933697) (xy 312.258717 -282.919373) (xy 312.27751 -282.911674)
			(xy 312.287666 -282.911296) (xy 313.687206 -282.911296) (xy 313.697328 -282.91182) (xy 313.716041 -282.919542)
			(xy 313.730395 -282.933816) (xy 313.738222 -282.952485) (xy 313.738768 -282.962604) (xy 313.738768 -283.371544)
			(xy 313.738414 -283.381705) (xy 313.730598 -283.400464) (xy 313.71618 -283.414787) (xy 313.69737 -283.42248)
			(xy 313.687206 -283.422852) (xy 312.287666 -283.422852) (xy 312.277536 -283.422401) (xy 312.258813 -283.414661)
			(xy 312.244457 -283.400364) (xy 312.236641 -283.381672) (xy 312.236104 -283.371544) (xy 306.194968 -283.371544)
			(xy 306.194614 -283.381705) (xy 306.186798 -283.400464) (xy 306.17238 -283.414787) (xy 306.15357 -283.42248)
			(xy 306.143406 -283.422852) (xy 304.743866 -283.422852) (xy 304.733736 -283.422401) (xy 304.715013 -283.414661)
			(xy 304.700657 -283.400364) (xy 304.692841 -283.381672) (xy 304.692304 -283.371544) (xy 298.651168 -283.371544)
			(xy 298.650814 -283.381705) (xy 298.642998 -283.400464) (xy 298.62858 -283.414787) (xy 298.60977 -283.42248)
			(xy 298.599606 -283.422852) (xy 297.200066 -283.422852) (xy 297.189936 -283.422401) (xy 297.171213 -283.414661)
			(xy 297.156857 -283.400364) (xy 297.149041 -283.381672) (xy 297.148504 -283.371544) (xy 291.107368 -283.371544)
			(xy 291.107014 -283.381705) (xy 291.099198 -283.400464) (xy 291.08478 -283.414787) (xy 291.06597 -283.42248)
			(xy 291.055806 -283.422852) (xy 289.656266 -283.422852) (xy 289.646136 -283.422401) (xy 289.627413 -283.414661)
			(xy 289.613057 -283.400364) (xy 289.605241 -283.381672) (xy 289.604704 -283.371544) (xy 283.563568 -283.371544)
			(xy 283.563214 -283.381705) (xy 283.555398 -283.400464) (xy 283.54098 -283.414787) (xy 283.52217 -283.42248)
			(xy 283.512006 -283.422852) (xy 282.112466 -283.422852) (xy 282.102336 -283.422401) (xy 282.083613 -283.414661)
			(xy 282.069257 -283.400364) (xy 282.061441 -283.381672) (xy 282.060904 -283.371544) (xy 276.019768 -283.371544)
			(xy 276.019414 -283.381705) (xy 276.011598 -283.400464) (xy 275.99718 -283.414787) (xy 275.97837 -283.42248)
			(xy 275.968206 -283.422852) (xy 274.568666 -283.422852) (xy 274.558536 -283.422401) (xy 274.539813 -283.414661)
			(xy 274.525457 -283.400364) (xy 274.517641 -283.381672) (xy 274.517104 -283.371544) (xy 268.475968 -283.371544)
			(xy 268.475614 -283.381705) (xy 268.467798 -283.400464) (xy 268.45338 -283.414787) (xy 268.43457 -283.42248)
			(xy 268.424406 -283.422852) (xy 267.024866 -283.422852) (xy 267.014736 -283.422401) (xy 266.996013 -283.414661)
			(xy 266.981657 -283.400364) (xy 266.973841 -283.381672) (xy 266.973304 -283.371544) (xy 260.932168 -283.371544)
			(xy 260.931814 -283.381705) (xy 260.923998 -283.400464) (xy 260.90958 -283.414787) (xy 260.89077 -283.42248)
			(xy 260.880606 -283.422852) (xy 259.481066 -283.422852) (xy 259.470936 -283.422401) (xy 259.452213 -283.414661)
			(xy 259.437857 -283.400364) (xy 259.430041 -283.381672) (xy 259.429504 -283.371544) (xy 216.4715 -283.371544)
			(xy 216.471114 -283.381701) (xy 216.463304 -283.400454) (xy 216.448897 -283.414776) (xy 216.430097 -283.422474)
			(xy 216.419938 -283.422852) (xy 215.020398 -283.422852) (xy 215.01027 -283.422375) (xy 214.991548 -283.414645)
			(xy 214.977191 -283.400356) (xy 214.969373 -283.381669) (xy 214.968836 -283.371544) (xy 208.9277 -283.371544)
			(xy 208.927314 -283.381701) (xy 208.919504 -283.400454) (xy 208.905097 -283.414776) (xy 208.886297 -283.422474)
			(xy 208.876138 -283.422852) (xy 207.476598 -283.422852) (xy 207.46647 -283.422375) (xy 207.447748 -283.414645)
			(xy 207.433391 -283.400356) (xy 207.425573 -283.381669) (xy 207.425036 -283.371544) (xy 201.3839 -283.371544)
			(xy 201.383514 -283.381701) (xy 201.375704 -283.400454) (xy 201.361297 -283.414776) (xy 201.342497 -283.422474)
			(xy 201.332338 -283.422852) (xy 199.932798 -283.422852) (xy 199.92267 -283.422375) (xy 199.903948 -283.414645)
			(xy 199.889591 -283.400356) (xy 199.881773 -283.381669) (xy 199.881236 -283.371544) (xy 193.8401 -283.371544)
			(xy 193.839714 -283.381701) (xy 193.831904 -283.400454) (xy 193.817497 -283.414776) (xy 193.798697 -283.422474)
			(xy 193.788538 -283.422852) (xy 192.388998 -283.422852) (xy 192.37887 -283.422375) (xy 192.360148 -283.414645)
			(xy 192.345791 -283.400356) (xy 192.337973 -283.381669) (xy 192.337436 -283.371544) (xy 186.2963 -283.371544)
			(xy 186.295914 -283.381701) (xy 186.288104 -283.400454) (xy 186.273697 -283.414776) (xy 186.254897 -283.422474)
			(xy 186.244738 -283.422852) (xy 184.845198 -283.422852) (xy 184.83507 -283.422375) (xy 184.816348 -283.414645)
			(xy 184.801991 -283.400356) (xy 184.794173 -283.381669) (xy 184.793636 -283.371544) (xy 178.7525 -283.371544)
			(xy 178.752114 -283.381701) (xy 178.744304 -283.400454) (xy 178.729897 -283.414776) (xy 178.711097 -283.422474)
			(xy 178.700938 -283.422852) (xy 177.301398 -283.422852) (xy 177.29127 -283.422375) (xy 177.272548 -283.414645)
			(xy 177.258191 -283.400356) (xy 177.250373 -283.381669) (xy 177.249836 -283.371544) (xy 171.2087 -283.371544)
			(xy 171.208314 -283.381701) (xy 171.200504 -283.400454) (xy 171.186097 -283.414776) (xy 171.167297 -283.422474)
			(xy 171.157138 -283.422852) (xy 169.757598 -283.422852) (xy 169.74747 -283.422375) (xy 169.728748 -283.414645)
			(xy 169.714391 -283.400356) (xy 169.706573 -283.381669) (xy 169.706036 -283.371544) (xy 163.6649 -283.371544)
			(xy 163.664514 -283.381701) (xy 163.656704 -283.400454) (xy 163.642297 -283.414776) (xy 163.623497 -283.422474)
			(xy 163.613338 -283.422852) (xy 162.213798 -283.422852) (xy 162.20367 -283.422375) (xy 162.184948 -283.414645)
			(xy 162.170591 -283.400356) (xy 162.162773 -283.381669) (xy 162.162236 -283.371544) (xy 105.463936 -283.371544)
			(xy 105.453291 -283.392436) (xy 105.422835 -283.434355) (xy 105.386197 -283.470993) (xy 105.344278 -283.501449)
			(xy 105.298111 -283.524972) (xy 105.248832 -283.540984) (xy 105.197655 -283.54909) (xy 105.145841 -283.54909)
			(xy 105.094664 -283.540984) (xy 105.045385 -283.524972) (xy 104.999218 -283.501449) (xy 104.957299 -283.470993)
			(xy 104.920661 -283.434355) (xy 104.890205 -283.392436) (xy 104.866682 -283.346269) (xy 104.85067 -283.29699)
			(xy 104.842564 -283.245813) (xy 104.842056 -283.219906) (xy 102.681237 -283.219906) (xy 102.681237 -283.245785)
			(xy 102.673139 -283.296919) (xy 102.657142 -283.346157) (xy 102.63364 -283.392286) (xy 102.603213 -283.434171)
			(xy 102.566608 -283.470781) (xy 102.524727 -283.501215) (xy 102.478601 -283.524723) (xy 102.429366 -283.540727)
			(xy 102.378233 -283.548833) (xy 102.352348 -283.549344) (xy 102.326836 -283.548851) (xy 102.276422 -283.540996)
			(xy 102.227819 -283.525467) (xy 102.18219 -283.502633) (xy 102.140624 -283.473042) (xy 102.104115 -283.437399)
			(xy 102.088442 -283.417264) (xy 101.676454 -283.417264) (xy 101.660739 -283.437366) (xy 101.624239 -283.473014)
			(xy 101.582683 -283.502612) (xy 101.537062 -283.525454) (xy 101.488467 -283.540995) (xy 101.438058 -283.548863)
			(xy 101.412548 -283.549344) (xy 101.386657 -283.548854) (xy 101.33551 -283.54076) (xy 101.28626 -283.524764)
			(xy 101.240119 -283.50126) (xy 101.198223 -283.470827) (xy 101.161604 -283.434214) (xy 101.131165 -283.392322)
			(xy 101.107654 -283.346184) (xy 101.091651 -283.296937) (xy 101.083549 -283.245791) (xy 99.862132 -283.245791)
			(xy 99.862132 -283.245813) (xy 99.854026 -283.29699) (xy 99.838014 -283.346269) (xy 99.814491 -283.392436)
			(xy 99.784035 -283.434355) (xy 99.747397 -283.470993) (xy 99.705478 -283.501449) (xy 99.659311 -283.524972)
			(xy 99.610032 -283.540984) (xy 99.558855 -283.54909) (xy 99.507041 -283.54909) (xy 99.455864 -283.540984)
			(xy 99.406585 -283.524972) (xy 99.360418 -283.501449) (xy 99.318499 -283.470993) (xy 99.281861 -283.434355)
			(xy 99.251405 -283.392436) (xy 99.227882 -283.346269) (xy 99.21187 -283.29699) (xy 99.203764 -283.245813)
			(xy 99.203256 -283.219906) (xy 97.04324 -283.219906) (xy 97.042732 -283.245813) (xy 97.034626 -283.29699)
			(xy 97.018614 -283.346269) (xy 96.995091 -283.392436) (xy 96.964635 -283.434355) (xy 96.927997 -283.470993)
			(xy 96.886078 -283.501449) (xy 96.839911 -283.524972) (xy 96.790632 -283.540984) (xy 96.739455 -283.54909)
			(xy 96.687641 -283.54909) (xy 96.636464 -283.540984) (xy 96.587185 -283.524972) (xy 96.541018 -283.501449)
			(xy 96.499099 -283.470993) (xy 96.462461 -283.434355) (xy 96.432005 -283.392436) (xy 96.408482 -283.346269)
			(xy 96.39247 -283.29699) (xy 96.384364 -283.245813) (xy 96.383856 -283.219906) (xy 96.384448 -283.192189)
			(xy 96.393773 -283.137542) (xy 96.402398 -283.111194) (xy 96.410272 -283.089096) (xy 96.205294 -282.734004)
			(xy 96.18218 -282.729686) (xy 96.15736 -282.724514) (xy 96.109579 -282.707563) (xy 96.064958 -282.683494)
			(xy 96.024551 -282.652875) (xy 95.989309 -282.616428) (xy 95.960065 -282.575014) (xy 95.937508 -282.52961)
			(xy 95.922171 -282.481287) (xy 95.914416 -282.431185) (xy 95.913956 -282.405836) (xy 95.633032 -282.405836)
			(xy 95.632524 -282.431723) (xy 95.624425 -282.482861) (xy 95.608426 -282.532101) (xy 95.58492 -282.578233)
			(xy 95.554488 -282.62012) (xy 95.517878 -282.65673) (xy 95.475991 -282.687162) (xy 95.429859 -282.710668)
			(xy 95.380619 -282.726667) (xy 95.329481 -282.734766) (xy 95.277707 -282.734766) (xy 95.226569 -282.726667)
			(xy 95.177329 -282.710668) (xy 95.131197 -282.687162) (xy 95.08931 -282.65673) (xy 95.0527 -282.62012)
			(xy 95.022268 -282.578233) (xy 94.998762 -282.532101) (xy 94.982763 -282.482861) (xy 94.974664 -282.431723)
			(xy 94.974156 -282.405836) (xy 93.75394 -282.405836) (xy 93.753432 -282.431743) (xy 93.745326 -282.48292)
			(xy 93.729314 -282.532199) (xy 93.705791 -282.578366) (xy 93.675335 -282.620285) (xy 93.638697 -282.656923)
			(xy 93.596778 -282.687379) (xy 93.550611 -282.710902) (xy 93.501332 -282.726914) (xy 93.450155 -282.73502)
			(xy 93.398341 -282.73502) (xy 93.347164 -282.726914) (xy 93.297885 -282.710902) (xy 93.251718 -282.687379)
			(xy 93.209799 -282.656923) (xy 93.173161 -282.620285) (xy 93.142705 -282.578366) (xy 93.119182 -282.532199)
			(xy 93.10317 -282.48292) (xy 93.095064 -282.431743) (xy 93.094556 -282.405836) (xy 91.87434 -282.405836)
			(xy 91.873903 -282.431201) (xy 91.86615 -282.481333) (xy 91.850801 -282.529685) (xy 91.828221 -282.575111)
			(xy 91.798942 -282.616537) (xy 91.763657 -282.652984) (xy 91.723202 -282.683591) (xy 91.678531 -282.707632)
			(xy 91.630703 -282.724539) (xy 91.605862 -282.729686) (xy 91.583002 -282.734004) (xy 91.378024 -283.089096)
			(xy 91.385644 -283.11094) (xy 91.394193 -283.137235) (xy 91.40339 -283.191753) (xy 91.403932 -283.219398)
			(xy 91.403932 -283.219906) (xy 91.403424 -283.245787) (xy 92.625176 -283.245787) (xy 92.625176 -283.194013)
			(xy 92.633275 -283.142878) (xy 92.649273 -283.093638) (xy 92.672778 -283.047508) (xy 92.703209 -283.005622)
			(xy 92.739818 -282.969013) (xy 92.781703 -282.938581) (xy 92.827833 -282.915076) (xy 92.877072 -282.899076)
			(xy 92.928207 -282.890976) (xy 92.954094 -282.890468) (xy 92.979605 -282.890965) (xy 93.030018 -282.898824)
			(xy 93.078619 -282.914355) (xy 93.124247 -282.937187) (xy 93.165813 -282.966776) (xy 93.202325 -283.002415)
			(xy 93.218 -283.022548) (xy 93.629988 -283.022548) (xy 93.645654 -283.002407) (xy 93.682167 -282.966766)
			(xy 93.723734 -282.937174) (xy 93.769364 -282.91434) (xy 93.817967 -282.898806) (xy 93.868382 -282.890945)
			(xy 93.893894 -282.890468) (xy 93.919784 -282.890937) (xy 93.970927 -282.899036) (xy 94.020174 -282.915037)
			(xy 94.066311 -282.938544) (xy 94.108202 -282.968979) (xy 94.144817 -283.005593) (xy 94.175253 -283.047484)
			(xy 94.198761 -283.093621) (xy 94.214762 -283.142867) (xy 94.222863 -283.19401) (xy 94.222863 -283.24579)
			(xy 94.214762 -283.296933) (xy 94.198761 -283.346179) (xy 94.175253 -283.392316) (xy 94.144817 -283.434207)
			(xy 94.108202 -283.470821) (xy 94.066311 -283.501256) (xy 94.020174 -283.524763) (xy 93.970927 -283.540764)
			(xy 93.919784 -283.548863) (xy 93.893894 -283.549344) (xy 93.868381 -283.54889) (xy 93.817964 -283.541027)
			(xy 93.769361 -283.52549) (xy 93.723732 -283.502649) (xy 93.682168 -283.473051) (xy 93.64566 -283.437402)
			(xy 93.629988 -283.417264) (xy 93.218 -283.417264) (xy 93.202317 -283.437392) (xy 93.16581 -283.473038)
			(xy 93.124247 -283.502633) (xy 93.078621 -283.525471) (xy 93.03002 -283.541006) (xy 92.979606 -283.548867)
			(xy 92.954094 -283.549344) (xy 92.928207 -283.548824) (xy 92.877072 -283.540724) (xy 92.827833 -283.524724)
			(xy 92.781703 -283.501219) (xy 92.739818 -283.470787) (xy 92.703209 -283.434178) (xy 92.672778 -283.392292)
			(xy 92.649273 -283.346162) (xy 92.633275 -283.296922) (xy 92.625176 -283.245787) (xy 91.403424 -283.245787)
			(xy 91.403424 -283.245793) (xy 91.395325 -283.296931) (xy 91.379326 -283.346171) (xy 91.35582 -283.392303)
			(xy 91.325388 -283.43419) (xy 91.288778 -283.4708) (xy 91.246891 -283.501232) (xy 91.200759 -283.524738)
			(xy 91.151519 -283.540737) (xy 91.100381 -283.548836) (xy 91.048607 -283.548836) (xy 90.997469 -283.540737)
			(xy 90.948229 -283.524738) (xy 90.902097 -283.501232) (xy 90.86021 -283.4708) (xy 90.8236 -283.43419)
			(xy 90.793168 -283.392303) (xy 90.769662 -283.346171) (xy 90.753663 -283.296931) (xy 90.745564 -283.245793)
			(xy 90.745056 -283.219906) (xy 88.584532 -283.219906) (xy 88.584024 -283.245793) (xy 88.575925 -283.296931)
			(xy 88.559926 -283.346171) (xy 88.53642 -283.392303) (xy 88.505988 -283.43419) (xy 88.469378 -283.4708)
			(xy 88.427491 -283.501232) (xy 88.381359 -283.524738) (xy 88.332119 -283.540737) (xy 88.280981 -283.548836)
			(xy 88.229207 -283.548836) (xy 88.178069 -283.540737) (xy 88.128829 -283.524738) (xy 88.082697 -283.501232)
			(xy 88.04081 -283.4708) (xy 88.0042 -283.43419) (xy 87.973768 -283.392303) (xy 87.950262 -283.346171)
			(xy 87.934263 -283.296931) (xy 87.926164 -283.245793) (xy 87.925656 -283.219906) (xy 87.926189 -283.192198)
			(xy 87.935382 -283.137551) (xy 87.943944 -283.111194) (xy 87.951818 -283.089096) (xy 87.746586 -282.734004)
			(xy 87.723726 -282.729686) (xy 87.698938 -282.724431) (xy 87.651203 -282.70745) (xy 87.606628 -282.683364)
			(xy 87.566263 -282.652742) (xy 87.531059 -282.616304) (xy 87.501844 -282.574908) (xy 87.479308 -282.52953)
			(xy 87.463981 -282.481238) (xy 87.456223 -282.431169) (xy 87.455756 -282.405836) (xy 61.698632 -282.405836)
			(xy 61.698632 -282.521406) (xy 61.69824 -282.531582) (xy 61.690448 -282.550382) (xy 61.676052 -282.564768)
			(xy 61.657246 -282.572547) (xy 61.64707 -282.572968) (xy 60.24753 -282.572968) (xy 60.237361 -282.572512)
			(xy 60.218568 -282.564738) (xy 60.204183 -282.550362) (xy 60.196396 -282.531575) (xy 60.195968 -282.521406)
			(xy 54.154832 -282.521406) (xy 54.15444 -282.531582) (xy 54.146648 -282.550382) (xy 54.132252 -282.564768)
			(xy 54.113446 -282.572547) (xy 54.10327 -282.572968) (xy 52.70373 -282.572968) (xy 52.693561 -282.572512)
			(xy 52.674768 -282.564738) (xy 52.660383 -282.550362) (xy 52.652596 -282.531575) (xy 52.652168 -282.521406)
			(xy 46.611032 -282.521406) (xy 46.61064 -282.531582) (xy 46.602848 -282.550382) (xy 46.588452 -282.564768)
			(xy 46.569646 -282.572547) (xy 46.55947 -282.572968) (xy 45.15993 -282.572968) (xy 45.149761 -282.572512)
			(xy 45.130968 -282.564738) (xy 45.116583 -282.550362) (xy 45.108796 -282.531575) (xy 45.108368 -282.521406)
			(xy 39.067232 -282.521406) (xy 39.06684 -282.531582) (xy 39.059048 -282.550382) (xy 39.044652 -282.564768)
			(xy 39.025846 -282.572547) (xy 39.01567 -282.572968) (xy 37.61613 -282.572968) (xy 37.605961 -282.572512)
			(xy 37.587168 -282.564738) (xy 37.572783 -282.550362) (xy 37.564996 -282.531575) (xy 37.564568 -282.521406)
			(xy 31.523432 -282.521406) (xy 31.52304 -282.531582) (xy 31.515248 -282.550382) (xy 31.500852 -282.564768)
			(xy 31.482046 -282.572547) (xy 31.47187 -282.572968) (xy 30.07233 -282.572968) (xy 30.062161 -282.572512)
			(xy 30.043368 -282.564738) (xy 30.028983 -282.550362) (xy 30.021196 -282.531575) (xy 30.020768 -282.521406)
			(xy 23.979632 -282.521406) (xy 23.97924 -282.531582) (xy 23.971448 -282.550382) (xy 23.957052 -282.564768)
			(xy 23.938246 -282.572547) (xy 23.92807 -282.572968) (xy 22.52853 -282.572968) (xy 22.518361 -282.572512)
			(xy 22.499568 -282.564738) (xy 22.485183 -282.550362) (xy 22.477396 -282.531575) (xy 22.476968 -282.521406)
			(xy 16.435832 -282.521406) (xy 16.43544 -282.531582) (xy 16.427648 -282.550382) (xy 16.413252 -282.564768)
			(xy 16.394446 -282.572547) (xy 16.38427 -282.572968) (xy 14.98473 -282.572968) (xy 14.974561 -282.572512)
			(xy 14.955768 -282.564738) (xy 14.941383 -282.550362) (xy 14.933596 -282.531575) (xy 14.933168 -282.521406)
			(xy 8.892032 -282.521406) (xy 8.89164 -282.531582) (xy 8.883848 -282.550382) (xy 8.869452 -282.564768)
			(xy 8.850646 -282.572547) (xy 8.84047 -282.572968) (xy 7.44093 -282.572968) (xy 7.430761 -282.572512)
			(xy 7.411968 -282.564738) (xy 7.397583 -282.550362) (xy 7.389796 -282.531575) (xy 7.389368 -282.521406)
			(xy 2.509012 -282.521406) (xy 2.509012 -283.371544) (xy 11.489436 -283.371544) (xy 11.489436 -282.962604)
			(xy 11.489826 -282.952446) (xy 11.497627 -282.933686) (xy 11.512034 -282.919362) (xy 11.530837 -282.911668)
			(xy 11.540998 -282.911296) (xy 12.940538 -282.911296) (xy 12.950662 -282.911794) (xy 12.969375 -282.919526)
			(xy 12.983729 -282.933808) (xy 12.991554 -282.952483) (xy 12.9921 -282.962604) (xy 12.9921 -283.371544)
			(xy 19.033236 -283.371544) (xy 19.033236 -282.962604) (xy 19.033626 -282.952446) (xy 19.041427 -282.933686)
			(xy 19.055834 -282.919362) (xy 19.074637 -282.911668) (xy 19.084798 -282.911296) (xy 20.484338 -282.911296)
			(xy 20.494462 -282.911794) (xy 20.513175 -282.919526) (xy 20.527529 -282.933808) (xy 20.535354 -282.952483)
			(xy 20.5359 -282.962604) (xy 20.5359 -283.371544) (xy 26.577036 -283.371544) (xy 26.577036 -282.962604)
			(xy 26.577426 -282.952446) (xy 26.585227 -282.933686) (xy 26.599634 -282.919362) (xy 26.618437 -282.911668)
			(xy 26.628598 -282.911296) (xy 28.028138 -282.911296) (xy 28.038262 -282.911794) (xy 28.056975 -282.919526)
			(xy 28.071329 -282.933808) (xy 28.079154 -282.952483) (xy 28.0797 -282.962604) (xy 28.0797 -283.371544)
			(xy 34.120836 -283.371544) (xy 34.120836 -282.962604) (xy 34.121226 -282.952446) (xy 34.129027 -282.933686)
			(xy 34.143434 -282.919362) (xy 34.162237 -282.911668) (xy 34.172398 -282.911296) (xy 35.571938 -282.911296)
			(xy 35.582062 -282.911794) (xy 35.600775 -282.919526) (xy 35.615129 -282.933808) (xy 35.622954 -282.952483)
			(xy 35.6235 -282.962604) (xy 35.6235 -283.371544) (xy 41.664636 -283.371544) (xy 41.664636 -282.962604)
			(xy 41.665026 -282.952446) (xy 41.672827 -282.933686) (xy 41.687234 -282.919362) (xy 41.706037 -282.911668)
			(xy 41.716198 -282.911296) (xy 43.115738 -282.911296) (xy 43.125862 -282.911794) (xy 43.144575 -282.919526)
			(xy 43.158929 -282.933808) (xy 43.166754 -282.952483) (xy 43.1673 -282.962604) (xy 43.1673 -283.371544)
			(xy 49.208436 -283.371544) (xy 49.208436 -282.962604) (xy 49.208826 -282.952446) (xy 49.216627 -282.933686)
			(xy 49.231034 -282.919362) (xy 49.249837 -282.911668) (xy 49.259998 -282.911296) (xy 50.659538 -282.911296)
			(xy 50.669662 -282.911794) (xy 50.688375 -282.919526) (xy 50.702729 -282.933808) (xy 50.710554 -282.952483)
			(xy 50.7111 -282.962604) (xy 50.7111 -283.371544) (xy 56.752236 -283.371544) (xy 56.752236 -282.962604)
			(xy 56.752626 -282.952446) (xy 56.760427 -282.933686) (xy 56.774834 -282.919362) (xy 56.793637 -282.911668)
			(xy 56.803798 -282.911296) (xy 58.203338 -282.911296) (xy 58.213462 -282.911794) (xy 58.232175 -282.919526)
			(xy 58.246529 -282.933808) (xy 58.254354 -282.952483) (xy 58.2549 -282.962604) (xy 58.2549 -283.371544)
			(xy 64.296036 -283.371544) (xy 64.296036 -282.962604) (xy 64.296426 -282.952446) (xy 64.304227 -282.933686)
			(xy 64.318634 -282.919362) (xy 64.337437 -282.911668) (xy 64.347598 -282.911296) (xy 65.747138 -282.911296)
			(xy 65.757262 -282.911794) (xy 65.775975 -282.919526) (xy 65.790329 -282.933808) (xy 65.798154 -282.952483)
			(xy 65.7987 -282.962604) (xy 65.7987 -283.371544) (xy 65.798314 -283.381701) (xy 65.790504 -283.400454)
			(xy 65.776097 -283.414776) (xy 65.757297 -283.422474) (xy 65.747138 -283.422852) (xy 64.347598 -283.422852)
			(xy 64.33747 -283.422375) (xy 64.318748 -283.414645) (xy 64.304391 -283.400356) (xy 64.296573 -283.381669)
			(xy 64.296036 -283.371544) (xy 58.2549 -283.371544) (xy 58.254514 -283.381701) (xy 58.246704 -283.400454)
			(xy 58.232297 -283.414776) (xy 58.213497 -283.422474) (xy 58.203338 -283.422852) (xy 56.803798 -283.422852)
			(xy 56.79367 -283.422375) (xy 56.774948 -283.414645) (xy 56.760591 -283.400356) (xy 56.752773 -283.381669)
			(xy 56.752236 -283.371544) (xy 50.7111 -283.371544) (xy 50.710714 -283.381701) (xy 50.702904 -283.400454)
			(xy 50.688497 -283.414776) (xy 50.669697 -283.422474) (xy 50.659538 -283.422852) (xy 49.259998 -283.422852)
			(xy 49.24987 -283.422375) (xy 49.231148 -283.414645) (xy 49.216791 -283.400356) (xy 49.208973 -283.381669)
			(xy 49.208436 -283.371544) (xy 43.1673 -283.371544) (xy 43.166914 -283.381701) (xy 43.159104 -283.400454)
			(xy 43.144697 -283.414776) (xy 43.125897 -283.422474) (xy 43.115738 -283.422852) (xy 41.716198 -283.422852)
			(xy 41.70607 -283.422375) (xy 41.687348 -283.414645) (xy 41.672991 -283.400356) (xy 41.665173 -283.381669)
			(xy 41.664636 -283.371544) (xy 35.6235 -283.371544) (xy 35.623114 -283.381701) (xy 35.615304 -283.400454)
			(xy 35.600897 -283.414776) (xy 35.582097 -283.422474) (xy 35.571938 -283.422852) (xy 34.172398 -283.422852)
			(xy 34.16227 -283.422375) (xy 34.143548 -283.414645) (xy 34.129191 -283.400356) (xy 34.121373 -283.381669)
			(xy 34.120836 -283.371544) (xy 28.0797 -283.371544) (xy 28.079314 -283.381701) (xy 28.071504 -283.400454)
			(xy 28.057097 -283.414776) (xy 28.038297 -283.422474) (xy 28.028138 -283.422852) (xy 26.628598 -283.422852)
			(xy 26.61847 -283.422375) (xy 26.599748 -283.414645) (xy 26.585391 -283.400356) (xy 26.577573 -283.381669)
			(xy 26.577036 -283.371544) (xy 20.5359 -283.371544) (xy 20.535514 -283.381701) (xy 20.527704 -283.400454)
			(xy 20.513297 -283.414776) (xy 20.494497 -283.422474) (xy 20.484338 -283.422852) (xy 19.084798 -283.422852)
			(xy 19.07467 -283.422375) (xy 19.055948 -283.414645) (xy 19.041591 -283.400356) (xy 19.033773 -283.381669)
			(xy 19.033236 -283.371544) (xy 12.9921 -283.371544) (xy 12.991714 -283.381701) (xy 12.983904 -283.400454)
			(xy 12.969497 -283.414776) (xy 12.950697 -283.422474) (xy 12.940538 -283.422852) (xy 11.540998 -283.422852)
			(xy 11.53087 -283.422375) (xy 11.512148 -283.414645) (xy 11.497791 -283.400356) (xy 11.489973 -283.381669)
			(xy 11.489436 -283.371544) (xy 2.509012 -283.371544) (xy 2.509012 -284.221428) (xy 7.389368 -284.221428)
			(xy 7.389368 -283.812488) (xy 7.389811 -283.802337) (xy 7.397604 -283.78359) (xy 7.411994 -283.769269)
			(xy 7.430777 -283.761564) (xy 7.44093 -283.76118) (xy 8.84047 -283.76118) (xy 8.8506 -283.761652)
			(xy 8.869328 -283.769377) (xy 8.883687 -283.783669) (xy 8.8915 -283.802361) (xy 8.892032 -283.812488)
			(xy 8.892032 -284.221428) (xy 11.489436 -284.221428) (xy 11.489436 -283.812488) (xy 11.489812 -283.802329)
			(xy 11.497619 -283.783569) (xy 11.51203 -283.769245) (xy 11.530836 -283.761552) (xy 11.540998 -283.76118)
			(xy 12.940538 -283.76118) (xy 12.950672 -283.761597) (xy 12.969402 -283.769344) (xy 12.983758 -283.783652)
			(xy 12.991569 -283.802356) (xy 12.9921 -283.812488) (xy 12.9921 -284.221428) (xy 14.933168 -284.221428)
			(xy 14.933168 -283.812488) (xy 14.933611 -283.802337) (xy 14.941404 -283.78359) (xy 14.955794 -283.769269)
			(xy 14.974577 -283.761564) (xy 14.98473 -283.76118) (xy 16.38427 -283.76118) (xy 16.3944 -283.761652)
			(xy 16.413128 -283.769377) (xy 16.427487 -283.783669) (xy 16.4353 -283.802361) (xy 16.435832 -283.812488)
			(xy 16.435832 -284.221428) (xy 19.033236 -284.221428) (xy 19.033236 -283.812488) (xy 19.033612 -283.802329)
			(xy 19.041419 -283.783569) (xy 19.05583 -283.769245) (xy 19.074636 -283.761552) (xy 19.084798 -283.76118)
			(xy 20.484338 -283.76118) (xy 20.494472 -283.761597) (xy 20.513202 -283.769344) (xy 20.527558 -283.783652)
			(xy 20.535369 -283.802356) (xy 20.5359 -283.812488) (xy 20.5359 -284.221428) (xy 22.476968 -284.221428)
			(xy 22.476968 -283.812488) (xy 22.477411 -283.802337) (xy 22.485204 -283.78359) (xy 22.499594 -283.769269)
			(xy 22.518377 -283.761564) (xy 22.52853 -283.76118) (xy 23.92807 -283.76118) (xy 23.9382 -283.761652)
			(xy 23.956928 -283.769377) (xy 23.971287 -283.783669) (xy 23.9791 -283.802361) (xy 23.979632 -283.812488)
			(xy 23.979632 -284.221428) (xy 26.577036 -284.221428) (xy 26.577036 -283.812488) (xy 26.577412 -283.802329)
			(xy 26.585219 -283.783569) (xy 26.59963 -283.769245) (xy 26.618436 -283.761552) (xy 26.628598 -283.76118)
			(xy 28.028138 -283.76118) (xy 28.038272 -283.761597) (xy 28.057002 -283.769344) (xy 28.071358 -283.783652)
			(xy 28.079169 -283.802356) (xy 28.0797 -283.812488) (xy 28.0797 -284.221428) (xy 30.020768 -284.221428)
			(xy 30.020768 -283.812488) (xy 30.021211 -283.802337) (xy 30.029004 -283.78359) (xy 30.043394 -283.769269)
			(xy 30.062177 -283.761564) (xy 30.07233 -283.76118) (xy 31.47187 -283.76118) (xy 31.482 -283.761652)
			(xy 31.500728 -283.769377) (xy 31.515087 -283.783669) (xy 31.5229 -283.802361) (xy 31.523432 -283.812488)
			(xy 31.523432 -284.221428) (xy 34.120836 -284.221428) (xy 34.120836 -283.812488) (xy 34.121212 -283.802329)
			(xy 34.129019 -283.783569) (xy 34.14343 -283.769245) (xy 34.162236 -283.761552) (xy 34.172398 -283.76118)
			(xy 35.571938 -283.76118) (xy 35.582072 -283.761597) (xy 35.600802 -283.769344) (xy 35.615158 -283.783652)
			(xy 35.622969 -283.802356) (xy 35.6235 -283.812488) (xy 35.6235 -284.221428) (xy 37.564568 -284.221428)
			(xy 37.564568 -283.812488) (xy 37.565011 -283.802337) (xy 37.572804 -283.78359) (xy 37.587194 -283.769269)
			(xy 37.605977 -283.761564) (xy 37.61613 -283.76118) (xy 39.01567 -283.76118) (xy 39.0258 -283.761652)
			(xy 39.044528 -283.769377) (xy 39.058887 -283.783669) (xy 39.0667 -283.802361) (xy 39.067232 -283.812488)
			(xy 39.067232 -284.221428) (xy 41.664636 -284.221428) (xy 41.664636 -283.812488) (xy 41.665012 -283.802329)
			(xy 41.672819 -283.783569) (xy 41.68723 -283.769245) (xy 41.706036 -283.761552) (xy 41.716198 -283.76118)
			(xy 43.115738 -283.76118) (xy 43.125872 -283.761597) (xy 43.144602 -283.769344) (xy 43.158958 -283.783652)
			(xy 43.166769 -283.802356) (xy 43.1673 -283.812488) (xy 43.1673 -284.221428) (xy 45.108368 -284.221428)
			(xy 45.108368 -283.812488) (xy 45.108811 -283.802337) (xy 45.116604 -283.78359) (xy 45.130994 -283.769269)
			(xy 45.149777 -283.761564) (xy 45.15993 -283.76118) (xy 46.55947 -283.76118) (xy 46.5696 -283.761652)
			(xy 46.588328 -283.769377) (xy 46.602687 -283.783669) (xy 46.6105 -283.802361) (xy 46.611032 -283.812488)
			(xy 46.611032 -284.221428) (xy 49.208436 -284.221428) (xy 49.208436 -283.812488) (xy 49.208812 -283.802329)
			(xy 49.216619 -283.783569) (xy 49.23103 -283.769245) (xy 49.249836 -283.761552) (xy 49.259998 -283.76118)
			(xy 50.659538 -283.76118) (xy 50.669672 -283.761597) (xy 50.688402 -283.769344) (xy 50.702758 -283.783652)
			(xy 50.710569 -283.802356) (xy 50.7111 -283.812488) (xy 50.7111 -284.221428) (xy 52.652168 -284.221428)
			(xy 52.652168 -283.812488) (xy 52.652611 -283.802337) (xy 52.660404 -283.78359) (xy 52.674794 -283.769269)
			(xy 52.693577 -283.761564) (xy 52.70373 -283.76118) (xy 54.10327 -283.76118) (xy 54.1134 -283.761652)
			(xy 54.132128 -283.769377) (xy 54.146487 -283.783669) (xy 54.1543 -283.802361) (xy 54.154832 -283.812488)
			(xy 54.154832 -284.221428) (xy 56.752236 -284.221428) (xy 56.752236 -283.812488) (xy 56.752612 -283.802329)
			(xy 56.760419 -283.783569) (xy 56.77483 -283.769245) (xy 56.793636 -283.761552) (xy 56.803798 -283.76118)
			(xy 58.203338 -283.76118) (xy 58.213472 -283.761597) (xy 58.232202 -283.769344) (xy 58.246558 -283.783652)
			(xy 58.254369 -283.802356) (xy 58.2549 -283.812488) (xy 58.2549 -284.221428) (xy 60.195968 -284.221428)
			(xy 60.195968 -283.812488) (xy 60.196411 -283.802337) (xy 60.204204 -283.78359) (xy 60.218594 -283.769269)
			(xy 60.237377 -283.761564) (xy 60.24753 -283.76118) (xy 61.64707 -283.76118) (xy 61.6572 -283.761652)
			(xy 61.675928 -283.769377) (xy 61.690287 -283.783669) (xy 61.6981 -283.802361) (xy 61.698632 -283.812488)
			(xy 61.698632 -284.221428) (xy 64.296036 -284.221428) (xy 64.296036 -283.812488) (xy 64.296412 -283.802329)
			(xy 64.304219 -283.783569) (xy 64.31863 -283.769245) (xy 64.337436 -283.761552) (xy 64.347598 -283.76118)
			(xy 65.747138 -283.76118) (xy 65.757272 -283.761597) (xy 65.776002 -283.769344) (xy 65.790358 -283.783652)
			(xy 65.798169 -283.802356) (xy 65.7987 -283.812488) (xy 65.7987 -284.033722) (xy 86.515956 -284.033722)
			(xy 86.516464 -284.007815) (xy 86.52457 -283.956638) (xy 86.540582 -283.907359) (xy 86.564105 -283.861192)
			(xy 86.594561 -283.819273) (xy 86.631199 -283.782635) (xy 86.673118 -283.752179) (xy 86.719285 -283.728656)
			(xy 86.768564 -283.712644) (xy 86.819741 -283.704538) (xy 86.871555 -283.704538) (xy 86.922732 -283.712644)
			(xy 86.972011 -283.728656) (xy 87.018178 -283.752179) (xy 87.060097 -283.782635) (xy 87.096735 -283.819273)
			(xy 87.127191 -283.861192) (xy 87.150714 -283.907359) (xy 87.166726 -283.956638) (xy 87.174832 -284.007815)
			(xy 87.17534 -284.033722) (xy 87.174755 -284.06144) (xy 87.165426 -284.116086) (xy 87.156798 -284.142434)
			(xy 87.148924 -284.164532) (xy 87.181791 -284.221428) (xy 158.062168 -284.221428) (xy 158.062168 -283.812488)
			(xy 158.062611 -283.802337) (xy 158.070404 -283.78359) (xy 158.084794 -283.769269) (xy 158.103577 -283.761564)
			(xy 158.11373 -283.76118) (xy 159.51327 -283.76118) (xy 159.5234 -283.761652) (xy 159.542128 -283.769377)
			(xy 159.556487 -283.783669) (xy 159.5643 -283.802361) (xy 159.564832 -283.812488) (xy 159.564832 -284.221428)
			(xy 162.162236 -284.221428) (xy 162.162236 -283.812488) (xy 162.162612 -283.802329) (xy 162.170419 -283.783569)
			(xy 162.18483 -283.769245) (xy 162.203636 -283.761552) (xy 162.213798 -283.76118) (xy 163.613338 -283.76118)
			(xy 163.623472 -283.761597) (xy 163.642202 -283.769344) (xy 163.656558 -283.783652) (xy 163.664369 -283.802356)
			(xy 163.6649 -283.812488) (xy 163.6649 -284.221428) (xy 165.605968 -284.221428) (xy 165.605968 -283.812488)
			(xy 165.606411 -283.802337) (xy 165.614204 -283.78359) (xy 165.628594 -283.769269) (xy 165.647377 -283.761564)
			(xy 165.65753 -283.76118) (xy 167.05707 -283.76118) (xy 167.0672 -283.761652) (xy 167.085928 -283.769377)
			(xy 167.100287 -283.783669) (xy 167.1081 -283.802361) (xy 167.108632 -283.812488) (xy 167.108632 -284.221428)
			(xy 169.706036 -284.221428) (xy 169.706036 -283.812488) (xy 169.706412 -283.802329) (xy 169.714219 -283.783569)
			(xy 169.72863 -283.769245) (xy 169.747436 -283.761552) (xy 169.757598 -283.76118) (xy 171.157138 -283.76118)
			(xy 171.167272 -283.761597) (xy 171.186002 -283.769344) (xy 171.200358 -283.783652) (xy 171.208169 -283.802356)
			(xy 171.2087 -283.812488) (xy 171.2087 -284.221428) (xy 173.149768 -284.221428) (xy 173.149768 -283.812488)
			(xy 173.150211 -283.802337) (xy 173.158004 -283.78359) (xy 173.172394 -283.769269) (xy 173.191177 -283.761564)
			(xy 173.20133 -283.76118) (xy 174.60087 -283.76118) (xy 174.611 -283.761652) (xy 174.629728 -283.769377)
			(xy 174.644087 -283.783669) (xy 174.6519 -283.802361) (xy 174.652432 -283.812488) (xy 174.652432 -284.221428)
			(xy 177.249836 -284.221428) (xy 177.249836 -283.812488) (xy 177.250212 -283.802329) (xy 177.258019 -283.783569)
			(xy 177.27243 -283.769245) (xy 177.291236 -283.761552) (xy 177.301398 -283.76118) (xy 178.700938 -283.76118)
			(xy 178.711072 -283.761597) (xy 178.729802 -283.769344) (xy 178.744158 -283.783652) (xy 178.751969 -283.802356)
			(xy 178.7525 -283.812488) (xy 178.7525 -284.221428) (xy 180.693568 -284.221428) (xy 180.693568 -283.812488)
			(xy 180.694011 -283.802337) (xy 180.701804 -283.78359) (xy 180.716194 -283.769269) (xy 180.734977 -283.761564)
			(xy 180.74513 -283.76118) (xy 182.14467 -283.76118) (xy 182.1548 -283.761652) (xy 182.173528 -283.769377)
			(xy 182.187887 -283.783669) (xy 182.1957 -283.802361) (xy 182.196232 -283.812488) (xy 182.196232 -284.221428)
			(xy 184.793636 -284.221428) (xy 184.793636 -283.812488) (xy 184.794012 -283.802329) (xy 184.801819 -283.783569)
			(xy 184.81623 -283.769245) (xy 184.835036 -283.761552) (xy 184.845198 -283.76118) (xy 186.244738 -283.76118)
			(xy 186.254872 -283.761597) (xy 186.273602 -283.769344) (xy 186.287958 -283.783652) (xy 186.295769 -283.802356)
			(xy 186.2963 -283.812488) (xy 186.2963 -284.221428) (xy 188.237368 -284.221428) (xy 188.237368 -283.812488)
			(xy 188.237811 -283.802337) (xy 188.245604 -283.78359) (xy 188.259994 -283.769269) (xy 188.278777 -283.761564)
			(xy 188.28893 -283.76118) (xy 189.68847 -283.76118) (xy 189.6986 -283.761652) (xy 189.717328 -283.769377)
			(xy 189.731687 -283.783669) (xy 189.7395 -283.802361) (xy 189.740032 -283.812488) (xy 189.740032 -284.221428)
			(xy 192.337436 -284.221428) (xy 192.337436 -283.812488) (xy 192.337812 -283.802329) (xy 192.345619 -283.783569)
			(xy 192.36003 -283.769245) (xy 192.378836 -283.761552) (xy 192.388998 -283.76118) (xy 193.788538 -283.76118)
			(xy 193.798672 -283.761597) (xy 193.817402 -283.769344) (xy 193.831758 -283.783652) (xy 193.839569 -283.802356)
			(xy 193.8401 -283.812488) (xy 193.8401 -284.221428) (xy 195.781168 -284.221428) (xy 195.781168 -283.812488)
			(xy 195.781611 -283.802337) (xy 195.789404 -283.78359) (xy 195.803794 -283.769269) (xy 195.822577 -283.761564)
			(xy 195.83273 -283.76118) (xy 197.23227 -283.76118) (xy 197.2424 -283.761652) (xy 197.261128 -283.769377)
			(xy 197.275487 -283.783669) (xy 197.2833 -283.802361) (xy 197.283832 -283.812488) (xy 197.283832 -284.221428)
			(xy 199.881236 -284.221428) (xy 199.881236 -283.812488) (xy 199.881612 -283.802329) (xy 199.889419 -283.783569)
			(xy 199.90383 -283.769245) (xy 199.922636 -283.761552) (xy 199.932798 -283.76118) (xy 201.332338 -283.76118)
			(xy 201.342472 -283.761597) (xy 201.361202 -283.769344) (xy 201.375558 -283.783652) (xy 201.383369 -283.802356)
			(xy 201.3839 -283.812488) (xy 201.3839 -284.221428) (xy 203.324968 -284.221428) (xy 203.324968 -283.812488)
			(xy 203.325411 -283.802337) (xy 203.333204 -283.78359) (xy 203.347594 -283.769269) (xy 203.366377 -283.761564)
			(xy 203.37653 -283.76118) (xy 204.77607 -283.76118) (xy 204.7862 -283.761652) (xy 204.804928 -283.769377)
			(xy 204.819287 -283.783669) (xy 204.8271 -283.802361) (xy 204.827632 -283.812488) (xy 204.827632 -284.221428)
			(xy 207.425036 -284.221428) (xy 207.425036 -283.812488) (xy 207.425412 -283.802329) (xy 207.433219 -283.783569)
			(xy 207.44763 -283.769245) (xy 207.466436 -283.761552) (xy 207.476598 -283.76118) (xy 208.876138 -283.76118)
			(xy 208.886272 -283.761597) (xy 208.905002 -283.769344) (xy 208.919358 -283.783652) (xy 208.927169 -283.802356)
			(xy 208.9277 -283.812488) (xy 208.9277 -284.221428) (xy 210.868768 -284.221428) (xy 210.868768 -283.812488)
			(xy 210.869211 -283.802337) (xy 210.877004 -283.78359) (xy 210.891394 -283.769269) (xy 210.910177 -283.761564)
			(xy 210.92033 -283.76118) (xy 212.31987 -283.76118) (xy 212.33 -283.761652) (xy 212.348728 -283.769377)
			(xy 212.363087 -283.783669) (xy 212.3709 -283.802361) (xy 212.371432 -283.812488) (xy 212.371432 -284.221428)
			(xy 214.968836 -284.221428) (xy 214.968836 -283.812488) (xy 214.969212 -283.802329) (xy 214.977019 -283.783569)
			(xy 214.99143 -283.769245) (xy 215.010236 -283.761552) (xy 215.020398 -283.76118) (xy 216.419938 -283.76118)
			(xy 216.430072 -283.761597) (xy 216.448802 -283.769344) (xy 216.463158 -283.783652) (xy 216.470969 -283.802356)
			(xy 216.4715 -283.812488) (xy 216.4715 -284.221428) (xy 255.329436 -284.221428) (xy 255.329436 -283.812488)
			(xy 255.329812 -283.802329) (xy 255.337619 -283.783569) (xy 255.35203 -283.769245) (xy 255.370836 -283.761552)
			(xy 255.380998 -283.76118) (xy 256.780538 -283.76118) (xy 256.790672 -283.761597) (xy 256.809402 -283.769344)
			(xy 256.823758 -283.783652) (xy 256.831569 -283.802356) (xy 256.8321 -283.812488) (xy 256.8321 -284.221428)
			(xy 259.429504 -284.221428) (xy 259.429504 -283.812488) (xy 259.429912 -283.802333) (xy 259.437712 -283.783579)
			(xy 259.452113 -283.769256) (xy 259.470908 -283.761557) (xy 259.481066 -283.76118) (xy 260.880606 -283.76118)
			(xy 260.890738 -283.761623) (xy 260.909467 -283.76936) (xy 260.923824 -283.78366) (xy 260.931636 -283.802358)
			(xy 260.932168 -283.812488) (xy 260.932168 -284.221428) (xy 262.873236 -284.221428) (xy 262.873236 -283.812488)
			(xy 262.873612 -283.802329) (xy 262.881419 -283.783569) (xy 262.89583 -283.769245) (xy 262.914636 -283.761552)
			(xy 262.924798 -283.76118) (xy 264.324338 -283.76118) (xy 264.334472 -283.761597) (xy 264.353202 -283.769344)
			(xy 264.367558 -283.783652) (xy 264.375369 -283.802356) (xy 264.3759 -283.812488) (xy 264.3759 -284.221428)
			(xy 266.973304 -284.221428) (xy 266.973304 -283.812488) (xy 266.973712 -283.802333) (xy 266.981512 -283.783579)
			(xy 266.995913 -283.769256) (xy 267.014708 -283.761557) (xy 267.024866 -283.76118) (xy 268.424406 -283.76118)
			(xy 268.434538 -283.761623) (xy 268.453267 -283.76936) (xy 268.467624 -283.78366) (xy 268.475436 -283.802358)
			(xy 268.475968 -283.812488) (xy 268.475968 -284.221428) (xy 270.417036 -284.221428) (xy 270.417036 -283.812488)
			(xy 270.417412 -283.802329) (xy 270.425219 -283.783569) (xy 270.43963 -283.769245) (xy 270.458436 -283.761552)
			(xy 270.468598 -283.76118) (xy 271.868138 -283.76118) (xy 271.878272 -283.761597) (xy 271.897002 -283.769344)
			(xy 271.911358 -283.783652) (xy 271.919169 -283.802356) (xy 271.9197 -283.812488) (xy 271.9197 -284.221428)
			(xy 274.517104 -284.221428) (xy 274.517104 -283.812488) (xy 274.517512 -283.802333) (xy 274.525312 -283.783579)
			(xy 274.539713 -283.769256) (xy 274.558508 -283.761557) (xy 274.568666 -283.76118) (xy 275.968206 -283.76118)
			(xy 275.978338 -283.761623) (xy 275.997067 -283.76936) (xy 276.011424 -283.78366) (xy 276.019236 -283.802358)
			(xy 276.019768 -283.812488) (xy 276.019768 -284.221428) (xy 277.960836 -284.221428) (xy 277.960836 -283.812488)
			(xy 277.961212 -283.802329) (xy 277.969019 -283.783569) (xy 277.98343 -283.769245) (xy 278.002236 -283.761552)
			(xy 278.012398 -283.76118) (xy 279.411938 -283.76118) (xy 279.422072 -283.761597) (xy 279.440802 -283.769344)
			(xy 279.455158 -283.783652) (xy 279.462969 -283.802356) (xy 279.4635 -283.812488) (xy 279.4635 -284.221428)
			(xy 282.060904 -284.221428) (xy 282.060904 -283.812488) (xy 282.061312 -283.802333) (xy 282.069112 -283.783579)
			(xy 282.083513 -283.769256) (xy 282.102308 -283.761557) (xy 282.112466 -283.76118) (xy 283.512006 -283.76118)
			(xy 283.522138 -283.761623) (xy 283.540867 -283.76936) (xy 283.555224 -283.78366) (xy 283.563036 -283.802358)
			(xy 283.563568 -283.812488) (xy 283.563568 -284.221428) (xy 285.504636 -284.221428) (xy 285.504636 -283.812488)
			(xy 285.505012 -283.802329) (xy 285.512819 -283.783569) (xy 285.52723 -283.769245) (xy 285.546036 -283.761552)
			(xy 285.556198 -283.76118) (xy 286.955738 -283.76118) (xy 286.965872 -283.761597) (xy 286.984602 -283.769344)
			(xy 286.998958 -283.783652) (xy 287.006769 -283.802356) (xy 287.0073 -283.812488) (xy 287.0073 -284.221428)
			(xy 289.604704 -284.221428) (xy 289.604704 -283.812488) (xy 289.605112 -283.802333) (xy 289.612912 -283.783579)
			(xy 289.627313 -283.769256) (xy 289.646108 -283.761557) (xy 289.656266 -283.76118) (xy 291.055806 -283.76118)
			(xy 291.065938 -283.761623) (xy 291.084667 -283.76936) (xy 291.099024 -283.78366) (xy 291.106836 -283.802358)
			(xy 291.107368 -283.812488) (xy 291.107368 -284.221428) (xy 293.048436 -284.221428) (xy 293.048436 -283.812488)
			(xy 293.048812 -283.802329) (xy 293.056619 -283.783569) (xy 293.07103 -283.769245) (xy 293.089836 -283.761552)
			(xy 293.099998 -283.76118) (xy 294.499538 -283.76118) (xy 294.509672 -283.761597) (xy 294.528402 -283.769344)
			(xy 294.542758 -283.783652) (xy 294.550569 -283.802356) (xy 294.5511 -283.812488) (xy 294.5511 -284.221428)
			(xy 297.148504 -284.221428) (xy 297.148504 -283.812488) (xy 297.148912 -283.802333) (xy 297.156712 -283.783579)
			(xy 297.171113 -283.769256) (xy 297.189908 -283.761557) (xy 297.200066 -283.76118) (xy 298.599606 -283.76118)
			(xy 298.609738 -283.761623) (xy 298.628467 -283.76936) (xy 298.642824 -283.78366) (xy 298.650636 -283.802358)
			(xy 298.651168 -283.812488) (xy 298.651168 -284.221428) (xy 300.592236 -284.221428) (xy 300.592236 -283.812488)
			(xy 300.592612 -283.802329) (xy 300.600419 -283.783569) (xy 300.61483 -283.769245) (xy 300.633636 -283.761552)
			(xy 300.643798 -283.76118) (xy 302.043338 -283.76118) (xy 302.053472 -283.761597) (xy 302.072202 -283.769344)
			(xy 302.086558 -283.783652) (xy 302.094369 -283.802356) (xy 302.0949 -283.812488) (xy 302.0949 -284.221428)
			(xy 304.692304 -284.221428) (xy 304.692304 -283.812488) (xy 304.692712 -283.802333) (xy 304.700512 -283.783579)
			(xy 304.714913 -283.769256) (xy 304.733708 -283.761557) (xy 304.743866 -283.76118) (xy 306.143406 -283.76118)
			(xy 306.153538 -283.761623) (xy 306.172267 -283.76936) (xy 306.186624 -283.78366) (xy 306.194436 -283.802358)
			(xy 306.194968 -283.812488) (xy 306.194968 -284.221428) (xy 308.136036 -284.221428) (xy 308.136036 -283.812488)
			(xy 308.136412 -283.802329) (xy 308.144219 -283.783569) (xy 308.15863 -283.769245) (xy 308.177436 -283.761552)
			(xy 308.187598 -283.76118) (xy 309.587138 -283.76118) (xy 309.597272 -283.761597) (xy 309.616002 -283.769344)
			(xy 309.630358 -283.783652) (xy 309.638169 -283.802356) (xy 309.6387 -283.812488) (xy 309.6387 -284.221428)
			(xy 312.236104 -284.221428) (xy 312.236104 -283.812488) (xy 312.236512 -283.802333) (xy 312.244312 -283.783579)
			(xy 312.258713 -283.769256) (xy 312.277508 -283.761557) (xy 312.287666 -283.76118) (xy 313.687206 -283.76118)
			(xy 313.697338 -283.761623) (xy 313.716067 -283.76936) (xy 313.730424 -283.78366) (xy 313.738236 -283.802358)
			(xy 313.738768 -283.812488) (xy 313.738768 -284.033722) (xy 334.456024 -284.033722) (xy 334.456532 -284.007815)
			(xy 334.464638 -283.956638) (xy 334.48065 -283.907359) (xy 334.504173 -283.861192) (xy 334.534629 -283.819273)
			(xy 334.571267 -283.782635) (xy 334.613186 -283.752179) (xy 334.659353 -283.728656) (xy 334.708632 -283.712644)
			(xy 334.759809 -283.704538) (xy 334.811623 -283.704538) (xy 334.8628 -283.712644) (xy 334.912079 -283.728656)
			(xy 334.958246 -283.752179) (xy 335.000165 -283.782635) (xy 335.036803 -283.819273) (xy 335.067259 -283.861192)
			(xy 335.090782 -283.907359) (xy 335.106794 -283.956638) (xy 335.1149 -284.007815) (xy 335.115408 -284.033722)
			(xy 335.114819 -284.06144) (xy 335.105492 -284.116086) (xy 335.096866 -284.142434) (xy 335.088992 -284.164532)
			(xy 335.121859 -284.221428) (xy 406.002236 -284.221428) (xy 406.002236 -283.812488) (xy 406.002612 -283.802329)
			(xy 406.010419 -283.783569) (xy 406.02483 -283.769245) (xy 406.043636 -283.761552) (xy 406.053798 -283.76118)
			(xy 407.453338 -283.76118) (xy 407.463472 -283.761597) (xy 407.482202 -283.769344) (xy 407.496558 -283.783652)
			(xy 407.504369 -283.802356) (xy 407.5049 -283.812488) (xy 407.5049 -284.221428) (xy 410.102304 -284.221428)
			(xy 410.102304 -283.812488) (xy 410.102712 -283.802333) (xy 410.110512 -283.783579) (xy 410.124913 -283.769256)
			(xy 410.143708 -283.761557) (xy 410.153866 -283.76118) (xy 411.553406 -283.76118) (xy 411.563538 -283.761623)
			(xy 411.582267 -283.76936) (xy 411.596624 -283.78366) (xy 411.604436 -283.802358) (xy 411.604968 -283.812488)
			(xy 411.604968 -284.221428) (xy 413.546036 -284.221428) (xy 413.546036 -283.812488) (xy 413.546412 -283.802329)
			(xy 413.554219 -283.783569) (xy 413.56863 -283.769245) (xy 413.587436 -283.761552) (xy 413.597598 -283.76118)
			(xy 414.997138 -283.76118) (xy 415.007272 -283.761597) (xy 415.026002 -283.769344) (xy 415.040358 -283.783652)
			(xy 415.048169 -283.802356) (xy 415.0487 -283.812488) (xy 415.0487 -284.221428) (xy 417.646104 -284.221428)
			(xy 417.646104 -283.812488) (xy 417.646512 -283.802333) (xy 417.654312 -283.783579) (xy 417.668713 -283.769256)
			(xy 417.687508 -283.761557) (xy 417.697666 -283.76118) (xy 419.097206 -283.76118) (xy 419.107338 -283.761623)
			(xy 419.126067 -283.76936) (xy 419.140424 -283.78366) (xy 419.148236 -283.802358) (xy 419.148768 -283.812488)
			(xy 419.148768 -284.221428) (xy 421.089836 -284.221428) (xy 421.089836 -283.812488) (xy 421.090212 -283.802329)
			(xy 421.098019 -283.783569) (xy 421.11243 -283.769245) (xy 421.131236 -283.761552) (xy 421.141398 -283.76118)
			(xy 422.540938 -283.76118) (xy 422.551072 -283.761597) (xy 422.569802 -283.769344) (xy 422.584158 -283.783652)
			(xy 422.591969 -283.802356) (xy 422.5925 -283.812488) (xy 422.5925 -284.221428) (xy 425.189904 -284.221428)
			(xy 425.189904 -283.812488) (xy 425.190312 -283.802333) (xy 425.198112 -283.783579) (xy 425.212513 -283.769256)
			(xy 425.231308 -283.761557) (xy 425.241466 -283.76118) (xy 426.641006 -283.76118) (xy 426.651138 -283.761623)
			(xy 426.669867 -283.76936) (xy 426.684224 -283.78366) (xy 426.692036 -283.802358) (xy 426.692568 -283.812488)
			(xy 426.692568 -284.221428) (xy 428.633636 -284.221428) (xy 428.633636 -283.812488) (xy 428.634012 -283.802329)
			(xy 428.641819 -283.783569) (xy 428.65623 -283.769245) (xy 428.675036 -283.761552) (xy 428.685198 -283.76118)
			(xy 430.084738 -283.76118) (xy 430.094872 -283.761597) (xy 430.113602 -283.769344) (xy 430.127958 -283.783652)
			(xy 430.135769 -283.802356) (xy 430.1363 -283.812488) (xy 430.1363 -284.221428) (xy 432.733704 -284.221428)
			(xy 432.733704 -283.812488) (xy 432.734112 -283.802333) (xy 432.741912 -283.783579) (xy 432.756313 -283.769256)
			(xy 432.775108 -283.761557) (xy 432.785266 -283.76118) (xy 434.184806 -283.76118) (xy 434.194938 -283.761623)
			(xy 434.213667 -283.76936) (xy 434.228024 -283.78366) (xy 434.235836 -283.802358) (xy 434.236368 -283.812488)
			(xy 434.236368 -284.221428) (xy 436.177436 -284.221428) (xy 436.177436 -283.812488) (xy 436.177812 -283.802329)
			(xy 436.185619 -283.783569) (xy 436.20003 -283.769245) (xy 436.218836 -283.761552) (xy 436.228998 -283.76118)
			(xy 437.628538 -283.76118) (xy 437.638672 -283.761597) (xy 437.657402 -283.769344) (xy 437.671758 -283.783652)
			(xy 437.679569 -283.802356) (xy 437.6801 -283.812488) (xy 437.6801 -284.221428) (xy 440.277504 -284.221428)
			(xy 440.277504 -283.812488) (xy 440.277912 -283.802333) (xy 440.285712 -283.783579) (xy 440.300113 -283.769256)
			(xy 440.318908 -283.761557) (xy 440.329066 -283.76118) (xy 441.728606 -283.76118) (xy 441.738738 -283.761623)
			(xy 441.757467 -283.76936) (xy 441.771824 -283.78366) (xy 441.779636 -283.802358) (xy 441.780168 -283.812488)
			(xy 441.780168 -284.221428) (xy 443.721236 -284.221428) (xy 443.721236 -283.812488) (xy 443.721612 -283.802329)
			(xy 443.729419 -283.783569) (xy 443.74383 -283.769245) (xy 443.762636 -283.761552) (xy 443.772798 -283.76118)
			(xy 445.172338 -283.76118) (xy 445.182472 -283.761597) (xy 445.201202 -283.769344) (xy 445.215558 -283.783652)
			(xy 445.223369 -283.802356) (xy 445.2239 -283.812488) (xy 445.2239 -284.221428) (xy 447.821304 -284.221428)
			(xy 447.821304 -283.812488) (xy 447.821712 -283.802333) (xy 447.829512 -283.783579) (xy 447.843913 -283.769256)
			(xy 447.862708 -283.761557) (xy 447.872866 -283.76118) (xy 449.272406 -283.76118) (xy 449.282538 -283.761623)
			(xy 449.301267 -283.76936) (xy 449.315624 -283.78366) (xy 449.323436 -283.802358) (xy 449.323968 -283.812488)
			(xy 449.323968 -284.221428) (xy 451.265036 -284.221428) (xy 451.265036 -283.812488) (xy 451.265412 -283.802329)
			(xy 451.273219 -283.783569) (xy 451.28763 -283.769245) (xy 451.306436 -283.761552) (xy 451.316598 -283.76118)
			(xy 452.716138 -283.76118) (xy 452.726272 -283.761597) (xy 452.745002 -283.769344) (xy 452.759358 -283.783652)
			(xy 452.767169 -283.802356) (xy 452.7677 -283.812488) (xy 452.7677 -284.221428) (xy 455.365104 -284.221428)
			(xy 455.365104 -283.812488) (xy 455.365512 -283.802333) (xy 455.373312 -283.783579) (xy 455.387713 -283.769256)
			(xy 455.406508 -283.761557) (xy 455.416666 -283.76118) (xy 456.816206 -283.76118) (xy 456.826338 -283.761623)
			(xy 456.845067 -283.76936) (xy 456.859424 -283.78366) (xy 456.867236 -283.802358) (xy 456.867768 -283.812488)
			(xy 456.867768 -284.221428) (xy 458.808836 -284.221428) (xy 458.808836 -283.812488) (xy 458.809212 -283.802329)
			(xy 458.817019 -283.783569) (xy 458.83143 -283.769245) (xy 458.850236 -283.761552) (xy 458.860398 -283.76118)
			(xy 460.259938 -283.76118) (xy 460.270072 -283.761597) (xy 460.288802 -283.769344) (xy 460.303158 -283.783652)
			(xy 460.310969 -283.802356) (xy 460.3115 -283.812488) (xy 460.3115 -284.221428) (xy 462.908904 -284.221428)
			(xy 462.908904 -283.812488) (xy 462.909312 -283.802333) (xy 462.917112 -283.783579) (xy 462.931513 -283.769256)
			(xy 462.950308 -283.761557) (xy 462.960466 -283.76118) (xy 464.360006 -283.76118) (xy 464.370138 -283.761623)
			(xy 464.388867 -283.76936) (xy 464.403224 -283.78366) (xy 464.411036 -283.802358) (xy 464.411568 -283.812488)
			(xy 464.411568 -284.221428) (xy 464.411201 -284.231588) (xy 464.40339 -284.250347) (xy 464.388976 -284.264671)
			(xy 464.370168 -284.272364) (xy 464.360006 -284.272736) (xy 462.960466 -284.272736) (xy 462.950334 -284.272301)
			(xy 462.931608 -284.264557) (xy 462.917252 -284.250255) (xy 462.909438 -284.231558) (xy 462.908904 -284.221428)
			(xy 460.3115 -284.221428) (xy 460.311101 -284.231584) (xy 460.303297 -284.250337) (xy 460.288893 -284.264659)
			(xy 460.270096 -284.272358) (xy 460.259938 -284.272736) (xy 458.860398 -284.272736) (xy 458.850268 -284.272274)
			(xy 458.831543 -284.264541) (xy 458.817185 -284.250247) (xy 458.809371 -284.231556) (xy 458.808836 -284.221428)
			(xy 456.867768 -284.221428) (xy 456.867401 -284.231588) (xy 456.85959 -284.250347) (xy 456.845176 -284.264671)
			(xy 456.826368 -284.272364) (xy 456.816206 -284.272736) (xy 455.416666 -284.272736) (xy 455.406534 -284.272301)
			(xy 455.387808 -284.264557) (xy 455.373452 -284.250255) (xy 455.365638 -284.231558) (xy 455.365104 -284.221428)
			(xy 452.7677 -284.221428) (xy 452.767301 -284.231584) (xy 452.759497 -284.250337) (xy 452.745093 -284.264659)
			(xy 452.726296 -284.272358) (xy 452.716138 -284.272736) (xy 451.316598 -284.272736) (xy 451.306468 -284.272274)
			(xy 451.287743 -284.264541) (xy 451.273385 -284.250247) (xy 451.265571 -284.231556) (xy 451.265036 -284.221428)
			(xy 449.323968 -284.221428) (xy 449.323601 -284.231588) (xy 449.31579 -284.250347) (xy 449.301376 -284.264671)
			(xy 449.282568 -284.272364) (xy 449.272406 -284.272736) (xy 447.872866 -284.272736) (xy 447.862734 -284.272301)
			(xy 447.844008 -284.264557) (xy 447.829652 -284.250255) (xy 447.821838 -284.231558) (xy 447.821304 -284.221428)
			(xy 445.2239 -284.221428) (xy 445.223501 -284.231584) (xy 445.215697 -284.250337) (xy 445.201293 -284.264659)
			(xy 445.182496 -284.272358) (xy 445.172338 -284.272736) (xy 443.772798 -284.272736) (xy 443.762668 -284.272274)
			(xy 443.743943 -284.264541) (xy 443.729585 -284.250247) (xy 443.721771 -284.231556) (xy 443.721236 -284.221428)
			(xy 441.780168 -284.221428) (xy 441.779801 -284.231588) (xy 441.77199 -284.250347) (xy 441.757576 -284.264671)
			(xy 441.738768 -284.272364) (xy 441.728606 -284.272736) (xy 440.329066 -284.272736) (xy 440.318934 -284.272301)
			(xy 440.300208 -284.264557) (xy 440.285852 -284.250255) (xy 440.278038 -284.231558) (xy 440.277504 -284.221428)
			(xy 437.6801 -284.221428) (xy 437.679701 -284.231584) (xy 437.671897 -284.250337) (xy 437.657493 -284.264659)
			(xy 437.638696 -284.272358) (xy 437.628538 -284.272736) (xy 436.228998 -284.272736) (xy 436.218868 -284.272274)
			(xy 436.200143 -284.264541) (xy 436.185785 -284.250247) (xy 436.177971 -284.231556) (xy 436.177436 -284.221428)
			(xy 434.236368 -284.221428) (xy 434.236001 -284.231588) (xy 434.22819 -284.250347) (xy 434.213776 -284.264671)
			(xy 434.194968 -284.272364) (xy 434.184806 -284.272736) (xy 432.785266 -284.272736) (xy 432.775134 -284.272301)
			(xy 432.756408 -284.264557) (xy 432.742052 -284.250255) (xy 432.734238 -284.231558) (xy 432.733704 -284.221428)
			(xy 430.1363 -284.221428) (xy 430.135901 -284.231584) (xy 430.128097 -284.250337) (xy 430.113693 -284.264659)
			(xy 430.094896 -284.272358) (xy 430.084738 -284.272736) (xy 428.685198 -284.272736) (xy 428.675068 -284.272274)
			(xy 428.656343 -284.264541) (xy 428.641985 -284.250247) (xy 428.634171 -284.231556) (xy 428.633636 -284.221428)
			(xy 426.692568 -284.221428) (xy 426.692201 -284.231588) (xy 426.68439 -284.250347) (xy 426.669976 -284.264671)
			(xy 426.651168 -284.272364) (xy 426.641006 -284.272736) (xy 425.241466 -284.272736) (xy 425.231334 -284.272301)
			(xy 425.212608 -284.264557) (xy 425.198252 -284.250255) (xy 425.190438 -284.231558) (xy 425.189904 -284.221428)
			(xy 422.5925 -284.221428) (xy 422.592101 -284.231584) (xy 422.584297 -284.250337) (xy 422.569893 -284.264659)
			(xy 422.551096 -284.272358) (xy 422.540938 -284.272736) (xy 421.141398 -284.272736) (xy 421.131268 -284.272274)
			(xy 421.112543 -284.264541) (xy 421.098185 -284.250247) (xy 421.090371 -284.231556) (xy 421.089836 -284.221428)
			(xy 419.148768 -284.221428) (xy 419.148401 -284.231588) (xy 419.14059 -284.250347) (xy 419.126176 -284.264671)
			(xy 419.107368 -284.272364) (xy 419.097206 -284.272736) (xy 417.697666 -284.272736) (xy 417.687534 -284.272301)
			(xy 417.668808 -284.264557) (xy 417.654452 -284.250255) (xy 417.646638 -284.231558) (xy 417.646104 -284.221428)
			(xy 415.0487 -284.221428) (xy 415.048301 -284.231584) (xy 415.040497 -284.250337) (xy 415.026093 -284.264659)
			(xy 415.007296 -284.272358) (xy 414.997138 -284.272736) (xy 413.597598 -284.272736) (xy 413.587468 -284.272274)
			(xy 413.568743 -284.264541) (xy 413.554385 -284.250247) (xy 413.546571 -284.231556) (xy 413.546036 -284.221428)
			(xy 411.604968 -284.221428) (xy 411.604601 -284.231588) (xy 411.59679 -284.250347) (xy 411.582376 -284.264671)
			(xy 411.563568 -284.272364) (xy 411.553406 -284.272736) (xy 410.153866 -284.272736) (xy 410.143734 -284.272301)
			(xy 410.125008 -284.264557) (xy 410.110652 -284.250255) (xy 410.102838 -284.231558) (xy 410.102304 -284.221428)
			(xy 407.5049 -284.221428) (xy 407.504501 -284.231584) (xy 407.496697 -284.250337) (xy 407.482293 -284.264659)
			(xy 407.463496 -284.272358) (xy 407.453338 -284.272736) (xy 406.053798 -284.272736) (xy 406.043668 -284.272274)
			(xy 406.024943 -284.264541) (xy 406.010585 -284.250247) (xy 406.002771 -284.231556) (xy 406.002236 -284.221428)
			(xy 335.121859 -284.221428) (xy 335.29397 -284.51937) (xy 335.31683 -284.523688) (xy 335.341643 -284.528833)
			(xy 335.389384 -284.545828) (xy 335.433962 -284.569927) (xy 335.474328 -284.600564) (xy 335.50953 -284.637016)
			(xy 335.538741 -284.678425) (xy 335.561271 -284.723817) (xy 335.576591 -284.772121) (xy 335.584339 -284.8222)
			(xy 335.5848 -284.847538) (xy 335.584292 -284.873425) (xy 335.576193 -284.924563) (xy 335.560194 -284.973803)
			(xy 335.536688 -285.019935) (xy 335.506256 -285.061822) (xy 335.469646 -285.098432) (xy 335.427759 -285.128864)
			(xy 335.381627 -285.15237) (xy 335.332387 -285.168369) (xy 335.281249 -285.176468) (xy 335.229475 -285.176468)
			(xy 335.178337 -285.168369) (xy 335.129097 -285.15237) (xy 335.082965 -285.128864) (xy 335.041078 -285.098432)
			(xy 335.004468 -285.061822) (xy 334.974036 -285.019935) (xy 334.95053 -284.973803) (xy 334.934531 -284.924563)
			(xy 334.926432 -284.873425) (xy 334.925924 -284.847538) (xy 334.926462 -284.81983) (xy 334.935651 -284.765183)
			(xy 334.944212 -284.738826) (xy 334.952086 -284.716728) (xy 334.747108 -284.36189) (xy 334.724248 -284.357572)
			(xy 334.699419 -284.352437) (xy 334.651638 -284.33548) (xy 334.607017 -284.311405) (xy 334.56661 -284.280781)
			(xy 334.531369 -284.24433) (xy 334.502126 -284.202912) (xy 334.479571 -284.157504) (xy 334.464236 -284.109178)
			(xy 334.456483 -284.059073) (xy 334.456024 -284.033722) (xy 313.738768 -284.033722) (xy 313.738768 -284.221428)
			(xy 313.738401 -284.231588) (xy 313.73059 -284.250347) (xy 313.716176 -284.264671) (xy 313.697368 -284.272364)
			(xy 313.687206 -284.272736) (xy 312.287666 -284.272736) (xy 312.277534 -284.272301) (xy 312.258808 -284.264557)
			(xy 312.244452 -284.250255) (xy 312.236638 -284.231558) (xy 312.236104 -284.221428) (xy 309.6387 -284.221428)
			(xy 309.638301 -284.231584) (xy 309.630497 -284.250337) (xy 309.616093 -284.264659) (xy 309.597296 -284.272358)
			(xy 309.587138 -284.272736) (xy 308.187598 -284.272736) (xy 308.177468 -284.272274) (xy 308.158743 -284.264541)
			(xy 308.144385 -284.250247) (xy 308.136571 -284.231556) (xy 308.136036 -284.221428) (xy 306.194968 -284.221428)
			(xy 306.194601 -284.231588) (xy 306.18679 -284.250347) (xy 306.172376 -284.264671) (xy 306.153568 -284.272364)
			(xy 306.143406 -284.272736) (xy 304.743866 -284.272736) (xy 304.733734 -284.272301) (xy 304.715008 -284.264557)
			(xy 304.700652 -284.250255) (xy 304.692838 -284.231558) (xy 304.692304 -284.221428) (xy 302.0949 -284.221428)
			(xy 302.094501 -284.231584) (xy 302.086697 -284.250337) (xy 302.072293 -284.264659) (xy 302.053496 -284.272358)
			(xy 302.043338 -284.272736) (xy 300.643798 -284.272736) (xy 300.633668 -284.272274) (xy 300.614943 -284.264541)
			(xy 300.600585 -284.250247) (xy 300.592771 -284.231556) (xy 300.592236 -284.221428) (xy 298.651168 -284.221428)
			(xy 298.650801 -284.231588) (xy 298.64299 -284.250347) (xy 298.628576 -284.264671) (xy 298.609768 -284.272364)
			(xy 298.599606 -284.272736) (xy 297.200066 -284.272736) (xy 297.189934 -284.272301) (xy 297.171208 -284.264557)
			(xy 297.156852 -284.250255) (xy 297.149038 -284.231558) (xy 297.148504 -284.221428) (xy 294.5511 -284.221428)
			(xy 294.550701 -284.231584) (xy 294.542897 -284.250337) (xy 294.528493 -284.264659) (xy 294.509696 -284.272358)
			(xy 294.499538 -284.272736) (xy 293.099998 -284.272736) (xy 293.089868 -284.272274) (xy 293.071143 -284.264541)
			(xy 293.056785 -284.250247) (xy 293.048971 -284.231556) (xy 293.048436 -284.221428) (xy 291.107368 -284.221428)
			(xy 291.107001 -284.231588) (xy 291.09919 -284.250347) (xy 291.084776 -284.264671) (xy 291.065968 -284.272364)
			(xy 291.055806 -284.272736) (xy 289.656266 -284.272736) (xy 289.646134 -284.272301) (xy 289.627408 -284.264557)
			(xy 289.613052 -284.250255) (xy 289.605238 -284.231558) (xy 289.604704 -284.221428) (xy 287.0073 -284.221428)
			(xy 287.006901 -284.231584) (xy 286.999097 -284.250337) (xy 286.984693 -284.264659) (xy 286.965896 -284.272358)
			(xy 286.955738 -284.272736) (xy 285.556198 -284.272736) (xy 285.546068 -284.272274) (xy 285.527343 -284.264541)
			(xy 285.512985 -284.250247) (xy 285.505171 -284.231556) (xy 285.504636 -284.221428) (xy 283.563568 -284.221428)
			(xy 283.563201 -284.231588) (xy 283.55539 -284.250347) (xy 283.540976 -284.264671) (xy 283.522168 -284.272364)
			(xy 283.512006 -284.272736) (xy 282.112466 -284.272736) (xy 282.102334 -284.272301) (xy 282.083608 -284.264557)
			(xy 282.069252 -284.250255) (xy 282.061438 -284.231558) (xy 282.060904 -284.221428) (xy 279.4635 -284.221428)
			(xy 279.463101 -284.231584) (xy 279.455297 -284.250337) (xy 279.440893 -284.264659) (xy 279.422096 -284.272358)
			(xy 279.411938 -284.272736) (xy 278.012398 -284.272736) (xy 278.002268 -284.272274) (xy 277.983543 -284.264541)
			(xy 277.969185 -284.250247) (xy 277.961371 -284.231556) (xy 277.960836 -284.221428) (xy 276.019768 -284.221428)
			(xy 276.019401 -284.231588) (xy 276.01159 -284.250347) (xy 275.997176 -284.264671) (xy 275.978368 -284.272364)
			(xy 275.968206 -284.272736) (xy 274.568666 -284.272736) (xy 274.558534 -284.272301) (xy 274.539808 -284.264557)
			(xy 274.525452 -284.250255) (xy 274.517638 -284.231558) (xy 274.517104 -284.221428) (xy 271.9197 -284.221428)
			(xy 271.919301 -284.231584) (xy 271.911497 -284.250337) (xy 271.897093 -284.264659) (xy 271.878296 -284.272358)
			(xy 271.868138 -284.272736) (xy 270.468598 -284.272736) (xy 270.458468 -284.272274) (xy 270.439743 -284.264541)
			(xy 270.425385 -284.250247) (xy 270.417571 -284.231556) (xy 270.417036 -284.221428) (xy 268.475968 -284.221428)
			(xy 268.475601 -284.231588) (xy 268.46779 -284.250347) (xy 268.453376 -284.264671) (xy 268.434568 -284.272364)
			(xy 268.424406 -284.272736) (xy 267.024866 -284.272736) (xy 267.014734 -284.272301) (xy 266.996008 -284.264557)
			(xy 266.981652 -284.250255) (xy 266.973838 -284.231558) (xy 266.973304 -284.221428) (xy 264.3759 -284.221428)
			(xy 264.375501 -284.231584) (xy 264.367697 -284.250337) (xy 264.353293 -284.264659) (xy 264.334496 -284.272358)
			(xy 264.324338 -284.272736) (xy 262.924798 -284.272736) (xy 262.914668 -284.272274) (xy 262.895943 -284.264541)
			(xy 262.881585 -284.250247) (xy 262.873771 -284.231556) (xy 262.873236 -284.221428) (xy 260.932168 -284.221428)
			(xy 260.931801 -284.231588) (xy 260.92399 -284.250347) (xy 260.909576 -284.264671) (xy 260.890768 -284.272364)
			(xy 260.880606 -284.272736) (xy 259.481066 -284.272736) (xy 259.470934 -284.272301) (xy 259.452208 -284.264557)
			(xy 259.437852 -284.250255) (xy 259.430038 -284.231558) (xy 259.429504 -284.221428) (xy 256.8321 -284.221428)
			(xy 256.831701 -284.231584) (xy 256.823897 -284.250337) (xy 256.809493 -284.264659) (xy 256.790696 -284.272358)
			(xy 256.780538 -284.272736) (xy 255.380998 -284.272736) (xy 255.370868 -284.272274) (xy 255.352143 -284.264541)
			(xy 255.337785 -284.250247) (xy 255.329971 -284.231556) (xy 255.329436 -284.221428) (xy 216.4715 -284.221428)
			(xy 216.471101 -284.231584) (xy 216.463297 -284.250337) (xy 216.448893 -284.264659) (xy 216.430096 -284.272358)
			(xy 216.419938 -284.272736) (xy 215.020398 -284.272736) (xy 215.010268 -284.272274) (xy 214.991543 -284.264541)
			(xy 214.977185 -284.250247) (xy 214.969371 -284.231556) (xy 214.968836 -284.221428) (xy 212.371432 -284.221428)
			(xy 212.371002 -284.23158) (xy 212.363203 -284.250327) (xy 212.34881 -284.264648) (xy 212.330024 -284.272353)
			(xy 212.31987 -284.272736) (xy 210.92033 -284.272736) (xy 210.910202 -284.272248) (xy 210.891477 -284.264526)
			(xy 210.877119 -284.250239) (xy 210.869303 -284.231553) (xy 210.868768 -284.221428) (xy 208.9277 -284.221428)
			(xy 208.927301 -284.231584) (xy 208.919497 -284.250337) (xy 208.905093 -284.264659) (xy 208.886296 -284.272358)
			(xy 208.876138 -284.272736) (xy 207.476598 -284.272736) (xy 207.466468 -284.272274) (xy 207.447743 -284.264541)
			(xy 207.433385 -284.250247) (xy 207.425571 -284.231556) (xy 207.425036 -284.221428) (xy 204.827632 -284.221428)
			(xy 204.827202 -284.23158) (xy 204.819403 -284.250327) (xy 204.80501 -284.264648) (xy 204.786224 -284.272353)
			(xy 204.77607 -284.272736) (xy 203.37653 -284.272736) (xy 203.366402 -284.272248) (xy 203.347677 -284.264526)
			(xy 203.333319 -284.250239) (xy 203.325503 -284.231553) (xy 203.324968 -284.221428) (xy 201.3839 -284.221428)
			(xy 201.383501 -284.231584) (xy 201.375697 -284.250337) (xy 201.361293 -284.264659) (xy 201.342496 -284.272358)
			(xy 201.332338 -284.272736) (xy 199.932798 -284.272736) (xy 199.922668 -284.272274) (xy 199.903943 -284.264541)
			(xy 199.889585 -284.250247) (xy 199.881771 -284.231556) (xy 199.881236 -284.221428) (xy 197.283832 -284.221428)
			(xy 197.283402 -284.23158) (xy 197.275603 -284.250327) (xy 197.26121 -284.264648) (xy 197.242424 -284.272353)
			(xy 197.23227 -284.272736) (xy 195.83273 -284.272736) (xy 195.822602 -284.272248) (xy 195.803877 -284.264526)
			(xy 195.789519 -284.250239) (xy 195.781703 -284.231553) (xy 195.781168 -284.221428) (xy 193.8401 -284.221428)
			(xy 193.839701 -284.231584) (xy 193.831897 -284.250337) (xy 193.817493 -284.264659) (xy 193.798696 -284.272358)
			(xy 193.788538 -284.272736) (xy 192.388998 -284.272736) (xy 192.378868 -284.272274) (xy 192.360143 -284.264541)
			(xy 192.345785 -284.250247) (xy 192.337971 -284.231556) (xy 192.337436 -284.221428) (xy 189.740032 -284.221428)
			(xy 189.739602 -284.23158) (xy 189.731803 -284.250327) (xy 189.71741 -284.264648) (xy 189.698624 -284.272353)
			(xy 189.68847 -284.272736) (xy 188.28893 -284.272736) (xy 188.278802 -284.272248) (xy 188.260077 -284.264526)
			(xy 188.245719 -284.250239) (xy 188.237903 -284.231553) (xy 188.237368 -284.221428) (xy 186.2963 -284.221428)
			(xy 186.295901 -284.231584) (xy 186.288097 -284.250337) (xy 186.273693 -284.264659) (xy 186.254896 -284.272358)
			(xy 186.244738 -284.272736) (xy 184.845198 -284.272736) (xy 184.835068 -284.272274) (xy 184.816343 -284.264541)
			(xy 184.801985 -284.250247) (xy 184.794171 -284.231556) (xy 184.793636 -284.221428) (xy 182.196232 -284.221428)
			(xy 182.195802 -284.23158) (xy 182.188003 -284.250327) (xy 182.17361 -284.264648) (xy 182.154824 -284.272353)
			(xy 182.14467 -284.272736) (xy 180.74513 -284.272736) (xy 180.735002 -284.272248) (xy 180.716277 -284.264526)
			(xy 180.701919 -284.250239) (xy 180.694103 -284.231553) (xy 180.693568 -284.221428) (xy 178.7525 -284.221428)
			(xy 178.752101 -284.231584) (xy 178.744297 -284.250337) (xy 178.729893 -284.264659) (xy 178.711096 -284.272358)
			(xy 178.700938 -284.272736) (xy 177.301398 -284.272736) (xy 177.291268 -284.272274) (xy 177.272543 -284.264541)
			(xy 177.258185 -284.250247) (xy 177.250371 -284.231556) (xy 177.249836 -284.221428) (xy 174.652432 -284.221428)
			(xy 174.652002 -284.23158) (xy 174.644203 -284.250327) (xy 174.62981 -284.264648) (xy 174.611024 -284.272353)
			(xy 174.60087 -284.272736) (xy 173.20133 -284.272736) (xy 173.191202 -284.272248) (xy 173.172477 -284.264526)
			(xy 173.158119 -284.250239) (xy 173.150303 -284.231553) (xy 173.149768 -284.221428) (xy 171.2087 -284.221428)
			(xy 171.208301 -284.231584) (xy 171.200497 -284.250337) (xy 171.186093 -284.264659) (xy 171.167296 -284.272358)
			(xy 171.157138 -284.272736) (xy 169.757598 -284.272736) (xy 169.747468 -284.272274) (xy 169.728743 -284.264541)
			(xy 169.714385 -284.250247) (xy 169.706571 -284.231556) (xy 169.706036 -284.221428) (xy 167.108632 -284.221428)
			(xy 167.108202 -284.23158) (xy 167.100403 -284.250327) (xy 167.08601 -284.264648) (xy 167.067224 -284.272353)
			(xy 167.05707 -284.272736) (xy 165.65753 -284.272736) (xy 165.647402 -284.272248) (xy 165.628677 -284.264526)
			(xy 165.614319 -284.250239) (xy 165.606503 -284.231553) (xy 165.605968 -284.221428) (xy 163.6649 -284.221428)
			(xy 163.664501 -284.231584) (xy 163.656697 -284.250337) (xy 163.642293 -284.264659) (xy 163.623496 -284.272358)
			(xy 163.613338 -284.272736) (xy 162.213798 -284.272736) (xy 162.203668 -284.272274) (xy 162.184943 -284.264541)
			(xy 162.170585 -284.250247) (xy 162.162771 -284.231556) (xy 162.162236 -284.221428) (xy 159.564832 -284.221428)
			(xy 159.564402 -284.23158) (xy 159.556603 -284.250327) (xy 159.54221 -284.264648) (xy 159.523424 -284.272353)
			(xy 159.51327 -284.272736) (xy 158.11373 -284.272736) (xy 158.103602 -284.272248) (xy 158.084877 -284.264526)
			(xy 158.070519 -284.250239) (xy 158.062703 -284.231553) (xy 158.062168 -284.221428) (xy 87.181791 -284.221428)
			(xy 87.353902 -284.51937) (xy 87.376762 -284.523688) (xy 87.401564 -284.528882) (xy 87.449305 -284.545867)
			(xy 87.493884 -284.569958) (xy 87.534252 -284.600587) (xy 87.569457 -284.637033) (xy 87.598669 -284.678438)
			(xy 87.621201 -284.723825) (xy 87.636522 -284.772125) (xy 87.644271 -284.822202) (xy 87.644732 -284.847538)
			(xy 87.644224 -284.873425) (xy 87.636125 -284.924563) (xy 87.620126 -284.973803) (xy 87.59662 -285.019935)
			(xy 87.566188 -285.061822) (xy 87.529578 -285.098432) (xy 87.487691 -285.128864) (xy 87.441559 -285.15237)
			(xy 87.392319 -285.168369) (xy 87.341181 -285.176468) (xy 87.289407 -285.176468) (xy 87.238269 -285.168369)
			(xy 87.189029 -285.15237) (xy 87.142897 -285.128864) (xy 87.10101 -285.098432) (xy 87.0644 -285.061822)
			(xy 87.033968 -285.019935) (xy 87.010462 -284.973803) (xy 86.994463 -284.924563) (xy 86.986364 -284.873425)
			(xy 86.985856 -284.847538) (xy 86.986397 -284.81983) (xy 86.995584 -284.765184) (xy 87.004144 -284.738826)
			(xy 87.012018 -284.716728) (xy 86.80704 -284.36189) (xy 86.78418 -284.357572) (xy 86.759356 -284.352414)
			(xy 86.711575 -284.335461) (xy 86.666954 -284.311391) (xy 86.626545 -284.28077) (xy 86.591303 -284.244322)
			(xy 86.56206 -284.202906) (xy 86.539504 -284.1575) (xy 86.524169 -284.109175) (xy 86.516415 -284.059072)
			(xy 86.515956 -284.033722) (xy 65.7987 -284.033722) (xy 65.7987 -284.221428) (xy 65.798301 -284.231584)
			(xy 65.790497 -284.250337) (xy 65.776093 -284.264659) (xy 65.757296 -284.272358) (xy 65.747138 -284.272736)
			(xy 64.347598 -284.272736) (xy 64.337468 -284.272274) (xy 64.318743 -284.264541) (xy 64.304385 -284.250247)
			(xy 64.296571 -284.231556) (xy 64.296036 -284.221428) (xy 61.698632 -284.221428) (xy 61.698202 -284.23158)
			(xy 61.690403 -284.250327) (xy 61.67601 -284.264648) (xy 61.657224 -284.272353) (xy 61.64707 -284.272736)
			(xy 60.24753 -284.272736) (xy 60.237402 -284.272248) (xy 60.218677 -284.264526) (xy 60.204319 -284.250239)
			(xy 60.196503 -284.231553) (xy 60.195968 -284.221428) (xy 58.2549 -284.221428) (xy 58.254501 -284.231584)
			(xy 58.246697 -284.250337) (xy 58.232293 -284.264659) (xy 58.213496 -284.272358) (xy 58.203338 -284.272736)
			(xy 56.803798 -284.272736) (xy 56.793668 -284.272274) (xy 56.774943 -284.264541) (xy 56.760585 -284.250247)
			(xy 56.752771 -284.231556) (xy 56.752236 -284.221428) (xy 54.154832 -284.221428) (xy 54.154402 -284.23158)
			(xy 54.146603 -284.250327) (xy 54.13221 -284.264648) (xy 54.113424 -284.272353) (xy 54.10327 -284.272736)
			(xy 52.70373 -284.272736) (xy 52.693602 -284.272248) (xy 52.674877 -284.264526) (xy 52.660519 -284.250239)
			(xy 52.652703 -284.231553) (xy 52.652168 -284.221428) (xy 50.7111 -284.221428) (xy 50.710701 -284.231584)
			(xy 50.702897 -284.250337) (xy 50.688493 -284.264659) (xy 50.669696 -284.272358) (xy 50.659538 -284.272736)
			(xy 49.259998 -284.272736) (xy 49.249868 -284.272274) (xy 49.231143 -284.264541) (xy 49.216785 -284.250247)
			(xy 49.208971 -284.231556) (xy 49.208436 -284.221428) (xy 46.611032 -284.221428) (xy 46.610602 -284.23158)
			(xy 46.602803 -284.250327) (xy 46.58841 -284.264648) (xy 46.569624 -284.272353) (xy 46.55947 -284.272736)
			(xy 45.15993 -284.272736) (xy 45.149802 -284.272248) (xy 45.131077 -284.264526) (xy 45.116719 -284.250239)
			(xy 45.108903 -284.231553) (xy 45.108368 -284.221428) (xy 43.1673 -284.221428) (xy 43.166901 -284.231584)
			(xy 43.159097 -284.250337) (xy 43.144693 -284.264659) (xy 43.125896 -284.272358) (xy 43.115738 -284.272736)
			(xy 41.716198 -284.272736) (xy 41.706068 -284.272274) (xy 41.687343 -284.264541) (xy 41.672985 -284.250247)
			(xy 41.665171 -284.231556) (xy 41.664636 -284.221428) (xy 39.067232 -284.221428) (xy 39.066802 -284.23158)
			(xy 39.059003 -284.250327) (xy 39.04461 -284.264648) (xy 39.025824 -284.272353) (xy 39.01567 -284.272736)
			(xy 37.61613 -284.272736) (xy 37.606002 -284.272248) (xy 37.587277 -284.264526) (xy 37.572919 -284.250239)
			(xy 37.565103 -284.231553) (xy 37.564568 -284.221428) (xy 35.6235 -284.221428) (xy 35.623101 -284.231584)
			(xy 35.615297 -284.250337) (xy 35.600893 -284.264659) (xy 35.582096 -284.272358) (xy 35.571938 -284.272736)
			(xy 34.172398 -284.272736) (xy 34.162268 -284.272274) (xy 34.143543 -284.264541) (xy 34.129185 -284.250247)
			(xy 34.121371 -284.231556) (xy 34.120836 -284.221428) (xy 31.523432 -284.221428) (xy 31.523002 -284.23158)
			(xy 31.515203 -284.250327) (xy 31.50081 -284.264648) (xy 31.482024 -284.272353) (xy 31.47187 -284.272736)
			(xy 30.07233 -284.272736) (xy 30.062202 -284.272248) (xy 30.043477 -284.264526) (xy 30.029119 -284.250239)
			(xy 30.021303 -284.231553) (xy 30.020768 -284.221428) (xy 28.0797 -284.221428) (xy 28.079301 -284.231584)
			(xy 28.071497 -284.250337) (xy 28.057093 -284.264659) (xy 28.038296 -284.272358) (xy 28.028138 -284.272736)
			(xy 26.628598 -284.272736) (xy 26.618468 -284.272274) (xy 26.599743 -284.264541) (xy 26.585385 -284.250247)
			(xy 26.577571 -284.231556) (xy 26.577036 -284.221428) (xy 23.979632 -284.221428) (xy 23.979202 -284.23158)
			(xy 23.971403 -284.250327) (xy 23.95701 -284.264648) (xy 23.938224 -284.272353) (xy 23.92807 -284.272736)
			(xy 22.52853 -284.272736) (xy 22.518402 -284.272248) (xy 22.499677 -284.264526) (xy 22.485319 -284.250239)
			(xy 22.477503 -284.231553) (xy 22.476968 -284.221428) (xy 20.5359 -284.221428) (xy 20.535501 -284.231584)
			(xy 20.527697 -284.250337) (xy 20.513293 -284.264659) (xy 20.494496 -284.272358) (xy 20.484338 -284.272736)
			(xy 19.084798 -284.272736) (xy 19.074668 -284.272274) (xy 19.055943 -284.264541) (xy 19.041585 -284.250247)
			(xy 19.033771 -284.231556) (xy 19.033236 -284.221428) (xy 16.435832 -284.221428) (xy 16.435402 -284.23158)
			(xy 16.427603 -284.250327) (xy 16.41321 -284.264648) (xy 16.394424 -284.272353) (xy 16.38427 -284.272736)
			(xy 14.98473 -284.272736) (xy 14.974602 -284.272248) (xy 14.955877 -284.264526) (xy 14.941519 -284.250239)
			(xy 14.933703 -284.231553) (xy 14.933168 -284.221428) (xy 12.9921 -284.221428) (xy 12.991701 -284.231584)
			(xy 12.983897 -284.250337) (xy 12.969493 -284.264659) (xy 12.950696 -284.272358) (xy 12.940538 -284.272736)
			(xy 11.540998 -284.272736) (xy 11.530868 -284.272274) (xy 11.512143 -284.264541) (xy 11.497785 -284.250247)
			(xy 11.489971 -284.231556) (xy 11.489436 -284.221428) (xy 8.892032 -284.221428) (xy 8.891602 -284.23158)
			(xy 8.883803 -284.250327) (xy 8.86941 -284.264648) (xy 8.850624 -284.272353) (xy 8.84047 -284.272736)
			(xy 7.44093 -284.272736) (xy 7.430802 -284.272248) (xy 7.412077 -284.264526) (xy 7.397719 -284.250239)
			(xy 7.389903 -284.231553) (xy 7.389368 -284.221428) (xy 2.509012 -284.221428) (xy 2.509012 -285.071312)
			(xy 7.389368 -285.071312) (xy 7.389368 -284.662372) (xy 7.389798 -284.65222) (xy 7.397597 -284.633473)
			(xy 7.41199 -284.619152) (xy 7.430776 -284.611447) (xy 7.44093 -284.611064) (xy 8.84047 -284.611064)
			(xy 8.850598 -284.611552) (xy 8.869323 -284.619274) (xy 8.883681 -284.633561) (xy 8.891497 -284.652247)
			(xy 8.892032 -284.662372) (xy 8.892032 -285.071312) (xy 14.933168 -285.071312) (xy 14.933168 -284.662372)
			(xy 14.933598 -284.65222) (xy 14.941397 -284.633473) (xy 14.95579 -284.619152) (xy 14.974576 -284.611447)
			(xy 14.98473 -284.611064) (xy 16.38427 -284.611064) (xy 16.394398 -284.611552) (xy 16.413123 -284.619274)
			(xy 16.427481 -284.633561) (xy 16.435297 -284.652247) (xy 16.435832 -284.662372) (xy 16.435832 -285.071312)
			(xy 22.476968 -285.071312) (xy 22.476968 -284.662372) (xy 22.477398 -284.65222) (xy 22.485197 -284.633473)
			(xy 22.49959 -284.619152) (xy 22.518376 -284.611447) (xy 22.52853 -284.611064) (xy 23.92807 -284.611064)
			(xy 23.938198 -284.611552) (xy 23.956923 -284.619274) (xy 23.971281 -284.633561) (xy 23.979097 -284.652247)
			(xy 23.979632 -284.662372) (xy 23.979632 -285.071312) (xy 30.020768 -285.071312) (xy 30.020768 -284.662372)
			(xy 30.021198 -284.65222) (xy 30.028997 -284.633473) (xy 30.04339 -284.619152) (xy 30.062176 -284.611447)
			(xy 30.07233 -284.611064) (xy 31.47187 -284.611064) (xy 31.481998 -284.611552) (xy 31.500723 -284.619274)
			(xy 31.515081 -284.633561) (xy 31.522897 -284.652247) (xy 31.523432 -284.662372) (xy 31.523432 -285.071312)
			(xy 37.564568 -285.071312) (xy 37.564568 -284.662372) (xy 37.564998 -284.65222) (xy 37.572797 -284.633473)
			(xy 37.58719 -284.619152) (xy 37.605976 -284.611447) (xy 37.61613 -284.611064) (xy 39.01567 -284.611064)
			(xy 39.025798 -284.611552) (xy 39.044523 -284.619274) (xy 39.058881 -284.633561) (xy 39.066697 -284.652247)
			(xy 39.067232 -284.662372) (xy 39.067232 -285.071312) (xy 45.108368 -285.071312) (xy 45.108368 -284.662372)
			(xy 45.108798 -284.65222) (xy 45.116597 -284.633473) (xy 45.13099 -284.619152) (xy 45.149776 -284.611447)
			(xy 45.15993 -284.611064) (xy 46.55947 -284.611064) (xy 46.569598 -284.611552) (xy 46.588323 -284.619274)
			(xy 46.602681 -284.633561) (xy 46.610497 -284.652247) (xy 46.611032 -284.662372) (xy 46.611032 -285.071312)
			(xy 52.652168 -285.071312) (xy 52.652168 -284.662372) (xy 52.652598 -284.65222) (xy 52.660397 -284.633473)
			(xy 52.67479 -284.619152) (xy 52.693576 -284.611447) (xy 52.70373 -284.611064) (xy 54.10327 -284.611064)
			(xy 54.113398 -284.611552) (xy 54.132123 -284.619274) (xy 54.146481 -284.633561) (xy 54.154297 -284.652247)
			(xy 54.154832 -284.662372) (xy 54.154832 -285.071312) (xy 60.195968 -285.071312) (xy 60.195968 -284.662372)
			(xy 60.196398 -284.65222) (xy 60.204197 -284.633473) (xy 60.21859 -284.619152) (xy 60.237376 -284.611447)
			(xy 60.24753 -284.611064) (xy 61.64707 -284.611064) (xy 61.657198 -284.611552) (xy 61.675923 -284.619274)
			(xy 61.690281 -284.633561) (xy 61.698097 -284.652247) (xy 61.698632 -284.662372) (xy 61.698632 -284.873384)
			(xy 85.106807 -284.873384) (xy 85.106807 -284.821616) (xy 85.114906 -284.770485) (xy 85.130903 -284.72125)
			(xy 85.154405 -284.675125) (xy 85.184833 -284.633243) (xy 85.221438 -284.596637) (xy 85.263319 -284.566208)
			(xy 85.309445 -284.542705) (xy 85.358679 -284.526707) (xy 85.40981 -284.518608) (xy 85.435694 -284.5181)
			(xy 85.461187 -284.518588) (xy 85.511565 -284.526449) (xy 85.560127 -284.541983) (xy 85.605714 -284.564818)
			(xy 85.647235 -284.594409) (xy 85.683698 -284.630049) (xy 85.699346 -284.65018) (xy 86.111842 -284.65018)
			(xy 86.127489 -284.630047) (xy 86.163951 -284.594407) (xy 86.205472 -284.564814) (xy 86.251059 -284.541976)
			(xy 86.299622 -284.526441) (xy 86.35 -284.518579) (xy 86.375494 -284.5181) (xy 86.401387 -284.518505)
			(xy 86.452535 -284.526605) (xy 86.501786 -284.542607) (xy 86.547927 -284.566116) (xy 86.589823 -284.596555)
			(xy 86.626441 -284.633172) (xy 86.65688 -284.675067) (xy 86.680391 -284.721208) (xy 86.696394 -284.770459)
			(xy 86.704495 -284.821607) (xy 86.704495 -284.873393) (xy 86.696394 -284.924541) (xy 86.680391 -284.973792)
			(xy 86.65688 -285.019933) (xy 86.626441 -285.061828) (xy 86.589823 -285.098445) (xy 86.547927 -285.128884)
			(xy 86.501786 -285.152393) (xy 86.452535 -285.168395) (xy 86.401387 -285.176495) (xy 86.375494 -285.176976)
			(xy 86.35 -285.176506) (xy 86.299621 -285.168643) (xy 86.251058 -285.153106) (xy 86.205471 -285.130267)
			(xy 86.16395 -285.100672) (xy 86.127489 -285.065029) (xy 86.111842 -285.044896) (xy 85.699346 -285.044896)
			(xy 85.683699 -285.065029) (xy 85.647238 -285.100671) (xy 85.605717 -285.130265) (xy 85.56013 -285.153102)
			(xy 85.511566 -285.168637) (xy 85.461188 -285.176498) (xy 85.435694 -285.176976) (xy 85.40981 -285.176392)
			(xy 85.358679 -285.168293) (xy 85.309445 -285.152295) (xy 85.263319 -285.128792) (xy 85.221438 -285.098363)
			(xy 85.184833 -285.061757) (xy 85.154405 -285.019875) (xy 85.130903 -284.97375) (xy 85.114906 -284.924515)
			(xy 85.106807 -284.873384) (xy 61.698632 -284.873384) (xy 61.698632 -285.071312) (xy 61.698189 -285.081463)
			(xy 61.690396 -285.10021) (xy 61.676006 -285.114531) (xy 61.657223 -285.122236) (xy 61.64707 -285.12262)
			(xy 60.24753 -285.12262) (xy 60.2374 -285.122148) (xy 60.218672 -285.114423) (xy 60.204313 -285.100131)
			(xy 60.1965 -285.081439) (xy 60.195968 -285.071312) (xy 54.154832 -285.071312) (xy 54.154389 -285.081463)
			(xy 54.146596 -285.10021) (xy 54.132206 -285.114531) (xy 54.113423 -285.122236) (xy 54.10327 -285.12262)
			(xy 52.70373 -285.12262) (xy 52.6936 -285.122148) (xy 52.674872 -285.114423) (xy 52.660513 -285.100131)
			(xy 52.6527 -285.081439) (xy 52.652168 -285.071312) (xy 46.611032 -285.071312) (xy 46.610589 -285.081463)
			(xy 46.602796 -285.10021) (xy 46.588406 -285.114531) (xy 46.569623 -285.122236) (xy 46.55947 -285.12262)
			(xy 45.15993 -285.12262) (xy 45.1498 -285.122148) (xy 45.131072 -285.114423) (xy 45.116713 -285.100131)
			(xy 45.1089 -285.081439) (xy 45.108368 -285.071312) (xy 39.067232 -285.071312) (xy 39.066789 -285.081463)
			(xy 39.058996 -285.10021) (xy 39.044606 -285.114531) (xy 39.025823 -285.122236) (xy 39.01567 -285.12262)
			(xy 37.61613 -285.12262) (xy 37.606 -285.122148) (xy 37.587272 -285.114423) (xy 37.572913 -285.100131)
			(xy 37.5651 -285.081439) (xy 37.564568 -285.071312) (xy 31.523432 -285.071312) (xy 31.522989 -285.081463)
			(xy 31.515196 -285.10021) (xy 31.500806 -285.114531) (xy 31.482023 -285.122236) (xy 31.47187 -285.12262)
			(xy 30.07233 -285.12262) (xy 30.0622 -285.122148) (xy 30.043472 -285.114423) (xy 30.029113 -285.100131)
			(xy 30.0213 -285.081439) (xy 30.020768 -285.071312) (xy 23.979632 -285.071312) (xy 23.979189 -285.081463)
			(xy 23.971396 -285.10021) (xy 23.957006 -285.114531) (xy 23.938223 -285.122236) (xy 23.92807 -285.12262)
			(xy 22.52853 -285.12262) (xy 22.5184 -285.122148) (xy 22.499672 -285.114423) (xy 22.485313 -285.100131)
			(xy 22.4775 -285.081439) (xy 22.476968 -285.071312) (xy 16.435832 -285.071312) (xy 16.435389 -285.081463)
			(xy 16.427596 -285.10021) (xy 16.413206 -285.114531) (xy 16.394423 -285.122236) (xy 16.38427 -285.12262)
			(xy 14.98473 -285.12262) (xy 14.9746 -285.122148) (xy 14.955872 -285.114423) (xy 14.941513 -285.100131)
			(xy 14.9337 -285.081439) (xy 14.933168 -285.071312) (xy 8.892032 -285.071312) (xy 8.891589 -285.081463)
			(xy 8.883796 -285.10021) (xy 8.869406 -285.114531) (xy 8.850623 -285.122236) (xy 8.84047 -285.12262)
			(xy 7.44093 -285.12262) (xy 7.4308 -285.122148) (xy 7.412072 -285.114423) (xy 7.397713 -285.100131)
			(xy 7.3899 -285.081439) (xy 7.389368 -285.071312) (xy 2.509012 -285.071312) (xy 2.509012 -285.92145)
			(xy 11.489436 -285.92145) (xy 11.489436 -285.51251) (xy 11.489872 -285.502339) (xy 11.497653 -285.483545)
			(xy 11.512035 -285.46916) (xy 11.530827 -285.461374) (xy 11.540998 -285.460948) (xy 12.940538 -285.460948)
			(xy 12.950699 -285.461403) (xy 12.969471 -285.469191) (xy 12.983836 -285.483569) (xy 12.991607 -285.502348)
			(xy 12.9921 -285.51251) (xy 12.9921 -285.92145) (xy 19.033236 -285.92145) (xy 19.033236 -285.51251)
			(xy 19.033672 -285.502339) (xy 19.041453 -285.483545) (xy 19.055835 -285.46916) (xy 19.074627 -285.461374)
			(xy 19.084798 -285.460948) (xy 20.484338 -285.460948) (xy 20.494499 -285.461403) (xy 20.513271 -285.469191)
			(xy 20.527636 -285.483569) (xy 20.535407 -285.502348) (xy 20.5359 -285.51251) (xy 20.5359 -285.92145)
			(xy 26.577036 -285.92145) (xy 26.577036 -285.51251) (xy 26.577472 -285.502339) (xy 26.585253 -285.483545)
			(xy 26.599635 -285.46916) (xy 26.618427 -285.461374) (xy 26.628598 -285.460948) (xy 28.028138 -285.460948)
			(xy 28.038299 -285.461403) (xy 28.057071 -285.469191) (xy 28.071436 -285.483569) (xy 28.079207 -285.502348)
			(xy 28.0797 -285.51251) (xy 28.0797 -285.92145) (xy 34.120836 -285.92145) (xy 34.120836 -285.51251)
			(xy 34.121272 -285.502339) (xy 34.129053 -285.483545) (xy 34.143435 -285.46916) (xy 34.162227 -285.461374)
			(xy 34.172398 -285.460948) (xy 35.571938 -285.460948) (xy 35.582099 -285.461403) (xy 35.600871 -285.469191)
			(xy 35.615236 -285.483569) (xy 35.623007 -285.502348) (xy 35.6235 -285.51251) (xy 35.6235 -285.92145)
			(xy 41.664636 -285.92145) (xy 41.664636 -285.51251) (xy 41.665072 -285.502339) (xy 41.672853 -285.483545)
			(xy 41.687235 -285.46916) (xy 41.706027 -285.461374) (xy 41.716198 -285.460948) (xy 43.115738 -285.460948)
			(xy 43.125899 -285.461403) (xy 43.144671 -285.469191) (xy 43.159036 -285.483569) (xy 43.166807 -285.502348)
			(xy 43.1673 -285.51251) (xy 43.1673 -285.92145) (xy 49.208436 -285.92145) (xy 49.208436 -285.51251)
			(xy 49.208872 -285.502339) (xy 49.216653 -285.483545) (xy 49.231035 -285.46916) (xy 49.249827 -285.461374)
			(xy 49.259998 -285.460948) (xy 50.659538 -285.460948) (xy 50.669699 -285.461403) (xy 50.688471 -285.469191)
			(xy 50.702836 -285.483569) (xy 50.710607 -285.502348) (xy 50.7111 -285.51251) (xy 50.7111 -285.92145)
			(xy 56.752236 -285.92145) (xy 56.752236 -285.51251) (xy 56.752672 -285.502339) (xy 56.760453 -285.483545)
			(xy 56.774835 -285.46916) (xy 56.793627 -285.461374) (xy 56.803798 -285.460948) (xy 58.203338 -285.460948)
			(xy 58.213499 -285.461403) (xy 58.232271 -285.469191) (xy 58.246636 -285.483569) (xy 58.254407 -285.502348)
			(xy 58.2549 -285.51251) (xy 58.2549 -285.92145) (xy 64.296036 -285.92145) (xy 64.296036 -285.51251)
			(xy 64.296472 -285.502339) (xy 64.304253 -285.483545) (xy 64.318635 -285.46916) (xy 64.337427 -285.461374)
			(xy 64.347598 -285.460948) (xy 65.747138 -285.460948) (xy 65.757299 -285.461403) (xy 65.776071 -285.469191)
			(xy 65.790436 -285.483569) (xy 65.798207 -285.502348) (xy 65.7987 -285.51251) (xy 65.7987 -285.661354)
			(xy 87.455756 -285.661354) (xy 87.456232 -285.63602) (xy 87.46399 -285.585949) (xy 87.479317 -285.537654)
			(xy 87.50185 -285.492273) (xy 87.531061 -285.450872) (xy 87.566261 -285.414427) (xy 87.606622 -285.383796)
			(xy 87.651194 -285.3597) (xy 87.698927 -285.342705) (xy 87.723726 -285.337504) (xy 87.746586 -285.333186)
			(xy 87.951564 -284.978094) (xy 87.943944 -284.95625) (xy 87.935376 -284.929894) (xy 87.926181 -284.875247)
			(xy 87.925656 -284.847538) (xy 87.926164 -284.821651) (xy 87.934263 -284.770513) (xy 87.950262 -284.721273)
			(xy 87.973768 -284.675141) (xy 88.0042 -284.633254) (xy 88.04081 -284.596644) (xy 88.082697 -284.566212)
			(xy 88.128829 -284.542706) (xy 88.178069 -284.526707) (xy 88.229207 -284.518608) (xy 88.280981 -284.518608)
			(xy 88.332119 -284.526707) (xy 88.381359 -284.542706) (xy 88.427491 -284.566212) (xy 88.469378 -284.596644)
			(xy 88.505988 -284.633254) (xy 88.53642 -284.675141) (xy 88.559926 -284.721273) (xy 88.575925 -284.770513)
			(xy 88.584024 -284.821651) (xy 88.584532 -284.847538) (xy 88.584058 -284.872872) (xy 88.576301 -284.922944)
			(xy 88.560975 -284.971239) (xy 88.538441 -285.016622) (xy 88.50923 -285.058022) (xy 88.47403 -285.094467)
			(xy 88.433668 -285.125098) (xy 88.389095 -285.149194) (xy 88.341361 -285.166187) (xy 88.316562 -285.171388)
			(xy 88.293702 -285.175706) (xy 88.088724 -285.530798) (xy 88.096344 -285.552642) (xy 88.104909 -285.578999)
			(xy 88.114106 -285.633646) (xy 88.114632 -285.661354) (xy 89.335356 -285.661354) (xy 89.335864 -285.635467)
			(xy 89.343963 -285.584329) (xy 89.359962 -285.535089) (xy 89.383468 -285.488957) (xy 89.4139 -285.44707)
			(xy 89.45051 -285.41046) (xy 89.492397 -285.380028) (xy 89.538529 -285.356522) (xy 89.587769 -285.340523)
			(xy 89.638907 -285.332424) (xy 89.690681 -285.332424) (xy 89.741819 -285.340523) (xy 89.791059 -285.356522)
			(xy 89.837191 -285.380028) (xy 89.879078 -285.41046) (xy 89.915688 -285.44707) (xy 89.94612 -285.488957)
			(xy 89.969626 -285.535089) (xy 89.985625 -285.584329) (xy 89.993724 -285.635467) (xy 89.994232 -285.661354)
			(xy 90.275156 -285.661354) (xy 90.27559 -285.636007) (xy 90.28337 -285.585913) (xy 90.298725 -285.537599)
			(xy 90.321292 -285.492204) (xy 90.35054 -285.450798) (xy 90.385779 -285.414354) (xy 90.426181 -285.383733)
			(xy 90.470793 -285.359656) (xy 90.518564 -285.342688) (xy 90.54338 -285.337504) (xy 90.56624 -285.333186)
			(xy 90.771218 -284.978348) (xy 90.763344 -284.956504) (xy 90.754767 -284.930085) (xy 90.745569 -284.87531)
			(xy 90.745056 -284.847538) (xy 90.745564 -284.821651) (xy 90.753663 -284.770513) (xy 90.769662 -284.721273)
			(xy 90.793168 -284.675141) (xy 90.8236 -284.633254) (xy 90.86021 -284.596644) (xy 90.902097 -284.566212)
			(xy 90.948229 -284.542706) (xy 90.997469 -284.526707) (xy 91.048607 -284.518608) (xy 91.100381 -284.518608)
			(xy 91.151519 -284.526707) (xy 91.200759 -284.542706) (xy 91.246891 -284.566212) (xy 91.288778 -284.596644)
			(xy 91.325388 -284.633254) (xy 91.35582 -284.675141) (xy 91.379326 -284.721273) (xy 91.395325 -284.770513)
			(xy 91.403424 -284.821651) (xy 91.403932 -284.847538) (xy 91.403458 -284.872872) (xy 91.395701 -284.922944)
			(xy 91.380375 -284.971239) (xy 91.357841 -285.016622) (xy 91.32863 -285.058022) (xy 91.29343 -285.094467)
			(xy 91.253068 -285.125098) (xy 91.208495 -285.149194) (xy 91.160761 -285.166187) (xy 91.135962 -285.171388)
			(xy 91.113102 -285.175706) (xy 90.908124 -285.530544) (xy 90.915998 -285.552642) (xy 90.924622 -285.57899)
			(xy 90.933948 -285.633636) (xy 90.93454 -285.661354) (xy 91.214956 -285.661354) (xy 91.215464 -285.635447)
			(xy 91.22357 -285.58427) (xy 91.239582 -285.534991) (xy 91.263105 -285.488824) (xy 91.293561 -285.446905)
			(xy 91.330199 -285.410267) (xy 91.372118 -285.379811) (xy 91.418285 -285.356288) (xy 91.467564 -285.340276)
			(xy 91.518741 -285.33217) (xy 91.570555 -285.33217) (xy 91.621732 -285.340276) (xy 91.671011 -285.356288)
			(xy 91.717178 -285.379811) (xy 91.759097 -285.410267) (xy 91.795735 -285.446905) (xy 91.826191 -285.488824)
			(xy 91.849714 -285.534991) (xy 91.865726 -285.58427) (xy 91.873832 -285.635447) (xy 91.87434 -285.661354)
			(xy 92.154756 -285.661354) (xy 92.155232 -285.63602) (xy 92.16299 -285.585949) (xy 92.178317 -285.537654)
			(xy 92.20085 -285.492273) (xy 92.230061 -285.450872) (xy 92.265261 -285.414427) (xy 92.305622 -285.383796)
			(xy 92.350194 -285.3597) (xy 92.397927 -285.342705) (xy 92.422726 -285.337504) (xy 92.445586 -285.333186)
			(xy 92.650818 -284.97784) (xy 92.643198 -284.955996) (xy 92.634574 -284.929714) (xy 92.625259 -284.875193)
			(xy 92.624656 -284.847538) (xy 92.625164 -284.821631) (xy 92.63327 -284.770454) (xy 92.649282 -284.721175)
			(xy 92.672805 -284.675008) (xy 92.703261 -284.633089) (xy 92.739899 -284.596451) (xy 92.781818 -284.565995)
			(xy 92.827985 -284.542472) (xy 92.877264 -284.52646) (xy 92.928441 -284.518354) (xy 92.980255 -284.518354)
			(xy 93.031432 -284.52646) (xy 93.080711 -284.542472) (xy 93.126878 -284.565995) (xy 93.168797 -284.596451)
			(xy 93.205435 -284.633089) (xy 93.235891 -284.675008) (xy 93.259414 -284.721175) (xy 93.275426 -284.770454)
			(xy 93.283532 -284.821631) (xy 93.28404 -284.847538) (xy 93.283648 -284.872916) (xy 93.275873 -284.923072)
			(xy 93.260496 -284.971442) (xy 93.237881 -285.016882) (xy 93.208565 -285.058314) (xy 93.17324 -285.09476)
			(xy 93.132743 -285.125356) (xy 93.088033 -285.149379) (xy 93.040166 -285.166259) (xy 93.015308 -285.171388)
			(xy 92.992448 -285.175706) (xy 92.78747 -285.530544) (xy 92.795344 -285.552642) (xy 92.803916 -285.578997)
			(xy 92.813107 -285.633645) (xy 92.813632 -285.661354) (xy 93.094556 -285.661354) (xy 93.095064 -285.635467)
			(xy 93.103163 -285.584329) (xy 93.119162 -285.535089) (xy 93.142668 -285.488957) (xy 93.1731 -285.44707)
			(xy 93.20971 -285.41046) (xy 93.251597 -285.380028) (xy 93.297729 -285.356522) (xy 93.346969 -285.340523)
			(xy 93.398107 -285.332424) (xy 93.449881 -285.332424) (xy 93.501019 -285.340523) (xy 93.550259 -285.356522)
			(xy 93.596391 -285.380028) (xy 93.638278 -285.41046) (xy 93.674888 -285.44707) (xy 93.70532 -285.488957)
			(xy 93.728826 -285.535089) (xy 93.744825 -285.584329) (xy 93.752924 -285.635467) (xy 93.753432 -285.661354)
			(xy 94.034356 -285.661354) (xy 94.034832 -285.63602) (xy 94.04259 -285.585949) (xy 94.057917 -285.537654)
			(xy 94.08045 -285.492273) (xy 94.109661 -285.450872) (xy 94.144861 -285.414427) (xy 94.185222 -285.383796)
			(xy 94.229794 -285.3597) (xy 94.277527 -285.342705) (xy 94.302326 -285.337504) (xy 94.325186 -285.333186)
			(xy 94.530418 -284.97784) (xy 94.522798 -284.955996) (xy 94.514174 -284.929714) (xy 94.504859 -284.875193)
			(xy 94.504256 -284.847538) (xy 94.504764 -284.821631) (xy 94.51287 -284.770454) (xy 94.528882 -284.721175)
			(xy 94.552405 -284.675008) (xy 94.582861 -284.633089) (xy 94.619499 -284.596451) (xy 94.661418 -284.565995)
			(xy 94.707585 -284.542472) (xy 94.756864 -284.52646) (xy 94.808041 -284.518354) (xy 94.859855 -284.518354)
			(xy 94.911032 -284.52646) (xy 94.960311 -284.542472) (xy 95.006478 -284.565995) (xy 95.048397 -284.596451)
			(xy 95.085035 -284.633089) (xy 95.115491 -284.675008) (xy 95.139014 -284.721175) (xy 95.155026 -284.770454)
			(xy 95.163132 -284.821631) (xy 95.16364 -284.847538) (xy 95.163248 -284.872916) (xy 95.155473 -284.923072)
			(xy 95.140096 -284.971442) (xy 95.117481 -285.016882) (xy 95.088165 -285.058314) (xy 95.05284 -285.09476)
			(xy 95.012343 -285.125356) (xy 94.967633 -285.149379) (xy 94.919766 -285.166259) (xy 94.894908 -285.171388)
			(xy 94.872048 -285.175706) (xy 94.66707 -285.530544) (xy 94.674944 -285.552642) (xy 94.683516 -285.578997)
			(xy 94.692707 -285.633645) (xy 94.693232 -285.661354) (xy 94.974156 -285.661354) (xy 94.974664 -285.635467)
			(xy 94.982763 -285.584329) (xy 94.998762 -285.535089) (xy 95.022268 -285.488957) (xy 95.0527 -285.44707)
			(xy 95.08931 -285.41046) (xy 95.131197 -285.380028) (xy 95.177329 -285.356522) (xy 95.226569 -285.340523)
			(xy 95.277707 -285.332424) (xy 95.329481 -285.332424) (xy 95.380619 -285.340523) (xy 95.429859 -285.356522)
			(xy 95.475991 -285.380028) (xy 95.517878 -285.41046) (xy 95.554488 -285.44707) (xy 95.58492 -285.488957)
			(xy 95.608426 -285.535089) (xy 95.624425 -285.584329) (xy 95.632524 -285.635467) (xy 95.633032 -285.661354)
			(xy 95.913956 -285.661354) (xy 95.914432 -285.63602) (xy 95.92219 -285.585949) (xy 95.937517 -285.537654)
			(xy 95.96005 -285.492273) (xy 95.989261 -285.450872) (xy 96.024461 -285.414427) (xy 96.064822 -285.383796)
			(xy 96.109394 -285.3597) (xy 96.157127 -285.342705) (xy 96.181926 -285.337504) (xy 96.204786 -285.333186)
			(xy 96.410018 -284.97784) (xy 96.402398 -284.955996) (xy 96.393774 -284.929714) (xy 96.384459 -284.875193)
			(xy 96.383856 -284.847538) (xy 96.384364 -284.821631) (xy 96.39247 -284.770454) (xy 96.408482 -284.721175)
			(xy 96.432005 -284.675008) (xy 96.462461 -284.633089) (xy 96.499099 -284.596451) (xy 96.541018 -284.565995)
			(xy 96.587185 -284.542472) (xy 96.636464 -284.52646) (xy 96.687641 -284.518354) (xy 96.739455 -284.518354)
			(xy 96.790632 -284.52646) (xy 96.839911 -284.542472) (xy 96.886078 -284.565995) (xy 96.927997 -284.596451)
			(xy 96.964635 -284.633089) (xy 96.995091 -284.675008) (xy 97.018614 -284.721175) (xy 97.034626 -284.770454)
			(xy 97.042732 -284.821631) (xy 97.04324 -284.847538) (xy 97.042848 -284.872916) (xy 97.035073 -284.923072)
			(xy 97.019696 -284.971442) (xy 96.997081 -285.016882) (xy 96.967765 -285.058314) (xy 96.93244 -285.09476)
			(xy 96.891943 -285.125356) (xy 96.847233 -285.149379) (xy 96.799366 -285.166259) (xy 96.774508 -285.171388)
			(xy 96.751648 -285.175706) (xy 96.54667 -285.530544) (xy 96.554544 -285.552642) (xy 96.563116 -285.578997)
			(xy 96.572307 -285.633645) (xy 96.572832 -285.661354) (xy 96.853756 -285.661354) (xy 96.854264 -285.635467)
			(xy 96.862363 -285.584329) (xy 96.878362 -285.535089) (xy 96.901868 -285.488957) (xy 96.9323 -285.44707)
			(xy 96.96891 -285.41046) (xy 97.010797 -285.380028) (xy 97.056929 -285.356522) (xy 97.106169 -285.340523)
			(xy 97.157307 -285.332424) (xy 97.209081 -285.332424) (xy 97.260219 -285.340523) (xy 97.309459 -285.356522)
			(xy 97.355591 -285.380028) (xy 97.397478 -285.41046) (xy 97.434088 -285.44707) (xy 97.46452 -285.488957)
			(xy 97.488026 -285.535089) (xy 97.504025 -285.584329) (xy 97.512124 -285.635467) (xy 97.512632 -285.661354)
			(xy 97.793556 -285.661354) (xy 97.794032 -285.63602) (xy 97.80179 -285.585949) (xy 97.817117 -285.537654)
			(xy 97.83965 -285.492273) (xy 97.868861 -285.450872) (xy 97.904061 -285.414427) (xy 97.944422 -285.383796)
			(xy 97.988994 -285.3597) (xy 98.036727 -285.342705) (xy 98.061526 -285.337504) (xy 98.084386 -285.333186)
			(xy 98.289618 -284.97784) (xy 98.281998 -284.955996) (xy 98.273374 -284.929714) (xy 98.264059 -284.875193)
			(xy 98.263456 -284.847538) (xy 98.263964 -284.821631) (xy 98.27207 -284.770454) (xy 98.288082 -284.721175)
			(xy 98.311605 -284.675008) (xy 98.342061 -284.633089) (xy 98.378699 -284.596451) (xy 98.420618 -284.565995)
			(xy 98.466785 -284.542472) (xy 98.516064 -284.52646) (xy 98.567241 -284.518354) (xy 98.619055 -284.518354)
			(xy 98.670232 -284.52646) (xy 98.719511 -284.542472) (xy 98.765678 -284.565995) (xy 98.807597 -284.596451)
			(xy 98.844235 -284.633089) (xy 98.874691 -284.675008) (xy 98.898214 -284.721175) (xy 98.914226 -284.770454)
			(xy 98.922332 -284.821631) (xy 98.92284 -284.847538) (xy 98.922448 -284.872916) (xy 98.914673 -284.923072)
			(xy 98.899296 -284.971442) (xy 98.876681 -285.016882) (xy 98.847365 -285.058314) (xy 98.81204 -285.09476)
			(xy 98.771543 -285.125356) (xy 98.726833 -285.149379) (xy 98.678966 -285.166259) (xy 98.654108 -285.171388)
			(xy 98.631248 -285.175706) (xy 98.42627 -285.530544) (xy 98.434144 -285.552642) (xy 98.442716 -285.578997)
			(xy 98.451907 -285.633645) (xy 98.452432 -285.661354) (xy 98.733356 -285.661354) (xy 98.733864 -285.635467)
			(xy 98.741963 -285.584329) (xy 98.757962 -285.535089) (xy 98.781468 -285.488957) (xy 98.8119 -285.44707)
			(xy 98.84851 -285.41046) (xy 98.890397 -285.380028) (xy 98.936529 -285.356522) (xy 98.985769 -285.340523)
			(xy 99.036907 -285.332424) (xy 99.088681 -285.332424) (xy 99.139819 -285.340523) (xy 99.189059 -285.356522)
			(xy 99.235191 -285.380028) (xy 99.277078 -285.41046) (xy 99.313688 -285.44707) (xy 99.34412 -285.488957)
			(xy 99.367626 -285.535089) (xy 99.383625 -285.584329) (xy 99.391724 -285.635467) (xy 99.392232 -285.661354)
			(xy 99.673156 -285.661354) (xy 99.673632 -285.63602) (xy 99.68139 -285.585949) (xy 99.696717 -285.537654)
			(xy 99.71925 -285.492273) (xy 99.748461 -285.450872) (xy 99.783661 -285.414427) (xy 99.824022 -285.383796)
			(xy 99.868594 -285.3597) (xy 99.916327 -285.342705) (xy 99.941126 -285.337504) (xy 99.963986 -285.333186)
			(xy 100.169218 -284.97784) (xy 100.161598 -284.955996) (xy 100.152974 -284.929714) (xy 100.143659 -284.875193)
			(xy 100.143056 -284.847538) (xy 100.143564 -284.821631) (xy 100.15167 -284.770454) (xy 100.167682 -284.721175)
			(xy 100.191205 -284.675008) (xy 100.221661 -284.633089) (xy 100.258299 -284.596451) (xy 100.300218 -284.565995)
			(xy 100.346385 -284.542472) (xy 100.395664 -284.52646) (xy 100.446841 -284.518354) (xy 100.498655 -284.518354)
			(xy 100.549832 -284.52646) (xy 100.599111 -284.542472) (xy 100.645278 -284.565995) (xy 100.687197 -284.596451)
			(xy 100.723835 -284.633089) (xy 100.754291 -284.675008) (xy 100.777814 -284.721175) (xy 100.793826 -284.770454)
			(xy 100.801932 -284.821631) (xy 100.80244 -284.847538) (xy 100.802048 -284.872916) (xy 100.794273 -284.923072)
			(xy 100.778896 -284.971442) (xy 100.756281 -285.016882) (xy 100.726965 -285.058314) (xy 100.69164 -285.09476)
			(xy 100.651143 -285.125356) (xy 100.606433 -285.149379) (xy 100.558566 -285.166259) (xy 100.533708 -285.171388)
			(xy 100.510848 -285.175706) (xy 100.30587 -285.530544) (xy 100.313744 -285.552642) (xy 100.322316 -285.578997)
			(xy 100.331507 -285.633645) (xy 100.332032 -285.661354) (xy 100.612956 -285.661354) (xy 100.613464 -285.635467)
			(xy 100.621563 -285.584329) (xy 100.637562 -285.535089) (xy 100.661068 -285.488957) (xy 100.6915 -285.44707)
			(xy 100.72811 -285.41046) (xy 100.769997 -285.380028) (xy 100.816129 -285.356522) (xy 100.865369 -285.340523)
			(xy 100.916507 -285.332424) (xy 100.968281 -285.332424) (xy 101.019419 -285.340523) (xy 101.068659 -285.356522)
			(xy 101.114791 -285.380028) (xy 101.156678 -285.41046) (xy 101.193288 -285.44707) (xy 101.22372 -285.488957)
			(xy 101.247226 -285.535089) (xy 101.263225 -285.584329) (xy 101.271324 -285.635467) (xy 101.271832 -285.661354)
			(xy 101.552756 -285.661354) (xy 101.553232 -285.63602) (xy 101.56099 -285.585949) (xy 101.576317 -285.537654)
			(xy 101.59885 -285.492273) (xy 101.628061 -285.450872) (xy 101.663261 -285.414427) (xy 101.703622 -285.383796)
			(xy 101.748194 -285.3597) (xy 101.795927 -285.342705) (xy 101.820726 -285.337504) (xy 101.843586 -285.333186)
			(xy 102.048818 -284.97784) (xy 102.041198 -284.955996) (xy 102.032574 -284.929714) (xy 102.023259 -284.875193)
			(xy 102.022656 -284.847538) (xy 102.023164 -284.821631) (xy 102.03127 -284.770454) (xy 102.047282 -284.721175)
			(xy 102.070805 -284.675008) (xy 102.101261 -284.633089) (xy 102.137899 -284.596451) (xy 102.179818 -284.565995)
			(xy 102.225985 -284.542472) (xy 102.275264 -284.52646) (xy 102.326441 -284.518354) (xy 102.378255 -284.518354)
			(xy 102.429432 -284.52646) (xy 102.478711 -284.542472) (xy 102.524878 -284.565995) (xy 102.566797 -284.596451)
			(xy 102.603435 -284.633089) (xy 102.633891 -284.675008) (xy 102.657414 -284.721175) (xy 102.673426 -284.770454)
			(xy 102.681532 -284.821631) (xy 102.68204 -284.847538) (xy 102.681648 -284.872916) (xy 102.673873 -284.923072)
			(xy 102.658496 -284.971442) (xy 102.635881 -285.016882) (xy 102.606565 -285.058314) (xy 102.57124 -285.09476)
			(xy 102.530743 -285.125356) (xy 102.486033 -285.149379) (xy 102.438166 -285.166259) (xy 102.413308 -285.171388)
			(xy 102.390448 -285.175706) (xy 102.18547 -285.530544) (xy 102.193344 -285.552642) (xy 102.201916 -285.578997)
			(xy 102.211107 -285.633645) (xy 102.211632 -285.661354) (xy 102.492556 -285.661354) (xy 102.493064 -285.635467)
			(xy 102.501163 -285.584329) (xy 102.517162 -285.535089) (xy 102.540668 -285.488957) (xy 102.5711 -285.44707)
			(xy 102.60771 -285.41046) (xy 102.649597 -285.380028) (xy 102.695729 -285.356522) (xy 102.744969 -285.340523)
			(xy 102.796107 -285.332424) (xy 102.847881 -285.332424) (xy 102.899019 -285.340523) (xy 102.948259 -285.356522)
			(xy 102.994391 -285.380028) (xy 103.036278 -285.41046) (xy 103.072888 -285.44707) (xy 103.10332 -285.488957)
			(xy 103.126826 -285.535089) (xy 103.142825 -285.584329) (xy 103.150924 -285.635467) (xy 103.151432 -285.661354)
			(xy 103.432356 -285.661354) (xy 103.432832 -285.63602) (xy 103.44059 -285.585949) (xy 103.455917 -285.537654)
			(xy 103.47845 -285.492273) (xy 103.507661 -285.450872) (xy 103.542861 -285.414427) (xy 103.583222 -285.383796)
			(xy 103.627794 -285.3597) (xy 103.675527 -285.342705) (xy 103.700326 -285.337504) (xy 103.723186 -285.333186)
			(xy 103.928418 -284.97784) (xy 103.920798 -284.955996) (xy 103.912174 -284.929714) (xy 103.902859 -284.875193)
			(xy 103.902256 -284.847538) (xy 103.902764 -284.821631) (xy 103.91087 -284.770454) (xy 103.926882 -284.721175)
			(xy 103.950405 -284.675008) (xy 103.980861 -284.633089) (xy 104.017499 -284.596451) (xy 104.059418 -284.565995)
			(xy 104.105585 -284.542472) (xy 104.154864 -284.52646) (xy 104.206041 -284.518354) (xy 104.257855 -284.518354)
			(xy 104.309032 -284.52646) (xy 104.358311 -284.542472) (xy 104.404478 -284.565995) (xy 104.446397 -284.596451)
			(xy 104.483035 -284.633089) (xy 104.513491 -284.675008) (xy 104.537014 -284.721175) (xy 104.553026 -284.770454)
			(xy 104.561132 -284.821631) (xy 104.56164 -284.847538) (xy 118.939056 -284.847538) (xy 118.939564 -284.821631)
			(xy 118.94767 -284.770454) (xy 118.963682 -284.721175) (xy 118.987205 -284.675008) (xy 119.017661 -284.633089)
			(xy 119.054299 -284.596451) (xy 119.096218 -284.565995) (xy 119.142385 -284.542472) (xy 119.191664 -284.52646)
			(xy 119.242841 -284.518354) (xy 119.294655 -284.518354) (xy 119.345832 -284.52646) (xy 119.395111 -284.542472)
			(xy 119.441278 -284.565995) (xy 119.483197 -284.596451) (xy 119.519835 -284.633089) (xy 119.550291 -284.675008)
			(xy 119.573814 -284.721175) (xy 119.589826 -284.770454) (xy 119.597932 -284.821631) (xy 119.59844 -284.847538)
			(xy 120.818656 -284.847538) (xy 120.819164 -284.821631) (xy 120.82727 -284.770454) (xy 120.843282 -284.721175)
			(xy 120.866805 -284.675008) (xy 120.897261 -284.633089) (xy 120.933899 -284.596451) (xy 120.975818 -284.565995)
			(xy 121.021985 -284.542472) (xy 121.071264 -284.52646) (xy 121.122441 -284.518354) (xy 121.174255 -284.518354)
			(xy 121.225432 -284.52646) (xy 121.274711 -284.542472) (xy 121.320878 -284.565995) (xy 121.362797 -284.596451)
			(xy 121.399435 -284.633089) (xy 121.429891 -284.675008) (xy 121.453414 -284.721175) (xy 121.469426 -284.770454)
			(xy 121.477532 -284.821631) (xy 121.47804 -284.847538) (xy 122.698256 -284.847538) (xy 122.698764 -284.821631)
			(xy 122.70687 -284.770454) (xy 122.722882 -284.721175) (xy 122.746405 -284.675008) (xy 122.776861 -284.633089)
			(xy 122.813499 -284.596451) (xy 122.855418 -284.565995) (xy 122.901585 -284.542472) (xy 122.950864 -284.52646)
			(xy 123.002041 -284.518354) (xy 123.053855 -284.518354) (xy 123.105032 -284.52646) (xy 123.154311 -284.542472)
			(xy 123.200478 -284.565995) (xy 123.242397 -284.596451) (xy 123.279035 -284.633089) (xy 123.309491 -284.675008)
			(xy 123.333014 -284.721175) (xy 123.349026 -284.770454) (xy 123.357132 -284.821631) (xy 123.35764 -284.847538)
			(xy 124.577856 -284.847538) (xy 124.578364 -284.821631) (xy 124.58647 -284.770454) (xy 124.602482 -284.721175)
			(xy 124.626005 -284.675008) (xy 124.656461 -284.633089) (xy 124.693099 -284.596451) (xy 124.735018 -284.565995)
			(xy 124.781185 -284.542472) (xy 124.830464 -284.52646) (xy 124.881641 -284.518354) (xy 124.933455 -284.518354)
			(xy 124.984632 -284.52646) (xy 125.033911 -284.542472) (xy 125.080078 -284.565995) (xy 125.121997 -284.596451)
			(xy 125.158635 -284.633089) (xy 125.189091 -284.675008) (xy 125.212614 -284.721175) (xy 125.228626 -284.770454)
			(xy 125.236732 -284.821631) (xy 125.23724 -284.847538) (xy 126.457456 -284.847538) (xy 126.457964 -284.821631)
			(xy 126.46607 -284.770454) (xy 126.482082 -284.721175) (xy 126.505605 -284.675008) (xy 126.536061 -284.633089)
			(xy 126.572699 -284.596451) (xy 126.614618 -284.565995) (xy 126.660785 -284.542472) (xy 126.710064 -284.52646)
			(xy 126.761241 -284.518354) (xy 126.813055 -284.518354) (xy 126.864232 -284.52646) (xy 126.913511 -284.542472)
			(xy 126.959678 -284.565995) (xy 127.001597 -284.596451) (xy 127.038235 -284.633089) (xy 127.068691 -284.675008)
			(xy 127.092214 -284.721175) (xy 127.108226 -284.770454) (xy 127.116332 -284.821631) (xy 127.11684 -284.847538)
			(xy 128.337056 -284.847538) (xy 128.337564 -284.821631) (xy 128.34567 -284.770454) (xy 128.361682 -284.721175)
			(xy 128.385205 -284.675008) (xy 128.415661 -284.633089) (xy 128.452299 -284.596451) (xy 128.494218 -284.565995)
			(xy 128.540385 -284.542472) (xy 128.589664 -284.52646) (xy 128.640841 -284.518354) (xy 128.692655 -284.518354)
			(xy 128.743832 -284.52646) (xy 128.793111 -284.542472) (xy 128.839278 -284.565995) (xy 128.881197 -284.596451)
			(xy 128.917835 -284.633089) (xy 128.948291 -284.675008) (xy 128.971814 -284.721175) (xy 128.987826 -284.770454)
			(xy 128.995932 -284.821631) (xy 128.99644 -284.847538) (xy 130.216656 -284.847538) (xy 130.217164 -284.821631)
			(xy 130.22527 -284.770454) (xy 130.241282 -284.721175) (xy 130.264805 -284.675008) (xy 130.295261 -284.633089)
			(xy 130.331899 -284.596451) (xy 130.373818 -284.565995) (xy 130.419985 -284.542472) (xy 130.469264 -284.52646)
			(xy 130.520441 -284.518354) (xy 130.572255 -284.518354) (xy 130.623432 -284.52646) (xy 130.672711 -284.542472)
			(xy 130.718878 -284.565995) (xy 130.760797 -284.596451) (xy 130.797435 -284.633089) (xy 130.827891 -284.675008)
			(xy 130.851414 -284.721175) (xy 130.867426 -284.770454) (xy 130.875532 -284.821631) (xy 130.87604 -284.847538)
			(xy 132.096256 -284.847538) (xy 132.096764 -284.821631) (xy 132.10487 -284.770454) (xy 132.120882 -284.721175)
			(xy 132.144405 -284.675008) (xy 132.174861 -284.633089) (xy 132.211499 -284.596451) (xy 132.253418 -284.565995)
			(xy 132.299585 -284.542472) (xy 132.348864 -284.52646) (xy 132.400041 -284.518354) (xy 132.451855 -284.518354)
			(xy 132.503032 -284.52646) (xy 132.552311 -284.542472) (xy 132.598478 -284.565995) (xy 132.640397 -284.596451)
			(xy 132.677035 -284.633089) (xy 132.707491 -284.675008) (xy 132.731014 -284.721175) (xy 132.747026 -284.770454)
			(xy 132.755132 -284.821631) (xy 132.75564 -284.847538) (xy 132.755034 -284.875255) (xy 132.745719 -284.929901)
			(xy 132.737098 -284.95625) (xy 132.729224 -284.978348) (xy 132.782926 -285.071312) (xy 158.062168 -285.071312)
			(xy 158.062168 -284.662372) (xy 158.062598 -284.65222) (xy 158.070397 -284.633473) (xy 158.08479 -284.619152)
			(xy 158.103576 -284.611447) (xy 158.11373 -284.611064) (xy 159.51327 -284.611064) (xy 159.523398 -284.611552)
			(xy 159.542123 -284.619274) (xy 159.556481 -284.633561) (xy 159.564297 -284.652247) (xy 159.564832 -284.662372)
			(xy 159.564832 -285.071312) (xy 165.605968 -285.071312) (xy 165.605968 -284.662372) (xy 165.606398 -284.65222)
			(xy 165.614197 -284.633473) (xy 165.62859 -284.619152) (xy 165.647376 -284.611447) (xy 165.65753 -284.611064)
			(xy 167.05707 -284.611064) (xy 167.067198 -284.611552) (xy 167.085923 -284.619274) (xy 167.100281 -284.633561)
			(xy 167.108097 -284.652247) (xy 167.108632 -284.662372) (xy 167.108632 -285.071312) (xy 173.149768 -285.071312)
			(xy 173.149768 -284.662372) (xy 173.150198 -284.65222) (xy 173.157997 -284.633473) (xy 173.17239 -284.619152)
			(xy 173.191176 -284.611447) (xy 173.20133 -284.611064) (xy 174.60087 -284.611064) (xy 174.610998 -284.611552)
			(xy 174.629723 -284.619274) (xy 174.644081 -284.633561) (xy 174.651897 -284.652247) (xy 174.652432 -284.662372)
			(xy 174.652432 -285.071312) (xy 180.693568 -285.071312) (xy 180.693568 -284.662372) (xy 180.693998 -284.65222)
			(xy 180.701797 -284.633473) (xy 180.71619 -284.619152) (xy 180.734976 -284.611447) (xy 180.74513 -284.611064)
			(xy 182.14467 -284.611064) (xy 182.154798 -284.611552) (xy 182.173523 -284.619274) (xy 182.187881 -284.633561)
			(xy 182.195697 -284.652247) (xy 182.196232 -284.662372) (xy 182.196232 -285.071312) (xy 188.237368 -285.071312)
			(xy 188.237368 -284.662372) (xy 188.237798 -284.65222) (xy 188.245597 -284.633473) (xy 188.25999 -284.619152)
			(xy 188.278776 -284.611447) (xy 188.28893 -284.611064) (xy 189.68847 -284.611064) (xy 189.698598 -284.611552)
			(xy 189.717323 -284.619274) (xy 189.731681 -284.633561) (xy 189.739497 -284.652247) (xy 189.740032 -284.662372)
			(xy 189.740032 -285.071312) (xy 195.781168 -285.071312) (xy 195.781168 -284.662372) (xy 195.781598 -284.65222)
			(xy 195.789397 -284.633473) (xy 195.80379 -284.619152) (xy 195.822576 -284.611447) (xy 195.83273 -284.611064)
			(xy 197.23227 -284.611064) (xy 197.242398 -284.611552) (xy 197.261123 -284.619274) (xy 197.275481 -284.633561)
			(xy 197.283297 -284.652247) (xy 197.283832 -284.662372) (xy 197.283832 -285.071312) (xy 203.324968 -285.071312)
			(xy 203.324968 -284.662372) (xy 203.325398 -284.65222) (xy 203.333197 -284.633473) (xy 203.34759 -284.619152)
			(xy 203.366376 -284.611447) (xy 203.37653 -284.611064) (xy 204.77607 -284.611064) (xy 204.786198 -284.611552)
			(xy 204.804923 -284.619274) (xy 204.819281 -284.633561) (xy 204.827097 -284.652247) (xy 204.827632 -284.662372)
			(xy 204.827632 -285.071312) (xy 210.868768 -285.071312) (xy 210.868768 -284.662372) (xy 210.869198 -284.65222)
			(xy 210.876997 -284.633473) (xy 210.89139 -284.619152) (xy 210.910176 -284.611447) (xy 210.92033 -284.611064)
			(xy 212.31987 -284.611064) (xy 212.329998 -284.611552) (xy 212.348723 -284.619274) (xy 212.363081 -284.633561)
			(xy 212.370897 -284.652247) (xy 212.371432 -284.662372) (xy 212.371432 -285.071312) (xy 255.329436 -285.071312)
			(xy 255.329436 -284.662372) (xy 255.329799 -284.652212) (xy 255.337611 -284.633452) (xy 255.352026 -284.619128)
			(xy 255.370835 -284.611436) (xy 255.380998 -284.611064) (xy 256.780538 -284.611064) (xy 256.79067 -284.611496)
			(xy 256.809397 -284.619241) (xy 256.823752 -284.633544) (xy 256.831566 -284.652242) (xy 256.8321 -284.662372)
			(xy 256.8321 -285.071312) (xy 262.873236 -285.071312) (xy 262.873236 -284.662372) (xy 262.873599 -284.652212)
			(xy 262.881411 -284.633452) (xy 262.895826 -284.619128) (xy 262.914635 -284.611436) (xy 262.924798 -284.611064)
			(xy 264.324338 -284.611064) (xy 264.33447 -284.611496) (xy 264.353197 -284.619241) (xy 264.367552 -284.633544)
			(xy 264.375366 -284.652242) (xy 264.3759 -284.662372) (xy 264.3759 -285.071312) (xy 270.417036 -285.071312)
			(xy 270.417036 -284.662372) (xy 270.417399 -284.652212) (xy 270.425211 -284.633452) (xy 270.439626 -284.619128)
			(xy 270.458435 -284.611436) (xy 270.468598 -284.611064) (xy 271.868138 -284.611064) (xy 271.87827 -284.611496)
			(xy 271.896997 -284.619241) (xy 271.911352 -284.633544) (xy 271.919166 -284.652242) (xy 271.9197 -284.662372)
			(xy 271.9197 -285.071312) (xy 277.960836 -285.071312) (xy 277.960836 -284.662372) (xy 277.961199 -284.652212)
			(xy 277.969011 -284.633452) (xy 277.983426 -284.619128) (xy 278.002235 -284.611436) (xy 278.012398 -284.611064)
			(xy 279.411938 -284.611064) (xy 279.42207 -284.611496) (xy 279.440797 -284.619241) (xy 279.455152 -284.633544)
			(xy 279.462966 -284.652242) (xy 279.4635 -284.662372) (xy 279.4635 -285.071312) (xy 285.504636 -285.071312)
			(xy 285.504636 -284.662372) (xy 285.504999 -284.652212) (xy 285.512811 -284.633452) (xy 285.527226 -284.619128)
			(xy 285.546035 -284.611436) (xy 285.556198 -284.611064) (xy 286.955738 -284.611064) (xy 286.96587 -284.611496)
			(xy 286.984597 -284.619241) (xy 286.998952 -284.633544) (xy 287.006766 -284.652242) (xy 287.0073 -284.662372)
			(xy 287.0073 -285.071312) (xy 293.048436 -285.071312) (xy 293.048436 -284.662372) (xy 293.048799 -284.652212)
			(xy 293.056611 -284.633452) (xy 293.071026 -284.619128) (xy 293.089835 -284.611436) (xy 293.099998 -284.611064)
			(xy 294.499538 -284.611064) (xy 294.50967 -284.611496) (xy 294.528397 -284.619241) (xy 294.542752 -284.633544)
			(xy 294.550566 -284.652242) (xy 294.5511 -284.662372) (xy 294.5511 -285.071312) (xy 300.592236 -285.071312)
			(xy 300.592236 -284.662372) (xy 300.592599 -284.652212) (xy 300.600411 -284.633452) (xy 300.614826 -284.619128)
			(xy 300.633635 -284.611436) (xy 300.643798 -284.611064) (xy 302.043338 -284.611064) (xy 302.05347 -284.611496)
			(xy 302.072197 -284.619241) (xy 302.086552 -284.633544) (xy 302.094366 -284.652242) (xy 302.0949 -284.662372)
			(xy 302.0949 -285.071312) (xy 308.136036 -285.071312) (xy 308.136036 -284.662372) (xy 308.136399 -284.652212)
			(xy 308.144211 -284.633452) (xy 308.158626 -284.619128) (xy 308.177435 -284.611436) (xy 308.187598 -284.611064)
			(xy 309.587138 -284.611064) (xy 309.59727 -284.611496) (xy 309.615997 -284.619241) (xy 309.630352 -284.633544)
			(xy 309.638166 -284.652242) (xy 309.6387 -284.662372) (xy 309.6387 -284.873383) (xy 333.046907 -284.873383)
			(xy 333.046907 -284.821618) (xy 333.055005 -284.77049) (xy 333.071 -284.721258) (xy 333.094499 -284.675134)
			(xy 333.124924 -284.633254) (xy 333.161525 -284.596648) (xy 333.203402 -284.566219) (xy 333.249523 -284.542714)
			(xy 333.298753 -284.526713) (xy 333.34988 -284.51861) (xy 333.375762 -284.5181) (xy 333.401254 -284.518612)
			(xy 333.451631 -284.526467) (xy 333.500193 -284.541996) (xy 333.54578 -284.564827) (xy 333.587302 -284.594415)
			(xy 333.623765 -284.63005) (xy 333.639414 -284.65018) (xy 334.05191 -284.65018) (xy 334.067576 -284.630063)
			(xy 334.104034 -284.594421) (xy 334.145551 -284.564826) (xy 334.191135 -284.541986) (xy 334.239694 -284.526447)
			(xy 334.290069 -284.518581) (xy 334.315562 -284.5181) (xy 334.341456 -284.518502) (xy 334.392608 -284.526599)
			(xy 334.441864 -284.542598) (xy 334.48801 -284.566106) (xy 334.52991 -284.596543) (xy 334.566532 -284.633161)
			(xy 334.596975 -284.675058) (xy 334.620488 -284.721201) (xy 334.636492 -284.770455) (xy 334.644595 -284.821606)
			(xy 334.644595 -284.873394) (xy 334.636492 -284.924545) (xy 334.620488 -284.973799) (xy 334.596975 -285.019942)
			(xy 334.566532 -285.061839) (xy 334.52991 -285.098457) (xy 334.48801 -285.128894) (xy 334.441864 -285.152402)
			(xy 334.392608 -285.168401) (xy 334.341456 -285.176498) (xy 334.315562 -285.176976) (xy 334.290067 -285.176529)
			(xy 334.239687 -285.168661) (xy 334.191123 -285.15312) (xy 334.145536 -285.130277) (xy 334.104016 -285.100678)
			(xy 334.067557 -285.065031) (xy 334.05191 -285.044896) (xy 333.639414 -285.044896) (xy 333.623786 -285.065045)
			(xy 333.587321 -285.100686) (xy 333.545796 -285.130277) (xy 333.500205 -285.153112) (xy 333.451638 -285.168644)
			(xy 333.401257 -285.176501) (xy 333.375762 -285.176976) (xy 333.34988 -285.17639) (xy 333.298753 -285.168287)
			(xy 333.249523 -285.152286) (xy 333.203402 -285.128781) (xy 333.161525 -285.098352) (xy 333.124924 -285.061746)
			(xy 333.094499 -285.019866) (xy 333.071 -284.973742) (xy 333.055005 -284.92451) (xy 333.046907 -284.873383)
			(xy 309.6387 -284.873383) (xy 309.6387 -285.071312) (xy 309.638288 -285.081467) (xy 309.630489 -285.10022)
			(xy 309.616089 -285.114543) (xy 309.597295 -285.122242) (xy 309.587138 -285.12262) (xy 308.187598 -285.12262)
			(xy 308.177466 -285.122174) (xy 308.158738 -285.114438) (xy 308.14438 -285.100139) (xy 308.136568 -285.081442)
			(xy 308.136036 -285.071312) (xy 302.0949 -285.071312) (xy 302.094488 -285.081467) (xy 302.086689 -285.10022)
			(xy 302.072289 -285.114543) (xy 302.053495 -285.122242) (xy 302.043338 -285.12262) (xy 300.643798 -285.12262)
			(xy 300.633666 -285.122174) (xy 300.614938 -285.114438) (xy 300.60058 -285.100139) (xy 300.592768 -285.081442)
			(xy 300.592236 -285.071312) (xy 294.5511 -285.071312) (xy 294.550688 -285.081467) (xy 294.542889 -285.10022)
			(xy 294.528489 -285.114543) (xy 294.509695 -285.122242) (xy 294.499538 -285.12262) (xy 293.099998 -285.12262)
			(xy 293.089866 -285.122174) (xy 293.071138 -285.114438) (xy 293.05678 -285.100139) (xy 293.048968 -285.081442)
			(xy 293.048436 -285.071312) (xy 287.0073 -285.071312) (xy 287.006888 -285.081467) (xy 286.999089 -285.10022)
			(xy 286.984689 -285.114543) (xy 286.965895 -285.122242) (xy 286.955738 -285.12262) (xy 285.556198 -285.12262)
			(xy 285.546066 -285.122174) (xy 285.527338 -285.114438) (xy 285.51298 -285.100139) (xy 285.505168 -285.081442)
			(xy 285.504636 -285.071312) (xy 279.4635 -285.071312) (xy 279.463088 -285.081467) (xy 279.455289 -285.10022)
			(xy 279.440889 -285.114543) (xy 279.422095 -285.122242) (xy 279.411938 -285.12262) (xy 278.012398 -285.12262)
			(xy 278.002266 -285.122174) (xy 277.983538 -285.114438) (xy 277.96918 -285.100139) (xy 277.961368 -285.081442)
			(xy 277.960836 -285.071312) (xy 271.9197 -285.071312) (xy 271.919288 -285.081467) (xy 271.911489 -285.10022)
			(xy 271.897089 -285.114543) (xy 271.878295 -285.122242) (xy 271.868138 -285.12262) (xy 270.468598 -285.12262)
			(xy 270.458466 -285.122174) (xy 270.439738 -285.114438) (xy 270.42538 -285.100139) (xy 270.417568 -285.081442)
			(xy 270.417036 -285.071312) (xy 264.3759 -285.071312) (xy 264.375488 -285.081467) (xy 264.367689 -285.10022)
			(xy 264.353289 -285.114543) (xy 264.334495 -285.122242) (xy 264.324338 -285.12262) (xy 262.924798 -285.12262)
			(xy 262.914666 -285.122174) (xy 262.895938 -285.114438) (xy 262.88158 -285.100139) (xy 262.873768 -285.081442)
			(xy 262.873236 -285.071312) (xy 256.8321 -285.071312) (xy 256.831688 -285.081467) (xy 256.823889 -285.10022)
			(xy 256.809489 -285.114543) (xy 256.790695 -285.122242) (xy 256.780538 -285.12262) (xy 255.380998 -285.12262)
			(xy 255.370866 -285.122174) (xy 255.352138 -285.114438) (xy 255.33778 -285.100139) (xy 255.329968 -285.081442)
			(xy 255.329436 -285.071312) (xy 212.371432 -285.071312) (xy 212.370989 -285.081463) (xy 212.363196 -285.10021)
			(xy 212.348806 -285.114531) (xy 212.330023 -285.122236) (xy 212.31987 -285.12262) (xy 210.92033 -285.12262)
			(xy 210.9102 -285.122148) (xy 210.891472 -285.114423) (xy 210.877113 -285.100131) (xy 210.8693 -285.081439)
			(xy 210.868768 -285.071312) (xy 204.827632 -285.071312) (xy 204.827189 -285.081463) (xy 204.819396 -285.10021)
			(xy 204.805006 -285.114531) (xy 204.786223 -285.122236) (xy 204.77607 -285.12262) (xy 203.37653 -285.12262)
			(xy 203.3664 -285.122148) (xy 203.347672 -285.114423) (xy 203.333313 -285.100131) (xy 203.3255 -285.081439)
			(xy 203.324968 -285.071312) (xy 197.283832 -285.071312) (xy 197.283389 -285.081463) (xy 197.275596 -285.10021)
			(xy 197.261206 -285.114531) (xy 197.242423 -285.122236) (xy 197.23227 -285.12262) (xy 195.83273 -285.12262)
			(xy 195.8226 -285.122148) (xy 195.803872 -285.114423) (xy 195.789513 -285.100131) (xy 195.7817 -285.081439)
			(xy 195.781168 -285.071312) (xy 189.740032 -285.071312) (xy 189.739589 -285.081463) (xy 189.731796 -285.10021)
			(xy 189.717406 -285.114531) (xy 189.698623 -285.122236) (xy 189.68847 -285.12262) (xy 188.28893 -285.12262)
			(xy 188.2788 -285.122148) (xy 188.260072 -285.114423) (xy 188.245713 -285.100131) (xy 188.2379 -285.081439)
			(xy 188.237368 -285.071312) (xy 182.196232 -285.071312) (xy 182.195789 -285.081463) (xy 182.187996 -285.10021)
			(xy 182.173606 -285.114531) (xy 182.154823 -285.122236) (xy 182.14467 -285.12262) (xy 180.74513 -285.12262)
			(xy 180.735 -285.122148) (xy 180.716272 -285.114423) (xy 180.701913 -285.100131) (xy 180.6941 -285.081439)
			(xy 180.693568 -285.071312) (xy 174.652432 -285.071312) (xy 174.651989 -285.081463) (xy 174.644196 -285.10021)
			(xy 174.629806 -285.114531) (xy 174.611023 -285.122236) (xy 174.60087 -285.12262) (xy 173.20133 -285.12262)
			(xy 173.1912 -285.122148) (xy 173.172472 -285.114423) (xy 173.158113 -285.100131) (xy 173.1503 -285.081439)
			(xy 173.149768 -285.071312) (xy 167.108632 -285.071312) (xy 167.108189 -285.081463) (xy 167.100396 -285.10021)
			(xy 167.086006 -285.114531) (xy 167.067223 -285.122236) (xy 167.05707 -285.12262) (xy 165.65753 -285.12262)
			(xy 165.6474 -285.122148) (xy 165.628672 -285.114423) (xy 165.614313 -285.100131) (xy 165.6065 -285.081439)
			(xy 165.605968 -285.071312) (xy 159.564832 -285.071312) (xy 159.564389 -285.081463) (xy 159.556596 -285.10021)
			(xy 159.542206 -285.114531) (xy 159.523423 -285.122236) (xy 159.51327 -285.12262) (xy 158.11373 -285.12262)
			(xy 158.1036 -285.122148) (xy 158.084872 -285.114423) (xy 158.070513 -285.100131) (xy 158.0627 -285.081439)
			(xy 158.062168 -285.071312) (xy 132.782926 -285.071312) (xy 132.934202 -285.333186) (xy 132.957062 -285.337504)
			(xy 132.981868 -285.342683) (xy 133.02961 -285.359669) (xy 133.07419 -285.383762) (xy 133.114558 -285.414393)
			(xy 133.149763 -285.450841) (xy 133.178975 -285.492247) (xy 133.201506 -285.537636) (xy 133.216825 -285.585939)
			(xy 133.224572 -285.636017) (xy 133.225032 -285.661354) (xy 133.224524 -285.687241) (xy 133.216425 -285.738379)
			(xy 133.200426 -285.787619) (xy 133.17692 -285.833751) (xy 133.146488 -285.875638) (xy 133.109878 -285.912248)
			(xy 133.067991 -285.94268) (xy 133.021859 -285.966186) (xy 132.972619 -285.982185) (xy 132.921481 -285.990284)
			(xy 132.869707 -285.990284) (xy 132.818569 -285.982185) (xy 132.769329 -285.966186) (xy 132.723197 -285.94268)
			(xy 132.68131 -285.912248) (xy 132.6447 -285.875638) (xy 132.614268 -285.833751) (xy 132.590762 -285.787619)
			(xy 132.574763 -285.738379) (xy 132.566664 -285.687241) (xy 132.566156 -285.661354) (xy 132.566701 -285.633647)
			(xy 132.575886 -285.579) (xy 132.584444 -285.552642) (xy 132.592318 -285.530544) (xy 132.38734 -285.175706)
			(xy 132.36448 -285.171388) (xy 132.33966 -285.166215) (xy 132.29188 -285.149263) (xy 132.247259 -285.125194)
			(xy 132.206851 -285.094575) (xy 132.171609 -285.058129) (xy 132.142365 -285.016715) (xy 132.119809 -284.971312)
			(xy 132.104472 -284.922989) (xy 132.096717 -284.872887) (xy 132.096256 -284.847538) (xy 130.87604 -284.847538)
			(xy 130.875434 -284.875255) (xy 130.866119 -284.929901) (xy 130.857498 -284.95625) (xy 130.849624 -284.978348)
			(xy 131.054602 -285.333186) (xy 131.077462 -285.337504) (xy 131.102268 -285.342683) (xy 131.15001 -285.359669)
			(xy 131.19459 -285.383762) (xy 131.234958 -285.414393) (xy 131.270163 -285.450841) (xy 131.299375 -285.492247)
			(xy 131.321906 -285.537636) (xy 131.337225 -285.585939) (xy 131.344972 -285.636017) (xy 131.345432 -285.661354)
			(xy 131.344924 -285.687241) (xy 131.336825 -285.738379) (xy 131.320826 -285.787619) (xy 131.29732 -285.833751)
			(xy 131.266888 -285.875638) (xy 131.230278 -285.912248) (xy 131.188391 -285.94268) (xy 131.142259 -285.966186)
			(xy 131.093019 -285.982185) (xy 131.041881 -285.990284) (xy 130.990107 -285.990284) (xy 130.938969 -285.982185)
			(xy 130.889729 -285.966186) (xy 130.843597 -285.94268) (xy 130.80171 -285.912248) (xy 130.7651 -285.875638)
			(xy 130.734668 -285.833751) (xy 130.711162 -285.787619) (xy 130.695163 -285.738379) (xy 130.687064 -285.687241)
			(xy 130.686556 -285.661354) (xy 130.687101 -285.633647) (xy 130.696286 -285.579) (xy 130.704844 -285.552642)
			(xy 130.712718 -285.530544) (xy 130.50774 -285.175706) (xy 130.48488 -285.171388) (xy 130.46006 -285.166215)
			(xy 130.41228 -285.149263) (xy 130.367659 -285.125194) (xy 130.327251 -285.094575) (xy 130.292009 -285.058129)
			(xy 130.262765 -285.016715) (xy 130.240209 -284.971312) (xy 130.224872 -284.922989) (xy 130.217117 -284.872887)
			(xy 130.216656 -284.847538) (xy 128.99644 -284.847538) (xy 128.995834 -284.875255) (xy 128.986519 -284.929901)
			(xy 128.977898 -284.95625) (xy 128.970024 -284.978348) (xy 129.175002 -285.333186) (xy 129.197862 -285.337504)
			(xy 129.222668 -285.342683) (xy 129.27041 -285.359669) (xy 129.31499 -285.383762) (xy 129.355358 -285.414393)
			(xy 129.390563 -285.450841) (xy 129.419775 -285.492247) (xy 129.442306 -285.537636) (xy 129.457625 -285.585939)
			(xy 129.465372 -285.636017) (xy 129.465832 -285.661354) (xy 129.465324 -285.687241) (xy 129.457225 -285.738379)
			(xy 129.441226 -285.787619) (xy 129.41772 -285.833751) (xy 129.387288 -285.875638) (xy 129.350678 -285.912248)
			(xy 129.308791 -285.94268) (xy 129.262659 -285.966186) (xy 129.213419 -285.982185) (xy 129.162281 -285.990284)
			(xy 129.110507 -285.990284) (xy 129.059369 -285.982185) (xy 129.010129 -285.966186) (xy 128.963997 -285.94268)
			(xy 128.92211 -285.912248) (xy 128.8855 -285.875638) (xy 128.855068 -285.833751) (xy 128.831562 -285.787619)
			(xy 128.815563 -285.738379) (xy 128.807464 -285.687241) (xy 128.806956 -285.661354) (xy 128.807501 -285.633647)
			(xy 128.816686 -285.579) (xy 128.825244 -285.552642) (xy 128.833118 -285.530544) (xy 128.62814 -285.175706)
			(xy 128.60528 -285.171388) (xy 128.58046 -285.166215) (xy 128.53268 -285.149263) (xy 128.488059 -285.125194)
			(xy 128.447651 -285.094575) (xy 128.412409 -285.058129) (xy 128.383165 -285.016715) (xy 128.360609 -284.971312)
			(xy 128.345272 -284.922989) (xy 128.337517 -284.872887) (xy 128.337056 -284.847538) (xy 127.11684 -284.847538)
			(xy 127.116234 -284.875255) (xy 127.106919 -284.929901) (xy 127.098298 -284.95625) (xy 127.090424 -284.978348)
			(xy 127.295402 -285.333186) (xy 127.318262 -285.337504) (xy 127.343068 -285.342683) (xy 127.39081 -285.359669)
			(xy 127.43539 -285.383762) (xy 127.475758 -285.414393) (xy 127.510963 -285.450841) (xy 127.540175 -285.492247)
			(xy 127.562706 -285.537636) (xy 127.578025 -285.585939) (xy 127.585772 -285.636017) (xy 127.586232 -285.661354)
			(xy 127.585724 -285.687241) (xy 127.577625 -285.738379) (xy 127.561626 -285.787619) (xy 127.53812 -285.833751)
			(xy 127.507688 -285.875638) (xy 127.471078 -285.912248) (xy 127.429191 -285.94268) (xy 127.383059 -285.966186)
			(xy 127.333819 -285.982185) (xy 127.282681 -285.990284) (xy 127.230907 -285.990284) (xy 127.179769 -285.982185)
			(xy 127.130529 -285.966186) (xy 127.084397 -285.94268) (xy 127.04251 -285.912248) (xy 127.0059 -285.875638)
			(xy 126.975468 -285.833751) (xy 126.951962 -285.787619) (xy 126.935963 -285.738379) (xy 126.927864 -285.687241)
			(xy 126.927356 -285.661354) (xy 126.927901 -285.633647) (xy 126.937086 -285.579) (xy 126.945644 -285.552642)
			(xy 126.953518 -285.530544) (xy 126.74854 -285.175706) (xy 126.72568 -285.171388) (xy 126.70086 -285.166215)
			(xy 126.65308 -285.149263) (xy 126.608459 -285.125194) (xy 126.568051 -285.094575) (xy 126.532809 -285.058129)
			(xy 126.503565 -285.016715) (xy 126.481009 -284.971312) (xy 126.465672 -284.922989) (xy 126.457917 -284.872887)
			(xy 126.457456 -284.847538) (xy 125.23724 -284.847538) (xy 125.236634 -284.875255) (xy 125.227319 -284.929901)
			(xy 125.218698 -284.95625) (xy 125.210824 -284.978348) (xy 125.415802 -285.333186) (xy 125.438662 -285.337504)
			(xy 125.463468 -285.342683) (xy 125.51121 -285.359669) (xy 125.55579 -285.383762) (xy 125.596158 -285.414393)
			(xy 125.631363 -285.450841) (xy 125.660575 -285.492247) (xy 125.683106 -285.537636) (xy 125.698425 -285.585939)
			(xy 125.706172 -285.636017) (xy 125.706632 -285.661354) (xy 125.706124 -285.687241) (xy 125.698025 -285.738379)
			(xy 125.682026 -285.787619) (xy 125.65852 -285.833751) (xy 125.628088 -285.875638) (xy 125.591478 -285.912248)
			(xy 125.549591 -285.94268) (xy 125.503459 -285.966186) (xy 125.454219 -285.982185) (xy 125.403081 -285.990284)
			(xy 125.351307 -285.990284) (xy 125.300169 -285.982185) (xy 125.250929 -285.966186) (xy 125.204797 -285.94268)
			(xy 125.16291 -285.912248) (xy 125.1263 -285.875638) (xy 125.095868 -285.833751) (xy 125.072362 -285.787619)
			(xy 125.056363 -285.738379) (xy 125.048264 -285.687241) (xy 125.047756 -285.661354) (xy 125.048301 -285.633647)
			(xy 125.057486 -285.579) (xy 125.066044 -285.552642) (xy 125.073918 -285.530544) (xy 124.86894 -285.175706)
			(xy 124.84608 -285.171388) (xy 124.82126 -285.166215) (xy 124.77348 -285.149263) (xy 124.728859 -285.125194)
			(xy 124.688451 -285.094575) (xy 124.653209 -285.058129) (xy 124.623965 -285.016715) (xy 124.601409 -284.971312)
			(xy 124.586072 -284.922989) (xy 124.578317 -284.872887) (xy 124.577856 -284.847538) (xy 123.35764 -284.847538)
			(xy 123.357034 -284.875255) (xy 123.347719 -284.929901) (xy 123.339098 -284.95625) (xy 123.331224 -284.978348)
			(xy 123.536202 -285.333186) (xy 123.559062 -285.337504) (xy 123.583868 -285.342683) (xy 123.63161 -285.359669)
			(xy 123.67619 -285.383762) (xy 123.716558 -285.414393) (xy 123.751763 -285.450841) (xy 123.780975 -285.492247)
			(xy 123.803506 -285.537636) (xy 123.818825 -285.585939) (xy 123.826572 -285.636017) (xy 123.827032 -285.661354)
			(xy 123.826524 -285.687241) (xy 123.818425 -285.738379) (xy 123.802426 -285.787619) (xy 123.77892 -285.833751)
			(xy 123.748488 -285.875638) (xy 123.711878 -285.912248) (xy 123.669991 -285.94268) (xy 123.623859 -285.966186)
			(xy 123.574619 -285.982185) (xy 123.523481 -285.990284) (xy 123.471707 -285.990284) (xy 123.420569 -285.982185)
			(xy 123.371329 -285.966186) (xy 123.325197 -285.94268) (xy 123.28331 -285.912248) (xy 123.2467 -285.875638)
			(xy 123.216268 -285.833751) (xy 123.192762 -285.787619) (xy 123.176763 -285.738379) (xy 123.168664 -285.687241)
			(xy 123.168156 -285.661354) (xy 123.168701 -285.633647) (xy 123.177886 -285.579) (xy 123.186444 -285.552642)
			(xy 123.194318 -285.530544) (xy 122.98934 -285.175706) (xy 122.96648 -285.171388) (xy 122.94166 -285.166215)
			(xy 122.89388 -285.149263) (xy 122.849259 -285.125194) (xy 122.808851 -285.094575) (xy 122.773609 -285.058129)
			(xy 122.744365 -285.016715) (xy 122.721809 -284.971312) (xy 122.706472 -284.922989) (xy 122.698717 -284.872887)
			(xy 122.698256 -284.847538) (xy 121.47804 -284.847538) (xy 121.477434 -284.875255) (xy 121.468119 -284.929901)
			(xy 121.459498 -284.95625) (xy 121.451624 -284.978348) (xy 121.656602 -285.333186) (xy 121.679462 -285.337504)
			(xy 121.704268 -285.342683) (xy 121.75201 -285.359669) (xy 121.79659 -285.383762) (xy 121.836958 -285.414393)
			(xy 121.872163 -285.450841) (xy 121.901375 -285.492247) (xy 121.923906 -285.537636) (xy 121.939225 -285.585939)
			(xy 121.946972 -285.636017) (xy 121.947432 -285.661354) (xy 121.946924 -285.687241) (xy 121.938825 -285.738379)
			(xy 121.922826 -285.787619) (xy 121.89932 -285.833751) (xy 121.868888 -285.875638) (xy 121.832278 -285.912248)
			(xy 121.790391 -285.94268) (xy 121.744259 -285.966186) (xy 121.695019 -285.982185) (xy 121.643881 -285.990284)
			(xy 121.592107 -285.990284) (xy 121.540969 -285.982185) (xy 121.491729 -285.966186) (xy 121.445597 -285.94268)
			(xy 121.40371 -285.912248) (xy 121.3671 -285.875638) (xy 121.336668 -285.833751) (xy 121.313162 -285.787619)
			(xy 121.297163 -285.738379) (xy 121.289064 -285.687241) (xy 121.288556 -285.661354) (xy 121.289101 -285.633647)
			(xy 121.298286 -285.579) (xy 121.306844 -285.552642) (xy 121.314718 -285.530544) (xy 121.10974 -285.175706)
			(xy 121.08688 -285.171388) (xy 121.06206 -285.166215) (xy 121.01428 -285.149263) (xy 120.969659 -285.125194)
			(xy 120.929251 -285.094575) (xy 120.894009 -285.058129) (xy 120.864765 -285.016715) (xy 120.842209 -284.971312)
			(xy 120.826872 -284.922989) (xy 120.819117 -284.872887) (xy 120.818656 -284.847538) (xy 119.59844 -284.847538)
			(xy 119.597834 -284.875255) (xy 119.588519 -284.929901) (xy 119.579898 -284.95625) (xy 119.572024 -284.978348)
			(xy 119.777002 -285.333186) (xy 119.799862 -285.337504) (xy 119.824668 -285.342683) (xy 119.87241 -285.359669)
			(xy 119.91699 -285.383762) (xy 119.957358 -285.414393) (xy 119.992563 -285.450841) (xy 120.021775 -285.492247)
			(xy 120.044306 -285.537636) (xy 120.059625 -285.585939) (xy 120.067372 -285.636017) (xy 120.067832 -285.661354)
			(xy 120.067324 -285.687241) (xy 120.059225 -285.738379) (xy 120.043226 -285.787619) (xy 120.01972 -285.833751)
			(xy 119.989288 -285.875638) (xy 119.952678 -285.912248) (xy 119.910791 -285.94268) (xy 119.864659 -285.966186)
			(xy 119.815419 -285.982185) (xy 119.764281 -285.990284) (xy 119.712507 -285.990284) (xy 119.661369 -285.982185)
			(xy 119.612129 -285.966186) (xy 119.565997 -285.94268) (xy 119.52411 -285.912248) (xy 119.4875 -285.875638)
			(xy 119.457068 -285.833751) (xy 119.433562 -285.787619) (xy 119.417563 -285.738379) (xy 119.409464 -285.687241)
			(xy 119.408956 -285.661354) (xy 119.409501 -285.633647) (xy 119.418686 -285.579) (xy 119.427244 -285.552642)
			(xy 119.435118 -285.530544) (xy 119.23014 -285.175706) (xy 119.20728 -285.171388) (xy 119.18246 -285.166215)
			(xy 119.13468 -285.149263) (xy 119.090059 -285.125194) (xy 119.049651 -285.094575) (xy 119.014409 -285.058129)
			(xy 118.985165 -285.016715) (xy 118.962609 -284.971312) (xy 118.947272 -284.922989) (xy 118.939517 -284.872887)
			(xy 118.939056 -284.847538) (xy 104.56164 -284.847538) (xy 104.561248 -284.872916) (xy 104.553473 -284.923072)
			(xy 104.538096 -284.971442) (xy 104.515481 -285.016882) (xy 104.486165 -285.058314) (xy 104.45084 -285.09476)
			(xy 104.410343 -285.125356) (xy 104.365633 -285.149379) (xy 104.317766 -285.166259) (xy 104.292908 -285.171388)
			(xy 104.270048 -285.175706) (xy 104.06507 -285.530544) (xy 104.072944 -285.552642) (xy 104.081516 -285.578997)
			(xy 104.090707 -285.633645) (xy 104.091232 -285.661354) (xy 104.090724 -285.687241) (xy 104.082625 -285.738379)
			(xy 104.066626 -285.787619) (xy 104.04312 -285.833751) (xy 104.012688 -285.875638) (xy 103.976078 -285.912248)
			(xy 103.934191 -285.94268) (xy 103.888059 -285.966186) (xy 103.838819 -285.982185) (xy 103.787681 -285.990284)
			(xy 103.735907 -285.990284) (xy 103.684769 -285.982185) (xy 103.635529 -285.966186) (xy 103.589397 -285.94268)
			(xy 103.54751 -285.912248) (xy 103.5109 -285.875638) (xy 103.480468 -285.833751) (xy 103.456962 -285.787619)
			(xy 103.440963 -285.738379) (xy 103.432864 -285.687241) (xy 103.432356 -285.661354) (xy 103.151432 -285.661354)
			(xy 103.151432 -285.661862) (xy 103.150853 -285.689379) (xy 103.141659 -285.74364) (xy 103.133144 -285.769812)
			(xy 103.125524 -285.79191) (xy 103.330756 -286.147256) (xy 103.353616 -286.151574) (xy 103.378427 -286.156786)
			(xy 103.426204 -286.173734) (xy 103.470823 -286.197799) (xy 103.51123 -286.228413) (xy 103.546472 -286.264855)
			(xy 103.575717 -286.306263) (xy 103.598276 -286.351662) (xy 103.613617 -286.399979) (xy 103.621377 -286.450077)
			(xy 103.62184 -286.475424) (xy 119.878856 -286.475424) (xy 119.879354 -286.450079) (xy 119.887123 -286.399987)
			(xy 119.902468 -286.351675) (xy 119.925026 -286.306281) (xy 119.954266 -286.264873) (xy 119.989499 -286.228429)
			(xy 120.029894 -286.197807) (xy 120.0745 -286.173728) (xy 120.122266 -286.156759) (xy 120.14708 -286.151574)
			(xy 120.16994 -286.147256) (xy 120.374918 -285.792164) (xy 120.367044 -285.77032) (xy 120.358471 -285.743899)
			(xy 120.34927 -285.689126) (xy 120.348756 -285.661354) (xy 120.349264 -285.635467) (xy 120.357363 -285.584329)
			(xy 120.373362 -285.535089) (xy 120.396868 -285.488957) (xy 120.4273 -285.44707) (xy 120.46391 -285.41046)
			(xy 120.505797 -285.380028) (xy 120.551929 -285.356522) (xy 120.601169 -285.340523) (xy 120.652307 -285.332424)
			(xy 120.704081 -285.332424) (xy 120.755219 -285.340523) (xy 120.804459 -285.356522) (xy 120.850591 -285.380028)
			(xy 120.892478 -285.41046) (xy 120.929088 -285.44707) (xy 120.95952 -285.488957) (xy 120.983026 -285.535089)
			(xy 120.999025 -285.584329) (xy 121.007124 -285.635467) (xy 121.007632 -285.661354) (xy 121.007172 -285.686689)
			(xy 120.999413 -285.736761) (xy 120.984085 -285.785057) (xy 120.961549 -285.830439) (xy 120.932336 -285.87184)
			(xy 120.897134 -285.908285) (xy 120.856771 -285.938915) (xy 120.812197 -285.963011) (xy 120.764462 -285.980004)
			(xy 120.739662 -285.985204) (xy 120.716802 -285.989522) (xy 120.511824 -286.344614) (xy 120.519698 -286.366458)
			(xy 120.528349 -286.392865) (xy 120.537666 -286.447642) (xy 120.53824 -286.475424) (xy 121.758456 -286.475424)
			(xy 121.758954 -286.450079) (xy 121.766723 -286.399987) (xy 121.782068 -286.351675) (xy 121.804626 -286.306281)
			(xy 121.833866 -286.264873) (xy 121.869099 -286.228429) (xy 121.909494 -286.197807) (xy 121.9541 -286.173728)
			(xy 122.001866 -286.156759) (xy 122.02668 -286.151574) (xy 122.04954 -286.147256) (xy 122.254518 -285.792164)
			(xy 122.246644 -285.77032) (xy 122.238071 -285.743899) (xy 122.22887 -285.689126) (xy 122.228356 -285.661354)
			(xy 122.228864 -285.635467) (xy 122.236963 -285.584329) (xy 122.252962 -285.535089) (xy 122.276468 -285.488957)
			(xy 122.3069 -285.44707) (xy 122.34351 -285.41046) (xy 122.385397 -285.380028) (xy 122.431529 -285.356522)
			(xy 122.480769 -285.340523) (xy 122.531907 -285.332424) (xy 122.583681 -285.332424) (xy 122.634819 -285.340523)
			(xy 122.684059 -285.356522) (xy 122.730191 -285.380028) (xy 122.772078 -285.41046) (xy 122.808688 -285.44707)
			(xy 122.83912 -285.488957) (xy 122.862626 -285.535089) (xy 122.878625 -285.584329) (xy 122.886724 -285.635467)
			(xy 122.887232 -285.661354) (xy 122.886772 -285.686689) (xy 122.879013 -285.736761) (xy 122.863685 -285.785057)
			(xy 122.841149 -285.830439) (xy 122.811936 -285.87184) (xy 122.776734 -285.908285) (xy 122.736371 -285.938915)
			(xy 122.691797 -285.963011) (xy 122.644062 -285.980004) (xy 122.619262 -285.985204) (xy 122.596402 -285.989522)
			(xy 122.391424 -286.344614) (xy 122.399298 -286.366458) (xy 122.407949 -286.392865) (xy 122.417266 -286.447642)
			(xy 122.41784 -286.475424) (xy 123.638056 -286.475424) (xy 123.638554 -286.450079) (xy 123.646323 -286.399987)
			(xy 123.661668 -286.351675) (xy 123.684226 -286.306281) (xy 123.713466 -286.264873) (xy 123.748699 -286.228429)
			(xy 123.789094 -286.197807) (xy 123.8337 -286.173728) (xy 123.881466 -286.156759) (xy 123.90628 -286.151574)
			(xy 123.92914 -286.147256) (xy 124.134118 -285.792164) (xy 124.126244 -285.77032) (xy 124.117671 -285.743899)
			(xy 124.10847 -285.689126) (xy 124.107956 -285.661354) (xy 124.108464 -285.635467) (xy 124.116563 -285.584329)
			(xy 124.132562 -285.535089) (xy 124.156068 -285.488957) (xy 124.1865 -285.44707) (xy 124.22311 -285.41046)
			(xy 124.264997 -285.380028) (xy 124.311129 -285.356522) (xy 124.360369 -285.340523) (xy 124.411507 -285.332424)
			(xy 124.463281 -285.332424) (xy 124.514419 -285.340523) (xy 124.563659 -285.356522) (xy 124.609791 -285.380028)
			(xy 124.651678 -285.41046) (xy 124.688288 -285.44707) (xy 124.71872 -285.488957) (xy 124.742226 -285.535089)
			(xy 124.758225 -285.584329) (xy 124.766324 -285.635467) (xy 124.766832 -285.661354) (xy 124.766372 -285.686689)
			(xy 124.758613 -285.736761) (xy 124.743285 -285.785057) (xy 124.720749 -285.830439) (xy 124.691536 -285.87184)
			(xy 124.656334 -285.908285) (xy 124.615971 -285.938915) (xy 124.571397 -285.963011) (xy 124.523662 -285.980004)
			(xy 124.498862 -285.985204) (xy 124.476002 -285.989522) (xy 124.271024 -286.344614) (xy 124.278898 -286.366458)
			(xy 124.287549 -286.392865) (xy 124.296866 -286.447642) (xy 124.29744 -286.475424) (xy 125.517656 -286.475424)
			(xy 125.518154 -286.450079) (xy 125.525923 -286.399987) (xy 125.541268 -286.351675) (xy 125.563826 -286.306281)
			(xy 125.593066 -286.264873) (xy 125.628299 -286.228429) (xy 125.668694 -286.197807) (xy 125.7133 -286.173728)
			(xy 125.761066 -286.156759) (xy 125.78588 -286.151574) (xy 125.80874 -286.147256) (xy 126.013718 -285.792164)
			(xy 126.005844 -285.77032) (xy 125.997271 -285.743899) (xy 125.98807 -285.689126) (xy 125.987556 -285.661354)
			(xy 125.988064 -285.635467) (xy 125.996163 -285.584329) (xy 126.012162 -285.535089) (xy 126.035668 -285.488957)
			(xy 126.0661 -285.44707) (xy 126.10271 -285.41046) (xy 126.144597 -285.380028) (xy 126.190729 -285.356522)
			(xy 126.239969 -285.340523) (xy 126.291107 -285.332424) (xy 126.342881 -285.332424) (xy 126.394019 -285.340523)
			(xy 126.443259 -285.356522) (xy 126.489391 -285.380028) (xy 126.531278 -285.41046) (xy 126.567888 -285.44707)
			(xy 126.59832 -285.488957) (xy 126.621826 -285.535089) (xy 126.637825 -285.584329) (xy 126.645924 -285.635467)
			(xy 126.646432 -285.661354) (xy 126.645972 -285.686689) (xy 126.638213 -285.736761) (xy 126.622885 -285.785057)
			(xy 126.600349 -285.830439) (xy 126.571136 -285.87184) (xy 126.535934 -285.908285) (xy 126.495571 -285.938915)
			(xy 126.450997 -285.963011) (xy 126.403262 -285.980004) (xy 126.378462 -285.985204) (xy 126.355602 -285.989522)
			(xy 126.150624 -286.344614) (xy 126.158498 -286.366458) (xy 126.167149 -286.392865) (xy 126.176466 -286.447642)
			(xy 126.17704 -286.475424) (xy 127.397256 -286.475424) (xy 127.397754 -286.450079) (xy 127.405523 -286.399987)
			(xy 127.420868 -286.351675) (xy 127.443426 -286.306281) (xy 127.472666 -286.264873) (xy 127.507899 -286.228429)
			(xy 127.548294 -286.197807) (xy 127.5929 -286.173728) (xy 127.640666 -286.156759) (xy 127.66548 -286.151574)
			(xy 127.68834 -286.147256) (xy 127.893318 -285.792164) (xy 127.885444 -285.77032) (xy 127.876871 -285.743899)
			(xy 127.86767 -285.689126) (xy 127.867156 -285.661354) (xy 127.867664 -285.635467) (xy 127.875763 -285.584329)
			(xy 127.891762 -285.535089) (xy 127.915268 -285.488957) (xy 127.9457 -285.44707) (xy 127.98231 -285.41046)
			(xy 128.024197 -285.380028) (xy 128.070329 -285.356522) (xy 128.119569 -285.340523) (xy 128.170707 -285.332424)
			(xy 128.222481 -285.332424) (xy 128.273619 -285.340523) (xy 128.322859 -285.356522) (xy 128.368991 -285.380028)
			(xy 128.410878 -285.41046) (xy 128.447488 -285.44707) (xy 128.47792 -285.488957) (xy 128.501426 -285.535089)
			(xy 128.517425 -285.584329) (xy 128.525524 -285.635467) (xy 128.526032 -285.661354) (xy 128.525572 -285.686689)
			(xy 128.517813 -285.736761) (xy 128.502485 -285.785057) (xy 128.479949 -285.830439) (xy 128.450736 -285.87184)
			(xy 128.415534 -285.908285) (xy 128.375171 -285.938915) (xy 128.330597 -285.963011) (xy 128.282862 -285.980004)
			(xy 128.258062 -285.985204) (xy 128.235202 -285.989522) (xy 128.030224 -286.344614) (xy 128.038098 -286.366458)
			(xy 128.046749 -286.392865) (xy 128.056066 -286.447642) (xy 128.05664 -286.475424) (xy 129.276856 -286.475424)
			(xy 129.277354 -286.450079) (xy 129.285123 -286.399987) (xy 129.300468 -286.351675) (xy 129.323026 -286.306281)
			(xy 129.352266 -286.264873) (xy 129.387499 -286.228429) (xy 129.427894 -286.197807) (xy 129.4725 -286.173728)
			(xy 129.520266 -286.156759) (xy 129.54508 -286.151574) (xy 129.56794 -286.147256) (xy 129.772918 -285.792164)
			(xy 129.765044 -285.77032) (xy 129.756471 -285.743899) (xy 129.74727 -285.689126) (xy 129.746756 -285.661354)
			(xy 129.747264 -285.635467) (xy 129.755363 -285.584329) (xy 129.771362 -285.535089) (xy 129.794868 -285.488957)
			(xy 129.8253 -285.44707) (xy 129.86191 -285.41046) (xy 129.903797 -285.380028) (xy 129.949929 -285.356522)
			(xy 129.999169 -285.340523) (xy 130.050307 -285.332424) (xy 130.102081 -285.332424) (xy 130.153219 -285.340523)
			(xy 130.202459 -285.356522) (xy 130.248591 -285.380028) (xy 130.290478 -285.41046) (xy 130.327088 -285.44707)
			(xy 130.35752 -285.488957) (xy 130.381026 -285.535089) (xy 130.397025 -285.584329) (xy 130.405124 -285.635467)
			(xy 130.405632 -285.661354) (xy 130.405172 -285.686689) (xy 130.397413 -285.736761) (xy 130.382085 -285.785057)
			(xy 130.359549 -285.830439) (xy 130.330336 -285.87184) (xy 130.295134 -285.908285) (xy 130.254771 -285.938915)
			(xy 130.210197 -285.963011) (xy 130.162462 -285.980004) (xy 130.137662 -285.985204) (xy 130.114802 -285.989522)
			(xy 129.909824 -286.344614) (xy 129.917698 -286.366458) (xy 129.926349 -286.392865) (xy 129.935666 -286.447642)
			(xy 129.93624 -286.475424) (xy 131.156456 -286.475424) (xy 131.156954 -286.450079) (xy 131.164723 -286.399987)
			(xy 131.180068 -286.351675) (xy 131.202626 -286.306281) (xy 131.231866 -286.264873) (xy 131.267099 -286.228429)
			(xy 131.307494 -286.197807) (xy 131.3521 -286.173728) (xy 131.399866 -286.156759) (xy 131.42468 -286.151574)
			(xy 131.44754 -286.147256) (xy 131.652518 -285.792164) (xy 131.644644 -285.77032) (xy 131.636071 -285.743899)
			(xy 131.62687 -285.689126) (xy 131.626356 -285.661354) (xy 131.626864 -285.635467) (xy 131.634963 -285.584329)
			(xy 131.650962 -285.535089) (xy 131.674468 -285.488957) (xy 131.7049 -285.44707) (xy 131.74151 -285.41046)
			(xy 131.783397 -285.380028) (xy 131.829529 -285.356522) (xy 131.878769 -285.340523) (xy 131.929907 -285.332424)
			(xy 131.981681 -285.332424) (xy 132.032819 -285.340523) (xy 132.082059 -285.356522) (xy 132.128191 -285.380028)
			(xy 132.170078 -285.41046) (xy 132.206688 -285.44707) (xy 132.23712 -285.488957) (xy 132.260626 -285.535089)
			(xy 132.276625 -285.584329) (xy 132.284724 -285.635467) (xy 132.285232 -285.661354) (xy 132.284772 -285.686689)
			(xy 132.277013 -285.736761) (xy 132.261685 -285.785057) (xy 132.239149 -285.830439) (xy 132.209936 -285.87184)
			(xy 132.174734 -285.908285) (xy 132.134371 -285.938915) (xy 132.089797 -285.963011) (xy 132.042062 -285.980004)
			(xy 132.017262 -285.985204) (xy 131.994402 -285.989522) (xy 131.789424 -286.344614) (xy 131.797298 -286.366458)
			(xy 131.805949 -286.392865) (xy 131.815266 -286.447642) (xy 131.81584 -286.475424) (xy 133.036056 -286.475424)
			(xy 133.036554 -286.450079) (xy 133.044323 -286.399987) (xy 133.059668 -286.351675) (xy 133.082226 -286.306281)
			(xy 133.111466 -286.264873) (xy 133.146699 -286.228429) (xy 133.187094 -286.197807) (xy 133.2317 -286.173728)
			(xy 133.279466 -286.156759) (xy 133.30428 -286.151574) (xy 133.32714 -286.147256) (xy 133.532118 -285.792164)
			(xy 133.524244 -285.77032) (xy 133.515671 -285.743899) (xy 133.50647 -285.689126) (xy 133.505956 -285.661354)
			(xy 133.506464 -285.635467) (xy 133.514563 -285.584329) (xy 133.530562 -285.535089) (xy 133.554068 -285.488957)
			(xy 133.5845 -285.44707) (xy 133.62111 -285.41046) (xy 133.662997 -285.380028) (xy 133.709129 -285.356522)
			(xy 133.758369 -285.340523) (xy 133.809507 -285.332424) (xy 133.861281 -285.332424) (xy 133.912419 -285.340523)
			(xy 133.961659 -285.356522) (xy 134.007791 -285.380028) (xy 134.049678 -285.41046) (xy 134.086288 -285.44707)
			(xy 134.11672 -285.488957) (xy 134.140226 -285.535089) (xy 134.156225 -285.584329) (xy 134.164324 -285.635467)
			(xy 134.164832 -285.661354) (xy 134.164372 -285.686689) (xy 134.156613 -285.736761) (xy 134.141285 -285.785057)
			(xy 134.118749 -285.830439) (xy 134.089536 -285.87184) (xy 134.054334 -285.908285) (xy 134.036986 -285.92145)
			(xy 162.162236 -285.92145) (xy 162.162236 -285.51251) (xy 162.162672 -285.502339) (xy 162.170453 -285.483545)
			(xy 162.184835 -285.46916) (xy 162.203627 -285.461374) (xy 162.213798 -285.460948) (xy 163.613338 -285.460948)
			(xy 163.623499 -285.461403) (xy 163.642271 -285.469191) (xy 163.656636 -285.483569) (xy 163.664407 -285.502348)
			(xy 163.6649 -285.51251) (xy 163.6649 -285.92145) (xy 169.706036 -285.92145) (xy 169.706036 -285.51251)
			(xy 169.706472 -285.502339) (xy 169.714253 -285.483545) (xy 169.728635 -285.46916) (xy 169.747427 -285.461374)
			(xy 169.757598 -285.460948) (xy 171.157138 -285.460948) (xy 171.167299 -285.461403) (xy 171.186071 -285.469191)
			(xy 171.200436 -285.483569) (xy 171.208207 -285.502348) (xy 171.2087 -285.51251) (xy 171.2087 -285.92145)
			(xy 177.249836 -285.92145) (xy 177.249836 -285.51251) (xy 177.250272 -285.502339) (xy 177.258053 -285.483545)
			(xy 177.272435 -285.46916) (xy 177.291227 -285.461374) (xy 177.301398 -285.460948) (xy 178.700938 -285.460948)
			(xy 178.711099 -285.461403) (xy 178.729871 -285.469191) (xy 178.744236 -285.483569) (xy 178.752007 -285.502348)
			(xy 178.7525 -285.51251) (xy 178.7525 -285.92145) (xy 184.793636 -285.92145) (xy 184.793636 -285.51251)
			(xy 184.794072 -285.502339) (xy 184.801853 -285.483545) (xy 184.816235 -285.46916) (xy 184.835027 -285.461374)
			(xy 184.845198 -285.460948) (xy 186.244738 -285.460948) (xy 186.254899 -285.461403) (xy 186.273671 -285.469191)
			(xy 186.288036 -285.483569) (xy 186.295807 -285.502348) (xy 186.2963 -285.51251) (xy 186.2963 -285.92145)
			(xy 192.337436 -285.92145) (xy 192.337436 -285.51251) (xy 192.337872 -285.502339) (xy 192.345653 -285.483545)
			(xy 192.360035 -285.46916) (xy 192.378827 -285.461374) (xy 192.388998 -285.460948) (xy 193.788538 -285.460948)
			(xy 193.798699 -285.461403) (xy 193.817471 -285.469191) (xy 193.831836 -285.483569) (xy 193.839607 -285.502348)
			(xy 193.8401 -285.51251) (xy 193.8401 -285.92145) (xy 199.881236 -285.92145) (xy 199.881236 -285.51251)
			(xy 199.881672 -285.502339) (xy 199.889453 -285.483545) (xy 199.903835 -285.46916) (xy 199.922627 -285.461374)
			(xy 199.932798 -285.460948) (xy 201.332338 -285.460948) (xy 201.342499 -285.461403) (xy 201.361271 -285.469191)
			(xy 201.375636 -285.483569) (xy 201.383407 -285.502348) (xy 201.3839 -285.51251) (xy 201.3839 -285.92145)
			(xy 207.425036 -285.92145) (xy 207.425036 -285.51251) (xy 207.425472 -285.502339) (xy 207.433253 -285.483545)
			(xy 207.447635 -285.46916) (xy 207.466427 -285.461374) (xy 207.476598 -285.460948) (xy 208.876138 -285.460948)
			(xy 208.886299 -285.461403) (xy 208.905071 -285.469191) (xy 208.919436 -285.483569) (xy 208.927207 -285.502348)
			(xy 208.9277 -285.51251) (xy 208.9277 -285.92145) (xy 214.968836 -285.92145) (xy 214.968836 -285.51251)
			(xy 214.969272 -285.502339) (xy 214.977053 -285.483545) (xy 214.991435 -285.46916) (xy 215.010227 -285.461374)
			(xy 215.020398 -285.460948) (xy 216.419938 -285.460948) (xy 216.430099 -285.461403) (xy 216.448871 -285.469191)
			(xy 216.463236 -285.483569) (xy 216.471007 -285.502348) (xy 216.4715 -285.51251) (xy 216.4715 -285.92145)
			(xy 259.429504 -285.92145) (xy 259.429504 -285.51251) (xy 259.430041 -285.502357) (xy 259.437806 -285.483595)
			(xy 259.452158 -285.46923) (xy 259.470913 -285.461449) (xy 259.481066 -285.460948) (xy 260.880606 -285.460948)
			(xy 260.890779 -285.461359) (xy 260.909576 -285.469148) (xy 260.923961 -285.483537) (xy 260.931744 -285.502337)
			(xy 260.932168 -285.51251) (xy 260.932168 -285.92145) (xy 266.973304 -285.92145) (xy 266.973304 -285.51251)
			(xy 266.973841 -285.502357) (xy 266.981606 -285.483595) (xy 266.995958 -285.46923) (xy 267.014713 -285.461449)
			(xy 267.024866 -285.460948) (xy 268.424406 -285.460948) (xy 268.434579 -285.461359) (xy 268.453376 -285.469148)
			(xy 268.467761 -285.483537) (xy 268.475544 -285.502337) (xy 268.475968 -285.51251) (xy 268.475968 -285.92145)
			(xy 274.517104 -285.92145) (xy 274.517104 -285.51251) (xy 274.517641 -285.502357) (xy 274.525406 -285.483595)
			(xy 274.539758 -285.46923) (xy 274.558513 -285.461449) (xy 274.568666 -285.460948) (xy 275.968206 -285.460948)
			(xy 275.978379 -285.461359) (xy 275.997176 -285.469148) (xy 276.011561 -285.483537) (xy 276.019344 -285.502337)
			(xy 276.019768 -285.51251) (xy 276.019768 -285.92145) (xy 282.060904 -285.92145) (xy 282.060904 -285.51251)
			(xy 282.061441 -285.502357) (xy 282.069206 -285.483595) (xy 282.083558 -285.46923) (xy 282.102313 -285.461449)
			(xy 282.112466 -285.460948) (xy 283.512006 -285.460948) (xy 283.522179 -285.461359) (xy 283.540976 -285.469148)
			(xy 283.555361 -285.483537) (xy 283.563144 -285.502337) (xy 283.563568 -285.51251) (xy 283.563568 -285.92145)
			(xy 289.604704 -285.92145) (xy 289.604704 -285.51251) (xy 289.605241 -285.502357) (xy 289.613006 -285.483595)
			(xy 289.627358 -285.46923) (xy 289.646113 -285.461449) (xy 289.656266 -285.460948) (xy 291.055806 -285.460948)
			(xy 291.065979 -285.461359) (xy 291.084776 -285.469148) (xy 291.099161 -285.483537) (xy 291.106944 -285.502337)
			(xy 291.107368 -285.51251) (xy 291.107368 -285.92145) (xy 297.148504 -285.92145) (xy 297.148504 -285.51251)
			(xy 297.149041 -285.502357) (xy 297.156806 -285.483595) (xy 297.171158 -285.46923) (xy 297.189913 -285.461449)
			(xy 297.200066 -285.460948) (xy 298.599606 -285.460948) (xy 298.609779 -285.461359) (xy 298.628576 -285.469148)
			(xy 298.642961 -285.483537) (xy 298.650744 -285.502337) (xy 298.651168 -285.51251) (xy 298.651168 -285.92145)
			(xy 304.692304 -285.92145) (xy 304.692304 -285.51251) (xy 304.692841 -285.502357) (xy 304.700606 -285.483595)
			(xy 304.714958 -285.46923) (xy 304.733713 -285.461449) (xy 304.743866 -285.460948) (xy 306.143406 -285.460948)
			(xy 306.153579 -285.461359) (xy 306.172376 -285.469148) (xy 306.186761 -285.483537) (xy 306.194544 -285.502337)
			(xy 306.194968 -285.51251) (xy 306.194968 -285.92145) (xy 312.236104 -285.92145) (xy 312.236104 -285.51251)
			(xy 312.236641 -285.502357) (xy 312.244406 -285.483595) (xy 312.258758 -285.46923) (xy 312.277513 -285.461449)
			(xy 312.287666 -285.460948) (xy 313.687206 -285.460948) (xy 313.697379 -285.461359) (xy 313.716176 -285.469148)
			(xy 313.730561 -285.483537) (xy 313.738344 -285.502337) (xy 313.738768 -285.51251) (xy 313.738768 -285.661354)
			(xy 335.395824 -285.661354) (xy 335.396245 -285.636017) (xy 335.404005 -285.585941) (xy 335.419335 -285.537642)
			(xy 335.441875 -285.492257) (xy 335.471092 -285.450854) (xy 335.5063 -285.41441) (xy 335.54667 -285.383781)
			(xy 335.59125 -285.359689) (xy 335.638992 -285.342701) (xy 335.663794 -285.337504) (xy 335.686654 -285.333186)
			(xy 335.891632 -284.978094) (xy 335.884012 -284.95625) (xy 335.875447 -284.929893) (xy 335.86625 -284.875247)
			(xy 335.865724 -284.847538) (xy 335.866232 -284.821651) (xy 335.874331 -284.770513) (xy 335.89033 -284.721273)
			(xy 335.913836 -284.675141) (xy 335.944268 -284.633254) (xy 335.980878 -284.596644) (xy 336.022765 -284.566212)
			(xy 336.068897 -284.542706) (xy 336.118137 -284.526707) (xy 336.169275 -284.518608) (xy 336.221049 -284.518608)
			(xy 336.272187 -284.526707) (xy 336.321427 -284.542706) (xy 336.367559 -284.566212) (xy 336.409446 -284.596644)
			(xy 336.446056 -284.633254) (xy 336.476488 -284.675141) (xy 336.499994 -284.721273) (xy 336.515993 -284.770513)
			(xy 336.524092 -284.821651) (xy 336.5246 -284.847538) (xy 336.524152 -284.872874) (xy 336.516394 -284.922948)
			(xy 336.501066 -284.971245) (xy 336.47853 -285.016629) (xy 336.449316 -285.058031) (xy 336.414111 -285.094476)
			(xy 336.373746 -285.125106) (xy 336.329169 -285.149199) (xy 336.281431 -285.16619) (xy 336.25663 -285.171388)
			(xy 336.23377 -285.175706) (xy 336.028792 -285.530798) (xy 336.036412 -285.552642) (xy 336.044976 -285.578999)
			(xy 336.054174 -285.633646) (xy 336.0547 -285.661354) (xy 337.275424 -285.661354) (xy 337.275932 -285.635467)
			(xy 337.284031 -285.584329) (xy 337.30003 -285.535089) (xy 337.323536 -285.488957) (xy 337.353968 -285.44707)
			(xy 337.390578 -285.41046) (xy 337.432465 -285.380028) (xy 337.478597 -285.356522) (xy 337.527837 -285.340523)
			(xy 337.578975 -285.332424) (xy 337.630749 -285.332424) (xy 337.681887 -285.340523) (xy 337.731127 -285.356522)
			(xy 337.777259 -285.380028) (xy 337.819146 -285.41046) (xy 337.855756 -285.44707) (xy 337.886188 -285.488957)
			(xy 337.909694 -285.535089) (xy 337.925693 -285.584329) (xy 337.933792 -285.635467) (xy 337.9343 -285.661354)
			(xy 338.215224 -285.661354) (xy 338.215684 -285.636008) (xy 338.223463 -285.585916) (xy 338.238816 -285.537605)
			(xy 338.26138 -285.492212) (xy 338.290625 -285.450806) (xy 338.325861 -285.414363) (xy 338.366259 -285.383741)
			(xy 338.410867 -285.359661) (xy 338.458634 -285.34269) (xy 338.483448 -285.337504) (xy 338.506308 -285.333186)
			(xy 338.711286 -284.978348) (xy 338.703412 -284.956504) (xy 338.694834 -284.930085) (xy 338.685636 -284.87531)
			(xy 338.685124 -284.847538) (xy 338.685632 -284.821651) (xy 338.693731 -284.770513) (xy 338.70973 -284.721273)
			(xy 338.733236 -284.675141) (xy 338.763668 -284.633254) (xy 338.800278 -284.596644) (xy 338.842165 -284.566212)
			(xy 338.888297 -284.542706) (xy 338.937537 -284.526707) (xy 338.988675 -284.518608) (xy 339.040449 -284.518608)
			(xy 339.091587 -284.526707) (xy 339.140827 -284.542706) (xy 339.186959 -284.566212) (xy 339.228846 -284.596644)
			(xy 339.265456 -284.633254) (xy 339.295888 -284.675141) (xy 339.319394 -284.721273) (xy 339.335393 -284.770513)
			(xy 339.343492 -284.821651) (xy 339.344 -284.847538) (xy 339.343552 -284.872874) (xy 339.335794 -284.922948)
			(xy 339.320466 -284.971245) (xy 339.29793 -285.016629) (xy 339.268716 -285.058031) (xy 339.233511 -285.094476)
			(xy 339.193146 -285.125106) (xy 339.148569 -285.149199) (xy 339.100831 -285.16619) (xy 339.07603 -285.171388)
			(xy 339.05317 -285.175706) (xy 338.848192 -285.530544) (xy 338.856066 -285.552642) (xy 338.86469 -285.578991)
			(xy 338.874015 -285.633637) (xy 338.874608 -285.661354) (xy 339.155024 -285.661354) (xy 339.155532 -285.635447)
			(xy 339.163638 -285.58427) (xy 339.17965 -285.534991) (xy 339.203173 -285.488824) (xy 339.233629 -285.446905)
			(xy 339.270267 -285.410267) (xy 339.312186 -285.379811) (xy 339.358353 -285.356288) (xy 339.407632 -285.340276)
			(xy 339.458809 -285.33217) (xy 339.510623 -285.33217) (xy 339.5618 -285.340276) (xy 339.611079 -285.356288)
			(xy 339.657246 -285.379811) (xy 339.699165 -285.410267) (xy 339.735803 -285.446905) (xy 339.766259 -285.488824)
			(xy 339.789782 -285.534991) (xy 339.805794 -285.58427) (xy 339.8139 -285.635447) (xy 339.814408 -285.661354)
			(xy 340.094824 -285.661354) (xy 340.095245 -285.636017) (xy 340.103005 -285.585941) (xy 340.118335 -285.537642)
			(xy 340.140875 -285.492257) (xy 340.170092 -285.450854) (xy 340.2053 -285.41441) (xy 340.24567 -285.383781)
			(xy 340.29025 -285.359689) (xy 340.337992 -285.342701) (xy 340.362794 -285.337504) (xy 340.385654 -285.333186)
			(xy 340.590886 -284.97784) (xy 340.583266 -284.955996) (xy 340.574644 -284.929713) (xy 340.565327 -284.875193)
			(xy 340.564724 -284.847538) (xy 340.565232 -284.821631) (xy 340.573338 -284.770454) (xy 340.58935 -284.721175)
			(xy 340.612873 -284.675008) (xy 340.643329 -284.633089) (xy 340.679967 -284.596451) (xy 340.721886 -284.565995)
			(xy 340.768053 -284.542472) (xy 340.817332 -284.52646) (xy 340.868509 -284.518354) (xy 340.920323 -284.518354)
			(xy 340.9715 -284.52646) (xy 341.020779 -284.542472) (xy 341.066946 -284.565995) (xy 341.108865 -284.596451)
			(xy 341.145503 -284.633089) (xy 341.175959 -284.675008) (xy 341.199482 -284.721175) (xy 341.215494 -284.770454)
			(xy 341.2236 -284.821631) (xy 341.224108 -284.847538) (xy 341.223661 -284.872913) (xy 341.215887 -284.923064)
			(xy 341.200514 -284.97143) (xy 341.177905 -285.016866) (xy 341.148596 -285.058297) (xy 341.113279 -285.094742)
			(xy 341.072791 -285.125341) (xy 341.028089 -285.149367) (xy 340.980231 -285.166254) (xy 340.955376 -285.171388)
			(xy 340.932516 -285.175706) (xy 340.727538 -285.530544) (xy 340.735412 -285.552642) (xy 340.743983 -285.578997)
			(xy 340.753175 -285.633645) (xy 340.7537 -285.661354) (xy 341.034624 -285.661354) (xy 341.035132 -285.635467)
			(xy 341.043231 -285.584329) (xy 341.05923 -285.535089) (xy 341.082736 -285.488957) (xy 341.113168 -285.44707)
			(xy 341.149778 -285.41046) (xy 341.191665 -285.380028) (xy 341.237797 -285.356522) (xy 341.287037 -285.340523)
			(xy 341.338175 -285.332424) (xy 341.389949 -285.332424) (xy 341.441087 -285.340523) (xy 341.490327 -285.356522)
			(xy 341.536459 -285.380028) (xy 341.578346 -285.41046) (xy 341.614956 -285.44707) (xy 341.645388 -285.488957)
			(xy 341.668894 -285.535089) (xy 341.684893 -285.584329) (xy 341.692992 -285.635467) (xy 341.6935 -285.661354)
			(xy 341.974424 -285.661354) (xy 341.974845 -285.636017) (xy 341.982605 -285.585941) (xy 341.997935 -285.537642)
			(xy 342.020475 -285.492257) (xy 342.049692 -285.450854) (xy 342.0849 -285.41441) (xy 342.12527 -285.383781)
			(xy 342.16985 -285.359689) (xy 342.217592 -285.342701) (xy 342.242394 -285.337504) (xy 342.265254 -285.333186)
			(xy 342.470486 -284.97784) (xy 342.462866 -284.955996) (xy 342.454244 -284.929713) (xy 342.444927 -284.875193)
			(xy 342.444324 -284.847538) (xy 342.444832 -284.821631) (xy 342.452938 -284.770454) (xy 342.46895 -284.721175)
			(xy 342.492473 -284.675008) (xy 342.522929 -284.633089) (xy 342.559567 -284.596451) (xy 342.601486 -284.565995)
			(xy 342.647653 -284.542472) (xy 342.696932 -284.52646) (xy 342.748109 -284.518354) (xy 342.799923 -284.518354)
			(xy 342.8511 -284.52646) (xy 342.900379 -284.542472) (xy 342.946546 -284.565995) (xy 342.988465 -284.596451)
			(xy 343.025103 -284.633089) (xy 343.055559 -284.675008) (xy 343.079082 -284.721175) (xy 343.095094 -284.770454)
			(xy 343.1032 -284.821631) (xy 343.103708 -284.847538) (xy 343.103261 -284.872913) (xy 343.095487 -284.923064)
			(xy 343.080114 -284.97143) (xy 343.057505 -285.016866) (xy 343.028196 -285.058297) (xy 342.992879 -285.094742)
			(xy 342.952391 -285.125341) (xy 342.907689 -285.149367) (xy 342.859831 -285.166254) (xy 342.834976 -285.171388)
			(xy 342.812116 -285.175706) (xy 342.607138 -285.530544) (xy 342.615012 -285.552642) (xy 342.623583 -285.578997)
			(xy 342.632775 -285.633645) (xy 342.6333 -285.661354) (xy 342.914224 -285.661354) (xy 342.914732 -285.635467)
			(xy 342.922831 -285.584329) (xy 342.93883 -285.535089) (xy 342.962336 -285.488957) (xy 342.992768 -285.44707)
			(xy 343.029378 -285.41046) (xy 343.071265 -285.380028) (xy 343.117397 -285.356522) (xy 343.166637 -285.340523)
			(xy 343.217775 -285.332424) (xy 343.269549 -285.332424) (xy 343.320687 -285.340523) (xy 343.369927 -285.356522)
			(xy 343.416059 -285.380028) (xy 343.457946 -285.41046) (xy 343.494556 -285.44707) (xy 343.524988 -285.488957)
			(xy 343.548494 -285.535089) (xy 343.564493 -285.584329) (xy 343.572592 -285.635467) (xy 343.5731 -285.661354)
			(xy 343.854024 -285.661354) (xy 343.854445 -285.636017) (xy 343.862205 -285.585941) (xy 343.877535 -285.537642)
			(xy 343.900075 -285.492257) (xy 343.929292 -285.450854) (xy 343.9645 -285.41441) (xy 344.00487 -285.383781)
			(xy 344.04945 -285.359689) (xy 344.097192 -285.342701) (xy 344.121994 -285.337504) (xy 344.144854 -285.333186)
			(xy 344.350086 -284.97784) (xy 344.342466 -284.955996) (xy 344.333844 -284.929713) (xy 344.324527 -284.875193)
			(xy 344.323924 -284.847538) (xy 344.324432 -284.821631) (xy 344.332538 -284.770454) (xy 344.34855 -284.721175)
			(xy 344.372073 -284.675008) (xy 344.402529 -284.633089) (xy 344.439167 -284.596451) (xy 344.481086 -284.565995)
			(xy 344.527253 -284.542472) (xy 344.576532 -284.52646) (xy 344.627709 -284.518354) (xy 344.679523 -284.518354)
			(xy 344.7307 -284.52646) (xy 344.779979 -284.542472) (xy 344.826146 -284.565995) (xy 344.868065 -284.596451)
			(xy 344.904703 -284.633089) (xy 344.935159 -284.675008) (xy 344.958682 -284.721175) (xy 344.974694 -284.770454)
			(xy 344.9828 -284.821631) (xy 344.983308 -284.847538) (xy 344.982861 -284.872913) (xy 344.975087 -284.923064)
			(xy 344.959714 -284.97143) (xy 344.937105 -285.016866) (xy 344.907796 -285.058297) (xy 344.872479 -285.094742)
			(xy 344.831991 -285.125341) (xy 344.787289 -285.149367) (xy 344.739431 -285.166254) (xy 344.714576 -285.171388)
			(xy 344.691716 -285.175706) (xy 344.486738 -285.530544) (xy 344.494612 -285.552642) (xy 344.503183 -285.578997)
			(xy 344.512375 -285.633645) (xy 344.5129 -285.661354) (xy 344.793824 -285.661354) (xy 344.794332 -285.635467)
			(xy 344.802431 -285.584329) (xy 344.81843 -285.535089) (xy 344.841936 -285.488957) (xy 344.872368 -285.44707)
			(xy 344.908978 -285.41046) (xy 344.950865 -285.380028) (xy 344.996997 -285.356522) (xy 345.046237 -285.340523)
			(xy 345.097375 -285.332424) (xy 345.149149 -285.332424) (xy 345.200287 -285.340523) (xy 345.249527 -285.356522)
			(xy 345.295659 -285.380028) (xy 345.337546 -285.41046) (xy 345.374156 -285.44707) (xy 345.404588 -285.488957)
			(xy 345.428094 -285.535089) (xy 345.444093 -285.584329) (xy 345.452192 -285.635467) (xy 345.4527 -285.661354)
			(xy 345.733624 -285.661354) (xy 345.734045 -285.636017) (xy 345.741805 -285.585941) (xy 345.757135 -285.537642)
			(xy 345.779675 -285.492257) (xy 345.808892 -285.450854) (xy 345.8441 -285.41441) (xy 345.88447 -285.383781)
			(xy 345.92905 -285.359689) (xy 345.976792 -285.342701) (xy 346.001594 -285.337504) (xy 346.024454 -285.333186)
			(xy 346.229686 -284.97784) (xy 346.222066 -284.955996) (xy 346.213444 -284.929713) (xy 346.204127 -284.875193)
			(xy 346.203524 -284.847538) (xy 346.204032 -284.821631) (xy 346.212138 -284.770454) (xy 346.22815 -284.721175)
			(xy 346.251673 -284.675008) (xy 346.282129 -284.633089) (xy 346.318767 -284.596451) (xy 346.360686 -284.565995)
			(xy 346.406853 -284.542472) (xy 346.456132 -284.52646) (xy 346.507309 -284.518354) (xy 346.559123 -284.518354)
			(xy 346.6103 -284.52646) (xy 346.659579 -284.542472) (xy 346.705746 -284.565995) (xy 346.747665 -284.596451)
			(xy 346.784303 -284.633089) (xy 346.814759 -284.675008) (xy 346.838282 -284.721175) (xy 346.854294 -284.770454)
			(xy 346.8624 -284.821631) (xy 346.862908 -284.847538) (xy 346.862461 -284.872913) (xy 346.854687 -284.923064)
			(xy 346.839314 -284.97143) (xy 346.816705 -285.016866) (xy 346.787396 -285.058297) (xy 346.752079 -285.094742)
			(xy 346.711591 -285.125341) (xy 346.666889 -285.149367) (xy 346.619031 -285.166254) (xy 346.594176 -285.171388)
			(xy 346.571316 -285.175706) (xy 346.366338 -285.530544) (xy 346.374212 -285.552642) (xy 346.382783 -285.578997)
			(xy 346.391975 -285.633645) (xy 346.3925 -285.661354) (xy 346.673424 -285.661354) (xy 346.673932 -285.635467)
			(xy 346.682031 -285.584329) (xy 346.69803 -285.535089) (xy 346.721536 -285.488957) (xy 346.751968 -285.44707)
			(xy 346.788578 -285.41046) (xy 346.830465 -285.380028) (xy 346.876597 -285.356522) (xy 346.925837 -285.340523)
			(xy 346.976975 -285.332424) (xy 347.028749 -285.332424) (xy 347.079887 -285.340523) (xy 347.129127 -285.356522)
			(xy 347.175259 -285.380028) (xy 347.217146 -285.41046) (xy 347.253756 -285.44707) (xy 347.284188 -285.488957)
			(xy 347.307694 -285.535089) (xy 347.323693 -285.584329) (xy 347.331792 -285.635467) (xy 347.3323 -285.661354)
			(xy 347.613224 -285.661354) (xy 347.613645 -285.636017) (xy 347.621405 -285.585941) (xy 347.636735 -285.537642)
			(xy 347.659275 -285.492257) (xy 347.688492 -285.450854) (xy 347.7237 -285.41441) (xy 347.76407 -285.383781)
			(xy 347.80865 -285.359689) (xy 347.856392 -285.342701) (xy 347.881194 -285.337504) (xy 347.904054 -285.333186)
			(xy 348.109286 -284.97784) (xy 348.101666 -284.955996) (xy 348.093044 -284.929713) (xy 348.083727 -284.875193)
			(xy 348.083124 -284.847538) (xy 348.083632 -284.821631) (xy 348.091738 -284.770454) (xy 348.10775 -284.721175)
			(xy 348.131273 -284.675008) (xy 348.161729 -284.633089) (xy 348.198367 -284.596451) (xy 348.240286 -284.565995)
			(xy 348.286453 -284.542472) (xy 348.335732 -284.52646) (xy 348.386909 -284.518354) (xy 348.438723 -284.518354)
			(xy 348.4899 -284.52646) (xy 348.539179 -284.542472) (xy 348.585346 -284.565995) (xy 348.627265 -284.596451)
			(xy 348.663903 -284.633089) (xy 348.694359 -284.675008) (xy 348.717882 -284.721175) (xy 348.733894 -284.770454)
			(xy 348.742 -284.821631) (xy 348.742508 -284.847538) (xy 348.742061 -284.872913) (xy 348.734287 -284.923064)
			(xy 348.718914 -284.97143) (xy 348.696305 -285.016866) (xy 348.666996 -285.058297) (xy 348.631679 -285.094742)
			(xy 348.591191 -285.125341) (xy 348.546489 -285.149367) (xy 348.498631 -285.166254) (xy 348.473776 -285.171388)
			(xy 348.450916 -285.175706) (xy 348.245938 -285.530544) (xy 348.253812 -285.552642) (xy 348.262383 -285.578997)
			(xy 348.271575 -285.633645) (xy 348.2721 -285.661354) (xy 348.553024 -285.661354) (xy 348.553532 -285.635467)
			(xy 348.561631 -285.584329) (xy 348.57763 -285.535089) (xy 348.601136 -285.488957) (xy 348.631568 -285.44707)
			(xy 348.668178 -285.41046) (xy 348.710065 -285.380028) (xy 348.756197 -285.356522) (xy 348.805437 -285.340523)
			(xy 348.856575 -285.332424) (xy 348.908349 -285.332424) (xy 348.959487 -285.340523) (xy 349.008727 -285.356522)
			(xy 349.054859 -285.380028) (xy 349.096746 -285.41046) (xy 349.133356 -285.44707) (xy 349.163788 -285.488957)
			(xy 349.187294 -285.535089) (xy 349.203293 -285.584329) (xy 349.211392 -285.635467) (xy 349.2119 -285.661354)
			(xy 349.492824 -285.661354) (xy 349.493245 -285.636017) (xy 349.501005 -285.585941) (xy 349.516335 -285.537642)
			(xy 349.538875 -285.492257) (xy 349.568092 -285.450854) (xy 349.6033 -285.41441) (xy 349.64367 -285.383781)
			(xy 349.68825 -285.359689) (xy 349.735992 -285.342701) (xy 349.760794 -285.337504) (xy 349.783654 -285.333186)
			(xy 349.988886 -284.97784) (xy 349.981266 -284.955996) (xy 349.972644 -284.929713) (xy 349.963327 -284.875193)
			(xy 349.962724 -284.847538) (xy 349.963232 -284.821631) (xy 349.971338 -284.770454) (xy 349.98735 -284.721175)
			(xy 350.010873 -284.675008) (xy 350.041329 -284.633089) (xy 350.077967 -284.596451) (xy 350.119886 -284.565995)
			(xy 350.166053 -284.542472) (xy 350.215332 -284.52646) (xy 350.266509 -284.518354) (xy 350.318323 -284.518354)
			(xy 350.3695 -284.52646) (xy 350.418779 -284.542472) (xy 350.464946 -284.565995) (xy 350.506865 -284.596451)
			(xy 350.543503 -284.633089) (xy 350.573959 -284.675008) (xy 350.597482 -284.721175) (xy 350.613494 -284.770454)
			(xy 350.6216 -284.821631) (xy 350.622108 -284.847538) (xy 350.621661 -284.872913) (xy 350.613887 -284.923064)
			(xy 350.598514 -284.97143) (xy 350.575905 -285.016866) (xy 350.546596 -285.058297) (xy 350.511279 -285.094742)
			(xy 350.470791 -285.125341) (xy 350.426089 -285.149367) (xy 350.378231 -285.166254) (xy 350.353376 -285.171388)
			(xy 350.330516 -285.175706) (xy 350.125538 -285.530544) (xy 350.133412 -285.552642) (xy 350.141983 -285.578997)
			(xy 350.151175 -285.633645) (xy 350.1517 -285.661354) (xy 350.432624 -285.661354) (xy 350.433132 -285.635467)
			(xy 350.441231 -285.584329) (xy 350.45723 -285.535089) (xy 350.480736 -285.488957) (xy 350.511168 -285.44707)
			(xy 350.547778 -285.41046) (xy 350.589665 -285.380028) (xy 350.635797 -285.356522) (xy 350.685037 -285.340523)
			(xy 350.736175 -285.332424) (xy 350.787949 -285.332424) (xy 350.839087 -285.340523) (xy 350.888327 -285.356522)
			(xy 350.934459 -285.380028) (xy 350.976346 -285.41046) (xy 351.012956 -285.44707) (xy 351.043388 -285.488957)
			(xy 351.066894 -285.535089) (xy 351.082893 -285.584329) (xy 351.090992 -285.635467) (xy 351.0915 -285.661354)
			(xy 351.372424 -285.661354) (xy 351.372845 -285.636017) (xy 351.380605 -285.585941) (xy 351.395935 -285.537642)
			(xy 351.418475 -285.492257) (xy 351.447692 -285.450854) (xy 351.4829 -285.41441) (xy 351.52327 -285.383781)
			(xy 351.56785 -285.359689) (xy 351.615592 -285.342701) (xy 351.640394 -285.337504) (xy 351.663254 -285.333186)
			(xy 351.868486 -284.97784) (xy 351.860866 -284.955996) (xy 351.852244 -284.929713) (xy 351.842927 -284.875193)
			(xy 351.842324 -284.847538) (xy 351.842832 -284.821631) (xy 351.850938 -284.770454) (xy 351.86695 -284.721175)
			(xy 351.890473 -284.675008) (xy 351.920929 -284.633089) (xy 351.957567 -284.596451) (xy 351.999486 -284.565995)
			(xy 352.045653 -284.542472) (xy 352.094932 -284.52646) (xy 352.146109 -284.518354) (xy 352.197923 -284.518354)
			(xy 352.2491 -284.52646) (xy 352.298379 -284.542472) (xy 352.344546 -284.565995) (xy 352.386465 -284.596451)
			(xy 352.423103 -284.633089) (xy 352.453559 -284.675008) (xy 352.477082 -284.721175) (xy 352.493094 -284.770454)
			(xy 352.5012 -284.821631) (xy 352.501708 -284.847538) (xy 366.879124 -284.847538) (xy 366.879632 -284.821631)
			(xy 366.887738 -284.770454) (xy 366.90375 -284.721175) (xy 366.927273 -284.675008) (xy 366.957729 -284.633089)
			(xy 366.994367 -284.596451) (xy 367.036286 -284.565995) (xy 367.082453 -284.542472) (xy 367.131732 -284.52646)
			(xy 367.182909 -284.518354) (xy 367.234723 -284.518354) (xy 367.2859 -284.52646) (xy 367.335179 -284.542472)
			(xy 367.381346 -284.565995) (xy 367.423265 -284.596451) (xy 367.459903 -284.633089) (xy 367.490359 -284.675008)
			(xy 367.513882 -284.721175) (xy 367.529894 -284.770454) (xy 367.538 -284.821631) (xy 367.538508 -284.847538)
			(xy 368.758724 -284.847538) (xy 368.759232 -284.821631) (xy 368.767338 -284.770454) (xy 368.78335 -284.721175)
			(xy 368.806873 -284.675008) (xy 368.837329 -284.633089) (xy 368.873967 -284.596451) (xy 368.915886 -284.565995)
			(xy 368.962053 -284.542472) (xy 369.011332 -284.52646) (xy 369.062509 -284.518354) (xy 369.114323 -284.518354)
			(xy 369.1655 -284.52646) (xy 369.214779 -284.542472) (xy 369.260946 -284.565995) (xy 369.302865 -284.596451)
			(xy 369.339503 -284.633089) (xy 369.369959 -284.675008) (xy 369.393482 -284.721175) (xy 369.409494 -284.770454)
			(xy 369.4176 -284.821631) (xy 369.418108 -284.847538) (xy 370.638324 -284.847538) (xy 370.638832 -284.821631)
			(xy 370.646938 -284.770454) (xy 370.66295 -284.721175) (xy 370.686473 -284.675008) (xy 370.716929 -284.633089)
			(xy 370.753567 -284.596451) (xy 370.795486 -284.565995) (xy 370.841653 -284.542472) (xy 370.890932 -284.52646)
			(xy 370.942109 -284.518354) (xy 370.993923 -284.518354) (xy 371.0451 -284.52646) (xy 371.094379 -284.542472)
			(xy 371.140546 -284.565995) (xy 371.182465 -284.596451) (xy 371.219103 -284.633089) (xy 371.249559 -284.675008)
			(xy 371.273082 -284.721175) (xy 371.289094 -284.770454) (xy 371.2972 -284.821631) (xy 371.297708 -284.847538)
			(xy 372.517924 -284.847538) (xy 372.518432 -284.821631) (xy 372.526538 -284.770454) (xy 372.54255 -284.721175)
			(xy 372.566073 -284.675008) (xy 372.596529 -284.633089) (xy 372.633167 -284.596451) (xy 372.675086 -284.565995)
			(xy 372.721253 -284.542472) (xy 372.770532 -284.52646) (xy 372.821709 -284.518354) (xy 372.873523 -284.518354)
			(xy 372.9247 -284.52646) (xy 372.973979 -284.542472) (xy 373.020146 -284.565995) (xy 373.062065 -284.596451)
			(xy 373.098703 -284.633089) (xy 373.129159 -284.675008) (xy 373.152682 -284.721175) (xy 373.168694 -284.770454)
			(xy 373.1768 -284.821631) (xy 373.177308 -284.847538) (xy 374.397524 -284.847538) (xy 374.398032 -284.821631)
			(xy 374.406138 -284.770454) (xy 374.42215 -284.721175) (xy 374.445673 -284.675008) (xy 374.476129 -284.633089)
			(xy 374.512767 -284.596451) (xy 374.554686 -284.565995) (xy 374.600853 -284.542472) (xy 374.650132 -284.52646)
			(xy 374.701309 -284.518354) (xy 374.753123 -284.518354) (xy 374.8043 -284.52646) (xy 374.853579 -284.542472)
			(xy 374.899746 -284.565995) (xy 374.941665 -284.596451) (xy 374.978303 -284.633089) (xy 375.008759 -284.675008)
			(xy 375.032282 -284.721175) (xy 375.048294 -284.770454) (xy 375.0564 -284.821631) (xy 375.056908 -284.847538)
			(xy 376.277124 -284.847538) (xy 376.277632 -284.821631) (xy 376.285738 -284.770454) (xy 376.30175 -284.721175)
			(xy 376.325273 -284.675008) (xy 376.355729 -284.633089) (xy 376.392367 -284.596451) (xy 376.434286 -284.565995)
			(xy 376.480453 -284.542472) (xy 376.529732 -284.52646) (xy 376.580909 -284.518354) (xy 376.632723 -284.518354)
			(xy 376.6839 -284.52646) (xy 376.733179 -284.542472) (xy 376.779346 -284.565995) (xy 376.821265 -284.596451)
			(xy 376.857903 -284.633089) (xy 376.888359 -284.675008) (xy 376.911882 -284.721175) (xy 376.927894 -284.770454)
			(xy 376.936 -284.821631) (xy 376.936508 -284.847538) (xy 378.156724 -284.847538) (xy 378.157232 -284.821631)
			(xy 378.165338 -284.770454) (xy 378.18135 -284.721175) (xy 378.204873 -284.675008) (xy 378.235329 -284.633089)
			(xy 378.271967 -284.596451) (xy 378.313886 -284.565995) (xy 378.360053 -284.542472) (xy 378.409332 -284.52646)
			(xy 378.460509 -284.518354) (xy 378.512323 -284.518354) (xy 378.5635 -284.52646) (xy 378.612779 -284.542472)
			(xy 378.658946 -284.565995) (xy 378.700865 -284.596451) (xy 378.737503 -284.633089) (xy 378.767959 -284.675008)
			(xy 378.791482 -284.721175) (xy 378.807494 -284.770454) (xy 378.8156 -284.821631) (xy 378.816108 -284.847538)
			(xy 380.036324 -284.847538) (xy 380.036832 -284.821631) (xy 380.044938 -284.770454) (xy 380.06095 -284.721175)
			(xy 380.084473 -284.675008) (xy 380.114929 -284.633089) (xy 380.151567 -284.596451) (xy 380.193486 -284.565995)
			(xy 380.239653 -284.542472) (xy 380.288932 -284.52646) (xy 380.340109 -284.518354) (xy 380.391923 -284.518354)
			(xy 380.4431 -284.52646) (xy 380.492379 -284.542472) (xy 380.538546 -284.565995) (xy 380.580465 -284.596451)
			(xy 380.617103 -284.633089) (xy 380.647559 -284.675008) (xy 380.671082 -284.721175) (xy 380.687094 -284.770454)
			(xy 380.6952 -284.821631) (xy 380.695708 -284.847538) (xy 380.695098 -284.875255) (xy 380.685785 -284.929901)
			(xy 380.677166 -284.95625) (xy 380.669292 -284.978348) (xy 380.722994 -285.071312) (xy 406.002236 -285.071312)
			(xy 406.002236 -284.662372) (xy 406.002599 -284.652212) (xy 406.010411 -284.633452) (xy 406.024826 -284.619128)
			(xy 406.043635 -284.611436) (xy 406.053798 -284.611064) (xy 407.453338 -284.611064) (xy 407.46347 -284.611496)
			(xy 407.482197 -284.619241) (xy 407.496552 -284.633544) (xy 407.504366 -284.652242) (xy 407.5049 -284.662372)
			(xy 407.5049 -285.071312) (xy 413.546036 -285.071312) (xy 413.546036 -284.662372) (xy 413.546399 -284.652212)
			(xy 413.554211 -284.633452) (xy 413.568626 -284.619128) (xy 413.587435 -284.611436) (xy 413.597598 -284.611064)
			(xy 414.997138 -284.611064) (xy 415.00727 -284.611496) (xy 415.025997 -284.619241) (xy 415.040352 -284.633544)
			(xy 415.048166 -284.652242) (xy 415.0487 -284.662372) (xy 415.0487 -285.071312) (xy 421.089836 -285.071312)
			(xy 421.089836 -284.662372) (xy 421.090199 -284.652212) (xy 421.098011 -284.633452) (xy 421.112426 -284.619128)
			(xy 421.131235 -284.611436) (xy 421.141398 -284.611064) (xy 422.540938 -284.611064) (xy 422.55107 -284.611496)
			(xy 422.569797 -284.619241) (xy 422.584152 -284.633544) (xy 422.591966 -284.652242) (xy 422.5925 -284.662372)
			(xy 422.5925 -285.071312) (xy 428.633636 -285.071312) (xy 428.633636 -284.662372) (xy 428.633999 -284.652212)
			(xy 428.641811 -284.633452) (xy 428.656226 -284.619128) (xy 428.675035 -284.611436) (xy 428.685198 -284.611064)
			(xy 430.084738 -284.611064) (xy 430.09487 -284.611496) (xy 430.113597 -284.619241) (xy 430.127952 -284.633544)
			(xy 430.135766 -284.652242) (xy 430.1363 -284.662372) (xy 430.1363 -285.071312) (xy 436.177436 -285.071312)
			(xy 436.177436 -284.662372) (xy 436.177799 -284.652212) (xy 436.185611 -284.633452) (xy 436.200026 -284.619128)
			(xy 436.218835 -284.611436) (xy 436.228998 -284.611064) (xy 437.628538 -284.611064) (xy 437.63867 -284.611496)
			(xy 437.657397 -284.619241) (xy 437.671752 -284.633544) (xy 437.679566 -284.652242) (xy 437.6801 -284.662372)
			(xy 437.6801 -285.071312) (xy 443.721236 -285.071312) (xy 443.721236 -284.662372) (xy 443.721599 -284.652212)
			(xy 443.729411 -284.633452) (xy 443.743826 -284.619128) (xy 443.762635 -284.611436) (xy 443.772798 -284.611064)
			(xy 445.172338 -284.611064) (xy 445.18247 -284.611496) (xy 445.201197 -284.619241) (xy 445.215552 -284.633544)
			(xy 445.223366 -284.652242) (xy 445.2239 -284.662372) (xy 445.2239 -285.071312) (xy 451.265036 -285.071312)
			(xy 451.265036 -284.662372) (xy 451.265399 -284.652212) (xy 451.273211 -284.633452) (xy 451.287626 -284.619128)
			(xy 451.306435 -284.611436) (xy 451.316598 -284.611064) (xy 452.716138 -284.611064) (xy 452.72627 -284.611496)
			(xy 452.744997 -284.619241) (xy 452.759352 -284.633544) (xy 452.767166 -284.652242) (xy 452.7677 -284.662372)
			(xy 452.7677 -285.071312) (xy 458.808836 -285.071312) (xy 458.808836 -284.662372) (xy 458.809199 -284.652212)
			(xy 458.817011 -284.633452) (xy 458.831426 -284.619128) (xy 458.850235 -284.611436) (xy 458.860398 -284.611064)
			(xy 460.259938 -284.611064) (xy 460.27007 -284.611496) (xy 460.288797 -284.619241) (xy 460.303152 -284.633544)
			(xy 460.310966 -284.652242) (xy 460.3115 -284.662372) (xy 460.3115 -285.071312) (xy 460.311088 -285.081467)
			(xy 460.303289 -285.10022) (xy 460.288889 -285.114543) (xy 460.270095 -285.122242) (xy 460.259938 -285.12262)
			(xy 458.860398 -285.12262) (xy 458.850266 -285.122174) (xy 458.831538 -285.114438) (xy 458.81718 -285.100139)
			(xy 458.809368 -285.081442) (xy 458.808836 -285.071312) (xy 452.7677 -285.071312) (xy 452.767288 -285.081467)
			(xy 452.759489 -285.10022) (xy 452.745089 -285.114543) (xy 452.726295 -285.122242) (xy 452.716138 -285.12262)
			(xy 451.316598 -285.12262) (xy 451.306466 -285.122174) (xy 451.287738 -285.114438) (xy 451.27338 -285.100139)
			(xy 451.265568 -285.081442) (xy 451.265036 -285.071312) (xy 445.2239 -285.071312) (xy 445.223488 -285.081467)
			(xy 445.215689 -285.10022) (xy 445.201289 -285.114543) (xy 445.182495 -285.122242) (xy 445.172338 -285.12262)
			(xy 443.772798 -285.12262) (xy 443.762666 -285.122174) (xy 443.743938 -285.114438) (xy 443.72958 -285.100139)
			(xy 443.721768 -285.081442) (xy 443.721236 -285.071312) (xy 437.6801 -285.071312) (xy 437.679688 -285.081467)
			(xy 437.671889 -285.10022) (xy 437.657489 -285.114543) (xy 437.638695 -285.122242) (xy 437.628538 -285.12262)
			(xy 436.228998 -285.12262) (xy 436.218866 -285.122174) (xy 436.200138 -285.114438) (xy 436.18578 -285.100139)
			(xy 436.177968 -285.081442) (xy 436.177436 -285.071312) (xy 430.1363 -285.071312) (xy 430.135888 -285.081467)
			(xy 430.128089 -285.10022) (xy 430.113689 -285.114543) (xy 430.094895 -285.122242) (xy 430.084738 -285.12262)
			(xy 428.685198 -285.12262) (xy 428.675066 -285.122174) (xy 428.656338 -285.114438) (xy 428.64198 -285.100139)
			(xy 428.634168 -285.081442) (xy 428.633636 -285.071312) (xy 422.5925 -285.071312) (xy 422.592088 -285.081467)
			(xy 422.584289 -285.10022) (xy 422.569889 -285.114543) (xy 422.551095 -285.122242) (xy 422.540938 -285.12262)
			(xy 421.141398 -285.12262) (xy 421.131266 -285.122174) (xy 421.112538 -285.114438) (xy 421.09818 -285.100139)
			(xy 421.090368 -285.081442) (xy 421.089836 -285.071312) (xy 415.0487 -285.071312) (xy 415.048288 -285.081467)
			(xy 415.040489 -285.10022) (xy 415.026089 -285.114543) (xy 415.007295 -285.122242) (xy 414.997138 -285.12262)
			(xy 413.597598 -285.12262) (xy 413.587466 -285.122174) (xy 413.568738 -285.114438) (xy 413.55438 -285.100139)
			(xy 413.546568 -285.081442) (xy 413.546036 -285.071312) (xy 407.5049 -285.071312) (xy 407.504488 -285.081467)
			(xy 407.496689 -285.10022) (xy 407.482289 -285.114543) (xy 407.463495 -285.122242) (xy 407.453338 -285.12262)
			(xy 406.053798 -285.12262) (xy 406.043666 -285.122174) (xy 406.024938 -285.114438) (xy 406.01058 -285.100139)
			(xy 406.002768 -285.081442) (xy 406.002236 -285.071312) (xy 380.722994 -285.071312) (xy 380.87427 -285.333186)
			(xy 380.89713 -285.337504) (xy 380.921947 -285.342634) (xy 380.969689 -285.35963) (xy 381.014267 -285.383731)
			(xy 381.054634 -285.414369) (xy 381.089836 -285.450823) (xy 381.119046 -285.492235) (xy 381.141576 -285.537628)
			(xy 381.156894 -285.585934) (xy 381.16464 -285.636016) (xy 381.1651 -285.661354) (xy 381.164592 -285.687241)
			(xy 381.156493 -285.738379) (xy 381.140494 -285.787619) (xy 381.116988 -285.833751) (xy 381.086556 -285.875638)
			(xy 381.049946 -285.912248) (xy 381.008059 -285.94268) (xy 380.961927 -285.966186) (xy 380.912687 -285.982185)
			(xy 380.861549 -285.990284) (xy 380.809775 -285.990284) (xy 380.758637 -285.982185) (xy 380.709397 -285.966186)
			(xy 380.663265 -285.94268) (xy 380.621378 -285.912248) (xy 380.584768 -285.875638) (xy 380.554336 -285.833751)
			(xy 380.53083 -285.787619) (xy 380.514831 -285.738379) (xy 380.506732 -285.687241) (xy 380.506224 -285.661354)
			(xy 380.506766 -285.633646) (xy 380.515953 -285.579) (xy 380.524512 -285.552642) (xy 380.532386 -285.530544)
			(xy 380.327408 -285.175706) (xy 380.304548 -285.171388) (xy 380.279723 -285.166238) (xy 380.231943 -285.149282)
			(xy 380.187323 -285.125209) (xy 380.146916 -285.094586) (xy 380.111675 -285.058137) (xy 380.082431 -285.016721)
			(xy 380.059876 -284.971315) (xy 380.044539 -284.922991) (xy 380.036785 -284.872888) (xy 380.036324 -284.847538)
			(xy 378.816108 -284.847538) (xy 378.815498 -284.875255) (xy 378.806185 -284.929901) (xy 378.797566 -284.95625)
			(xy 378.789692 -284.978348) (xy 378.99467 -285.333186) (xy 379.01753 -285.337504) (xy 379.042347 -285.342634)
			(xy 379.090089 -285.35963) (xy 379.134667 -285.383731) (xy 379.175034 -285.414369) (xy 379.210236 -285.450823)
			(xy 379.239446 -285.492235) (xy 379.261976 -285.537628) (xy 379.277294 -285.585934) (xy 379.28504 -285.636016)
			(xy 379.2855 -285.661354) (xy 379.284992 -285.687241) (xy 379.276893 -285.738379) (xy 379.260894 -285.787619)
			(xy 379.237388 -285.833751) (xy 379.206956 -285.875638) (xy 379.170346 -285.912248) (xy 379.128459 -285.94268)
			(xy 379.082327 -285.966186) (xy 379.033087 -285.982185) (xy 378.981949 -285.990284) (xy 378.930175 -285.990284)
			(xy 378.879037 -285.982185) (xy 378.829797 -285.966186) (xy 378.783665 -285.94268) (xy 378.741778 -285.912248)
			(xy 378.705168 -285.875638) (xy 378.674736 -285.833751) (xy 378.65123 -285.787619) (xy 378.635231 -285.738379)
			(xy 378.627132 -285.687241) (xy 378.626624 -285.661354) (xy 378.627166 -285.633646) (xy 378.636353 -285.579)
			(xy 378.644912 -285.552642) (xy 378.652786 -285.530544) (xy 378.447808 -285.175706) (xy 378.424948 -285.171388)
			(xy 378.400123 -285.166238) (xy 378.352343 -285.149282) (xy 378.307723 -285.125209) (xy 378.267316 -285.094586)
			(xy 378.232075 -285.058137) (xy 378.202831 -285.016721) (xy 378.180276 -284.971315) (xy 378.164939 -284.922991)
			(xy 378.157185 -284.872888) (xy 378.156724 -284.847538) (xy 376.936508 -284.847538) (xy 376.935898 -284.875255)
			(xy 376.926585 -284.929901) (xy 376.917966 -284.95625) (xy 376.910092 -284.978348) (xy 377.11507 -285.333186)
			(xy 377.13793 -285.337504) (xy 377.162747 -285.342634) (xy 377.210489 -285.35963) (xy 377.255067 -285.383731)
			(xy 377.295434 -285.414369) (xy 377.330636 -285.450823) (xy 377.359846 -285.492235) (xy 377.382376 -285.537628)
			(xy 377.397694 -285.585934) (xy 377.40544 -285.636016) (xy 377.4059 -285.661354) (xy 377.405392 -285.687241)
			(xy 377.397293 -285.738379) (xy 377.381294 -285.787619) (xy 377.357788 -285.833751) (xy 377.327356 -285.875638)
			(xy 377.290746 -285.912248) (xy 377.248859 -285.94268) (xy 377.202727 -285.966186) (xy 377.153487 -285.982185)
			(xy 377.102349 -285.990284) (xy 377.050575 -285.990284) (xy 376.999437 -285.982185) (xy 376.950197 -285.966186)
			(xy 376.904065 -285.94268) (xy 376.862178 -285.912248) (xy 376.825568 -285.875638) (xy 376.795136 -285.833751)
			(xy 376.77163 -285.787619) (xy 376.755631 -285.738379) (xy 376.747532 -285.687241) (xy 376.747024 -285.661354)
			(xy 376.747566 -285.633646) (xy 376.756753 -285.579) (xy 376.765312 -285.552642) (xy 376.773186 -285.530544)
			(xy 376.568208 -285.175706) (xy 376.545348 -285.171388) (xy 376.520523 -285.166238) (xy 376.472743 -285.149282)
			(xy 376.428123 -285.125209) (xy 376.387716 -285.094586) (xy 376.352475 -285.058137) (xy 376.323231 -285.016721)
			(xy 376.300676 -284.971315) (xy 376.285339 -284.922991) (xy 376.277585 -284.872888) (xy 376.277124 -284.847538)
			(xy 375.056908 -284.847538) (xy 375.056298 -284.875255) (xy 375.046985 -284.929901) (xy 375.038366 -284.95625)
			(xy 375.030492 -284.978348) (xy 375.23547 -285.333186) (xy 375.25833 -285.337504) (xy 375.283147 -285.342634)
			(xy 375.330889 -285.35963) (xy 375.375467 -285.383731) (xy 375.415834 -285.414369) (xy 375.451036 -285.450823)
			(xy 375.480246 -285.492235) (xy 375.502776 -285.537628) (xy 375.518094 -285.585934) (xy 375.52584 -285.636016)
			(xy 375.5263 -285.661354) (xy 375.525792 -285.687241) (xy 375.517693 -285.738379) (xy 375.501694 -285.787619)
			(xy 375.478188 -285.833751) (xy 375.447756 -285.875638) (xy 375.411146 -285.912248) (xy 375.369259 -285.94268)
			(xy 375.323127 -285.966186) (xy 375.273887 -285.982185) (xy 375.222749 -285.990284) (xy 375.170975 -285.990284)
			(xy 375.119837 -285.982185) (xy 375.070597 -285.966186) (xy 375.024465 -285.94268) (xy 374.982578 -285.912248)
			(xy 374.945968 -285.875638) (xy 374.915536 -285.833751) (xy 374.89203 -285.787619) (xy 374.876031 -285.738379)
			(xy 374.867932 -285.687241) (xy 374.867424 -285.661354) (xy 374.867966 -285.633646) (xy 374.877153 -285.579)
			(xy 374.885712 -285.552642) (xy 374.893586 -285.530544) (xy 374.688608 -285.175706) (xy 374.665748 -285.171388)
			(xy 374.640923 -285.166238) (xy 374.593143 -285.149282) (xy 374.548523 -285.125209) (xy 374.508116 -285.094586)
			(xy 374.472875 -285.058137) (xy 374.443631 -285.016721) (xy 374.421076 -284.971315) (xy 374.405739 -284.922991)
			(xy 374.397985 -284.872888) (xy 374.397524 -284.847538) (xy 373.177308 -284.847538) (xy 373.176698 -284.875255)
			(xy 373.167385 -284.929901) (xy 373.158766 -284.95625) (xy 373.150892 -284.978348) (xy 373.35587 -285.333186)
			(xy 373.37873 -285.337504) (xy 373.403547 -285.342634) (xy 373.451289 -285.35963) (xy 373.495867 -285.383731)
			(xy 373.536234 -285.414369) (xy 373.571436 -285.450823) (xy 373.600646 -285.492235) (xy 373.623176 -285.537628)
			(xy 373.638494 -285.585934) (xy 373.64624 -285.636016) (xy 373.6467 -285.661354) (xy 373.646192 -285.687241)
			(xy 373.638093 -285.738379) (xy 373.622094 -285.787619) (xy 373.598588 -285.833751) (xy 373.568156 -285.875638)
			(xy 373.531546 -285.912248) (xy 373.489659 -285.94268) (xy 373.443527 -285.966186) (xy 373.394287 -285.982185)
			(xy 373.343149 -285.990284) (xy 373.291375 -285.990284) (xy 373.240237 -285.982185) (xy 373.190997 -285.966186)
			(xy 373.144865 -285.94268) (xy 373.102978 -285.912248) (xy 373.066368 -285.875638) (xy 373.035936 -285.833751)
			(xy 373.01243 -285.787619) (xy 372.996431 -285.738379) (xy 372.988332 -285.687241) (xy 372.987824 -285.661354)
			(xy 372.988366 -285.633646) (xy 372.997553 -285.579) (xy 373.006112 -285.552642) (xy 373.013986 -285.530544)
			(xy 372.809008 -285.175706) (xy 372.786148 -285.171388) (xy 372.761323 -285.166238) (xy 372.713543 -285.149282)
			(xy 372.668923 -285.125209) (xy 372.628516 -285.094586) (xy 372.593275 -285.058137) (xy 372.564031 -285.016721)
			(xy 372.541476 -284.971315) (xy 372.526139 -284.922991) (xy 372.518385 -284.872888) (xy 372.517924 -284.847538)
			(xy 371.297708 -284.847538) (xy 371.297098 -284.875255) (xy 371.287785 -284.929901) (xy 371.279166 -284.95625)
			(xy 371.271292 -284.978348) (xy 371.47627 -285.333186) (xy 371.49913 -285.337504) (xy 371.523947 -285.342634)
			(xy 371.571689 -285.35963) (xy 371.616267 -285.383731) (xy 371.656634 -285.414369) (xy 371.691836 -285.450823)
			(xy 371.721046 -285.492235) (xy 371.743576 -285.537628) (xy 371.758894 -285.585934) (xy 371.76664 -285.636016)
			(xy 371.7671 -285.661354) (xy 371.766592 -285.687241) (xy 371.758493 -285.738379) (xy 371.742494 -285.787619)
			(xy 371.718988 -285.833751) (xy 371.688556 -285.875638) (xy 371.651946 -285.912248) (xy 371.610059 -285.94268)
			(xy 371.563927 -285.966186) (xy 371.514687 -285.982185) (xy 371.463549 -285.990284) (xy 371.411775 -285.990284)
			(xy 371.360637 -285.982185) (xy 371.311397 -285.966186) (xy 371.265265 -285.94268) (xy 371.223378 -285.912248)
			(xy 371.186768 -285.875638) (xy 371.156336 -285.833751) (xy 371.13283 -285.787619) (xy 371.116831 -285.738379)
			(xy 371.108732 -285.687241) (xy 371.108224 -285.661354) (xy 371.108766 -285.633646) (xy 371.117953 -285.579)
			(xy 371.126512 -285.552642) (xy 371.134386 -285.530544) (xy 370.929408 -285.175706) (xy 370.906548 -285.171388)
			(xy 370.881723 -285.166238) (xy 370.833943 -285.149282) (xy 370.789323 -285.125209) (xy 370.748916 -285.094586)
			(xy 370.713675 -285.058137) (xy 370.684431 -285.016721) (xy 370.661876 -284.971315) (xy 370.646539 -284.922991)
			(xy 370.638785 -284.872888) (xy 370.638324 -284.847538) (xy 369.418108 -284.847538) (xy 369.417498 -284.875255)
			(xy 369.408185 -284.929901) (xy 369.399566 -284.95625) (xy 369.391692 -284.978348) (xy 369.59667 -285.333186)
			(xy 369.61953 -285.337504) (xy 369.644347 -285.342634) (xy 369.692089 -285.35963) (xy 369.736667 -285.383731)
			(xy 369.777034 -285.414369) (xy 369.812236 -285.450823) (xy 369.841446 -285.492235) (xy 369.863976 -285.537628)
			(xy 369.879294 -285.585934) (xy 369.88704 -285.636016) (xy 369.8875 -285.661354) (xy 369.886992 -285.687241)
			(xy 369.878893 -285.738379) (xy 369.862894 -285.787619) (xy 369.839388 -285.833751) (xy 369.808956 -285.875638)
			(xy 369.772346 -285.912248) (xy 369.730459 -285.94268) (xy 369.684327 -285.966186) (xy 369.635087 -285.982185)
			(xy 369.583949 -285.990284) (xy 369.532175 -285.990284) (xy 369.481037 -285.982185) (xy 369.431797 -285.966186)
			(xy 369.385665 -285.94268) (xy 369.343778 -285.912248) (xy 369.307168 -285.875638) (xy 369.276736 -285.833751)
			(xy 369.25323 -285.787619) (xy 369.237231 -285.738379) (xy 369.229132 -285.687241) (xy 369.228624 -285.661354)
			(xy 369.229166 -285.633646) (xy 369.238353 -285.579) (xy 369.246912 -285.552642) (xy 369.254786 -285.530544)
			(xy 369.049808 -285.175706) (xy 369.026948 -285.171388) (xy 369.002123 -285.166238) (xy 368.954343 -285.149282)
			(xy 368.909723 -285.125209) (xy 368.869316 -285.094586) (xy 368.834075 -285.058137) (xy 368.804831 -285.016721)
			(xy 368.782276 -284.971315) (xy 368.766939 -284.922991) (xy 368.759185 -284.872888) (xy 368.758724 -284.847538)
			(xy 367.538508 -284.847538) (xy 367.537898 -284.875255) (xy 367.528585 -284.929901) (xy 367.519966 -284.95625)
			(xy 367.512092 -284.978348) (xy 367.71707 -285.333186) (xy 367.73993 -285.337504) (xy 367.764747 -285.342634)
			(xy 367.812489 -285.35963) (xy 367.857067 -285.383731) (xy 367.897434 -285.414369) (xy 367.932636 -285.450823)
			(xy 367.961846 -285.492235) (xy 367.984376 -285.537628) (xy 367.999694 -285.585934) (xy 368.00744 -285.636016)
			(xy 368.0079 -285.661354) (xy 368.007392 -285.687241) (xy 367.999293 -285.738379) (xy 367.983294 -285.787619)
			(xy 367.959788 -285.833751) (xy 367.929356 -285.875638) (xy 367.892746 -285.912248) (xy 367.850859 -285.94268)
			(xy 367.804727 -285.966186) (xy 367.755487 -285.982185) (xy 367.704349 -285.990284) (xy 367.652575 -285.990284)
			(xy 367.601437 -285.982185) (xy 367.552197 -285.966186) (xy 367.506065 -285.94268) (xy 367.464178 -285.912248)
			(xy 367.427568 -285.875638) (xy 367.397136 -285.833751) (xy 367.37363 -285.787619) (xy 367.357631 -285.738379)
			(xy 367.349532 -285.687241) (xy 367.349024 -285.661354) (xy 367.349566 -285.633646) (xy 367.358753 -285.579)
			(xy 367.367312 -285.552642) (xy 367.375186 -285.530544) (xy 367.170208 -285.175706) (xy 367.147348 -285.171388)
			(xy 367.122523 -285.166238) (xy 367.074743 -285.149282) (xy 367.030123 -285.125209) (xy 366.989716 -285.094586)
			(xy 366.954475 -285.058137) (xy 366.925231 -285.016721) (xy 366.902676 -284.971315) (xy 366.887339 -284.922991)
			(xy 366.879585 -284.872888) (xy 366.879124 -284.847538) (xy 352.501708 -284.847538) (xy 352.501261 -284.872913)
			(xy 352.493487 -284.923064) (xy 352.478114 -284.97143) (xy 352.455505 -285.016866) (xy 352.426196 -285.058297)
			(xy 352.390879 -285.094742) (xy 352.350391 -285.125341) (xy 352.305689 -285.149367) (xy 352.257831 -285.166254)
			(xy 352.232976 -285.171388) (xy 352.210116 -285.175706) (xy 352.005138 -285.530544) (xy 352.013012 -285.552642)
			(xy 352.021583 -285.578997) (xy 352.030775 -285.633645) (xy 352.0313 -285.661354) (xy 352.030792 -285.687241)
			(xy 352.022693 -285.738379) (xy 352.006694 -285.787619) (xy 351.983188 -285.833751) (xy 351.952756 -285.875638)
			(xy 351.916146 -285.912248) (xy 351.874259 -285.94268) (xy 351.828127 -285.966186) (xy 351.778887 -285.982185)
			(xy 351.727749 -285.990284) (xy 351.675975 -285.990284) (xy 351.624837 -285.982185) (xy 351.575597 -285.966186)
			(xy 351.529465 -285.94268) (xy 351.487578 -285.912248) (xy 351.450968 -285.875638) (xy 351.420536 -285.833751)
			(xy 351.39703 -285.787619) (xy 351.381031 -285.738379) (xy 351.372932 -285.687241) (xy 351.372424 -285.661354)
			(xy 351.0915 -285.661354) (xy 351.0915 -285.661862) (xy 351.090923 -285.689379) (xy 351.081728 -285.74364)
			(xy 351.073212 -285.769812) (xy 351.065592 -285.79191) (xy 351.270824 -286.147256) (xy 351.293684 -286.151574)
			(xy 351.318506 -286.156737) (xy 351.366283 -286.173695) (xy 351.410901 -286.197768) (xy 351.451306 -286.22839)
			(xy 351.486546 -286.264837) (xy 351.515789 -286.30625) (xy 351.538346 -286.351653) (xy 351.553685 -286.399975)
			(xy 351.561445 -286.450075) (xy 351.561908 -286.475424) (xy 367.818924 -286.475424) (xy 367.819448 -286.45008)
			(xy 367.827216 -286.399991) (xy 367.842559 -286.351681) (xy 367.865115 -286.306288) (xy 367.894351 -286.264882)
			(xy 367.92958 -286.228438) (xy 367.969972 -286.197814) (xy 368.014574 -286.173733) (xy 368.062336 -286.156761)
			(xy 368.087148 -286.151574) (xy 368.110008 -286.147256) (xy 368.314986 -285.792164) (xy 368.307112 -285.77032)
			(xy 368.298538 -285.7439) (xy 368.289338 -285.689126) (xy 368.288824 -285.661354) (xy 368.289332 -285.635467)
			(xy 368.297431 -285.584329) (xy 368.31343 -285.535089) (xy 368.336936 -285.488957) (xy 368.367368 -285.44707)
			(xy 368.403978 -285.41046) (xy 368.445865 -285.380028) (xy 368.491997 -285.356522) (xy 368.541237 -285.340523)
			(xy 368.592375 -285.332424) (xy 368.644149 -285.332424) (xy 368.695287 -285.340523) (xy 368.744527 -285.356522)
			(xy 368.790659 -285.380028) (xy 368.832546 -285.41046) (xy 368.869156 -285.44707) (xy 368.899588 -285.488957)
			(xy 368.923094 -285.535089) (xy 368.939093 -285.584329) (xy 368.947192 -285.635467) (xy 368.9477 -285.661354)
			(xy 368.947266 -285.68669) (xy 368.939506 -285.736765) (xy 368.924176 -285.785062) (xy 368.901638 -285.830446)
			(xy 368.872422 -285.871848) (xy 368.837216 -285.908293) (xy 368.796849 -285.938922) (xy 368.752271 -285.963016)
			(xy 368.704531 -285.980006) (xy 368.67973 -285.985204) (xy 368.65687 -285.989522) (xy 368.451892 -286.344614)
			(xy 368.459766 -286.366458) (xy 368.468419 -286.392864) (xy 368.477734 -286.447642) (xy 368.478308 -286.475424)
			(xy 369.698524 -286.475424) (xy 369.699048 -286.45008) (xy 369.706816 -286.399991) (xy 369.722159 -286.351681)
			(xy 369.744715 -286.306288) (xy 369.773951 -286.264882) (xy 369.80918 -286.228438) (xy 369.849572 -286.197814)
			(xy 369.894174 -286.173733) (xy 369.941936 -286.156761) (xy 369.966748 -286.151574) (xy 369.989608 -286.147256)
			(xy 370.194586 -285.792164) (xy 370.186712 -285.77032) (xy 370.178138 -285.7439) (xy 370.168938 -285.689126)
			(xy 370.168424 -285.661354) (xy 370.168932 -285.635467) (xy 370.177031 -285.584329) (xy 370.19303 -285.535089)
			(xy 370.216536 -285.488957) (xy 370.246968 -285.44707) (xy 370.283578 -285.41046) (xy 370.325465 -285.380028)
			(xy 370.371597 -285.356522) (xy 370.420837 -285.340523) (xy 370.471975 -285.332424) (xy 370.523749 -285.332424)
			(xy 370.574887 -285.340523) (xy 370.624127 -285.356522) (xy 370.670259 -285.380028) (xy 370.712146 -285.41046)
			(xy 370.748756 -285.44707) (xy 370.779188 -285.488957) (xy 370.802694 -285.535089) (xy 370.818693 -285.584329)
			(xy 370.826792 -285.635467) (xy 370.8273 -285.661354) (xy 370.826866 -285.68669) (xy 370.819106 -285.736765)
			(xy 370.803776 -285.785062) (xy 370.781238 -285.830446) (xy 370.752022 -285.871848) (xy 370.716816 -285.908293)
			(xy 370.676449 -285.938922) (xy 370.631871 -285.963016) (xy 370.584131 -285.980006) (xy 370.55933 -285.985204)
			(xy 370.53647 -285.989522) (xy 370.331492 -286.344614) (xy 370.339366 -286.366458) (xy 370.348019 -286.392864)
			(xy 370.357334 -286.447642) (xy 370.357908 -286.475424) (xy 371.578124 -286.475424) (xy 371.578648 -286.45008)
			(xy 371.586416 -286.399991) (xy 371.601759 -286.351681) (xy 371.624315 -286.306288) (xy 371.653551 -286.264882)
			(xy 371.68878 -286.228438) (xy 371.729172 -286.197814) (xy 371.773774 -286.173733) (xy 371.821536 -286.156761)
			(xy 371.846348 -286.151574) (xy 371.869208 -286.147256) (xy 372.074186 -285.792164) (xy 372.066312 -285.77032)
			(xy 372.057738 -285.7439) (xy 372.048538 -285.689126) (xy 372.048024 -285.661354) (xy 372.048532 -285.635467)
			(xy 372.056631 -285.584329) (xy 372.07263 -285.535089) (xy 372.096136 -285.488957) (xy 372.126568 -285.44707)
			(xy 372.163178 -285.41046) (xy 372.205065 -285.380028) (xy 372.251197 -285.356522) (xy 372.300437 -285.340523)
			(xy 372.351575 -285.332424) (xy 372.403349 -285.332424) (xy 372.454487 -285.340523) (xy 372.503727 -285.356522)
			(xy 372.549859 -285.380028) (xy 372.591746 -285.41046) (xy 372.628356 -285.44707) (xy 372.658788 -285.488957)
			(xy 372.682294 -285.535089) (xy 372.698293 -285.584329) (xy 372.706392 -285.635467) (xy 372.7069 -285.661354)
			(xy 372.706466 -285.68669) (xy 372.698706 -285.736765) (xy 372.683376 -285.785062) (xy 372.660838 -285.830446)
			(xy 372.631622 -285.871848) (xy 372.596416 -285.908293) (xy 372.556049 -285.938922) (xy 372.511471 -285.963016)
			(xy 372.463731 -285.980006) (xy 372.43893 -285.985204) (xy 372.41607 -285.989522) (xy 372.211092 -286.344614)
			(xy 372.218966 -286.366458) (xy 372.227619 -286.392864) (xy 372.236934 -286.447642) (xy 372.237508 -286.475424)
			(xy 373.457724 -286.475424) (xy 373.458248 -286.45008) (xy 373.466016 -286.399991) (xy 373.481359 -286.351681)
			(xy 373.503915 -286.306288) (xy 373.533151 -286.264882) (xy 373.56838 -286.228438) (xy 373.608772 -286.197814)
			(xy 373.653374 -286.173733) (xy 373.701136 -286.156761) (xy 373.725948 -286.151574) (xy 373.748808 -286.147256)
			(xy 373.953786 -285.792164) (xy 373.945912 -285.77032) (xy 373.937338 -285.7439) (xy 373.928138 -285.689126)
			(xy 373.927624 -285.661354) (xy 373.928132 -285.635467) (xy 373.936231 -285.584329) (xy 373.95223 -285.535089)
			(xy 373.975736 -285.488957) (xy 374.006168 -285.44707) (xy 374.042778 -285.41046) (xy 374.084665 -285.380028)
			(xy 374.130797 -285.356522) (xy 374.180037 -285.340523) (xy 374.231175 -285.332424) (xy 374.282949 -285.332424)
			(xy 374.334087 -285.340523) (xy 374.383327 -285.356522) (xy 374.429459 -285.380028) (xy 374.471346 -285.41046)
			(xy 374.507956 -285.44707) (xy 374.538388 -285.488957) (xy 374.561894 -285.535089) (xy 374.577893 -285.584329)
			(xy 374.585992 -285.635467) (xy 374.5865 -285.661354) (xy 374.586066 -285.68669) (xy 374.578306 -285.736765)
			(xy 374.562976 -285.785062) (xy 374.540438 -285.830446) (xy 374.511222 -285.871848) (xy 374.476016 -285.908293)
			(xy 374.435649 -285.938922) (xy 374.391071 -285.963016) (xy 374.343331 -285.980006) (xy 374.31853 -285.985204)
			(xy 374.29567 -285.989522) (xy 374.090692 -286.344614) (xy 374.098566 -286.366458) (xy 374.107219 -286.392864)
			(xy 374.116534 -286.447642) (xy 374.117108 -286.475424) (xy 375.337324 -286.475424) (xy 375.337848 -286.45008)
			(xy 375.345616 -286.399991) (xy 375.360959 -286.351681) (xy 375.383515 -286.306288) (xy 375.412751 -286.264882)
			(xy 375.44798 -286.228438) (xy 375.488372 -286.197814) (xy 375.532974 -286.173733) (xy 375.580736 -286.156761)
			(xy 375.605548 -286.151574) (xy 375.628408 -286.147256) (xy 375.833386 -285.792164) (xy 375.825512 -285.77032)
			(xy 375.816938 -285.7439) (xy 375.807738 -285.689126) (xy 375.807224 -285.661354) (xy 375.807732 -285.635467)
			(xy 375.815831 -285.584329) (xy 375.83183 -285.535089) (xy 375.855336 -285.488957) (xy 375.885768 -285.44707)
			(xy 375.922378 -285.41046) (xy 375.964265 -285.380028) (xy 376.010397 -285.356522) (xy 376.059637 -285.340523)
			(xy 376.110775 -285.332424) (xy 376.162549 -285.332424) (xy 376.213687 -285.340523) (xy 376.262927 -285.356522)
			(xy 376.309059 -285.380028) (xy 376.350946 -285.41046) (xy 376.387556 -285.44707) (xy 376.417988 -285.488957)
			(xy 376.441494 -285.535089) (xy 376.457493 -285.584329) (xy 376.465592 -285.635467) (xy 376.4661 -285.661354)
			(xy 376.465666 -285.68669) (xy 376.457906 -285.736765) (xy 376.442576 -285.785062) (xy 376.420038 -285.830446)
			(xy 376.390822 -285.871848) (xy 376.355616 -285.908293) (xy 376.315249 -285.938922) (xy 376.270671 -285.963016)
			(xy 376.222931 -285.980006) (xy 376.19813 -285.985204) (xy 376.17527 -285.989522) (xy 375.970292 -286.344614)
			(xy 375.978166 -286.366458) (xy 375.986819 -286.392864) (xy 375.996134 -286.447642) (xy 375.996708 -286.475424)
			(xy 377.216924 -286.475424) (xy 377.217448 -286.45008) (xy 377.225216 -286.399991) (xy 377.240559 -286.351681)
			(xy 377.263115 -286.306288) (xy 377.292351 -286.264882) (xy 377.32758 -286.228438) (xy 377.367972 -286.197814)
			(xy 377.412574 -286.173733) (xy 377.460336 -286.156761) (xy 377.485148 -286.151574) (xy 377.508008 -286.147256)
			(xy 377.712986 -285.792164) (xy 377.705112 -285.77032) (xy 377.696538 -285.7439) (xy 377.687338 -285.689126)
			(xy 377.686824 -285.661354) (xy 377.687332 -285.635467) (xy 377.695431 -285.584329) (xy 377.71143 -285.535089)
			(xy 377.734936 -285.488957) (xy 377.765368 -285.44707) (xy 377.801978 -285.41046) (xy 377.843865 -285.380028)
			(xy 377.889997 -285.356522) (xy 377.939237 -285.340523) (xy 377.990375 -285.332424) (xy 378.042149 -285.332424)
			(xy 378.093287 -285.340523) (xy 378.142527 -285.356522) (xy 378.188659 -285.380028) (xy 378.230546 -285.41046)
			(xy 378.267156 -285.44707) (xy 378.297588 -285.488957) (xy 378.321094 -285.535089) (xy 378.337093 -285.584329)
			(xy 378.345192 -285.635467) (xy 378.3457 -285.661354) (xy 378.345266 -285.68669) (xy 378.337506 -285.736765)
			(xy 378.322176 -285.785062) (xy 378.299638 -285.830446) (xy 378.270422 -285.871848) (xy 378.235216 -285.908293)
			(xy 378.194849 -285.938922) (xy 378.150271 -285.963016) (xy 378.102531 -285.980006) (xy 378.07773 -285.985204)
			(xy 378.05487 -285.989522) (xy 377.849892 -286.344614) (xy 377.857766 -286.366458) (xy 377.866419 -286.392864)
			(xy 377.875734 -286.447642) (xy 377.876308 -286.475424) (xy 379.096524 -286.475424) (xy 379.097048 -286.45008)
			(xy 379.104816 -286.399991) (xy 379.120159 -286.351681) (xy 379.142715 -286.306288) (xy 379.171951 -286.264882)
			(xy 379.20718 -286.228438) (xy 379.247572 -286.197814) (xy 379.292174 -286.173733) (xy 379.339936 -286.156761)
			(xy 379.364748 -286.151574) (xy 379.387608 -286.147256) (xy 379.592586 -285.792164) (xy 379.584712 -285.77032)
			(xy 379.576138 -285.7439) (xy 379.566938 -285.689126) (xy 379.566424 -285.661354) (xy 379.566932 -285.635467)
			(xy 379.575031 -285.584329) (xy 379.59103 -285.535089) (xy 379.614536 -285.488957) (xy 379.644968 -285.44707)
			(xy 379.681578 -285.41046) (xy 379.723465 -285.380028) (xy 379.769597 -285.356522) (xy 379.818837 -285.340523)
			(xy 379.869975 -285.332424) (xy 379.921749 -285.332424) (xy 379.972887 -285.340523) (xy 380.022127 -285.356522)
			(xy 380.068259 -285.380028) (xy 380.110146 -285.41046) (xy 380.146756 -285.44707) (xy 380.177188 -285.488957)
			(xy 380.200694 -285.535089) (xy 380.216693 -285.584329) (xy 380.224792 -285.635467) (xy 380.2253 -285.661354)
			(xy 380.224866 -285.68669) (xy 380.217106 -285.736765) (xy 380.201776 -285.785062) (xy 380.179238 -285.830446)
			(xy 380.150022 -285.871848) (xy 380.114816 -285.908293) (xy 380.074449 -285.938922) (xy 380.029871 -285.963016)
			(xy 379.982131 -285.980006) (xy 379.95733 -285.985204) (xy 379.93447 -285.989522) (xy 379.729492 -286.344614)
			(xy 379.737366 -286.366458) (xy 379.746019 -286.392864) (xy 379.755334 -286.447642) (xy 379.755908 -286.475424)
			(xy 380.976124 -286.475424) (xy 380.976648 -286.45008) (xy 380.984416 -286.399991) (xy 380.999759 -286.351681)
			(xy 381.022315 -286.306288) (xy 381.051551 -286.264882) (xy 381.08678 -286.228438) (xy 381.127172 -286.197814)
			(xy 381.171774 -286.173733) (xy 381.219536 -286.156761) (xy 381.244348 -286.151574) (xy 381.267208 -286.147256)
			(xy 381.472186 -285.792164) (xy 381.464312 -285.77032) (xy 381.455738 -285.7439) (xy 381.446538 -285.689126)
			(xy 381.446024 -285.661354) (xy 381.446532 -285.635467) (xy 381.454631 -285.584329) (xy 381.47063 -285.535089)
			(xy 381.494136 -285.488957) (xy 381.524568 -285.44707) (xy 381.561178 -285.41046) (xy 381.603065 -285.380028)
			(xy 381.649197 -285.356522) (xy 381.698437 -285.340523) (xy 381.749575 -285.332424) (xy 381.801349 -285.332424)
			(xy 381.852487 -285.340523) (xy 381.901727 -285.356522) (xy 381.947859 -285.380028) (xy 381.989746 -285.41046)
			(xy 382.026356 -285.44707) (xy 382.056788 -285.488957) (xy 382.080294 -285.535089) (xy 382.096293 -285.584329)
			(xy 382.104392 -285.635467) (xy 382.1049 -285.661354) (xy 382.104466 -285.68669) (xy 382.096706 -285.736765)
			(xy 382.081376 -285.785062) (xy 382.058838 -285.830446) (xy 382.029622 -285.871848) (xy 381.994416 -285.908293)
			(xy 381.977076 -285.92145) (xy 410.102304 -285.92145) (xy 410.102304 -285.51251) (xy 410.102841 -285.502357)
			(xy 410.110606 -285.483595) (xy 410.124958 -285.46923) (xy 410.143713 -285.461449) (xy 410.153866 -285.460948)
			(xy 411.553406 -285.460948) (xy 411.563579 -285.461359) (xy 411.582376 -285.469148) (xy 411.596761 -285.483537)
			(xy 411.604544 -285.502337) (xy 411.604968 -285.51251) (xy 411.604968 -285.92145) (xy 417.646104 -285.92145)
			(xy 417.646104 -285.51251) (xy 417.646641 -285.502357) (xy 417.654406 -285.483595) (xy 417.668758 -285.46923)
			(xy 417.687513 -285.461449) (xy 417.697666 -285.460948) (xy 419.097206 -285.460948) (xy 419.107379 -285.461359)
			(xy 419.126176 -285.469148) (xy 419.140561 -285.483537) (xy 419.148344 -285.502337) (xy 419.148768 -285.51251)
			(xy 419.148768 -285.92145) (xy 425.189904 -285.92145) (xy 425.189904 -285.51251) (xy 425.190441 -285.502357)
			(xy 425.198206 -285.483595) (xy 425.212558 -285.46923) (xy 425.231313 -285.461449) (xy 425.241466 -285.460948)
			(xy 426.641006 -285.460948) (xy 426.651179 -285.461359) (xy 426.669976 -285.469148) (xy 426.684361 -285.483537)
			(xy 426.692144 -285.502337) (xy 426.692568 -285.51251) (xy 426.692568 -285.92145) (xy 432.733704 -285.92145)
			(xy 432.733704 -285.51251) (xy 432.734241 -285.502357) (xy 432.742006 -285.483595) (xy 432.756358 -285.46923)
			(xy 432.775113 -285.461449) (xy 432.785266 -285.460948) (xy 434.184806 -285.460948) (xy 434.194979 -285.461359)
			(xy 434.213776 -285.469148) (xy 434.228161 -285.483537) (xy 434.235944 -285.502337) (xy 434.236368 -285.51251)
			(xy 434.236368 -285.92145) (xy 440.277504 -285.92145) (xy 440.277504 -285.51251) (xy 440.278041 -285.502357)
			(xy 440.285806 -285.483595) (xy 440.300158 -285.46923) (xy 440.318913 -285.461449) (xy 440.329066 -285.460948)
			(xy 441.728606 -285.460948) (xy 441.738779 -285.461359) (xy 441.757576 -285.469148) (xy 441.771961 -285.483537)
			(xy 441.779744 -285.502337) (xy 441.780168 -285.51251) (xy 441.780168 -285.92145) (xy 447.821304 -285.92145)
			(xy 447.821304 -285.51251) (xy 447.821841 -285.502357) (xy 447.829606 -285.483595) (xy 447.843958 -285.46923)
			(xy 447.862713 -285.461449) (xy 447.872866 -285.460948) (xy 449.272406 -285.460948) (xy 449.282579 -285.461359)
			(xy 449.301376 -285.469148) (xy 449.315761 -285.483537) (xy 449.323544 -285.502337) (xy 449.323968 -285.51251)
			(xy 449.323968 -285.92145) (xy 455.365104 -285.92145) (xy 455.365104 -285.51251) (xy 455.365641 -285.502357)
			(xy 455.373406 -285.483595) (xy 455.387758 -285.46923) (xy 455.406513 -285.461449) (xy 455.416666 -285.460948)
			(xy 456.816206 -285.460948) (xy 456.826379 -285.461359) (xy 456.845176 -285.469148) (xy 456.859561 -285.483537)
			(xy 456.867344 -285.502337) (xy 456.867768 -285.51251) (xy 456.867768 -285.92145) (xy 462.908904 -285.92145)
			(xy 462.908904 -285.51251) (xy 462.909441 -285.502357) (xy 462.917206 -285.483595) (xy 462.931558 -285.46923)
			(xy 462.950313 -285.461449) (xy 462.960466 -285.460948) (xy 464.360006 -285.460948) (xy 464.370179 -285.461359)
			(xy 464.388976 -285.469148) (xy 464.403361 -285.483537) (xy 464.411144 -285.502337) (xy 464.411568 -285.51251)
			(xy 464.411568 -285.92145) (xy 464.411095 -285.931618) (xy 464.403328 -285.95041) (xy 464.388957 -285.964797)
			(xy 464.370173 -285.972584) (xy 464.360006 -285.973012) (xy 462.960466 -285.973012) (xy 462.950286 -285.972663)
			(xy 462.931481 -285.964857) (xy 462.917095 -285.950448) (xy 462.909321 -285.931631) (xy 462.908904 -285.92145)
			(xy 456.867768 -285.92145) (xy 456.867295 -285.931618) (xy 456.859528 -285.95041) (xy 456.845157 -285.964797)
			(xy 456.826373 -285.972584) (xy 456.816206 -285.973012) (xy 455.416666 -285.973012) (xy 455.406486 -285.972663)
			(xy 455.387681 -285.964857) (xy 455.373295 -285.950448) (xy 455.365521 -285.931631) (xy 455.365104 -285.92145)
			(xy 449.323968 -285.92145) (xy 449.323495 -285.931618) (xy 449.315728 -285.95041) (xy 449.301357 -285.964797)
			(xy 449.282573 -285.972584) (xy 449.272406 -285.973012) (xy 447.872866 -285.973012) (xy 447.862686 -285.972663)
			(xy 447.843881 -285.964857) (xy 447.829495 -285.950448) (xy 447.821721 -285.931631) (xy 447.821304 -285.92145)
			(xy 441.780168 -285.92145) (xy 441.779695 -285.931618) (xy 441.771928 -285.95041) (xy 441.757557 -285.964797)
			(xy 441.738773 -285.972584) (xy 441.728606 -285.973012) (xy 440.329066 -285.973012) (xy 440.318886 -285.972663)
			(xy 440.300081 -285.964857) (xy 440.285695 -285.950448) (xy 440.277921 -285.931631) (xy 440.277504 -285.92145)
			(xy 434.236368 -285.92145) (xy 434.235895 -285.931618) (xy 434.228128 -285.95041) (xy 434.213757 -285.964797)
			(xy 434.194973 -285.972584) (xy 434.184806 -285.973012) (xy 432.785266 -285.973012) (xy 432.775086 -285.972663)
			(xy 432.756281 -285.964857) (xy 432.741895 -285.950448) (xy 432.734121 -285.931631) (xy 432.733704 -285.92145)
			(xy 426.692568 -285.92145) (xy 426.692095 -285.931618) (xy 426.684328 -285.95041) (xy 426.669957 -285.964797)
			(xy 426.651173 -285.972584) (xy 426.641006 -285.973012) (xy 425.241466 -285.973012) (xy 425.231286 -285.972663)
			(xy 425.212481 -285.964857) (xy 425.198095 -285.950448) (xy 425.190321 -285.931631) (xy 425.189904 -285.92145)
			(xy 419.148768 -285.92145) (xy 419.148295 -285.931618) (xy 419.140528 -285.95041) (xy 419.126157 -285.964797)
			(xy 419.107373 -285.972584) (xy 419.097206 -285.973012) (xy 417.697666 -285.973012) (xy 417.687486 -285.972663)
			(xy 417.668681 -285.964857) (xy 417.654295 -285.950448) (xy 417.646521 -285.931631) (xy 417.646104 -285.92145)
			(xy 411.604968 -285.92145) (xy 411.604495 -285.931618) (xy 411.596728 -285.95041) (xy 411.582357 -285.964797)
			(xy 411.563573 -285.972584) (xy 411.553406 -285.973012) (xy 410.153866 -285.973012) (xy 410.143686 -285.972663)
			(xy 410.124881 -285.964857) (xy 410.110495 -285.950448) (xy 410.102721 -285.931631) (xy 410.102304 -285.92145)
			(xy 381.977076 -285.92145) (xy 381.954049 -285.938922) (xy 381.909471 -285.963016) (xy 381.861731 -285.980006)
			(xy 381.83693 -285.985204) (xy 381.81407 -285.989522) (xy 381.609092 -286.344614) (xy 381.616966 -286.366458)
			(xy 381.625619 -286.392864) (xy 381.634934 -286.447642) (xy 381.635508 -286.475424) (xy 381.635 -286.501331)
			(xy 381.626894 -286.552508) (xy 381.610882 -286.601787) (xy 381.587359 -286.647954) (xy 381.556903 -286.689873)
			(xy 381.520265 -286.726511) (xy 381.478346 -286.756967) (xy 381.450149 -286.771334) (xy 406.002236 -286.771334)
			(xy 406.002236 -286.362394) (xy 406.002729 -286.352236) (xy 406.010505 -286.333467) (xy 406.024871 -286.319102)
			(xy 406.04364 -286.311328) (xy 406.053798 -286.310832) (xy 407.453338 -286.310832) (xy 407.463497 -286.311302)
			(xy 407.482266 -286.319088) (xy 407.49663 -286.333461) (xy 407.504404 -286.352234) (xy 407.5049 -286.362394)
			(xy 407.5049 -286.771334) (xy 413.546036 -286.771334) (xy 413.546036 -286.362394) (xy 413.546529 -286.352236)
			(xy 413.554305 -286.333467) (xy 413.568671 -286.319102) (xy 413.58744 -286.311328) (xy 413.597598 -286.310832)
			(xy 414.997138 -286.310832) (xy 415.007297 -286.311302) (xy 415.026066 -286.319088) (xy 415.04043 -286.333461)
			(xy 415.048204 -286.352234) (xy 415.0487 -286.362394) (xy 415.0487 -286.771334) (xy 421.089836 -286.771334)
			(xy 421.089836 -286.362394) (xy 421.090329 -286.352236) (xy 421.098105 -286.333467) (xy 421.112471 -286.319102)
			(xy 421.13124 -286.311328) (xy 421.141398 -286.310832) (xy 422.540938 -286.310832) (xy 422.551097 -286.311302)
			(xy 422.569866 -286.319088) (xy 422.58423 -286.333461) (xy 422.592004 -286.352234) (xy 422.5925 -286.362394)
			(xy 422.5925 -286.771334) (xy 428.633636 -286.771334) (xy 428.633636 -286.362394) (xy 428.634129 -286.352236)
			(xy 428.641905 -286.333467) (xy 428.656271 -286.319102) (xy 428.67504 -286.311328) (xy 428.685198 -286.310832)
			(xy 430.084738 -286.310832) (xy 430.094897 -286.311302) (xy 430.113666 -286.319088) (xy 430.12803 -286.333461)
			(xy 430.135804 -286.352234) (xy 430.1363 -286.362394) (xy 430.1363 -286.771334) (xy 436.177436 -286.771334)
			(xy 436.177436 -286.362394) (xy 436.177929 -286.352236) (xy 436.185705 -286.333467) (xy 436.200071 -286.319102)
			(xy 436.21884 -286.311328) (xy 436.228998 -286.310832) (xy 437.628538 -286.310832) (xy 437.638697 -286.311302)
			(xy 437.657466 -286.319088) (xy 437.67183 -286.333461) (xy 437.679604 -286.352234) (xy 437.6801 -286.362394)
			(xy 437.6801 -286.771334) (xy 443.721236 -286.771334) (xy 443.721236 -286.362394) (xy 443.721729 -286.352236)
			(xy 443.729505 -286.333467) (xy 443.743871 -286.319102) (xy 443.76264 -286.311328) (xy 443.772798 -286.310832)
			(xy 445.172338 -286.310832) (xy 445.182497 -286.311302) (xy 445.201266 -286.319088) (xy 445.21563 -286.333461)
			(xy 445.223404 -286.352234) (xy 445.2239 -286.362394) (xy 445.2239 -286.771334) (xy 451.265036 -286.771334)
			(xy 451.265036 -286.362394) (xy 451.265529 -286.352236) (xy 451.273305 -286.333467) (xy 451.287671 -286.319102)
			(xy 451.30644 -286.311328) (xy 451.316598 -286.310832) (xy 452.716138 -286.310832) (xy 452.726297 -286.311302)
			(xy 452.745066 -286.319088) (xy 452.75943 -286.333461) (xy 452.767204 -286.352234) (xy 452.7677 -286.362394)
			(xy 452.7677 -286.771334) (xy 458.808836 -286.771334) (xy 458.808836 -286.362394) (xy 458.809329 -286.352236)
			(xy 458.817105 -286.333467) (xy 458.831471 -286.319102) (xy 458.85024 -286.311328) (xy 458.860398 -286.310832)
			(xy 460.259938 -286.310832) (xy 460.270097 -286.311302) (xy 460.288866 -286.319088) (xy 460.30323 -286.333461)
			(xy 460.311004 -286.352234) (xy 460.3115 -286.362394) (xy 460.3115 -286.771334) (xy 460.310995 -286.781489)
			(xy 460.303217 -286.800252) (xy 460.288855 -286.814615) (xy 460.270093 -286.822395) (xy 460.259938 -286.822896)
			(xy 458.860398 -286.822896) (xy 458.850244 -286.822369) (xy 458.831482 -286.8146) (xy 458.817118 -286.800245)
			(xy 458.809337 -286.781487) (xy 458.808836 -286.771334) (xy 452.7677 -286.771334) (xy 452.767195 -286.781489)
			(xy 452.759417 -286.800252) (xy 452.745055 -286.814615) (xy 452.726293 -286.822395) (xy 452.716138 -286.822896)
			(xy 451.316598 -286.822896) (xy 451.306444 -286.822369) (xy 451.287682 -286.8146) (xy 451.273318 -286.800245)
			(xy 451.265537 -286.781487) (xy 451.265036 -286.771334) (xy 445.2239 -286.771334) (xy 445.223395 -286.781489)
			(xy 445.215617 -286.800252) (xy 445.201255 -286.814615) (xy 445.182493 -286.822395) (xy 445.172338 -286.822896)
			(xy 443.772798 -286.822896) (xy 443.762644 -286.822369) (xy 443.743882 -286.8146) (xy 443.729518 -286.800245)
			(xy 443.721737 -286.781487) (xy 443.721236 -286.771334) (xy 437.6801 -286.771334) (xy 437.679595 -286.781489)
			(xy 437.671817 -286.800252) (xy 437.657455 -286.814615) (xy 437.638693 -286.822395) (xy 437.628538 -286.822896)
			(xy 436.228998 -286.822896) (xy 436.218844 -286.822369) (xy 436.200082 -286.8146) (xy 436.185718 -286.800245)
			(xy 436.177937 -286.781487) (xy 436.177436 -286.771334) (xy 430.1363 -286.771334) (xy 430.135795 -286.781489)
			(xy 430.128017 -286.800252) (xy 430.113655 -286.814615) (xy 430.094893 -286.822395) (xy 430.084738 -286.822896)
			(xy 428.685198 -286.822896) (xy 428.675044 -286.822369) (xy 428.656282 -286.8146) (xy 428.641918 -286.800245)
			(xy 428.634137 -286.781487) (xy 428.633636 -286.771334) (xy 422.5925 -286.771334) (xy 422.591995 -286.781489)
			(xy 422.584217 -286.800252) (xy 422.569855 -286.814615) (xy 422.551093 -286.822395) (xy 422.540938 -286.822896)
			(xy 421.141398 -286.822896) (xy 421.131244 -286.822369) (xy 421.112482 -286.8146) (xy 421.098118 -286.800245)
			(xy 421.090337 -286.781487) (xy 421.089836 -286.771334) (xy 415.0487 -286.771334) (xy 415.048195 -286.781489)
			(xy 415.040417 -286.800252) (xy 415.026055 -286.814615) (xy 415.007293 -286.822395) (xy 414.997138 -286.822896)
			(xy 413.597598 -286.822896) (xy 413.587444 -286.822369) (xy 413.568682 -286.8146) (xy 413.554318 -286.800245)
			(xy 413.546537 -286.781487) (xy 413.546036 -286.771334) (xy 407.5049 -286.771334) (xy 407.504395 -286.781489)
			(xy 407.496617 -286.800252) (xy 407.482255 -286.814615) (xy 407.463493 -286.822395) (xy 407.453338 -286.822896)
			(xy 406.053798 -286.822896) (xy 406.043644 -286.822369) (xy 406.024882 -286.8146) (xy 406.010518 -286.800245)
			(xy 406.002737 -286.781487) (xy 406.002236 -286.771334) (xy 381.450149 -286.771334) (xy 381.432179 -286.78049)
			(xy 381.3829 -286.796502) (xy 381.331723 -286.804608) (xy 381.279909 -286.804608) (xy 381.228732 -286.796502)
			(xy 381.179453 -286.78049) (xy 381.133286 -286.756967) (xy 381.091367 -286.726511) (xy 381.054729 -286.689873)
			(xy 381.024273 -286.647954) (xy 381.00075 -286.601787) (xy 380.984738 -286.552508) (xy 380.976632 -286.501331)
			(xy 380.976124 -286.475424) (xy 379.755908 -286.475424) (xy 379.7554 -286.501331) (xy 379.747294 -286.552508)
			(xy 379.731282 -286.601787) (xy 379.707759 -286.647954) (xy 379.677303 -286.689873) (xy 379.640665 -286.726511)
			(xy 379.598746 -286.756967) (xy 379.552579 -286.78049) (xy 379.5033 -286.796502) (xy 379.452123 -286.804608)
			(xy 379.400309 -286.804608) (xy 379.349132 -286.796502) (xy 379.299853 -286.78049) (xy 379.253686 -286.756967)
			(xy 379.211767 -286.726511) (xy 379.175129 -286.689873) (xy 379.144673 -286.647954) (xy 379.12115 -286.601787)
			(xy 379.105138 -286.552508) (xy 379.097032 -286.501331) (xy 379.096524 -286.475424) (xy 377.876308 -286.475424)
			(xy 377.8758 -286.501331) (xy 377.867694 -286.552508) (xy 377.851682 -286.601787) (xy 377.828159 -286.647954)
			(xy 377.797703 -286.689873) (xy 377.761065 -286.726511) (xy 377.719146 -286.756967) (xy 377.672979 -286.78049)
			(xy 377.6237 -286.796502) (xy 377.572523 -286.804608) (xy 377.520709 -286.804608) (xy 377.469532 -286.796502)
			(xy 377.420253 -286.78049) (xy 377.374086 -286.756967) (xy 377.332167 -286.726511) (xy 377.295529 -286.689873)
			(xy 377.265073 -286.647954) (xy 377.24155 -286.601787) (xy 377.225538 -286.552508) (xy 377.217432 -286.501331)
			(xy 377.216924 -286.475424) (xy 375.996708 -286.475424) (xy 375.9962 -286.501331) (xy 375.988094 -286.552508)
			(xy 375.972082 -286.601787) (xy 375.948559 -286.647954) (xy 375.918103 -286.689873) (xy 375.881465 -286.726511)
			(xy 375.839546 -286.756967) (xy 375.793379 -286.78049) (xy 375.7441 -286.796502) (xy 375.692923 -286.804608)
			(xy 375.641109 -286.804608) (xy 375.589932 -286.796502) (xy 375.540653 -286.78049) (xy 375.494486 -286.756967)
			(xy 375.452567 -286.726511) (xy 375.415929 -286.689873) (xy 375.385473 -286.647954) (xy 375.36195 -286.601787)
			(xy 375.345938 -286.552508) (xy 375.337832 -286.501331) (xy 375.337324 -286.475424) (xy 374.117108 -286.475424)
			(xy 374.1166 -286.501331) (xy 374.108494 -286.552508) (xy 374.092482 -286.601787) (xy 374.068959 -286.647954)
			(xy 374.038503 -286.689873) (xy 374.001865 -286.726511) (xy 373.959946 -286.756967) (xy 373.913779 -286.78049)
			(xy 373.8645 -286.796502) (xy 373.813323 -286.804608) (xy 373.761509 -286.804608) (xy 373.710332 -286.796502)
			(xy 373.661053 -286.78049) (xy 373.614886 -286.756967) (xy 373.572967 -286.726511) (xy 373.536329 -286.689873)
			(xy 373.505873 -286.647954) (xy 373.48235 -286.601787) (xy 373.466338 -286.552508) (xy 373.458232 -286.501331)
			(xy 373.457724 -286.475424) (xy 372.237508 -286.475424) (xy 372.237 -286.501331) (xy 372.228894 -286.552508)
			(xy 372.212882 -286.601787) (xy 372.189359 -286.647954) (xy 372.158903 -286.689873) (xy 372.122265 -286.726511)
			(xy 372.080346 -286.756967) (xy 372.034179 -286.78049) (xy 371.9849 -286.796502) (xy 371.933723 -286.804608)
			(xy 371.881909 -286.804608) (xy 371.830732 -286.796502) (xy 371.781453 -286.78049) (xy 371.735286 -286.756967)
			(xy 371.693367 -286.726511) (xy 371.656729 -286.689873) (xy 371.626273 -286.647954) (xy 371.60275 -286.601787)
			(xy 371.586738 -286.552508) (xy 371.578632 -286.501331) (xy 371.578124 -286.475424) (xy 370.357908 -286.475424)
			(xy 370.3574 -286.501331) (xy 370.349294 -286.552508) (xy 370.333282 -286.601787) (xy 370.309759 -286.647954)
			(xy 370.279303 -286.689873) (xy 370.242665 -286.726511) (xy 370.200746 -286.756967) (xy 370.154579 -286.78049)
			(xy 370.1053 -286.796502) (xy 370.054123 -286.804608) (xy 370.002309 -286.804608) (xy 369.951132 -286.796502)
			(xy 369.901853 -286.78049) (xy 369.855686 -286.756967) (xy 369.813767 -286.726511) (xy 369.777129 -286.689873)
			(xy 369.746673 -286.647954) (xy 369.72315 -286.601787) (xy 369.707138 -286.552508) (xy 369.699032 -286.501331)
			(xy 369.698524 -286.475424) (xy 368.478308 -286.475424) (xy 368.4778 -286.501331) (xy 368.469694 -286.552508)
			(xy 368.453682 -286.601787) (xy 368.430159 -286.647954) (xy 368.399703 -286.689873) (xy 368.363065 -286.726511)
			(xy 368.321146 -286.756967) (xy 368.274979 -286.78049) (xy 368.2257 -286.796502) (xy 368.174523 -286.804608)
			(xy 368.122709 -286.804608) (xy 368.071532 -286.796502) (xy 368.022253 -286.78049) (xy 367.976086 -286.756967)
			(xy 367.934167 -286.726511) (xy 367.897529 -286.689873) (xy 367.867073 -286.647954) (xy 367.84355 -286.601787)
			(xy 367.827538 -286.552508) (xy 367.819432 -286.501331) (xy 367.818924 -286.475424) (xy 351.561908 -286.475424)
			(xy 351.5614 -286.501331) (xy 351.553294 -286.552508) (xy 351.537282 -286.601787) (xy 351.513759 -286.647954)
			(xy 351.483303 -286.689873) (xy 351.446665 -286.726511) (xy 351.404746 -286.756967) (xy 351.358579 -286.78049)
			(xy 351.3093 -286.796502) (xy 351.258123 -286.804608) (xy 351.206309 -286.804608) (xy 351.155132 -286.796502)
			(xy 351.105853 -286.78049) (xy 351.059686 -286.756967) (xy 351.017767 -286.726511) (xy 350.981129 -286.689873)
			(xy 350.950673 -286.647954) (xy 350.92715 -286.601787) (xy 350.911138 -286.552508) (xy 350.903032 -286.501331)
			(xy 350.902524 -286.475424) (xy 350.903123 -286.447707) (xy 350.912443 -286.39306) (xy 350.921066 -286.366712)
			(xy 350.92894 -286.344614) (xy 350.723962 -285.989522) (xy 350.700848 -285.985204) (xy 350.676027 -285.980039)
			(xy 350.628247 -285.963084) (xy 350.583628 -285.939012) (xy 350.543222 -285.908392) (xy 350.507981 -285.871945)
			(xy 350.478737 -285.830531) (xy 350.45618 -285.785127) (xy 350.440843 -285.736804) (xy 350.433086 -285.686703)
			(xy 350.432624 -285.661354) (xy 350.1517 -285.661354) (xy 350.151192 -285.687241) (xy 350.143093 -285.738379)
			(xy 350.127094 -285.787619) (xy 350.103588 -285.833751) (xy 350.073156 -285.875638) (xy 350.036546 -285.912248)
			(xy 349.994659 -285.94268) (xy 349.948527 -285.966186) (xy 349.899287 -285.982185) (xy 349.848149 -285.990284)
			(xy 349.796375 -285.990284) (xy 349.745237 -285.982185) (xy 349.695997 -285.966186) (xy 349.649865 -285.94268)
			(xy 349.607978 -285.912248) (xy 349.571368 -285.875638) (xy 349.540936 -285.833751) (xy 349.51743 -285.787619)
			(xy 349.501431 -285.738379) (xy 349.493332 -285.687241) (xy 349.492824 -285.661354) (xy 349.2119 -285.661354)
			(xy 349.2119 -285.661862) (xy 349.211323 -285.689379) (xy 349.202128 -285.74364) (xy 349.193612 -285.769812)
			(xy 349.185992 -285.79191) (xy 349.391224 -286.147256) (xy 349.414084 -286.151574) (xy 349.438906 -286.156737)
			(xy 349.486683 -286.173695) (xy 349.531301 -286.197768) (xy 349.571706 -286.22839) (xy 349.606946 -286.264837)
			(xy 349.636189 -286.30625) (xy 349.658746 -286.351653) (xy 349.674085 -286.399975) (xy 349.681845 -286.450075)
			(xy 349.682308 -286.475424) (xy 349.6818 -286.501331) (xy 349.673694 -286.552508) (xy 349.657682 -286.601787)
			(xy 349.634159 -286.647954) (xy 349.603703 -286.689873) (xy 349.567065 -286.726511) (xy 349.525146 -286.756967)
			(xy 349.478979 -286.78049) (xy 349.4297 -286.796502) (xy 349.378523 -286.804608) (xy 349.326709 -286.804608)
			(xy 349.275532 -286.796502) (xy 349.226253 -286.78049) (xy 349.180086 -286.756967) (xy 349.138167 -286.726511)
			(xy 349.101529 -286.689873) (xy 349.071073 -286.647954) (xy 349.04755 -286.601787) (xy 349.031538 -286.552508)
			(xy 349.023432 -286.501331) (xy 349.022924 -286.475424) (xy 349.023523 -286.447707) (xy 349.032843 -286.39306)
			(xy 349.041466 -286.366712) (xy 349.04934 -286.344614) (xy 348.844362 -285.989522) (xy 348.821248 -285.985204)
			(xy 348.796427 -285.980039) (xy 348.748647 -285.963084) (xy 348.704028 -285.939012) (xy 348.663622 -285.908392)
			(xy 348.628381 -285.871945) (xy 348.599137 -285.830531) (xy 348.57658 -285.785127) (xy 348.561243 -285.736804)
			(xy 348.553486 -285.686703) (xy 348.553024 -285.661354) (xy 348.2721 -285.661354) (xy 348.271592 -285.687241)
			(xy 348.263493 -285.738379) (xy 348.247494 -285.787619) (xy 348.223988 -285.833751) (xy 348.193556 -285.875638)
			(xy 348.156946 -285.912248) (xy 348.115059 -285.94268) (xy 348.068927 -285.966186) (xy 348.019687 -285.982185)
			(xy 347.968549 -285.990284) (xy 347.916775 -285.990284) (xy 347.865637 -285.982185) (xy 347.816397 -285.966186)
			(xy 347.770265 -285.94268) (xy 347.728378 -285.912248) (xy 347.691768 -285.875638) (xy 347.661336 -285.833751)
			(xy 347.63783 -285.787619) (xy 347.621831 -285.738379) (xy 347.613732 -285.687241) (xy 347.613224 -285.661354)
			(xy 347.3323 -285.661354) (xy 347.3323 -285.661862) (xy 347.331723 -285.689379) (xy 347.322528 -285.74364)
			(xy 347.314012 -285.769812) (xy 347.306392 -285.79191) (xy 347.511624 -286.147256) (xy 347.534484 -286.151574)
			(xy 347.559306 -286.156737) (xy 347.607083 -286.173695) (xy 347.651701 -286.197768) (xy 347.692106 -286.22839)
			(xy 347.727346 -286.264837) (xy 347.756589 -286.30625) (xy 347.779146 -286.351653) (xy 347.794485 -286.399975)
			(xy 347.802245 -286.450075) (xy 347.802708 -286.475424) (xy 347.8022 -286.501331) (xy 347.794094 -286.552508)
			(xy 347.778082 -286.601787) (xy 347.754559 -286.647954) (xy 347.724103 -286.689873) (xy 347.687465 -286.726511)
			(xy 347.645546 -286.756967) (xy 347.599379 -286.78049) (xy 347.5501 -286.796502) (xy 347.498923 -286.804608)
			(xy 347.447109 -286.804608) (xy 347.395932 -286.796502) (xy 347.346653 -286.78049) (xy 347.300486 -286.756967)
			(xy 347.258567 -286.726511) (xy 347.221929 -286.689873) (xy 347.191473 -286.647954) (xy 347.16795 -286.601787)
			(xy 347.151938 -286.552508) (xy 347.143832 -286.501331) (xy 347.143324 -286.475424) (xy 347.143923 -286.447707)
			(xy 347.153243 -286.39306) (xy 347.161866 -286.366712) (xy 347.16974 -286.344614) (xy 346.964762 -285.989522)
			(xy 346.941648 -285.985204) (xy 346.916827 -285.980039) (xy 346.869047 -285.963084) (xy 346.824428 -285.939012)
			(xy 346.784022 -285.908392) (xy 346.748781 -285.871945) (xy 346.719537 -285.830531) (xy 346.69698 -285.785127)
			(xy 346.681643 -285.736804) (xy 346.673886 -285.686703) (xy 346.673424 -285.661354) (xy 346.3925 -285.661354)
			(xy 346.391992 -285.687241) (xy 346.383893 -285.738379) (xy 346.367894 -285.787619) (xy 346.344388 -285.833751)
			(xy 346.313956 -285.875638) (xy 346.277346 -285.912248) (xy 346.235459 -285.94268) (xy 346.189327 -285.966186)
			(xy 346.140087 -285.982185) (xy 346.088949 -285.990284) (xy 346.037175 -285.990284) (xy 345.986037 -285.982185)
			(xy 345.936797 -285.966186) (xy 345.890665 -285.94268) (xy 345.848778 -285.912248) (xy 345.812168 -285.875638)
			(xy 345.781736 -285.833751) (xy 345.75823 -285.787619) (xy 345.742231 -285.738379) (xy 345.734132 -285.687241)
			(xy 345.733624 -285.661354) (xy 345.4527 -285.661354) (xy 345.4527 -285.661862) (xy 345.452123 -285.689379)
			(xy 345.442928 -285.74364) (xy 345.434412 -285.769812) (xy 345.426792 -285.79191) (xy 345.632024 -286.147256)
			(xy 345.654884 -286.151574) (xy 345.679706 -286.156737) (xy 345.727483 -286.173695) (xy 345.772101 -286.197768)
			(xy 345.812506 -286.22839) (xy 345.847746 -286.264837) (xy 345.876989 -286.30625) (xy 345.899546 -286.351653)
			(xy 345.914885 -286.399975) (xy 345.922645 -286.450075) (xy 345.923108 -286.475424) (xy 345.9226 -286.501331)
			(xy 345.914494 -286.552508) (xy 345.898482 -286.601787) (xy 345.874959 -286.647954) (xy 345.844503 -286.689873)
			(xy 345.807865 -286.726511) (xy 345.765946 -286.756967) (xy 345.719779 -286.78049) (xy 345.6705 -286.796502)
			(xy 345.619323 -286.804608) (xy 345.567509 -286.804608) (xy 345.516332 -286.796502) (xy 345.467053 -286.78049)
			(xy 345.420886 -286.756967) (xy 345.378967 -286.726511) (xy 345.342329 -286.689873) (xy 345.311873 -286.647954)
			(xy 345.28835 -286.601787) (xy 345.272338 -286.552508) (xy 345.264232 -286.501331) (xy 345.263724 -286.475424)
			(xy 345.264323 -286.447707) (xy 345.273643 -286.39306) (xy 345.282266 -286.366712) (xy 345.29014 -286.344614)
			(xy 345.085162 -285.989522) (xy 345.062048 -285.985204) (xy 345.037227 -285.980039) (xy 344.989447 -285.963084)
			(xy 344.944828 -285.939012) (xy 344.904422 -285.908392) (xy 344.869181 -285.871945) (xy 344.839937 -285.830531)
			(xy 344.81738 -285.785127) (xy 344.802043 -285.736804) (xy 344.794286 -285.686703) (xy 344.793824 -285.661354)
			(xy 344.5129 -285.661354) (xy 344.512392 -285.687241) (xy 344.504293 -285.738379) (xy 344.488294 -285.787619)
			(xy 344.464788 -285.833751) (xy 344.434356 -285.875638) (xy 344.397746 -285.912248) (xy 344.355859 -285.94268)
			(xy 344.309727 -285.966186) (xy 344.260487 -285.982185) (xy 344.209349 -285.990284) (xy 344.157575 -285.990284)
			(xy 344.106437 -285.982185) (xy 344.057197 -285.966186) (xy 344.011065 -285.94268) (xy 343.969178 -285.912248)
			(xy 343.932568 -285.875638) (xy 343.902136 -285.833751) (xy 343.87863 -285.787619) (xy 343.862631 -285.738379)
			(xy 343.854532 -285.687241) (xy 343.854024 -285.661354) (xy 343.5731 -285.661354) (xy 343.5731 -285.661862)
			(xy 343.572523 -285.689379) (xy 343.563328 -285.74364) (xy 343.554812 -285.769812) (xy 343.547192 -285.79191)
			(xy 343.752424 -286.147256) (xy 343.775284 -286.151574) (xy 343.800106 -286.156737) (xy 343.847883 -286.173695)
			(xy 343.892501 -286.197768) (xy 343.932906 -286.22839) (xy 343.968146 -286.264837) (xy 343.997389 -286.30625)
			(xy 344.019946 -286.351653) (xy 344.035285 -286.399975) (xy 344.043045 -286.450075) (xy 344.043508 -286.475424)
			(xy 344.043 -286.501331) (xy 344.034894 -286.552508) (xy 344.018882 -286.601787) (xy 343.995359 -286.647954)
			(xy 343.964903 -286.689873) (xy 343.928265 -286.726511) (xy 343.886346 -286.756967) (xy 343.840179 -286.78049)
			(xy 343.7909 -286.796502) (xy 343.739723 -286.804608) (xy 343.687909 -286.804608) (xy 343.636732 -286.796502)
			(xy 343.587453 -286.78049) (xy 343.541286 -286.756967) (xy 343.499367 -286.726511) (xy 343.462729 -286.689873)
			(xy 343.432273 -286.647954) (xy 343.40875 -286.601787) (xy 343.392738 -286.552508) (xy 343.384632 -286.501331)
			(xy 343.384124 -286.475424) (xy 343.384723 -286.447707) (xy 343.394043 -286.39306) (xy 343.402666 -286.366712)
			(xy 343.41054 -286.344614) (xy 343.205562 -285.989522) (xy 343.182448 -285.985204) (xy 343.157627 -285.980039)
			(xy 343.109847 -285.963084) (xy 343.065228 -285.939012) (xy 343.024822 -285.908392) (xy 342.989581 -285.871945)
			(xy 342.960337 -285.830531) (xy 342.93778 -285.785127) (xy 342.922443 -285.736804) (xy 342.914686 -285.686703)
			(xy 342.914224 -285.661354) (xy 342.6333 -285.661354) (xy 342.632792 -285.687241) (xy 342.624693 -285.738379)
			(xy 342.608694 -285.787619) (xy 342.585188 -285.833751) (xy 342.554756 -285.875638) (xy 342.518146 -285.912248)
			(xy 342.476259 -285.94268) (xy 342.430127 -285.966186) (xy 342.380887 -285.982185) (xy 342.329749 -285.990284)
			(xy 342.277975 -285.990284) (xy 342.226837 -285.982185) (xy 342.177597 -285.966186) (xy 342.131465 -285.94268)
			(xy 342.089578 -285.912248) (xy 342.052968 -285.875638) (xy 342.022536 -285.833751) (xy 341.99903 -285.787619)
			(xy 341.983031 -285.738379) (xy 341.974932 -285.687241) (xy 341.974424 -285.661354) (xy 341.6935 -285.661354)
			(xy 341.6935 -285.661862) (xy 341.692923 -285.689379) (xy 341.683728 -285.74364) (xy 341.675212 -285.769812)
			(xy 341.667592 -285.79191) (xy 341.872824 -286.147256) (xy 341.895684 -286.151574) (xy 341.920506 -286.156737)
			(xy 341.968283 -286.173695) (xy 342.012901 -286.197768) (xy 342.053306 -286.22839) (xy 342.088546 -286.264837)
			(xy 342.117789 -286.30625) (xy 342.140346 -286.351653) (xy 342.155685 -286.399975) (xy 342.163445 -286.450075)
			(xy 342.163908 -286.475424) (xy 342.1634 -286.501331) (xy 342.155294 -286.552508) (xy 342.139282 -286.601787)
			(xy 342.115759 -286.647954) (xy 342.085303 -286.689873) (xy 342.048665 -286.726511) (xy 342.006746 -286.756967)
			(xy 341.960579 -286.78049) (xy 341.9113 -286.796502) (xy 341.860123 -286.804608) (xy 341.808309 -286.804608)
			(xy 341.757132 -286.796502) (xy 341.707853 -286.78049) (xy 341.661686 -286.756967) (xy 341.619767 -286.726511)
			(xy 341.583129 -286.689873) (xy 341.552673 -286.647954) (xy 341.52915 -286.601787) (xy 341.513138 -286.552508)
			(xy 341.505032 -286.501331) (xy 341.504524 -286.475424) (xy 341.505123 -286.447707) (xy 341.514443 -286.39306)
			(xy 341.523066 -286.366712) (xy 341.53094 -286.344614) (xy 341.325962 -285.989522) (xy 341.302848 -285.985204)
			(xy 341.278027 -285.980039) (xy 341.230247 -285.963084) (xy 341.185628 -285.939012) (xy 341.145222 -285.908392)
			(xy 341.109981 -285.871945) (xy 341.080737 -285.830531) (xy 341.05818 -285.785127) (xy 341.042843 -285.736804)
			(xy 341.035086 -285.686703) (xy 341.034624 -285.661354) (xy 340.7537 -285.661354) (xy 340.753192 -285.687241)
			(xy 340.745093 -285.738379) (xy 340.729094 -285.787619) (xy 340.705588 -285.833751) (xy 340.675156 -285.875638)
			(xy 340.638546 -285.912248) (xy 340.596659 -285.94268) (xy 340.550527 -285.966186) (xy 340.501287 -285.982185)
			(xy 340.450149 -285.990284) (xy 340.398375 -285.990284) (xy 340.347237 -285.982185) (xy 340.297997 -285.966186)
			(xy 340.251865 -285.94268) (xy 340.209978 -285.912248) (xy 340.173368 -285.875638) (xy 340.142936 -285.833751)
			(xy 340.11943 -285.787619) (xy 340.103431 -285.738379) (xy 340.095332 -285.687241) (xy 340.094824 -285.661354)
			(xy 339.814408 -285.661354) (xy 339.813802 -285.689071) (xy 339.804487 -285.743717) (xy 339.795866 -285.770066)
			(xy 339.787992 -285.792164) (xy 339.993224 -286.147256) (xy 340.016084 -286.151574) (xy 340.040906 -286.156737)
			(xy 340.088683 -286.173695) (xy 340.133301 -286.197768) (xy 340.173706 -286.22839) (xy 340.208946 -286.264837)
			(xy 340.238189 -286.30625) (xy 340.260746 -286.351653) (xy 340.276085 -286.399975) (xy 340.283845 -286.450075)
			(xy 340.284308 -286.475424) (xy 340.2838 -286.501331) (xy 340.275694 -286.552508) (xy 340.259682 -286.601787)
			(xy 340.236159 -286.647954) (xy 340.205703 -286.689873) (xy 340.169065 -286.726511) (xy 340.127146 -286.756967)
			(xy 340.080979 -286.78049) (xy 340.0317 -286.796502) (xy 339.980523 -286.804608) (xy 339.928709 -286.804608)
			(xy 339.877532 -286.796502) (xy 339.828253 -286.78049) (xy 339.782086 -286.756967) (xy 339.740167 -286.726511)
			(xy 339.703529 -286.689873) (xy 339.673073 -286.647954) (xy 339.64955 -286.601787) (xy 339.633538 -286.552508)
			(xy 339.625432 -286.501331) (xy 339.624924 -286.475424) (xy 339.625523 -286.447707) (xy 339.634843 -286.39306)
			(xy 339.643466 -286.366712) (xy 339.65134 -286.344614) (xy 339.446108 -285.989522) (xy 339.423248 -285.985204)
			(xy 339.398427 -285.980039) (xy 339.350647 -285.963084) (xy 339.306028 -285.939012) (xy 339.265622 -285.908392)
			(xy 339.230381 -285.871945) (xy 339.201137 -285.830531) (xy 339.17858 -285.785127) (xy 339.163243 -285.736804)
			(xy 339.155486 -285.686703) (xy 339.155024 -285.661354) (xy 338.874608 -285.661354) (xy 338.8741 -285.687261)
			(xy 338.865994 -285.738438) (xy 338.849982 -285.787717) (xy 338.826459 -285.833884) (xy 338.796003 -285.875803)
			(xy 338.759365 -285.912441) (xy 338.717446 -285.942897) (xy 338.671279 -285.96642) (xy 338.622 -285.982432)
			(xy 338.570823 -285.990538) (xy 338.519009 -285.990538) (xy 338.467832 -285.982432) (xy 338.418553 -285.96642)
			(xy 338.372386 -285.942897) (xy 338.330467 -285.912441) (xy 338.293829 -285.875803) (xy 338.263373 -285.833884)
			(xy 338.23985 -285.787717) (xy 338.223838 -285.738438) (xy 338.215732 -285.687261) (xy 338.215224 -285.661354)
			(xy 337.9343 -285.661354) (xy 337.933759 -285.689062) (xy 337.924571 -285.743708) (xy 337.916012 -285.770066)
			(xy 337.908138 -285.792164) (xy 338.11337 -286.147256) (xy 338.13623 -286.151574) (xy 338.16104 -286.156732)
			(xy 338.20878 -286.173726) (xy 338.253357 -286.197824) (xy 338.293722 -286.228459) (xy 338.328925 -286.264909)
			(xy 338.358136 -286.306317) (xy 338.380667 -286.351707) (xy 338.395988 -286.400009) (xy 338.403738 -286.450087)
			(xy 338.4042 -286.475424) (xy 338.403692 -286.501311) (xy 338.395593 -286.552449) (xy 338.379594 -286.601689)
			(xy 338.356088 -286.647821) (xy 338.325656 -286.689708) (xy 338.289046 -286.726318) (xy 338.247159 -286.75675)
			(xy 338.201027 -286.780256) (xy 338.151787 -286.796255) (xy 338.100649 -286.804354) (xy 338.048875 -286.804354)
			(xy 337.997737 -286.796255) (xy 337.948497 -286.780256) (xy 337.902365 -286.75675) (xy 337.860478 -286.726318)
			(xy 337.823868 -286.689708) (xy 337.793436 -286.647821) (xy 337.76993 -286.601689) (xy 337.753931 -286.552449)
			(xy 337.745832 -286.501311) (xy 337.745324 -286.475424) (xy 337.745858 -286.447716) (xy 337.75505 -286.393069)
			(xy 337.763612 -286.366712) (xy 337.771486 -286.344614) (xy 337.566254 -285.989522) (xy 337.543394 -285.985204)
			(xy 337.518583 -285.980049) (xy 337.470842 -285.963057) (xy 337.426263 -285.93896) (xy 337.385896 -285.908325)
			(xy 337.350693 -285.871874) (xy 337.321482 -285.830466) (xy 337.298951 -285.785075) (xy 337.283632 -285.736771)
			(xy 337.275885 -285.686692) (xy 337.275424 -285.661354) (xy 336.0547 -285.661354) (xy 336.054192 -285.687241)
			(xy 336.046093 -285.738379) (xy 336.030094 -285.787619) (xy 336.006588 -285.833751) (xy 335.976156 -285.875638)
			(xy 335.939546 -285.912248) (xy 335.897659 -285.94268) (xy 335.851527 -285.966186) (xy 335.802287 -285.982185)
			(xy 335.751149 -285.990284) (xy 335.699375 -285.990284) (xy 335.648237 -285.982185) (xy 335.598997 -285.966186)
			(xy 335.552865 -285.94268) (xy 335.510978 -285.912248) (xy 335.474368 -285.875638) (xy 335.443936 -285.833751)
			(xy 335.42043 -285.787619) (xy 335.404431 -285.738379) (xy 335.396332 -285.687241) (xy 335.395824 -285.661354)
			(xy 313.738768 -285.661354) (xy 313.738768 -285.92145) (xy 313.738295 -285.931618) (xy 313.730528 -285.95041)
			(xy 313.716157 -285.964797) (xy 313.697373 -285.972584) (xy 313.687206 -285.973012) (xy 312.287666 -285.973012)
			(xy 312.277486 -285.972663) (xy 312.258681 -285.964857) (xy 312.244295 -285.950448) (xy 312.236521 -285.931631)
			(xy 312.236104 -285.92145) (xy 306.194968 -285.92145) (xy 306.194495 -285.931618) (xy 306.186728 -285.95041)
			(xy 306.172357 -285.964797) (xy 306.153573 -285.972584) (xy 306.143406 -285.973012) (xy 304.743866 -285.973012)
			(xy 304.733686 -285.972663) (xy 304.714881 -285.964857) (xy 304.700495 -285.950448) (xy 304.692721 -285.931631)
			(xy 304.692304 -285.92145) (xy 298.651168 -285.92145) (xy 298.650695 -285.931618) (xy 298.642928 -285.95041)
			(xy 298.628557 -285.964797) (xy 298.609773 -285.972584) (xy 298.599606 -285.973012) (xy 297.200066 -285.973012)
			(xy 297.189886 -285.972663) (xy 297.171081 -285.964857) (xy 297.156695 -285.950448) (xy 297.148921 -285.931631)
			(xy 297.148504 -285.92145) (xy 291.107368 -285.92145) (xy 291.106895 -285.931618) (xy 291.099128 -285.95041)
			(xy 291.084757 -285.964797) (xy 291.065973 -285.972584) (xy 291.055806 -285.973012) (xy 289.656266 -285.973012)
			(xy 289.646086 -285.972663) (xy 289.627281 -285.964857) (xy 289.612895 -285.950448) (xy 289.605121 -285.931631)
			(xy 289.604704 -285.92145) (xy 283.563568 -285.92145) (xy 283.563095 -285.931618) (xy 283.555328 -285.95041)
			(xy 283.540957 -285.964797) (xy 283.522173 -285.972584) (xy 283.512006 -285.973012) (xy 282.112466 -285.973012)
			(xy 282.102286 -285.972663) (xy 282.083481 -285.964857) (xy 282.069095 -285.950448) (xy 282.061321 -285.931631)
			(xy 282.060904 -285.92145) (xy 276.019768 -285.92145) (xy 276.019295 -285.931618) (xy 276.011528 -285.95041)
			(xy 275.997157 -285.964797) (xy 275.978373 -285.972584) (xy 275.968206 -285.973012) (xy 274.568666 -285.973012)
			(xy 274.558486 -285.972663) (xy 274.539681 -285.964857) (xy 274.525295 -285.950448) (xy 274.517521 -285.931631)
			(xy 274.517104 -285.92145) (xy 268.475968 -285.92145) (xy 268.475495 -285.931618) (xy 268.467728 -285.95041)
			(xy 268.453357 -285.964797) (xy 268.434573 -285.972584) (xy 268.424406 -285.973012) (xy 267.024866 -285.973012)
			(xy 267.014686 -285.972663) (xy 266.995881 -285.964857) (xy 266.981495 -285.950448) (xy 266.973721 -285.931631)
			(xy 266.973304 -285.92145) (xy 260.932168 -285.92145) (xy 260.931695 -285.931618) (xy 260.923928 -285.95041)
			(xy 260.909557 -285.964797) (xy 260.890773 -285.972584) (xy 260.880606 -285.973012) (xy 259.481066 -285.973012)
			(xy 259.470886 -285.972663) (xy 259.452081 -285.964857) (xy 259.437695 -285.950448) (xy 259.429921 -285.931631)
			(xy 259.429504 -285.92145) (xy 216.4715 -285.92145) (xy 216.470996 -285.931614) (xy 216.463235 -285.9504)
			(xy 216.448874 -285.964785) (xy 216.430101 -285.972579) (xy 216.419938 -285.973012) (xy 215.020398 -285.973012)
			(xy 215.01022 -285.972637) (xy 214.991416 -285.964842) (xy 214.977029 -285.950441) (xy 214.969253 -285.931628)
			(xy 214.968836 -285.92145) (xy 208.9277 -285.92145) (xy 208.927196 -285.931614) (xy 208.919435 -285.9504)
			(xy 208.905074 -285.964785) (xy 208.886301 -285.972579) (xy 208.876138 -285.973012) (xy 207.476598 -285.973012)
			(xy 207.46642 -285.972637) (xy 207.447616 -285.964842) (xy 207.433229 -285.950441) (xy 207.425453 -285.931628)
			(xy 207.425036 -285.92145) (xy 201.3839 -285.92145) (xy 201.383396 -285.931614) (xy 201.375635 -285.9504)
			(xy 201.361274 -285.964785) (xy 201.342501 -285.972579) (xy 201.332338 -285.973012) (xy 199.932798 -285.973012)
			(xy 199.92262 -285.972637) (xy 199.903816 -285.964842) (xy 199.889429 -285.950441) (xy 199.881653 -285.931628)
			(xy 199.881236 -285.92145) (xy 193.8401 -285.92145) (xy 193.839596 -285.931614) (xy 193.831835 -285.9504)
			(xy 193.817474 -285.964785) (xy 193.798701 -285.972579) (xy 193.788538 -285.973012) (xy 192.388998 -285.973012)
			(xy 192.37882 -285.972637) (xy 192.360016 -285.964842) (xy 192.345629 -285.950441) (xy 192.337853 -285.931628)
			(xy 192.337436 -285.92145) (xy 186.2963 -285.92145) (xy 186.295796 -285.931614) (xy 186.288035 -285.9504)
			(xy 186.273674 -285.964785) (xy 186.254901 -285.972579) (xy 186.244738 -285.973012) (xy 184.845198 -285.973012)
			(xy 184.83502 -285.972637) (xy 184.816216 -285.964842) (xy 184.801829 -285.950441) (xy 184.794053 -285.931628)
			(xy 184.793636 -285.92145) (xy 178.7525 -285.92145) (xy 178.751996 -285.931614) (xy 178.744235 -285.9504)
			(xy 178.729874 -285.964785) (xy 178.711101 -285.972579) (xy 178.700938 -285.973012) (xy 177.301398 -285.973012)
			(xy 177.29122 -285.972637) (xy 177.272416 -285.964842) (xy 177.258029 -285.950441) (xy 177.250253 -285.931628)
			(xy 177.249836 -285.92145) (xy 171.2087 -285.92145) (xy 171.208196 -285.931614) (xy 171.200435 -285.9504)
			(xy 171.186074 -285.964785) (xy 171.167301 -285.972579) (xy 171.157138 -285.973012) (xy 169.757598 -285.973012)
			(xy 169.74742 -285.972637) (xy 169.728616 -285.964842) (xy 169.714229 -285.950441) (xy 169.706453 -285.931628)
			(xy 169.706036 -285.92145) (xy 163.6649 -285.92145) (xy 163.664396 -285.931614) (xy 163.656635 -285.9504)
			(xy 163.642274 -285.964785) (xy 163.623501 -285.972579) (xy 163.613338 -285.973012) (xy 162.213798 -285.973012)
			(xy 162.20362 -285.972637) (xy 162.184816 -285.964842) (xy 162.170429 -285.950441) (xy 162.162653 -285.931628)
			(xy 162.162236 -285.92145) (xy 134.036986 -285.92145) (xy 134.013971 -285.938915) (xy 133.969397 -285.963011)
			(xy 133.921662 -285.980004) (xy 133.896862 -285.985204) (xy 133.874002 -285.989522) (xy 133.669024 -286.344614)
			(xy 133.676898 -286.366458) (xy 133.685549 -286.392865) (xy 133.694866 -286.447642) (xy 133.69544 -286.475424)
			(xy 133.694932 -286.501331) (xy 133.686826 -286.552508) (xy 133.670814 -286.601787) (xy 133.647291 -286.647954)
			(xy 133.616835 -286.689873) (xy 133.580197 -286.726511) (xy 133.538278 -286.756967) (xy 133.510081 -286.771334)
			(xy 158.062168 -286.771334) (xy 158.062168 -286.362394) (xy 158.06256 -286.352218) (xy 158.070352 -286.333418)
			(xy 158.084748 -286.319032) (xy 158.103554 -286.311253) (xy 158.11373 -286.310832) (xy 159.51327 -286.310832)
			(xy 159.523439 -286.311288) (xy 159.542232 -286.319062) (xy 159.556617 -286.333438) (xy 159.564404 -286.352225)
			(xy 159.564832 -286.362394) (xy 159.564832 -286.771334) (xy 165.605968 -286.771334) (xy 165.605968 -286.362394)
			(xy 165.60636 -286.352218) (xy 165.614152 -286.333418) (xy 165.628548 -286.319032) (xy 165.647354 -286.311253)
			(xy 165.65753 -286.310832) (xy 167.05707 -286.310832) (xy 167.067239 -286.311288) (xy 167.086032 -286.319062)
			(xy 167.100417 -286.333438) (xy 167.108204 -286.352225) (xy 167.108632 -286.362394) (xy 167.108632 -286.771334)
			(xy 173.149768 -286.771334) (xy 173.149768 -286.362394) (xy 173.15016 -286.352218) (xy 173.157952 -286.333418)
			(xy 173.172348 -286.319032) (xy 173.191154 -286.311253) (xy 173.20133 -286.310832) (xy 174.60087 -286.310832)
			(xy 174.611039 -286.311288) (xy 174.629832 -286.319062) (xy 174.644217 -286.333438) (xy 174.652004 -286.352225)
			(xy 174.652432 -286.362394) (xy 174.652432 -286.771334) (xy 180.693568 -286.771334) (xy 180.693568 -286.362394)
			(xy 180.69396 -286.352218) (xy 180.701752 -286.333418) (xy 180.716148 -286.319032) (xy 180.734954 -286.311253)
			(xy 180.74513 -286.310832) (xy 182.14467 -286.310832) (xy 182.154839 -286.311288) (xy 182.173632 -286.319062)
			(xy 182.188017 -286.333438) (xy 182.195804 -286.352225) (xy 182.196232 -286.362394) (xy 182.196232 -286.771334)
			(xy 188.237368 -286.771334) (xy 188.237368 -286.362394) (xy 188.23776 -286.352218) (xy 188.245552 -286.333418)
			(xy 188.259948 -286.319032) (xy 188.278754 -286.311253) (xy 188.28893 -286.310832) (xy 189.68847 -286.310832)
			(xy 189.698639 -286.311288) (xy 189.717432 -286.319062) (xy 189.731817 -286.333438) (xy 189.739604 -286.352225)
			(xy 189.740032 -286.362394) (xy 189.740032 -286.771334) (xy 195.781168 -286.771334) (xy 195.781168 -286.362394)
			(xy 195.78156 -286.352218) (xy 195.789352 -286.333418) (xy 195.803748 -286.319032) (xy 195.822554 -286.311253)
			(xy 195.83273 -286.310832) (xy 197.23227 -286.310832) (xy 197.242439 -286.311288) (xy 197.261232 -286.319062)
			(xy 197.275617 -286.333438) (xy 197.283404 -286.352225) (xy 197.283832 -286.362394) (xy 197.283832 -286.771334)
			(xy 203.324968 -286.771334) (xy 203.324968 -286.362394) (xy 203.32536 -286.352218) (xy 203.333152 -286.333418)
			(xy 203.347548 -286.319032) (xy 203.366354 -286.311253) (xy 203.37653 -286.310832) (xy 204.77607 -286.310832)
			(xy 204.786239 -286.311288) (xy 204.805032 -286.319062) (xy 204.819417 -286.333438) (xy 204.827204 -286.352225)
			(xy 204.827632 -286.362394) (xy 204.827632 -286.771334) (xy 210.868768 -286.771334) (xy 210.868768 -286.362394)
			(xy 210.86916 -286.352218) (xy 210.876952 -286.333418) (xy 210.891348 -286.319032) (xy 210.910154 -286.311253)
			(xy 210.92033 -286.310832) (xy 212.31987 -286.310832) (xy 212.330039 -286.311288) (xy 212.348832 -286.319062)
			(xy 212.363217 -286.333438) (xy 212.371004 -286.352225) (xy 212.371432 -286.362394) (xy 212.371432 -286.771334)
			(xy 255.329436 -286.771334) (xy 255.329436 -286.362394) (xy 255.329929 -286.352236) (xy 255.337705 -286.333467)
			(xy 255.352071 -286.319102) (xy 255.37084 -286.311328) (xy 255.380998 -286.310832) (xy 256.780538 -286.310832)
			(xy 256.790697 -286.311302) (xy 256.809466 -286.319088) (xy 256.82383 -286.333461) (xy 256.831604 -286.352234)
			(xy 256.8321 -286.362394) (xy 256.8321 -286.771334) (xy 262.873236 -286.771334) (xy 262.873236 -286.362394)
			(xy 262.873729 -286.352236) (xy 262.881505 -286.333467) (xy 262.895871 -286.319102) (xy 262.91464 -286.311328)
			(xy 262.924798 -286.310832) (xy 264.324338 -286.310832) (xy 264.334497 -286.311302) (xy 264.353266 -286.319088)
			(xy 264.36763 -286.333461) (xy 264.375404 -286.352234) (xy 264.3759 -286.362394) (xy 264.3759 -286.771334)
			(xy 270.417036 -286.771334) (xy 270.417036 -286.362394) (xy 270.417529 -286.352236) (xy 270.425305 -286.333467)
			(xy 270.439671 -286.319102) (xy 270.45844 -286.311328) (xy 270.468598 -286.310832) (xy 271.868138 -286.310832)
			(xy 271.878297 -286.311302) (xy 271.897066 -286.319088) (xy 271.91143 -286.333461) (xy 271.919204 -286.352234)
			(xy 271.9197 -286.362394) (xy 271.9197 -286.771334) (xy 277.960836 -286.771334) (xy 277.960836 -286.362394)
			(xy 277.961329 -286.352236) (xy 277.969105 -286.333467) (xy 277.983471 -286.319102) (xy 278.00224 -286.311328)
			(xy 278.012398 -286.310832) (xy 279.411938 -286.310832) (xy 279.422097 -286.311302) (xy 279.440866 -286.319088)
			(xy 279.45523 -286.333461) (xy 279.463004 -286.352234) (xy 279.4635 -286.362394) (xy 279.4635 -286.771334)
			(xy 285.504636 -286.771334) (xy 285.504636 -286.362394) (xy 285.505129 -286.352236) (xy 285.512905 -286.333467)
			(xy 285.527271 -286.319102) (xy 285.54604 -286.311328) (xy 285.556198 -286.310832) (xy 286.955738 -286.310832)
			(xy 286.965897 -286.311302) (xy 286.984666 -286.319088) (xy 286.99903 -286.333461) (xy 287.006804 -286.352234)
			(xy 287.0073 -286.362394) (xy 287.0073 -286.771334) (xy 293.048436 -286.771334) (xy 293.048436 -286.362394)
			(xy 293.048929 -286.352236) (xy 293.056705 -286.333467) (xy 293.071071 -286.319102) (xy 293.08984 -286.311328)
			(xy 293.099998 -286.310832) (xy 294.499538 -286.310832) (xy 294.509697 -286.311302) (xy 294.528466 -286.319088)
			(xy 294.54283 -286.333461) (xy 294.550604 -286.352234) (xy 294.5511 -286.362394) (xy 294.5511 -286.771334)
			(xy 300.592236 -286.771334) (xy 300.592236 -286.362394) (xy 300.592729 -286.352236) (xy 300.600505 -286.333467)
			(xy 300.614871 -286.319102) (xy 300.63364 -286.311328) (xy 300.643798 -286.310832) (xy 302.043338 -286.310832)
			(xy 302.053497 -286.311302) (xy 302.072266 -286.319088) (xy 302.08663 -286.333461) (xy 302.094404 -286.352234)
			(xy 302.0949 -286.362394) (xy 302.0949 -286.771334) (xy 308.136036 -286.771334) (xy 308.136036 -286.362394)
			(xy 308.136529 -286.352236) (xy 308.144305 -286.333467) (xy 308.158671 -286.319102) (xy 308.17744 -286.311328)
			(xy 308.187598 -286.310832) (xy 309.587138 -286.310832) (xy 309.597297 -286.311302) (xy 309.616066 -286.319088)
			(xy 309.63043 -286.333461) (xy 309.638204 -286.352234) (xy 309.6387 -286.362394) (xy 309.6387 -286.475424)
			(xy 333.986124 -286.475424) (xy 333.986632 -286.449537) (xy 333.994731 -286.398399) (xy 334.01073 -286.349159)
			(xy 334.034236 -286.303027) (xy 334.064668 -286.26114) (xy 334.101278 -286.22453) (xy 334.143165 -286.194098)
			(xy 334.189297 -286.170592) (xy 334.238537 -286.154593) (xy 334.289675 -286.146494) (xy 334.341449 -286.146494)
			(xy 334.392587 -286.154593) (xy 334.441827 -286.170592) (xy 334.487959 -286.194098) (xy 334.529846 -286.22453)
			(xy 334.566456 -286.26114) (xy 334.596888 -286.303027) (xy 334.620394 -286.349159) (xy 334.636393 -286.398399)
			(xy 334.644492 -286.449537) (xy 334.645 -286.475424) (xy 334.644511 -286.501304) (xy 334.92624 -286.501304)
			(xy 334.92624 -286.449496) (xy 334.934344 -286.398327) (xy 334.950352 -286.349055) (xy 334.97387 -286.302894)
			(xy 335.00432 -286.26098) (xy 335.040951 -286.224345) (xy 335.082862 -286.19389) (xy 335.12902 -286.170367)
			(xy 335.17829 -286.154353) (xy 335.229459 -286.146243) (xy 335.255362 -286.145732) (xy 335.280855 -286.146231)
			(xy 335.331232 -286.154087) (xy 335.379796 -286.169618) (xy 335.425383 -286.192452) (xy 335.466904 -286.222042)
			(xy 335.503366 -286.257681) (xy 335.519014 -286.277812) (xy 335.93151 -286.277812) (xy 335.947185 -286.257701)
			(xy 335.98364 -286.222058) (xy 336.025155 -286.192461) (xy 336.070737 -286.16962) (xy 336.119296 -286.15408)
			(xy 336.16967 -286.146213) (xy 336.195162 -286.145732) (xy 336.221075 -286.146163) (xy 336.272264 -286.154265)
			(xy 336.321556 -286.170276) (xy 336.367735 -286.193801) (xy 336.409666 -286.22426) (xy 336.446315 -286.260905)
			(xy 336.47678 -286.302832) (xy 336.50031 -286.349009) (xy 336.516326 -286.398299) (xy 336.524434 -286.449487)
			(xy 336.524434 -286.501313) (xy 336.516326 -286.552501) (xy 336.50031 -286.601791) (xy 336.47678 -286.647968)
			(xy 336.446315 -286.689895) (xy 336.409666 -286.72654) (xy 336.367735 -286.756999) (xy 336.321556 -286.780524)
			(xy 336.272264 -286.796535) (xy 336.221075 -286.804637) (xy 336.195162 -286.805116) (xy 336.169668 -286.804653)
			(xy 336.11929 -286.796786) (xy 336.070727 -286.781247) (xy 336.02514 -286.758407) (xy 335.98362 -286.728811)
			(xy 335.947158 -286.693169) (xy 335.93151 -286.673036) (xy 335.519014 -286.673036) (xy 335.503397 -286.693193)
			(xy 335.466928 -286.728832) (xy 335.425401 -286.758421) (xy 335.379808 -286.781254) (xy 335.33124 -286.796785)
			(xy 335.280857 -286.804641) (xy 335.255362 -286.805116) (xy 335.229459 -286.804557) (xy 335.17829 -286.796447)
			(xy 335.12902 -286.780433) (xy 335.082862 -286.75691) (xy 335.040951 -286.726455) (xy 335.00432 -286.68982)
			(xy 334.97387 -286.647906) (xy 334.950352 -286.601745) (xy 334.934344 -286.552473) (xy 334.92624 -286.501304)
			(xy 334.644511 -286.501304) (xy 334.644476 -286.503132) (xy 334.635277 -286.557779) (xy 334.626712 -286.584136)
			(xy 334.619092 -286.60598) (xy 334.82407 -286.961072) (xy 334.84693 -286.96539) (xy 334.871744 -286.970533)
			(xy 334.919484 -286.987528) (xy 334.964063 -287.011628) (xy 335.004428 -287.042264) (xy 335.039631 -287.078717)
			(xy 335.068841 -287.120126) (xy 335.091372 -287.165518) (xy 335.106691 -287.213822) (xy 335.114439 -287.263902)
			(xy 335.1149 -287.28924) (xy 335.114392 -287.315127) (xy 335.106293 -287.366265) (xy 335.090294 -287.415505)
			(xy 335.066788 -287.461637) (xy 335.036356 -287.503524) (xy 334.999746 -287.540134) (xy 334.957859 -287.570566)
			(xy 334.911727 -287.594072) (xy 334.862487 -287.610071) (xy 334.811349 -287.61817) (xy 334.759575 -287.61817)
			(xy 334.708437 -287.610071) (xy 334.659197 -287.594072) (xy 334.613065 -287.570566) (xy 334.571178 -287.540134)
			(xy 334.534568 -287.503524) (xy 334.504136 -287.461637) (xy 334.48063 -287.415505) (xy 334.464631 -287.366265)
			(xy 334.456532 -287.315127) (xy 334.456024 -287.28924) (xy 334.456562 -287.261532) (xy 334.465751 -287.206885)
			(xy 334.474312 -287.180528) (xy 334.481932 -287.158684) (xy 334.276954 -286.803592) (xy 334.254094 -286.799274)
			(xy 334.229299 -286.794053) (xy 334.181562 -286.777067) (xy 334.136987 -286.752976) (xy 334.096622 -286.722349)
			(xy 334.061419 -286.685906) (xy 334.032206 -286.644507) (xy 334.009672 -286.599125) (xy 333.994346 -286.55083)
			(xy 333.98659 -286.500758) (xy 333.986124 -286.475424) (xy 309.6387 -286.475424) (xy 309.6387 -286.771334)
			(xy 309.638195 -286.781489) (xy 309.630417 -286.800252) (xy 309.616055 -286.814615) (xy 309.597293 -286.822395)
			(xy 309.587138 -286.822896) (xy 308.187598 -286.822896) (xy 308.177444 -286.822369) (xy 308.158682 -286.8146)
			(xy 308.144318 -286.800245) (xy 308.136537 -286.781487) (xy 308.136036 -286.771334) (xy 302.0949 -286.771334)
			(xy 302.094395 -286.781489) (xy 302.086617 -286.800252) (xy 302.072255 -286.814615) (xy 302.053493 -286.822395)
			(xy 302.043338 -286.822896) (xy 300.643798 -286.822896) (xy 300.633644 -286.822369) (xy 300.614882 -286.8146)
			(xy 300.600518 -286.800245) (xy 300.592737 -286.781487) (xy 300.592236 -286.771334) (xy 294.5511 -286.771334)
			(xy 294.550595 -286.781489) (xy 294.542817 -286.800252) (xy 294.528455 -286.814615) (xy 294.509693 -286.822395)
			(xy 294.499538 -286.822896) (xy 293.099998 -286.822896) (xy 293.089844 -286.822369) (xy 293.071082 -286.8146)
			(xy 293.056718 -286.800245) (xy 293.048937 -286.781487) (xy 293.048436 -286.771334) (xy 287.0073 -286.771334)
			(xy 287.006795 -286.781489) (xy 286.999017 -286.800252) (xy 286.984655 -286.814615) (xy 286.965893 -286.822395)
			(xy 286.955738 -286.822896) (xy 285.556198 -286.822896) (xy 285.546044 -286.822369) (xy 285.527282 -286.8146)
			(xy 285.512918 -286.800245) (xy 285.505137 -286.781487) (xy 285.504636 -286.771334) (xy 279.4635 -286.771334)
			(xy 279.462995 -286.781489) (xy 279.455217 -286.800252) (xy 279.440855 -286.814615) (xy 279.422093 -286.822395)
			(xy 279.411938 -286.822896) (xy 278.012398 -286.822896) (xy 278.002244 -286.822369) (xy 277.983482 -286.8146)
			(xy 277.969118 -286.800245) (xy 277.961337 -286.781487) (xy 277.960836 -286.771334) (xy 271.9197 -286.771334)
			(xy 271.919195 -286.781489) (xy 271.911417 -286.800252) (xy 271.897055 -286.814615) (xy 271.878293 -286.822395)
			(xy 271.868138 -286.822896) (xy 270.468598 -286.822896) (xy 270.458444 -286.822369) (xy 270.439682 -286.8146)
			(xy 270.425318 -286.800245) (xy 270.417537 -286.781487) (xy 270.417036 -286.771334) (xy 264.3759 -286.771334)
			(xy 264.375395 -286.781489) (xy 264.367617 -286.800252) (xy 264.353255 -286.814615) (xy 264.334493 -286.822395)
			(xy 264.324338 -286.822896) (xy 262.924798 -286.822896) (xy 262.914644 -286.822369) (xy 262.895882 -286.8146)
			(xy 262.881518 -286.800245) (xy 262.873737 -286.781487) (xy 262.873236 -286.771334) (xy 256.8321 -286.771334)
			(xy 256.831595 -286.781489) (xy 256.823817 -286.800252) (xy 256.809455 -286.814615) (xy 256.790693 -286.822395)
			(xy 256.780538 -286.822896) (xy 255.380998 -286.822896) (xy 255.370844 -286.822369) (xy 255.352082 -286.8146)
			(xy 255.337718 -286.800245) (xy 255.329937 -286.781487) (xy 255.329436 -286.771334) (xy 212.371432 -286.771334)
			(xy 212.370994 -286.781498) (xy 212.363203 -286.800273) (xy 212.34882 -286.814638) (xy 212.330034 -286.822406)
			(xy 212.31987 -286.822896) (xy 210.92033 -286.822896) (xy 210.910178 -286.822343) (xy 210.891416 -286.814585)
			(xy 210.877051 -286.800237) (xy 210.869269 -286.781485) (xy 210.868768 -286.771334) (xy 204.827632 -286.771334)
			(xy 204.827194 -286.781498) (xy 204.819403 -286.800273) (xy 204.80502 -286.814638) (xy 204.786234 -286.822406)
			(xy 204.77607 -286.822896) (xy 203.37653 -286.822896) (xy 203.366378 -286.822343) (xy 203.347616 -286.814585)
			(xy 203.333251 -286.800237) (xy 203.325469 -286.781485) (xy 203.324968 -286.771334) (xy 197.283832 -286.771334)
			(xy 197.283394 -286.781498) (xy 197.275603 -286.800273) (xy 197.26122 -286.814638) (xy 197.242434 -286.822406)
			(xy 197.23227 -286.822896) (xy 195.83273 -286.822896) (xy 195.822578 -286.822343) (xy 195.803816 -286.814585)
			(xy 195.789451 -286.800237) (xy 195.781669 -286.781485) (xy 195.781168 -286.771334) (xy 189.740032 -286.771334)
			(xy 189.739594 -286.781498) (xy 189.731803 -286.800273) (xy 189.71742 -286.814638) (xy 189.698634 -286.822406)
			(xy 189.68847 -286.822896) (xy 188.28893 -286.822896) (xy 188.278778 -286.822343) (xy 188.260016 -286.814585)
			(xy 188.245651 -286.800237) (xy 188.237869 -286.781485) (xy 188.237368 -286.771334) (xy 182.196232 -286.771334)
			(xy 182.195794 -286.781498) (xy 182.188003 -286.800273) (xy 182.17362 -286.814638) (xy 182.154834 -286.822406)
			(xy 182.14467 -286.822896) (xy 180.74513 -286.822896) (xy 180.734978 -286.822343) (xy 180.716216 -286.814585)
			(xy 180.701851 -286.800237) (xy 180.694069 -286.781485) (xy 180.693568 -286.771334) (xy 174.652432 -286.771334)
			(xy 174.651994 -286.781498) (xy 174.644203 -286.800273) (xy 174.62982 -286.814638) (xy 174.611034 -286.822406)
			(xy 174.60087 -286.822896) (xy 173.20133 -286.822896) (xy 173.191178 -286.822343) (xy 173.172416 -286.814585)
			(xy 173.158051 -286.800237) (xy 173.150269 -286.781485) (xy 173.149768 -286.771334) (xy 167.108632 -286.771334)
			(xy 167.108194 -286.781498) (xy 167.100403 -286.800273) (xy 167.08602 -286.814638) (xy 167.067234 -286.822406)
			(xy 167.05707 -286.822896) (xy 165.65753 -286.822896) (xy 165.647378 -286.822343) (xy 165.628616 -286.814585)
			(xy 165.614251 -286.800237) (xy 165.606469 -286.781485) (xy 165.605968 -286.771334) (xy 159.564832 -286.771334)
			(xy 159.564394 -286.781498) (xy 159.556603 -286.800273) (xy 159.54222 -286.814638) (xy 159.523434 -286.822406)
			(xy 159.51327 -286.822896) (xy 158.11373 -286.822896) (xy 158.103578 -286.822343) (xy 158.084816 -286.814585)
			(xy 158.070451 -286.800237) (xy 158.062669 -286.781485) (xy 158.062168 -286.771334) (xy 133.510081 -286.771334)
			(xy 133.492111 -286.78049) (xy 133.442832 -286.796502) (xy 133.391655 -286.804608) (xy 133.339841 -286.804608)
			(xy 133.288664 -286.796502) (xy 133.239385 -286.78049) (xy 133.193218 -286.756967) (xy 133.151299 -286.726511)
			(xy 133.114661 -286.689873) (xy 133.084205 -286.647954) (xy 133.060682 -286.601787) (xy 133.04467 -286.552508)
			(xy 133.036564 -286.501331) (xy 133.036056 -286.475424) (xy 131.81584 -286.475424) (xy 131.815332 -286.501331)
			(xy 131.807226 -286.552508) (xy 131.791214 -286.601787) (xy 131.767691 -286.647954) (xy 131.737235 -286.689873)
			(xy 131.700597 -286.726511) (xy 131.658678 -286.756967) (xy 131.612511 -286.78049) (xy 131.563232 -286.796502)
			(xy 131.512055 -286.804608) (xy 131.460241 -286.804608) (xy 131.409064 -286.796502) (xy 131.359785 -286.78049)
			(xy 131.313618 -286.756967) (xy 131.271699 -286.726511) (xy 131.235061 -286.689873) (xy 131.204605 -286.647954)
			(xy 131.181082 -286.601787) (xy 131.16507 -286.552508) (xy 131.156964 -286.501331) (xy 131.156456 -286.475424)
			(xy 129.93624 -286.475424) (xy 129.935732 -286.501331) (xy 129.927626 -286.552508) (xy 129.911614 -286.601787)
			(xy 129.888091 -286.647954) (xy 129.857635 -286.689873) (xy 129.820997 -286.726511) (xy 129.779078 -286.756967)
			(xy 129.732911 -286.78049) (xy 129.683632 -286.796502) (xy 129.632455 -286.804608) (xy 129.580641 -286.804608)
			(xy 129.529464 -286.796502) (xy 129.480185 -286.78049) (xy 129.434018 -286.756967) (xy 129.392099 -286.726511)
			(xy 129.355461 -286.689873) (xy 129.325005 -286.647954) (xy 129.301482 -286.601787) (xy 129.28547 -286.552508)
			(xy 129.277364 -286.501331) (xy 129.276856 -286.475424) (xy 128.05664 -286.475424) (xy 128.056132 -286.501331)
			(xy 128.048026 -286.552508) (xy 128.032014 -286.601787) (xy 128.008491 -286.647954) (xy 127.978035 -286.689873)
			(xy 127.941397 -286.726511) (xy 127.899478 -286.756967) (xy 127.853311 -286.78049) (xy 127.804032 -286.796502)
			(xy 127.752855 -286.804608) (xy 127.701041 -286.804608) (xy 127.649864 -286.796502) (xy 127.600585 -286.78049)
			(xy 127.554418 -286.756967) (xy 127.512499 -286.726511) (xy 127.475861 -286.689873) (xy 127.445405 -286.647954)
			(xy 127.421882 -286.601787) (xy 127.40587 -286.552508) (xy 127.397764 -286.501331) (xy 127.397256 -286.475424)
			(xy 126.17704 -286.475424) (xy 126.176532 -286.501331) (xy 126.168426 -286.552508) (xy 126.152414 -286.601787)
			(xy 126.128891 -286.647954) (xy 126.098435 -286.689873) (xy 126.061797 -286.726511) (xy 126.019878 -286.756967)
			(xy 125.973711 -286.78049) (xy 125.924432 -286.796502) (xy 125.873255 -286.804608) (xy 125.821441 -286.804608)
			(xy 125.770264 -286.796502) (xy 125.720985 -286.78049) (xy 125.674818 -286.756967) (xy 125.632899 -286.726511)
			(xy 125.596261 -286.689873) (xy 125.565805 -286.647954) (xy 125.542282 -286.601787) (xy 125.52627 -286.552508)
			(xy 125.518164 -286.501331) (xy 125.517656 -286.475424) (xy 124.29744 -286.475424) (xy 124.296932 -286.501331)
			(xy 124.288826 -286.552508) (xy 124.272814 -286.601787) (xy 124.249291 -286.647954) (xy 124.218835 -286.689873)
			(xy 124.182197 -286.726511) (xy 124.140278 -286.756967) (xy 124.094111 -286.78049) (xy 124.044832 -286.796502)
			(xy 123.993655 -286.804608) (xy 123.941841 -286.804608) (xy 123.890664 -286.796502) (xy 123.841385 -286.78049)
			(xy 123.795218 -286.756967) (xy 123.753299 -286.726511) (xy 123.716661 -286.689873) (xy 123.686205 -286.647954)
			(xy 123.662682 -286.601787) (xy 123.64667 -286.552508) (xy 123.638564 -286.501331) (xy 123.638056 -286.475424)
			(xy 122.41784 -286.475424) (xy 122.417332 -286.501331) (xy 122.409226 -286.552508) (xy 122.393214 -286.601787)
			(xy 122.369691 -286.647954) (xy 122.339235 -286.689873) (xy 122.302597 -286.726511) (xy 122.260678 -286.756967)
			(xy 122.214511 -286.78049) (xy 122.165232 -286.796502) (xy 122.114055 -286.804608) (xy 122.062241 -286.804608)
			(xy 122.011064 -286.796502) (xy 121.961785 -286.78049) (xy 121.915618 -286.756967) (xy 121.873699 -286.726511)
			(xy 121.837061 -286.689873) (xy 121.806605 -286.647954) (xy 121.783082 -286.601787) (xy 121.76707 -286.552508)
			(xy 121.758964 -286.501331) (xy 121.758456 -286.475424) (xy 120.53824 -286.475424) (xy 120.537732 -286.501331)
			(xy 120.529626 -286.552508) (xy 120.513614 -286.601787) (xy 120.490091 -286.647954) (xy 120.459635 -286.689873)
			(xy 120.422997 -286.726511) (xy 120.381078 -286.756967) (xy 120.334911 -286.78049) (xy 120.285632 -286.796502)
			(xy 120.234455 -286.804608) (xy 120.182641 -286.804608) (xy 120.131464 -286.796502) (xy 120.082185 -286.78049)
			(xy 120.036018 -286.756967) (xy 119.994099 -286.726511) (xy 119.957461 -286.689873) (xy 119.927005 -286.647954)
			(xy 119.903482 -286.601787) (xy 119.88747 -286.552508) (xy 119.879364 -286.501331) (xy 119.878856 -286.475424)
			(xy 103.62184 -286.475424) (xy 103.621332 -286.501331) (xy 103.613226 -286.552508) (xy 103.597214 -286.601787)
			(xy 103.573691 -286.647954) (xy 103.543235 -286.689873) (xy 103.506597 -286.726511) (xy 103.464678 -286.756967)
			(xy 103.418511 -286.78049) (xy 103.369232 -286.796502) (xy 103.318055 -286.804608) (xy 103.266241 -286.804608)
			(xy 103.215064 -286.796502) (xy 103.165785 -286.78049) (xy 103.119618 -286.756967) (xy 103.077699 -286.726511)
			(xy 103.041061 -286.689873) (xy 103.010605 -286.647954) (xy 102.987082 -286.601787) (xy 102.97107 -286.552508)
			(xy 102.962964 -286.501331) (xy 102.962456 -286.475424) (xy 102.963053 -286.447707) (xy 102.972374 -286.39306)
			(xy 102.980998 -286.366712) (xy 102.988872 -286.344614) (xy 102.783894 -285.989522) (xy 102.76078 -285.985204)
			(xy 102.735964 -285.980016) (xy 102.688184 -285.963065) (xy 102.643565 -285.938998) (xy 102.603157 -285.908381)
			(xy 102.567916 -285.871936) (xy 102.538671 -285.830525) (xy 102.516113 -285.785123) (xy 102.500775 -285.736802)
			(xy 102.493018 -285.686702) (xy 102.492556 -285.661354) (xy 102.211632 -285.661354) (xy 102.211124 -285.687241)
			(xy 102.203025 -285.738379) (xy 102.187026 -285.787619) (xy 102.16352 -285.833751) (xy 102.133088 -285.875638)
			(xy 102.096478 -285.912248) (xy 102.054591 -285.94268) (xy 102.008459 -285.966186) (xy 101.959219 -285.982185)
			(xy 101.908081 -285.990284) (xy 101.856307 -285.990284) (xy 101.805169 -285.982185) (xy 101.755929 -285.966186)
			(xy 101.709797 -285.94268) (xy 101.66791 -285.912248) (xy 101.6313 -285.875638) (xy 101.600868 -285.833751)
			(xy 101.577362 -285.787619) (xy 101.561363 -285.738379) (xy 101.553264 -285.687241) (xy 101.552756 -285.661354)
			(xy 101.271832 -285.661354) (xy 101.271832 -285.661862) (xy 101.271253 -285.689379) (xy 101.262059 -285.74364)
			(xy 101.253544 -285.769812) (xy 101.245924 -285.79191) (xy 101.451156 -286.147256) (xy 101.474016 -286.151574)
			(xy 101.498827 -286.156786) (xy 101.546604 -286.173734) (xy 101.591223 -286.197799) (xy 101.63163 -286.228413)
			(xy 101.666872 -286.264855) (xy 101.696117 -286.306263) (xy 101.718676 -286.351662) (xy 101.734017 -286.399979)
			(xy 101.741777 -286.450077) (xy 101.74224 -286.475424) (xy 101.741732 -286.501331) (xy 101.733626 -286.552508)
			(xy 101.717614 -286.601787) (xy 101.694091 -286.647954) (xy 101.663635 -286.689873) (xy 101.626997 -286.726511)
			(xy 101.585078 -286.756967) (xy 101.538911 -286.78049) (xy 101.489632 -286.796502) (xy 101.438455 -286.804608)
			(xy 101.386641 -286.804608) (xy 101.335464 -286.796502) (xy 101.286185 -286.78049) (xy 101.240018 -286.756967)
			(xy 101.198099 -286.726511) (xy 101.161461 -286.689873) (xy 101.131005 -286.647954) (xy 101.107482 -286.601787)
			(xy 101.09147 -286.552508) (xy 101.083364 -286.501331) (xy 101.082856 -286.475424) (xy 101.083453 -286.447707)
			(xy 101.092774 -286.39306) (xy 101.101398 -286.366712) (xy 101.109272 -286.344614) (xy 100.904294 -285.989522)
			(xy 100.88118 -285.985204) (xy 100.856364 -285.980016) (xy 100.808584 -285.963065) (xy 100.763965 -285.938998)
			(xy 100.723557 -285.908381) (xy 100.688316 -285.871936) (xy 100.659071 -285.830525) (xy 100.636513 -285.785123)
			(xy 100.621175 -285.736802) (xy 100.613418 -285.686702) (xy 100.612956 -285.661354) (xy 100.332032 -285.661354)
			(xy 100.331524 -285.687241) (xy 100.323425 -285.738379) (xy 100.307426 -285.787619) (xy 100.28392 -285.833751)
			(xy 100.253488 -285.875638) (xy 100.216878 -285.912248) (xy 100.174991 -285.94268) (xy 100.128859 -285.966186)
			(xy 100.079619 -285.982185) (xy 100.028481 -285.990284) (xy 99.976707 -285.990284) (xy 99.925569 -285.982185)
			(xy 99.876329 -285.966186) (xy 99.830197 -285.94268) (xy 99.78831 -285.912248) (xy 99.7517 -285.875638)
			(xy 99.721268 -285.833751) (xy 99.697762 -285.787619) (xy 99.681763 -285.738379) (xy 99.673664 -285.687241)
			(xy 99.673156 -285.661354) (xy 99.392232 -285.661354) (xy 99.392232 -285.661862) (xy 99.391653 -285.689379)
			(xy 99.382459 -285.74364) (xy 99.373944 -285.769812) (xy 99.366324 -285.79191) (xy 99.571556 -286.147256)
			(xy 99.594416 -286.151574) (xy 99.619227 -286.156786) (xy 99.667004 -286.173734) (xy 99.711623 -286.197799)
			(xy 99.75203 -286.228413) (xy 99.787272 -286.264855) (xy 99.816517 -286.306263) (xy 99.839076 -286.351662)
			(xy 99.854417 -286.399979) (xy 99.862177 -286.450077) (xy 99.86264 -286.475424) (xy 99.862132 -286.501331)
			(xy 99.854026 -286.552508) (xy 99.838014 -286.601787) (xy 99.814491 -286.647954) (xy 99.784035 -286.689873)
			(xy 99.747397 -286.726511) (xy 99.705478 -286.756967) (xy 99.659311 -286.78049) (xy 99.610032 -286.796502)
			(xy 99.558855 -286.804608) (xy 99.507041 -286.804608) (xy 99.455864 -286.796502) (xy 99.406585 -286.78049)
			(xy 99.360418 -286.756967) (xy 99.318499 -286.726511) (xy 99.281861 -286.689873) (xy 99.251405 -286.647954)
			(xy 99.227882 -286.601787) (xy 99.21187 -286.552508) (xy 99.203764 -286.501331) (xy 99.203256 -286.475424)
			(xy 99.203853 -286.447707) (xy 99.213174 -286.39306) (xy 99.221798 -286.366712) (xy 99.229672 -286.344614)
			(xy 99.024694 -285.989522) (xy 99.00158 -285.985204) (xy 98.976764 -285.980016) (xy 98.928984 -285.963065)
			(xy 98.884365 -285.938998) (xy 98.843957 -285.908381) (xy 98.808716 -285.871936) (xy 98.779471 -285.830525)
			(xy 98.756913 -285.785123) (xy 98.741575 -285.736802) (xy 98.733818 -285.686702) (xy 98.733356 -285.661354)
			(xy 98.452432 -285.661354) (xy 98.451924 -285.687241) (xy 98.443825 -285.738379) (xy 98.427826 -285.787619)
			(xy 98.40432 -285.833751) (xy 98.373888 -285.875638) (xy 98.337278 -285.912248) (xy 98.295391 -285.94268)
			(xy 98.249259 -285.966186) (xy 98.200019 -285.982185) (xy 98.148881 -285.990284) (xy 98.097107 -285.990284)
			(xy 98.045969 -285.982185) (xy 97.996729 -285.966186) (xy 97.950597 -285.94268) (xy 97.90871 -285.912248)
			(xy 97.8721 -285.875638) (xy 97.841668 -285.833751) (xy 97.818162 -285.787619) (xy 97.802163 -285.738379)
			(xy 97.794064 -285.687241) (xy 97.793556 -285.661354) (xy 97.512632 -285.661354) (xy 97.512632 -285.661862)
			(xy 97.512053 -285.689379) (xy 97.502859 -285.74364) (xy 97.494344 -285.769812) (xy 97.486724 -285.79191)
			(xy 97.691956 -286.147256) (xy 97.714816 -286.151574) (xy 97.739627 -286.156786) (xy 97.787404 -286.173734)
			(xy 97.832023 -286.197799) (xy 97.87243 -286.228413) (xy 97.907672 -286.264855) (xy 97.936917 -286.306263)
			(xy 97.959476 -286.351662) (xy 97.974817 -286.399979) (xy 97.982577 -286.450077) (xy 97.98304 -286.475424)
			(xy 97.982532 -286.501331) (xy 97.974426 -286.552508) (xy 97.958414 -286.601787) (xy 97.934891 -286.647954)
			(xy 97.904435 -286.689873) (xy 97.867797 -286.726511) (xy 97.825878 -286.756967) (xy 97.779711 -286.78049)
			(xy 97.730432 -286.796502) (xy 97.679255 -286.804608) (xy 97.627441 -286.804608) (xy 97.576264 -286.796502)
			(xy 97.526985 -286.78049) (xy 97.480818 -286.756967) (xy 97.438899 -286.726511) (xy 97.402261 -286.689873)
			(xy 97.371805 -286.647954) (xy 97.348282 -286.601787) (xy 97.33227 -286.552508) (xy 97.324164 -286.501331)
			(xy 97.323656 -286.475424) (xy 97.324253 -286.447707) (xy 97.333574 -286.39306) (xy 97.342198 -286.366712)
			(xy 97.350072 -286.344614) (xy 97.145094 -285.989522) (xy 97.12198 -285.985204) (xy 97.097164 -285.980016)
			(xy 97.049384 -285.963065) (xy 97.004765 -285.938998) (xy 96.964357 -285.908381) (xy 96.929116 -285.871936)
			(xy 96.899871 -285.830525) (xy 96.877313 -285.785123) (xy 96.861975 -285.736802) (xy 96.854218 -285.686702)
			(xy 96.853756 -285.661354) (xy 96.572832 -285.661354) (xy 96.572324 -285.687241) (xy 96.564225 -285.738379)
			(xy 96.548226 -285.787619) (xy 96.52472 -285.833751) (xy 96.494288 -285.875638) (xy 96.457678 -285.912248)
			(xy 96.415791 -285.94268) (xy 96.369659 -285.966186) (xy 96.320419 -285.982185) (xy 96.269281 -285.990284)
			(xy 96.217507 -285.990284) (xy 96.166369 -285.982185) (xy 96.117129 -285.966186) (xy 96.070997 -285.94268)
			(xy 96.02911 -285.912248) (xy 95.9925 -285.875638) (xy 95.962068 -285.833751) (xy 95.938562 -285.787619)
			(xy 95.922563 -285.738379) (xy 95.914464 -285.687241) (xy 95.913956 -285.661354) (xy 95.633032 -285.661354)
			(xy 95.633032 -285.661862) (xy 95.632453 -285.689379) (xy 95.623259 -285.74364) (xy 95.614744 -285.769812)
			(xy 95.607124 -285.79191) (xy 95.812356 -286.147256) (xy 95.835216 -286.151574) (xy 95.860027 -286.156786)
			(xy 95.907804 -286.173734) (xy 95.952423 -286.197799) (xy 95.99283 -286.228413) (xy 96.028072 -286.264855)
			(xy 96.057317 -286.306263) (xy 96.079876 -286.351662) (xy 96.095217 -286.399979) (xy 96.102977 -286.450077)
			(xy 96.10344 -286.475424) (xy 96.102932 -286.501331) (xy 96.094826 -286.552508) (xy 96.078814 -286.601787)
			(xy 96.055291 -286.647954) (xy 96.024835 -286.689873) (xy 95.988197 -286.726511) (xy 95.946278 -286.756967)
			(xy 95.900111 -286.78049) (xy 95.850832 -286.796502) (xy 95.799655 -286.804608) (xy 95.747841 -286.804608)
			(xy 95.696664 -286.796502) (xy 95.647385 -286.78049) (xy 95.601218 -286.756967) (xy 95.559299 -286.726511)
			(xy 95.522661 -286.689873) (xy 95.492205 -286.647954) (xy 95.468682 -286.601787) (xy 95.45267 -286.552508)
			(xy 95.444564 -286.501331) (xy 95.444056 -286.475424) (xy 95.444653 -286.447707) (xy 95.453974 -286.39306)
			(xy 95.462598 -286.366712) (xy 95.470472 -286.344614) (xy 95.265494 -285.989522) (xy 95.24238 -285.985204)
			(xy 95.217564 -285.980016) (xy 95.169784 -285.963065) (xy 95.125165 -285.938998) (xy 95.084757 -285.908381)
			(xy 95.049516 -285.871936) (xy 95.020271 -285.830525) (xy 94.997713 -285.785123) (xy 94.982375 -285.736802)
			(xy 94.974618 -285.686702) (xy 94.974156 -285.661354) (xy 94.693232 -285.661354) (xy 94.692724 -285.687241)
			(xy 94.684625 -285.738379) (xy 94.668626 -285.787619) (xy 94.64512 -285.833751) (xy 94.614688 -285.875638)
			(xy 94.578078 -285.912248) (xy 94.536191 -285.94268) (xy 94.490059 -285.966186) (xy 94.440819 -285.982185)
			(xy 94.389681 -285.990284) (xy 94.337907 -285.990284) (xy 94.286769 -285.982185) (xy 94.237529 -285.966186)
			(xy 94.191397 -285.94268) (xy 94.14951 -285.912248) (xy 94.1129 -285.875638) (xy 94.082468 -285.833751)
			(xy 94.058962 -285.787619) (xy 94.042963 -285.738379) (xy 94.034864 -285.687241) (xy 94.034356 -285.661354)
			(xy 93.753432 -285.661354) (xy 93.753432 -285.661862) (xy 93.752853 -285.689379) (xy 93.743659 -285.74364)
			(xy 93.735144 -285.769812) (xy 93.727524 -285.79191) (xy 93.932756 -286.147256) (xy 93.955616 -286.151574)
			(xy 93.980427 -286.156786) (xy 94.028204 -286.173734) (xy 94.072823 -286.197799) (xy 94.11323 -286.228413)
			(xy 94.148472 -286.264855) (xy 94.177717 -286.306263) (xy 94.200276 -286.351662) (xy 94.215617 -286.399979)
			(xy 94.223377 -286.450077) (xy 94.22384 -286.475424) (xy 94.223332 -286.501331) (xy 94.215226 -286.552508)
			(xy 94.199214 -286.601787) (xy 94.175691 -286.647954) (xy 94.145235 -286.689873) (xy 94.108597 -286.726511)
			(xy 94.066678 -286.756967) (xy 94.020511 -286.78049) (xy 93.971232 -286.796502) (xy 93.920055 -286.804608)
			(xy 93.868241 -286.804608) (xy 93.817064 -286.796502) (xy 93.767785 -286.78049) (xy 93.721618 -286.756967)
			(xy 93.679699 -286.726511) (xy 93.643061 -286.689873) (xy 93.612605 -286.647954) (xy 93.589082 -286.601787)
			(xy 93.57307 -286.552508) (xy 93.564964 -286.501331) (xy 93.564456 -286.475424) (xy 93.565053 -286.447707)
			(xy 93.574374 -286.39306) (xy 93.582998 -286.366712) (xy 93.590872 -286.344614) (xy 93.385894 -285.989522)
			(xy 93.36278 -285.985204) (xy 93.337964 -285.980016) (xy 93.290184 -285.963065) (xy 93.245565 -285.938998)
			(xy 93.205157 -285.908381) (xy 93.169916 -285.871936) (xy 93.140671 -285.830525) (xy 93.118113 -285.785123)
			(xy 93.102775 -285.736802) (xy 93.095018 -285.686702) (xy 93.094556 -285.661354) (xy 92.813632 -285.661354)
			(xy 92.813124 -285.687241) (xy 92.805025 -285.738379) (xy 92.789026 -285.787619) (xy 92.76552 -285.833751)
			(xy 92.735088 -285.875638) (xy 92.698478 -285.912248) (xy 92.656591 -285.94268) (xy 92.610459 -285.966186)
			(xy 92.561219 -285.982185) (xy 92.510081 -285.990284) (xy 92.458307 -285.990284) (xy 92.407169 -285.982185)
			(xy 92.357929 -285.966186) (xy 92.311797 -285.94268) (xy 92.26991 -285.912248) (xy 92.2333 -285.875638)
			(xy 92.202868 -285.833751) (xy 92.179362 -285.787619) (xy 92.163363 -285.738379) (xy 92.155264 -285.687241)
			(xy 92.154756 -285.661354) (xy 91.87434 -285.661354) (xy 91.873738 -285.689071) (xy 91.86442 -285.743718)
			(xy 91.855798 -285.770066) (xy 91.847924 -285.792164) (xy 92.053156 -286.147256) (xy 92.076016 -286.151574)
			(xy 92.100827 -286.156786) (xy 92.148604 -286.173734) (xy 92.193223 -286.197799) (xy 92.23363 -286.228413)
			(xy 92.268872 -286.264855) (xy 92.298117 -286.306263) (xy 92.320676 -286.351662) (xy 92.336017 -286.399979)
			(xy 92.343777 -286.450077) (xy 92.34424 -286.475424) (xy 92.343732 -286.501331) (xy 92.335626 -286.552508)
			(xy 92.319614 -286.601787) (xy 92.296091 -286.647954) (xy 92.265635 -286.689873) (xy 92.228997 -286.726511)
			(xy 92.187078 -286.756967) (xy 92.140911 -286.78049) (xy 92.091632 -286.796502) (xy 92.040455 -286.804608)
			(xy 91.988641 -286.804608) (xy 91.937464 -286.796502) (xy 91.888185 -286.78049) (xy 91.842018 -286.756967)
			(xy 91.800099 -286.726511) (xy 91.763461 -286.689873) (xy 91.733005 -286.647954) (xy 91.709482 -286.601787)
			(xy 91.69347 -286.552508) (xy 91.685364 -286.501331) (xy 91.684856 -286.475424) (xy 91.685453 -286.447707)
			(xy 91.694774 -286.39306) (xy 91.703398 -286.366712) (xy 91.711272 -286.344614) (xy 91.50604 -285.989522)
			(xy 91.48318 -285.985204) (xy 91.458364 -285.980016) (xy 91.410584 -285.963065) (xy 91.365965 -285.938998)
			(xy 91.325557 -285.908381) (xy 91.290316 -285.871936) (xy 91.261071 -285.830525) (xy 91.238513 -285.785123)
			(xy 91.223175 -285.736802) (xy 91.215418 -285.686702) (xy 91.214956 -285.661354) (xy 90.93454 -285.661354)
			(xy 90.934032 -285.687261) (xy 90.925926 -285.738438) (xy 90.909914 -285.787717) (xy 90.886391 -285.833884)
			(xy 90.855935 -285.875803) (xy 90.819297 -285.912441) (xy 90.777378 -285.942897) (xy 90.731211 -285.96642)
			(xy 90.681932 -285.982432) (xy 90.630755 -285.990538) (xy 90.578941 -285.990538) (xy 90.527764 -285.982432)
			(xy 90.478485 -285.96642) (xy 90.432318 -285.942897) (xy 90.390399 -285.912441) (xy 90.353761 -285.875803)
			(xy 90.323305 -285.833884) (xy 90.299782 -285.787717) (xy 90.28377 -285.738438) (xy 90.275664 -285.687261)
			(xy 90.275156 -285.661354) (xy 89.994232 -285.661354) (xy 89.993689 -285.689062) (xy 89.984503 -285.743708)
			(xy 89.975944 -285.770066) (xy 89.96807 -285.792164) (xy 90.173302 -286.147256) (xy 90.196162 -286.151574)
			(xy 90.220961 -286.156781) (xy 90.268701 -286.173765) (xy 90.31328 -286.197855) (xy 90.353647 -286.228483)
			(xy 90.388851 -286.264927) (xy 90.418064 -286.30633) (xy 90.440597 -286.351715) (xy 90.455919 -286.400014)
			(xy 90.46367 -286.450088) (xy 90.464132 -286.475424) (xy 90.463624 -286.501311) (xy 90.455525 -286.552449)
			(xy 90.439526 -286.601689) (xy 90.41602 -286.647821) (xy 90.385588 -286.689708) (xy 90.348978 -286.726318)
			(xy 90.307091 -286.75675) (xy 90.260959 -286.780256) (xy 90.211719 -286.796255) (xy 90.160581 -286.804354)
			(xy 90.108807 -286.804354) (xy 90.057669 -286.796255) (xy 90.008429 -286.780256) (xy 89.962297 -286.75675)
			(xy 89.92041 -286.726318) (xy 89.8838 -286.689708) (xy 89.853368 -286.647821) (xy 89.829862 -286.601689)
			(xy 89.813863 -286.552449) (xy 89.805764 -286.501311) (xy 89.805256 -286.475424) (xy 89.805793 -286.447716)
			(xy 89.814983 -286.393069) (xy 89.823544 -286.366712) (xy 89.831418 -286.344614) (xy 89.626186 -285.989522)
			(xy 89.603326 -285.985204) (xy 89.57852 -285.980026) (xy 89.530779 -285.963039) (xy 89.486199 -285.938946)
			(xy 89.445832 -285.908314) (xy 89.410627 -285.871866) (xy 89.381416 -285.83046) (xy 89.358884 -285.785071)
			(xy 89.343564 -285.736769) (xy 89.335817 -285.686691) (xy 89.335356 -285.661354) (xy 88.114632 -285.661354)
			(xy 88.114124 -285.687241) (xy 88.106025 -285.738379) (xy 88.090026 -285.787619) (xy 88.06652 -285.833751)
			(xy 88.036088 -285.875638) (xy 87.999478 -285.912248) (xy 87.957591 -285.94268) (xy 87.911459 -285.966186)
			(xy 87.862219 -285.982185) (xy 87.811081 -285.990284) (xy 87.759307 -285.990284) (xy 87.708169 -285.982185)
			(xy 87.658929 -285.966186) (xy 87.612797 -285.94268) (xy 87.57091 -285.912248) (xy 87.5343 -285.875638)
			(xy 87.503868 -285.833751) (xy 87.480362 -285.787619) (xy 87.464363 -285.738379) (xy 87.456264 -285.687241)
			(xy 87.455756 -285.661354) (xy 65.7987 -285.661354) (xy 65.7987 -285.92145) (xy 65.798196 -285.931614)
			(xy 65.790435 -285.9504) (xy 65.776074 -285.964785) (xy 65.757301 -285.972579) (xy 65.747138 -285.973012)
			(xy 64.347598 -285.973012) (xy 64.33742 -285.972637) (xy 64.318616 -285.964842) (xy 64.304229 -285.950441)
			(xy 64.296453 -285.931628) (xy 64.296036 -285.92145) (xy 58.2549 -285.92145) (xy 58.254396 -285.931614)
			(xy 58.246635 -285.9504) (xy 58.232274 -285.964785) (xy 58.213501 -285.972579) (xy 58.203338 -285.973012)
			(xy 56.803798 -285.973012) (xy 56.79362 -285.972637) (xy 56.774816 -285.964842) (xy 56.760429 -285.950441)
			(xy 56.752653 -285.931628) (xy 56.752236 -285.92145) (xy 50.7111 -285.92145) (xy 50.710596 -285.931614)
			(xy 50.702835 -285.9504) (xy 50.688474 -285.964785) (xy 50.669701 -285.972579) (xy 50.659538 -285.973012)
			(xy 49.259998 -285.973012) (xy 49.24982 -285.972637) (xy 49.231016 -285.964842) (xy 49.216629 -285.950441)
			(xy 49.208853 -285.931628) (xy 49.208436 -285.92145) (xy 43.1673 -285.92145) (xy 43.166796 -285.931614)
			(xy 43.159035 -285.9504) (xy 43.144674 -285.964785) (xy 43.125901 -285.972579) (xy 43.115738 -285.973012)
			(xy 41.716198 -285.973012) (xy 41.70602 -285.972637) (xy 41.687216 -285.964842) (xy 41.672829 -285.950441)
			(xy 41.665053 -285.931628) (xy 41.664636 -285.92145) (xy 35.6235 -285.92145) (xy 35.622996 -285.931614)
			(xy 35.615235 -285.9504) (xy 35.600874 -285.964785) (xy 35.582101 -285.972579) (xy 35.571938 -285.973012)
			(xy 34.172398 -285.973012) (xy 34.16222 -285.972637) (xy 34.143416 -285.964842) (xy 34.129029 -285.950441)
			(xy 34.121253 -285.931628) (xy 34.120836 -285.92145) (xy 28.0797 -285.92145) (xy 28.079196 -285.931614)
			(xy 28.071435 -285.9504) (xy 28.057074 -285.964785) (xy 28.038301 -285.972579) (xy 28.028138 -285.973012)
			(xy 26.628598 -285.973012) (xy 26.61842 -285.972637) (xy 26.599616 -285.964842) (xy 26.585229 -285.950441)
			(xy 26.577453 -285.931628) (xy 26.577036 -285.92145) (xy 20.5359 -285.92145) (xy 20.535396 -285.931614)
			(xy 20.527635 -285.9504) (xy 20.513274 -285.964785) (xy 20.494501 -285.972579) (xy 20.484338 -285.973012)
			(xy 19.084798 -285.973012) (xy 19.07462 -285.972637) (xy 19.055816 -285.964842) (xy 19.041429 -285.950441)
			(xy 19.033653 -285.931628) (xy 19.033236 -285.92145) (xy 12.9921 -285.92145) (xy 12.991596 -285.931614)
			(xy 12.983835 -285.9504) (xy 12.969474 -285.964785) (xy 12.950701 -285.972579) (xy 12.940538 -285.973012)
			(xy 11.540998 -285.973012) (xy 11.53082 -285.972637) (xy 11.512016 -285.964842) (xy 11.497629 -285.950441)
			(xy 11.489853 -285.931628) (xy 11.489436 -285.92145) (xy 2.509012 -285.92145) (xy 2.509012 -286.771334)
			(xy 7.389368 -286.771334) (xy 7.389368 -286.362394) (xy 7.38976 -286.352218) (xy 7.397552 -286.333418)
			(xy 7.411948 -286.319032) (xy 7.430754 -286.311253) (xy 7.44093 -286.310832) (xy 8.84047 -286.310832)
			(xy 8.850639 -286.311288) (xy 8.869432 -286.319062) (xy 8.883817 -286.333438) (xy 8.891604 -286.352225)
			(xy 8.892032 -286.362394) (xy 8.892032 -286.771334) (xy 14.933168 -286.771334) (xy 14.933168 -286.362394)
			(xy 14.93356 -286.352218) (xy 14.941352 -286.333418) (xy 14.955748 -286.319032) (xy 14.974554 -286.311253)
			(xy 14.98473 -286.310832) (xy 16.38427 -286.310832) (xy 16.394439 -286.311288) (xy 16.413232 -286.319062)
			(xy 16.427617 -286.333438) (xy 16.435404 -286.352225) (xy 16.435832 -286.362394) (xy 16.435832 -286.771334)
			(xy 22.476968 -286.771334) (xy 22.476968 -286.362394) (xy 22.47736 -286.352218) (xy 22.485152 -286.333418)
			(xy 22.499548 -286.319032) (xy 22.518354 -286.311253) (xy 22.52853 -286.310832) (xy 23.92807 -286.310832)
			(xy 23.938239 -286.311288) (xy 23.957032 -286.319062) (xy 23.971417 -286.333438) (xy 23.979204 -286.352225)
			(xy 23.979632 -286.362394) (xy 23.979632 -286.771334) (xy 30.020768 -286.771334) (xy 30.020768 -286.362394)
			(xy 30.02116 -286.352218) (xy 30.028952 -286.333418) (xy 30.043348 -286.319032) (xy 30.062154 -286.311253)
			(xy 30.07233 -286.310832) (xy 31.47187 -286.310832) (xy 31.482039 -286.311288) (xy 31.500832 -286.319062)
			(xy 31.515217 -286.333438) (xy 31.523004 -286.352225) (xy 31.523432 -286.362394) (xy 31.523432 -286.771334)
			(xy 37.564568 -286.771334) (xy 37.564568 -286.362394) (xy 37.56496 -286.352218) (xy 37.572752 -286.333418)
			(xy 37.587148 -286.319032) (xy 37.605954 -286.311253) (xy 37.61613 -286.310832) (xy 39.01567 -286.310832)
			(xy 39.025839 -286.311288) (xy 39.044632 -286.319062) (xy 39.059017 -286.333438) (xy 39.066804 -286.352225)
			(xy 39.067232 -286.362394) (xy 39.067232 -286.771334) (xy 45.108368 -286.771334) (xy 45.108368 -286.362394)
			(xy 45.10876 -286.352218) (xy 45.116552 -286.333418) (xy 45.130948 -286.319032) (xy 45.149754 -286.311253)
			(xy 45.15993 -286.310832) (xy 46.55947 -286.310832) (xy 46.569639 -286.311288) (xy 46.588432 -286.319062)
			(xy 46.602817 -286.333438) (xy 46.610604 -286.352225) (xy 46.611032 -286.362394) (xy 46.611032 -286.771334)
			(xy 52.652168 -286.771334) (xy 52.652168 -286.362394) (xy 52.65256 -286.352218) (xy 52.660352 -286.333418)
			(xy 52.674748 -286.319032) (xy 52.693554 -286.311253) (xy 52.70373 -286.310832) (xy 54.10327 -286.310832)
			(xy 54.113439 -286.311288) (xy 54.132232 -286.319062) (xy 54.146617 -286.333438) (xy 54.154404 -286.352225)
			(xy 54.154832 -286.362394) (xy 54.154832 -286.771334) (xy 60.195968 -286.771334) (xy 60.195968 -286.362394)
			(xy 60.19636 -286.352218) (xy 60.204152 -286.333418) (xy 60.218548 -286.319032) (xy 60.237354 -286.311253)
			(xy 60.24753 -286.310832) (xy 61.64707 -286.310832) (xy 61.657239 -286.311288) (xy 61.676032 -286.319062)
			(xy 61.690417 -286.333438) (xy 61.698204 -286.352225) (xy 61.698632 -286.362394) (xy 61.698632 -286.475424)
			(xy 86.046056 -286.475424) (xy 86.046564 -286.449537) (xy 86.054663 -286.398399) (xy 86.070662 -286.349159)
			(xy 86.094168 -286.303027) (xy 86.1246 -286.26114) (xy 86.16121 -286.22453) (xy 86.203097 -286.194098)
			(xy 86.249229 -286.170592) (xy 86.298469 -286.154593) (xy 86.349607 -286.146494) (xy 86.401381 -286.146494)
			(xy 86.452519 -286.154593) (xy 86.501759 -286.170592) (xy 86.547891 -286.194098) (xy 86.589778 -286.22453)
			(xy 86.626388 -286.26114) (xy 86.65682 -286.303027) (xy 86.680326 -286.349159) (xy 86.696325 -286.398399)
			(xy 86.704424 -286.449537) (xy 86.704932 -286.475424) (xy 86.704442 -286.501305) (xy 86.98614 -286.501305)
			(xy 86.98614 -286.449495) (xy 86.994245 -286.398322) (xy 87.010255 -286.349048) (xy 87.033776 -286.302885)
			(xy 87.064229 -286.260969) (xy 87.100864 -286.224333) (xy 87.142779 -286.193879) (xy 87.188942 -286.170357)
			(xy 87.238217 -286.154347) (xy 87.289389 -286.146241) (xy 87.315294 -286.145732) (xy 87.340788 -286.146208)
			(xy 87.391166 -286.154069) (xy 87.43973 -286.169604) (xy 87.485317 -286.192442) (xy 87.526838 -286.222037)
			(xy 87.563299 -286.257679) (xy 87.578946 -286.277812) (xy 87.991442 -286.277812) (xy 88.007098 -286.257686)
			(xy 88.043557 -286.222043) (xy 88.085076 -286.192449) (xy 88.130661 -286.16961) (xy 88.179224 -286.154073)
			(xy 88.229601 -286.146211) (xy 88.255094 -286.145732) (xy 88.281006 -286.146165) (xy 88.332191 -286.154271)
			(xy 88.381478 -286.170285) (xy 88.427653 -286.193811) (xy 88.469579 -286.224272) (xy 88.506224 -286.260916)
			(xy 88.536685 -286.302842) (xy 88.560213 -286.349016) (xy 88.576227 -286.398303) (xy 88.584334 -286.449488)
			(xy 88.584334 -286.501312) (xy 88.576227 -286.552497) (xy 88.560213 -286.601784) (xy 88.536685 -286.647958)
			(xy 88.506224 -286.689884) (xy 88.469579 -286.726528) (xy 88.427653 -286.756989) (xy 88.381478 -286.780515)
			(xy 88.332191 -286.796529) (xy 88.281006 -286.804635) (xy 88.255094 -286.805116) (xy 88.229601 -286.80463)
			(xy 88.179224 -286.796768) (xy 88.130661 -286.781233) (xy 88.085074 -286.758397) (xy 88.043553 -286.728806)
			(xy 88.007091 -286.693167) (xy 87.991442 -286.673036) (xy 87.578946 -286.673036) (xy 87.56331 -286.693178)
			(xy 87.526845 -286.728817) (xy 87.485322 -286.758409) (xy 87.439733 -286.781244) (xy 87.391168 -286.796778)
			(xy 87.340788 -286.804638) (xy 87.315294 -286.805116) (xy 87.289389 -286.804559) (xy 87.238217 -286.796453)
			(xy 87.188942 -286.780443) (xy 87.142779 -286.756921) (xy 87.100864 -286.726467) (xy 87.064229 -286.689831)
			(xy 87.033776 -286.647915) (xy 87.010255 -286.601752) (xy 86.994245 -286.552478) (xy 86.98614 -286.501305)
			(xy 86.704442 -286.501305) (xy 86.704407 -286.503132) (xy 86.695209 -286.557779) (xy 86.686644 -286.584136)
			(xy 86.679024 -286.60598) (xy 86.884002 -286.961072) (xy 86.906862 -286.96539) (xy 86.931665 -286.970582)
			(xy 86.979406 -286.987567) (xy 87.023985 -287.011659) (xy 87.064353 -287.042288) (xy 87.099557 -287.078734)
			(xy 87.12877 -287.120139) (xy 87.151302 -287.165526) (xy 87.166622 -287.213827) (xy 87.174371 -287.263904)
			(xy 87.174832 -287.28924) (xy 87.174324 -287.315127) (xy 87.166225 -287.366265) (xy 87.150226 -287.415505)
			(xy 87.12672 -287.461637) (xy 87.096288 -287.503524) (xy 87.059678 -287.540134) (xy 87.017791 -287.570566)
			(xy 86.971659 -287.594072) (xy 86.922419 -287.610071) (xy 86.871281 -287.61817) (xy 86.819507 -287.61817)
			(xy 86.768369 -287.610071) (xy 86.719129 -287.594072) (xy 86.672997 -287.570566) (xy 86.63111 -287.540134)
			(xy 86.5945 -287.503524) (xy 86.564068 -287.461637) (xy 86.540562 -287.415505) (xy 86.524563 -287.366265)
			(xy 86.516464 -287.315127) (xy 86.515956 -287.28924) (xy 86.516497 -287.261532) (xy 86.525685 -287.206886)
			(xy 86.534244 -287.180528) (xy 86.541864 -287.158684) (xy 86.336886 -286.803592) (xy 86.314026 -286.799274)
			(xy 86.289236 -286.79403) (xy 86.241499 -286.777048) (xy 86.196923 -286.752961) (xy 86.156558 -286.722338)
			(xy 86.121354 -286.685898) (xy 86.09214 -286.644501) (xy 86.069605 -286.599121) (xy 86.054278 -286.550828)
			(xy 86.046522 -286.500758) (xy 86.046056 -286.475424) (xy 61.698632 -286.475424) (xy 61.698632 -286.771334)
			(xy 61.698194 -286.781498) (xy 61.690403 -286.800273) (xy 61.67602 -286.814638) (xy 61.657234 -286.822406)
			(xy 61.64707 -286.822896) (xy 60.24753 -286.822896) (xy 60.237378 -286.822343) (xy 60.218616 -286.814585)
			(xy 60.204251 -286.800237) (xy 60.196469 -286.781485) (xy 60.195968 -286.771334) (xy 54.154832 -286.771334)
			(xy 54.154394 -286.781498) (xy 54.146603 -286.800273) (xy 54.13222 -286.814638) (xy 54.113434 -286.822406)
			(xy 54.10327 -286.822896) (xy 52.70373 -286.822896) (xy 52.693578 -286.822343) (xy 52.674816 -286.814585)
			(xy 52.660451 -286.800237) (xy 52.652669 -286.781485) (xy 52.652168 -286.771334) (xy 46.611032 -286.771334)
			(xy 46.610594 -286.781498) (xy 46.602803 -286.800273) (xy 46.58842 -286.814638) (xy 46.569634 -286.822406)
			(xy 46.55947 -286.822896) (xy 45.15993 -286.822896) (xy 45.149778 -286.822343) (xy 45.131016 -286.814585)
			(xy 45.116651 -286.800237) (xy 45.108869 -286.781485) (xy 45.108368 -286.771334) (xy 39.067232 -286.771334)
			(xy 39.066794 -286.781498) (xy 39.059003 -286.800273) (xy 39.04462 -286.814638) (xy 39.025834 -286.822406)
			(xy 39.01567 -286.822896) (xy 37.61613 -286.822896) (xy 37.605978 -286.822343) (xy 37.587216 -286.814585)
			(xy 37.572851 -286.800237) (xy 37.565069 -286.781485) (xy 37.564568 -286.771334) (xy 31.523432 -286.771334)
			(xy 31.522994 -286.781498) (xy 31.515203 -286.800273) (xy 31.50082 -286.814638) (xy 31.482034 -286.822406)
			(xy 31.47187 -286.822896) (xy 30.07233 -286.822896) (xy 30.062178 -286.822343) (xy 30.043416 -286.814585)
			(xy 30.029051 -286.800237) (xy 30.021269 -286.781485) (xy 30.020768 -286.771334) (xy 23.979632 -286.771334)
			(xy 23.979194 -286.781498) (xy 23.971403 -286.800273) (xy 23.95702 -286.814638) (xy 23.938234 -286.822406)
			(xy 23.92807 -286.822896) (xy 22.52853 -286.822896) (xy 22.518378 -286.822343) (xy 22.499616 -286.814585)
			(xy 22.485251 -286.800237) (xy 22.477469 -286.781485) (xy 22.476968 -286.771334) (xy 16.435832 -286.771334)
			(xy 16.435394 -286.781498) (xy 16.427603 -286.800273) (xy 16.41322 -286.814638) (xy 16.394434 -286.822406)
			(xy 16.38427 -286.822896) (xy 14.98473 -286.822896) (xy 14.974578 -286.822343) (xy 14.955816 -286.814585)
			(xy 14.941451 -286.800237) (xy 14.933669 -286.781485) (xy 14.933168 -286.771334) (xy 8.892032 -286.771334)
			(xy 8.891594 -286.781498) (xy 8.883803 -286.800273) (xy 8.86942 -286.814638) (xy 8.850634 -286.822406)
			(xy 8.84047 -286.822896) (xy 7.44093 -286.822896) (xy 7.430778 -286.822343) (xy 7.412016 -286.814585)
			(xy 7.397651 -286.800237) (xy 7.389869 -286.781485) (xy 7.389368 -286.771334) (xy 2.509012 -286.771334)
			(xy 2.509012 -287.621472) (xy 11.489436 -287.621472) (xy 11.489436 -287.212532) (xy 11.489848 -287.202375)
			(xy 11.49764 -287.183617) (xy 11.51204 -287.169291) (xy 11.530839 -287.161596) (xy 11.540998 -287.161224)
			(xy 12.940538 -287.161224) (xy 12.950665 -287.161695) (xy 12.969384 -287.169432) (xy 12.983739 -287.183723)
			(xy 12.991559 -287.202407) (xy 12.9921 -287.212532) (xy 12.9921 -287.621472) (xy 19.033236 -287.621472)
			(xy 19.033236 -287.212532) (xy 19.033648 -287.202375) (xy 19.04144 -287.183617) (xy 19.05584 -287.169291)
			(xy 19.074639 -287.161596) (xy 19.084798 -287.161224) (xy 20.484338 -287.161224) (xy 20.494465 -287.161695)
			(xy 20.513184 -287.169432) (xy 20.527539 -287.183723) (xy 20.535359 -287.202407) (xy 20.5359 -287.212532)
			(xy 20.5359 -287.621472) (xy 26.577036 -287.621472) (xy 26.577036 -287.212532) (xy 26.577448 -287.202375)
			(xy 26.58524 -287.183617) (xy 26.59964 -287.169291) (xy 26.618439 -287.161596) (xy 26.628598 -287.161224)
			(xy 28.028138 -287.161224) (xy 28.038265 -287.161695) (xy 28.056984 -287.169432) (xy 28.071339 -287.183723)
			(xy 28.079159 -287.202407) (xy 28.0797 -287.212532) (xy 28.0797 -287.621472) (xy 34.120836 -287.621472)
			(xy 34.120836 -287.212532) (xy 34.121248 -287.202375) (xy 34.12904 -287.183617) (xy 34.14344 -287.169291)
			(xy 34.162239 -287.161596) (xy 34.172398 -287.161224) (xy 35.571938 -287.161224) (xy 35.582065 -287.161695)
			(xy 35.600784 -287.169432) (xy 35.615139 -287.183723) (xy 35.622959 -287.202407) (xy 35.6235 -287.212532)
			(xy 35.6235 -287.621472) (xy 41.664636 -287.621472) (xy 41.664636 -287.212532) (xy 41.665048 -287.202375)
			(xy 41.67284 -287.183617) (xy 41.68724 -287.169291) (xy 41.706039 -287.161596) (xy 41.716198 -287.161224)
			(xy 43.115738 -287.161224) (xy 43.125865 -287.161695) (xy 43.144584 -287.169432) (xy 43.158939 -287.183723)
			(xy 43.166759 -287.202407) (xy 43.1673 -287.212532) (xy 43.1673 -287.621472) (xy 49.208436 -287.621472)
			(xy 49.208436 -287.212532) (xy 49.208848 -287.202375) (xy 49.21664 -287.183617) (xy 49.23104 -287.169291)
			(xy 49.249839 -287.161596) (xy 49.259998 -287.161224) (xy 50.659538 -287.161224) (xy 50.669665 -287.161695)
			(xy 50.688384 -287.169432) (xy 50.702739 -287.183723) (xy 50.710559 -287.202407) (xy 50.7111 -287.212532)
			(xy 50.7111 -287.621472) (xy 56.752236 -287.621472) (xy 56.752236 -287.212532) (xy 56.752648 -287.202375)
			(xy 56.76044 -287.183617) (xy 56.77484 -287.169291) (xy 56.793639 -287.161596) (xy 56.803798 -287.161224)
			(xy 58.203338 -287.161224) (xy 58.213465 -287.161695) (xy 58.232184 -287.169432) (xy 58.246539 -287.183723)
			(xy 58.254359 -287.202407) (xy 58.2549 -287.212532) (xy 58.2549 -287.621472) (xy 64.296036 -287.621472)
			(xy 64.296036 -287.212532) (xy 64.296448 -287.202375) (xy 64.30424 -287.183617) (xy 64.31864 -287.169291)
			(xy 64.337439 -287.161596) (xy 64.347598 -287.161224) (xy 65.747138 -287.161224) (xy 65.757265 -287.161695)
			(xy 65.775984 -287.169432) (xy 65.790339 -287.183723) (xy 65.798159 -287.202407) (xy 65.7987 -287.212532)
			(xy 65.7987 -287.621472) (xy 162.162236 -287.621472) (xy 162.162236 -287.212532) (xy 162.162648 -287.202375)
			(xy 162.17044 -287.183617) (xy 162.18484 -287.169291) (xy 162.203639 -287.161596) (xy 162.213798 -287.161224)
			(xy 163.613338 -287.161224) (xy 163.623465 -287.161695) (xy 163.642184 -287.169432) (xy 163.656539 -287.183723)
			(xy 163.664359 -287.202407) (xy 163.6649 -287.212532) (xy 163.6649 -287.621472) (xy 169.706036 -287.621472)
			(xy 169.706036 -287.212532) (xy 169.706448 -287.202375) (xy 169.71424 -287.183617) (xy 169.72864 -287.169291)
			(xy 169.747439 -287.161596) (xy 169.757598 -287.161224) (xy 171.157138 -287.161224) (xy 171.167265 -287.161695)
			(xy 171.185984 -287.169432) (xy 171.200339 -287.183723) (xy 171.208159 -287.202407) (xy 171.2087 -287.212532)
			(xy 171.2087 -287.621472) (xy 177.249836 -287.621472) (xy 177.249836 -287.212532) (xy 177.250248 -287.202375)
			(xy 177.25804 -287.183617) (xy 177.27244 -287.169291) (xy 177.291239 -287.161596) (xy 177.301398 -287.161224)
			(xy 178.700938 -287.161224) (xy 178.711065 -287.161695) (xy 178.729784 -287.169432) (xy 178.744139 -287.183723)
			(xy 178.751959 -287.202407) (xy 178.7525 -287.212532) (xy 178.7525 -287.621472) (xy 184.793636 -287.621472)
			(xy 184.793636 -287.212532) (xy 184.794048 -287.202375) (xy 184.80184 -287.183617) (xy 184.81624 -287.169291)
			(xy 184.835039 -287.161596) (xy 184.845198 -287.161224) (xy 186.244738 -287.161224) (xy 186.254865 -287.161695)
			(xy 186.273584 -287.169432) (xy 186.287939 -287.183723) (xy 186.295759 -287.202407) (xy 186.2963 -287.212532)
			(xy 186.2963 -287.621472) (xy 192.337436 -287.621472) (xy 192.337436 -287.212532) (xy 192.337848 -287.202375)
			(xy 192.34564 -287.183617) (xy 192.36004 -287.169291) (xy 192.378839 -287.161596) (xy 192.388998 -287.161224)
			(xy 193.788538 -287.161224) (xy 193.798665 -287.161695) (xy 193.817384 -287.169432) (xy 193.831739 -287.183723)
			(xy 193.839559 -287.202407) (xy 193.8401 -287.212532) (xy 193.8401 -287.621472) (xy 199.881236 -287.621472)
			(xy 199.881236 -287.212532) (xy 199.881648 -287.202375) (xy 199.88944 -287.183617) (xy 199.90384 -287.169291)
			(xy 199.922639 -287.161596) (xy 199.932798 -287.161224) (xy 201.332338 -287.161224) (xy 201.342465 -287.161695)
			(xy 201.361184 -287.169432) (xy 201.375539 -287.183723) (xy 201.383359 -287.202407) (xy 201.3839 -287.212532)
			(xy 201.3839 -287.621472) (xy 207.425036 -287.621472) (xy 207.425036 -287.212532) (xy 207.425448 -287.202375)
			(xy 207.43324 -287.183617) (xy 207.44764 -287.169291) (xy 207.466439 -287.161596) (xy 207.476598 -287.161224)
			(xy 208.876138 -287.161224) (xy 208.886265 -287.161695) (xy 208.904984 -287.169432) (xy 208.919339 -287.183723)
			(xy 208.927159 -287.202407) (xy 208.9277 -287.212532) (xy 208.9277 -287.621472) (xy 214.968836 -287.621472)
			(xy 214.968836 -287.212532) (xy 214.969248 -287.202375) (xy 214.97704 -287.183617) (xy 214.99144 -287.169291)
			(xy 215.010239 -287.161596) (xy 215.020398 -287.161224) (xy 216.419938 -287.161224) (xy 216.430065 -287.161695)
			(xy 216.448784 -287.169432) (xy 216.463139 -287.183723) (xy 216.470959 -287.202407) (xy 216.4715 -287.212532)
			(xy 216.4715 -287.621472) (xy 259.429504 -287.621472) (xy 259.429504 -287.212532) (xy 259.429948 -287.202379)
			(xy 259.437733 -287.183627) (xy 259.452124 -287.169302) (xy 259.470912 -287.161602) (xy 259.481066 -287.161224)
			(xy 260.880606 -287.161224) (xy 260.890731 -287.161721) (xy 260.909449 -287.169448) (xy 260.923805 -287.183731)
			(xy 260.931627 -287.20241) (xy 260.932168 -287.212532) (xy 260.932168 -287.621472) (xy 266.973304 -287.621472)
			(xy 266.973304 -287.212532) (xy 266.973748 -287.202379) (xy 266.981533 -287.183627) (xy 266.995924 -287.169302)
			(xy 267.014712 -287.161602) (xy 267.024866 -287.161224) (xy 268.424406 -287.161224) (xy 268.434531 -287.161721)
			(xy 268.453249 -287.169448) (xy 268.467605 -287.183731) (xy 268.475427 -287.20241) (xy 268.475968 -287.212532)
			(xy 268.475968 -287.621472) (xy 274.517104 -287.621472) (xy 274.517104 -287.212532) (xy 274.517548 -287.202379)
			(xy 274.525333 -287.183627) (xy 274.539724 -287.169302) (xy 274.558512 -287.161602) (xy 274.568666 -287.161224)
			(xy 275.968206 -287.161224) (xy 275.978331 -287.161721) (xy 275.997049 -287.169448) (xy 276.011405 -287.183731)
			(xy 276.019227 -287.20241) (xy 276.019768 -287.212532) (xy 276.019768 -287.621472) (xy 282.060904 -287.621472)
			(xy 282.060904 -287.212532) (xy 282.061348 -287.202379) (xy 282.069133 -287.183627) (xy 282.083524 -287.169302)
			(xy 282.102312 -287.161602) (xy 282.112466 -287.161224) (xy 283.512006 -287.161224) (xy 283.522131 -287.161721)
			(xy 283.540849 -287.169448) (xy 283.555205 -287.183731) (xy 283.563027 -287.20241) (xy 283.563568 -287.212532)
			(xy 283.563568 -287.621472) (xy 289.604704 -287.621472) (xy 289.604704 -287.212532) (xy 289.605148 -287.202379)
			(xy 289.612933 -287.183627) (xy 289.627324 -287.169302) (xy 289.646112 -287.161602) (xy 289.656266 -287.161224)
			(xy 291.055806 -287.161224) (xy 291.065931 -287.161721) (xy 291.084649 -287.169448) (xy 291.099005 -287.183731)
			(xy 291.106827 -287.20241) (xy 291.107368 -287.212532) (xy 291.107368 -287.621472) (xy 297.148504 -287.621472)
			(xy 297.148504 -287.212532) (xy 297.148948 -287.202379) (xy 297.156733 -287.183627) (xy 297.171124 -287.169302)
			(xy 297.189912 -287.161602) (xy 297.200066 -287.161224) (xy 298.599606 -287.161224) (xy 298.609731 -287.161721)
			(xy 298.628449 -287.169448) (xy 298.642805 -287.183731) (xy 298.650627 -287.20241) (xy 298.651168 -287.212532)
			(xy 298.651168 -287.621472) (xy 304.692304 -287.621472) (xy 304.692304 -287.212532) (xy 304.692748 -287.202379)
			(xy 304.700533 -287.183627) (xy 304.714924 -287.169302) (xy 304.733712 -287.161602) (xy 304.743866 -287.161224)
			(xy 306.143406 -287.161224) (xy 306.153531 -287.161721) (xy 306.172249 -287.169448) (xy 306.186605 -287.183731)
			(xy 306.194427 -287.20241) (xy 306.194968 -287.212532) (xy 306.194968 -287.621472) (xy 312.236104 -287.621472)
			(xy 312.236104 -287.212532) (xy 312.236548 -287.202379) (xy 312.244333 -287.183627) (xy 312.258724 -287.169302)
			(xy 312.277512 -287.161602) (xy 312.287666 -287.161224) (xy 313.687206 -287.161224) (xy 313.697331 -287.161721)
			(xy 313.716049 -287.169448) (xy 313.730405 -287.183731) (xy 313.738227 -287.20241) (xy 313.738768 -287.212532)
			(xy 313.738768 -287.621472) (xy 410.102304 -287.621472) (xy 410.102304 -287.212532) (xy 410.102748 -287.202379)
			(xy 410.110533 -287.183627) (xy 410.124924 -287.169302) (xy 410.143712 -287.161602) (xy 410.153866 -287.161224)
			(xy 411.553406 -287.161224) (xy 411.563531 -287.161721) (xy 411.582249 -287.169448) (xy 411.596605 -287.183731)
			(xy 411.604427 -287.20241) (xy 411.604968 -287.212532) (xy 411.604968 -287.621472) (xy 417.646104 -287.621472)
			(xy 417.646104 -287.212532) (xy 417.646548 -287.202379) (xy 417.654333 -287.183627) (xy 417.668724 -287.169302)
			(xy 417.687512 -287.161602) (xy 417.697666 -287.161224) (xy 419.097206 -287.161224) (xy 419.107331 -287.161721)
			(xy 419.126049 -287.169448) (xy 419.140405 -287.183731) (xy 419.148227 -287.20241) (xy 419.148768 -287.212532)
			(xy 419.148768 -287.621472) (xy 425.189904 -287.621472) (xy 425.189904 -287.212532) (xy 425.190348 -287.202379)
			(xy 425.198133 -287.183627) (xy 425.212524 -287.169302) (xy 425.231312 -287.161602) (xy 425.241466 -287.161224)
			(xy 426.641006 -287.161224) (xy 426.651131 -287.161721) (xy 426.669849 -287.169448) (xy 426.684205 -287.183731)
			(xy 426.692027 -287.20241) (xy 426.692568 -287.212532) (xy 426.692568 -287.621472) (xy 432.733704 -287.621472)
			(xy 432.733704 -287.212532) (xy 432.734148 -287.202379) (xy 432.741933 -287.183627) (xy 432.756324 -287.169302)
			(xy 432.775112 -287.161602) (xy 432.785266 -287.161224) (xy 434.184806 -287.161224) (xy 434.194931 -287.161721)
			(xy 434.213649 -287.169448) (xy 434.228005 -287.183731) (xy 434.235827 -287.20241) (xy 434.236368 -287.212532)
			(xy 434.236368 -287.621472) (xy 440.277504 -287.621472) (xy 440.277504 -287.212532) (xy 440.277948 -287.202379)
			(xy 440.285733 -287.183627) (xy 440.300124 -287.169302) (xy 440.318912 -287.161602) (xy 440.329066 -287.161224)
			(xy 441.728606 -287.161224) (xy 441.738731 -287.161721) (xy 441.757449 -287.169448) (xy 441.771805 -287.183731)
			(xy 441.779627 -287.20241) (xy 441.780168 -287.212532) (xy 441.780168 -287.621472) (xy 447.821304 -287.621472)
			(xy 447.821304 -287.212532) (xy 447.821748 -287.202379) (xy 447.829533 -287.183627) (xy 447.843924 -287.169302)
			(xy 447.862712 -287.161602) (xy 447.872866 -287.161224) (xy 449.272406 -287.161224) (xy 449.282531 -287.161721)
			(xy 449.301249 -287.169448) (xy 449.315605 -287.183731) (xy 449.323427 -287.20241) (xy 449.323968 -287.212532)
			(xy 449.323968 -287.621472) (xy 455.365104 -287.621472) (xy 455.365104 -287.212532) (xy 455.365548 -287.202379)
			(xy 455.373333 -287.183627) (xy 455.387724 -287.169302) (xy 455.406512 -287.161602) (xy 455.416666 -287.161224)
			(xy 456.816206 -287.161224) (xy 456.826331 -287.161721) (xy 456.845049 -287.169448) (xy 456.859405 -287.183731)
			(xy 456.867227 -287.20241) (xy 456.867768 -287.212532) (xy 456.867768 -287.621472) (xy 462.908904 -287.621472)
			(xy 462.908904 -287.212532) (xy 462.909348 -287.202379) (xy 462.917133 -287.183627) (xy 462.931524 -287.169302)
			(xy 462.950312 -287.161602) (xy 462.960466 -287.161224) (xy 464.360006 -287.161224) (xy 464.370131 -287.161721)
			(xy 464.388849 -287.169448) (xy 464.403205 -287.183731) (xy 464.411027 -287.20241) (xy 464.411568 -287.212532)
			(xy 464.411568 -287.621472) (xy 464.411155 -287.631628) (xy 464.403363 -287.650386) (xy 464.388963 -287.664712)
			(xy 464.370164 -287.672407) (xy 464.360006 -287.67278) (xy 462.960466 -287.67278) (xy 462.95034 -287.672302)
			(xy 462.931621 -287.664567) (xy 462.917267 -287.650278) (xy 462.909445 -287.631596) (xy 462.908904 -287.621472)
			(xy 456.867768 -287.621472) (xy 456.867355 -287.631628) (xy 456.859563 -287.650386) (xy 456.845163 -287.664712)
			(xy 456.826364 -287.672407) (xy 456.816206 -287.67278) (xy 455.416666 -287.67278) (xy 455.40654 -287.672302)
			(xy 455.387821 -287.664567) (xy 455.373467 -287.650278) (xy 455.365645 -287.631596) (xy 455.365104 -287.621472)
			(xy 449.323968 -287.621472) (xy 449.323555 -287.631628) (xy 449.315763 -287.650386) (xy 449.301363 -287.664712)
			(xy 449.282564 -287.672407) (xy 449.272406 -287.67278) (xy 447.872866 -287.67278) (xy 447.86274 -287.672302)
			(xy 447.844021 -287.664567) (xy 447.829667 -287.650278) (xy 447.821845 -287.631596) (xy 447.821304 -287.621472)
			(xy 441.780168 -287.621472) (xy 441.779755 -287.631628) (xy 441.771963 -287.650386) (xy 441.757563 -287.664712)
			(xy 441.738764 -287.672407) (xy 441.728606 -287.67278) (xy 440.329066 -287.67278) (xy 440.31894 -287.672302)
			(xy 440.300221 -287.664567) (xy 440.285867 -287.650278) (xy 440.278045 -287.631596) (xy 440.277504 -287.621472)
			(xy 434.236368 -287.621472) (xy 434.235955 -287.631628) (xy 434.228163 -287.650386) (xy 434.213763 -287.664712)
			(xy 434.194964 -287.672407) (xy 434.184806 -287.67278) (xy 432.785266 -287.67278) (xy 432.77514 -287.672302)
			(xy 432.756421 -287.664567) (xy 432.742067 -287.650278) (xy 432.734245 -287.631596) (xy 432.733704 -287.621472)
			(xy 426.692568 -287.621472) (xy 426.692155 -287.631628) (xy 426.684363 -287.650386) (xy 426.669963 -287.664712)
			(xy 426.651164 -287.672407) (xy 426.641006 -287.67278) (xy 425.241466 -287.67278) (xy 425.23134 -287.672302)
			(xy 425.212621 -287.664567) (xy 425.198267 -287.650278) (xy 425.190445 -287.631596) (xy 425.189904 -287.621472)
			(xy 419.148768 -287.621472) (xy 419.148355 -287.631628) (xy 419.140563 -287.650386) (xy 419.126163 -287.664712)
			(xy 419.107364 -287.672407) (xy 419.097206 -287.67278) (xy 417.697666 -287.67278) (xy 417.68754 -287.672302)
			(xy 417.668821 -287.664567) (xy 417.654467 -287.650278) (xy 417.646645 -287.631596) (xy 417.646104 -287.621472)
			(xy 411.604968 -287.621472) (xy 411.604555 -287.631628) (xy 411.596763 -287.650386) (xy 411.582363 -287.664712)
			(xy 411.563564 -287.672407) (xy 411.553406 -287.67278) (xy 410.153866 -287.67278) (xy 410.14374 -287.672302)
			(xy 410.125021 -287.664567) (xy 410.110667 -287.650278) (xy 410.102845 -287.631596) (xy 410.102304 -287.621472)
			(xy 313.738768 -287.621472) (xy 313.738355 -287.631628) (xy 313.730563 -287.650386) (xy 313.716163 -287.664712)
			(xy 313.697364 -287.672407) (xy 313.687206 -287.67278) (xy 312.287666 -287.67278) (xy 312.27754 -287.672302)
			(xy 312.258821 -287.664567) (xy 312.244467 -287.650278) (xy 312.236645 -287.631596) (xy 312.236104 -287.621472)
			(xy 306.194968 -287.621472) (xy 306.194555 -287.631628) (xy 306.186763 -287.650386) (xy 306.172363 -287.664712)
			(xy 306.153564 -287.672407) (xy 306.143406 -287.67278) (xy 304.743866 -287.67278) (xy 304.73374 -287.672302)
			(xy 304.715021 -287.664567) (xy 304.700667 -287.650278) (xy 304.692845 -287.631596) (xy 304.692304 -287.621472)
			(xy 298.651168 -287.621472) (xy 298.650755 -287.631628) (xy 298.642963 -287.650386) (xy 298.628563 -287.664712)
			(xy 298.609764 -287.672407) (xy 298.599606 -287.67278) (xy 297.200066 -287.67278) (xy 297.18994 -287.672302)
			(xy 297.171221 -287.664567) (xy 297.156867 -287.650278) (xy 297.149045 -287.631596) (xy 297.148504 -287.621472)
			(xy 291.107368 -287.621472) (xy 291.106955 -287.631628) (xy 291.099163 -287.650386) (xy 291.084763 -287.664712)
			(xy 291.065964 -287.672407) (xy 291.055806 -287.67278) (xy 289.656266 -287.67278) (xy 289.64614 -287.672302)
			(xy 289.627421 -287.664567) (xy 289.613067 -287.650278) (xy 289.605245 -287.631596) (xy 289.604704 -287.621472)
			(xy 283.563568 -287.621472) (xy 283.563155 -287.631628) (xy 283.555363 -287.650386) (xy 283.540963 -287.664712)
			(xy 283.522164 -287.672407) (xy 283.512006 -287.67278) (xy 282.112466 -287.67278) (xy 282.10234 -287.672302)
			(xy 282.083621 -287.664567) (xy 282.069267 -287.650278) (xy 282.061445 -287.631596) (xy 282.060904 -287.621472)
			(xy 276.019768 -287.621472) (xy 276.019355 -287.631628) (xy 276.011563 -287.650386) (xy 275.997163 -287.664712)
			(xy 275.978364 -287.672407) (xy 275.968206 -287.67278) (xy 274.568666 -287.67278) (xy 274.55854 -287.672302)
			(xy 274.539821 -287.664567) (xy 274.525467 -287.650278) (xy 274.517645 -287.631596) (xy 274.517104 -287.621472)
			(xy 268.475968 -287.621472) (xy 268.475555 -287.631628) (xy 268.467763 -287.650386) (xy 268.453363 -287.664712)
			(xy 268.434564 -287.672407) (xy 268.424406 -287.67278) (xy 267.024866 -287.67278) (xy 267.01474 -287.672302)
			(xy 266.996021 -287.664567) (xy 266.981667 -287.650278) (xy 266.973845 -287.631596) (xy 266.973304 -287.621472)
			(xy 260.932168 -287.621472) (xy 260.931755 -287.631628) (xy 260.923963 -287.650386) (xy 260.909563 -287.664712)
			(xy 260.890764 -287.672407) (xy 260.880606 -287.67278) (xy 259.481066 -287.67278) (xy 259.47094 -287.672302)
			(xy 259.452221 -287.664567) (xy 259.437867 -287.650278) (xy 259.430045 -287.631596) (xy 259.429504 -287.621472)
			(xy 216.4715 -287.621472) (xy 216.471056 -287.631624) (xy 216.463269 -287.650376) (xy 216.448879 -287.664701)
			(xy 216.430092 -287.672401) (xy 216.419938 -287.67278) (xy 215.020398 -287.67278) (xy 215.010274 -287.672276)
			(xy 214.991556 -287.664551) (xy 214.977201 -287.65027) (xy 214.969378 -287.631594) (xy 214.968836 -287.621472)
			(xy 208.9277 -287.621472) (xy 208.927256 -287.631624) (xy 208.919469 -287.650376) (xy 208.905079 -287.664701)
			(xy 208.886292 -287.672401) (xy 208.876138 -287.67278) (xy 207.476598 -287.67278) (xy 207.466474 -287.672276)
			(xy 207.447756 -287.664551) (xy 207.433401 -287.65027) (xy 207.425578 -287.631594) (xy 207.425036 -287.621472)
			(xy 201.3839 -287.621472) (xy 201.383456 -287.631624) (xy 201.375669 -287.650376) (xy 201.361279 -287.664701)
			(xy 201.342492 -287.672401) (xy 201.332338 -287.67278) (xy 199.932798 -287.67278) (xy 199.922674 -287.672276)
			(xy 199.903956 -287.664551) (xy 199.889601 -287.65027) (xy 199.881778 -287.631594) (xy 199.881236 -287.621472)
			(xy 193.8401 -287.621472) (xy 193.839656 -287.631624) (xy 193.831869 -287.650376) (xy 193.817479 -287.664701)
			(xy 193.798692 -287.672401) (xy 193.788538 -287.67278) (xy 192.388998 -287.67278) (xy 192.378874 -287.672276)
			(xy 192.360156 -287.664551) (xy 192.345801 -287.65027) (xy 192.337978 -287.631594) (xy 192.337436 -287.621472)
			(xy 186.2963 -287.621472) (xy 186.295856 -287.631624) (xy 186.288069 -287.650376) (xy 186.273679 -287.664701)
			(xy 186.254892 -287.672401) (xy 186.244738 -287.67278) (xy 184.845198 -287.67278) (xy 184.835074 -287.672276)
			(xy 184.816356 -287.664551) (xy 184.802001 -287.65027) (xy 184.794178 -287.631594) (xy 184.793636 -287.621472)
			(xy 178.7525 -287.621472) (xy 178.752056 -287.631624) (xy 178.744269 -287.650376) (xy 178.729879 -287.664701)
			(xy 178.711092 -287.672401) (xy 178.700938 -287.67278) (xy 177.301398 -287.67278) (xy 177.291274 -287.672276)
			(xy 177.272556 -287.664551) (xy 177.258201 -287.65027) (xy 177.250378 -287.631594) (xy 177.249836 -287.621472)
			(xy 171.2087 -287.621472) (xy 171.208256 -287.631624) (xy 171.200469 -287.650376) (xy 171.186079 -287.664701)
			(xy 171.167292 -287.672401) (xy 171.157138 -287.67278) (xy 169.757598 -287.67278) (xy 169.747474 -287.672276)
			(xy 169.728756 -287.664551) (xy 169.714401 -287.65027) (xy 169.706578 -287.631594) (xy 169.706036 -287.621472)
			(xy 163.6649 -287.621472) (xy 163.664456 -287.631624) (xy 163.656669 -287.650376) (xy 163.642279 -287.664701)
			(xy 163.623492 -287.672401) (xy 163.613338 -287.67278) (xy 162.213798 -287.67278) (xy 162.203674 -287.672276)
			(xy 162.184956 -287.664551) (xy 162.170601 -287.65027) (xy 162.162778 -287.631594) (xy 162.162236 -287.621472)
			(xy 65.7987 -287.621472) (xy 65.798256 -287.631624) (xy 65.790469 -287.650376) (xy 65.776079 -287.664701)
			(xy 65.757292 -287.672401) (xy 65.747138 -287.67278) (xy 64.347598 -287.67278) (xy 64.337474 -287.672276)
			(xy 64.318756 -287.664551) (xy 64.304401 -287.65027) (xy 64.296578 -287.631594) (xy 64.296036 -287.621472)
			(xy 58.2549 -287.621472) (xy 58.254456 -287.631624) (xy 58.246669 -287.650376) (xy 58.232279 -287.664701)
			(xy 58.213492 -287.672401) (xy 58.203338 -287.67278) (xy 56.803798 -287.67278) (xy 56.793674 -287.672276)
			(xy 56.774956 -287.664551) (xy 56.760601 -287.65027) (xy 56.752778 -287.631594) (xy 56.752236 -287.621472)
			(xy 50.7111 -287.621472) (xy 50.710656 -287.631624) (xy 50.702869 -287.650376) (xy 50.688479 -287.664701)
			(xy 50.669692 -287.672401) (xy 50.659538 -287.67278) (xy 49.259998 -287.67278) (xy 49.249874 -287.672276)
			(xy 49.231156 -287.664551) (xy 49.216801 -287.65027) (xy 49.208978 -287.631594) (xy 49.208436 -287.621472)
			(xy 43.1673 -287.621472) (xy 43.166856 -287.631624) (xy 43.159069 -287.650376) (xy 43.144679 -287.664701)
			(xy 43.125892 -287.672401) (xy 43.115738 -287.67278) (xy 41.716198 -287.67278) (xy 41.706074 -287.672276)
			(xy 41.687356 -287.664551) (xy 41.673001 -287.65027) (xy 41.665178 -287.631594) (xy 41.664636 -287.621472)
			(xy 35.6235 -287.621472) (xy 35.623056 -287.631624) (xy 35.615269 -287.650376) (xy 35.600879 -287.664701)
			(xy 35.582092 -287.672401) (xy 35.571938 -287.67278) (xy 34.172398 -287.67278) (xy 34.162274 -287.672276)
			(xy 34.143556 -287.664551) (xy 34.129201 -287.65027) (xy 34.121378 -287.631594) (xy 34.120836 -287.621472)
			(xy 28.0797 -287.621472) (xy 28.079256 -287.631624) (xy 28.071469 -287.650376) (xy 28.057079 -287.664701)
			(xy 28.038292 -287.672401) (xy 28.028138 -287.67278) (xy 26.628598 -287.67278) (xy 26.618474 -287.672276)
			(xy 26.599756 -287.664551) (xy 26.585401 -287.65027) (xy 26.577578 -287.631594) (xy 26.577036 -287.621472)
			(xy 20.5359 -287.621472) (xy 20.535456 -287.631624) (xy 20.527669 -287.650376) (xy 20.513279 -287.664701)
			(xy 20.494492 -287.672401) (xy 20.484338 -287.67278) (xy 19.084798 -287.67278) (xy 19.074674 -287.672276)
			(xy 19.055956 -287.664551) (xy 19.041601 -287.65027) (xy 19.033778 -287.631594) (xy 19.033236 -287.621472)
			(xy 12.9921 -287.621472) (xy 12.991656 -287.631624) (xy 12.983869 -287.650376) (xy 12.969479 -287.664701)
			(xy 12.950692 -287.672401) (xy 12.940538 -287.67278) (xy 11.540998 -287.67278) (xy 11.530874 -287.672276)
			(xy 11.512156 -287.664551) (xy 11.497801 -287.65027) (xy 11.489978 -287.631594) (xy 11.489436 -287.621472)
			(xy 2.509012 -287.621472) (xy 2.509012 -288.471356) (xy 7.389368 -288.471356) (xy 7.389368 -288.062416)
			(xy 7.389834 -288.052267) (xy 7.397618 -288.033521) (xy 7.412001 -288.019198) (xy 7.430779 -288.011492)
			(xy 7.44093 -288.011108) (xy 8.84047 -288.011108) (xy 8.850591 -288.01165) (xy 8.869305 -288.019362)
			(xy 8.883662 -288.033631) (xy 8.891488 -288.052298) (xy 8.892032 -288.062416) (xy 8.892032 -288.471356)
			(xy 14.933168 -288.471356) (xy 14.933168 -288.062416) (xy 14.933634 -288.052267) (xy 14.941418 -288.033521)
			(xy 14.955801 -288.019198) (xy 14.974579 -288.011492) (xy 14.98473 -288.011108) (xy 16.38427 -288.011108)
			(xy 16.394391 -288.01165) (xy 16.413105 -288.019362) (xy 16.427462 -288.033631) (xy 16.435288 -288.052298)
			(xy 16.435832 -288.062416) (xy 16.435832 -288.471356) (xy 22.476968 -288.471356) (xy 22.476968 -288.062416)
			(xy 22.477434 -288.052267) (xy 22.485218 -288.033521) (xy 22.499601 -288.019198) (xy 22.518379 -288.011492)
			(xy 22.52853 -288.011108) (xy 23.92807 -288.011108) (xy 23.938191 -288.01165) (xy 23.956905 -288.019362)
			(xy 23.971262 -288.033631) (xy 23.979088 -288.052298) (xy 23.979632 -288.062416) (xy 23.979632 -288.471356)
			(xy 30.020768 -288.471356) (xy 30.020768 -288.062416) (xy 30.021234 -288.052267) (xy 30.029018 -288.033521)
			(xy 30.043401 -288.019198) (xy 30.062179 -288.011492) (xy 30.07233 -288.011108) (xy 31.47187 -288.011108)
			(xy 31.481991 -288.01165) (xy 31.500705 -288.019362) (xy 31.515062 -288.033631) (xy 31.522888 -288.052298)
			(xy 31.523432 -288.062416) (xy 31.523432 -288.471356) (xy 37.564568 -288.471356) (xy 37.564568 -288.062416)
			(xy 37.565034 -288.052267) (xy 37.572818 -288.033521) (xy 37.587201 -288.019198) (xy 37.605979 -288.011492)
			(xy 37.61613 -288.011108) (xy 39.01567 -288.011108) (xy 39.025791 -288.01165) (xy 39.044505 -288.019362)
			(xy 39.058862 -288.033631) (xy 39.066688 -288.052298) (xy 39.067232 -288.062416) (xy 39.067232 -288.471356)
			(xy 45.108368 -288.471356) (xy 45.108368 -288.062416) (xy 45.108834 -288.052267) (xy 45.116618 -288.033521)
			(xy 45.131001 -288.019198) (xy 45.149779 -288.011492) (xy 45.15993 -288.011108) (xy 46.55947 -288.011108)
			(xy 46.569591 -288.01165) (xy 46.588305 -288.019362) (xy 46.602662 -288.033631) (xy 46.610488 -288.052298)
			(xy 46.611032 -288.062416) (xy 46.611032 -288.471356) (xy 52.652168 -288.471356) (xy 52.652168 -288.062416)
			(xy 52.652634 -288.052267) (xy 52.660418 -288.033521) (xy 52.674801 -288.019198) (xy 52.693579 -288.011492)
			(xy 52.70373 -288.011108) (xy 54.10327 -288.011108) (xy 54.113391 -288.01165) (xy 54.132105 -288.019362)
			(xy 54.146462 -288.033631) (xy 54.154288 -288.052298) (xy 54.154832 -288.062416) (xy 54.154832 -288.471356)
			(xy 60.195968 -288.471356) (xy 60.195968 -288.062416) (xy 60.196434 -288.052267) (xy 60.204218 -288.033521)
			(xy 60.218601 -288.019198) (xy 60.237379 -288.011492) (xy 60.24753 -288.011108) (xy 61.64707 -288.011108)
			(xy 61.657191 -288.01165) (xy 61.675905 -288.019362) (xy 61.690262 -288.033631) (xy 61.698088 -288.052298)
			(xy 61.698632 -288.062416) (xy 61.698632 -288.471356) (xy 61.698143 -288.481503) (xy 61.690368 -288.500249)
			(xy 61.675992 -288.514572) (xy 61.657219 -288.522279) (xy 61.64707 -288.522664) (xy 60.24753 -288.522664)
			(xy 60.237406 -288.522149) (xy 60.218686 -288.514432) (xy 60.204329 -288.500154) (xy 60.196508 -288.481478)
			(xy 60.195968 -288.471356) (xy 54.154832 -288.471356) (xy 54.154343 -288.481503) (xy 54.146568 -288.500249)
			(xy 54.132192 -288.514572) (xy 54.113419 -288.522279) (xy 54.10327 -288.522664) (xy 52.70373 -288.522664)
			(xy 52.693606 -288.522149) (xy 52.674886 -288.514432) (xy 52.660529 -288.500154) (xy 52.652708 -288.481478)
			(xy 52.652168 -288.471356) (xy 46.611032 -288.471356) (xy 46.610543 -288.481503) (xy 46.602768 -288.500249)
			(xy 46.588392 -288.514572) (xy 46.569619 -288.522279) (xy 46.55947 -288.522664) (xy 45.15993 -288.522664)
			(xy 45.149806 -288.522149) (xy 45.131086 -288.514432) (xy 45.116729 -288.500154) (xy 45.108908 -288.481478)
			(xy 45.108368 -288.471356) (xy 39.067232 -288.471356) (xy 39.066743 -288.481503) (xy 39.058968 -288.500249)
			(xy 39.044592 -288.514572) (xy 39.025819 -288.522279) (xy 39.01567 -288.522664) (xy 37.61613 -288.522664)
			(xy 37.606006 -288.522149) (xy 37.587286 -288.514432) (xy 37.572929 -288.500154) (xy 37.565108 -288.481478)
			(xy 37.564568 -288.471356) (xy 31.523432 -288.471356) (xy 31.522943 -288.481503) (xy 31.515168 -288.500249)
			(xy 31.500792 -288.514572) (xy 31.482019 -288.522279) (xy 31.47187 -288.522664) (xy 30.07233 -288.522664)
			(xy 30.062206 -288.522149) (xy 30.043486 -288.514432) (xy 30.029129 -288.500154) (xy 30.021308 -288.481478)
			(xy 30.020768 -288.471356) (xy 23.979632 -288.471356) (xy 23.979143 -288.481503) (xy 23.971368 -288.500249)
			(xy 23.956992 -288.514572) (xy 23.938219 -288.522279) (xy 23.92807 -288.522664) (xy 22.52853 -288.522664)
			(xy 22.518406 -288.522149) (xy 22.499686 -288.514432) (xy 22.485329 -288.500154) (xy 22.477508 -288.481478)
			(xy 22.476968 -288.471356) (xy 16.435832 -288.471356) (xy 16.435343 -288.481503) (xy 16.427568 -288.500249)
			(xy 16.413192 -288.514572) (xy 16.394419 -288.522279) (xy 16.38427 -288.522664) (xy 14.98473 -288.522664)
			(xy 14.974606 -288.522149) (xy 14.955886 -288.514432) (xy 14.941529 -288.500154) (xy 14.933708 -288.481478)
			(xy 14.933168 -288.471356) (xy 8.892032 -288.471356) (xy 8.891543 -288.481503) (xy 8.883768 -288.500249)
			(xy 8.869392 -288.514572) (xy 8.850619 -288.522279) (xy 8.84047 -288.522664) (xy 7.44093 -288.522664)
			(xy 7.430806 -288.522149) (xy 7.412086 -288.514432) (xy 7.397729 -288.500154) (xy 7.389908 -288.481478)
			(xy 7.389368 -288.471356) (xy 2.509012 -288.471356) (xy 2.509012 -289.321494) (xy 11.489436 -289.321494)
			(xy 11.489436 -288.912554) (xy 11.489896 -288.902394) (xy 11.497685 -288.883624) (xy 11.512061 -288.86926)
			(xy 11.530837 -288.861487) (xy 11.540998 -288.860992) (xy 12.940538 -288.860992) (xy 12.950693 -288.861501)
			(xy 12.969454 -288.869279) (xy 12.983816 -288.88364) (xy 12.991597 -288.9024) (xy 12.9921 -288.912554)
			(xy 12.9921 -289.321494) (xy 19.033236 -289.321494) (xy 19.033236 -288.912554) (xy 19.033696 -288.902394)
			(xy 19.041485 -288.883624) (xy 19.055861 -288.86926) (xy 19.074637 -288.861487) (xy 19.084798 -288.860992)
			(xy 20.484338 -288.860992) (xy 20.494493 -288.861501) (xy 20.513254 -288.869279) (xy 20.527616 -288.88364)
			(xy 20.535397 -288.9024) (xy 20.5359 -288.912554) (xy 20.5359 -289.321494) (xy 26.577036 -289.321494)
			(xy 26.577036 -288.912554) (xy 26.577496 -288.902394) (xy 26.585285 -288.883624) (xy 26.599661 -288.86926)
			(xy 26.618437 -288.861487) (xy 26.628598 -288.860992) (xy 28.028138 -288.860992) (xy 28.038293 -288.861501)
			(xy 28.057054 -288.869279) (xy 28.071416 -288.88364) (xy 28.079197 -288.9024) (xy 28.0797 -288.912554)
			(xy 28.0797 -289.321494) (xy 34.120836 -289.321494) (xy 34.120836 -288.912554) (xy 34.121296 -288.902394)
			(xy 34.129085 -288.883624) (xy 34.143461 -288.86926) (xy 34.162237 -288.861487) (xy 34.172398 -288.860992)
			(xy 35.571938 -288.860992) (xy 35.582093 -288.861501) (xy 35.600854 -288.869279) (xy 35.615216 -288.88364)
			(xy 35.622997 -288.9024) (xy 35.6235 -288.912554) (xy 35.6235 -289.321494) (xy 41.664636 -289.321494)
			(xy 41.664636 -288.912554) (xy 41.665096 -288.902394) (xy 41.672885 -288.883624) (xy 41.687261 -288.86926)
			(xy 41.706037 -288.861487) (xy 41.716198 -288.860992) (xy 43.115738 -288.860992) (xy 43.125893 -288.861501)
			(xy 43.144654 -288.869279) (xy 43.159016 -288.88364) (xy 43.166797 -288.9024) (xy 43.1673 -288.912554)
			(xy 43.1673 -289.321494) (xy 49.208436 -289.321494) (xy 49.208436 -288.912554) (xy 49.208896 -288.902394)
			(xy 49.216685 -288.883624) (xy 49.231061 -288.86926) (xy 49.249837 -288.861487) (xy 49.259998 -288.860992)
			(xy 50.659538 -288.860992) (xy 50.669693 -288.861501) (xy 50.688454 -288.869279) (xy 50.702816 -288.88364)
			(xy 50.710597 -288.9024) (xy 50.7111 -288.912554) (xy 50.7111 -289.321494) (xy 56.752236 -289.321494)
			(xy 56.752236 -288.912554) (xy 56.752696 -288.902394) (xy 56.760485 -288.883624) (xy 56.774861 -288.86926)
			(xy 56.793637 -288.861487) (xy 56.803798 -288.860992) (xy 58.203338 -288.860992) (xy 58.213493 -288.861501)
			(xy 58.232254 -288.869279) (xy 58.246616 -288.88364) (xy 58.254397 -288.9024) (xy 58.2549 -288.912554)
			(xy 58.2549 -289.321494) (xy 64.296036 -289.321494) (xy 64.296036 -288.912554) (xy 64.296496 -288.902394)
			(xy 64.304285 -288.883624) (xy 64.318661 -288.86926) (xy 64.337437 -288.861487) (xy 64.347598 -288.860992)
			(xy 65.747138 -288.860992) (xy 65.757293 -288.861501) (xy 65.776054 -288.869279) (xy 65.790416 -288.88364)
			(xy 65.798197 -288.9024) (xy 65.7987 -288.912554) (xy 65.7987 -288.917126) (xy 88.395556 -288.917126)
			(xy 88.396056 -288.891781) (xy 88.403825 -288.84169) (xy 88.419169 -288.793377) (xy 88.441727 -288.747983)
			(xy 88.470967 -288.706576) (xy 88.506199 -288.670131) (xy 88.546595 -288.639509) (xy 88.591201 -288.61543)
			(xy 88.638966 -288.598461) (xy 88.66378 -288.593276) (xy 88.68664 -288.588958) (xy 88.891618 -288.233866)
			(xy 88.883744 -288.212022) (xy 88.875171 -288.185601) (xy 88.86597 -288.130828) (xy 88.865456 -288.103056)
			(xy 88.865964 -288.077169) (xy 88.874063 -288.026031) (xy 88.890062 -287.976791) (xy 88.913568 -287.930659)
			(xy 88.944 -287.888772) (xy 88.98061 -287.852162) (xy 89.022497 -287.82173) (xy 89.068629 -287.798224)
			(xy 89.117869 -287.782225) (xy 89.169007 -287.774126) (xy 89.220781 -287.774126) (xy 89.271919 -287.782225)
			(xy 89.321159 -287.798224) (xy 89.367291 -287.82173) (xy 89.409178 -287.852162) (xy 89.445788 -287.888772)
			(xy 89.47622 -287.930659) (xy 89.499726 -287.976791) (xy 89.515725 -288.026031) (xy 89.523824 -288.077169)
			(xy 89.524332 -288.103056) (xy 89.523874 -288.128391) (xy 89.516115 -288.178463) (xy 89.500786 -288.226759)
			(xy 89.47825 -288.272141) (xy 89.449037 -288.313542) (xy 89.413835 -288.349987) (xy 89.373471 -288.380617)
			(xy 89.328897 -288.404713) (xy 89.281162 -288.421706) (xy 89.256362 -288.426906) (xy 89.233502 -288.431224)
			(xy 89.028524 -288.786316) (xy 89.036398 -288.80816) (xy 89.045049 -288.834567) (xy 89.054366 -288.889344)
			(xy 89.05494 -288.917126) (xy 90.275156 -288.917126) (xy 90.275656 -288.891781) (xy 90.283425 -288.84169)
			(xy 90.298769 -288.793377) (xy 90.321327 -288.747983) (xy 90.350567 -288.706576) (xy 90.385799 -288.670131)
			(xy 90.426195 -288.639509) (xy 90.470801 -288.61543) (xy 90.518566 -288.598461) (xy 90.54338 -288.593276)
			(xy 90.56624 -288.588958) (xy 90.771218 -288.233866) (xy 90.763344 -288.212022) (xy 90.754771 -288.185601)
			(xy 90.74557 -288.130828) (xy 90.745056 -288.103056) (xy 90.745564 -288.077169) (xy 90.753663 -288.026031)
			(xy 90.769662 -287.976791) (xy 90.793168 -287.930659) (xy 90.8236 -287.888772) (xy 90.86021 -287.852162)
			(xy 90.902097 -287.82173) (xy 90.948229 -287.798224) (xy 90.997469 -287.782225) (xy 91.048607 -287.774126)
			(xy 91.100381 -287.774126) (xy 91.151519 -287.782225) (xy 91.200759 -287.798224) (xy 91.246891 -287.82173)
			(xy 91.288778 -287.852162) (xy 91.325388 -287.888772) (xy 91.35582 -287.930659) (xy 91.379326 -287.976791)
			(xy 91.395325 -288.026031) (xy 91.403424 -288.077169) (xy 91.403932 -288.103056) (xy 91.403474 -288.128391)
			(xy 91.395715 -288.178463) (xy 91.380386 -288.226759) (xy 91.35785 -288.272141) (xy 91.328637 -288.313542)
			(xy 91.293435 -288.349987) (xy 91.253071 -288.380617) (xy 91.208497 -288.404713) (xy 91.160762 -288.421706)
			(xy 91.135962 -288.426906) (xy 91.113102 -288.431224) (xy 90.908124 -288.786316) (xy 90.915998 -288.80816)
			(xy 90.924649 -288.834567) (xy 90.933966 -288.889344) (xy 90.93454 -288.917126) (xy 91.214956 -288.917126)
			(xy 91.215464 -288.891219) (xy 91.22357 -288.840042) (xy 91.239582 -288.790763) (xy 91.263105 -288.744596)
			(xy 91.293561 -288.702677) (xy 91.330199 -288.666039) (xy 91.372118 -288.635583) (xy 91.418285 -288.61206)
			(xy 91.467564 -288.596048) (xy 91.518741 -288.587942) (xy 91.570555 -288.587942) (xy 91.621732 -288.596048)
			(xy 91.671011 -288.61206) (xy 91.717178 -288.635583) (xy 91.759097 -288.666039) (xy 91.795735 -288.702677)
			(xy 91.826191 -288.744596) (xy 91.849714 -288.790763) (xy 91.865726 -288.840042) (xy 91.873832 -288.891219)
			(xy 91.87434 -288.917126) (xy 92.154756 -288.917126) (xy 92.155256 -288.891781) (xy 92.163025 -288.84169)
			(xy 92.178369 -288.793377) (xy 92.200927 -288.747983) (xy 92.230167 -288.706576) (xy 92.265399 -288.670131)
			(xy 92.305795 -288.639509) (xy 92.350401 -288.61543) (xy 92.398166 -288.598461) (xy 92.42298 -288.593276)
			(xy 92.44584 -288.588958) (xy 92.651072 -288.233866) (xy 92.643198 -288.211768) (xy 92.634576 -288.185419)
			(xy 92.625249 -288.130773) (xy 92.624656 -288.103056) (xy 92.625164 -288.077149) (xy 92.63327 -288.025972)
			(xy 92.649282 -287.976693) (xy 92.672805 -287.930526) (xy 92.703261 -287.888607) (xy 92.739899 -287.851969)
			(xy 92.781818 -287.821513) (xy 92.827985 -287.79799) (xy 92.877264 -287.781978) (xy 92.928441 -287.773872)
			(xy 92.980255 -287.773872) (xy 93.031432 -287.781978) (xy 93.080711 -287.79799) (xy 93.126878 -287.821513)
			(xy 93.168797 -287.851969) (xy 93.205435 -287.888607) (xy 93.235891 -287.930526) (xy 93.259414 -287.976693)
			(xy 93.275426 -288.025972) (xy 93.283532 -288.077149) (xy 93.28404 -288.103056) (xy 93.283618 -288.128404)
			(xy 93.275836 -288.178499) (xy 93.26048 -288.226813) (xy 93.237912 -288.272208) (xy 93.208662 -288.313614)
			(xy 93.173421 -288.350057) (xy 93.133018 -288.380678) (xy 93.088405 -288.404755) (xy 93.040632 -288.421722)
			(xy 93.015816 -288.426906) (xy 92.992956 -288.431224) (xy 92.787724 -288.786316) (xy 92.795598 -288.808414)
			(xy 92.80424 -288.834757) (xy 92.813554 -288.889407) (xy 92.81414 -288.917126) (xy 93.094556 -288.917126)
			(xy 93.095064 -288.891219) (xy 93.10317 -288.840042) (xy 93.119182 -288.790763) (xy 93.142705 -288.744596)
			(xy 93.173161 -288.702677) (xy 93.209799 -288.666039) (xy 93.251718 -288.635583) (xy 93.297885 -288.61206)
			(xy 93.347164 -288.596048) (xy 93.398341 -288.587942) (xy 93.450155 -288.587942) (xy 93.501332 -288.596048)
			(xy 93.550611 -288.61206) (xy 93.596778 -288.635583) (xy 93.638697 -288.666039) (xy 93.675335 -288.702677)
			(xy 93.705791 -288.744596) (xy 93.729314 -288.790763) (xy 93.745326 -288.840042) (xy 93.753432 -288.891219)
			(xy 93.75394 -288.917126) (xy 94.034356 -288.917126) (xy 94.034856 -288.891781) (xy 94.042625 -288.84169)
			(xy 94.057969 -288.793377) (xy 94.080527 -288.747983) (xy 94.109767 -288.706576) (xy 94.144999 -288.670131)
			(xy 94.185395 -288.639509) (xy 94.230001 -288.61543) (xy 94.277766 -288.598461) (xy 94.30258 -288.593276)
			(xy 94.32544 -288.588958) (xy 94.530672 -288.233866) (xy 94.522798 -288.211768) (xy 94.514176 -288.185419)
			(xy 94.504849 -288.130773) (xy 94.504256 -288.103056) (xy 94.504764 -288.077149) (xy 94.51287 -288.025972)
			(xy 94.528882 -287.976693) (xy 94.552405 -287.930526) (xy 94.582861 -287.888607) (xy 94.619499 -287.851969)
			(xy 94.661418 -287.821513) (xy 94.707585 -287.79799) (xy 94.756864 -287.781978) (xy 94.808041 -287.773872)
			(xy 94.859855 -287.773872) (xy 94.911032 -287.781978) (xy 94.960311 -287.79799) (xy 95.006478 -287.821513)
			(xy 95.048397 -287.851969) (xy 95.085035 -287.888607) (xy 95.115491 -287.930526) (xy 95.139014 -287.976693)
			(xy 95.155026 -288.025972) (xy 95.163132 -288.077149) (xy 95.16364 -288.103056) (xy 95.163218 -288.128404)
			(xy 95.155436 -288.178499) (xy 95.14008 -288.226813) (xy 95.117512 -288.272208) (xy 95.088262 -288.313614)
			(xy 95.053021 -288.350057) (xy 95.012618 -288.380678) (xy 94.968005 -288.404755) (xy 94.920232 -288.421722)
			(xy 94.895416 -288.426906) (xy 94.872556 -288.431224) (xy 94.667324 -288.786316) (xy 94.675198 -288.808414)
			(xy 94.68384 -288.834757) (xy 94.693154 -288.889407) (xy 94.69374 -288.917126) (xy 94.974156 -288.917126)
			(xy 94.974664 -288.891219) (xy 94.98277 -288.840042) (xy 94.998782 -288.790763) (xy 95.022305 -288.744596)
			(xy 95.052761 -288.702677) (xy 95.089399 -288.666039) (xy 95.131318 -288.635583) (xy 95.177485 -288.61206)
			(xy 95.226764 -288.596048) (xy 95.277941 -288.587942) (xy 95.329755 -288.587942) (xy 95.380932 -288.596048)
			(xy 95.430211 -288.61206) (xy 95.476378 -288.635583) (xy 95.518297 -288.666039) (xy 95.554935 -288.702677)
			(xy 95.585391 -288.744596) (xy 95.608914 -288.790763) (xy 95.624926 -288.840042) (xy 95.633032 -288.891219)
			(xy 95.63354 -288.917126) (xy 95.913956 -288.917126) (xy 95.914456 -288.891781) (xy 95.922225 -288.84169)
			(xy 95.937569 -288.793377) (xy 95.960127 -288.747983) (xy 95.989367 -288.706576) (xy 96.024599 -288.670131)
			(xy 96.064995 -288.639509) (xy 96.109601 -288.61543) (xy 96.157366 -288.598461) (xy 96.18218 -288.593276)
			(xy 96.20504 -288.588958) (xy 96.410272 -288.233866) (xy 96.402398 -288.211768) (xy 96.393776 -288.185419)
			(xy 96.384449 -288.130773) (xy 96.383856 -288.103056) (xy 96.384364 -288.077149) (xy 96.39247 -288.025972)
			(xy 96.408482 -287.976693) (xy 96.432005 -287.930526) (xy 96.462461 -287.888607) (xy 96.499099 -287.851969)
			(xy 96.541018 -287.821513) (xy 96.587185 -287.79799) (xy 96.636464 -287.781978) (xy 96.687641 -287.773872)
			(xy 96.739455 -287.773872) (xy 96.790632 -287.781978) (xy 96.839911 -287.79799) (xy 96.886078 -287.821513)
			(xy 96.927997 -287.851969) (xy 96.964635 -287.888607) (xy 96.995091 -287.930526) (xy 97.018614 -287.976693)
			(xy 97.034626 -288.025972) (xy 97.042732 -288.077149) (xy 97.04324 -288.103056) (xy 97.042818 -288.128404)
			(xy 97.035036 -288.178499) (xy 97.01968 -288.226813) (xy 96.997112 -288.272208) (xy 96.967862 -288.313614)
			(xy 96.932621 -288.350057) (xy 96.892218 -288.380678) (xy 96.847605 -288.404755) (xy 96.799832 -288.421722)
			(xy 96.775016 -288.426906) (xy 96.752156 -288.431224) (xy 96.546924 -288.786316) (xy 96.554798 -288.808414)
			(xy 96.56344 -288.834757) (xy 96.572754 -288.889407) (xy 96.57334 -288.917126) (xy 96.853756 -288.917126)
			(xy 96.854264 -288.891219) (xy 96.86237 -288.840042) (xy 96.878382 -288.790763) (xy 96.901905 -288.744596)
			(xy 96.932361 -288.702677) (xy 96.968999 -288.666039) (xy 97.010918 -288.635583) (xy 97.057085 -288.61206)
			(xy 97.106364 -288.596048) (xy 97.157541 -288.587942) (xy 97.209355 -288.587942) (xy 97.260532 -288.596048)
			(xy 97.309811 -288.61206) (xy 97.355978 -288.635583) (xy 97.397897 -288.666039) (xy 97.434535 -288.702677)
			(xy 97.464991 -288.744596) (xy 97.488514 -288.790763) (xy 97.504526 -288.840042) (xy 97.512632 -288.891219)
			(xy 97.51314 -288.917126) (xy 97.793556 -288.917126) (xy 97.794056 -288.891781) (xy 97.801825 -288.84169)
			(xy 97.817169 -288.793377) (xy 97.839727 -288.747983) (xy 97.868967 -288.706576) (xy 97.904199 -288.670131)
			(xy 97.944595 -288.639509) (xy 97.989201 -288.61543) (xy 98.036966 -288.598461) (xy 98.06178 -288.593276)
			(xy 98.08464 -288.588958) (xy 98.289872 -288.233866) (xy 98.281998 -288.211768) (xy 98.273376 -288.185419)
			(xy 98.264049 -288.130773) (xy 98.263456 -288.103056) (xy 98.263964 -288.077149) (xy 98.27207 -288.025972)
			(xy 98.288082 -287.976693) (xy 98.311605 -287.930526) (xy 98.342061 -287.888607) (xy 98.378699 -287.851969)
			(xy 98.420618 -287.821513) (xy 98.466785 -287.79799) (xy 98.516064 -287.781978) (xy 98.567241 -287.773872)
			(xy 98.619055 -287.773872) (xy 98.670232 -287.781978) (xy 98.719511 -287.79799) (xy 98.765678 -287.821513)
			(xy 98.807597 -287.851969) (xy 98.844235 -287.888607) (xy 98.874691 -287.930526) (xy 98.898214 -287.976693)
			(xy 98.914226 -288.025972) (xy 98.922332 -288.077149) (xy 98.92284 -288.103056) (xy 98.922418 -288.128404)
			(xy 98.914636 -288.178499) (xy 98.89928 -288.226813) (xy 98.876712 -288.272208) (xy 98.847462 -288.313614)
			(xy 98.812221 -288.350057) (xy 98.771818 -288.380678) (xy 98.727205 -288.404755) (xy 98.679432 -288.421722)
			(xy 98.654616 -288.426906) (xy 98.631756 -288.431224) (xy 98.426524 -288.786316) (xy 98.434398 -288.808414)
			(xy 98.44304 -288.834757) (xy 98.452354 -288.889407) (xy 98.45294 -288.917126) (xy 98.733356 -288.917126)
			(xy 98.733864 -288.891219) (xy 98.74197 -288.840042) (xy 98.757982 -288.790763) (xy 98.781505 -288.744596)
			(xy 98.811961 -288.702677) (xy 98.848599 -288.666039) (xy 98.890518 -288.635583) (xy 98.936685 -288.61206)
			(xy 98.985964 -288.596048) (xy 99.037141 -288.587942) (xy 99.088955 -288.587942) (xy 99.140132 -288.596048)
			(xy 99.189411 -288.61206) (xy 99.235578 -288.635583) (xy 99.277497 -288.666039) (xy 99.314135 -288.702677)
			(xy 99.344591 -288.744596) (xy 99.368114 -288.790763) (xy 99.384126 -288.840042) (xy 99.392232 -288.891219)
			(xy 99.39274 -288.917126) (xy 99.673156 -288.917126) (xy 99.673656 -288.891781) (xy 99.681425 -288.84169)
			(xy 99.696769 -288.793377) (xy 99.719327 -288.747983) (xy 99.748567 -288.706576) (xy 99.783799 -288.670131)
			(xy 99.824195 -288.639509) (xy 99.868801 -288.61543) (xy 99.916566 -288.598461) (xy 99.94138 -288.593276)
			(xy 99.96424 -288.588958) (xy 100.169472 -288.233866) (xy 100.161598 -288.211768) (xy 100.152976 -288.185419)
			(xy 100.143649 -288.130773) (xy 100.143056 -288.103056) (xy 100.143564 -288.077149) (xy 100.15167 -288.025972)
			(xy 100.167682 -287.976693) (xy 100.191205 -287.930526) (xy 100.221661 -287.888607) (xy 100.258299 -287.851969)
			(xy 100.300218 -287.821513) (xy 100.346385 -287.79799) (xy 100.395664 -287.781978) (xy 100.446841 -287.773872)
			(xy 100.498655 -287.773872) (xy 100.549832 -287.781978) (xy 100.599111 -287.79799) (xy 100.645278 -287.821513)
			(xy 100.687197 -287.851969) (xy 100.723835 -287.888607) (xy 100.754291 -287.930526) (xy 100.777814 -287.976693)
			(xy 100.793826 -288.025972) (xy 100.801932 -288.077149) (xy 100.80244 -288.103056) (xy 100.802018 -288.128404)
			(xy 100.794236 -288.178499) (xy 100.77888 -288.226813) (xy 100.756312 -288.272208) (xy 100.727062 -288.313614)
			(xy 100.691821 -288.350057) (xy 100.651418 -288.380678) (xy 100.606805 -288.404755) (xy 100.559032 -288.421722)
			(xy 100.534216 -288.426906) (xy 100.511356 -288.431224) (xy 100.306124 -288.786316) (xy 100.313998 -288.808414)
			(xy 100.32264 -288.834757) (xy 100.331954 -288.889407) (xy 100.33254 -288.917126) (xy 100.612956 -288.917126)
			(xy 100.613464 -288.891219) (xy 100.62157 -288.840042) (xy 100.637582 -288.790763) (xy 100.661105 -288.744596)
			(xy 100.691561 -288.702677) (xy 100.728199 -288.666039) (xy 100.770118 -288.635583) (xy 100.816285 -288.61206)
			(xy 100.865564 -288.596048) (xy 100.916741 -288.587942) (xy 100.968555 -288.587942) (xy 101.019732 -288.596048)
			(xy 101.069011 -288.61206) (xy 101.115178 -288.635583) (xy 101.157097 -288.666039) (xy 101.193735 -288.702677)
			(xy 101.224191 -288.744596) (xy 101.247714 -288.790763) (xy 101.263726 -288.840042) (xy 101.271832 -288.891219)
			(xy 101.27234 -288.917126) (xy 101.552756 -288.917126) (xy 101.553256 -288.891781) (xy 101.561025 -288.84169)
			(xy 101.576369 -288.793377) (xy 101.598927 -288.747983) (xy 101.628167 -288.706576) (xy 101.663399 -288.670131)
			(xy 101.703795 -288.639509) (xy 101.748401 -288.61543) (xy 101.796166 -288.598461) (xy 101.82098 -288.593276)
			(xy 101.84384 -288.588958) (xy 102.049072 -288.233866) (xy 102.041198 -288.211768) (xy 102.032576 -288.185419)
			(xy 102.023249 -288.130773) (xy 102.022656 -288.103056) (xy 102.023164 -288.077149) (xy 102.03127 -288.025972)
			(xy 102.047282 -287.976693) (xy 102.070805 -287.930526) (xy 102.101261 -287.888607) (xy 102.137899 -287.851969)
			(xy 102.179818 -287.821513) (xy 102.225985 -287.79799) (xy 102.275264 -287.781978) (xy 102.326441 -287.773872)
			(xy 102.378255 -287.773872) (xy 102.429432 -287.781978) (xy 102.478711 -287.79799) (xy 102.524878 -287.821513)
			(xy 102.566797 -287.851969) (xy 102.603435 -287.888607) (xy 102.633891 -287.930526) (xy 102.657414 -287.976693)
			(xy 102.673426 -288.025972) (xy 102.681532 -288.077149) (xy 102.68204 -288.103056) (xy 102.681618 -288.128404)
			(xy 102.673836 -288.178499) (xy 102.65848 -288.226813) (xy 102.635912 -288.272208) (xy 102.606662 -288.313614)
			(xy 102.571421 -288.350057) (xy 102.531018 -288.380678) (xy 102.486405 -288.404755) (xy 102.438632 -288.421722)
			(xy 102.413816 -288.426906) (xy 102.390956 -288.431224) (xy 102.185724 -288.786316) (xy 102.193598 -288.808414)
			(xy 102.20224 -288.834757) (xy 102.211554 -288.889407) (xy 102.21214 -288.917126) (xy 102.492556 -288.917126)
			(xy 102.493064 -288.891219) (xy 102.50117 -288.840042) (xy 102.517182 -288.790763) (xy 102.540705 -288.744596)
			(xy 102.571161 -288.702677) (xy 102.607799 -288.666039) (xy 102.649718 -288.635583) (xy 102.695885 -288.61206)
			(xy 102.745164 -288.596048) (xy 102.796341 -288.587942) (xy 102.848155 -288.587942) (xy 102.899332 -288.596048)
			(xy 102.948611 -288.61206) (xy 102.994778 -288.635583) (xy 103.036697 -288.666039) (xy 103.073335 -288.702677)
			(xy 103.103791 -288.744596) (xy 103.127314 -288.790763) (xy 103.143326 -288.840042) (xy 103.151432 -288.891219)
			(xy 103.15194 -288.917126) (xy 103.432356 -288.917126) (xy 103.432856 -288.891781) (xy 103.440625 -288.84169)
			(xy 103.455969 -288.793377) (xy 103.478527 -288.747983) (xy 103.507767 -288.706576) (xy 103.542999 -288.670131)
			(xy 103.583395 -288.639509) (xy 103.628001 -288.61543) (xy 103.675766 -288.598461) (xy 103.70058 -288.593276)
			(xy 103.72344 -288.588958) (xy 103.928672 -288.233866) (xy 103.920798 -288.211768) (xy 103.912176 -288.185419)
			(xy 103.902849 -288.130773) (xy 103.902256 -288.103056) (xy 103.902764 -288.077149) (xy 103.91087 -288.025972)
			(xy 103.926882 -287.976693) (xy 103.950405 -287.930526) (xy 103.980861 -287.888607) (xy 104.017499 -287.851969)
			(xy 104.059418 -287.821513) (xy 104.105585 -287.79799) (xy 104.154864 -287.781978) (xy 104.206041 -287.773872)
			(xy 104.257855 -287.773872) (xy 104.309032 -287.781978) (xy 104.358311 -287.79799) (xy 104.404478 -287.821513)
			(xy 104.446397 -287.851969) (xy 104.483035 -287.888607) (xy 104.513491 -287.930526) (xy 104.537014 -287.976693)
			(xy 104.553026 -288.025972) (xy 104.561132 -288.077149) (xy 104.56164 -288.103056) (xy 120.818656 -288.103056)
			(xy 120.819164 -288.077149) (xy 120.82727 -288.025972) (xy 120.843282 -287.976693) (xy 120.866805 -287.930526)
			(xy 120.897261 -287.888607) (xy 120.933899 -287.851969) (xy 120.975818 -287.821513) (xy 121.021985 -287.79799)
			(xy 121.071264 -287.781978) (xy 121.122441 -287.773872) (xy 121.174255 -287.773872) (xy 121.225432 -287.781978)
			(xy 121.274711 -287.79799) (xy 121.320878 -287.821513) (xy 121.362797 -287.851969) (xy 121.399435 -287.888607)
			(xy 121.429891 -287.930526) (xy 121.453414 -287.976693) (xy 121.469426 -288.025972) (xy 121.477532 -288.077149)
			(xy 121.47804 -288.103056) (xy 122.698256 -288.103056) (xy 122.698764 -288.077149) (xy 122.70687 -288.025972)
			(xy 122.722882 -287.976693) (xy 122.746405 -287.930526) (xy 122.776861 -287.888607) (xy 122.813499 -287.851969)
			(xy 122.855418 -287.821513) (xy 122.901585 -287.79799) (xy 122.950864 -287.781978) (xy 123.002041 -287.773872)
			(xy 123.053855 -287.773872) (xy 123.105032 -287.781978) (xy 123.154311 -287.79799) (xy 123.200478 -287.821513)
			(xy 123.242397 -287.851969) (xy 123.279035 -287.888607) (xy 123.309491 -287.930526) (xy 123.333014 -287.976693)
			(xy 123.349026 -288.025972) (xy 123.357132 -288.077149) (xy 123.35764 -288.103056) (xy 124.577856 -288.103056)
			(xy 124.578364 -288.077149) (xy 124.58647 -288.025972) (xy 124.602482 -287.976693) (xy 124.626005 -287.930526)
			(xy 124.656461 -287.888607) (xy 124.693099 -287.851969) (xy 124.735018 -287.821513) (xy 124.781185 -287.79799)
			(xy 124.830464 -287.781978) (xy 124.881641 -287.773872) (xy 124.933455 -287.773872) (xy 124.984632 -287.781978)
			(xy 125.033911 -287.79799) (xy 125.080078 -287.821513) (xy 125.121997 -287.851969) (xy 125.158635 -287.888607)
			(xy 125.189091 -287.930526) (xy 125.212614 -287.976693) (xy 125.228626 -288.025972) (xy 125.236732 -288.077149)
			(xy 125.23724 -288.103056) (xy 126.457456 -288.103056) (xy 126.457964 -288.077149) (xy 126.46607 -288.025972)
			(xy 126.482082 -287.976693) (xy 126.505605 -287.930526) (xy 126.536061 -287.888607) (xy 126.572699 -287.851969)
			(xy 126.614618 -287.821513) (xy 126.660785 -287.79799) (xy 126.710064 -287.781978) (xy 126.761241 -287.773872)
			(xy 126.813055 -287.773872) (xy 126.864232 -287.781978) (xy 126.913511 -287.79799) (xy 126.959678 -287.821513)
			(xy 127.001597 -287.851969) (xy 127.038235 -287.888607) (xy 127.068691 -287.930526) (xy 127.092214 -287.976693)
			(xy 127.108226 -288.025972) (xy 127.116332 -288.077149) (xy 127.11684 -288.103056) (xy 128.337056 -288.103056)
			(xy 128.337564 -288.077149) (xy 128.34567 -288.025972) (xy 128.361682 -287.976693) (xy 128.385205 -287.930526)
			(xy 128.415661 -287.888607) (xy 128.452299 -287.851969) (xy 128.494218 -287.821513) (xy 128.540385 -287.79799)
			(xy 128.589664 -287.781978) (xy 128.640841 -287.773872) (xy 128.692655 -287.773872) (xy 128.743832 -287.781978)
			(xy 128.793111 -287.79799) (xy 128.839278 -287.821513) (xy 128.881197 -287.851969) (xy 128.917835 -287.888607)
			(xy 128.948291 -287.930526) (xy 128.971814 -287.976693) (xy 128.987826 -288.025972) (xy 128.995932 -288.077149)
			(xy 128.99644 -288.103056) (xy 130.216656 -288.103056) (xy 130.217164 -288.077149) (xy 130.22527 -288.025972)
			(xy 130.241282 -287.976693) (xy 130.264805 -287.930526) (xy 130.295261 -287.888607) (xy 130.331899 -287.851969)
			(xy 130.373818 -287.821513) (xy 130.419985 -287.79799) (xy 130.469264 -287.781978) (xy 130.520441 -287.773872)
			(xy 130.572255 -287.773872) (xy 130.623432 -287.781978) (xy 130.672711 -287.79799) (xy 130.718878 -287.821513)
			(xy 130.760797 -287.851969) (xy 130.797435 -287.888607) (xy 130.827891 -287.930526) (xy 130.851414 -287.976693)
			(xy 130.867426 -288.025972) (xy 130.875532 -288.077149) (xy 130.87604 -288.103056) (xy 132.096256 -288.103056)
			(xy 132.096764 -288.077149) (xy 132.10487 -288.025972) (xy 132.120882 -287.976693) (xy 132.144405 -287.930526)
			(xy 132.174861 -287.888607) (xy 132.211499 -287.851969) (xy 132.253418 -287.821513) (xy 132.299585 -287.79799)
			(xy 132.348864 -287.781978) (xy 132.400041 -287.773872) (xy 132.451855 -287.773872) (xy 132.503032 -287.781978)
			(xy 132.552311 -287.79799) (xy 132.598478 -287.821513) (xy 132.640397 -287.851969) (xy 132.677035 -287.888607)
			(xy 132.707491 -287.930526) (xy 132.731014 -287.976693) (xy 132.747026 -288.025972) (xy 132.755132 -288.077149)
			(xy 132.75564 -288.103056) (xy 134.915656 -288.103056) (xy 134.916164 -288.077149) (xy 134.92427 -288.025972)
			(xy 134.940282 -287.976693) (xy 134.963805 -287.930526) (xy 134.994261 -287.888607) (xy 135.030899 -287.851969)
			(xy 135.072818 -287.821513) (xy 135.118985 -287.79799) (xy 135.168264 -287.781978) (xy 135.219441 -287.773872)
			(xy 135.271255 -287.773872) (xy 135.322432 -287.781978) (xy 135.371711 -287.79799) (xy 135.417878 -287.821513)
			(xy 135.459797 -287.851969) (xy 135.496435 -287.888607) (xy 135.526891 -287.930526) (xy 135.550414 -287.976693)
			(xy 135.566426 -288.025972) (xy 135.574532 -288.077149) (xy 135.57504 -288.103056) (xy 135.574438 -288.130773)
			(xy 135.56512 -288.18542) (xy 135.556498 -288.211768) (xy 135.548624 -288.233866) (xy 135.685886 -288.471356)
			(xy 158.062168 -288.471356) (xy 158.062168 -288.062416) (xy 158.062634 -288.052267) (xy 158.070418 -288.033521)
			(xy 158.084801 -288.019198) (xy 158.103579 -288.011492) (xy 158.11373 -288.011108) (xy 159.51327 -288.011108)
			(xy 159.523391 -288.01165) (xy 159.542105 -288.019362) (xy 159.556462 -288.033631) (xy 159.564288 -288.052298)
			(xy 159.564832 -288.062416) (xy 159.564832 -288.471356) (xy 165.605968 -288.471356) (xy 165.605968 -288.062416)
			(xy 165.606434 -288.052267) (xy 165.614218 -288.033521) (xy 165.628601 -288.019198) (xy 165.647379 -288.011492)
			(xy 165.65753 -288.011108) (xy 167.05707 -288.011108) (xy 167.067191 -288.01165) (xy 167.085905 -288.019362)
			(xy 167.100262 -288.033631) (xy 167.108088 -288.052298) (xy 167.108632 -288.062416) (xy 167.108632 -288.471356)
			(xy 173.149768 -288.471356) (xy 173.149768 -288.062416) (xy 173.150234 -288.052267) (xy 173.158018 -288.033521)
			(xy 173.172401 -288.019198) (xy 173.191179 -288.011492) (xy 173.20133 -288.011108) (xy 174.60087 -288.011108)
			(xy 174.610991 -288.01165) (xy 174.629705 -288.019362) (xy 174.644062 -288.033631) (xy 174.651888 -288.052298)
			(xy 174.652432 -288.062416) (xy 174.652432 -288.471356) (xy 180.693568 -288.471356) (xy 180.693568 -288.062416)
			(xy 180.694034 -288.052267) (xy 180.701818 -288.033521) (xy 180.716201 -288.019198) (xy 180.734979 -288.011492)
			(xy 180.74513 -288.011108) (xy 182.14467 -288.011108) (xy 182.154791 -288.01165) (xy 182.173505 -288.019362)
			(xy 182.187862 -288.033631) (xy 182.195688 -288.052298) (xy 182.196232 -288.062416) (xy 182.196232 -288.471356)
			(xy 188.237368 -288.471356) (xy 188.237368 -288.062416) (xy 188.237834 -288.052267) (xy 188.245618 -288.033521)
			(xy 188.260001 -288.019198) (xy 188.278779 -288.011492) (xy 188.28893 -288.011108) (xy 189.68847 -288.011108)
			(xy 189.698591 -288.01165) (xy 189.717305 -288.019362) (xy 189.731662 -288.033631) (xy 189.739488 -288.052298)
			(xy 189.740032 -288.062416) (xy 189.740032 -288.471356) (xy 195.781168 -288.471356) (xy 195.781168 -288.062416)
			(xy 195.781634 -288.052267) (xy 195.789418 -288.033521) (xy 195.803801 -288.019198) (xy 195.822579 -288.011492)
			(xy 195.83273 -288.011108) (xy 197.23227 -288.011108) (xy 197.242391 -288.01165) (xy 197.261105 -288.019362)
			(xy 197.275462 -288.033631) (xy 197.283288 -288.052298) (xy 197.283832 -288.062416) (xy 197.283832 -288.471356)
			(xy 203.324968 -288.471356) (xy 203.324968 -288.062416) (xy 203.325434 -288.052267) (xy 203.333218 -288.033521)
			(xy 203.347601 -288.019198) (xy 203.366379 -288.011492) (xy 203.37653 -288.011108) (xy 204.77607 -288.011108)
			(xy 204.786191 -288.01165) (xy 204.804905 -288.019362) (xy 204.819262 -288.033631) (xy 204.827088 -288.052298)
			(xy 204.827632 -288.062416) (xy 204.827632 -288.471356) (xy 210.868768 -288.471356) (xy 210.868768 -288.062416)
			(xy 210.869234 -288.052267) (xy 210.877018 -288.033521) (xy 210.891401 -288.019198) (xy 210.910179 -288.011492)
			(xy 210.92033 -288.011108) (xy 212.31987 -288.011108) (xy 212.329991 -288.01165) (xy 212.348705 -288.019362)
			(xy 212.363062 -288.033631) (xy 212.370888 -288.052298) (xy 212.371432 -288.062416) (xy 212.371432 -288.471356)
			(xy 255.329436 -288.471356) (xy 255.329436 -288.062416) (xy 255.329835 -288.052258) (xy 255.337632 -288.033499)
			(xy 255.352037 -288.019174) (xy 255.370838 -288.01148) (xy 255.380998 -288.011108) (xy 256.780538 -288.011108)
			(xy 256.790663 -288.011594) (xy 256.809379 -288.019329) (xy 256.823733 -288.033614) (xy 256.831556 -288.052293)
			(xy 256.8321 -288.062416) (xy 256.8321 -288.471356) (xy 262.873236 -288.471356) (xy 262.873236 -288.062416)
			(xy 262.873635 -288.052258) (xy 262.881432 -288.033499) (xy 262.895837 -288.019174) (xy 262.914638 -288.01148)
			(xy 262.924798 -288.011108) (xy 264.324338 -288.011108) (xy 264.334463 -288.011594) (xy 264.353179 -288.019329)
			(xy 264.367533 -288.033614) (xy 264.375356 -288.052293) (xy 264.3759 -288.062416) (xy 264.3759 -288.471356)
			(xy 270.417036 -288.471356) (xy 270.417036 -288.062416) (xy 270.417435 -288.052258) (xy 270.425232 -288.033499)
			(xy 270.439637 -288.019174) (xy 270.458438 -288.01148) (xy 270.468598 -288.011108) (xy 271.868138 -288.011108)
			(xy 271.878263 -288.011594) (xy 271.896979 -288.019329) (xy 271.911333 -288.033614) (xy 271.919156 -288.052293)
			(xy 271.9197 -288.062416) (xy 271.9197 -288.471356) (xy 277.960836 -288.471356) (xy 277.960836 -288.062416)
			(xy 277.961235 -288.052258) (xy 277.969032 -288.033499) (xy 277.983437 -288.019174) (xy 278.002238 -288.01148)
			(xy 278.012398 -288.011108) (xy 279.411938 -288.011108) (xy 279.422063 -288.011594) (xy 279.440779 -288.019329)
			(xy 279.455133 -288.033614) (xy 279.462956 -288.052293) (xy 279.4635 -288.062416) (xy 279.4635 -288.471356)
			(xy 285.504636 -288.471356) (xy 285.504636 -288.062416) (xy 285.505035 -288.052258) (xy 285.512832 -288.033499)
			(xy 285.527237 -288.019174) (xy 285.546038 -288.01148) (xy 285.556198 -288.011108) (xy 286.955738 -288.011108)
			(xy 286.965863 -288.011594) (xy 286.984579 -288.019329) (xy 286.998933 -288.033614) (xy 287.006756 -288.052293)
			(xy 287.0073 -288.062416) (xy 287.0073 -288.471356) (xy 293.048436 -288.471356) (xy 293.048436 -288.062416)
			(xy 293.048835 -288.052258) (xy 293.056632 -288.033499) (xy 293.071037 -288.019174) (xy 293.089838 -288.01148)
			(xy 293.099998 -288.011108) (xy 294.499538 -288.011108) (xy 294.509663 -288.011594) (xy 294.528379 -288.019329)
			(xy 294.542733 -288.033614) (xy 294.550556 -288.052293) (xy 294.5511 -288.062416) (xy 294.5511 -288.471356)
			(xy 300.592236 -288.471356) (xy 300.592236 -288.062416) (xy 300.592635 -288.052258) (xy 300.600432 -288.033499)
			(xy 300.614837 -288.019174) (xy 300.633638 -288.01148) (xy 300.643798 -288.011108) (xy 302.043338 -288.011108)
			(xy 302.053463 -288.011594) (xy 302.072179 -288.019329) (xy 302.086533 -288.033614) (xy 302.094356 -288.052293)
			(xy 302.0949 -288.062416) (xy 302.0949 -288.471356) (xy 308.136036 -288.471356) (xy 308.136036 -288.062416)
			(xy 308.136435 -288.052258) (xy 308.144232 -288.033499) (xy 308.158637 -288.019174) (xy 308.177438 -288.01148)
			(xy 308.187598 -288.011108) (xy 309.587138 -288.011108) (xy 309.597263 -288.011594) (xy 309.615979 -288.019329)
			(xy 309.630333 -288.033614) (xy 309.638156 -288.052293) (xy 309.6387 -288.062416) (xy 309.6387 -288.471356)
			(xy 309.638242 -288.481507) (xy 309.630461 -288.500259) (xy 309.616075 -288.514584) (xy 309.597291 -288.522285)
			(xy 309.587138 -288.522664) (xy 308.187598 -288.522664) (xy 308.177472 -288.522175) (xy 308.158751 -288.514447)
			(xy 308.144395 -288.500162) (xy 308.136575 -288.48148) (xy 308.136036 -288.471356) (xy 302.0949 -288.471356)
			(xy 302.094442 -288.481507) (xy 302.086661 -288.500259) (xy 302.072275 -288.514584) (xy 302.053491 -288.522285)
			(xy 302.043338 -288.522664) (xy 300.643798 -288.522664) (xy 300.633672 -288.522175) (xy 300.614951 -288.514447)
			(xy 300.600595 -288.500162) (xy 300.592775 -288.48148) (xy 300.592236 -288.471356) (xy 294.5511 -288.471356)
			(xy 294.550642 -288.481507) (xy 294.542861 -288.500259) (xy 294.528475 -288.514584) (xy 294.509691 -288.522285)
			(xy 294.499538 -288.522664) (xy 293.099998 -288.522664) (xy 293.089872 -288.522175) (xy 293.071151 -288.514447)
			(xy 293.056795 -288.500162) (xy 293.048975 -288.48148) (xy 293.048436 -288.471356) (xy 287.0073 -288.471356)
			(xy 287.006842 -288.481507) (xy 286.999061 -288.500259) (xy 286.984675 -288.514584) (xy 286.965891 -288.522285)
			(xy 286.955738 -288.522664) (xy 285.556198 -288.522664) (xy 285.546072 -288.522175) (xy 285.527351 -288.514447)
			(xy 285.512995 -288.500162) (xy 285.505175 -288.48148) (xy 285.504636 -288.471356) (xy 279.4635 -288.471356)
			(xy 279.463042 -288.481507) (xy 279.455261 -288.500259) (xy 279.440875 -288.514584) (xy 279.422091 -288.522285)
			(xy 279.411938 -288.522664) (xy 278.012398 -288.522664) (xy 278.002272 -288.522175) (xy 277.983551 -288.514447)
			(xy 277.969195 -288.500162) (xy 277.961375 -288.48148) (xy 277.960836 -288.471356) (xy 271.9197 -288.471356)
			(xy 271.919242 -288.481507) (xy 271.911461 -288.500259) (xy 271.897075 -288.514584) (xy 271.878291 -288.522285)
			(xy 271.868138 -288.522664) (xy 270.468598 -288.522664) (xy 270.458472 -288.522175) (xy 270.439751 -288.514447)
			(xy 270.425395 -288.500162) (xy 270.417575 -288.48148) (xy 270.417036 -288.471356) (xy 264.3759 -288.471356)
			(xy 264.375442 -288.481507) (xy 264.367661 -288.500259) (xy 264.353275 -288.514584) (xy 264.334491 -288.522285)
			(xy 264.324338 -288.522664) (xy 262.924798 -288.522664) (xy 262.914672 -288.522175) (xy 262.895951 -288.514447)
			(xy 262.881595 -288.500162) (xy 262.873775 -288.48148) (xy 262.873236 -288.471356) (xy 256.8321 -288.471356)
			(xy 256.831642 -288.481507) (xy 256.823861 -288.500259) (xy 256.809475 -288.514584) (xy 256.790691 -288.522285)
			(xy 256.780538 -288.522664) (xy 255.380998 -288.522664) (xy 255.370872 -288.522175) (xy 255.352151 -288.514447)
			(xy 255.337795 -288.500162) (xy 255.329975 -288.48148) (xy 255.329436 -288.471356) (xy 212.371432 -288.471356)
			(xy 212.370943 -288.481503) (xy 212.363168 -288.500249) (xy 212.348792 -288.514572) (xy 212.330019 -288.522279)
			(xy 212.31987 -288.522664) (xy 210.92033 -288.522664) (xy 210.910206 -288.522149) (xy 210.891486 -288.514432)
			(xy 210.877129 -288.500154) (xy 210.869308 -288.481478) (xy 210.868768 -288.471356) (xy 204.827632 -288.471356)
			(xy 204.827143 -288.481503) (xy 204.819368 -288.500249) (xy 204.804992 -288.514572) (xy 204.786219 -288.522279)
			(xy 204.77607 -288.522664) (xy 203.37653 -288.522664) (xy 203.366406 -288.522149) (xy 203.347686 -288.514432)
			(xy 203.333329 -288.500154) (xy 203.325508 -288.481478) (xy 203.324968 -288.471356) (xy 197.283832 -288.471356)
			(xy 197.283343 -288.481503) (xy 197.275568 -288.500249) (xy 197.261192 -288.514572) (xy 197.242419 -288.522279)
			(xy 197.23227 -288.522664) (xy 195.83273 -288.522664) (xy 195.822606 -288.522149) (xy 195.803886 -288.514432)
			(xy 195.789529 -288.500154) (xy 195.781708 -288.481478) (xy 195.781168 -288.471356) (xy 189.740032 -288.471356)
			(xy 189.739543 -288.481503) (xy 189.731768 -288.500249) (xy 189.717392 -288.514572) (xy 189.698619 -288.522279)
			(xy 189.68847 -288.522664) (xy 188.28893 -288.522664) (xy 188.278806 -288.522149) (xy 188.260086 -288.514432)
			(xy 188.245729 -288.500154) (xy 188.237908 -288.481478) (xy 188.237368 -288.471356) (xy 182.196232 -288.471356)
			(xy 182.195743 -288.481503) (xy 182.187968 -288.500249) (xy 182.173592 -288.514572) (xy 182.154819 -288.522279)
			(xy 182.14467 -288.522664) (xy 180.74513 -288.522664) (xy 180.735006 -288.522149) (xy 180.716286 -288.514432)
			(xy 180.701929 -288.500154) (xy 180.694108 -288.481478) (xy 180.693568 -288.471356) (xy 174.652432 -288.471356)
			(xy 174.651943 -288.481503) (xy 174.644168 -288.500249) (xy 174.629792 -288.514572) (xy 174.611019 -288.522279)
			(xy 174.60087 -288.522664) (xy 173.20133 -288.522664) (xy 173.191206 -288.522149) (xy 173.172486 -288.514432)
			(xy 173.158129 -288.500154) (xy 173.150308 -288.481478) (xy 173.149768 -288.471356) (xy 167.108632 -288.471356)
			(xy 167.108143 -288.481503) (xy 167.100368 -288.500249) (xy 167.085992 -288.514572) (xy 167.067219 -288.522279)
			(xy 167.05707 -288.522664) (xy 165.65753 -288.522664) (xy 165.647406 -288.522149) (xy 165.628686 -288.514432)
			(xy 165.614329 -288.500154) (xy 165.606508 -288.481478) (xy 165.605968 -288.471356) (xy 159.564832 -288.471356)
			(xy 159.564343 -288.481503) (xy 159.556568 -288.500249) (xy 159.542192 -288.514572) (xy 159.523419 -288.522279)
			(xy 159.51327 -288.522664) (xy 158.11373 -288.522664) (xy 158.103606 -288.522149) (xy 158.084886 -288.514432)
			(xy 158.070529 -288.500154) (xy 158.062708 -288.481478) (xy 158.062168 -288.471356) (xy 135.685886 -288.471356)
			(xy 135.753856 -288.588958) (xy 135.776716 -288.593276) (xy 135.801527 -288.598486) (xy 135.849305 -288.615434)
			(xy 135.893924 -288.6395) (xy 135.934331 -288.670114) (xy 135.969573 -288.706556) (xy 135.998818 -288.747964)
			(xy 136.021377 -288.793363) (xy 136.036717 -288.841681) (xy 136.044477 -288.891779) (xy 136.04494 -288.917126)
			(xy 136.044432 -288.943033) (xy 136.036326 -288.99421) (xy 136.020314 -289.043489) (xy 135.996791 -289.089656)
			(xy 135.966335 -289.131575) (xy 135.929697 -289.168213) (xy 135.887778 -289.198669) (xy 135.841611 -289.222192)
			(xy 135.792332 -289.238204) (xy 135.741155 -289.24631) (xy 135.689341 -289.24631) (xy 135.638164 -289.238204)
			(xy 135.588885 -289.222192) (xy 135.542718 -289.198669) (xy 135.500799 -289.168213) (xy 135.464161 -289.131575)
			(xy 135.433705 -289.089656) (xy 135.410182 -289.043489) (xy 135.39417 -288.99421) (xy 135.386064 -288.943033)
			(xy 135.385556 -288.917126) (xy 135.386153 -288.889409) (xy 135.395474 -288.834762) (xy 135.404098 -288.808414)
			(xy 135.411972 -288.786316) (xy 135.20674 -288.431224) (xy 135.18388 -288.426906) (xy 135.159064 -288.421716)
			(xy 135.111285 -288.404766) (xy 135.066665 -288.380698) (xy 135.026258 -288.350081) (xy 134.991016 -288.313637)
			(xy 134.961772 -288.272226) (xy 134.939214 -288.226825) (xy 134.923875 -288.178504) (xy 134.916118 -288.128404)
			(xy 134.915656 -288.103056) (xy 132.75564 -288.103056) (xy 132.755038 -288.130773) (xy 132.74572 -288.18542)
			(xy 132.737098 -288.211768) (xy 132.729478 -288.233866) (xy 132.934456 -288.588958) (xy 132.957316 -288.593276)
			(xy 132.982127 -288.598486) (xy 133.029905 -288.615434) (xy 133.074524 -288.6395) (xy 133.114931 -288.670114)
			(xy 133.150173 -288.706556) (xy 133.179418 -288.747964) (xy 133.201977 -288.793363) (xy 133.217317 -288.841681)
			(xy 133.225077 -288.891779) (xy 133.22554 -288.917126) (xy 133.225032 -288.943033) (xy 133.216926 -288.99421)
			(xy 133.200914 -289.043489) (xy 133.177391 -289.089656) (xy 133.146935 -289.131575) (xy 133.110297 -289.168213)
			(xy 133.068378 -289.198669) (xy 133.022211 -289.222192) (xy 132.972932 -289.238204) (xy 132.921755 -289.24631)
			(xy 132.869941 -289.24631) (xy 132.818764 -289.238204) (xy 132.769485 -289.222192) (xy 132.723318 -289.198669)
			(xy 132.681399 -289.168213) (xy 132.644761 -289.131575) (xy 132.614305 -289.089656) (xy 132.590782 -289.043489)
			(xy 132.57477 -288.99421) (xy 132.566664 -288.943033) (xy 132.566156 -288.917126) (xy 132.566753 -288.889409)
			(xy 132.576074 -288.834762) (xy 132.584698 -288.808414) (xy 132.592572 -288.786316) (xy 132.387594 -288.431224)
			(xy 132.364734 -288.426906) (xy 132.339899 -288.421756) (xy 132.292089 -288.404821) (xy 132.247438 -288.380764)
			(xy 132.206999 -288.350151) (xy 132.171726 -288.313705) (xy 132.142451 -288.272287) (xy 132.119866 -288.226873)
			(xy 132.104504 -288.178536) (xy 132.096726 -288.128416) (xy 132.096256 -288.103056) (xy 130.87604 -288.103056)
			(xy 130.875438 -288.130773) (xy 130.86612 -288.18542) (xy 130.857498 -288.211768) (xy 130.849878 -288.233866)
			(xy 131.054856 -288.588958) (xy 131.077716 -288.593276) (xy 131.102527 -288.598486) (xy 131.150305 -288.615434)
			(xy 131.194924 -288.6395) (xy 131.235331 -288.670114) (xy 131.270573 -288.706556) (xy 131.299818 -288.747964)
			(xy 131.322377 -288.793363) (xy 131.337717 -288.841681) (xy 131.345477 -288.891779) (xy 131.34594 -288.917126)
			(xy 131.345432 -288.943033) (xy 131.337326 -288.99421) (xy 131.321314 -289.043489) (xy 131.297791 -289.089656)
			(xy 131.267335 -289.131575) (xy 131.230697 -289.168213) (xy 131.188778 -289.198669) (xy 131.142611 -289.222192)
			(xy 131.093332 -289.238204) (xy 131.042155 -289.24631) (xy 130.990341 -289.24631) (xy 130.939164 -289.238204)
			(xy 130.889885 -289.222192) (xy 130.843718 -289.198669) (xy 130.801799 -289.168213) (xy 130.765161 -289.131575)
			(xy 130.734705 -289.089656) (xy 130.711182 -289.043489) (xy 130.69517 -288.99421) (xy 130.687064 -288.943033)
			(xy 130.686556 -288.917126) (xy 130.687153 -288.889409) (xy 130.696474 -288.834762) (xy 130.705098 -288.808414)
			(xy 130.712972 -288.786316) (xy 130.507994 -288.431224) (xy 130.485134 -288.426906) (xy 130.460299 -288.421756)
			(xy 130.412489 -288.404821) (xy 130.367838 -288.380764) (xy 130.327399 -288.350151) (xy 130.292126 -288.313705)
			(xy 130.262851 -288.272287) (xy 130.240266 -288.226873) (xy 130.224904 -288.178536) (xy 130.217126 -288.128416)
			(xy 130.216656 -288.103056) (xy 128.99644 -288.103056) (xy 128.995838 -288.130773) (xy 128.98652 -288.18542)
			(xy 128.977898 -288.211768) (xy 128.970278 -288.233866) (xy 129.175256 -288.588958) (xy 129.198116 -288.593276)
			(xy 129.222927 -288.598486) (xy 129.270705 -288.615434) (xy 129.315324 -288.6395) (xy 129.355731 -288.670114)
			(xy 129.390973 -288.706556) (xy 129.420218 -288.747964) (xy 129.442777 -288.793363) (xy 129.458117 -288.841681)
			(xy 129.465877 -288.891779) (xy 129.46634 -288.917126) (xy 129.465832 -288.943033) (xy 129.457726 -288.99421)
			(xy 129.441714 -289.043489) (xy 129.418191 -289.089656) (xy 129.387735 -289.131575) (xy 129.351097 -289.168213)
			(xy 129.309178 -289.198669) (xy 129.263011 -289.222192) (xy 129.213732 -289.238204) (xy 129.162555 -289.24631)
			(xy 129.110741 -289.24631) (xy 129.059564 -289.238204) (xy 129.010285 -289.222192) (xy 128.964118 -289.198669)
			(xy 128.922199 -289.168213) (xy 128.885561 -289.131575) (xy 128.855105 -289.089656) (xy 128.831582 -289.043489)
			(xy 128.81557 -288.99421) (xy 128.807464 -288.943033) (xy 128.806956 -288.917126) (xy 128.807553 -288.889409)
			(xy 128.816874 -288.834762) (xy 128.825498 -288.808414) (xy 128.833372 -288.786316) (xy 128.628394 -288.431224)
			(xy 128.605534 -288.426906) (xy 128.580699 -288.421756) (xy 128.532889 -288.404821) (xy 128.488238 -288.380764)
			(xy 128.447799 -288.350151) (xy 128.412526 -288.313705) (xy 128.383251 -288.272287) (xy 128.360666 -288.226873)
			(xy 128.345304 -288.178536) (xy 128.337526 -288.128416) (xy 128.337056 -288.103056) (xy 127.11684 -288.103056)
			(xy 127.116238 -288.130773) (xy 127.10692 -288.18542) (xy 127.098298 -288.211768) (xy 127.090678 -288.233866)
			(xy 127.295656 -288.588958) (xy 127.318516 -288.593276) (xy 127.343327 -288.598486) (xy 127.391105 -288.615434)
			(xy 127.435724 -288.6395) (xy 127.476131 -288.670114) (xy 127.511373 -288.706556) (xy 127.540618 -288.747964)
			(xy 127.563177 -288.793363) (xy 127.578517 -288.841681) (xy 127.586277 -288.891779) (xy 127.58674 -288.917126)
			(xy 127.586232 -288.943033) (xy 127.578126 -288.99421) (xy 127.562114 -289.043489) (xy 127.538591 -289.089656)
			(xy 127.508135 -289.131575) (xy 127.471497 -289.168213) (xy 127.429578 -289.198669) (xy 127.383411 -289.222192)
			(xy 127.334132 -289.238204) (xy 127.282955 -289.24631) (xy 127.231141 -289.24631) (xy 127.179964 -289.238204)
			(xy 127.130685 -289.222192) (xy 127.084518 -289.198669) (xy 127.042599 -289.168213) (xy 127.005961 -289.131575)
			(xy 126.975505 -289.089656) (xy 126.951982 -289.043489) (xy 126.93597 -288.99421) (xy 126.927864 -288.943033)
			(xy 126.927356 -288.917126) (xy 126.927953 -288.889409) (xy 126.937274 -288.834762) (xy 126.945898 -288.808414)
			(xy 126.953772 -288.786316) (xy 126.748794 -288.431224) (xy 126.725934 -288.426906) (xy 126.701099 -288.421756)
			(xy 126.653289 -288.404821) (xy 126.608638 -288.380764) (xy 126.568199 -288.350151) (xy 126.532926 -288.313705)
			(xy 126.503651 -288.272287) (xy 126.481066 -288.226873) (xy 126.465704 -288.178536) (xy 126.457926 -288.128416)
			(xy 126.457456 -288.103056) (xy 125.23724 -288.103056) (xy 125.236638 -288.130773) (xy 125.22732 -288.18542)
			(xy 125.218698 -288.211768) (xy 125.211078 -288.233866) (xy 125.416056 -288.588958) (xy 125.438916 -288.593276)
			(xy 125.463727 -288.598486) (xy 125.511505 -288.615434) (xy 125.556124 -288.6395) (xy 125.596531 -288.670114)
			(xy 125.631773 -288.706556) (xy 125.661018 -288.747964) (xy 125.683577 -288.793363) (xy 125.698917 -288.841681)
			(xy 125.706677 -288.891779) (xy 125.70714 -288.917126) (xy 125.706632 -288.943033) (xy 125.698526 -288.99421)
			(xy 125.682514 -289.043489) (xy 125.658991 -289.089656) (xy 125.628535 -289.131575) (xy 125.591897 -289.168213)
			(xy 125.549978 -289.198669) (xy 125.503811 -289.222192) (xy 125.454532 -289.238204) (xy 125.403355 -289.24631)
			(xy 125.351541 -289.24631) (xy 125.300364 -289.238204) (xy 125.251085 -289.222192) (xy 125.204918 -289.198669)
			(xy 125.162999 -289.168213) (xy 125.126361 -289.131575) (xy 125.095905 -289.089656) (xy 125.072382 -289.043489)
			(xy 125.05637 -288.99421) (xy 125.048264 -288.943033) (xy 125.047756 -288.917126) (xy 125.048353 -288.889409)
			(xy 125.057674 -288.834762) (xy 125.066298 -288.808414) (xy 125.074172 -288.786316) (xy 124.869194 -288.431224)
			(xy 124.846334 -288.426906) (xy 124.821499 -288.421756) (xy 124.773689 -288.404821) (xy 124.729038 -288.380764)
			(xy 124.688599 -288.350151) (xy 124.653326 -288.313705) (xy 124.624051 -288.272287) (xy 124.601466 -288.226873)
			(xy 124.586104 -288.178536) (xy 124.578326 -288.128416) (xy 124.577856 -288.103056) (xy 123.35764 -288.103056)
			(xy 123.357038 -288.130773) (xy 123.34772 -288.18542) (xy 123.339098 -288.211768) (xy 123.331478 -288.233866)
			(xy 123.536456 -288.588958) (xy 123.559316 -288.593276) (xy 123.584127 -288.598486) (xy 123.631905 -288.615434)
			(xy 123.676524 -288.6395) (xy 123.716931 -288.670114) (xy 123.752173 -288.706556) (xy 123.781418 -288.747964)
			(xy 123.803977 -288.793363) (xy 123.819317 -288.841681) (xy 123.827077 -288.891779) (xy 123.82754 -288.917126)
			(xy 123.827032 -288.943033) (xy 123.818926 -288.99421) (xy 123.802914 -289.043489) (xy 123.779391 -289.089656)
			(xy 123.748935 -289.131575) (xy 123.712297 -289.168213) (xy 123.670378 -289.198669) (xy 123.624211 -289.222192)
			(xy 123.574932 -289.238204) (xy 123.523755 -289.24631) (xy 123.471941 -289.24631) (xy 123.420764 -289.238204)
			(xy 123.371485 -289.222192) (xy 123.325318 -289.198669) (xy 123.283399 -289.168213) (xy 123.246761 -289.131575)
			(xy 123.216305 -289.089656) (xy 123.192782 -289.043489) (xy 123.17677 -288.99421) (xy 123.168664 -288.943033)
			(xy 123.168156 -288.917126) (xy 123.168753 -288.889409) (xy 123.178074 -288.834762) (xy 123.186698 -288.808414)
			(xy 123.194572 -288.786316) (xy 122.989594 -288.431224) (xy 122.966734 -288.426906) (xy 122.941899 -288.421756)
			(xy 122.894089 -288.404821) (xy 122.849438 -288.380764) (xy 122.808999 -288.350151) (xy 122.773726 -288.313705)
			(xy 122.744451 -288.272287) (xy 122.721866 -288.226873) (xy 122.706504 -288.178536) (xy 122.698726 -288.128416)
			(xy 122.698256 -288.103056) (xy 121.47804 -288.103056) (xy 121.477438 -288.130773) (xy 121.46812 -288.18542)
			(xy 121.459498 -288.211768) (xy 121.451624 -288.233866) (xy 121.656856 -288.588958) (xy 121.679716 -288.593276)
			(xy 121.704527 -288.598486) (xy 121.752305 -288.615434) (xy 121.796924 -288.6395) (xy 121.837331 -288.670114)
			(xy 121.872573 -288.706556) (xy 121.901818 -288.747964) (xy 121.924377 -288.793363) (xy 121.939717 -288.841681)
			(xy 121.947477 -288.891779) (xy 121.94794 -288.917126) (xy 121.947432 -288.943033) (xy 121.939326 -288.99421)
			(xy 121.923314 -289.043489) (xy 121.899791 -289.089656) (xy 121.869335 -289.131575) (xy 121.832697 -289.168213)
			(xy 121.790778 -289.198669) (xy 121.744611 -289.222192) (xy 121.695332 -289.238204) (xy 121.644155 -289.24631)
			(xy 121.592341 -289.24631) (xy 121.541164 -289.238204) (xy 121.491885 -289.222192) (xy 121.445718 -289.198669)
			(xy 121.403799 -289.168213) (xy 121.367161 -289.131575) (xy 121.336705 -289.089656) (xy 121.313182 -289.043489)
			(xy 121.29717 -288.99421) (xy 121.289064 -288.943033) (xy 121.288556 -288.917126) (xy 121.289153 -288.889409)
			(xy 121.298474 -288.834762) (xy 121.307098 -288.808414) (xy 121.314972 -288.786316) (xy 121.10974 -288.431224)
			(xy 121.08688 -288.426906) (xy 121.062064 -288.421716) (xy 121.014285 -288.404766) (xy 120.969665 -288.380698)
			(xy 120.929258 -288.350081) (xy 120.894016 -288.313637) (xy 120.864772 -288.272226) (xy 120.842214 -288.226825)
			(xy 120.826875 -288.178504) (xy 120.819118 -288.128404) (xy 120.818656 -288.103056) (xy 104.56164 -288.103056)
			(xy 104.561218 -288.128404) (xy 104.553436 -288.178499) (xy 104.53808 -288.226813) (xy 104.515512 -288.272208)
			(xy 104.486262 -288.313614) (xy 104.451021 -288.350057) (xy 104.410618 -288.380678) (xy 104.366005 -288.404755)
			(xy 104.318232 -288.421722) (xy 104.293416 -288.426906) (xy 104.270556 -288.431224) (xy 104.065324 -288.786316)
			(xy 104.073198 -288.808414) (xy 104.08184 -288.834757) (xy 104.091154 -288.889407) (xy 104.09174 -288.917126)
			(xy 104.091232 -288.943033) (xy 104.083126 -288.99421) (xy 104.067114 -289.043489) (xy 104.043591 -289.089656)
			(xy 104.013135 -289.131575) (xy 103.976497 -289.168213) (xy 103.934578 -289.198669) (xy 103.888411 -289.222192)
			(xy 103.839132 -289.238204) (xy 103.787955 -289.24631) (xy 103.736141 -289.24631) (xy 103.684964 -289.238204)
			(xy 103.635685 -289.222192) (xy 103.589518 -289.198669) (xy 103.547599 -289.168213) (xy 103.510961 -289.131575)
			(xy 103.480505 -289.089656) (xy 103.456982 -289.043489) (xy 103.44097 -288.99421) (xy 103.432864 -288.943033)
			(xy 103.432356 -288.917126) (xy 103.15194 -288.917126) (xy 103.151518 -288.940067) (xy 103.14509 -288.985498)
			(xy 103.132444 -289.029604) (xy 103.123492 -289.05073) (xy 103.113586 -289.073336) (xy 103.327454 -289.478466)
			(xy 103.351584 -289.483038) (xy 103.37651 -289.488115) (xy 103.424521 -289.50492) (xy 103.469379 -289.528904)
			(xy 103.510019 -289.559496) (xy 103.545476 -289.59597) (xy 103.574906 -289.637459) (xy 103.597612 -289.682977)
			(xy 103.613053 -289.731444) (xy 103.620863 -289.781708) (xy 103.621332 -289.807142) (xy 119.878856 -289.807142)
			(xy 119.879399 -289.781715) (xy 119.887229 -289.731468) (xy 119.90268 -289.683018) (xy 119.925386 -289.637514)
			(xy 119.954808 -289.596036) (xy 119.990248 -289.559565) (xy 120.030867 -289.528967) (xy 120.075701 -289.504967)
			(xy 120.123688 -289.488134) (xy 120.148604 -289.483038) (xy 120.172734 -289.478466) (xy 120.38711 -289.073082)
			(xy 120.377204 -289.050476) (xy 120.368243 -289.029398) (xy 120.355596 -288.985377) (xy 120.349182 -288.940026)
			(xy 120.348756 -288.917126) (xy 120.349264 -288.891219) (xy 120.35737 -288.840042) (xy 120.373382 -288.790763)
			(xy 120.396905 -288.744596) (xy 120.427361 -288.702677) (xy 120.463999 -288.666039) (xy 120.505918 -288.635583)
			(xy 120.552085 -288.61206) (xy 120.601364 -288.596048) (xy 120.652541 -288.587942) (xy 120.704355 -288.587942)
			(xy 120.755532 -288.596048) (xy 120.804811 -288.61206) (xy 120.850978 -288.635583) (xy 120.892897 -288.666039)
			(xy 120.929535 -288.702677) (xy 120.959991 -288.744596) (xy 120.983514 -288.790763) (xy 120.999526 -288.840042)
			(xy 121.007632 -288.891219) (xy 121.00814 -288.917126) (xy 121.007659 -288.942574) (xy 120.999856 -288.992867)
			(xy 120.984408 -289.041361) (xy 120.961683 -289.086901) (xy 120.932222 -289.128403) (xy 120.896727 -289.164878)
			(xy 120.856043 -289.195458) (xy 120.811139 -289.219415) (xy 120.763084 -289.236178) (xy 120.738138 -289.24123)
			(xy 120.714008 -289.245802) (xy 120.499632 -289.651186) (xy 120.509538 -289.673792) (xy 120.518456 -289.694878)
			(xy 120.531008 -289.738907) (xy 120.537342 -289.78425) (xy 120.537732 -289.807142) (xy 121.758456 -289.807142)
			(xy 121.758999 -289.781715) (xy 121.766829 -289.731468) (xy 121.78228 -289.683018) (xy 121.804986 -289.637514)
			(xy 121.834408 -289.596036) (xy 121.869848 -289.559565) (xy 121.910467 -289.528967) (xy 121.955301 -289.504967)
			(xy 122.003288 -289.488134) (xy 122.028204 -289.483038) (xy 122.052334 -289.478466) (xy 122.26671 -289.073082)
			(xy 122.256804 -289.050476) (xy 122.247843 -289.029398) (xy 122.235196 -288.985377) (xy 122.228782 -288.940026)
			(xy 122.228356 -288.917126) (xy 122.228864 -288.891219) (xy 122.23697 -288.840042) (xy 122.252982 -288.790763)
			(xy 122.276505 -288.744596) (xy 122.306961 -288.702677) (xy 122.343599 -288.666039) (xy 122.385518 -288.635583)
			(xy 122.431685 -288.61206) (xy 122.480964 -288.596048) (xy 122.532141 -288.587942) (xy 122.583955 -288.587942)
			(xy 122.635132 -288.596048) (xy 122.684411 -288.61206) (xy 122.730578 -288.635583) (xy 122.772497 -288.666039)
			(xy 122.809135 -288.702677) (xy 122.839591 -288.744596) (xy 122.863114 -288.790763) (xy 122.879126 -288.840042)
			(xy 122.887232 -288.891219) (xy 122.88774 -288.917126) (xy 122.887259 -288.942574) (xy 122.879456 -288.992867)
			(xy 122.864008 -289.041361) (xy 122.841283 -289.086901) (xy 122.811822 -289.128403) (xy 122.776327 -289.164878)
			(xy 122.735643 -289.195458) (xy 122.690739 -289.219415) (xy 122.642684 -289.236178) (xy 122.617738 -289.24123)
			(xy 122.593608 -289.245802) (xy 122.379232 -289.651186) (xy 122.389138 -289.673792) (xy 122.398056 -289.694878)
			(xy 122.410608 -289.738907) (xy 122.416942 -289.78425) (xy 122.417332 -289.807142) (xy 123.638056 -289.807142)
			(xy 123.638599 -289.781715) (xy 123.646429 -289.731468) (xy 123.66188 -289.683018) (xy 123.684586 -289.637514)
			(xy 123.714008 -289.596036) (xy 123.749448 -289.559565) (xy 123.790067 -289.528967) (xy 123.834901 -289.504967)
			(xy 123.882888 -289.488134) (xy 123.907804 -289.483038) (xy 123.931934 -289.478466) (xy 124.14631 -289.073082)
			(xy 124.136404 -289.050476) (xy 124.127443 -289.029398) (xy 124.114796 -288.985377) (xy 124.108382 -288.940026)
			(xy 124.107956 -288.917126) (xy 124.108464 -288.891219) (xy 124.11657 -288.840042) (xy 124.132582 -288.790763)
			(xy 124.156105 -288.744596) (xy 124.186561 -288.702677) (xy 124.223199 -288.666039) (xy 124.265118 -288.635583)
			(xy 124.311285 -288.61206) (xy 124.360564 -288.596048) (xy 124.411741 -288.587942) (xy 124.463555 -288.587942)
			(xy 124.514732 -288.596048) (xy 124.564011 -288.61206) (xy 124.610178 -288.635583) (xy 124.652097 -288.666039)
			(xy 124.688735 -288.702677) (xy 124.719191 -288.744596) (xy 124.742714 -288.790763) (xy 124.758726 -288.840042)
			(xy 124.766832 -288.891219) (xy 124.76734 -288.917126) (xy 124.766859 -288.942574) (xy 124.759056 -288.992867)
			(xy 124.743608 -289.041361) (xy 124.720883 -289.086901) (xy 124.691422 -289.128403) (xy 124.655927 -289.164878)
			(xy 124.615243 -289.195458) (xy 124.570339 -289.219415) (xy 124.522284 -289.236178) (xy 124.497338 -289.24123)
			(xy 124.473208 -289.245802) (xy 124.258832 -289.651186) (xy 124.268738 -289.673792) (xy 124.277656 -289.694878)
			(xy 124.290208 -289.738907) (xy 124.296542 -289.78425) (xy 124.296932 -289.807142) (xy 125.517656 -289.807142)
			(xy 125.518199 -289.781715) (xy 125.526029 -289.731468) (xy 125.54148 -289.683018) (xy 125.564186 -289.637514)
			(xy 125.593608 -289.596036) (xy 125.629048 -289.559565) (xy 125.669667 -289.528967) (xy 125.714501 -289.504967)
			(xy 125.762488 -289.488134) (xy 125.787404 -289.483038) (xy 125.811534 -289.478466) (xy 126.02591 -289.073082)
			(xy 126.016004 -289.050476) (xy 126.007043 -289.029398) (xy 125.994396 -288.985377) (xy 125.987982 -288.940026)
			(xy 125.987556 -288.917126) (xy 125.988064 -288.891219) (xy 125.99617 -288.840042) (xy 126.012182 -288.790763)
			(xy 126.035705 -288.744596) (xy 126.066161 -288.702677) (xy 126.102799 -288.666039) (xy 126.144718 -288.635583)
			(xy 126.190885 -288.61206) (xy 126.240164 -288.596048) (xy 126.291341 -288.587942) (xy 126.343155 -288.587942)
			(xy 126.394332 -288.596048) (xy 126.443611 -288.61206) (xy 126.489778 -288.635583) (xy 126.531697 -288.666039)
			(xy 126.568335 -288.702677) (xy 126.598791 -288.744596) (xy 126.622314 -288.790763) (xy 126.638326 -288.840042)
			(xy 126.646432 -288.891219) (xy 126.64694 -288.917126) (xy 126.646459 -288.942574) (xy 126.638656 -288.992867)
			(xy 126.623208 -289.041361) (xy 126.600483 -289.086901) (xy 126.571022 -289.128403) (xy 126.535527 -289.164878)
			(xy 126.494843 -289.195458) (xy 126.449939 -289.219415) (xy 126.401884 -289.236178) (xy 126.376938 -289.24123)
			(xy 126.352808 -289.245802) (xy 126.138432 -289.651186) (xy 126.148338 -289.673792) (xy 126.157256 -289.694878)
			(xy 126.169808 -289.738907) (xy 126.176142 -289.78425) (xy 126.176532 -289.807142) (xy 127.397256 -289.807142)
			(xy 127.397799 -289.781715) (xy 127.405629 -289.731468) (xy 127.42108 -289.683018) (xy 127.443786 -289.637514)
			(xy 127.473208 -289.596036) (xy 127.508648 -289.559565) (xy 127.549267 -289.528967) (xy 127.594101 -289.504967)
			(xy 127.642088 -289.488134) (xy 127.667004 -289.483038) (xy 127.691134 -289.478466) (xy 127.90551 -289.073082)
			(xy 127.895604 -289.050476) (xy 127.886643 -289.029398) (xy 127.873996 -288.985377) (xy 127.867582 -288.940026)
			(xy 127.867156 -288.917126) (xy 127.867664 -288.891219) (xy 127.87577 -288.840042) (xy 127.891782 -288.790763)
			(xy 127.915305 -288.744596) (xy 127.945761 -288.702677) (xy 127.982399 -288.666039) (xy 128.024318 -288.635583)
			(xy 128.070485 -288.61206) (xy 128.119764 -288.596048) (xy 128.170941 -288.587942) (xy 128.222755 -288.587942)
			(xy 128.273932 -288.596048) (xy 128.323211 -288.61206) (xy 128.369378 -288.635583) (xy 128.411297 -288.666039)
			(xy 128.447935 -288.702677) (xy 128.478391 -288.744596) (xy 128.501914 -288.790763) (xy 128.517926 -288.840042)
			(xy 128.526032 -288.891219) (xy 128.52654 -288.917126) (xy 128.526059 -288.942574) (xy 128.518256 -288.992867)
			(xy 128.502808 -289.041361) (xy 128.480083 -289.086901) (xy 128.450622 -289.128403) (xy 128.415127 -289.164878)
			(xy 128.374443 -289.195458) (xy 128.329539 -289.219415) (xy 128.281484 -289.236178) (xy 128.256538 -289.24123)
			(xy 128.232408 -289.245802) (xy 128.018032 -289.651186) (xy 128.027938 -289.673792) (xy 128.036856 -289.694878)
			(xy 128.049408 -289.738907) (xy 128.055742 -289.78425) (xy 128.056132 -289.807142) (xy 129.276856 -289.807142)
			(xy 129.277399 -289.781715) (xy 129.285229 -289.731468) (xy 129.30068 -289.683018) (xy 129.323386 -289.637514)
			(xy 129.352808 -289.596036) (xy 129.388248 -289.559565) (xy 129.428867 -289.528967) (xy 129.473701 -289.504967)
			(xy 129.521688 -289.488134) (xy 129.546604 -289.483038) (xy 129.570734 -289.478466) (xy 129.78511 -289.073082)
			(xy 129.775204 -289.050476) (xy 129.766243 -289.029398) (xy 129.753596 -288.985377) (xy 129.747182 -288.940026)
			(xy 129.746756 -288.917126) (xy 129.747264 -288.891219) (xy 129.75537 -288.840042) (xy 129.771382 -288.790763)
			(xy 129.794905 -288.744596) (xy 129.825361 -288.702677) (xy 129.861999 -288.666039) (xy 129.903918 -288.635583)
			(xy 129.950085 -288.61206) (xy 129.999364 -288.596048) (xy 130.050541 -288.587942) (xy 130.102355 -288.587942)
			(xy 130.153532 -288.596048) (xy 130.202811 -288.61206) (xy 130.248978 -288.635583) (xy 130.290897 -288.666039)
			(xy 130.327535 -288.702677) (xy 130.357991 -288.744596) (xy 130.381514 -288.790763) (xy 130.397526 -288.840042)
			(xy 130.405632 -288.891219) (xy 130.40614 -288.917126) (xy 130.405659 -288.942574) (xy 130.397856 -288.992867)
			(xy 130.382408 -289.041361) (xy 130.359683 -289.086901) (xy 130.330222 -289.128403) (xy 130.294727 -289.164878)
			(xy 130.254043 -289.195458) (xy 130.209139 -289.219415) (xy 130.161084 -289.236178) (xy 130.136138 -289.24123)
			(xy 130.112008 -289.245802) (xy 129.897632 -289.651186) (xy 129.907538 -289.673792) (xy 129.916456 -289.694878)
			(xy 129.929008 -289.738907) (xy 129.935342 -289.78425) (xy 129.935732 -289.807142) (xy 131.156456 -289.807142)
			(xy 131.156999 -289.781715) (xy 131.164829 -289.731468) (xy 131.18028 -289.683018) (xy 131.202986 -289.637514)
			(xy 131.232408 -289.596036) (xy 131.267848 -289.559565) (xy 131.308467 -289.528967) (xy 131.353301 -289.504967)
			(xy 131.401288 -289.488134) (xy 131.426204 -289.483038) (xy 131.450334 -289.478466) (xy 131.66471 -289.073082)
			(xy 131.654804 -289.050476) (xy 131.645843 -289.029398) (xy 131.633196 -288.985377) (xy 131.626782 -288.940026)
			(xy 131.626356 -288.917126) (xy 131.626864 -288.891219) (xy 131.63497 -288.840042) (xy 131.650982 -288.790763)
			(xy 131.674505 -288.744596) (xy 131.704961 -288.702677) (xy 131.741599 -288.666039) (xy 131.783518 -288.635583)
			(xy 131.829685 -288.61206) (xy 131.878964 -288.596048) (xy 131.930141 -288.587942) (xy 131.981955 -288.587942)
			(xy 132.033132 -288.596048) (xy 132.082411 -288.61206) (xy 132.128578 -288.635583) (xy 132.170497 -288.666039)
			(xy 132.207135 -288.702677) (xy 132.237591 -288.744596) (xy 132.261114 -288.790763) (xy 132.277126 -288.840042)
			(xy 132.285232 -288.891219) (xy 132.28574 -288.917126) (xy 132.285259 -288.942574) (xy 132.277456 -288.992867)
			(xy 132.262008 -289.041361) (xy 132.239283 -289.086901) (xy 132.209822 -289.128403) (xy 132.174327 -289.164878)
			(xy 132.133643 -289.195458) (xy 132.088739 -289.219415) (xy 132.040684 -289.236178) (xy 132.015738 -289.24123)
			(xy 131.991608 -289.245802) (xy 131.777232 -289.651186) (xy 131.787138 -289.673792) (xy 131.796056 -289.694878)
			(xy 131.808608 -289.738907) (xy 131.814942 -289.78425) (xy 131.815332 -289.807142) (xy 133.036056 -289.807142)
			(xy 133.036599 -289.781715) (xy 133.044429 -289.731468) (xy 133.05988 -289.683018) (xy 133.082586 -289.637514)
			(xy 133.112008 -289.596036) (xy 133.147448 -289.559565) (xy 133.188067 -289.528967) (xy 133.232901 -289.504967)
			(xy 133.280888 -289.488134) (xy 133.305804 -289.483038) (xy 133.329934 -289.478466) (xy 133.54431 -289.073082)
			(xy 133.534404 -289.050476) (xy 133.525443 -289.029398) (xy 133.512796 -288.985377) (xy 133.506382 -288.940026)
			(xy 133.505956 -288.917126) (xy 133.506464 -288.891219) (xy 133.51457 -288.840042) (xy 133.530582 -288.790763)
			(xy 133.554105 -288.744596) (xy 133.584561 -288.702677) (xy 133.621199 -288.666039) (xy 133.663118 -288.635583)
			(xy 133.709285 -288.61206) (xy 133.758564 -288.596048) (xy 133.809741 -288.587942) (xy 133.861555 -288.587942)
			(xy 133.912732 -288.596048) (xy 133.962011 -288.61206) (xy 134.008178 -288.635583) (xy 134.050097 -288.666039)
			(xy 134.086735 -288.702677) (xy 134.117191 -288.744596) (xy 134.140714 -288.790763) (xy 134.156726 -288.840042)
			(xy 134.164832 -288.891219) (xy 134.16534 -288.917126) (xy 134.164859 -288.942574) (xy 134.157056 -288.992867)
			(xy 134.141608 -289.041361) (xy 134.118883 -289.086901) (xy 134.089422 -289.128403) (xy 134.053927 -289.164878)
			(xy 134.013243 -289.195458) (xy 133.968339 -289.219415) (xy 133.920284 -289.236178) (xy 133.895338 -289.24123)
			(xy 133.871208 -289.245802) (xy 133.83118 -289.321494) (xy 162.162236 -289.321494) (xy 162.162236 -288.912554)
			(xy 162.162696 -288.902394) (xy 162.170485 -288.883624) (xy 162.184861 -288.86926) (xy 162.203637 -288.861487)
			(xy 162.213798 -288.860992) (xy 163.613338 -288.860992) (xy 163.623493 -288.861501) (xy 163.642254 -288.869279)
			(xy 163.656616 -288.88364) (xy 163.664397 -288.9024) (xy 163.6649 -288.912554) (xy 163.6649 -289.321494)
			(xy 169.706036 -289.321494) (xy 169.706036 -288.912554) (xy 169.706496 -288.902394) (xy 169.714285 -288.883624)
			(xy 169.728661 -288.86926) (xy 169.747437 -288.861487) (xy 169.757598 -288.860992) (xy 171.157138 -288.860992)
			(xy 171.167293 -288.861501) (xy 171.186054 -288.869279) (xy 171.200416 -288.88364) (xy 171.208197 -288.9024)
			(xy 171.2087 -288.912554) (xy 171.2087 -289.321494) (xy 177.249836 -289.321494) (xy 177.249836 -288.912554)
			(xy 177.250296 -288.902394) (xy 177.258085 -288.883624) (xy 177.272461 -288.86926) (xy 177.291237 -288.861487)
			(xy 177.301398 -288.860992) (xy 178.700938 -288.860992) (xy 178.711093 -288.861501) (xy 178.729854 -288.869279)
			(xy 178.744216 -288.88364) (xy 178.751997 -288.9024) (xy 178.7525 -288.912554) (xy 178.7525 -289.321494)
			(xy 184.793636 -289.321494) (xy 184.793636 -288.912554) (xy 184.794096 -288.902394) (xy 184.801885 -288.883624)
			(xy 184.816261 -288.86926) (xy 184.835037 -288.861487) (xy 184.845198 -288.860992) (xy 186.244738 -288.860992)
			(xy 186.254893 -288.861501) (xy 186.273654 -288.869279) (xy 186.288016 -288.88364) (xy 186.295797 -288.9024)
			(xy 186.2963 -288.912554) (xy 186.2963 -289.321494) (xy 192.337436 -289.321494) (xy 192.337436 -288.912554)
			(xy 192.337896 -288.902394) (xy 192.345685 -288.883624) (xy 192.360061 -288.86926) (xy 192.378837 -288.861487)
			(xy 192.388998 -288.860992) (xy 193.788538 -288.860992) (xy 193.798693 -288.861501) (xy 193.817454 -288.869279)
			(xy 193.831816 -288.88364) (xy 193.839597 -288.9024) (xy 193.8401 -288.912554) (xy 193.8401 -289.321494)
			(xy 199.881236 -289.321494) (xy 199.881236 -288.912554) (xy 199.881696 -288.902394) (xy 199.889485 -288.883624)
			(xy 199.903861 -288.86926) (xy 199.922637 -288.861487) (xy 199.932798 -288.860992) (xy 201.332338 -288.860992)
			(xy 201.342493 -288.861501) (xy 201.361254 -288.869279) (xy 201.375616 -288.88364) (xy 201.383397 -288.9024)
			(xy 201.3839 -288.912554) (xy 201.3839 -289.321494) (xy 207.425036 -289.321494) (xy 207.425036 -288.912554)
			(xy 207.425496 -288.902394) (xy 207.433285 -288.883624) (xy 207.447661 -288.86926) (xy 207.466437 -288.861487)
			(xy 207.476598 -288.860992) (xy 208.876138 -288.860992) (xy 208.886293 -288.861501) (xy 208.905054 -288.869279)
			(xy 208.919416 -288.88364) (xy 208.927197 -288.9024) (xy 208.9277 -288.912554) (xy 208.9277 -289.321494)
			(xy 214.968836 -289.321494) (xy 214.968836 -288.912554) (xy 214.969296 -288.902394) (xy 214.977085 -288.883624)
			(xy 214.991461 -288.86926) (xy 215.010237 -288.861487) (xy 215.020398 -288.860992) (xy 216.419938 -288.860992)
			(xy 216.430093 -288.861501) (xy 216.448854 -288.869279) (xy 216.463216 -288.88364) (xy 216.470997 -288.9024)
			(xy 216.4715 -288.912554) (xy 216.4715 -289.321494) (xy 259.429504 -289.321494) (xy 259.429504 -288.912554)
			(xy 259.429995 -288.902397) (xy 259.437778 -288.883634) (xy 259.452144 -288.869271) (xy 259.470909 -288.861493)
			(xy 259.481066 -288.860992) (xy 260.880606 -288.860992) (xy 260.890758 -288.861527) (xy 260.909519 -288.869295)
			(xy 260.923882 -288.883648) (xy 260.931665 -288.902402) (xy 260.932168 -288.912554) (xy 260.932168 -289.321494)
			(xy 266.973304 -289.321494) (xy 266.973304 -288.912554) (xy 266.973795 -288.902397) (xy 266.981578 -288.883634)
			(xy 266.995944 -288.869271) (xy 267.014709 -288.861493) (xy 267.024866 -288.860992) (xy 268.424406 -288.860992)
			(xy 268.434558 -288.861527) (xy 268.453319 -288.869295) (xy 268.467682 -288.883648) (xy 268.475465 -288.902402)
			(xy 268.475968 -288.912554) (xy 268.475968 -289.321494) (xy 274.517104 -289.321494) (xy 274.517104 -288.912554)
			(xy 274.517595 -288.902397) (xy 274.525378 -288.883634) (xy 274.539744 -288.869271) (xy 274.558509 -288.861493)
			(xy 274.568666 -288.860992) (xy 275.968206 -288.860992) (xy 275.978358 -288.861527) (xy 275.997119 -288.869295)
			(xy 276.011482 -288.883648) (xy 276.019265 -288.902402) (xy 276.019768 -288.912554) (xy 276.019768 -289.321494)
			(xy 282.060904 -289.321494) (xy 282.060904 -288.912554) (xy 282.061395 -288.902397) (xy 282.069178 -288.883634)
			(xy 282.083544 -288.869271) (xy 282.102309 -288.861493) (xy 282.112466 -288.860992) (xy 283.512006 -288.860992)
			(xy 283.522158 -288.861527) (xy 283.540919 -288.869295) (xy 283.555282 -288.883648) (xy 283.563065 -288.902402)
			(xy 283.563568 -288.912554) (xy 283.563568 -289.321494) (xy 289.604704 -289.321494) (xy 289.604704 -288.912554)
			(xy 289.605195 -288.902397) (xy 289.612978 -288.883634) (xy 289.627344 -288.869271) (xy 289.646109 -288.861493)
			(xy 289.656266 -288.860992) (xy 291.055806 -288.860992) (xy 291.065958 -288.861527) (xy 291.084719 -288.869295)
			(xy 291.099082 -288.883648) (xy 291.106865 -288.902402) (xy 291.107368 -288.912554) (xy 291.107368 -289.321494)
			(xy 297.148504 -289.321494) (xy 297.148504 -288.912554) (xy 297.148995 -288.902397) (xy 297.156778 -288.883634)
			(xy 297.171144 -288.869271) (xy 297.189909 -288.861493) (xy 297.200066 -288.860992) (xy 298.599606 -288.860992)
			(xy 298.609758 -288.861527) (xy 298.628519 -288.869295) (xy 298.642882 -288.883648) (xy 298.650665 -288.902402)
			(xy 298.651168 -288.912554) (xy 298.651168 -289.321494) (xy 304.692304 -289.321494) (xy 304.692304 -288.912554)
			(xy 304.692795 -288.902397) (xy 304.700578 -288.883634) (xy 304.714944 -288.869271) (xy 304.733709 -288.861493)
			(xy 304.743866 -288.860992) (xy 306.143406 -288.860992) (xy 306.153558 -288.861527) (xy 306.172319 -288.869295)
			(xy 306.186682 -288.883648) (xy 306.194465 -288.902402) (xy 306.194968 -288.912554) (xy 306.194968 -289.321494)
			(xy 312.236104 -289.321494) (xy 312.236104 -288.912554) (xy 312.236595 -288.902397) (xy 312.244378 -288.883634)
			(xy 312.258744 -288.869271) (xy 312.277509 -288.861493) (xy 312.287666 -288.860992) (xy 313.687206 -288.860992)
			(xy 313.697358 -288.861527) (xy 313.716119 -288.869295) (xy 313.730482 -288.883648) (xy 313.738265 -288.902402)
			(xy 313.738768 -288.912554) (xy 313.738768 -288.917126) (xy 336.335624 -288.917126) (xy 336.336149 -288.891782)
			(xy 336.343918 -288.841693) (xy 336.359261 -288.793383) (xy 336.381816 -288.74799) (xy 336.411052 -288.706584)
			(xy 336.446281 -288.67014) (xy 336.486672 -288.639516) (xy 336.531274 -288.615435) (xy 336.579036 -288.598463)
			(xy 336.603848 -288.593276) (xy 336.626708 -288.588958) (xy 336.831686 -288.233866) (xy 336.823812 -288.212022)
			(xy 336.815238 -288.185602) (xy 336.806038 -288.130828) (xy 336.805524 -288.103056) (xy 336.806032 -288.077169)
			(xy 336.814131 -288.026031) (xy 336.83013 -287.976791) (xy 336.853636 -287.930659) (xy 336.884068 -287.888772)
			(xy 336.920678 -287.852162) (xy 336.962565 -287.82173) (xy 337.008697 -287.798224) (xy 337.057937 -287.782225)
			(xy 337.109075 -287.774126) (xy 337.160849 -287.774126) (xy 337.211987 -287.782225) (xy 337.261227 -287.798224)
			(xy 337.307359 -287.82173) (xy 337.349246 -287.852162) (xy 337.385856 -287.888772) (xy 337.416288 -287.930659)
			(xy 337.439794 -287.976791) (xy 337.455793 -288.026031) (xy 337.463892 -288.077169) (xy 337.4644 -288.103056)
			(xy 337.463968 -288.128392) (xy 337.456207 -288.178467) (xy 337.440877 -288.226765) (xy 337.418339 -288.272149)
			(xy 337.389123 -288.31355) (xy 337.353916 -288.349995) (xy 337.313549 -288.380624) (xy 337.268971 -288.404718)
			(xy 337.221232 -288.421708) (xy 337.19643 -288.426906) (xy 337.17357 -288.431224) (xy 336.968592 -288.786316)
			(xy 336.976466 -288.80816) (xy 336.985119 -288.834566) (xy 336.994435 -288.889344) (xy 336.995008 -288.917126)
			(xy 338.215224 -288.917126) (xy 338.215749 -288.891782) (xy 338.223518 -288.841693) (xy 338.238861 -288.793383)
			(xy 338.261416 -288.74799) (xy 338.290652 -288.706584) (xy 338.325881 -288.67014) (xy 338.366272 -288.639516)
			(xy 338.410874 -288.615435) (xy 338.458636 -288.598463) (xy 338.483448 -288.593276) (xy 338.506308 -288.588958)
			(xy 338.711286 -288.233866) (xy 338.703412 -288.212022) (xy 338.694838 -288.185602) (xy 338.685638 -288.130828)
			(xy 338.685124 -288.103056) (xy 338.685632 -288.077169) (xy 338.693731 -288.026031) (xy 338.70973 -287.976791)
			(xy 338.733236 -287.930659) (xy 338.763668 -287.888772) (xy 338.800278 -287.852162) (xy 338.842165 -287.82173)
			(xy 338.888297 -287.798224) (xy 338.937537 -287.782225) (xy 338.988675 -287.774126) (xy 339.040449 -287.774126)
			(xy 339.091587 -287.782225) (xy 339.140827 -287.798224) (xy 339.186959 -287.82173) (xy 339.228846 -287.852162)
			(xy 339.265456 -287.888772) (xy 339.295888 -287.930659) (xy 339.319394 -287.976791) (xy 339.335393 -288.026031)
			(xy 339.343492 -288.077169) (xy 339.344 -288.103056) (xy 339.343568 -288.128392) (xy 339.335807 -288.178467)
			(xy 339.320477 -288.226765) (xy 339.297939 -288.272149) (xy 339.268723 -288.31355) (xy 339.233516 -288.349995)
			(xy 339.193149 -288.380624) (xy 339.148571 -288.404718) (xy 339.100832 -288.421708) (xy 339.07603 -288.426906)
			(xy 339.05317 -288.431224) (xy 338.848192 -288.786316) (xy 338.856066 -288.80816) (xy 338.864719 -288.834566)
			(xy 338.874035 -288.889344) (xy 338.874608 -288.917126) (xy 339.155024 -288.917126) (xy 339.155532 -288.891219)
			(xy 339.163638 -288.840042) (xy 339.17965 -288.790763) (xy 339.203173 -288.744596) (xy 339.233629 -288.702677)
			(xy 339.270267 -288.666039) (xy 339.312186 -288.635583) (xy 339.358353 -288.61206) (xy 339.407632 -288.596048)
			(xy 339.458809 -288.587942) (xy 339.510623 -288.587942) (xy 339.5618 -288.596048) (xy 339.611079 -288.61206)
			(xy 339.657246 -288.635583) (xy 339.699165 -288.666039) (xy 339.735803 -288.702677) (xy 339.766259 -288.744596)
			(xy 339.789782 -288.790763) (xy 339.805794 -288.840042) (xy 339.8139 -288.891219) (xy 339.814408 -288.917126)
			(xy 340.094824 -288.917126) (xy 340.095349 -288.891782) (xy 340.103118 -288.841693) (xy 340.118461 -288.793383)
			(xy 340.141016 -288.74799) (xy 340.170252 -288.706584) (xy 340.205481 -288.67014) (xy 340.245872 -288.639516)
			(xy 340.290474 -288.615435) (xy 340.338236 -288.598463) (xy 340.363048 -288.593276) (xy 340.385908 -288.588958)
			(xy 340.59114 -288.233866) (xy 340.583266 -288.211768) (xy 340.574642 -288.185419) (xy 340.565317 -288.130773)
			(xy 340.564724 -288.103056) (xy 340.565232 -288.077149) (xy 340.573338 -288.025972) (xy 340.58935 -287.976693)
			(xy 340.612873 -287.930526) (xy 340.643329 -287.888607) (xy 340.679967 -287.851969) (xy 340.721886 -287.821513)
			(xy 340.768053 -287.79799) (xy 340.817332 -287.781978) (xy 340.868509 -287.773872) (xy 340.920323 -287.773872)
			(xy 340.9715 -287.781978) (xy 341.020779 -287.79799) (xy 341.066946 -287.821513) (xy 341.108865 -287.851969)
			(xy 341.145503 -287.888607) (xy 341.175959 -287.930526) (xy 341.199482 -287.976693) (xy 341.215494 -288.025972)
			(xy 341.2236 -288.077149) (xy 341.224108 -288.103056) (xy 341.223631 -288.128401) (xy 341.215851 -288.178491)
			(xy 341.200499 -288.2268) (xy 341.177936 -288.272192) (xy 341.148694 -288.313597) (xy 341.11346 -288.35004)
			(xy 341.073065 -288.380663) (xy 341.028461 -288.404744) (xy 340.980697 -288.421718) (xy 340.955884 -288.426906)
			(xy 340.933024 -288.431224) (xy 340.727792 -288.786316) (xy 340.735666 -288.808414) (xy 340.744307 -288.834758)
			(xy 340.753621 -288.889407) (xy 340.754208 -288.917126) (xy 341.034624 -288.917126) (xy 341.035132 -288.891219)
			(xy 341.043238 -288.840042) (xy 341.05925 -288.790763) (xy 341.082773 -288.744596) (xy 341.113229 -288.702677)
			(xy 341.149867 -288.666039) (xy 341.191786 -288.635583) (xy 341.237953 -288.61206) (xy 341.287232 -288.596048)
			(xy 341.338409 -288.587942) (xy 341.390223 -288.587942) (xy 341.4414 -288.596048) (xy 341.490679 -288.61206)
			(xy 341.536846 -288.635583) (xy 341.578765 -288.666039) (xy 341.615403 -288.702677) (xy 341.645859 -288.744596)
			(xy 341.669382 -288.790763) (xy 341.685394 -288.840042) (xy 341.6935 -288.891219) (xy 341.694008 -288.917126)
			(xy 341.974424 -288.917126) (xy 341.974949 -288.891782) (xy 341.982718 -288.841693) (xy 341.998061 -288.793383)
			(xy 342.020616 -288.74799) (xy 342.049852 -288.706584) (xy 342.085081 -288.67014) (xy 342.125472 -288.639516)
			(xy 342.170074 -288.615435) (xy 342.217836 -288.598463) (xy 342.242648 -288.593276) (xy 342.265508 -288.588958)
			(xy 342.47074 -288.233866) (xy 342.462866 -288.211768) (xy 342.454242 -288.185419) (xy 342.444917 -288.130773)
			(xy 342.444324 -288.103056) (xy 342.444832 -288.077149) (xy 342.452938 -288.025972) (xy 342.46895 -287.976693)
			(xy 342.492473 -287.930526) (xy 342.522929 -287.888607) (xy 342.559567 -287.851969) (xy 342.601486 -287.821513)
			(xy 342.647653 -287.79799) (xy 342.696932 -287.781978) (xy 342.748109 -287.773872) (xy 342.799923 -287.773872)
			(xy 342.8511 -287.781978) (xy 342.900379 -287.79799) (xy 342.946546 -287.821513) (xy 342.988465 -287.851969)
			(xy 343.025103 -287.888607) (xy 343.055559 -287.930526) (xy 343.079082 -287.976693) (xy 343.095094 -288.025972)
			(xy 343.1032 -288.077149) (xy 343.103708 -288.103056) (xy 343.103231 -288.128401) (xy 343.095451 -288.178491)
			(xy 343.080099 -288.2268) (xy 343.057536 -288.272192) (xy 343.028294 -288.313597) (xy 342.99306 -288.35004)
			(xy 342.952665 -288.380663) (xy 342.908061 -288.404744) (xy 342.860297 -288.421718) (xy 342.835484 -288.426906)
			(xy 342.812624 -288.431224) (xy 342.607392 -288.786316) (xy 342.615266 -288.808414) (xy 342.623907 -288.834758)
			(xy 342.633221 -288.889407) (xy 342.633808 -288.917126) (xy 342.914224 -288.917126) (xy 342.914732 -288.891219)
			(xy 342.922838 -288.840042) (xy 342.93885 -288.790763) (xy 342.962373 -288.744596) (xy 342.992829 -288.702677)
			(xy 343.029467 -288.666039) (xy 343.071386 -288.635583) (xy 343.117553 -288.61206) (xy 343.166832 -288.596048)
			(xy 343.218009 -288.587942) (xy 343.269823 -288.587942) (xy 343.321 -288.596048) (xy 343.370279 -288.61206)
			(xy 343.416446 -288.635583) (xy 343.458365 -288.666039) (xy 343.495003 -288.702677) (xy 343.525459 -288.744596)
			(xy 343.548982 -288.790763) (xy 343.564994 -288.840042) (xy 343.5731 -288.891219) (xy 343.573608 -288.917126)
			(xy 343.854024 -288.917126) (xy 343.854549 -288.891782) (xy 343.862318 -288.841693) (xy 343.877661 -288.793383)
			(xy 343.900216 -288.74799) (xy 343.929452 -288.706584) (xy 343.964681 -288.67014) (xy 344.005072 -288.639516)
			(xy 344.049674 -288.615435) (xy 344.097436 -288.598463) (xy 344.122248 -288.593276) (xy 344.145108 -288.588958)
			(xy 344.35034 -288.233866) (xy 344.342466 -288.211768) (xy 344.333842 -288.185419) (xy 344.324517 -288.130773)
			(xy 344.323924 -288.103056) (xy 344.324432 -288.077149) (xy 344.332538 -288.025972) (xy 344.34855 -287.976693)
			(xy 344.372073 -287.930526) (xy 344.402529 -287.888607) (xy 344.439167 -287.851969) (xy 344.481086 -287.821513)
			(xy 344.527253 -287.79799) (xy 344.576532 -287.781978) (xy 344.627709 -287.773872) (xy 344.679523 -287.773872)
			(xy 344.7307 -287.781978) (xy 344.779979 -287.79799) (xy 344.826146 -287.821513) (xy 344.868065 -287.851969)
			(xy 344.904703 -287.888607) (xy 344.935159 -287.930526) (xy 344.958682 -287.976693) (xy 344.974694 -288.025972)
			(xy 344.9828 -288.077149) (xy 344.983308 -288.103056) (xy 344.982831 -288.128401) (xy 344.975051 -288.178491)
			(xy 344.959699 -288.2268) (xy 344.937136 -288.272192) (xy 344.907894 -288.313597) (xy 344.87266 -288.35004)
			(xy 344.832265 -288.380663) (xy 344.787661 -288.404744) (xy 344.739897 -288.421718) (xy 344.715084 -288.426906)
			(xy 344.692224 -288.431224) (xy 344.486992 -288.786316) (xy 344.494866 -288.808414) (xy 344.503507 -288.834758)
			(xy 344.512821 -288.889407) (xy 344.513408 -288.917126) (xy 344.793824 -288.917126) (xy 344.794332 -288.891219)
			(xy 344.802438 -288.840042) (xy 344.81845 -288.790763) (xy 344.841973 -288.744596) (xy 344.872429 -288.702677)
			(xy 344.909067 -288.666039) (xy 344.950986 -288.635583) (xy 344.997153 -288.61206) (xy 345.046432 -288.596048)
			(xy 345.097609 -288.587942) (xy 345.149423 -288.587942) (xy 345.2006 -288.596048) (xy 345.249879 -288.61206)
			(xy 345.296046 -288.635583) (xy 345.337965 -288.666039) (xy 345.374603 -288.702677) (xy 345.405059 -288.744596)
			(xy 345.428582 -288.790763) (xy 345.444594 -288.840042) (xy 345.4527 -288.891219) (xy 345.453208 -288.917126)
			(xy 345.733624 -288.917126) (xy 345.734149 -288.891782) (xy 345.741918 -288.841693) (xy 345.757261 -288.793383)
			(xy 345.779816 -288.74799) (xy 345.809052 -288.706584) (xy 345.844281 -288.67014) (xy 345.884672 -288.639516)
			(xy 345.929274 -288.615435) (xy 345.977036 -288.598463) (xy 346.001848 -288.593276) (xy 346.024708 -288.588958)
			(xy 346.22994 -288.233866) (xy 346.222066 -288.211768) (xy 346.213442 -288.185419) (xy 346.204117 -288.130773)
			(xy 346.203524 -288.103056) (xy 346.204032 -288.077149) (xy 346.212138 -288.025972) (xy 346.22815 -287.976693)
			(xy 346.251673 -287.930526) (xy 346.282129 -287.888607) (xy 346.318767 -287.851969) (xy 346.360686 -287.821513)
			(xy 346.406853 -287.79799) (xy 346.456132 -287.781978) (xy 346.507309 -287.773872) (xy 346.559123 -287.773872)
			(xy 346.6103 -287.781978) (xy 346.659579 -287.79799) (xy 346.705746 -287.821513) (xy 346.747665 -287.851969)
			(xy 346.784303 -287.888607) (xy 346.814759 -287.930526) (xy 346.838282 -287.976693) (xy 346.854294 -288.025972)
			(xy 346.8624 -288.077149) (xy 346.862908 -288.103056) (xy 346.862431 -288.128401) (xy 346.854651 -288.178491)
			(xy 346.839299 -288.2268) (xy 346.816736 -288.272192) (xy 346.787494 -288.313597) (xy 346.75226 -288.35004)
			(xy 346.711865 -288.380663) (xy 346.667261 -288.404744) (xy 346.619497 -288.421718) (xy 346.594684 -288.426906)
			(xy 346.571824 -288.431224) (xy 346.366592 -288.786316) (xy 346.374466 -288.808414) (xy 346.383107 -288.834758)
			(xy 346.392421 -288.889407) (xy 346.393008 -288.917126) (xy 346.673424 -288.917126) (xy 346.673932 -288.891219)
			(xy 346.682038 -288.840042) (xy 346.69805 -288.790763) (xy 346.721573 -288.744596) (xy 346.752029 -288.702677)
			(xy 346.788667 -288.666039) (xy 346.830586 -288.635583) (xy 346.876753 -288.61206) (xy 346.926032 -288.596048)
			(xy 346.977209 -288.587942) (xy 347.029023 -288.587942) (xy 347.0802 -288.596048) (xy 347.129479 -288.61206)
			(xy 347.175646 -288.635583) (xy 347.217565 -288.666039) (xy 347.254203 -288.702677) (xy 347.284659 -288.744596)
			(xy 347.308182 -288.790763) (xy 347.324194 -288.840042) (xy 347.3323 -288.891219) (xy 347.332808 -288.917126)
			(xy 347.613224 -288.917126) (xy 347.613749 -288.891782) (xy 347.621518 -288.841693) (xy 347.636861 -288.793383)
			(xy 347.659416 -288.74799) (xy 347.688652 -288.706584) (xy 347.723881 -288.67014) (xy 347.764272 -288.639516)
			(xy 347.808874 -288.615435) (xy 347.856636 -288.598463) (xy 347.881448 -288.593276) (xy 347.904308 -288.588958)
			(xy 348.10954 -288.233866) (xy 348.101666 -288.211768) (xy 348.093042 -288.185419) (xy 348.083717 -288.130773)
			(xy 348.083124 -288.103056) (xy 348.083632 -288.077149) (xy 348.091738 -288.025972) (xy 348.10775 -287.976693)
			(xy 348.131273 -287.930526) (xy 348.161729 -287.888607) (xy 348.198367 -287.851969) (xy 348.240286 -287.821513)
			(xy 348.286453 -287.79799) (xy 348.335732 -287.781978) (xy 348.386909 -287.773872) (xy 348.438723 -287.773872)
			(xy 348.4899 -287.781978) (xy 348.539179 -287.79799) (xy 348.585346 -287.821513) (xy 348.627265 -287.851969)
			(xy 348.663903 -287.888607) (xy 348.694359 -287.930526) (xy 348.717882 -287.976693) (xy 348.733894 -288.025972)
			(xy 348.742 -288.077149) (xy 348.742508 -288.103056) (xy 348.742031 -288.128401) (xy 348.734251 -288.178491)
			(xy 348.718899 -288.2268) (xy 348.696336 -288.272192) (xy 348.667094 -288.313597) (xy 348.63186 -288.35004)
			(xy 348.591465 -288.380663) (xy 348.546861 -288.404744) (xy 348.499097 -288.421718) (xy 348.474284 -288.426906)
			(xy 348.451424 -288.431224) (xy 348.246192 -288.786316) (xy 348.254066 -288.808414) (xy 348.262707 -288.834758)
			(xy 348.272021 -288.889407) (xy 348.272608 -288.917126) (xy 348.553024 -288.917126) (xy 348.553532 -288.891219)
			(xy 348.561638 -288.840042) (xy 348.57765 -288.790763) (xy 348.601173 -288.744596) (xy 348.631629 -288.702677)
			(xy 348.668267 -288.666039) (xy 348.710186 -288.635583) (xy 348.756353 -288.61206) (xy 348.805632 -288.596048)
			(xy 348.856809 -288.587942) (xy 348.908623 -288.587942) (xy 348.9598 -288.596048) (xy 349.009079 -288.61206)
			(xy 349.055246 -288.635583) (xy 349.097165 -288.666039) (xy 349.133803 -288.702677) (xy 349.164259 -288.744596)
			(xy 349.187782 -288.790763) (xy 349.203794 -288.840042) (xy 349.2119 -288.891219) (xy 349.212408 -288.917126)
			(xy 349.492824 -288.917126) (xy 349.493349 -288.891782) (xy 349.501118 -288.841693) (xy 349.516461 -288.793383)
			(xy 349.539016 -288.74799) (xy 349.568252 -288.706584) (xy 349.603481 -288.67014) (xy 349.643872 -288.639516)
			(xy 349.688474 -288.615435) (xy 349.736236 -288.598463) (xy 349.761048 -288.593276) (xy 349.783908 -288.588958)
			(xy 349.98914 -288.233866) (xy 349.981266 -288.211768) (xy 349.972642 -288.185419) (xy 349.963317 -288.130773)
			(xy 349.962724 -288.103056) (xy 349.963232 -288.077149) (xy 349.971338 -288.025972) (xy 349.98735 -287.976693)
			(xy 350.010873 -287.930526) (xy 350.041329 -287.888607) (xy 350.077967 -287.851969) (xy 350.119886 -287.821513)
			(xy 350.166053 -287.79799) (xy 350.215332 -287.781978) (xy 350.266509 -287.773872) (xy 350.318323 -287.773872)
			(xy 350.3695 -287.781978) (xy 350.418779 -287.79799) (xy 350.464946 -287.821513) (xy 350.506865 -287.851969)
			(xy 350.543503 -287.888607) (xy 350.573959 -287.930526) (xy 350.597482 -287.976693) (xy 350.613494 -288.025972)
			(xy 350.6216 -288.077149) (xy 350.622108 -288.103056) (xy 350.621631 -288.128401) (xy 350.613851 -288.178491)
			(xy 350.598499 -288.2268) (xy 350.575936 -288.272192) (xy 350.546694 -288.313597) (xy 350.51146 -288.35004)
			(xy 350.471065 -288.380663) (xy 350.426461 -288.404744) (xy 350.378697 -288.421718) (xy 350.353884 -288.426906)
			(xy 350.331024 -288.431224) (xy 350.125792 -288.786316) (xy 350.133666 -288.808414) (xy 350.142307 -288.834758)
			(xy 350.151621 -288.889407) (xy 350.152208 -288.917126) (xy 350.432624 -288.917126) (xy 350.433132 -288.891219)
			(xy 350.441238 -288.840042) (xy 350.45725 -288.790763) (xy 350.480773 -288.744596) (xy 350.511229 -288.702677)
			(xy 350.547867 -288.666039) (xy 350.589786 -288.635583) (xy 350.635953 -288.61206) (xy 350.685232 -288.596048)
			(xy 350.736409 -288.587942) (xy 350.788223 -288.587942) (xy 350.8394 -288.596048) (xy 350.888679 -288.61206)
			(xy 350.934846 -288.635583) (xy 350.976765 -288.666039) (xy 351.013403 -288.702677) (xy 351.043859 -288.744596)
			(xy 351.067382 -288.790763) (xy 351.083394 -288.840042) (xy 351.0915 -288.891219) (xy 351.092008 -288.917126)
			(xy 351.372424 -288.917126) (xy 351.372949 -288.891782) (xy 351.380718 -288.841693) (xy 351.396061 -288.793383)
			(xy 351.418616 -288.74799) (xy 351.447852 -288.706584) (xy 351.483081 -288.67014) (xy 351.523472 -288.639516)
			(xy 351.568074 -288.615435) (xy 351.615836 -288.598463) (xy 351.640648 -288.593276) (xy 351.663508 -288.588958)
			(xy 351.86874 -288.233866) (xy 351.860866 -288.211768) (xy 351.852242 -288.185419) (xy 351.842917 -288.130773)
			(xy 351.842324 -288.103056) (xy 351.842832 -288.077149) (xy 351.850938 -288.025972) (xy 351.86695 -287.976693)
			(xy 351.890473 -287.930526) (xy 351.920929 -287.888607) (xy 351.957567 -287.851969) (xy 351.999486 -287.821513)
			(xy 352.045653 -287.79799) (xy 352.094932 -287.781978) (xy 352.146109 -287.773872) (xy 352.197923 -287.773872)
			(xy 352.2491 -287.781978) (xy 352.298379 -287.79799) (xy 352.344546 -287.821513) (xy 352.386465 -287.851969)
			(xy 352.423103 -287.888607) (xy 352.453559 -287.930526) (xy 352.477082 -287.976693) (xy 352.493094 -288.025972)
			(xy 352.5012 -288.077149) (xy 352.501708 -288.103056) (xy 368.758724 -288.103056) (xy 368.759232 -288.077149)
			(xy 368.767338 -288.025972) (xy 368.78335 -287.976693) (xy 368.806873 -287.930526) (xy 368.837329 -287.888607)
			(xy 368.873967 -287.851969) (xy 368.915886 -287.821513) (xy 368.962053 -287.79799) (xy 369.011332 -287.781978)
			(xy 369.062509 -287.773872) (xy 369.114323 -287.773872) (xy 369.1655 -287.781978) (xy 369.214779 -287.79799)
			(xy 369.260946 -287.821513) (xy 369.302865 -287.851969) (xy 369.339503 -287.888607) (xy 369.369959 -287.930526)
			(xy 369.393482 -287.976693) (xy 369.409494 -288.025972) (xy 369.4176 -288.077149) (xy 369.418108 -288.103056)
			(xy 370.638324 -288.103056) (xy 370.638832 -288.077149) (xy 370.646938 -288.025972) (xy 370.66295 -287.976693)
			(xy 370.686473 -287.930526) (xy 370.716929 -287.888607) (xy 370.753567 -287.851969) (xy 370.795486 -287.821513)
			(xy 370.841653 -287.79799) (xy 370.890932 -287.781978) (xy 370.942109 -287.773872) (xy 370.993923 -287.773872)
			(xy 371.0451 -287.781978) (xy 371.094379 -287.79799) (xy 371.140546 -287.821513) (xy 371.182465 -287.851969)
			(xy 371.219103 -287.888607) (xy 371.249559 -287.930526) (xy 371.273082 -287.976693) (xy 371.289094 -288.025972)
			(xy 371.2972 -288.077149) (xy 371.297708 -288.103056) (xy 372.517924 -288.103056) (xy 372.518432 -288.077149)
			(xy 372.526538 -288.025972) (xy 372.54255 -287.976693) (xy 372.566073 -287.930526) (xy 372.596529 -287.888607)
			(xy 372.633167 -287.851969) (xy 372.675086 -287.821513) (xy 372.721253 -287.79799) (xy 372.770532 -287.781978)
			(xy 372.821709 -287.773872) (xy 372.873523 -287.773872) (xy 372.9247 -287.781978) (xy 372.973979 -287.79799)
			(xy 373.020146 -287.821513) (xy 373.062065 -287.851969) (xy 373.098703 -287.888607) (xy 373.129159 -287.930526)
			(xy 373.152682 -287.976693) (xy 373.168694 -288.025972) (xy 373.1768 -288.077149) (xy 373.177308 -288.103056)
			(xy 374.397524 -288.103056) (xy 374.398032 -288.077149) (xy 374.406138 -288.025972) (xy 374.42215 -287.976693)
			(xy 374.445673 -287.930526) (xy 374.476129 -287.888607) (xy 374.512767 -287.851969) (xy 374.554686 -287.821513)
			(xy 374.600853 -287.79799) (xy 374.650132 -287.781978) (xy 374.701309 -287.773872) (xy 374.753123 -287.773872)
			(xy 374.8043 -287.781978) (xy 374.853579 -287.79799) (xy 374.899746 -287.821513) (xy 374.941665 -287.851969)
			(xy 374.978303 -287.888607) (xy 375.008759 -287.930526) (xy 375.032282 -287.976693) (xy 375.048294 -288.025972)
			(xy 375.0564 -288.077149) (xy 375.056908 -288.103056) (xy 376.277124 -288.103056) (xy 376.277632 -288.077149)
			(xy 376.285738 -288.025972) (xy 376.30175 -287.976693) (xy 376.325273 -287.930526) (xy 376.355729 -287.888607)
			(xy 376.392367 -287.851969) (xy 376.434286 -287.821513) (xy 376.480453 -287.79799) (xy 376.529732 -287.781978)
			(xy 376.580909 -287.773872) (xy 376.632723 -287.773872) (xy 376.6839 -287.781978) (xy 376.733179 -287.79799)
			(xy 376.779346 -287.821513) (xy 376.821265 -287.851969) (xy 376.857903 -287.888607) (xy 376.888359 -287.930526)
			(xy 376.911882 -287.976693) (xy 376.927894 -288.025972) (xy 376.936 -288.077149) (xy 376.936508 -288.103056)
			(xy 378.156724 -288.103056) (xy 378.157232 -288.077149) (xy 378.165338 -288.025972) (xy 378.18135 -287.976693)
			(xy 378.204873 -287.930526) (xy 378.235329 -287.888607) (xy 378.271967 -287.851969) (xy 378.313886 -287.821513)
			(xy 378.360053 -287.79799) (xy 378.409332 -287.781978) (xy 378.460509 -287.773872) (xy 378.512323 -287.773872)
			(xy 378.5635 -287.781978) (xy 378.612779 -287.79799) (xy 378.658946 -287.821513) (xy 378.700865 -287.851969)
			(xy 378.737503 -287.888607) (xy 378.767959 -287.930526) (xy 378.791482 -287.976693) (xy 378.807494 -288.025972)
			(xy 378.8156 -288.077149) (xy 378.816108 -288.103056) (xy 380.036324 -288.103056) (xy 380.036832 -288.077149)
			(xy 380.044938 -288.025972) (xy 380.06095 -287.976693) (xy 380.084473 -287.930526) (xy 380.114929 -287.888607)
			(xy 380.151567 -287.851969) (xy 380.193486 -287.821513) (xy 380.239653 -287.79799) (xy 380.288932 -287.781978)
			(xy 380.340109 -287.773872) (xy 380.391923 -287.773872) (xy 380.4431 -287.781978) (xy 380.492379 -287.79799)
			(xy 380.538546 -287.821513) (xy 380.580465 -287.851969) (xy 380.617103 -287.888607) (xy 380.647559 -287.930526)
			(xy 380.671082 -287.976693) (xy 380.687094 -288.025972) (xy 380.6952 -288.077149) (xy 380.695708 -288.103056)
			(xy 382.855724 -288.103056) (xy 382.856232 -288.077149) (xy 382.864338 -288.025972) (xy 382.88035 -287.976693)
			(xy 382.903873 -287.930526) (xy 382.934329 -287.888607) (xy 382.970967 -287.851969) (xy 383.012886 -287.821513)
			(xy 383.059053 -287.79799) (xy 383.108332 -287.781978) (xy 383.159509 -287.773872) (xy 383.211323 -287.773872)
			(xy 383.2625 -287.781978) (xy 383.311779 -287.79799) (xy 383.357946 -287.821513) (xy 383.399865 -287.851969)
			(xy 383.436503 -287.888607) (xy 383.466959 -287.930526) (xy 383.490482 -287.976693) (xy 383.506494 -288.025972)
			(xy 383.5146 -288.077149) (xy 383.515108 -288.103056) (xy 383.514503 -288.130773) (xy 383.505187 -288.185419)
			(xy 383.496566 -288.211768) (xy 383.488692 -288.233866) (xy 383.625954 -288.471356) (xy 406.002236 -288.471356)
			(xy 406.002236 -288.062416) (xy 406.002635 -288.052258) (xy 406.010432 -288.033499) (xy 406.024837 -288.019174)
			(xy 406.043638 -288.01148) (xy 406.053798 -288.011108) (xy 407.453338 -288.011108) (xy 407.463463 -288.011594)
			(xy 407.482179 -288.019329) (xy 407.496533 -288.033614) (xy 407.504356 -288.052293) (xy 407.5049 -288.062416)
			(xy 407.5049 -288.471356) (xy 413.546036 -288.471356) (xy 413.546036 -288.062416) (xy 413.546435 -288.052258)
			(xy 413.554232 -288.033499) (xy 413.568637 -288.019174) (xy 413.587438 -288.01148) (xy 413.597598 -288.011108)
			(xy 414.997138 -288.011108) (xy 415.007263 -288.011594) (xy 415.025979 -288.019329) (xy 415.040333 -288.033614)
			(xy 415.048156 -288.052293) (xy 415.0487 -288.062416) (xy 415.0487 -288.471356) (xy 421.089836 -288.471356)
			(xy 421.089836 -288.062416) (xy 421.090235 -288.052258) (xy 421.098032 -288.033499) (xy 421.112437 -288.019174)
			(xy 421.131238 -288.01148) (xy 421.141398 -288.011108) (xy 422.540938 -288.011108) (xy 422.551063 -288.011594)
			(xy 422.569779 -288.019329) (xy 422.584133 -288.033614) (xy 422.591956 -288.052293) (xy 422.5925 -288.062416)
			(xy 422.5925 -288.471356) (xy 428.633636 -288.471356) (xy 428.633636 -288.062416) (xy 428.634035 -288.052258)
			(xy 428.641832 -288.033499) (xy 428.656237 -288.019174) (xy 428.675038 -288.01148) (xy 428.685198 -288.011108)
			(xy 430.084738 -288.011108) (xy 430.094863 -288.011594) (xy 430.113579 -288.019329) (xy 430.127933 -288.033614)
			(xy 430.135756 -288.052293) (xy 430.1363 -288.062416) (xy 430.1363 -288.471356) (xy 436.177436 -288.471356)
			(xy 436.177436 -288.062416) (xy 436.177835 -288.052258) (xy 436.185632 -288.033499) (xy 436.200037 -288.019174)
			(xy 436.218838 -288.01148) (xy 436.228998 -288.011108) (xy 437.628538 -288.011108) (xy 437.638663 -288.011594)
			(xy 437.657379 -288.019329) (xy 437.671733 -288.033614) (xy 437.679556 -288.052293) (xy 437.6801 -288.062416)
			(xy 437.6801 -288.471356) (xy 443.721236 -288.471356) (xy 443.721236 -288.062416) (xy 443.721635 -288.052258)
			(xy 443.729432 -288.033499) (xy 443.743837 -288.019174) (xy 443.762638 -288.01148) (xy 443.772798 -288.011108)
			(xy 445.172338 -288.011108) (xy 445.182463 -288.011594) (xy 445.201179 -288.019329) (xy 445.215533 -288.033614)
			(xy 445.223356 -288.052293) (xy 445.2239 -288.062416) (xy 445.2239 -288.471356) (xy 451.265036 -288.471356)
			(xy 451.265036 -288.062416) (xy 451.265435 -288.052258) (xy 451.273232 -288.033499) (xy 451.287637 -288.019174)
			(xy 451.306438 -288.01148) (xy 451.316598 -288.011108) (xy 452.716138 -288.011108) (xy 452.726263 -288.011594)
			(xy 452.744979 -288.019329) (xy 452.759333 -288.033614) (xy 452.767156 -288.052293) (xy 452.7677 -288.062416)
			(xy 452.7677 -288.471356) (xy 458.808836 -288.471356) (xy 458.808836 -288.062416) (xy 458.809235 -288.052258)
			(xy 458.817032 -288.033499) (xy 458.831437 -288.019174) (xy 458.850238 -288.01148) (xy 458.860398 -288.011108)
			(xy 460.259938 -288.011108) (xy 460.270063 -288.011594) (xy 460.288779 -288.019329) (xy 460.303133 -288.033614)
			(xy 460.310956 -288.052293) (xy 460.3115 -288.062416) (xy 460.3115 -288.471356) (xy 460.311042 -288.481507)
			(xy 460.303261 -288.500259) (xy 460.288875 -288.514584) (xy 460.270091 -288.522285) (xy 460.259938 -288.522664)
			(xy 458.860398 -288.522664) (xy 458.850272 -288.522175) (xy 458.831551 -288.514447) (xy 458.817195 -288.500162)
			(xy 458.809375 -288.48148) (xy 458.808836 -288.471356) (xy 452.7677 -288.471356) (xy 452.767242 -288.481507)
			(xy 452.759461 -288.500259) (xy 452.745075 -288.514584) (xy 452.726291 -288.522285) (xy 452.716138 -288.522664)
			(xy 451.316598 -288.522664) (xy 451.306472 -288.522175) (xy 451.287751 -288.514447) (xy 451.273395 -288.500162)
			(xy 451.265575 -288.48148) (xy 451.265036 -288.471356) (xy 445.2239 -288.471356) (xy 445.223442 -288.481507)
			(xy 445.215661 -288.500259) (xy 445.201275 -288.514584) (xy 445.182491 -288.522285) (xy 445.172338 -288.522664)
			(xy 443.772798 -288.522664) (xy 443.762672 -288.522175) (xy 443.743951 -288.514447) (xy 443.729595 -288.500162)
			(xy 443.721775 -288.48148) (xy 443.721236 -288.471356) (xy 437.6801 -288.471356) (xy 437.679642 -288.481507)
			(xy 437.671861 -288.500259) (xy 437.657475 -288.514584) (xy 437.638691 -288.522285) (xy 437.628538 -288.522664)
			(xy 436.228998 -288.522664) (xy 436.218872 -288.522175) (xy 436.200151 -288.514447) (xy 436.185795 -288.500162)
			(xy 436.177975 -288.48148) (xy 436.177436 -288.471356) (xy 430.1363 -288.471356) (xy 430.135842 -288.481507)
			(xy 430.128061 -288.500259) (xy 430.113675 -288.514584) (xy 430.094891 -288.522285) (xy 430.084738 -288.522664)
			(xy 428.685198 -288.522664) (xy 428.675072 -288.522175) (xy 428.656351 -288.514447) (xy 428.641995 -288.500162)
			(xy 428.634175 -288.48148) (xy 428.633636 -288.471356) (xy 422.5925 -288.471356) (xy 422.592042 -288.481507)
			(xy 422.584261 -288.500259) (xy 422.569875 -288.514584) (xy 422.551091 -288.522285) (xy 422.540938 -288.522664)
			(xy 421.141398 -288.522664) (xy 421.131272 -288.522175) (xy 421.112551 -288.514447) (xy 421.098195 -288.500162)
			(xy 421.090375 -288.48148) (xy 421.089836 -288.471356) (xy 415.0487 -288.471356) (xy 415.048242 -288.481507)
			(xy 415.040461 -288.500259) (xy 415.026075 -288.514584) (xy 415.007291 -288.522285) (xy 414.997138 -288.522664)
			(xy 413.597598 -288.522664) (xy 413.587472 -288.522175) (xy 413.568751 -288.514447) (xy 413.554395 -288.500162)
			(xy 413.546575 -288.48148) (xy 413.546036 -288.471356) (xy 407.5049 -288.471356) (xy 407.504442 -288.481507)
			(xy 407.496661 -288.500259) (xy 407.482275 -288.514584) (xy 407.463491 -288.522285) (xy 407.453338 -288.522664)
			(xy 406.053798 -288.522664) (xy 406.043672 -288.522175) (xy 406.024951 -288.514447) (xy 406.010595 -288.500162)
			(xy 406.002775 -288.48148) (xy 406.002236 -288.471356) (xy 383.625954 -288.471356) (xy 383.693924 -288.588958)
			(xy 383.716784 -288.593276) (xy 383.741606 -288.598437) (xy 383.789384 -288.615395) (xy 383.834001 -288.639469)
			(xy 383.874406 -288.67009) (xy 383.909646 -288.706538) (xy 383.93889 -288.747952) (xy 383.961447 -288.793355)
			(xy 383.976786 -288.841676) (xy 383.984545 -288.891777) (xy 383.985008 -288.917126) (xy 383.9845 -288.943033)
			(xy 383.976394 -288.99421) (xy 383.960382 -289.043489) (xy 383.936859 -289.089656) (xy 383.906403 -289.131575)
			(xy 383.869765 -289.168213) (xy 383.827846 -289.198669) (xy 383.781679 -289.222192) (xy 383.7324 -289.238204)
			(xy 383.681223 -289.24631) (xy 383.629409 -289.24631) (xy 383.578232 -289.238204) (xy 383.528953 -289.222192)
			(xy 383.482786 -289.198669) (xy 383.440867 -289.168213) (xy 383.404229 -289.131575) (xy 383.373773 -289.089656)
			(xy 383.35025 -289.043489) (xy 383.334238 -288.99421) (xy 383.326132 -288.943033) (xy 383.325624 -288.917126)
			(xy 383.326223 -288.889409) (xy 383.335543 -288.834762) (xy 383.344166 -288.808414) (xy 383.35204 -288.786316)
			(xy 383.146808 -288.431224) (xy 383.123948 -288.426906) (xy 383.099127 -288.421739) (xy 383.051348 -288.404784)
			(xy 383.006729 -288.380713) (xy 382.966322 -288.350092) (xy 382.931082 -288.313646) (xy 382.901838 -288.272232)
			(xy 382.879281 -288.226828) (xy 382.863943 -288.178506) (xy 382.856186 -288.128405) (xy 382.855724 -288.103056)
			(xy 380.695708 -288.103056) (xy 380.695103 -288.130773) (xy 380.685787 -288.185419) (xy 380.677166 -288.211768)
			(xy 380.669546 -288.233866) (xy 380.874524 -288.588958) (xy 380.897384 -288.593276) (xy 380.922206 -288.598437)
			(xy 380.969984 -288.615395) (xy 381.014601 -288.639469) (xy 381.055006 -288.67009) (xy 381.090246 -288.706538)
			(xy 381.11949 -288.747952) (xy 381.142047 -288.793355) (xy 381.157386 -288.841676) (xy 381.165145 -288.891777)
			(xy 381.165608 -288.917126) (xy 381.1651 -288.943033) (xy 381.156994 -288.99421) (xy 381.140982 -289.043489)
			(xy 381.117459 -289.089656) (xy 381.087003 -289.131575) (xy 381.050365 -289.168213) (xy 381.008446 -289.198669)
			(xy 380.962279 -289.222192) (xy 380.913 -289.238204) (xy 380.861823 -289.24631) (xy 380.810009 -289.24631)
			(xy 380.758832 -289.238204) (xy 380.709553 -289.222192) (xy 380.663386 -289.198669) (xy 380.621467 -289.168213)
			(xy 380.584829 -289.131575) (xy 380.554373 -289.089656) (xy 380.53085 -289.043489) (xy 380.514838 -288.99421)
			(xy 380.506732 -288.943033) (xy 380.506224 -288.917126) (xy 380.506823 -288.889409) (xy 380.516143 -288.834762)
			(xy 380.524766 -288.808414) (xy 380.53264 -288.786316) (xy 380.327662 -288.431224) (xy 380.304802 -288.426906)
			(xy 380.279961 -288.421779) (xy 380.232152 -288.40484) (xy 380.187502 -288.380778) (xy 380.147063 -288.350162)
			(xy 380.111791 -288.313713) (xy 380.082517 -288.272293) (xy 380.059933 -288.226877) (xy 380.044571 -288.178538)
			(xy 380.036794 -288.128417) (xy 380.036324 -288.103056) (xy 378.816108 -288.103056) (xy 378.815503 -288.130773)
			(xy 378.806187 -288.185419) (xy 378.797566 -288.211768) (xy 378.789946 -288.233866) (xy 378.994924 -288.588958)
			(xy 379.017784 -288.593276) (xy 379.042606 -288.598437) (xy 379.090384 -288.615395) (xy 379.135001 -288.639469)
			(xy 379.175406 -288.67009) (xy 379.210646 -288.706538) (xy 379.23989 -288.747952) (xy 379.262447 -288.793355)
			(xy 379.277786 -288.841676) (xy 379.285545 -288.891777) (xy 379.286008 -288.917126) (xy 379.2855 -288.943033)
			(xy 379.277394 -288.99421) (xy 379.261382 -289.043489) (xy 379.237859 -289.089656) (xy 379.207403 -289.131575)
			(xy 379.170765 -289.168213) (xy 379.128846 -289.198669) (xy 379.082679 -289.222192) (xy 379.0334 -289.238204)
			(xy 378.982223 -289.24631) (xy 378.930409 -289.24631) (xy 378.879232 -289.238204) (xy 378.829953 -289.222192)
			(xy 378.783786 -289.198669) (xy 378.741867 -289.168213) (xy 378.705229 -289.131575) (xy 378.674773 -289.089656)
			(xy 378.65125 -289.043489) (xy 378.635238 -288.99421) (xy 378.627132 -288.943033) (xy 378.626624 -288.917126)
			(xy 378.627223 -288.889409) (xy 378.636543 -288.834762) (xy 378.645166 -288.808414) (xy 378.65304 -288.786316)
			(xy 378.448062 -288.431224) (xy 378.425202 -288.426906) (xy 378.400361 -288.421779) (xy 378.352552 -288.40484)
			(xy 378.307902 -288.380778) (xy 378.267463 -288.350162) (xy 378.232191 -288.313713) (xy 378.202917 -288.272293)
			(xy 378.180333 -288.226877) (xy 378.164971 -288.178538) (xy 378.157194 -288.128417) (xy 378.156724 -288.103056)
			(xy 376.936508 -288.103056) (xy 376.935903 -288.130773) (xy 376.926587 -288.185419) (xy 376.917966 -288.211768)
			(xy 376.910346 -288.233866) (xy 377.115324 -288.588958) (xy 377.138184 -288.593276) (xy 377.163006 -288.598437)
			(xy 377.210784 -288.615395) (xy 377.255401 -288.639469) (xy 377.295806 -288.67009) (xy 377.331046 -288.706538)
			(xy 377.36029 -288.747952) (xy 377.382847 -288.793355) (xy 377.398186 -288.841676) (xy 377.405945 -288.891777)
			(xy 377.406408 -288.917126) (xy 377.4059 -288.943033) (xy 377.397794 -288.99421) (xy 377.381782 -289.043489)
			(xy 377.358259 -289.089656) (xy 377.327803 -289.131575) (xy 377.291165 -289.168213) (xy 377.249246 -289.198669)
			(xy 377.203079 -289.222192) (xy 377.1538 -289.238204) (xy 377.102623 -289.24631) (xy 377.050809 -289.24631)
			(xy 376.999632 -289.238204) (xy 376.950353 -289.222192) (xy 376.904186 -289.198669) (xy 376.862267 -289.168213)
			(xy 376.825629 -289.131575) (xy 376.795173 -289.089656) (xy 376.77165 -289.043489) (xy 376.755638 -288.99421)
			(xy 376.747532 -288.943033) (xy 376.747024 -288.917126) (xy 376.747623 -288.889409) (xy 376.756943 -288.834762)
			(xy 376.765566 -288.808414) (xy 376.77344 -288.786316) (xy 376.568462 -288.431224) (xy 376.545602 -288.426906)
			(xy 376.520761 -288.421779) (xy 376.472952 -288.40484) (xy 376.428302 -288.380778) (xy 376.387863 -288.350162)
			(xy 376.352591 -288.313713) (xy 376.323317 -288.272293) (xy 376.300733 -288.226877) (xy 376.285371 -288.178538)
			(xy 376.277594 -288.128417) (xy 376.277124 -288.103056) (xy 375.056908 -288.103056) (xy 375.056303 -288.130773)
			(xy 375.046987 -288.185419) (xy 375.038366 -288.211768) (xy 375.030746 -288.233866) (xy 375.235724 -288.588958)
			(xy 375.258584 -288.593276) (xy 375.283406 -288.598437) (xy 375.331184 -288.615395) (xy 375.375801 -288.639469)
			(xy 375.416206 -288.67009) (xy 375.451446 -288.706538) (xy 375.48069 -288.747952) (xy 375.503247 -288.793355)
			(xy 375.518586 -288.841676) (xy 375.526345 -288.891777) (xy 375.526808 -288.917126) (xy 375.5263 -288.943033)
			(xy 375.518194 -288.99421) (xy 375.502182 -289.043489) (xy 375.478659 -289.089656) (xy 375.448203 -289.131575)
			(xy 375.411565 -289.168213) (xy 375.369646 -289.198669) (xy 375.323479 -289.222192) (xy 375.2742 -289.238204)
			(xy 375.223023 -289.24631) (xy 375.171209 -289.24631) (xy 375.120032 -289.238204) (xy 375.070753 -289.222192)
			(xy 375.024586 -289.198669) (xy 374.982667 -289.168213) (xy 374.946029 -289.131575) (xy 374.915573 -289.089656)
			(xy 374.89205 -289.043489) (xy 374.876038 -288.99421) (xy 374.867932 -288.943033) (xy 374.867424 -288.917126)
			(xy 374.868023 -288.889409) (xy 374.877343 -288.834762) (xy 374.885966 -288.808414) (xy 374.89384 -288.786316)
			(xy 374.688862 -288.431224) (xy 374.666002 -288.426906) (xy 374.641161 -288.421779) (xy 374.593352 -288.40484)
			(xy 374.548702 -288.380778) (xy 374.508263 -288.350162) (xy 374.472991 -288.313713) (xy 374.443717 -288.272293)
			(xy 374.421133 -288.226877) (xy 374.405771 -288.178538) (xy 374.397994 -288.128417) (xy 374.397524 -288.103056)
			(xy 373.177308 -288.103056) (xy 373.176703 -288.130773) (xy 373.167387 -288.185419) (xy 373.158766 -288.211768)
			(xy 373.151146 -288.233866) (xy 373.356124 -288.588958) (xy 373.378984 -288.593276) (xy 373.403806 -288.598437)
			(xy 373.451584 -288.615395) (xy 373.496201 -288.639469) (xy 373.536606 -288.67009) (xy 373.571846 -288.706538)
			(xy 373.60109 -288.747952) (xy 373.623647 -288.793355) (xy 373.638986 -288.841676) (xy 373.646745 -288.891777)
			(xy 373.647208 -288.917126) (xy 373.6467 -288.943033) (xy 373.638594 -288.99421) (xy 373.622582 -289.043489)
			(xy 373.599059 -289.089656) (xy 373.568603 -289.131575) (xy 373.531965 -289.168213) (xy 373.490046 -289.198669)
			(xy 373.443879 -289.222192) (xy 373.3946 -289.238204) (xy 373.343423 -289.24631) (xy 373.291609 -289.24631)
			(xy 373.240432 -289.238204) (xy 373.191153 -289.222192) (xy 373.144986 -289.198669) (xy 373.103067 -289.168213)
			(xy 373.066429 -289.131575) (xy 373.035973 -289.089656) (xy 373.01245 -289.043489) (xy 372.996438 -288.99421)
			(xy 372.988332 -288.943033) (xy 372.987824 -288.917126) (xy 372.988423 -288.889409) (xy 372.997743 -288.834762)
			(xy 373.006366 -288.808414) (xy 373.01424 -288.786316) (xy 372.809262 -288.431224) (xy 372.786402 -288.426906)
			(xy 372.761561 -288.421779) (xy 372.713752 -288.40484) (xy 372.669102 -288.380778) (xy 372.628663 -288.350162)
			(xy 372.593391 -288.313713) (xy 372.564117 -288.272293) (xy 372.541533 -288.226877) (xy 372.526171 -288.178538)
			(xy 372.518394 -288.128417) (xy 372.517924 -288.103056) (xy 371.297708 -288.103056) (xy 371.297103 -288.130773)
			(xy 371.287787 -288.185419) (xy 371.279166 -288.211768) (xy 371.271546 -288.233866) (xy 371.476524 -288.588958)
			(xy 371.499384 -288.593276) (xy 371.524206 -288.598437) (xy 371.571984 -288.615395) (xy 371.616601 -288.639469)
			(xy 371.657006 -288.67009) (xy 371.692246 -288.706538) (xy 371.72149 -288.747952) (xy 371.744047 -288.793355)
			(xy 371.759386 -288.841676) (xy 371.767145 -288.891777) (xy 371.767608 -288.917126) (xy 371.7671 -288.943033)
			(xy 371.758994 -288.99421) (xy 371.742982 -289.043489) (xy 371.719459 -289.089656) (xy 371.689003 -289.131575)
			(xy 371.652365 -289.168213) (xy 371.610446 -289.198669) (xy 371.564279 -289.222192) (xy 371.515 -289.238204)
			(xy 371.463823 -289.24631) (xy 371.412009 -289.24631) (xy 371.360832 -289.238204) (xy 371.311553 -289.222192)
			(xy 371.265386 -289.198669) (xy 371.223467 -289.168213) (xy 371.186829 -289.131575) (xy 371.156373 -289.089656)
			(xy 371.13285 -289.043489) (xy 371.116838 -288.99421) (xy 371.108732 -288.943033) (xy 371.108224 -288.917126)
			(xy 371.108823 -288.889409) (xy 371.118143 -288.834762) (xy 371.126766 -288.808414) (xy 371.13464 -288.786316)
			(xy 370.929662 -288.431224) (xy 370.906802 -288.426906) (xy 370.881961 -288.421779) (xy 370.834152 -288.40484)
			(xy 370.789502 -288.380778) (xy 370.749063 -288.350162) (xy 370.713791 -288.313713) (xy 370.684517 -288.272293)
			(xy 370.661933 -288.226877) (xy 370.646571 -288.178538) (xy 370.638794 -288.128417) (xy 370.638324 -288.103056)
			(xy 369.418108 -288.103056) (xy 369.417503 -288.130773) (xy 369.408187 -288.185419) (xy 369.399566 -288.211768)
			(xy 369.391692 -288.233866) (xy 369.596924 -288.588958) (xy 369.619784 -288.593276) (xy 369.644606 -288.598437)
			(xy 369.692384 -288.615395) (xy 369.737001 -288.639469) (xy 369.777406 -288.67009) (xy 369.812646 -288.706538)
			(xy 369.84189 -288.747952) (xy 369.864447 -288.793355) (xy 369.879786 -288.841676) (xy 369.887545 -288.891777)
			(xy 369.888008 -288.917126) (xy 369.8875 -288.943033) (xy 369.879394 -288.99421) (xy 369.863382 -289.043489)
			(xy 369.839859 -289.089656) (xy 369.809403 -289.131575) (xy 369.772765 -289.168213) (xy 369.730846 -289.198669)
			(xy 369.684679 -289.222192) (xy 369.6354 -289.238204) (xy 369.584223 -289.24631) (xy 369.532409 -289.24631)
			(xy 369.481232 -289.238204) (xy 369.431953 -289.222192) (xy 369.385786 -289.198669) (xy 369.343867 -289.168213)
			(xy 369.307229 -289.131575) (xy 369.276773 -289.089656) (xy 369.25325 -289.043489) (xy 369.237238 -288.99421)
			(xy 369.229132 -288.943033) (xy 369.228624 -288.917126) (xy 369.229223 -288.889409) (xy 369.238543 -288.834762)
			(xy 369.247166 -288.808414) (xy 369.25504 -288.786316) (xy 369.049808 -288.431224) (xy 369.026948 -288.426906)
			(xy 369.002127 -288.421739) (xy 368.954348 -288.404784) (xy 368.909729 -288.380713) (xy 368.869322 -288.350092)
			(xy 368.834082 -288.313646) (xy 368.804838 -288.272232) (xy 368.782281 -288.226828) (xy 368.766943 -288.178506)
			(xy 368.759186 -288.128405) (xy 368.758724 -288.103056) (xy 352.501708 -288.103056) (xy 352.501231 -288.128401)
			(xy 352.493451 -288.178491) (xy 352.478099 -288.2268) (xy 352.455536 -288.272192) (xy 352.426294 -288.313597)
			(xy 352.39106 -288.35004) (xy 352.350665 -288.380663) (xy 352.306061 -288.404744) (xy 352.258297 -288.421718)
			(xy 352.233484 -288.426906) (xy 352.210624 -288.431224) (xy 352.005392 -288.786316) (xy 352.013266 -288.808414)
			(xy 352.021907 -288.834758) (xy 352.031221 -288.889407) (xy 352.031808 -288.917126) (xy 352.0313 -288.943033)
			(xy 352.023194 -288.99421) (xy 352.007182 -289.043489) (xy 351.983659 -289.089656) (xy 351.953203 -289.131575)
			(xy 351.916565 -289.168213) (xy 351.874646 -289.198669) (xy 351.828479 -289.222192) (xy 351.7792 -289.238204)
			(xy 351.728023 -289.24631) (xy 351.676209 -289.24631) (xy 351.625032 -289.238204) (xy 351.575753 -289.222192)
			(xy 351.529586 -289.198669) (xy 351.487667 -289.168213) (xy 351.451029 -289.131575) (xy 351.420573 -289.089656)
			(xy 351.39705 -289.043489) (xy 351.381038 -288.99421) (xy 351.372932 -288.943033) (xy 351.372424 -288.917126)
			(xy 351.092008 -288.917126) (xy 351.091589 -288.940067) (xy 351.08516 -288.985498) (xy 351.072513 -289.029604)
			(xy 351.06356 -289.05073) (xy 351.053654 -289.073336) (xy 351.267522 -289.478466) (xy 351.291652 -289.483038)
			(xy 351.316573 -289.488138) (xy 351.364584 -289.504939) (xy 351.409443 -289.528919) (xy 351.450084 -289.559507)
			(xy 351.485541 -289.595978) (xy 351.514973 -289.637465) (xy 351.537679 -289.682981) (xy 351.553121 -289.731446)
			(xy 351.560931 -289.781709) (xy 351.5614 -289.807142) (xy 367.818924 -289.807142) (xy 367.819411 -289.781712)
			(xy 367.827244 -289.73146) (xy 367.842699 -289.683005) (xy 367.86541 -289.637498) (xy 367.894839 -289.596018)
			(xy 367.930287 -289.559547) (xy 367.970914 -289.528951) (xy 368.015757 -289.504956) (xy 368.063753 -289.48813)
			(xy 368.088672 -289.483038) (xy 368.112802 -289.478466) (xy 368.327178 -289.073082) (xy 368.317272 -289.050476)
			(xy 368.308309 -289.029398) (xy 368.295664 -288.985377) (xy 368.289249 -288.940026) (xy 368.288824 -288.917126)
			(xy 368.289332 -288.891219) (xy 368.297438 -288.840042) (xy 368.31345 -288.790763) (xy 368.336973 -288.744596)
			(xy 368.367429 -288.702677) (xy 368.404067 -288.666039) (xy 368.445986 -288.635583) (xy 368.492153 -288.61206)
			(xy 368.541432 -288.596048) (xy 368.592609 -288.587942) (xy 368.644423 -288.587942) (xy 368.6956 -288.596048)
			(xy 368.744879 -288.61206) (xy 368.791046 -288.635583) (xy 368.832965 -288.666039) (xy 368.869603 -288.702677)
			(xy 368.900059 -288.744596) (xy 368.923582 -288.790763) (xy 368.939594 -288.840042) (xy 368.9477 -288.891219)
			(xy 368.948208 -288.917126) (xy 368.947753 -288.942575) (xy 368.939949 -288.992871) (xy 368.924499 -289.041367)
			(xy 368.901771 -289.086909) (xy 368.872307 -289.128411) (xy 368.836809 -289.164887) (xy 368.796121 -289.195466)
			(xy 368.751213 -289.21942) (xy 368.703153 -289.23618) (xy 368.678206 -289.24123) (xy 368.654076 -289.245802)
			(xy 368.4397 -289.651186) (xy 368.449606 -289.673792) (xy 368.458528 -289.694877) (xy 368.471078 -289.738907)
			(xy 368.47741 -289.78425) (xy 368.4778 -289.807142) (xy 369.698524 -289.807142) (xy 369.699011 -289.781712)
			(xy 369.706844 -289.73146) (xy 369.722299 -289.683005) (xy 369.74501 -289.637498) (xy 369.774439 -289.596018)
			(xy 369.809887 -289.559547) (xy 369.850514 -289.528951) (xy 369.895357 -289.504956) (xy 369.943353 -289.48813)
			(xy 369.968272 -289.483038) (xy 369.992402 -289.478466) (xy 370.206778 -289.073082) (xy 370.196872 -289.050476)
			(xy 370.187909 -289.029398) (xy 370.175264 -288.985377) (xy 370.168849 -288.940026) (xy 370.168424 -288.917126)
			(xy 370.168932 -288.891219) (xy 370.177038 -288.840042) (xy 370.19305 -288.790763) (xy 370.216573 -288.744596)
			(xy 370.247029 -288.702677) (xy 370.283667 -288.666039) (xy 370.325586 -288.635583) (xy 370.371753 -288.61206)
			(xy 370.421032 -288.596048) (xy 370.472209 -288.587942) (xy 370.524023 -288.587942) (xy 370.5752 -288.596048)
			(xy 370.624479 -288.61206) (xy 370.670646 -288.635583) (xy 370.712565 -288.666039) (xy 370.749203 -288.702677)
			(xy 370.779659 -288.744596) (xy 370.803182 -288.790763) (xy 370.819194 -288.840042) (xy 370.8273 -288.891219)
			(xy 370.827808 -288.917126) (xy 370.827353 -288.942575) (xy 370.819549 -288.992871) (xy 370.804099 -289.041367)
			(xy 370.781371 -289.086909) (xy 370.751907 -289.128411) (xy 370.716409 -289.164887) (xy 370.675721 -289.195466)
			(xy 370.630813 -289.21942) (xy 370.582753 -289.23618) (xy 370.557806 -289.24123) (xy 370.533676 -289.245802)
			(xy 370.3193 -289.651186) (xy 370.329206 -289.673792) (xy 370.338128 -289.694877) (xy 370.350678 -289.738907)
			(xy 370.35701 -289.78425) (xy 370.3574 -289.807142) (xy 371.578124 -289.807142) (xy 371.578611 -289.781712)
			(xy 371.586444 -289.73146) (xy 371.601899 -289.683005) (xy 371.62461 -289.637498) (xy 371.654039 -289.596018)
			(xy 371.689487 -289.559547) (xy 371.730114 -289.528951) (xy 371.774957 -289.504956) (xy 371.822953 -289.48813)
			(xy 371.847872 -289.483038) (xy 371.872002 -289.478466) (xy 372.086378 -289.073082) (xy 372.076472 -289.050476)
			(xy 372.067509 -289.029398) (xy 372.054864 -288.985377) (xy 372.048449 -288.940026) (xy 372.048024 -288.917126)
			(xy 372.048532 -288.891219) (xy 372.056638 -288.840042) (xy 372.07265 -288.790763) (xy 372.096173 -288.744596)
			(xy 372.126629 -288.702677) (xy 372.163267 -288.666039) (xy 372.205186 -288.635583) (xy 372.251353 -288.61206)
			(xy 372.300632 -288.596048) (xy 372.351809 -288.587942) (xy 372.403623 -288.587942) (xy 372.4548 -288.596048)
			(xy 372.504079 -288.61206) (xy 372.550246 -288.635583) (xy 372.592165 -288.666039) (xy 372.628803 -288.702677)
			(xy 372.659259 -288.744596) (xy 372.682782 -288.790763) (xy 372.698794 -288.840042) (xy 372.7069 -288.891219)
			(xy 372.707408 -288.917126) (xy 372.706953 -288.942575) (xy 372.699149 -288.992871) (xy 372.683699 -289.041367)
			(xy 372.660971 -289.086909) (xy 372.631507 -289.128411) (xy 372.596009 -289.164887) (xy 372.555321 -289.195466)
			(xy 372.510413 -289.21942) (xy 372.462353 -289.23618) (xy 372.437406 -289.24123) (xy 372.413276 -289.245802)
			(xy 372.1989 -289.651186) (xy 372.208806 -289.673792) (xy 372.217728 -289.694877) (xy 372.230278 -289.738907)
			(xy 372.23661 -289.78425) (xy 372.237 -289.807142) (xy 373.457724 -289.807142) (xy 373.458211 -289.781712)
			(xy 373.466044 -289.73146) (xy 373.481499 -289.683005) (xy 373.50421 -289.637498) (xy 373.533639 -289.596018)
			(xy 373.569087 -289.559547) (xy 373.609714 -289.528951) (xy 373.654557 -289.504956) (xy 373.702553 -289.48813)
			(xy 373.727472 -289.483038) (xy 373.751602 -289.478466) (xy 373.965978 -289.073082) (xy 373.956072 -289.050476)
			(xy 373.947109 -289.029398) (xy 373.934464 -288.985377) (xy 373.928049 -288.940026) (xy 373.927624 -288.917126)
			(xy 373.928132 -288.891219) (xy 373.936238 -288.840042) (xy 373.95225 -288.790763) (xy 373.975773 -288.744596)
			(xy 374.006229 -288.702677) (xy 374.042867 -288.666039) (xy 374.084786 -288.635583) (xy 374.130953 -288.61206)
			(xy 374.180232 -288.596048) (xy 374.231409 -288.587942) (xy 374.283223 -288.587942) (xy 374.3344 -288.596048)
			(xy 374.383679 -288.61206) (xy 374.429846 -288.635583) (xy 374.471765 -288.666039) (xy 374.508403 -288.702677)
			(xy 374.538859 -288.744596) (xy 374.562382 -288.790763) (xy 374.578394 -288.840042) (xy 374.5865 -288.891219)
			(xy 374.587008 -288.917126) (xy 374.586553 -288.942575) (xy 374.578749 -288.992871) (xy 374.563299 -289.041367)
			(xy 374.540571 -289.086909) (xy 374.511107 -289.128411) (xy 374.475609 -289.164887) (xy 374.434921 -289.195466)
			(xy 374.390013 -289.21942) (xy 374.341953 -289.23618) (xy 374.317006 -289.24123) (xy 374.292876 -289.245802)
			(xy 374.0785 -289.651186) (xy 374.088406 -289.673792) (xy 374.097328 -289.694877) (xy 374.109878 -289.738907)
			(xy 374.11621 -289.78425) (xy 374.1166 -289.807142) (xy 375.337324 -289.807142) (xy 375.337811 -289.781712)
			(xy 375.345644 -289.73146) (xy 375.361099 -289.683005) (xy 375.38381 -289.637498) (xy 375.413239 -289.596018)
			(xy 375.448687 -289.559547) (xy 375.489314 -289.528951) (xy 375.534157 -289.504956) (xy 375.582153 -289.48813)
			(xy 375.607072 -289.483038) (xy 375.631202 -289.478466) (xy 375.845578 -289.073082) (xy 375.835672 -289.050476)
			(xy 375.826709 -289.029398) (xy 375.814064 -288.985377) (xy 375.807649 -288.940026) (xy 375.807224 -288.917126)
			(xy 375.807732 -288.891219) (xy 375.815838 -288.840042) (xy 375.83185 -288.790763) (xy 375.855373 -288.744596)
			(xy 375.885829 -288.702677) (xy 375.922467 -288.666039) (xy 375.964386 -288.635583) (xy 376.010553 -288.61206)
			(xy 376.059832 -288.596048) (xy 376.111009 -288.587942) (xy 376.162823 -288.587942) (xy 376.214 -288.596048)
			(xy 376.263279 -288.61206) (xy 376.309446 -288.635583) (xy 376.351365 -288.666039) (xy 376.388003 -288.702677)
			(xy 376.418459 -288.744596) (xy 376.441982 -288.790763) (xy 376.457994 -288.840042) (xy 376.4661 -288.891219)
			(xy 376.466608 -288.917126) (xy 376.466153 -288.942575) (xy 376.458349 -288.992871) (xy 376.442899 -289.041367)
			(xy 376.420171 -289.086909) (xy 376.390707 -289.128411) (xy 376.355209 -289.164887) (xy 376.314521 -289.195466)
			(xy 376.269613 -289.21942) (xy 376.221553 -289.23618) (xy 376.196606 -289.24123) (xy 376.172476 -289.245802)
			(xy 375.9581 -289.651186) (xy 375.968006 -289.673792) (xy 375.976928 -289.694877) (xy 375.989478 -289.738907)
			(xy 375.99581 -289.78425) (xy 375.9962 -289.807142) (xy 377.216924 -289.807142) (xy 377.217411 -289.781712)
			(xy 377.225244 -289.73146) (xy 377.240699 -289.683005) (xy 377.26341 -289.637498) (xy 377.292839 -289.596018)
			(xy 377.328287 -289.559547) (xy 377.368914 -289.528951) (xy 377.413757 -289.504956) (xy 377.461753 -289.48813)
			(xy 377.486672 -289.483038) (xy 377.510802 -289.478466) (xy 377.725178 -289.073082) (xy 377.715272 -289.050476)
			(xy 377.706309 -289.029398) (xy 377.693664 -288.985377) (xy 377.687249 -288.940026) (xy 377.686824 -288.917126)
			(xy 377.687332 -288.891219) (xy 377.695438 -288.840042) (xy 377.71145 -288.790763) (xy 377.734973 -288.744596)
			(xy 377.765429 -288.702677) (xy 377.802067 -288.666039) (xy 377.843986 -288.635583) (xy 377.890153 -288.61206)
			(xy 377.939432 -288.596048) (xy 377.990609 -288.587942) (xy 378.042423 -288.587942) (xy 378.0936 -288.596048)
			(xy 378.142879 -288.61206) (xy 378.189046 -288.635583) (xy 378.230965 -288.666039) (xy 378.267603 -288.702677)
			(xy 378.298059 -288.744596) (xy 378.321582 -288.790763) (xy 378.337594 -288.840042) (xy 378.3457 -288.891219)
			(xy 378.346208 -288.917126) (xy 378.345753 -288.942575) (xy 378.337949 -288.992871) (xy 378.322499 -289.041367)
			(xy 378.299771 -289.086909) (xy 378.270307 -289.128411) (xy 378.234809 -289.164887) (xy 378.194121 -289.195466)
			(xy 378.149213 -289.21942) (xy 378.101153 -289.23618) (xy 378.076206 -289.24123) (xy 378.052076 -289.245802)
			(xy 377.8377 -289.651186) (xy 377.847606 -289.673792) (xy 377.856528 -289.694877) (xy 377.869078 -289.738907)
			(xy 377.87541 -289.78425) (xy 377.8758 -289.807142) (xy 379.096524 -289.807142) (xy 379.097011 -289.781712)
			(xy 379.104844 -289.73146) (xy 379.120299 -289.683005) (xy 379.14301 -289.637498) (xy 379.172439 -289.596018)
			(xy 379.207887 -289.559547) (xy 379.248514 -289.528951) (xy 379.293357 -289.504956) (xy 379.341353 -289.48813)
			(xy 379.366272 -289.483038) (xy 379.390402 -289.478466) (xy 379.604778 -289.073082) (xy 379.594872 -289.050476)
			(xy 379.585909 -289.029398) (xy 379.573264 -288.985377) (xy 379.566849 -288.940026) (xy 379.566424 -288.917126)
			(xy 379.566932 -288.891219) (xy 379.575038 -288.840042) (xy 379.59105 -288.790763) (xy 379.614573 -288.744596)
			(xy 379.645029 -288.702677) (xy 379.681667 -288.666039) (xy 379.723586 -288.635583) (xy 379.769753 -288.61206)
			(xy 379.819032 -288.596048) (xy 379.870209 -288.587942) (xy 379.922023 -288.587942) (xy 379.9732 -288.596048)
			(xy 380.022479 -288.61206) (xy 380.068646 -288.635583) (xy 380.110565 -288.666039) (xy 380.147203 -288.702677)
			(xy 380.177659 -288.744596) (xy 380.201182 -288.790763) (xy 380.217194 -288.840042) (xy 380.2253 -288.891219)
			(xy 380.225808 -288.917126) (xy 380.225353 -288.942575) (xy 380.217549 -288.992871) (xy 380.202099 -289.041367)
			(xy 380.179371 -289.086909) (xy 380.149907 -289.128411) (xy 380.114409 -289.164887) (xy 380.073721 -289.195466)
			(xy 380.028813 -289.21942) (xy 379.980753 -289.23618) (xy 379.955806 -289.24123) (xy 379.931676 -289.245802)
			(xy 379.7173 -289.651186) (xy 379.727206 -289.673792) (xy 379.736128 -289.694877) (xy 379.748678 -289.738907)
			(xy 379.75501 -289.78425) (xy 379.7554 -289.807142) (xy 380.976124 -289.807142) (xy 380.976611 -289.781712)
			(xy 380.984444 -289.73146) (xy 380.999899 -289.683005) (xy 381.02261 -289.637498) (xy 381.052039 -289.596018)
			(xy 381.087487 -289.559547) (xy 381.128114 -289.528951) (xy 381.172957 -289.504956) (xy 381.220953 -289.48813)
			(xy 381.245872 -289.483038) (xy 381.270002 -289.478466) (xy 381.484378 -289.073082) (xy 381.474472 -289.050476)
			(xy 381.465509 -289.029398) (xy 381.452864 -288.985377) (xy 381.446449 -288.940026) (xy 381.446024 -288.917126)
			(xy 381.446532 -288.891219) (xy 381.454638 -288.840042) (xy 381.47065 -288.790763) (xy 381.494173 -288.744596)
			(xy 381.524629 -288.702677) (xy 381.561267 -288.666039) (xy 381.603186 -288.635583) (xy 381.649353 -288.61206)
			(xy 381.698632 -288.596048) (xy 381.749809 -288.587942) (xy 381.801623 -288.587942) (xy 381.8528 -288.596048)
			(xy 381.902079 -288.61206) (xy 381.948246 -288.635583) (xy 381.990165 -288.666039) (xy 382.026803 -288.702677)
			(xy 382.057259 -288.744596) (xy 382.080782 -288.790763) (xy 382.096794 -288.840042) (xy 382.1049 -288.891219)
			(xy 382.105408 -288.917126) (xy 382.104953 -288.942575) (xy 382.097149 -288.992871) (xy 382.081699 -289.041367)
			(xy 382.058971 -289.086909) (xy 382.029507 -289.128411) (xy 381.994009 -289.164887) (xy 381.953321 -289.195466)
			(xy 381.908413 -289.21942) (xy 381.860353 -289.23618) (xy 381.835406 -289.24123) (xy 381.811276 -289.245802)
			(xy 381.771248 -289.321494) (xy 410.102304 -289.321494) (xy 410.102304 -288.912554) (xy 410.102795 -288.902397)
			(xy 410.110578 -288.883634) (xy 410.124944 -288.869271) (xy 410.143709 -288.861493) (xy 410.153866 -288.860992)
			(xy 411.553406 -288.860992) (xy 411.563558 -288.861527) (xy 411.582319 -288.869295) (xy 411.596682 -288.883648)
			(xy 411.604465 -288.902402) (xy 411.604968 -288.912554) (xy 411.604968 -289.321494) (xy 417.646104 -289.321494)
			(xy 417.646104 -288.912554) (xy 417.646595 -288.902397) (xy 417.654378 -288.883634) (xy 417.668744 -288.869271)
			(xy 417.687509 -288.861493) (xy 417.697666 -288.860992) (xy 419.097206 -288.860992) (xy 419.107358 -288.861527)
			(xy 419.126119 -288.869295) (xy 419.140482 -288.883648) (xy 419.148265 -288.902402) (xy 419.148768 -288.912554)
			(xy 419.148768 -289.321494) (xy 425.189904 -289.321494) (xy 425.189904 -288.912554) (xy 425.190395 -288.902397)
			(xy 425.198178 -288.883634) (xy 425.212544 -288.869271) (xy 425.231309 -288.861493) (xy 425.241466 -288.860992)
			(xy 426.641006 -288.860992) (xy 426.651158 -288.861527) (xy 426.669919 -288.869295) (xy 426.684282 -288.883648)
			(xy 426.692065 -288.902402) (xy 426.692568 -288.912554) (xy 426.692568 -289.321494) (xy 432.733704 -289.321494)
			(xy 432.733704 -288.912554) (xy 432.734195 -288.902397) (xy 432.741978 -288.883634) (xy 432.756344 -288.869271)
			(xy 432.775109 -288.861493) (xy 432.785266 -288.860992) (xy 434.184806 -288.860992) (xy 434.194958 -288.861527)
			(xy 434.213719 -288.869295) (xy 434.228082 -288.883648) (xy 434.235865 -288.902402) (xy 434.236368 -288.912554)
			(xy 434.236368 -289.321494) (xy 440.277504 -289.321494) (xy 440.277504 -288.912554) (xy 440.277995 -288.902397)
			(xy 440.285778 -288.883634) (xy 440.300144 -288.869271) (xy 440.318909 -288.861493) (xy 440.329066 -288.860992)
			(xy 441.728606 -288.860992) (xy 441.738758 -288.861527) (xy 441.757519 -288.869295) (xy 441.771882 -288.883648)
			(xy 441.779665 -288.902402) (xy 441.780168 -288.912554) (xy 441.780168 -289.321494) (xy 447.821304 -289.321494)
			(xy 447.821304 -288.912554) (xy 447.821795 -288.902397) (xy 447.829578 -288.883634) (xy 447.843944 -288.869271)
			(xy 447.862709 -288.861493) (xy 447.872866 -288.860992) (xy 449.272406 -288.860992) (xy 449.282558 -288.861527)
			(xy 449.301319 -288.869295) (xy 449.315682 -288.883648) (xy 449.323465 -288.902402) (xy 449.323968 -288.912554)
			(xy 449.323968 -289.321494) (xy 455.365104 -289.321494) (xy 455.365104 -288.912554) (xy 455.365595 -288.902397)
			(xy 455.373378 -288.883634) (xy 455.387744 -288.869271) (xy 455.406509 -288.861493) (xy 455.416666 -288.860992)
			(xy 456.816206 -288.860992) (xy 456.826358 -288.861527) (xy 456.845119 -288.869295) (xy 456.859482 -288.883648)
			(xy 456.867265 -288.902402) (xy 456.867768 -288.912554) (xy 456.867768 -289.321494) (xy 462.908904 -289.321494)
			(xy 462.908904 -288.912554) (xy 462.909395 -288.902397) (xy 462.917178 -288.883634) (xy 462.931544 -288.869271)
			(xy 462.950309 -288.861493) (xy 462.960466 -288.860992) (xy 464.360006 -288.860992) (xy 464.370158 -288.861527)
			(xy 464.388919 -288.869295) (xy 464.403282 -288.883648) (xy 464.411065 -288.902402) (xy 464.411568 -288.912554)
			(xy 464.411568 -289.321494) (xy 464.411062 -289.331651) (xy 464.403291 -289.350419) (xy 464.388929 -289.364784)
			(xy 464.370163 -289.372559) (xy 464.360006 -289.373056) (xy 462.960466 -289.373056) (xy 462.950305 -289.372594)
			(xy 462.931534 -289.364808) (xy 462.91717 -289.350432) (xy 462.909398 -289.331655) (xy 462.908904 -289.321494)
			(xy 456.867768 -289.321494) (xy 456.867262 -289.331651) (xy 456.859491 -289.350419) (xy 456.845129 -289.364784)
			(xy 456.826363 -289.372559) (xy 456.816206 -289.373056) (xy 455.416666 -289.373056) (xy 455.406505 -289.372594)
			(xy 455.387734 -289.364808) (xy 455.37337 -289.350432) (xy 455.365598 -289.331655) (xy 455.365104 -289.321494)
			(xy 449.323968 -289.321494) (xy 449.323462 -289.331651) (xy 449.315691 -289.350419) (xy 449.301329 -289.364784)
			(xy 449.282563 -289.372559) (xy 449.272406 -289.373056) (xy 447.872866 -289.373056) (xy 447.862705 -289.372594)
			(xy 447.843934 -289.364808) (xy 447.82957 -289.350432) (xy 447.821798 -289.331655) (xy 447.821304 -289.321494)
			(xy 441.780168 -289.321494) (xy 441.779662 -289.331651) (xy 441.771891 -289.350419) (xy 441.757529 -289.364784)
			(xy 441.738763 -289.372559) (xy 441.728606 -289.373056) (xy 440.329066 -289.373056) (xy 440.318905 -289.372594)
			(xy 440.300134 -289.364808) (xy 440.28577 -289.350432) (xy 440.277998 -289.331655) (xy 440.277504 -289.321494)
			(xy 434.236368 -289.321494) (xy 434.235862 -289.331651) (xy 434.228091 -289.350419) (xy 434.213729 -289.364784)
			(xy 434.194963 -289.372559) (xy 434.184806 -289.373056) (xy 432.785266 -289.373056) (xy 432.775105 -289.372594)
			(xy 432.756334 -289.364808) (xy 432.74197 -289.350432) (xy 432.734198 -289.331655) (xy 432.733704 -289.321494)
			(xy 426.692568 -289.321494) (xy 426.692062 -289.331651) (xy 426.684291 -289.350419) (xy 426.669929 -289.364784)
			(xy 426.651163 -289.372559) (xy 426.641006 -289.373056) (xy 425.241466 -289.373056) (xy 425.231305 -289.372594)
			(xy 425.212534 -289.364808) (xy 425.19817 -289.350432) (xy 425.190398 -289.331655) (xy 425.189904 -289.321494)
			(xy 419.148768 -289.321494) (xy 419.148262 -289.331651) (xy 419.140491 -289.350419) (xy 419.126129 -289.364784)
			(xy 419.107363 -289.372559) (xy 419.097206 -289.373056) (xy 417.697666 -289.373056) (xy 417.687505 -289.372594)
			(xy 417.668734 -289.364808) (xy 417.65437 -289.350432) (xy 417.646598 -289.331655) (xy 417.646104 -289.321494)
			(xy 411.604968 -289.321494) (xy 411.604462 -289.331651) (xy 411.596691 -289.350419) (xy 411.582329 -289.364784)
			(xy 411.563563 -289.372559) (xy 411.553406 -289.373056) (xy 410.153866 -289.373056) (xy 410.143705 -289.372594)
			(xy 410.124934 -289.364808) (xy 410.11057 -289.350432) (xy 410.102798 -289.331655) (xy 410.102304 -289.321494)
			(xy 381.771248 -289.321494) (xy 381.5969 -289.651186) (xy 381.606806 -289.673792) (xy 381.615728 -289.694877)
			(xy 381.628278 -289.738907) (xy 381.63461 -289.78425) (xy 381.635 -289.807142) (xy 381.634492 -289.833029)
			(xy 381.626393 -289.884167) (xy 381.610394 -289.933407) (xy 381.586888 -289.979539) (xy 381.556456 -290.021426)
			(xy 381.519846 -290.058036) (xy 381.477959 -290.088468) (xy 381.431827 -290.111974) (xy 381.382587 -290.127973)
			(xy 381.331449 -290.136072) (xy 381.279675 -290.136072) (xy 381.228537 -290.127973) (xy 381.179297 -290.111974)
			(xy 381.133165 -290.088468) (xy 381.091278 -290.058036) (xy 381.054668 -290.021426) (xy 381.024236 -289.979539)
			(xy 381.00073 -289.933407) (xy 380.984731 -289.884167) (xy 380.976632 -289.833029) (xy 380.976124 -289.807142)
			(xy 379.7554 -289.807142) (xy 379.754892 -289.833029) (xy 379.746793 -289.884167) (xy 379.730794 -289.933407)
			(xy 379.707288 -289.979539) (xy 379.676856 -290.021426) (xy 379.640246 -290.058036) (xy 379.598359 -290.088468)
			(xy 379.552227 -290.111974) (xy 379.502987 -290.127973) (xy 379.451849 -290.136072) (xy 379.400075 -290.136072)
			(xy 379.348937 -290.127973) (xy 379.299697 -290.111974) (xy 379.253565 -290.088468) (xy 379.211678 -290.058036)
			(xy 379.175068 -290.021426) (xy 379.144636 -289.979539) (xy 379.12113 -289.933407) (xy 379.105131 -289.884167)
			(xy 379.097032 -289.833029) (xy 379.096524 -289.807142) (xy 377.8758 -289.807142) (xy 377.875292 -289.833029)
			(xy 377.867193 -289.884167) (xy 377.851194 -289.933407) (xy 377.827688 -289.979539) (xy 377.797256 -290.021426)
			(xy 377.760646 -290.058036) (xy 377.718759 -290.088468) (xy 377.672627 -290.111974) (xy 377.623387 -290.127973)
			(xy 377.572249 -290.136072) (xy 377.520475 -290.136072) (xy 377.469337 -290.127973) (xy 377.420097 -290.111974)
			(xy 377.373965 -290.088468) (xy 377.332078 -290.058036) (xy 377.295468 -290.021426) (xy 377.265036 -289.979539)
			(xy 377.24153 -289.933407) (xy 377.225531 -289.884167) (xy 377.217432 -289.833029) (xy 377.216924 -289.807142)
			(xy 375.9962 -289.807142) (xy 375.995692 -289.833029) (xy 375.987593 -289.884167) (xy 375.971594 -289.933407)
			(xy 375.948088 -289.979539) (xy 375.917656 -290.021426) (xy 375.881046 -290.058036) (xy 375.839159 -290.088468)
			(xy 375.793027 -290.111974) (xy 375.743787 -290.127973) (xy 375.692649 -290.136072) (xy 375.640875 -290.136072)
			(xy 375.589737 -290.127973) (xy 375.540497 -290.111974) (xy 375.494365 -290.088468) (xy 375.452478 -290.058036)
			(xy 375.415868 -290.021426) (xy 375.385436 -289.979539) (xy 375.36193 -289.933407) (xy 375.345931 -289.884167)
			(xy 375.337832 -289.833029) (xy 375.337324 -289.807142) (xy 374.1166 -289.807142) (xy 374.116092 -289.833029)
			(xy 374.107993 -289.884167) (xy 374.091994 -289.933407) (xy 374.068488 -289.979539) (xy 374.038056 -290.021426)
			(xy 374.001446 -290.058036) (xy 373.959559 -290.088468) (xy 373.913427 -290.111974) (xy 373.864187 -290.127973)
			(xy 373.813049 -290.136072) (xy 373.761275 -290.136072) (xy 373.710137 -290.127973) (xy 373.660897 -290.111974)
			(xy 373.614765 -290.088468) (xy 373.572878 -290.058036) (xy 373.536268 -290.021426) (xy 373.505836 -289.979539)
			(xy 373.48233 -289.933407) (xy 373.466331 -289.884167) (xy 373.458232 -289.833029) (xy 373.457724 -289.807142)
			(xy 372.237 -289.807142) (xy 372.236492 -289.833029) (xy 372.228393 -289.884167) (xy 372.212394 -289.933407)
			(xy 372.188888 -289.979539) (xy 372.158456 -290.021426) (xy 372.121846 -290.058036) (xy 372.079959 -290.088468)
			(xy 372.033827 -290.111974) (xy 371.984587 -290.127973) (xy 371.933449 -290.136072) (xy 371.881675 -290.136072)
			(xy 371.830537 -290.127973) (xy 371.781297 -290.111974) (xy 371.735165 -290.088468) (xy 371.693278 -290.058036)
			(xy 371.656668 -290.021426) (xy 371.626236 -289.979539) (xy 371.60273 -289.933407) (xy 371.586731 -289.884167)
			(xy 371.578632 -289.833029) (xy 371.578124 -289.807142) (xy 370.3574 -289.807142) (xy 370.356892 -289.833029)
			(xy 370.348793 -289.884167) (xy 370.332794 -289.933407) (xy 370.309288 -289.979539) (xy 370.278856 -290.021426)
			(xy 370.242246 -290.058036) (xy 370.200359 -290.088468) (xy 370.154227 -290.111974) (xy 370.104987 -290.127973)
			(xy 370.053849 -290.136072) (xy 370.002075 -290.136072) (xy 369.950937 -290.127973) (xy 369.901697 -290.111974)
			(xy 369.855565 -290.088468) (xy 369.813678 -290.058036) (xy 369.777068 -290.021426) (xy 369.746636 -289.979539)
			(xy 369.72313 -289.933407) (xy 369.707131 -289.884167) (xy 369.699032 -289.833029) (xy 369.698524 -289.807142)
			(xy 368.4778 -289.807142) (xy 368.477292 -289.833029) (xy 368.469193 -289.884167) (xy 368.453194 -289.933407)
			(xy 368.429688 -289.979539) (xy 368.399256 -290.021426) (xy 368.362646 -290.058036) (xy 368.320759 -290.088468)
			(xy 368.274627 -290.111974) (xy 368.225387 -290.127973) (xy 368.174249 -290.136072) (xy 368.122475 -290.136072)
			(xy 368.071337 -290.127973) (xy 368.022097 -290.111974) (xy 367.975965 -290.088468) (xy 367.934078 -290.058036)
			(xy 367.897468 -290.021426) (xy 367.867036 -289.979539) (xy 367.84353 -289.933407) (xy 367.827531 -289.884167)
			(xy 367.819432 -289.833029) (xy 367.818924 -289.807142) (xy 351.5614 -289.807142) (xy 351.560892 -289.833029)
			(xy 351.552793 -289.884167) (xy 351.536794 -289.933407) (xy 351.513288 -289.979539) (xy 351.482856 -290.021426)
			(xy 351.446246 -290.058036) (xy 351.404359 -290.088468) (xy 351.358227 -290.111974) (xy 351.308987 -290.127973)
			(xy 351.257849 -290.136072) (xy 351.206075 -290.136072) (xy 351.154937 -290.127973) (xy 351.105697 -290.111974)
			(xy 351.059565 -290.088468) (xy 351.017678 -290.058036) (xy 350.981068 -290.021426) (xy 350.950636 -289.979539)
			(xy 350.92713 -289.933407) (xy 350.911131 -289.884167) (xy 350.903032 -289.833029) (xy 350.902524 -289.807142)
			(xy 350.902524 -289.806634) (xy 350.902922 -289.783785) (xy 350.909275 -289.738531) (xy 350.921824 -289.694589)
			(xy 350.930718 -289.673538) (xy 350.940624 -289.650932) (xy 350.726756 -289.245802) (xy 350.702626 -289.24123)
			(xy 350.677682 -289.236182) (xy 350.629639 -289.219398) (xy 350.584746 -289.195428) (xy 350.544072 -289.164843)
			(xy 350.508582 -289.128369) (xy 350.479121 -289.086873) (xy 350.456389 -289.041341) (xy 350.440925 -288.992857)
			(xy 350.433099 -288.942571) (xy 350.432624 -288.917126) (xy 350.152208 -288.917126) (xy 350.1517 -288.943033)
			(xy 350.143594 -288.99421) (xy 350.127582 -289.043489) (xy 350.104059 -289.089656) (xy 350.073603 -289.131575)
			(xy 350.036965 -289.168213) (xy 349.995046 -289.198669) (xy 349.948879 -289.222192) (xy 349.8996 -289.238204)
			(xy 349.848423 -289.24631) (xy 349.796609 -289.24631) (xy 349.745432 -289.238204) (xy 349.696153 -289.222192)
			(xy 349.649986 -289.198669) (xy 349.608067 -289.168213) (xy 349.571429 -289.131575) (xy 349.540973 -289.089656)
			(xy 349.51745 -289.043489) (xy 349.501438 -288.99421) (xy 349.493332 -288.943033) (xy 349.492824 -288.917126)
			(xy 349.212408 -288.917126) (xy 349.211989 -288.940067) (xy 349.20556 -288.985498) (xy 349.192913 -289.029604)
			(xy 349.18396 -289.05073) (xy 349.174054 -289.073336) (xy 349.387922 -289.478466) (xy 349.412052 -289.483038)
			(xy 349.436973 -289.488138) (xy 349.484984 -289.504939) (xy 349.529843 -289.528919) (xy 349.570484 -289.559507)
			(xy 349.605941 -289.595978) (xy 349.635373 -289.637465) (xy 349.658079 -289.682981) (xy 349.673521 -289.731446)
			(xy 349.681331 -289.781709) (xy 349.6818 -289.807142) (xy 349.681292 -289.833029) (xy 349.673193 -289.884167)
			(xy 349.657194 -289.933407) (xy 349.633688 -289.979539) (xy 349.603256 -290.021426) (xy 349.566646 -290.058036)
			(xy 349.524759 -290.088468) (xy 349.478627 -290.111974) (xy 349.429387 -290.127973) (xy 349.378249 -290.136072)
			(xy 349.326475 -290.136072) (xy 349.275337 -290.127973) (xy 349.226097 -290.111974) (xy 349.179965 -290.088468)
			(xy 349.138078 -290.058036) (xy 349.101468 -290.021426) (xy 349.071036 -289.979539) (xy 349.04753 -289.933407)
			(xy 349.031531 -289.884167) (xy 349.023432 -289.833029) (xy 349.022924 -289.807142) (xy 349.022924 -289.806634)
			(xy 349.023322 -289.783785) (xy 349.029675 -289.738531) (xy 349.042224 -289.694589) (xy 349.051118 -289.673538)
			(xy 349.061024 -289.650932) (xy 348.847156 -289.245802) (xy 348.823026 -289.24123) (xy 348.798082 -289.236182)
			(xy 348.750039 -289.219398) (xy 348.705146 -289.195428) (xy 348.664472 -289.164843) (xy 348.628982 -289.128369)
			(xy 348.599521 -289.086873) (xy 348.576789 -289.041341) (xy 348.561325 -288.992857) (xy 348.553499 -288.942571)
			(xy 348.553024 -288.917126) (xy 348.272608 -288.917126) (xy 348.2721 -288.943033) (xy 348.263994 -288.99421)
			(xy 348.247982 -289.043489) (xy 348.224459 -289.089656) (xy 348.194003 -289.131575) (xy 348.157365 -289.168213)
			(xy 348.115446 -289.198669) (xy 348.069279 -289.222192) (xy 348.02 -289.238204) (xy 347.968823 -289.24631)
			(xy 347.917009 -289.24631) (xy 347.865832 -289.238204) (xy 347.816553 -289.222192) (xy 347.770386 -289.198669)
			(xy 347.728467 -289.168213) (xy 347.691829 -289.131575) (xy 347.661373 -289.089656) (xy 347.63785 -289.043489)
			(xy 347.621838 -288.99421) (xy 347.613732 -288.943033) (xy 347.613224 -288.917126) (xy 347.332808 -288.917126)
			(xy 347.332389 -288.940067) (xy 347.32596 -288.985498) (xy 347.313313 -289.029604) (xy 347.30436 -289.05073)
			(xy 347.294454 -289.073336) (xy 347.508322 -289.478466) (xy 347.532452 -289.483038) (xy 347.557373 -289.488138)
			(xy 347.605384 -289.504939) (xy 347.650243 -289.528919) (xy 347.690884 -289.559507) (xy 347.726341 -289.595978)
			(xy 347.755773 -289.637465) (xy 347.778479 -289.682981) (xy 347.793921 -289.731446) (xy 347.801731 -289.781709)
			(xy 347.8022 -289.807142) (xy 347.801692 -289.833029) (xy 347.793593 -289.884167) (xy 347.777594 -289.933407)
			(xy 347.754088 -289.979539) (xy 347.723656 -290.021426) (xy 347.687046 -290.058036) (xy 347.645159 -290.088468)
			(xy 347.599027 -290.111974) (xy 347.549787 -290.127973) (xy 347.498649 -290.136072) (xy 347.446875 -290.136072)
			(xy 347.395737 -290.127973) (xy 347.346497 -290.111974) (xy 347.300365 -290.088468) (xy 347.258478 -290.058036)
			(xy 347.221868 -290.021426) (xy 347.191436 -289.979539) (xy 347.16793 -289.933407) (xy 347.151931 -289.884167)
			(xy 347.143832 -289.833029) (xy 347.143324 -289.807142) (xy 347.143324 -289.806634) (xy 347.143722 -289.783785)
			(xy 347.150075 -289.738531) (xy 347.162624 -289.694589) (xy 347.171518 -289.673538) (xy 347.181424 -289.650932)
			(xy 346.967556 -289.245802) (xy 346.943426 -289.24123) (xy 346.918482 -289.236182) (xy 346.870439 -289.219398)
			(xy 346.825546 -289.195428) (xy 346.784872 -289.164843) (xy 346.749382 -289.128369) (xy 346.719921 -289.086873)
			(xy 346.697189 -289.041341) (xy 346.681725 -288.992857) (xy 346.673899 -288.942571) (xy 346.673424 -288.917126)
			(xy 346.393008 -288.917126) (xy 346.3925 -288.943033) (xy 346.384394 -288.99421) (xy 346.368382 -289.043489)
			(xy 346.344859 -289.089656) (xy 346.314403 -289.131575) (xy 346.277765 -289.168213) (xy 346.235846 -289.198669)
			(xy 346.189679 -289.222192) (xy 346.1404 -289.238204) (xy 346.089223 -289.24631) (xy 346.037409 -289.24631)
			(xy 345.986232 -289.238204) (xy 345.936953 -289.222192) (xy 345.890786 -289.198669) (xy 345.848867 -289.168213)
			(xy 345.812229 -289.131575) (xy 345.781773 -289.089656) (xy 345.75825 -289.043489) (xy 345.742238 -288.99421)
			(xy 345.734132 -288.943033) (xy 345.733624 -288.917126) (xy 345.453208 -288.917126) (xy 345.452789 -288.940067)
			(xy 345.44636 -288.985498) (xy 345.433713 -289.029604) (xy 345.42476 -289.05073) (xy 345.414854 -289.073336)
			(xy 345.628722 -289.478466) (xy 345.652852 -289.483038) (xy 345.677773 -289.488138) (xy 345.725784 -289.504939)
			(xy 345.770643 -289.528919) (xy 345.811284 -289.559507) (xy 345.846741 -289.595978) (xy 345.876173 -289.637465)
			(xy 345.898879 -289.682981) (xy 345.914321 -289.731446) (xy 345.922131 -289.781709) (xy 345.9226 -289.807142)
			(xy 345.922092 -289.833029) (xy 345.913993 -289.884167) (xy 345.897994 -289.933407) (xy 345.874488 -289.979539)
			(xy 345.844056 -290.021426) (xy 345.807446 -290.058036) (xy 345.765559 -290.088468) (xy 345.719427 -290.111974)
			(xy 345.670187 -290.127973) (xy 345.619049 -290.136072) (xy 345.567275 -290.136072) (xy 345.516137 -290.127973)
			(xy 345.466897 -290.111974) (xy 345.420765 -290.088468) (xy 345.378878 -290.058036) (xy 345.342268 -290.021426)
			(xy 345.311836 -289.979539) (xy 345.28833 -289.933407) (xy 345.272331 -289.884167) (xy 345.264232 -289.833029)
			(xy 345.263724 -289.807142) (xy 345.263724 -289.806634) (xy 345.264122 -289.783785) (xy 345.270475 -289.738531)
			(xy 345.283024 -289.694589) (xy 345.291918 -289.673538) (xy 345.301824 -289.650932) (xy 345.087956 -289.245802)
			(xy 345.063826 -289.24123) (xy 345.038882 -289.236182) (xy 344.990839 -289.219398) (xy 344.945946 -289.195428)
			(xy 344.905272 -289.164843) (xy 344.869782 -289.128369) (xy 344.840321 -289.086873) (xy 344.817589 -289.041341)
			(xy 344.802125 -288.992857) (xy 344.794299 -288.942571) (xy 344.793824 -288.917126) (xy 344.513408 -288.917126)
			(xy 344.5129 -288.943033) (xy 344.504794 -288.99421) (xy 344.488782 -289.043489) (xy 344.465259 -289.089656)
			(xy 344.434803 -289.131575) (xy 344.398165 -289.168213) (xy 344.356246 -289.198669) (xy 344.310079 -289.222192)
			(xy 344.2608 -289.238204) (xy 344.209623 -289.24631) (xy 344.157809 -289.24631) (xy 344.106632 -289.238204)
			(xy 344.057353 -289.222192) (xy 344.011186 -289.198669) (xy 343.969267 -289.168213) (xy 343.932629 -289.131575)
			(xy 343.902173 -289.089656) (xy 343.87865 -289.043489) (xy 343.862638 -288.99421) (xy 343.854532 -288.943033)
			(xy 343.854024 -288.917126) (xy 343.573608 -288.917126) (xy 343.573189 -288.940067) (xy 343.56676 -288.985498)
			(xy 343.554113 -289.029604) (xy 343.54516 -289.05073) (xy 343.535254 -289.073336) (xy 343.749122 -289.478466)
			(xy 343.773252 -289.483038) (xy 343.798173 -289.488138) (xy 343.846184 -289.504939) (xy 343.891043 -289.528919)
			(xy 343.931684 -289.559507) (xy 343.967141 -289.595978) (xy 343.996573 -289.637465) (xy 344.019279 -289.682981)
			(xy 344.034721 -289.731446) (xy 344.042531 -289.781709) (xy 344.043 -289.807142) (xy 344.042492 -289.833029)
			(xy 344.034393 -289.884167) (xy 344.018394 -289.933407) (xy 343.994888 -289.979539) (xy 343.964456 -290.021426)
			(xy 343.927846 -290.058036) (xy 343.885959 -290.088468) (xy 343.839827 -290.111974) (xy 343.790587 -290.127973)
			(xy 343.739449 -290.136072) (xy 343.687675 -290.136072) (xy 343.636537 -290.127973) (xy 343.587297 -290.111974)
			(xy 343.541165 -290.088468) (xy 343.499278 -290.058036) (xy 343.462668 -290.021426) (xy 343.432236 -289.979539)
			(xy 343.40873 -289.933407) (xy 343.392731 -289.884167) (xy 343.384632 -289.833029) (xy 343.384124 -289.807142)
			(xy 343.384124 -289.806634) (xy 343.384522 -289.783785) (xy 343.390875 -289.738531) (xy 343.403424 -289.694589)
			(xy 343.412318 -289.673538) (xy 343.422224 -289.650932) (xy 343.208356 -289.245802) (xy 343.184226 -289.24123)
			(xy 343.159282 -289.236182) (xy 343.111239 -289.219398) (xy 343.066346 -289.195428) (xy 343.025672 -289.164843)
			(xy 342.990182 -289.128369) (xy 342.960721 -289.086873) (xy 342.937989 -289.041341) (xy 342.922525 -288.992857)
			(xy 342.914699 -288.942571) (xy 342.914224 -288.917126) (xy 342.633808 -288.917126) (xy 342.6333 -288.943033)
			(xy 342.625194 -288.99421) (xy 342.609182 -289.043489) (xy 342.585659 -289.089656) (xy 342.555203 -289.131575)
			(xy 342.518565 -289.168213) (xy 342.476646 -289.198669) (xy 342.430479 -289.222192) (xy 342.3812 -289.238204)
			(xy 342.330023 -289.24631) (xy 342.278209 -289.24631) (xy 342.227032 -289.238204) (xy 342.177753 -289.222192)
			(xy 342.131586 -289.198669) (xy 342.089667 -289.168213) (xy 342.053029 -289.131575) (xy 342.022573 -289.089656)
			(xy 341.99905 -289.043489) (xy 341.983038 -288.99421) (xy 341.974932 -288.943033) (xy 341.974424 -288.917126)
			(xy 341.694008 -288.917126) (xy 341.693589 -288.940067) (xy 341.68716 -288.985498) (xy 341.674513 -289.029604)
			(xy 341.66556 -289.05073) (xy 341.655654 -289.073336) (xy 341.869522 -289.478466) (xy 341.893652 -289.483038)
			(xy 341.918573 -289.488138) (xy 341.966584 -289.504939) (xy 342.011443 -289.528919) (xy 342.052084 -289.559507)
			(xy 342.087541 -289.595978) (xy 342.116973 -289.637465) (xy 342.139679 -289.682981) (xy 342.155121 -289.731446)
			(xy 342.162931 -289.781709) (xy 342.1634 -289.807142) (xy 342.162892 -289.833029) (xy 342.154793 -289.884167)
			(xy 342.138794 -289.933407) (xy 342.115288 -289.979539) (xy 342.084856 -290.021426) (xy 342.048246 -290.058036)
			(xy 342.006359 -290.088468) (xy 341.960227 -290.111974) (xy 341.910987 -290.127973) (xy 341.859849 -290.136072)
			(xy 341.808075 -290.136072) (xy 341.756937 -290.127973) (xy 341.707697 -290.111974) (xy 341.661565 -290.088468)
			(xy 341.619678 -290.058036) (xy 341.583068 -290.021426) (xy 341.552636 -289.979539) (xy 341.52913 -289.933407)
			(xy 341.513131 -289.884167) (xy 341.505032 -289.833029) (xy 341.504524 -289.807142) (xy 341.504524 -289.806634)
			(xy 341.504922 -289.783785) (xy 341.511275 -289.738531) (xy 341.523824 -289.694589) (xy 341.532718 -289.673538)
			(xy 341.542624 -289.650932) (xy 341.328756 -289.245802) (xy 341.304626 -289.24123) (xy 341.279682 -289.236182)
			(xy 341.231639 -289.219398) (xy 341.186746 -289.195428) (xy 341.146072 -289.164843) (xy 341.110582 -289.128369)
			(xy 341.081121 -289.086873) (xy 341.058389 -289.041341) (xy 341.042925 -288.992857) (xy 341.035099 -288.942571)
			(xy 341.034624 -288.917126) (xy 340.754208 -288.917126) (xy 340.7537 -288.943033) (xy 340.745594 -288.99421)
			(xy 340.729582 -289.043489) (xy 340.706059 -289.089656) (xy 340.675603 -289.131575) (xy 340.638965 -289.168213)
			(xy 340.597046 -289.198669) (xy 340.550879 -289.222192) (xy 340.5016 -289.238204) (xy 340.450423 -289.24631)
			(xy 340.398609 -289.24631) (xy 340.347432 -289.238204) (xy 340.298153 -289.222192) (xy 340.251986 -289.198669)
			(xy 340.210067 -289.168213) (xy 340.173429 -289.131575) (xy 340.142973 -289.089656) (xy 340.11945 -289.043489)
			(xy 340.103438 -288.99421) (xy 340.095332 -288.943033) (xy 340.094824 -288.917126) (xy 339.814408 -288.917126)
			(xy 339.813989 -288.940067) (xy 339.80756 -288.985498) (xy 339.794913 -289.029604) (xy 339.78596 -289.05073)
			(xy 339.776054 -289.073336) (xy 339.989922 -289.478466) (xy 340.014052 -289.483038) (xy 340.038973 -289.488138)
			(xy 340.086984 -289.504939) (xy 340.131843 -289.528919) (xy 340.172484 -289.559507) (xy 340.207941 -289.595978)
			(xy 340.237373 -289.637465) (xy 340.260079 -289.682981) (xy 340.275521 -289.731446) (xy 340.283331 -289.781709)
			(xy 340.2838 -289.807142) (xy 340.283292 -289.833029) (xy 340.275193 -289.884167) (xy 340.259194 -289.933407)
			(xy 340.235688 -289.979539) (xy 340.205256 -290.021426) (xy 340.168646 -290.058036) (xy 340.126759 -290.088468)
			(xy 340.080627 -290.111974) (xy 340.031387 -290.127973) (xy 339.980249 -290.136072) (xy 339.928475 -290.136072)
			(xy 339.877337 -290.127973) (xy 339.828097 -290.111974) (xy 339.781965 -290.088468) (xy 339.740078 -290.058036)
			(xy 339.703468 -290.021426) (xy 339.673036 -289.979539) (xy 339.64953 -289.933407) (xy 339.633531 -289.884167)
			(xy 339.625432 -289.833029) (xy 339.624924 -289.807142) (xy 339.624924 -289.806634) (xy 339.625322 -289.783785)
			(xy 339.631675 -289.738531) (xy 339.644224 -289.694589) (xy 339.653118 -289.673538) (xy 339.663024 -289.650932)
			(xy 339.449156 -289.245802) (xy 339.425026 -289.24123) (xy 339.400082 -289.236182) (xy 339.352039 -289.219398)
			(xy 339.307146 -289.195428) (xy 339.266472 -289.164843) (xy 339.230982 -289.128369) (xy 339.201521 -289.086873)
			(xy 339.178789 -289.041341) (xy 339.163325 -288.992857) (xy 339.155499 -288.942571) (xy 339.155024 -288.917126)
			(xy 338.874608 -288.917126) (xy 338.8741 -288.943033) (xy 338.865994 -288.99421) (xy 338.849982 -289.043489)
			(xy 338.826459 -289.089656) (xy 338.796003 -289.131575) (xy 338.759365 -289.168213) (xy 338.717446 -289.198669)
			(xy 338.671279 -289.222192) (xy 338.622 -289.238204) (xy 338.570823 -289.24631) (xy 338.519009 -289.24631)
			(xy 338.467832 -289.238204) (xy 338.418553 -289.222192) (xy 338.372386 -289.198669) (xy 338.330467 -289.168213)
			(xy 338.293829 -289.131575) (xy 338.263373 -289.089656) (xy 338.23985 -289.043489) (xy 338.223838 -288.99421)
			(xy 338.215732 -288.943033) (xy 338.215224 -288.917126) (xy 336.995008 -288.917126) (xy 336.9945 -288.943033)
			(xy 336.986394 -288.99421) (xy 336.970382 -289.043489) (xy 336.946859 -289.089656) (xy 336.916403 -289.131575)
			(xy 336.879765 -289.168213) (xy 336.837846 -289.198669) (xy 336.791679 -289.222192) (xy 336.7424 -289.238204)
			(xy 336.691223 -289.24631) (xy 336.639409 -289.24631) (xy 336.588232 -289.238204) (xy 336.538953 -289.222192)
			(xy 336.492786 -289.198669) (xy 336.450867 -289.168213) (xy 336.414229 -289.131575) (xy 336.383773 -289.089656)
			(xy 336.36025 -289.043489) (xy 336.344238 -288.99421) (xy 336.336132 -288.943033) (xy 336.335624 -288.917126)
			(xy 313.738768 -288.917126) (xy 313.738768 -289.321494) (xy 313.738262 -289.331651) (xy 313.730491 -289.350419)
			(xy 313.716129 -289.364784) (xy 313.697363 -289.372559) (xy 313.687206 -289.373056) (xy 312.287666 -289.373056)
			(xy 312.277505 -289.372594) (xy 312.258734 -289.364808) (xy 312.24437 -289.350432) (xy 312.236598 -289.331655)
			(xy 312.236104 -289.321494) (xy 306.194968 -289.321494) (xy 306.194462 -289.331651) (xy 306.186691 -289.350419)
			(xy 306.172329 -289.364784) (xy 306.153563 -289.372559) (xy 306.143406 -289.373056) (xy 304.743866 -289.373056)
			(xy 304.733705 -289.372594) (xy 304.714934 -289.364808) (xy 304.70057 -289.350432) (xy 304.692798 -289.331655)
			(xy 304.692304 -289.321494) (xy 298.651168 -289.321494) (xy 298.650662 -289.331651) (xy 298.642891 -289.350419)
			(xy 298.628529 -289.364784) (xy 298.609763 -289.372559) (xy 298.599606 -289.373056) (xy 297.200066 -289.373056)
			(xy 297.189905 -289.372594) (xy 297.171134 -289.364808) (xy 297.15677 -289.350432) (xy 297.148998 -289.331655)
			(xy 297.148504 -289.321494) (xy 291.107368 -289.321494) (xy 291.106862 -289.331651) (xy 291.099091 -289.350419)
			(xy 291.084729 -289.364784) (xy 291.065963 -289.372559) (xy 291.055806 -289.373056) (xy 289.656266 -289.373056)
			(xy 289.646105 -289.372594) (xy 289.627334 -289.364808) (xy 289.61297 -289.350432) (xy 289.605198 -289.331655)
			(xy 289.604704 -289.321494) (xy 283.563568 -289.321494) (xy 283.563062 -289.331651) (xy 283.555291 -289.350419)
			(xy 283.540929 -289.364784) (xy 283.522163 -289.372559) (xy 283.512006 -289.373056) (xy 282.112466 -289.373056)
			(xy 282.102305 -289.372594) (xy 282.083534 -289.364808) (xy 282.06917 -289.350432) (xy 282.061398 -289.331655)
			(xy 282.060904 -289.321494) (xy 276.019768 -289.321494) (xy 276.019262 -289.331651) (xy 276.011491 -289.350419)
			(xy 275.997129 -289.364784) (xy 275.978363 -289.372559) (xy 275.968206 -289.373056) (xy 274.568666 -289.373056)
			(xy 274.558505 -289.372594) (xy 274.539734 -289.364808) (xy 274.52537 -289.350432) (xy 274.517598 -289.331655)
			(xy 274.517104 -289.321494) (xy 268.475968 -289.321494) (xy 268.475462 -289.331651) (xy 268.467691 -289.350419)
			(xy 268.453329 -289.364784) (xy 268.434563 -289.372559) (xy 268.424406 -289.373056) (xy 267.024866 -289.373056)
			(xy 267.014705 -289.372594) (xy 266.995934 -289.364808) (xy 266.98157 -289.350432) (xy 266.973798 -289.331655)
			(xy 266.973304 -289.321494) (xy 260.932168 -289.321494) (xy 260.931662 -289.331651) (xy 260.923891 -289.350419)
			(xy 260.909529 -289.364784) (xy 260.890763 -289.372559) (xy 260.880606 -289.373056) (xy 259.481066 -289.373056)
			(xy 259.470905 -289.372594) (xy 259.452134 -289.364808) (xy 259.43777 -289.350432) (xy 259.429998 -289.331655)
			(xy 259.429504 -289.321494) (xy 216.4715 -289.321494) (xy 216.470963 -289.331647) (xy 216.463197 -289.350408)
			(xy 216.448845 -289.364773) (xy 216.43009 -289.372554) (xy 216.419938 -289.373056) (xy 215.020398 -289.373056)
			(xy 215.010226 -289.372638) (xy 214.99143 -289.364851) (xy 214.977045 -289.350464) (xy 214.969261 -289.331667)
			(xy 214.968836 -289.321494) (xy 208.9277 -289.321494) (xy 208.927163 -289.331647) (xy 208.919397 -289.350408)
			(xy 208.905045 -289.364773) (xy 208.88629 -289.372554) (xy 208.876138 -289.373056) (xy 207.476598 -289.373056)
			(xy 207.466426 -289.372638) (xy 207.44763 -289.364851) (xy 207.433245 -289.350464) (xy 207.425461 -289.331667)
			(xy 207.425036 -289.321494) (xy 201.3839 -289.321494) (xy 201.383363 -289.331647) (xy 201.375597 -289.350408)
			(xy 201.361245 -289.364773) (xy 201.34249 -289.372554) (xy 201.332338 -289.373056) (xy 199.932798 -289.373056)
			(xy 199.922626 -289.372638) (xy 199.90383 -289.364851) (xy 199.889445 -289.350464) (xy 199.881661 -289.331667)
			(xy 199.881236 -289.321494) (xy 193.8401 -289.321494) (xy 193.839563 -289.331647) (xy 193.831797 -289.350408)
			(xy 193.817445 -289.364773) (xy 193.79869 -289.372554) (xy 193.788538 -289.373056) (xy 192.388998 -289.373056)
			(xy 192.378826 -289.372638) (xy 192.36003 -289.364851) (xy 192.345645 -289.350464) (xy 192.337861 -289.331667)
			(xy 192.337436 -289.321494) (xy 186.2963 -289.321494) (xy 186.295763 -289.331647) (xy 186.287997 -289.350408)
			(xy 186.273645 -289.364773) (xy 186.25489 -289.372554) (xy 186.244738 -289.373056) (xy 184.845198 -289.373056)
			(xy 184.835026 -289.372638) (xy 184.81623 -289.364851) (xy 184.801845 -289.350464) (xy 184.794061 -289.331667)
			(xy 184.793636 -289.321494) (xy 178.7525 -289.321494) (xy 178.751963 -289.331647) (xy 178.744197 -289.350408)
			(xy 178.729845 -289.364773) (xy 178.71109 -289.372554) (xy 178.700938 -289.373056) (xy 177.301398 -289.373056)
			(xy 177.291226 -289.372638) (xy 177.27243 -289.364851) (xy 177.258045 -289.350464) (xy 177.250261 -289.331667)
			(xy 177.249836 -289.321494) (xy 171.2087 -289.321494) (xy 171.208163 -289.331647) (xy 171.200397 -289.350408)
			(xy 171.186045 -289.364773) (xy 171.16729 -289.372554) (xy 171.157138 -289.373056) (xy 169.757598 -289.373056)
			(xy 169.747426 -289.372638) (xy 169.72863 -289.364851) (xy 169.714245 -289.350464) (xy 169.706461 -289.331667)
			(xy 169.706036 -289.321494) (xy 163.6649 -289.321494) (xy 163.664363 -289.331647) (xy 163.656597 -289.350408)
			(xy 163.642245 -289.364773) (xy 163.62349 -289.372554) (xy 163.613338 -289.373056) (xy 162.213798 -289.373056)
			(xy 162.203626 -289.372638) (xy 162.18483 -289.364851) (xy 162.170445 -289.350464) (xy 162.162661 -289.331667)
			(xy 162.162236 -289.321494) (xy 133.83118 -289.321494) (xy 133.656832 -289.651186) (xy 133.666738 -289.673792)
			(xy 133.675656 -289.694878) (xy 133.688208 -289.738907) (xy 133.694542 -289.78425) (xy 133.694932 -289.807142)
			(xy 133.694424 -289.833029) (xy 133.686325 -289.884167) (xy 133.670326 -289.933407) (xy 133.64682 -289.979539)
			(xy 133.616388 -290.021426) (xy 133.579778 -290.058036) (xy 133.537891 -290.088468) (xy 133.491759 -290.111974)
			(xy 133.442519 -290.127973) (xy 133.391381 -290.136072) (xy 133.339607 -290.136072) (xy 133.288469 -290.127973)
			(xy 133.239229 -290.111974) (xy 133.193097 -290.088468) (xy 133.15121 -290.058036) (xy 133.1146 -290.021426)
			(xy 133.084168 -289.979539) (xy 133.060662 -289.933407) (xy 133.044663 -289.884167) (xy 133.036564 -289.833029)
			(xy 133.036056 -289.807142) (xy 131.815332 -289.807142) (xy 131.814824 -289.833029) (xy 131.806725 -289.884167)
			(xy 131.790726 -289.933407) (xy 131.76722 -289.979539) (xy 131.736788 -290.021426) (xy 131.700178 -290.058036)
			(xy 131.658291 -290.088468) (xy 131.612159 -290.111974) (xy 131.562919 -290.127973) (xy 131.511781 -290.136072)
			(xy 131.460007 -290.136072) (xy 131.408869 -290.127973) (xy 131.359629 -290.111974) (xy 131.313497 -290.088468)
			(xy 131.27161 -290.058036) (xy 131.235 -290.021426) (xy 131.204568 -289.979539) (xy 131.181062 -289.933407)
			(xy 131.165063 -289.884167) (xy 131.156964 -289.833029) (xy 131.156456 -289.807142) (xy 129.935732 -289.807142)
			(xy 129.935224 -289.833029) (xy 129.927125 -289.884167) (xy 129.911126 -289.933407) (xy 129.88762 -289.979539)
			(xy 129.857188 -290.021426) (xy 129.820578 -290.058036) (xy 129.778691 -290.088468) (xy 129.732559 -290.111974)
			(xy 129.683319 -290.127973) (xy 129.632181 -290.136072) (xy 129.580407 -290.136072) (xy 129.529269 -290.127973)
			(xy 129.480029 -290.111974) (xy 129.433897 -290.088468) (xy 129.39201 -290.058036) (xy 129.3554 -290.021426)
			(xy 129.324968 -289.979539) (xy 129.301462 -289.933407) (xy 129.285463 -289.884167) (xy 129.277364 -289.833029)
			(xy 129.276856 -289.807142) (xy 128.056132 -289.807142) (xy 128.055624 -289.833029) (xy 128.047525 -289.884167)
			(xy 128.031526 -289.933407) (xy 128.00802 -289.979539) (xy 127.977588 -290.021426) (xy 127.940978 -290.058036)
			(xy 127.899091 -290.088468) (xy 127.852959 -290.111974) (xy 127.803719 -290.127973) (xy 127.752581 -290.136072)
			(xy 127.700807 -290.136072) (xy 127.649669 -290.127973) (xy 127.600429 -290.111974) (xy 127.554297 -290.088468)
			(xy 127.51241 -290.058036) (xy 127.4758 -290.021426) (xy 127.445368 -289.979539) (xy 127.421862 -289.933407)
			(xy 127.405863 -289.884167) (xy 127.397764 -289.833029) (xy 127.397256 -289.807142) (xy 126.176532 -289.807142)
			(xy 126.176024 -289.833029) (xy 126.167925 -289.884167) (xy 126.151926 -289.933407) (xy 126.12842 -289.979539)
			(xy 126.097988 -290.021426) (xy 126.061378 -290.058036) (xy 126.019491 -290.088468) (xy 125.973359 -290.111974)
			(xy 125.924119 -290.127973) (xy 125.872981 -290.136072) (xy 125.821207 -290.136072) (xy 125.770069 -290.127973)
			(xy 125.720829 -290.111974) (xy 125.674697 -290.088468) (xy 125.63281 -290.058036) (xy 125.5962 -290.021426)
			(xy 125.565768 -289.979539) (xy 125.542262 -289.933407) (xy 125.526263 -289.884167) (xy 125.518164 -289.833029)
			(xy 125.517656 -289.807142) (xy 124.296932 -289.807142) (xy 124.296424 -289.833029) (xy 124.288325 -289.884167)
			(xy 124.272326 -289.933407) (xy 124.24882 -289.979539) (xy 124.218388 -290.021426) (xy 124.181778 -290.058036)
			(xy 124.139891 -290.088468) (xy 124.093759 -290.111974) (xy 124.044519 -290.127973) (xy 123.993381 -290.136072)
			(xy 123.941607 -290.136072) (xy 123.890469 -290.127973) (xy 123.841229 -290.111974) (xy 123.795097 -290.088468)
			(xy 123.75321 -290.058036) (xy 123.7166 -290.021426) (xy 123.686168 -289.979539) (xy 123.662662 -289.933407)
			(xy 123.646663 -289.884167) (xy 123.638564 -289.833029) (xy 123.638056 -289.807142) (xy 122.417332 -289.807142)
			(xy 122.416824 -289.833029) (xy 122.408725 -289.884167) (xy 122.392726 -289.933407) (xy 122.36922 -289.979539)
			(xy 122.338788 -290.021426) (xy 122.302178 -290.058036) (xy 122.260291 -290.088468) (xy 122.214159 -290.111974)
			(xy 122.164919 -290.127973) (xy 122.113781 -290.136072) (xy 122.062007 -290.136072) (xy 122.010869 -290.127973)
			(xy 121.961629 -290.111974) (xy 121.915497 -290.088468) (xy 121.87361 -290.058036) (xy 121.837 -290.021426)
			(xy 121.806568 -289.979539) (xy 121.783062 -289.933407) (xy 121.767063 -289.884167) (xy 121.758964 -289.833029)
			(xy 121.758456 -289.807142) (xy 120.537732 -289.807142) (xy 120.537224 -289.833029) (xy 120.529125 -289.884167)
			(xy 120.513126 -289.933407) (xy 120.48962 -289.979539) (xy 120.459188 -290.021426) (xy 120.422578 -290.058036)
			(xy 120.380691 -290.088468) (xy 120.334559 -290.111974) (xy 120.285319 -290.127973) (xy 120.234181 -290.136072)
			(xy 120.182407 -290.136072) (xy 120.131269 -290.127973) (xy 120.082029 -290.111974) (xy 120.035897 -290.088468)
			(xy 119.99401 -290.058036) (xy 119.9574 -290.021426) (xy 119.926968 -289.979539) (xy 119.903462 -289.933407)
			(xy 119.887463 -289.884167) (xy 119.879364 -289.833029) (xy 119.878856 -289.807142) (xy 103.621332 -289.807142)
			(xy 103.620824 -289.833029) (xy 103.612725 -289.884167) (xy 103.596726 -289.933407) (xy 103.57322 -289.979539)
			(xy 103.542788 -290.021426) (xy 103.506178 -290.058036) (xy 103.464291 -290.088468) (xy 103.418159 -290.111974)
			(xy 103.368919 -290.127973) (xy 103.317781 -290.136072) (xy 103.266007 -290.136072) (xy 103.214869 -290.127973)
			(xy 103.165629 -290.111974) (xy 103.119497 -290.088468) (xy 103.07761 -290.058036) (xy 103.041 -290.021426)
			(xy 103.010568 -289.979539) (xy 102.987062 -289.933407) (xy 102.971063 -289.884167) (xy 102.962964 -289.833029)
			(xy 102.962456 -289.807142) (xy 102.962456 -289.806634) (xy 102.962859 -289.783785) (xy 102.969212 -289.738531)
			(xy 102.981758 -289.694589) (xy 102.99065 -289.673538) (xy 103.000556 -289.650932) (xy 102.786688 -289.245802)
			(xy 102.762558 -289.24123) (xy 102.737619 -289.236158) (xy 102.689576 -289.219379) (xy 102.644683 -289.195414)
			(xy 102.604007 -289.164832) (xy 102.568517 -289.12836) (xy 102.539055 -289.086867) (xy 102.516322 -289.041337)
			(xy 102.500858 -288.992854) (xy 102.493031 -288.942571) (xy 102.492556 -288.917126) (xy 102.21214 -288.917126)
			(xy 102.211632 -288.943033) (xy 102.203526 -288.99421) (xy 102.187514 -289.043489) (xy 102.163991 -289.089656)
			(xy 102.133535 -289.131575) (xy 102.096897 -289.168213) (xy 102.054978 -289.198669) (xy 102.008811 -289.222192)
			(xy 101.959532 -289.238204) (xy 101.908355 -289.24631) (xy 101.856541 -289.24631) (xy 101.805364 -289.238204)
			(xy 101.756085 -289.222192) (xy 101.709918 -289.198669) (xy 101.667999 -289.168213) (xy 101.631361 -289.131575)
			(xy 101.600905 -289.089656) (xy 101.577382 -289.043489) (xy 101.56137 -288.99421) (xy 101.553264 -288.943033)
			(xy 101.552756 -288.917126) (xy 101.27234 -288.917126) (xy 101.271918 -288.940067) (xy 101.26549 -288.985498)
			(xy 101.252844 -289.029604) (xy 101.243892 -289.05073) (xy 101.233986 -289.073336) (xy 101.447854 -289.478466)
			(xy 101.471984 -289.483038) (xy 101.49691 -289.488115) (xy 101.544921 -289.50492) (xy 101.589779 -289.528904)
			(xy 101.630419 -289.559496) (xy 101.665876 -289.59597) (xy 101.695306 -289.637459) (xy 101.718012 -289.682977)
			(xy 101.733453 -289.731444) (xy 101.741263 -289.781708) (xy 101.741732 -289.807142) (xy 101.741224 -289.833029)
			(xy 101.733125 -289.884167) (xy 101.717126 -289.933407) (xy 101.69362 -289.979539) (xy 101.663188 -290.021426)
			(xy 101.626578 -290.058036) (xy 101.584691 -290.088468) (xy 101.538559 -290.111974) (xy 101.489319 -290.127973)
			(xy 101.438181 -290.136072) (xy 101.386407 -290.136072) (xy 101.335269 -290.127973) (xy 101.286029 -290.111974)
			(xy 101.239897 -290.088468) (xy 101.19801 -290.058036) (xy 101.1614 -290.021426) (xy 101.130968 -289.979539)
			(xy 101.107462 -289.933407) (xy 101.091463 -289.884167) (xy 101.083364 -289.833029) (xy 101.082856 -289.807142)
			(xy 101.082856 -289.806634) (xy 101.083259 -289.783785) (xy 101.089612 -289.738531) (xy 101.102158 -289.694589)
			(xy 101.11105 -289.673538) (xy 101.120956 -289.650932) (xy 100.907088 -289.245802) (xy 100.882958 -289.24123)
			(xy 100.858019 -289.236158) (xy 100.809976 -289.219379) (xy 100.765083 -289.195414) (xy 100.724407 -289.164832)
			(xy 100.688917 -289.12836) (xy 100.659455 -289.086867) (xy 100.636722 -289.041337) (xy 100.621258 -288.992854)
			(xy 100.613431 -288.942571) (xy 100.612956 -288.917126) (xy 100.33254 -288.917126) (xy 100.332032 -288.943033)
			(xy 100.323926 -288.99421) (xy 100.307914 -289.043489) (xy 100.284391 -289.089656) (xy 100.253935 -289.131575)
			(xy 100.217297 -289.168213) (xy 100.175378 -289.198669) (xy 100.129211 -289.222192) (xy 100.079932 -289.238204)
			(xy 100.028755 -289.24631) (xy 99.976941 -289.24631) (xy 99.925764 -289.238204) (xy 99.876485 -289.222192)
			(xy 99.830318 -289.198669) (xy 99.788399 -289.168213) (xy 99.751761 -289.131575) (xy 99.721305 -289.089656)
			(xy 99.697782 -289.043489) (xy 99.68177 -288.99421) (xy 99.673664 -288.943033) (xy 99.673156 -288.917126)
			(xy 99.39274 -288.917126) (xy 99.392318 -288.940067) (xy 99.38589 -288.985498) (xy 99.373244 -289.029604)
			(xy 99.364292 -289.05073) (xy 99.354386 -289.073336) (xy 99.568254 -289.478466) (xy 99.592384 -289.483038)
			(xy 99.61731 -289.488115) (xy 99.665321 -289.50492) (xy 99.710179 -289.528904) (xy 99.750819 -289.559496)
			(xy 99.786276 -289.59597) (xy 99.815706 -289.637459) (xy 99.838412 -289.682977) (xy 99.853853 -289.731444)
			(xy 99.861663 -289.781708) (xy 99.862132 -289.807142) (xy 99.861624 -289.833029) (xy 99.853525 -289.884167)
			(xy 99.837526 -289.933407) (xy 99.81402 -289.979539) (xy 99.783588 -290.021426) (xy 99.746978 -290.058036)
			(xy 99.705091 -290.088468) (xy 99.658959 -290.111974) (xy 99.609719 -290.127973) (xy 99.558581 -290.136072)
			(xy 99.506807 -290.136072) (xy 99.455669 -290.127973) (xy 99.406429 -290.111974) (xy 99.360297 -290.088468)
			(xy 99.31841 -290.058036) (xy 99.2818 -290.021426) (xy 99.251368 -289.979539) (xy 99.227862 -289.933407)
			(xy 99.211863 -289.884167) (xy 99.203764 -289.833029) (xy 99.203256 -289.807142) (xy 99.203256 -289.806634)
			(xy 99.203659 -289.783785) (xy 99.210012 -289.738531) (xy 99.222558 -289.694589) (xy 99.23145 -289.673538)
			(xy 99.241356 -289.650932) (xy 99.027488 -289.245802) (xy 99.003358 -289.24123) (xy 98.978419 -289.236158)
			(xy 98.930376 -289.219379) (xy 98.885483 -289.195414) (xy 98.844807 -289.164832) (xy 98.809317 -289.12836)
			(xy 98.779855 -289.086867) (xy 98.757122 -289.041337) (xy 98.741658 -288.992854) (xy 98.733831 -288.942571)
			(xy 98.733356 -288.917126) (xy 98.45294 -288.917126) (xy 98.452432 -288.943033) (xy 98.444326 -288.99421)
			(xy 98.428314 -289.043489) (xy 98.404791 -289.089656) (xy 98.374335 -289.131575) (xy 98.337697 -289.168213)
			(xy 98.295778 -289.198669) (xy 98.249611 -289.222192) (xy 98.200332 -289.238204) (xy 98.149155 -289.24631)
			(xy 98.097341 -289.24631) (xy 98.046164 -289.238204) (xy 97.996885 -289.222192) (xy 97.950718 -289.198669)
			(xy 97.908799 -289.168213) (xy 97.872161 -289.131575) (xy 97.841705 -289.089656) (xy 97.818182 -289.043489)
			(xy 97.80217 -288.99421) (xy 97.794064 -288.943033) (xy 97.793556 -288.917126) (xy 97.51314 -288.917126)
			(xy 97.512718 -288.940067) (xy 97.50629 -288.985498) (xy 97.493644 -289.029604) (xy 97.484692 -289.05073)
			(xy 97.474786 -289.073336) (xy 97.688654 -289.478466) (xy 97.712784 -289.483038) (xy 97.73771 -289.488115)
			(xy 97.785721 -289.50492) (xy 97.830579 -289.528904) (xy 97.871219 -289.559496) (xy 97.906676 -289.59597)
			(xy 97.936106 -289.637459) (xy 97.958812 -289.682977) (xy 97.974253 -289.731444) (xy 97.982063 -289.781708)
			(xy 97.982532 -289.807142) (xy 97.982024 -289.833029) (xy 97.973925 -289.884167) (xy 97.957926 -289.933407)
			(xy 97.93442 -289.979539) (xy 97.903988 -290.021426) (xy 97.867378 -290.058036) (xy 97.825491 -290.088468)
			(xy 97.779359 -290.111974) (xy 97.730119 -290.127973) (xy 97.678981 -290.136072) (xy 97.627207 -290.136072)
			(xy 97.576069 -290.127973) (xy 97.526829 -290.111974) (xy 97.480697 -290.088468) (xy 97.43881 -290.058036)
			(xy 97.4022 -290.021426) (xy 97.371768 -289.979539) (xy 97.348262 -289.933407) (xy 97.332263 -289.884167)
			(xy 97.324164 -289.833029) (xy 97.323656 -289.807142) (xy 97.323656 -289.806634) (xy 97.324059 -289.783785)
			(xy 97.330412 -289.738531) (xy 97.342958 -289.694589) (xy 97.35185 -289.673538) (xy 97.361756 -289.650932)
			(xy 97.147888 -289.245802) (xy 97.123758 -289.24123) (xy 97.098819 -289.236158) (xy 97.050776 -289.219379)
			(xy 97.005883 -289.195414) (xy 96.965207 -289.164832) (xy 96.929717 -289.12836) (xy 96.900255 -289.086867)
			(xy 96.877522 -289.041337) (xy 96.862058 -288.992854) (xy 96.854231 -288.942571) (xy 96.853756 -288.917126)
			(xy 96.57334 -288.917126) (xy 96.572832 -288.943033) (xy 96.564726 -288.99421) (xy 96.548714 -289.043489)
			(xy 96.525191 -289.089656) (xy 96.494735 -289.131575) (xy 96.458097 -289.168213) (xy 96.416178 -289.198669)
			(xy 96.370011 -289.222192) (xy 96.320732 -289.238204) (xy 96.269555 -289.24631) (xy 96.217741 -289.24631)
			(xy 96.166564 -289.238204) (xy 96.117285 -289.222192) (xy 96.071118 -289.198669) (xy 96.029199 -289.168213)
			(xy 95.992561 -289.131575) (xy 95.962105 -289.089656) (xy 95.938582 -289.043489) (xy 95.92257 -288.99421)
			(xy 95.914464 -288.943033) (xy 95.913956 -288.917126) (xy 95.63354 -288.917126) (xy 95.633118 -288.940067)
			(xy 95.62669 -288.985498) (xy 95.614044 -289.029604) (xy 95.605092 -289.05073) (xy 95.595186 -289.073336)
			(xy 95.809054 -289.478466) (xy 95.833184 -289.483038) (xy 95.85811 -289.488115) (xy 95.906121 -289.50492)
			(xy 95.950979 -289.528904) (xy 95.991619 -289.559496) (xy 96.027076 -289.59597) (xy 96.056506 -289.637459)
			(xy 96.079212 -289.682977) (xy 96.094653 -289.731444) (xy 96.102463 -289.781708) (xy 96.102932 -289.807142)
			(xy 96.102424 -289.833029) (xy 96.094325 -289.884167) (xy 96.078326 -289.933407) (xy 96.05482 -289.979539)
			(xy 96.024388 -290.021426) (xy 95.987778 -290.058036) (xy 95.945891 -290.088468) (xy 95.899759 -290.111974)
			(xy 95.850519 -290.127973) (xy 95.799381 -290.136072) (xy 95.747607 -290.136072) (xy 95.696469 -290.127973)
			(xy 95.647229 -290.111974) (xy 95.601097 -290.088468) (xy 95.55921 -290.058036) (xy 95.5226 -290.021426)
			(xy 95.492168 -289.979539) (xy 95.468662 -289.933407) (xy 95.452663 -289.884167) (xy 95.444564 -289.833029)
			(xy 95.444056 -289.807142) (xy 95.444056 -289.806634) (xy 95.444459 -289.783785) (xy 95.450812 -289.738531)
			(xy 95.463358 -289.694589) (xy 95.47225 -289.673538) (xy 95.482156 -289.650932) (xy 95.268288 -289.245802)
			(xy 95.244158 -289.24123) (xy 95.219219 -289.236158) (xy 95.171176 -289.219379) (xy 95.126283 -289.195414)
			(xy 95.085607 -289.164832) (xy 95.050117 -289.12836) (xy 95.020655 -289.086867) (xy 94.997922 -289.041337)
			(xy 94.982458 -288.992854) (xy 94.974631 -288.942571) (xy 94.974156 -288.917126) (xy 94.69374 -288.917126)
			(xy 94.693232 -288.943033) (xy 94.685126 -288.99421) (xy 94.669114 -289.043489) (xy 94.645591 -289.089656)
			(xy 94.615135 -289.131575) (xy 94.578497 -289.168213) (xy 94.536578 -289.198669) (xy 94.490411 -289.222192)
			(xy 94.441132 -289.238204) (xy 94.389955 -289.24631) (xy 94.338141 -289.24631) (xy 94.286964 -289.238204)
			(xy 94.237685 -289.222192) (xy 94.191518 -289.198669) (xy 94.149599 -289.168213) (xy 94.112961 -289.131575)
			(xy 94.082505 -289.089656) (xy 94.058982 -289.043489) (xy 94.04297 -288.99421) (xy 94.034864 -288.943033)
			(xy 94.034356 -288.917126) (xy 93.75394 -288.917126) (xy 93.753518 -288.940067) (xy 93.74709 -288.985498)
			(xy 93.734444 -289.029604) (xy 93.725492 -289.05073) (xy 93.715586 -289.073336) (xy 93.929454 -289.478466)
			(xy 93.953584 -289.483038) (xy 93.97851 -289.488115) (xy 94.026521 -289.50492) (xy 94.071379 -289.528904)
			(xy 94.112019 -289.559496) (xy 94.147476 -289.59597) (xy 94.176906 -289.637459) (xy 94.199612 -289.682977)
			(xy 94.215053 -289.731444) (xy 94.222863 -289.781708) (xy 94.223332 -289.807142) (xy 94.222824 -289.833029)
			(xy 94.214725 -289.884167) (xy 94.198726 -289.933407) (xy 94.17522 -289.979539) (xy 94.144788 -290.021426)
			(xy 94.108178 -290.058036) (xy 94.066291 -290.088468) (xy 94.020159 -290.111974) (xy 93.970919 -290.127973)
			(xy 93.919781 -290.136072) (xy 93.868007 -290.136072) (xy 93.816869 -290.127973) (xy 93.767629 -290.111974)
			(xy 93.721497 -290.088468) (xy 93.67961 -290.058036) (xy 93.643 -290.021426) (xy 93.612568 -289.979539)
			(xy 93.589062 -289.933407) (xy 93.573063 -289.884167) (xy 93.564964 -289.833029) (xy 93.564456 -289.807142)
			(xy 93.564456 -289.806634) (xy 93.564859 -289.783785) (xy 93.571212 -289.738531) (xy 93.583758 -289.694589)
			(xy 93.59265 -289.673538) (xy 93.602556 -289.650932) (xy 93.388688 -289.245802) (xy 93.364558 -289.24123)
			(xy 93.339619 -289.236158) (xy 93.291576 -289.219379) (xy 93.246683 -289.195414) (xy 93.206007 -289.164832)
			(xy 93.170517 -289.12836) (xy 93.141055 -289.086867) (xy 93.118322 -289.041337) (xy 93.102858 -288.992854)
			(xy 93.095031 -288.942571) (xy 93.094556 -288.917126) (xy 92.81414 -288.917126) (xy 92.813632 -288.943033)
			(xy 92.805526 -288.99421) (xy 92.789514 -289.043489) (xy 92.765991 -289.089656) (xy 92.735535 -289.131575)
			(xy 92.698897 -289.168213) (xy 92.656978 -289.198669) (xy 92.610811 -289.222192) (xy 92.561532 -289.238204)
			(xy 92.510355 -289.24631) (xy 92.458541 -289.24631) (xy 92.407364 -289.238204) (xy 92.358085 -289.222192)
			(xy 92.311918 -289.198669) (xy 92.269999 -289.168213) (xy 92.233361 -289.131575) (xy 92.202905 -289.089656)
			(xy 92.179382 -289.043489) (xy 92.16337 -288.99421) (xy 92.155264 -288.943033) (xy 92.154756 -288.917126)
			(xy 91.87434 -288.917126) (xy 91.873918 -288.940067) (xy 91.86749 -288.985498) (xy 91.854844 -289.029604)
			(xy 91.845892 -289.05073) (xy 91.835986 -289.073336) (xy 92.049854 -289.478466) (xy 92.073984 -289.483038)
			(xy 92.09891 -289.488115) (xy 92.146921 -289.50492) (xy 92.191779 -289.528904) (xy 92.232419 -289.559496)
			(xy 92.267876 -289.59597) (xy 92.297306 -289.637459) (xy 92.320012 -289.682977) (xy 92.335453 -289.731444)
			(xy 92.343263 -289.781708) (xy 92.343732 -289.807142) (xy 92.343224 -289.833029) (xy 92.335125 -289.884167)
			(xy 92.319126 -289.933407) (xy 92.29562 -289.979539) (xy 92.265188 -290.021426) (xy 92.228578 -290.058036)
			(xy 92.186691 -290.088468) (xy 92.140559 -290.111974) (xy 92.091319 -290.127973) (xy 92.040181 -290.136072)
			(xy 91.988407 -290.136072) (xy 91.937269 -290.127973) (xy 91.888029 -290.111974) (xy 91.841897 -290.088468)
			(xy 91.80001 -290.058036) (xy 91.7634 -290.021426) (xy 91.732968 -289.979539) (xy 91.709462 -289.933407)
			(xy 91.693463 -289.884167) (xy 91.685364 -289.833029) (xy 91.684856 -289.807142) (xy 91.684856 -289.806634)
			(xy 91.685259 -289.783785) (xy 91.691612 -289.738531) (xy 91.704158 -289.694589) (xy 91.71305 -289.673538)
			(xy 91.722956 -289.650932) (xy 91.509088 -289.245802) (xy 91.484958 -289.24123) (xy 91.460019 -289.236158)
			(xy 91.411976 -289.219379) (xy 91.367083 -289.195414) (xy 91.326407 -289.164832) (xy 91.290917 -289.12836)
			(xy 91.261455 -289.086867) (xy 91.238722 -289.041337) (xy 91.223258 -288.992854) (xy 91.215431 -288.942571)
			(xy 91.214956 -288.917126) (xy 90.93454 -288.917126) (xy 90.934032 -288.943033) (xy 90.925926 -288.99421)
			(xy 90.909914 -289.043489) (xy 90.886391 -289.089656) (xy 90.855935 -289.131575) (xy 90.819297 -289.168213)
			(xy 90.777378 -289.198669) (xy 90.731211 -289.222192) (xy 90.681932 -289.238204) (xy 90.630755 -289.24631)
			(xy 90.578941 -289.24631) (xy 90.527764 -289.238204) (xy 90.478485 -289.222192) (xy 90.432318 -289.198669)
			(xy 90.390399 -289.168213) (xy 90.353761 -289.131575) (xy 90.323305 -289.089656) (xy 90.299782 -289.043489)
			(xy 90.28377 -288.99421) (xy 90.275664 -288.943033) (xy 90.275156 -288.917126) (xy 89.05494 -288.917126)
			(xy 89.054432 -288.943033) (xy 89.046326 -288.99421) (xy 89.030314 -289.043489) (xy 89.006791 -289.089656)
			(xy 88.976335 -289.131575) (xy 88.939697 -289.168213) (xy 88.897778 -289.198669) (xy 88.851611 -289.222192)
			(xy 88.802332 -289.238204) (xy 88.751155 -289.24631) (xy 88.699341 -289.24631) (xy 88.648164 -289.238204)
			(xy 88.598885 -289.222192) (xy 88.552718 -289.198669) (xy 88.510799 -289.168213) (xy 88.474161 -289.131575)
			(xy 88.443705 -289.089656) (xy 88.420182 -289.043489) (xy 88.40417 -288.99421) (xy 88.396064 -288.943033)
			(xy 88.395556 -288.917126) (xy 65.7987 -288.917126) (xy 65.7987 -289.321494) (xy 65.798163 -289.331647)
			(xy 65.790397 -289.350408) (xy 65.776045 -289.364773) (xy 65.75729 -289.372554) (xy 65.747138 -289.373056)
			(xy 64.347598 -289.373056) (xy 64.337426 -289.372638) (xy 64.31863 -289.364851) (xy 64.304245 -289.350464)
			(xy 64.296461 -289.331667) (xy 64.296036 -289.321494) (xy 58.2549 -289.321494) (xy 58.254363 -289.331647)
			(xy 58.246597 -289.350408) (xy 58.232245 -289.364773) (xy 58.21349 -289.372554) (xy 58.203338 -289.373056)
			(xy 56.803798 -289.373056) (xy 56.793626 -289.372638) (xy 56.77483 -289.364851) (xy 56.760445 -289.350464)
			(xy 56.752661 -289.331667) (xy 56.752236 -289.321494) (xy 50.7111 -289.321494) (xy 50.710563 -289.331647)
			(xy 50.702797 -289.350408) (xy 50.688445 -289.364773) (xy 50.66969 -289.372554) (xy 50.659538 -289.373056)
			(xy 49.259998 -289.373056) (xy 49.249826 -289.372638) (xy 49.23103 -289.364851) (xy 49.216645 -289.350464)
			(xy 49.208861 -289.331667) (xy 49.208436 -289.321494) (xy 43.1673 -289.321494) (xy 43.166763 -289.331647)
			(xy 43.158997 -289.350408) (xy 43.144645 -289.364773) (xy 43.12589 -289.372554) (xy 43.115738 -289.373056)
			(xy 41.716198 -289.373056) (xy 41.706026 -289.372638) (xy 41.68723 -289.364851) (xy 41.672845 -289.350464)
			(xy 41.665061 -289.331667) (xy 41.664636 -289.321494) (xy 35.6235 -289.321494) (xy 35.622963 -289.331647)
			(xy 35.615197 -289.350408) (xy 35.600845 -289.364773) (xy 35.58209 -289.372554) (xy 35.571938 -289.373056)
			(xy 34.172398 -289.373056) (xy 34.162226 -289.372638) (xy 34.14343 -289.364851) (xy 34.129045 -289.350464)
			(xy 34.121261 -289.331667) (xy 34.120836 -289.321494) (xy 28.0797 -289.321494) (xy 28.079163 -289.331647)
			(xy 28.071397 -289.350408) (xy 28.057045 -289.364773) (xy 28.03829 -289.372554) (xy 28.028138 -289.373056)
			(xy 26.628598 -289.373056) (xy 26.618426 -289.372638) (xy 26.59963 -289.364851) (xy 26.585245 -289.350464)
			(xy 26.577461 -289.331667) (xy 26.577036 -289.321494) (xy 20.5359 -289.321494) (xy 20.535363 -289.331647)
			(xy 20.527597 -289.350408) (xy 20.513245 -289.364773) (xy 20.49449 -289.372554) (xy 20.484338 -289.373056)
			(xy 19.084798 -289.373056) (xy 19.074626 -289.372638) (xy 19.05583 -289.364851) (xy 19.041445 -289.350464)
			(xy 19.033661 -289.331667) (xy 19.033236 -289.321494) (xy 12.9921 -289.321494) (xy 12.991563 -289.331647)
			(xy 12.983797 -289.350408) (xy 12.969445 -289.364773) (xy 12.95069 -289.372554) (xy 12.940538 -289.373056)
			(xy 11.540998 -289.373056) (xy 11.530826 -289.372638) (xy 11.51203 -289.364851) (xy 11.497645 -289.350464)
			(xy 11.489861 -289.331667) (xy 11.489436 -289.321494) (xy 2.509012 -289.321494) (xy 2.509012 -290.171378)
			(xy 7.389368 -290.171378) (xy 7.389368 -289.762438) (xy 7.389796 -289.752265) (xy 7.397574 -289.733466)
			(xy 7.411959 -289.719078) (xy 7.430757 -289.711297) (xy 7.44093 -289.710876) (xy 8.84047 -289.710876)
			(xy 8.850644 -289.711289) (xy 8.869446 -289.719072) (xy 8.883833 -289.733461) (xy 8.891612 -289.752264)
			(xy 8.892032 -289.762438) (xy 8.892032 -290.171378) (xy 14.933168 -290.171378) (xy 14.933168 -289.762438)
			(xy 14.933596 -289.752265) (xy 14.941374 -289.733466) (xy 14.955759 -289.719078) (xy 14.974557 -289.711297)
			(xy 14.98473 -289.710876) (xy 16.38427 -289.710876) (xy 16.394444 -289.711289) (xy 16.413246 -289.719072)
			(xy 16.427633 -289.733461) (xy 16.435412 -289.752264) (xy 16.435832 -289.762438) (xy 16.435832 -290.171378)
			(xy 22.476968 -290.171378) (xy 22.476968 -289.762438) (xy 22.477396 -289.752265) (xy 22.485174 -289.733466)
			(xy 22.499559 -289.719078) (xy 22.518357 -289.711297) (xy 22.52853 -289.710876) (xy 23.92807 -289.710876)
			(xy 23.938244 -289.711289) (xy 23.957046 -289.719072) (xy 23.971433 -289.733461) (xy 23.979212 -289.752264)
			(xy 23.979632 -289.762438) (xy 23.979632 -290.171378) (xy 30.020768 -290.171378) (xy 30.020768 -289.762438)
			(xy 30.021196 -289.752265) (xy 30.028974 -289.733466) (xy 30.043359 -289.719078) (xy 30.062157 -289.711297)
			(xy 30.07233 -289.710876) (xy 31.47187 -289.710876) (xy 31.482044 -289.711289) (xy 31.500846 -289.719072)
			(xy 31.515233 -289.733461) (xy 31.523012 -289.752264) (xy 31.523432 -289.762438) (xy 31.523432 -290.171378)
			(xy 37.564568 -290.171378) (xy 37.564568 -289.762438) (xy 37.564996 -289.752265) (xy 37.572774 -289.733466)
			(xy 37.587159 -289.719078) (xy 37.605957 -289.711297) (xy 37.61613 -289.710876) (xy 39.01567 -289.710876)
			(xy 39.025844 -289.711289) (xy 39.044646 -289.719072) (xy 39.059033 -289.733461) (xy 39.066812 -289.752264)
			(xy 39.067232 -289.762438) (xy 39.067232 -290.171378) (xy 45.108368 -290.171378) (xy 45.108368 -289.762438)
			(xy 45.108796 -289.752265) (xy 45.116574 -289.733466) (xy 45.130959 -289.719078) (xy 45.149757 -289.711297)
			(xy 45.15993 -289.710876) (xy 46.55947 -289.710876) (xy 46.569644 -289.711289) (xy 46.588446 -289.719072)
			(xy 46.602833 -289.733461) (xy 46.610612 -289.752264) (xy 46.611032 -289.762438) (xy 46.611032 -290.171378)
			(xy 52.652168 -290.171378) (xy 52.652168 -289.762438) (xy 52.652596 -289.752265) (xy 52.660374 -289.733466)
			(xy 52.674759 -289.719078) (xy 52.693557 -289.711297) (xy 52.70373 -289.710876) (xy 54.10327 -289.710876)
			(xy 54.113444 -289.711289) (xy 54.132246 -289.719072) (xy 54.146633 -289.733461) (xy 54.154412 -289.752264)
			(xy 54.154832 -289.762438) (xy 54.154832 -290.171378) (xy 60.195968 -290.171378) (xy 60.195968 -289.762438)
			(xy 60.196396 -289.752265) (xy 60.204174 -289.733466) (xy 60.218559 -289.719078) (xy 60.237357 -289.711297)
			(xy 60.24753 -289.710876) (xy 61.64707 -289.710876) (xy 61.657244 -289.711289) (xy 61.676046 -289.719072)
			(xy 61.690433 -289.733461) (xy 61.698212 -289.752264) (xy 61.698632 -289.762438) (xy 61.698632 -290.171378)
			(xy 158.062168 -290.171378) (xy 158.062168 -289.762438) (xy 158.062596 -289.752265) (xy 158.070374 -289.733466)
			(xy 158.084759 -289.719078) (xy 158.103557 -289.711297) (xy 158.11373 -289.710876) (xy 159.51327 -289.710876)
			(xy 159.523444 -289.711289) (xy 159.542246 -289.719072) (xy 159.556633 -289.733461) (xy 159.564412 -289.752264)
			(xy 159.564832 -289.762438) (xy 159.564832 -290.171378) (xy 165.605968 -290.171378) (xy 165.605968 -289.762438)
			(xy 165.606396 -289.752265) (xy 165.614174 -289.733466) (xy 165.628559 -289.719078) (xy 165.647357 -289.711297)
			(xy 165.65753 -289.710876) (xy 167.05707 -289.710876) (xy 167.067244 -289.711289) (xy 167.086046 -289.719072)
			(xy 167.100433 -289.733461) (xy 167.108212 -289.752264) (xy 167.108632 -289.762438) (xy 167.108632 -290.171378)
			(xy 173.149768 -290.171378) (xy 173.149768 -289.762438) (xy 173.150196 -289.752265) (xy 173.157974 -289.733466)
			(xy 173.172359 -289.719078) (xy 173.191157 -289.711297) (xy 173.20133 -289.710876) (xy 174.60087 -289.710876)
			(xy 174.611044 -289.711289) (xy 174.629846 -289.719072) (xy 174.644233 -289.733461) (xy 174.652012 -289.752264)
			(xy 174.652432 -289.762438) (xy 174.652432 -290.171378) (xy 180.693568 -290.171378) (xy 180.693568 -289.762438)
			(xy 180.693996 -289.752265) (xy 180.701774 -289.733466) (xy 180.716159 -289.719078) (xy 180.734957 -289.711297)
			(xy 180.74513 -289.710876) (xy 182.14467 -289.710876) (xy 182.154844 -289.711289) (xy 182.173646 -289.719072)
			(xy 182.188033 -289.733461) (xy 182.195812 -289.752264) (xy 182.196232 -289.762438) (xy 182.196232 -290.171378)
			(xy 188.237368 -290.171378) (xy 188.237368 -289.762438) (xy 188.237796 -289.752265) (xy 188.245574 -289.733466)
			(xy 188.259959 -289.719078) (xy 188.278757 -289.711297) (xy 188.28893 -289.710876) (xy 189.68847 -289.710876)
			(xy 189.698644 -289.711289) (xy 189.717446 -289.719072) (xy 189.731833 -289.733461) (xy 189.739612 -289.752264)
			(xy 189.740032 -289.762438) (xy 189.740032 -290.171378) (xy 195.781168 -290.171378) (xy 195.781168 -289.762438)
			(xy 195.781596 -289.752265) (xy 195.789374 -289.733466) (xy 195.803759 -289.719078) (xy 195.822557 -289.711297)
			(xy 195.83273 -289.710876) (xy 197.23227 -289.710876) (xy 197.242444 -289.711289) (xy 197.261246 -289.719072)
			(xy 197.275633 -289.733461) (xy 197.283412 -289.752264) (xy 197.283832 -289.762438) (xy 197.283832 -290.171378)
			(xy 203.324968 -290.171378) (xy 203.324968 -289.762438) (xy 203.325396 -289.752265) (xy 203.333174 -289.733466)
			(xy 203.347559 -289.719078) (xy 203.366357 -289.711297) (xy 203.37653 -289.710876) (xy 204.77607 -289.710876)
			(xy 204.786244 -289.711289) (xy 204.805046 -289.719072) (xy 204.819433 -289.733461) (xy 204.827212 -289.752264)
			(xy 204.827632 -289.762438) (xy 204.827632 -290.171378) (xy 210.868768 -290.171378) (xy 210.868768 -289.762438)
			(xy 210.869196 -289.752265) (xy 210.876974 -289.733466) (xy 210.891359 -289.719078) (xy 210.910157 -289.711297)
			(xy 210.92033 -289.710876) (xy 212.31987 -289.710876) (xy 212.330044 -289.711289) (xy 212.348846 -289.719072)
			(xy 212.363233 -289.733461) (xy 212.371012 -289.752264) (xy 212.371432 -289.762438) (xy 212.371432 -290.171378)
			(xy 255.329436 -290.171378) (xy 255.329436 -289.762438) (xy 255.329895 -289.752269) (xy 255.337667 -289.733476)
			(xy 255.352042 -289.71909) (xy 255.370829 -289.711303) (xy 255.380998 -289.710876) (xy 256.780538 -289.710876)
			(xy 256.790703 -289.711303) (xy 256.80948 -289.719097) (xy 256.823845 -289.733484) (xy 256.831612 -289.752272)
			(xy 256.8321 -289.762438) (xy 256.8321 -290.171378) (xy 262.873236 -290.171378) (xy 262.873236 -289.762438)
			(xy 262.873695 -289.752269) (xy 262.881467 -289.733476) (xy 262.895842 -289.71909) (xy 262.914629 -289.711303)
			(xy 262.924798 -289.710876) (xy 264.324338 -289.710876) (xy 264.334503 -289.711303) (xy 264.35328 -289.719097)
			(xy 264.367645 -289.733484) (xy 264.375412 -289.752272) (xy 264.3759 -289.762438) (xy 264.3759 -290.171378)
			(xy 270.417036 -290.171378) (xy 270.417036 -289.762438) (xy 270.417495 -289.752269) (xy 270.425267 -289.733476)
			(xy 270.439642 -289.71909) (xy 270.458429 -289.711303) (xy 270.468598 -289.710876) (xy 271.868138 -289.710876)
			(xy 271.878303 -289.711303) (xy 271.89708 -289.719097) (xy 271.911445 -289.733484) (xy 271.919212 -289.752272)
			(xy 271.9197 -289.762438) (xy 271.9197 -290.171378) (xy 277.960836 -290.171378) (xy 277.960836 -289.762438)
			(xy 277.961295 -289.752269) (xy 277.969067 -289.733476) (xy 277.983442 -289.71909) (xy 278.002229 -289.711303)
			(xy 278.012398 -289.710876) (xy 279.411938 -289.710876) (xy 279.422103 -289.711303) (xy 279.44088 -289.719097)
			(xy 279.455245 -289.733484) (xy 279.463012 -289.752272) (xy 279.4635 -289.762438) (xy 279.4635 -290.171378)
			(xy 285.504636 -290.171378) (xy 285.504636 -289.762438) (xy 285.505095 -289.752269) (xy 285.512867 -289.733476)
			(xy 285.527242 -289.71909) (xy 285.546029 -289.711303) (xy 285.556198 -289.710876) (xy 286.955738 -289.710876)
			(xy 286.965903 -289.711303) (xy 286.98468 -289.719097) (xy 286.999045 -289.733484) (xy 287.006812 -289.752272)
			(xy 287.0073 -289.762438) (xy 287.0073 -290.171378) (xy 293.048436 -290.171378) (xy 293.048436 -289.762438)
			(xy 293.048895 -289.752269) (xy 293.056667 -289.733476) (xy 293.071042 -289.71909) (xy 293.089829 -289.711303)
			(xy 293.099998 -289.710876) (xy 294.499538 -289.710876) (xy 294.509703 -289.711303) (xy 294.52848 -289.719097)
			(xy 294.542845 -289.733484) (xy 294.550612 -289.752272) (xy 294.5511 -289.762438) (xy 294.5511 -290.171378)
			(xy 300.592236 -290.171378) (xy 300.592236 -289.762438) (xy 300.592695 -289.752269) (xy 300.600467 -289.733476)
			(xy 300.614842 -289.71909) (xy 300.633629 -289.711303) (xy 300.643798 -289.710876) (xy 302.043338 -289.710876)
			(xy 302.053503 -289.711303) (xy 302.07228 -289.719097) (xy 302.086645 -289.733484) (xy 302.094412 -289.752272)
			(xy 302.0949 -289.762438) (xy 302.0949 -290.171378) (xy 308.136036 -290.171378) (xy 308.136036 -289.762438)
			(xy 308.136495 -289.752269) (xy 308.144267 -289.733476) (xy 308.158642 -289.71909) (xy 308.177429 -289.711303)
			(xy 308.187598 -289.710876) (xy 309.587138 -289.710876) (xy 309.597303 -289.711303) (xy 309.61608 -289.719097)
			(xy 309.630445 -289.733484) (xy 309.638212 -289.752272) (xy 309.6387 -289.762438) (xy 309.6387 -290.171378)
			(xy 406.002236 -290.171378) (xy 406.002236 -289.762438) (xy 406.002695 -289.752269) (xy 406.010467 -289.733476)
			(xy 406.024842 -289.71909) (xy 406.043629 -289.711303) (xy 406.053798 -289.710876) (xy 407.453338 -289.710876)
			(xy 407.463503 -289.711303) (xy 407.48228 -289.719097) (xy 407.496645 -289.733484) (xy 407.504412 -289.752272)
			(xy 407.5049 -289.762438) (xy 407.5049 -290.171378) (xy 413.546036 -290.171378) (xy 413.546036 -289.762438)
			(xy 413.546495 -289.752269) (xy 413.554267 -289.733476) (xy 413.568642 -289.71909) (xy 413.587429 -289.711303)
			(xy 413.597598 -289.710876) (xy 414.997138 -289.710876) (xy 415.007303 -289.711303) (xy 415.02608 -289.719097)
			(xy 415.040445 -289.733484) (xy 415.048212 -289.752272) (xy 415.0487 -289.762438) (xy 415.0487 -290.171378)
			(xy 421.089836 -290.171378) (xy 421.089836 -289.762438) (xy 421.090295 -289.752269) (xy 421.098067 -289.733476)
			(xy 421.112442 -289.71909) (xy 421.131229 -289.711303) (xy 421.141398 -289.710876) (xy 422.540938 -289.710876)
			(xy 422.551103 -289.711303) (xy 422.56988 -289.719097) (xy 422.584245 -289.733484) (xy 422.592012 -289.752272)
			(xy 422.5925 -289.762438) (xy 422.5925 -290.171378) (xy 428.633636 -290.171378) (xy 428.633636 -289.762438)
			(xy 428.634095 -289.752269) (xy 428.641867 -289.733476) (xy 428.656242 -289.71909) (xy 428.675029 -289.711303)
			(xy 428.685198 -289.710876) (xy 430.084738 -289.710876) (xy 430.094903 -289.711303) (xy 430.11368 -289.719097)
			(xy 430.128045 -289.733484) (xy 430.135812 -289.752272) (xy 430.1363 -289.762438) (xy 430.1363 -290.171378)
			(xy 436.177436 -290.171378) (xy 436.177436 -289.762438) (xy 436.177895 -289.752269) (xy 436.185667 -289.733476)
			(xy 436.200042 -289.71909) (xy 436.218829 -289.711303) (xy 436.228998 -289.710876) (xy 437.628538 -289.710876)
			(xy 437.638703 -289.711303) (xy 437.65748 -289.719097) (xy 437.671845 -289.733484) (xy 437.679612 -289.752272)
			(xy 437.6801 -289.762438) (xy 437.6801 -290.171378) (xy 443.721236 -290.171378) (xy 443.721236 -289.762438)
			(xy 443.721695 -289.752269) (xy 443.729467 -289.733476) (xy 443.743842 -289.71909) (xy 443.762629 -289.711303)
			(xy 443.772798 -289.710876) (xy 445.172338 -289.710876) (xy 445.182503 -289.711303) (xy 445.20128 -289.719097)
			(xy 445.215645 -289.733484) (xy 445.223412 -289.752272) (xy 445.2239 -289.762438) (xy 445.2239 -290.171378)
			(xy 451.265036 -290.171378) (xy 451.265036 -289.762438) (xy 451.265495 -289.752269) (xy 451.273267 -289.733476)
			(xy 451.287642 -289.71909) (xy 451.306429 -289.711303) (xy 451.316598 -289.710876) (xy 452.716138 -289.710876)
			(xy 452.726303 -289.711303) (xy 452.74508 -289.719097) (xy 452.759445 -289.733484) (xy 452.767212 -289.752272)
			(xy 452.7677 -289.762438) (xy 452.7677 -290.171378) (xy 458.808836 -290.171378) (xy 458.808836 -289.762438)
			(xy 458.809295 -289.752269) (xy 458.817067 -289.733476) (xy 458.831442 -289.71909) (xy 458.850229 -289.711303)
			(xy 458.860398 -289.710876) (xy 460.259938 -289.710876) (xy 460.270103 -289.711303) (xy 460.28888 -289.719097)
			(xy 460.303245 -289.733484) (xy 460.311012 -289.752272) (xy 460.3115 -289.762438) (xy 460.3115 -290.171378)
			(xy 460.31095 -290.18153) (xy 460.30319 -290.200291) (xy 460.288842 -290.214656) (xy 460.270089 -290.222438)
			(xy 460.259938 -290.22294) (xy 458.860398 -290.22294) (xy 458.850224 -290.222537) (xy 458.831425 -290.214747)
			(xy 458.817039 -290.200355) (xy 458.809258 -290.181553) (xy 458.808836 -290.171378) (xy 452.7677 -290.171378)
			(xy 452.76715 -290.18153) (xy 452.75939 -290.200291) (xy 452.745042 -290.214656) (xy 452.726289 -290.222438)
			(xy 452.716138 -290.22294) (xy 451.316598 -290.22294) (xy 451.306424 -290.222537) (xy 451.287625 -290.214747)
			(xy 451.273239 -290.200355) (xy 451.265458 -290.181553) (xy 451.265036 -290.171378) (xy 445.2239 -290.171378)
			(xy 445.22335 -290.18153) (xy 445.21559 -290.200291) (xy 445.201242 -290.214656) (xy 445.182489 -290.222438)
			(xy 445.172338 -290.22294) (xy 443.772798 -290.22294) (xy 443.762624 -290.222537) (xy 443.743825 -290.214747)
			(xy 443.729439 -290.200355) (xy 443.721658 -290.181553) (xy 443.721236 -290.171378) (xy 437.6801 -290.171378)
			(xy 437.67955 -290.18153) (xy 437.67179 -290.200291) (xy 437.657442 -290.214656) (xy 437.638689 -290.222438)
			(xy 437.628538 -290.22294) (xy 436.228998 -290.22294) (xy 436.218824 -290.222537) (xy 436.200025 -290.214747)
			(xy 436.185639 -290.200355) (xy 436.177858 -290.181553) (xy 436.177436 -290.171378) (xy 430.1363 -290.171378)
			(xy 430.13575 -290.18153) (xy 430.12799 -290.200291) (xy 430.113642 -290.214656) (xy 430.094889 -290.222438)
			(xy 430.084738 -290.22294) (xy 428.685198 -290.22294) (xy 428.675024 -290.222537) (xy 428.656225 -290.214747)
			(xy 428.641839 -290.200355) (xy 428.634058 -290.181553) (xy 428.633636 -290.171378) (xy 422.5925 -290.171378)
			(xy 422.59195 -290.18153) (xy 422.58419 -290.200291) (xy 422.569842 -290.214656) (xy 422.551089 -290.222438)
			(xy 422.540938 -290.22294) (xy 421.141398 -290.22294) (xy 421.131224 -290.222537) (xy 421.112425 -290.214747)
			(xy 421.098039 -290.200355) (xy 421.090258 -290.181553) (xy 421.089836 -290.171378) (xy 415.0487 -290.171378)
			(xy 415.04815 -290.18153) (xy 415.04039 -290.200291) (xy 415.026042 -290.214656) (xy 415.007289 -290.222438)
			(xy 414.997138 -290.22294) (xy 413.597598 -290.22294) (xy 413.587424 -290.222537) (xy 413.568625 -290.214747)
			(xy 413.554239 -290.200355) (xy 413.546458 -290.181553) (xy 413.546036 -290.171378) (xy 407.5049 -290.171378)
			(xy 407.50435 -290.18153) (xy 407.49659 -290.200291) (xy 407.482242 -290.214656) (xy 407.463489 -290.222438)
			(xy 407.453338 -290.22294) (xy 406.053798 -290.22294) (xy 406.043624 -290.222537) (xy 406.024825 -290.214747)
			(xy 406.010439 -290.200355) (xy 406.002658 -290.181553) (xy 406.002236 -290.171378) (xy 309.6387 -290.171378)
			(xy 309.63815 -290.18153) (xy 309.63039 -290.200291) (xy 309.616042 -290.214656) (xy 309.597289 -290.222438)
			(xy 309.587138 -290.22294) (xy 308.187598 -290.22294) (xy 308.177424 -290.222537) (xy 308.158625 -290.214747)
			(xy 308.144239 -290.200355) (xy 308.136458 -290.181553) (xy 308.136036 -290.171378) (xy 302.0949 -290.171378)
			(xy 302.09435 -290.18153) (xy 302.08659 -290.200291) (xy 302.072242 -290.214656) (xy 302.053489 -290.222438)
			(xy 302.043338 -290.22294) (xy 300.643798 -290.22294) (xy 300.633624 -290.222537) (xy 300.614825 -290.214747)
			(xy 300.600439 -290.200355) (xy 300.592658 -290.181553) (xy 300.592236 -290.171378) (xy 294.5511 -290.171378)
			(xy 294.55055 -290.18153) (xy 294.54279 -290.200291) (xy 294.528442 -290.214656) (xy 294.509689 -290.222438)
			(xy 294.499538 -290.22294) (xy 293.099998 -290.22294) (xy 293.089824 -290.222537) (xy 293.071025 -290.214747)
			(xy 293.056639 -290.200355) (xy 293.048858 -290.181553) (xy 293.048436 -290.171378) (xy 287.0073 -290.171378)
			(xy 287.00675 -290.18153) (xy 286.99899 -290.200291) (xy 286.984642 -290.214656) (xy 286.965889 -290.222438)
			(xy 286.955738 -290.22294) (xy 285.556198 -290.22294) (xy 285.546024 -290.222537) (xy 285.527225 -290.214747)
			(xy 285.512839 -290.200355) (xy 285.505058 -290.181553) (xy 285.504636 -290.171378) (xy 279.4635 -290.171378)
			(xy 279.46295 -290.18153) (xy 279.45519 -290.200291) (xy 279.440842 -290.214656) (xy 279.422089 -290.222438)
			(xy 279.411938 -290.22294) (xy 278.012398 -290.22294) (xy 278.002224 -290.222537) (xy 277.983425 -290.214747)
			(xy 277.969039 -290.200355) (xy 277.961258 -290.181553) (xy 277.960836 -290.171378) (xy 271.9197 -290.171378)
			(xy 271.91915 -290.18153) (xy 271.91139 -290.200291) (xy 271.897042 -290.214656) (xy 271.878289 -290.222438)
			(xy 271.868138 -290.22294) (xy 270.468598 -290.22294) (xy 270.458424 -290.222537) (xy 270.439625 -290.214747)
			(xy 270.425239 -290.200355) (xy 270.417458 -290.181553) (xy 270.417036 -290.171378) (xy 264.3759 -290.171378)
			(xy 264.37535 -290.18153) (xy 264.36759 -290.200291) (xy 264.353242 -290.214656) (xy 264.334489 -290.222438)
			(xy 264.324338 -290.22294) (xy 262.924798 -290.22294) (xy 262.914624 -290.222537) (xy 262.895825 -290.214747)
			(xy 262.881439 -290.200355) (xy 262.873658 -290.181553) (xy 262.873236 -290.171378) (xy 256.8321 -290.171378)
			(xy 256.83155 -290.18153) (xy 256.82379 -290.200291) (xy 256.809442 -290.214656) (xy 256.790689 -290.222438)
			(xy 256.780538 -290.22294) (xy 255.380998 -290.22294) (xy 255.370824 -290.222537) (xy 255.352025 -290.214747)
			(xy 255.337639 -290.200355) (xy 255.329858 -290.181553) (xy 255.329436 -290.171378) (xy 212.371432 -290.171378)
			(xy 212.371017 -290.181552) (xy 212.363234 -290.200352) (xy 212.348845 -290.214738) (xy 212.330044 -290.222519)
			(xy 212.31987 -290.22294) (xy 210.92033 -290.22294) (xy 210.910158 -290.222511) (xy 210.891359 -290.214732)
			(xy 210.876973 -290.200347) (xy 210.869191 -290.18155) (xy 210.868768 -290.171378) (xy 204.827632 -290.171378)
			(xy 204.827217 -290.181552) (xy 204.819434 -290.200352) (xy 204.805045 -290.214738) (xy 204.786244 -290.222519)
			(xy 204.77607 -290.22294) (xy 203.37653 -290.22294) (xy 203.366358 -290.222511) (xy 203.347559 -290.214732)
			(xy 203.333173 -290.200347) (xy 203.325391 -290.18155) (xy 203.324968 -290.171378) (xy 197.283832 -290.171378)
			(xy 197.283417 -290.181552) (xy 197.275634 -290.200352) (xy 197.261245 -290.214738) (xy 197.242444 -290.222519)
			(xy 197.23227 -290.22294) (xy 195.83273 -290.22294) (xy 195.822558 -290.222511) (xy 195.803759 -290.214732)
			(xy 195.789373 -290.200347) (xy 195.781591 -290.18155) (xy 195.781168 -290.171378) (xy 189.740032 -290.171378)
			(xy 189.739617 -290.181552) (xy 189.731834 -290.200352) (xy 189.717445 -290.214738) (xy 189.698644 -290.222519)
			(xy 189.68847 -290.22294) (xy 188.28893 -290.22294) (xy 188.278758 -290.222511) (xy 188.259959 -290.214732)
			(xy 188.245573 -290.200347) (xy 188.237791 -290.18155) (xy 188.237368 -290.171378) (xy 182.196232 -290.171378)
			(xy 182.195817 -290.181552) (xy 182.188034 -290.200352) (xy 182.173645 -290.214738) (xy 182.154844 -290.222519)
			(xy 182.14467 -290.22294) (xy 180.74513 -290.22294) (xy 180.734958 -290.222511) (xy 180.716159 -290.214732)
			(xy 180.701773 -290.200347) (xy 180.693991 -290.18155) (xy 180.693568 -290.171378) (xy 174.652432 -290.171378)
			(xy 174.652017 -290.181552) (xy 174.644234 -290.200352) (xy 174.629845 -290.214738) (xy 174.611044 -290.222519)
			(xy 174.60087 -290.22294) (xy 173.20133 -290.22294) (xy 173.191158 -290.222511) (xy 173.172359 -290.214732)
			(xy 173.157973 -290.200347) (xy 173.150191 -290.18155) (xy 173.149768 -290.171378) (xy 167.108632 -290.171378)
			(xy 167.108217 -290.181552) (xy 167.100434 -290.200352) (xy 167.086045 -290.214738) (xy 167.067244 -290.222519)
			(xy 167.05707 -290.22294) (xy 165.65753 -290.22294) (xy 165.647358 -290.222511) (xy 165.628559 -290.214732)
			(xy 165.614173 -290.200347) (xy 165.606391 -290.18155) (xy 165.605968 -290.171378) (xy 159.564832 -290.171378)
			(xy 159.564417 -290.181552) (xy 159.556634 -290.200352) (xy 159.542245 -290.214738) (xy 159.523444 -290.222519)
			(xy 159.51327 -290.22294) (xy 158.11373 -290.22294) (xy 158.103558 -290.222511) (xy 158.084759 -290.214732)
			(xy 158.070373 -290.200347) (xy 158.062591 -290.18155) (xy 158.062168 -290.171378) (xy 61.698632 -290.171378)
			(xy 61.698217 -290.181552) (xy 61.690434 -290.200352) (xy 61.676045 -290.214738) (xy 61.657244 -290.222519)
			(xy 61.64707 -290.22294) (xy 60.24753 -290.22294) (xy 60.237358 -290.222511) (xy 60.218559 -290.214732)
			(xy 60.204173 -290.200347) (xy 60.196391 -290.18155) (xy 60.195968 -290.171378) (xy 54.154832 -290.171378)
			(xy 54.154417 -290.181552) (xy 54.146634 -290.200352) (xy 54.132245 -290.214738) (xy 54.113444 -290.222519)
			(xy 54.10327 -290.22294) (xy 52.70373 -290.22294) (xy 52.693558 -290.222511) (xy 52.674759 -290.214732)
			(xy 52.660373 -290.200347) (xy 52.652591 -290.18155) (xy 52.652168 -290.171378) (xy 46.611032 -290.171378)
			(xy 46.610617 -290.181552) (xy 46.602834 -290.200352) (xy 46.588445 -290.214738) (xy 46.569644 -290.222519)
			(xy 46.55947 -290.22294) (xy 45.15993 -290.22294) (xy 45.149758 -290.222511) (xy 45.130959 -290.214732)
			(xy 45.116573 -290.200347) (xy 45.108791 -290.18155) (xy 45.108368 -290.171378) (xy 39.067232 -290.171378)
			(xy 39.066817 -290.181552) (xy 39.059034 -290.200352) (xy 39.044645 -290.214738) (xy 39.025844 -290.222519)
			(xy 39.01567 -290.22294) (xy 37.61613 -290.22294) (xy 37.605958 -290.222511) (xy 37.587159 -290.214732)
			(xy 37.572773 -290.200347) (xy 37.564991 -290.18155) (xy 37.564568 -290.171378) (xy 31.523432 -290.171378)
			(xy 31.523017 -290.181552) (xy 31.515234 -290.200352) (xy 31.500845 -290.214738) (xy 31.482044 -290.222519)
			(xy 31.47187 -290.22294) (xy 30.07233 -290.22294) (xy 30.062158 -290.222511) (xy 30.043359 -290.214732)
			(xy 30.028973 -290.200347) (xy 30.021191 -290.18155) (xy 30.020768 -290.171378) (xy 23.979632 -290.171378)
			(xy 23.979217 -290.181552) (xy 23.971434 -290.200352) (xy 23.957045 -290.214738) (xy 23.938244 -290.222519)
			(xy 23.92807 -290.22294) (xy 22.52853 -290.22294) (xy 22.518358 -290.222511) (xy 22.499559 -290.214732)
			(xy 22.485173 -290.200347) (xy 22.477391 -290.18155) (xy 22.476968 -290.171378) (xy 16.435832 -290.171378)
			(xy 16.435417 -290.181552) (xy 16.427634 -290.200352) (xy 16.413245 -290.214738) (xy 16.394444 -290.222519)
			(xy 16.38427 -290.22294) (xy 14.98473 -290.22294) (xy 14.974558 -290.222511) (xy 14.955759 -290.214732)
			(xy 14.941373 -290.200347) (xy 14.933591 -290.18155) (xy 14.933168 -290.171378) (xy 8.892032 -290.171378)
			(xy 8.891617 -290.181552) (xy 8.883834 -290.200352) (xy 8.869445 -290.214738) (xy 8.850644 -290.222519)
			(xy 8.84047 -290.22294) (xy 7.44093 -290.22294) (xy 7.430758 -290.222511) (xy 7.411959 -290.214732)
			(xy 7.397573 -290.200347) (xy 7.389791 -290.18155) (xy 7.389368 -290.171378) (xy 2.509012 -290.171378)
			(xy 2.509012 -291.021516) (xy 11.489436 -291.021516) (xy 11.489436 -290.612576) (xy 11.489803 -290.602416)
			(xy 11.497613 -290.583656) (xy 11.512027 -290.569332) (xy 11.530835 -290.56164) (xy 11.540998 -290.561268)
			(xy 12.940538 -290.561268) (xy 12.950671 -290.561696) (xy 12.969398 -290.569442) (xy 12.983754 -290.583746)
			(xy 12.991567 -290.602445) (xy 12.9921 -290.612576) (xy 12.9921 -291.021516) (xy 19.033236 -291.021516)
			(xy 19.033236 -290.612576) (xy 19.033603 -290.602416) (xy 19.041413 -290.583656) (xy 19.055827 -290.569332)
			(xy 19.074635 -290.56164) (xy 19.084798 -290.561268) (xy 20.484338 -290.561268) (xy 20.494471 -290.561696)
			(xy 20.513198 -290.569442) (xy 20.527554 -290.583746) (xy 20.535367 -290.602445) (xy 20.5359 -290.612576)
			(xy 20.5359 -291.021516) (xy 26.577036 -291.021516) (xy 26.577036 -290.612576) (xy 26.577403 -290.602416)
			(xy 26.585213 -290.583656) (xy 26.599627 -290.569332) (xy 26.618435 -290.56164) (xy 26.628598 -290.561268)
			(xy 28.028138 -290.561268) (xy 28.038271 -290.561696) (xy 28.056998 -290.569442) (xy 28.071354 -290.583746)
			(xy 28.079167 -290.602445) (xy 28.0797 -290.612576) (xy 28.0797 -291.021516) (xy 34.120836 -291.021516)
			(xy 34.120836 -290.612576) (xy 34.121203 -290.602416) (xy 34.129013 -290.583656) (xy 34.143427 -290.569332)
			(xy 34.162235 -290.56164) (xy 34.172398 -290.561268) (xy 35.571938 -290.561268) (xy 35.582071 -290.561696)
			(xy 35.600798 -290.569442) (xy 35.615154 -290.583746) (xy 35.622967 -290.602445) (xy 35.6235 -290.612576)
			(xy 35.6235 -291.021516) (xy 41.664636 -291.021516) (xy 41.664636 -290.612576) (xy 41.665003 -290.602416)
			(xy 41.672813 -290.583656) (xy 41.687227 -290.569332) (xy 41.706035 -290.56164) (xy 41.716198 -290.561268)
			(xy 43.115738 -290.561268) (xy 43.125871 -290.561696) (xy 43.144598 -290.569442) (xy 43.158954 -290.583746)
			(xy 43.166767 -290.602445) (xy 43.1673 -290.612576) (xy 43.1673 -291.021516) (xy 49.208436 -291.021516)
			(xy 49.208436 -290.612576) (xy 49.208803 -290.602416) (xy 49.216613 -290.583656) (xy 49.231027 -290.569332)
			(xy 49.249835 -290.56164) (xy 49.259998 -290.561268) (xy 50.659538 -290.561268) (xy 50.669671 -290.561696)
			(xy 50.688398 -290.569442) (xy 50.702754 -290.583746) (xy 50.710567 -290.602445) (xy 50.7111 -290.612576)
			(xy 50.7111 -291.021516) (xy 56.752236 -291.021516) (xy 56.752236 -290.612576) (xy 56.752603 -290.602416)
			(xy 56.760413 -290.583656) (xy 56.774827 -290.569332) (xy 56.793635 -290.56164) (xy 56.803798 -290.561268)
			(xy 58.203338 -290.561268) (xy 58.213471 -290.561696) (xy 58.232198 -290.569442) (xy 58.246554 -290.583746)
			(xy 58.254367 -290.602445) (xy 58.2549 -290.612576) (xy 58.2549 -291.021516) (xy 64.296036 -291.021516)
			(xy 64.296036 -290.612576) (xy 64.296403 -290.602416) (xy 64.304213 -290.583656) (xy 64.318627 -290.569332)
			(xy 64.337435 -290.56164) (xy 64.347598 -290.561268) (xy 65.747138 -290.561268) (xy 65.757271 -290.561696)
			(xy 65.775998 -290.569442) (xy 65.790354 -290.583746) (xy 65.798167 -290.602445) (xy 65.7987 -290.612576)
			(xy 65.7987 -291.021516) (xy 162.162236 -291.021516) (xy 162.162236 -290.612576) (xy 162.162603 -290.602416)
			(xy 162.170413 -290.583656) (xy 162.184827 -290.569332) (xy 162.203635 -290.56164) (xy 162.213798 -290.561268)
			(xy 163.613338 -290.561268) (xy 163.623471 -290.561696) (xy 163.642198 -290.569442) (xy 163.656554 -290.583746)
			(xy 163.664367 -290.602445) (xy 163.6649 -290.612576) (xy 163.6649 -291.021516) (xy 169.706036 -291.021516)
			(xy 169.706036 -290.612576) (xy 169.706403 -290.602416) (xy 169.714213 -290.583656) (xy 169.728627 -290.569332)
			(xy 169.747435 -290.56164) (xy 169.757598 -290.561268) (xy 171.157138 -290.561268) (xy 171.167271 -290.561696)
			(xy 171.185998 -290.569442) (xy 171.200354 -290.583746) (xy 171.208167 -290.602445) (xy 171.2087 -290.612576)
			(xy 171.2087 -291.021516) (xy 177.249836 -291.021516) (xy 177.249836 -290.612576) (xy 177.250203 -290.602416)
			(xy 177.258013 -290.583656) (xy 177.272427 -290.569332) (xy 177.291235 -290.56164) (xy 177.301398 -290.561268)
			(xy 178.700938 -290.561268) (xy 178.711071 -290.561696) (xy 178.729798 -290.569442) (xy 178.744154 -290.583746)
			(xy 178.751967 -290.602445) (xy 178.7525 -290.612576) (xy 178.7525 -291.021516) (xy 184.793636 -291.021516)
			(xy 184.793636 -290.612576) (xy 184.794003 -290.602416) (xy 184.801813 -290.583656) (xy 184.816227 -290.569332)
			(xy 184.835035 -290.56164) (xy 184.845198 -290.561268) (xy 186.244738 -290.561268) (xy 186.254871 -290.561696)
			(xy 186.273598 -290.569442) (xy 186.287954 -290.583746) (xy 186.295767 -290.602445) (xy 186.2963 -290.612576)
			(xy 186.2963 -291.021516) (xy 192.337436 -291.021516) (xy 192.337436 -290.612576) (xy 192.337803 -290.602416)
			(xy 192.345613 -290.583656) (xy 192.360027 -290.569332) (xy 192.378835 -290.56164) (xy 192.388998 -290.561268)
			(xy 193.788538 -290.561268) (xy 193.798671 -290.561696) (xy 193.817398 -290.569442) (xy 193.831754 -290.583746)
			(xy 193.839567 -290.602445) (xy 193.8401 -290.612576) (xy 193.8401 -291.021516) (xy 199.881236 -291.021516)
			(xy 199.881236 -290.612576) (xy 199.881603 -290.602416) (xy 199.889413 -290.583656) (xy 199.903827 -290.569332)
			(xy 199.922635 -290.56164) (xy 199.932798 -290.561268) (xy 201.332338 -290.561268) (xy 201.342471 -290.561696)
			(xy 201.361198 -290.569442) (xy 201.375554 -290.583746) (xy 201.383367 -290.602445) (xy 201.3839 -290.612576)
			(xy 201.3839 -291.021516) (xy 207.425036 -291.021516) (xy 207.425036 -290.612576) (xy 207.425403 -290.602416)
			(xy 207.433213 -290.583656) (xy 207.447627 -290.569332) (xy 207.466435 -290.56164) (xy 207.476598 -290.561268)
			(xy 208.876138 -290.561268) (xy 208.886271 -290.561696) (xy 208.904998 -290.569442) (xy 208.919354 -290.583746)
			(xy 208.927167 -290.602445) (xy 208.9277 -290.612576) (xy 208.9277 -291.021516) (xy 214.968836 -291.021516)
			(xy 214.968836 -290.612576) (xy 214.969203 -290.602416) (xy 214.977013 -290.583656) (xy 214.991427 -290.569332)
			(xy 215.010235 -290.56164) (xy 215.020398 -290.561268) (xy 216.419938 -290.561268) (xy 216.430071 -290.561696)
			(xy 216.448798 -290.569442) (xy 216.463154 -290.583746) (xy 216.470967 -290.602445) (xy 216.4715 -290.612576)
			(xy 216.4715 -291.021516) (xy 259.429504 -291.021516) (xy 259.429504 -290.612576) (xy 259.429902 -290.60242)
			(xy 259.437706 -290.583666) (xy 259.45211 -290.569343) (xy 259.470908 -290.561645) (xy 259.481066 -290.561268)
			(xy 260.880606 -290.561268) (xy 260.890737 -290.561723) (xy 260.909463 -290.569458) (xy 260.92382 -290.583754)
			(xy 260.931634 -290.602448) (xy 260.932168 -290.612576) (xy 260.932168 -291.021516) (xy 266.973304 -291.021516)
			(xy 266.973304 -290.612576) (xy 266.973702 -290.60242) (xy 266.981506 -290.583666) (xy 266.99591 -290.569343)
			(xy 267.014708 -290.561645) (xy 267.024866 -290.561268) (xy 268.424406 -290.561268) (xy 268.434537 -290.561723)
			(xy 268.453263 -290.569458) (xy 268.46762 -290.583754) (xy 268.475434 -290.602448) (xy 268.475968 -290.612576)
			(xy 268.475968 -291.021516) (xy 274.517104 -291.021516) (xy 274.517104 -290.612576) (xy 274.517502 -290.60242)
			(xy 274.525306 -290.583666) (xy 274.53971 -290.569343) (xy 274.558508 -290.561645) (xy 274.568666 -290.561268)
			(xy 275.968206 -290.561268) (xy 275.978337 -290.561723) (xy 275.997063 -290.569458) (xy 276.01142 -290.583754)
			(xy 276.019234 -290.602448) (xy 276.019768 -290.612576) (xy 276.019768 -291.021516) (xy 282.060904 -291.021516)
			(xy 282.060904 -290.612576) (xy 282.061302 -290.60242) (xy 282.069106 -290.583666) (xy 282.08351 -290.569343)
			(xy 282.102308 -290.561645) (xy 282.112466 -290.561268) (xy 283.512006 -290.561268) (xy 283.522137 -290.561723)
			(xy 283.540863 -290.569458) (xy 283.55522 -290.583754) (xy 283.563034 -290.602448) (xy 283.563568 -290.612576)
			(xy 283.563568 -291.021516) (xy 289.604704 -291.021516) (xy 289.604704 -290.612576) (xy 289.605102 -290.60242)
			(xy 289.612906 -290.583666) (xy 289.62731 -290.569343) (xy 289.646108 -290.561645) (xy 289.656266 -290.561268)
			(xy 291.055806 -290.561268) (xy 291.065937 -290.561723) (xy 291.084663 -290.569458) (xy 291.09902 -290.583754)
			(xy 291.106834 -290.602448) (xy 291.107368 -290.612576) (xy 291.107368 -291.021516) (xy 297.148504 -291.021516)
			(xy 297.148504 -290.612576) (xy 297.148902 -290.60242) (xy 297.156706 -290.583666) (xy 297.17111 -290.569343)
			(xy 297.189908 -290.561645) (xy 297.200066 -290.561268) (xy 298.599606 -290.561268) (xy 298.609737 -290.561723)
			(xy 298.628463 -290.569458) (xy 298.64282 -290.583754) (xy 298.650634 -290.602448) (xy 298.651168 -290.612576)
			(xy 298.651168 -291.021516) (xy 304.692304 -291.021516) (xy 304.692304 -290.612576) (xy 304.692702 -290.60242)
			(xy 304.700506 -290.583666) (xy 304.71491 -290.569343) (xy 304.733708 -290.561645) (xy 304.743866 -290.561268)
			(xy 306.143406 -290.561268) (xy 306.153537 -290.561723) (xy 306.172263 -290.569458) (xy 306.18662 -290.583754)
			(xy 306.194434 -290.602448) (xy 306.194968 -290.612576) (xy 306.194968 -291.021516) (xy 312.236104 -291.021516)
			(xy 312.236104 -290.612576) (xy 312.236502 -290.60242) (xy 312.244306 -290.583666) (xy 312.25871 -290.569343)
			(xy 312.277508 -290.561645) (xy 312.287666 -290.561268) (xy 313.687206 -290.561268) (xy 313.697337 -290.561723)
			(xy 313.716063 -290.569458) (xy 313.73042 -290.583754) (xy 313.738234 -290.602448) (xy 313.738768 -290.612576)
			(xy 313.738768 -291.021516) (xy 410.102304 -291.021516) (xy 410.102304 -290.612576) (xy 410.102702 -290.60242)
			(xy 410.110506 -290.583666) (xy 410.12491 -290.569343) (xy 410.143708 -290.561645) (xy 410.153866 -290.561268)
			(xy 411.553406 -290.561268) (xy 411.563537 -290.561723) (xy 411.582263 -290.569458) (xy 411.59662 -290.583754)
			(xy 411.604434 -290.602448) (xy 411.604968 -290.612576) (xy 411.604968 -291.021516) (xy 417.646104 -291.021516)
			(xy 417.646104 -290.612576) (xy 417.646502 -290.60242) (xy 417.654306 -290.583666) (xy 417.66871 -290.569343)
			(xy 417.687508 -290.561645) (xy 417.697666 -290.561268) (xy 419.097206 -290.561268) (xy 419.107337 -290.561723)
			(xy 419.126063 -290.569458) (xy 419.14042 -290.583754) (xy 419.148234 -290.602448) (xy 419.148768 -290.612576)
			(xy 419.148768 -291.021516) (xy 425.189904 -291.021516) (xy 425.189904 -290.612576) (xy 425.190302 -290.60242)
			(xy 425.198106 -290.583666) (xy 425.21251 -290.569343) (xy 425.231308 -290.561645) (xy 425.241466 -290.561268)
			(xy 426.641006 -290.561268) (xy 426.651137 -290.561723) (xy 426.669863 -290.569458) (xy 426.68422 -290.583754)
			(xy 426.692034 -290.602448) (xy 426.692568 -290.612576) (xy 426.692568 -291.021516) (xy 432.733704 -291.021516)
			(xy 432.733704 -290.612576) (xy 432.734102 -290.60242) (xy 432.741906 -290.583666) (xy 432.75631 -290.569343)
			(xy 432.775108 -290.561645) (xy 432.785266 -290.561268) (xy 434.184806 -290.561268) (xy 434.194937 -290.561723)
			(xy 434.213663 -290.569458) (xy 434.22802 -290.583754) (xy 434.235834 -290.602448) (xy 434.236368 -290.612576)
			(xy 434.236368 -291.021516) (xy 440.277504 -291.021516) (xy 440.277504 -290.612576) (xy 440.277902 -290.60242)
			(xy 440.285706 -290.583666) (xy 440.30011 -290.569343) (xy 440.318908 -290.561645) (xy 440.329066 -290.561268)
			(xy 441.728606 -290.561268) (xy 441.738737 -290.561723) (xy 441.757463 -290.569458) (xy 441.77182 -290.583754)
			(xy 441.779634 -290.602448) (xy 441.780168 -290.612576) (xy 441.780168 -291.021516) (xy 447.821304 -291.021516)
			(xy 447.821304 -290.612576) (xy 447.821702 -290.60242) (xy 447.829506 -290.583666) (xy 447.84391 -290.569343)
			(xy 447.862708 -290.561645) (xy 447.872866 -290.561268) (xy 449.272406 -290.561268) (xy 449.282537 -290.561723)
			(xy 449.301263 -290.569458) (xy 449.31562 -290.583754) (xy 449.323434 -290.602448) (xy 449.323968 -290.612576)
			(xy 449.323968 -291.021516) (xy 455.365104 -291.021516) (xy 455.365104 -290.612576) (xy 455.365502 -290.60242)
			(xy 455.373306 -290.583666) (xy 455.38771 -290.569343) (xy 455.406508 -290.561645) (xy 455.416666 -290.561268)
			(xy 456.816206 -290.561268) (xy 456.826337 -290.561723) (xy 456.845063 -290.569458) (xy 456.85942 -290.583754)
			(xy 456.867234 -290.602448) (xy 456.867768 -290.612576) (xy 456.867768 -291.021516) (xy 462.908904 -291.021516)
			(xy 462.908904 -290.612576) (xy 462.909302 -290.60242) (xy 462.917106 -290.583666) (xy 462.93151 -290.569343)
			(xy 462.950308 -290.561645) (xy 462.960466 -290.561268) (xy 464.360006 -290.561268) (xy 464.370137 -290.561723)
			(xy 464.388863 -290.569458) (xy 464.40322 -290.583754) (xy 464.411034 -290.602448) (xy 464.411568 -290.612576)
			(xy 464.411568 -291.021516) (xy 464.411191 -291.031675) (xy 464.403384 -291.050434) (xy 464.388973 -291.064758)
			(xy 464.370168 -291.072452) (xy 464.360006 -291.072824) (xy 462.960466 -291.072824) (xy 462.950333 -291.0724)
			(xy 462.931604 -291.064655) (xy 462.917248 -291.050349) (xy 462.909436 -291.031647) (xy 462.908904 -291.021516)
			(xy 456.867768 -291.021516) (xy 456.867391 -291.031675) (xy 456.859584 -291.050434) (xy 456.845173 -291.064758)
			(xy 456.826368 -291.072452) (xy 456.816206 -291.072824) (xy 455.416666 -291.072824) (xy 455.406533 -291.0724)
			(xy 455.387804 -291.064655) (xy 455.373448 -291.050349) (xy 455.365636 -291.031647) (xy 455.365104 -291.021516)
			(xy 449.323968 -291.021516) (xy 449.323591 -291.031675) (xy 449.315784 -291.050434) (xy 449.301373 -291.064758)
			(xy 449.282568 -291.072452) (xy 449.272406 -291.072824) (xy 447.872866 -291.072824) (xy 447.862733 -291.0724)
			(xy 447.844004 -291.064655) (xy 447.829648 -291.050349) (xy 447.821836 -291.031647) (xy 447.821304 -291.021516)
			(xy 441.780168 -291.021516) (xy 441.779791 -291.031675) (xy 441.771984 -291.050434) (xy 441.757573 -291.064758)
			(xy 441.738768 -291.072452) (xy 441.728606 -291.072824) (xy 440.329066 -291.072824) (xy 440.318933 -291.0724)
			(xy 440.300204 -291.064655) (xy 440.285848 -291.050349) (xy 440.278036 -291.031647) (xy 440.277504 -291.021516)
			(xy 434.236368 -291.021516) (xy 434.235991 -291.031675) (xy 434.228184 -291.050434) (xy 434.213773 -291.064758)
			(xy 434.194968 -291.072452) (xy 434.184806 -291.072824) (xy 432.785266 -291.072824) (xy 432.775133 -291.0724)
			(xy 432.756404 -291.064655) (xy 432.742048 -291.050349) (xy 432.734236 -291.031647) (xy 432.733704 -291.021516)
			(xy 426.692568 -291.021516) (xy 426.692191 -291.031675) (xy 426.684384 -291.050434) (xy 426.669973 -291.064758)
			(xy 426.651168 -291.072452) (xy 426.641006 -291.072824) (xy 425.241466 -291.072824) (xy 425.231333 -291.0724)
			(xy 425.212604 -291.064655) (xy 425.198248 -291.050349) (xy 425.190436 -291.031647) (xy 425.189904 -291.021516)
			(xy 419.148768 -291.021516) (xy 419.148391 -291.031675) (xy 419.140584 -291.050434) (xy 419.126173 -291.064758)
			(xy 419.107368 -291.072452) (xy 419.097206 -291.072824) (xy 417.697666 -291.072824) (xy 417.687533 -291.0724)
			(xy 417.668804 -291.064655) (xy 417.654448 -291.050349) (xy 417.646636 -291.031647) (xy 417.646104 -291.021516)
			(xy 411.604968 -291.021516) (xy 411.604591 -291.031675) (xy 411.596784 -291.050434) (xy 411.582373 -291.064758)
			(xy 411.563568 -291.072452) (xy 411.553406 -291.072824) (xy 410.153866 -291.072824) (xy 410.143733 -291.0724)
			(xy 410.125004 -291.064655) (xy 410.110648 -291.050349) (xy 410.102836 -291.031647) (xy 410.102304 -291.021516)
			(xy 313.738768 -291.021516) (xy 313.738391 -291.031675) (xy 313.730584 -291.050434) (xy 313.716173 -291.064758)
			(xy 313.697368 -291.072452) (xy 313.687206 -291.072824) (xy 312.287666 -291.072824) (xy 312.277533 -291.0724)
			(xy 312.258804 -291.064655) (xy 312.244448 -291.050349) (xy 312.236636 -291.031647) (xy 312.236104 -291.021516)
			(xy 306.194968 -291.021516) (xy 306.194591 -291.031675) (xy 306.186784 -291.050434) (xy 306.172373 -291.064758)
			(xy 306.153568 -291.072452) (xy 306.143406 -291.072824) (xy 304.743866 -291.072824) (xy 304.733733 -291.0724)
			(xy 304.715004 -291.064655) (xy 304.700648 -291.050349) (xy 304.692836 -291.031647) (xy 304.692304 -291.021516)
			(xy 298.651168 -291.021516) (xy 298.650791 -291.031675) (xy 298.642984 -291.050434) (xy 298.628573 -291.064758)
			(xy 298.609768 -291.072452) (xy 298.599606 -291.072824) (xy 297.200066 -291.072824) (xy 297.189933 -291.0724)
			(xy 297.171204 -291.064655) (xy 297.156848 -291.050349) (xy 297.149036 -291.031647) (xy 297.148504 -291.021516)
			(xy 291.107368 -291.021516) (xy 291.106991 -291.031675) (xy 291.099184 -291.050434) (xy 291.084773 -291.064758)
			(xy 291.065968 -291.072452) (xy 291.055806 -291.072824) (xy 289.656266 -291.072824) (xy 289.646133 -291.0724)
			(xy 289.627404 -291.064655) (xy 289.613048 -291.050349) (xy 289.605236 -291.031647) (xy 289.604704 -291.021516)
			(xy 283.563568 -291.021516) (xy 283.563191 -291.031675) (xy 283.555384 -291.050434) (xy 283.540973 -291.064758)
			(xy 283.522168 -291.072452) (xy 283.512006 -291.072824) (xy 282.112466 -291.072824) (xy 282.102333 -291.0724)
			(xy 282.083604 -291.064655) (xy 282.069248 -291.050349) (xy 282.061436 -291.031647) (xy 282.060904 -291.021516)
			(xy 276.019768 -291.021516) (xy 276.019391 -291.031675) (xy 276.011584 -291.050434) (xy 275.997173 -291.064758)
			(xy 275.978368 -291.072452) (xy 275.968206 -291.072824) (xy 274.568666 -291.072824) (xy 274.558533 -291.0724)
			(xy 274.539804 -291.064655) (xy 274.525448 -291.050349) (xy 274.517636 -291.031647) (xy 274.517104 -291.021516)
			(xy 268.475968 -291.021516) (xy 268.475591 -291.031675) (xy 268.467784 -291.050434) (xy 268.453373 -291.064758)
			(xy 268.434568 -291.072452) (xy 268.424406 -291.072824) (xy 267.024866 -291.072824) (xy 267.014733 -291.0724)
			(xy 266.996004 -291.064655) (xy 266.981648 -291.050349) (xy 266.973836 -291.031647) (xy 266.973304 -291.021516)
			(xy 260.932168 -291.021516) (xy 260.931791 -291.031675) (xy 260.923984 -291.050434) (xy 260.909573 -291.064758)
			(xy 260.890768 -291.072452) (xy 260.880606 -291.072824) (xy 259.481066 -291.072824) (xy 259.470933 -291.0724)
			(xy 259.452204 -291.064655) (xy 259.437848 -291.050349) (xy 259.430036 -291.031647) (xy 259.429504 -291.021516)
			(xy 216.4715 -291.021516) (xy 216.471092 -291.031671) (xy 216.463291 -291.050424) (xy 216.44889 -291.064747)
			(xy 216.430095 -291.072446) (xy 216.419938 -291.072824) (xy 215.020398 -291.072824) (xy 215.010267 -291.072374)
			(xy 214.991539 -291.064639) (xy 214.977181 -291.050341) (xy 214.969369 -291.031645) (xy 214.968836 -291.021516)
			(xy 208.9277 -291.021516) (xy 208.927292 -291.031671) (xy 208.919491 -291.050424) (xy 208.90509 -291.064747)
			(xy 208.886295 -291.072446) (xy 208.876138 -291.072824) (xy 207.476598 -291.072824) (xy 207.466467 -291.072374)
			(xy 207.447739 -291.064639) (xy 207.433381 -291.050341) (xy 207.425569 -291.031645) (xy 207.425036 -291.021516)
			(xy 201.3839 -291.021516) (xy 201.383492 -291.031671) (xy 201.375691 -291.050424) (xy 201.36129 -291.064747)
			(xy 201.342495 -291.072446) (xy 201.332338 -291.072824) (xy 199.932798 -291.072824) (xy 199.922667 -291.072374)
			(xy 199.903939 -291.064639) (xy 199.889581 -291.050341) (xy 199.881769 -291.031645) (xy 199.881236 -291.021516)
			(xy 193.8401 -291.021516) (xy 193.839692 -291.031671) (xy 193.831891 -291.050424) (xy 193.81749 -291.064747)
			(xy 193.798695 -291.072446) (xy 193.788538 -291.072824) (xy 192.388998 -291.072824) (xy 192.378867 -291.072374)
			(xy 192.360139 -291.064639) (xy 192.345781 -291.050341) (xy 192.337969 -291.031645) (xy 192.337436 -291.021516)
			(xy 186.2963 -291.021516) (xy 186.295892 -291.031671) (xy 186.288091 -291.050424) (xy 186.27369 -291.064747)
			(xy 186.254895 -291.072446) (xy 186.244738 -291.072824) (xy 184.845198 -291.072824) (xy 184.835067 -291.072374)
			(xy 184.816339 -291.064639) (xy 184.801981 -291.050341) (xy 184.794169 -291.031645) (xy 184.793636 -291.021516)
			(xy 178.7525 -291.021516) (xy 178.752092 -291.031671) (xy 178.744291 -291.050424) (xy 178.72989 -291.064747)
			(xy 178.711095 -291.072446) (xy 178.700938 -291.072824) (xy 177.301398 -291.072824) (xy 177.291267 -291.072374)
			(xy 177.272539 -291.064639) (xy 177.258181 -291.050341) (xy 177.250369 -291.031645) (xy 177.249836 -291.021516)
			(xy 171.2087 -291.021516) (xy 171.208292 -291.031671) (xy 171.200491 -291.050424) (xy 171.18609 -291.064747)
			(xy 171.167295 -291.072446) (xy 171.157138 -291.072824) (xy 169.757598 -291.072824) (xy 169.747467 -291.072374)
			(xy 169.728739 -291.064639) (xy 169.714381 -291.050341) (xy 169.706569 -291.031645) (xy 169.706036 -291.021516)
			(xy 163.6649 -291.021516) (xy 163.664492 -291.031671) (xy 163.656691 -291.050424) (xy 163.64229 -291.064747)
			(xy 163.623495 -291.072446) (xy 163.613338 -291.072824) (xy 162.213798 -291.072824) (xy 162.203667 -291.072374)
			(xy 162.184939 -291.064639) (xy 162.170581 -291.050341) (xy 162.162769 -291.031645) (xy 162.162236 -291.021516)
			(xy 65.7987 -291.021516) (xy 65.798292 -291.031671) (xy 65.790491 -291.050424) (xy 65.77609 -291.064747)
			(xy 65.757295 -291.072446) (xy 65.747138 -291.072824) (xy 64.347598 -291.072824) (xy 64.337467 -291.072374)
			(xy 64.318739 -291.064639) (xy 64.304381 -291.050341) (xy 64.296569 -291.031645) (xy 64.296036 -291.021516)
			(xy 58.2549 -291.021516) (xy 58.254492 -291.031671) (xy 58.246691 -291.050424) (xy 58.23229 -291.064747)
			(xy 58.213495 -291.072446) (xy 58.203338 -291.072824) (xy 56.803798 -291.072824) (xy 56.793667 -291.072374)
			(xy 56.774939 -291.064639) (xy 56.760581 -291.050341) (xy 56.752769 -291.031645) (xy 56.752236 -291.021516)
			(xy 50.7111 -291.021516) (xy 50.710692 -291.031671) (xy 50.702891 -291.050424) (xy 50.68849 -291.064747)
			(xy 50.669695 -291.072446) (xy 50.659538 -291.072824) (xy 49.259998 -291.072824) (xy 49.249867 -291.072374)
			(xy 49.231139 -291.064639) (xy 49.216781 -291.050341) (xy 49.208969 -291.031645) (xy 49.208436 -291.021516)
			(xy 43.1673 -291.021516) (xy 43.166892 -291.031671) (xy 43.159091 -291.050424) (xy 43.14469 -291.064747)
			(xy 43.125895 -291.072446) (xy 43.115738 -291.072824) (xy 41.716198 -291.072824) (xy 41.706067 -291.072374)
			(xy 41.687339 -291.064639) (xy 41.672981 -291.050341) (xy 41.665169 -291.031645) (xy 41.664636 -291.021516)
			(xy 35.6235 -291.021516) (xy 35.623092 -291.031671) (xy 35.615291 -291.050424) (xy 35.60089 -291.064747)
			(xy 35.582095 -291.072446) (xy 35.571938 -291.072824) (xy 34.172398 -291.072824) (xy 34.162267 -291.072374)
			(xy 34.143539 -291.064639) (xy 34.129181 -291.050341) (xy 34.121369 -291.031645) (xy 34.120836 -291.021516)
			(xy 28.0797 -291.021516) (xy 28.079292 -291.031671) (xy 28.071491 -291.050424) (xy 28.05709 -291.064747)
			(xy 28.038295 -291.072446) (xy 28.028138 -291.072824) (xy 26.628598 -291.072824) (xy 26.618467 -291.072374)
			(xy 26.599739 -291.064639) (xy 26.585381 -291.050341) (xy 26.577569 -291.031645) (xy 26.577036 -291.021516)
			(xy 20.5359 -291.021516) (xy 20.535492 -291.031671) (xy 20.527691 -291.050424) (xy 20.51329 -291.064747)
			(xy 20.494495 -291.072446) (xy 20.484338 -291.072824) (xy 19.084798 -291.072824) (xy 19.074667 -291.072374)
			(xy 19.055939 -291.064639) (xy 19.041581 -291.050341) (xy 19.033769 -291.031645) (xy 19.033236 -291.021516)
			(xy 12.9921 -291.021516) (xy 12.991692 -291.031671) (xy 12.983891 -291.050424) (xy 12.96949 -291.064747)
			(xy 12.950695 -291.072446) (xy 12.940538 -291.072824) (xy 11.540998 -291.072824) (xy 11.530867 -291.072374)
			(xy 11.512139 -291.064639) (xy 11.497781 -291.050341) (xy 11.489969 -291.031645) (xy 11.489436 -291.021516)
			(xy 2.509012 -291.021516) (xy 2.509012 -291.8714) (xy 7.389368 -291.8714) (xy 7.389368 -291.46246)
			(xy 7.389788 -291.452307) (xy 7.397591 -291.43356) (xy 7.411987 -291.419239) (xy 7.430775 -291.411535)
			(xy 7.44093 -291.411152) (xy 8.84047 -291.411152) (xy 8.850596 -291.411651) (xy 8.869319 -291.419371)
			(xy 8.883677 -291.433654) (xy 8.891495 -291.452336) (xy 8.892032 -291.46246) (xy 8.892032 -291.8714)
			(xy 14.933168 -291.8714) (xy 14.933168 -291.46246) (xy 14.933588 -291.452307) (xy 14.941391 -291.43356)
			(xy 14.955787 -291.419239) (xy 14.974575 -291.411535) (xy 14.98473 -291.411152) (xy 16.38427 -291.411152)
			(xy 16.394396 -291.411651) (xy 16.413119 -291.419371) (xy 16.427477 -291.433654) (xy 16.435295 -291.452336)
			(xy 16.435832 -291.46246) (xy 16.435832 -291.8714) (xy 22.476968 -291.8714) (xy 22.476968 -291.46246)
			(xy 22.477388 -291.452307) (xy 22.485191 -291.43356) (xy 22.499587 -291.419239) (xy 22.518375 -291.411535)
			(xy 22.52853 -291.411152) (xy 23.92807 -291.411152) (xy 23.938196 -291.411651) (xy 23.956919 -291.419371)
			(xy 23.971277 -291.433654) (xy 23.979095 -291.452336) (xy 23.979632 -291.46246) (xy 23.979632 -291.8714)
			(xy 30.020768 -291.8714) (xy 30.020768 -291.46246) (xy 30.021188 -291.452307) (xy 30.028991 -291.43356)
			(xy 30.043387 -291.419239) (xy 30.062175 -291.411535) (xy 30.07233 -291.411152) (xy 31.47187 -291.411152)
			(xy 31.481996 -291.411651) (xy 31.500719 -291.419371) (xy 31.515077 -291.433654) (xy 31.522895 -291.452336)
			(xy 31.523432 -291.46246) (xy 31.523432 -291.8714) (xy 37.564568 -291.8714) (xy 37.564568 -291.46246)
			(xy 37.564988 -291.452307) (xy 37.572791 -291.43356) (xy 37.587187 -291.419239) (xy 37.605975 -291.411535)
			(xy 37.61613 -291.411152) (xy 39.01567 -291.411152) (xy 39.025796 -291.411651) (xy 39.044519 -291.419371)
			(xy 39.058877 -291.433654) (xy 39.066695 -291.452336) (xy 39.067232 -291.46246) (xy 39.067232 -291.8714)
			(xy 45.108368 -291.8714) (xy 45.108368 -291.46246) (xy 45.108788 -291.452307) (xy 45.116591 -291.43356)
			(xy 45.130987 -291.419239) (xy 45.149775 -291.411535) (xy 45.15993 -291.411152) (xy 46.55947 -291.411152)
			(xy 46.569596 -291.411651) (xy 46.588319 -291.419371) (xy 46.602677 -291.433654) (xy 46.610495 -291.452336)
			(xy 46.611032 -291.46246) (xy 46.611032 -291.8714) (xy 52.652168 -291.8714) (xy 52.652168 -291.46246)
			(xy 52.652588 -291.452307) (xy 52.660391 -291.43356) (xy 52.674787 -291.419239) (xy 52.693575 -291.411535)
			(xy 52.70373 -291.411152) (xy 54.10327 -291.411152) (xy 54.113396 -291.411651) (xy 54.132119 -291.419371)
			(xy 54.146477 -291.433654) (xy 54.154295 -291.452336) (xy 54.154832 -291.46246) (xy 54.154832 -291.8714)
			(xy 60.195968 -291.8714) (xy 60.195968 -291.46246) (xy 60.196388 -291.452307) (xy 60.204191 -291.43356)
			(xy 60.218587 -291.419239) (xy 60.237375 -291.411535) (xy 60.24753 -291.411152) (xy 61.64707 -291.411152)
			(xy 61.657196 -291.411651) (xy 61.675919 -291.419371) (xy 61.690277 -291.433654) (xy 61.698095 -291.452336)
			(xy 61.698632 -291.46246) (xy 61.698632 -291.8714) (xy 158.062168 -291.8714) (xy 158.062168 -291.46246)
			(xy 158.062588 -291.452307) (xy 158.070391 -291.43356) (xy 158.084787 -291.419239) (xy 158.103575 -291.411535)
			(xy 158.11373 -291.411152) (xy 159.51327 -291.411152) (xy 159.523396 -291.411651) (xy 159.542119 -291.419371)
			(xy 159.556477 -291.433654) (xy 159.564295 -291.452336) (xy 159.564832 -291.46246) (xy 159.564832 -291.8714)
			(xy 165.605968 -291.8714) (xy 165.605968 -291.46246) (xy 165.606388 -291.452307) (xy 165.614191 -291.43356)
			(xy 165.628587 -291.419239) (xy 165.647375 -291.411535) (xy 165.65753 -291.411152) (xy 167.05707 -291.411152)
			(xy 167.067196 -291.411651) (xy 167.085919 -291.419371) (xy 167.100277 -291.433654) (xy 167.108095 -291.452336)
			(xy 167.108632 -291.46246) (xy 167.108632 -291.8714) (xy 173.149768 -291.8714) (xy 173.149768 -291.46246)
			(xy 173.150188 -291.452307) (xy 173.157991 -291.43356) (xy 173.172387 -291.419239) (xy 173.191175 -291.411535)
			(xy 173.20133 -291.411152) (xy 174.60087 -291.411152) (xy 174.610996 -291.411651) (xy 174.629719 -291.419371)
			(xy 174.644077 -291.433654) (xy 174.651895 -291.452336) (xy 174.652432 -291.46246) (xy 174.652432 -291.8714)
			(xy 180.693568 -291.8714) (xy 180.693568 -291.46246) (xy 180.693988 -291.452307) (xy 180.701791 -291.43356)
			(xy 180.716187 -291.419239) (xy 180.734975 -291.411535) (xy 180.74513 -291.411152) (xy 182.14467 -291.411152)
			(xy 182.154796 -291.411651) (xy 182.173519 -291.419371) (xy 182.187877 -291.433654) (xy 182.195695 -291.452336)
			(xy 182.196232 -291.46246) (xy 182.196232 -291.8714) (xy 188.237368 -291.8714) (xy 188.237368 -291.46246)
			(xy 188.237788 -291.452307) (xy 188.245591 -291.43356) (xy 188.259987 -291.419239) (xy 188.278775 -291.411535)
			(xy 188.28893 -291.411152) (xy 189.68847 -291.411152) (xy 189.698596 -291.411651) (xy 189.717319 -291.419371)
			(xy 189.731677 -291.433654) (xy 189.739495 -291.452336) (xy 189.740032 -291.46246) (xy 189.740032 -291.8714)
			(xy 195.781168 -291.8714) (xy 195.781168 -291.46246) (xy 195.781588 -291.452307) (xy 195.789391 -291.43356)
			(xy 195.803787 -291.419239) (xy 195.822575 -291.411535) (xy 195.83273 -291.411152) (xy 197.23227 -291.411152)
			(xy 197.242396 -291.411651) (xy 197.261119 -291.419371) (xy 197.275477 -291.433654) (xy 197.283295 -291.452336)
			(xy 197.283832 -291.46246) (xy 197.283832 -291.8714) (xy 203.324968 -291.8714) (xy 203.324968 -291.46246)
			(xy 203.325388 -291.452307) (xy 203.333191 -291.43356) (xy 203.347587 -291.419239) (xy 203.366375 -291.411535)
			(xy 203.37653 -291.411152) (xy 204.77607 -291.411152) (xy 204.786196 -291.411651) (xy 204.804919 -291.419371)
			(xy 204.819277 -291.433654) (xy 204.827095 -291.452336) (xy 204.827632 -291.46246) (xy 204.827632 -291.8714)
			(xy 210.868768 -291.8714) (xy 210.868768 -291.46246) (xy 210.869188 -291.452307) (xy 210.876991 -291.43356)
			(xy 210.891387 -291.419239) (xy 210.910175 -291.411535) (xy 210.92033 -291.411152) (xy 212.31987 -291.411152)
			(xy 212.329996 -291.411651) (xy 212.348719 -291.419371) (xy 212.363077 -291.433654) (xy 212.370895 -291.452336)
			(xy 212.371432 -291.46246) (xy 212.371432 -291.8714) (xy 255.329436 -291.8714) (xy 255.329436 -291.46246)
			(xy 255.32979 -291.452299) (xy 255.337605 -291.433539) (xy 255.352023 -291.419215) (xy 255.370834 -291.411524)
			(xy 255.380998 -291.411152) (xy 256.780538 -291.411152) (xy 256.790669 -291.411596) (xy 256.809393 -291.419338)
			(xy 256.823748 -291.433638) (xy 256.831564 -291.452331) (xy 256.8321 -291.46246) (xy 256.8321 -291.8714)
			(xy 262.873236 -291.8714) (xy 262.873236 -291.46246) (xy 262.87359 -291.452299) (xy 262.881405 -291.433539)
			(xy 262.895823 -291.419215) (xy 262.914634 -291.411524) (xy 262.924798 -291.411152) (xy 264.324338 -291.411152)
			(xy 264.334469 -291.411596) (xy 264.353193 -291.419338) (xy 264.367548 -291.433638) (xy 264.375364 -291.452331)
			(xy 264.3759 -291.46246) (xy 264.3759 -291.8714) (xy 270.417036 -291.8714) (xy 270.417036 -291.46246)
			(xy 270.41739 -291.452299) (xy 270.425205 -291.433539) (xy 270.439623 -291.419215) (xy 270.458434 -291.411524)
			(xy 270.468598 -291.411152) (xy 271.868138 -291.411152) (xy 271.878269 -291.411596) (xy 271.896993 -291.419338)
			(xy 271.911348 -291.433638) (xy 271.919164 -291.452331) (xy 271.9197 -291.46246) (xy 271.9197 -291.8714)
			(xy 277.960836 -291.8714) (xy 277.960836 -291.46246) (xy 277.96119 -291.452299) (xy 277.969005 -291.433539)
			(xy 277.983423 -291.419215) (xy 278.002234 -291.411524) (xy 278.012398 -291.411152) (xy 279.411938 -291.411152)
			(xy 279.422069 -291.411596) (xy 279.440793 -291.419338) (xy 279.455148 -291.433638) (xy 279.462964 -291.452331)
			(xy 279.4635 -291.46246) (xy 279.4635 -291.8714) (xy 285.504636 -291.8714) (xy 285.504636 -291.46246)
			(xy 285.50499 -291.452299) (xy 285.512805 -291.433539) (xy 285.527223 -291.419215) (xy 285.546034 -291.411524)
			(xy 285.556198 -291.411152) (xy 286.955738 -291.411152) (xy 286.965869 -291.411596) (xy 286.984593 -291.419338)
			(xy 286.998948 -291.433638) (xy 287.006764 -291.452331) (xy 287.0073 -291.46246) (xy 287.0073 -291.8714)
			(xy 293.048436 -291.8714) (xy 293.048436 -291.46246) (xy 293.04879 -291.452299) (xy 293.056605 -291.433539)
			(xy 293.071023 -291.419215) (xy 293.089834 -291.411524) (xy 293.099998 -291.411152) (xy 294.499538 -291.411152)
			(xy 294.509669 -291.411596) (xy 294.528393 -291.419338) (xy 294.542748 -291.433638) (xy 294.550564 -291.452331)
			(xy 294.5511 -291.46246) (xy 294.5511 -291.8714) (xy 300.592236 -291.8714) (xy 300.592236 -291.46246)
			(xy 300.59259 -291.452299) (xy 300.600405 -291.433539) (xy 300.614823 -291.419215) (xy 300.633634 -291.411524)
			(xy 300.643798 -291.411152) (xy 302.043338 -291.411152) (xy 302.053469 -291.411596) (xy 302.072193 -291.419338)
			(xy 302.086548 -291.433638) (xy 302.094364 -291.452331) (xy 302.0949 -291.46246) (xy 302.0949 -291.8714)
			(xy 308.136036 -291.8714) (xy 308.136036 -291.46246) (xy 308.13639 -291.452299) (xy 308.144205 -291.433539)
			(xy 308.158623 -291.419215) (xy 308.177434 -291.411524) (xy 308.187598 -291.411152) (xy 309.587138 -291.411152)
			(xy 309.597269 -291.411596) (xy 309.615993 -291.419338) (xy 309.630348 -291.433638) (xy 309.638164 -291.452331)
			(xy 309.6387 -291.46246) (xy 309.6387 -291.8714) (xy 406.002236 -291.8714) (xy 406.002236 -291.46246)
			(xy 406.00259 -291.452299) (xy 406.010405 -291.433539) (xy 406.024823 -291.419215) (xy 406.043634 -291.411524)
			(xy 406.053798 -291.411152) (xy 407.453338 -291.411152) (xy 407.463469 -291.411596) (xy 407.482193 -291.419338)
			(xy 407.496548 -291.433638) (xy 407.504364 -291.452331) (xy 407.5049 -291.46246) (xy 407.5049 -291.8714)
			(xy 413.546036 -291.8714) (xy 413.546036 -291.46246) (xy 413.54639 -291.452299) (xy 413.554205 -291.433539)
			(xy 413.568623 -291.419215) (xy 413.587434 -291.411524) (xy 413.597598 -291.411152) (xy 414.997138 -291.411152)
			(xy 415.007269 -291.411596) (xy 415.025993 -291.419338) (xy 415.040348 -291.433638) (xy 415.048164 -291.452331)
			(xy 415.0487 -291.46246) (xy 415.0487 -291.8714) (xy 421.089836 -291.8714) (xy 421.089836 -291.46246)
			(xy 421.09019 -291.452299) (xy 421.098005 -291.433539) (xy 421.112423 -291.419215) (xy 421.131234 -291.411524)
			(xy 421.141398 -291.411152) (xy 422.540938 -291.411152) (xy 422.551069 -291.411596) (xy 422.569793 -291.419338)
			(xy 422.584148 -291.433638) (xy 422.591964 -291.452331) (xy 422.5925 -291.46246) (xy 422.5925 -291.8714)
			(xy 428.633636 -291.8714) (xy 428.633636 -291.46246) (xy 428.63399 -291.452299) (xy 428.641805 -291.433539)
			(xy 428.656223 -291.419215) (xy 428.675034 -291.411524) (xy 428.685198 -291.411152) (xy 430.084738 -291.411152)
			(xy 430.094869 -291.411596) (xy 430.113593 -291.419338) (xy 430.127948 -291.433638) (xy 430.135764 -291.452331)
			(xy 430.1363 -291.46246) (xy 430.1363 -291.8714) (xy 436.177436 -291.8714) (xy 436.177436 -291.46246)
			(xy 436.17779 -291.452299) (xy 436.185605 -291.433539) (xy 436.200023 -291.419215) (xy 436.218834 -291.411524)
			(xy 436.228998 -291.411152) (xy 437.628538 -291.411152) (xy 437.638669 -291.411596) (xy 437.657393 -291.419338)
			(xy 437.671748 -291.433638) (xy 437.679564 -291.452331) (xy 437.6801 -291.46246) (xy 437.6801 -291.8714)
			(xy 443.721236 -291.8714) (xy 443.721236 -291.46246) (xy 443.72159 -291.452299) (xy 443.729405 -291.433539)
			(xy 443.743823 -291.419215) (xy 443.762634 -291.411524) (xy 443.772798 -291.411152) (xy 445.172338 -291.411152)
			(xy 445.182469 -291.411596) (xy 445.201193 -291.419338) (xy 445.215548 -291.433638) (xy 445.223364 -291.452331)
			(xy 445.2239 -291.46246) (xy 445.2239 -291.8714) (xy 451.265036 -291.8714) (xy 451.265036 -291.46246)
			(xy 451.26539 -291.452299) (xy 451.273205 -291.433539) (xy 451.287623 -291.419215) (xy 451.306434 -291.411524)
			(xy 451.316598 -291.411152) (xy 452.716138 -291.411152) (xy 452.726269 -291.411596) (xy 452.744993 -291.419338)
			(xy 452.759348 -291.433638) (xy 452.767164 -291.452331) (xy 452.7677 -291.46246) (xy 452.7677 -291.8714)
			(xy 458.808836 -291.8714) (xy 458.808836 -291.46246) (xy 458.80919 -291.452299) (xy 458.817005 -291.433539)
			(xy 458.831423 -291.419215) (xy 458.850234 -291.411524) (xy 458.860398 -291.411152) (xy 460.259938 -291.411152)
			(xy 460.270069 -291.411596) (xy 460.288793 -291.419338) (xy 460.303148 -291.433638) (xy 460.310964 -291.452331)
			(xy 460.3115 -291.46246) (xy 460.3115 -291.8714) (xy 460.311078 -291.881554) (xy 460.303283 -291.900306)
			(xy 460.288886 -291.91463) (xy 460.270094 -291.922329) (xy 460.259938 -291.922708) (xy 458.860398 -291.922708)
			(xy 458.850277 -291.922176) (xy 458.831565 -291.914457) (xy 458.817211 -291.900185) (xy 458.809383 -291.881518)
			(xy 458.808836 -291.8714) (xy 452.7677 -291.8714) (xy 452.767278 -291.881554) (xy 452.759483 -291.900306)
			(xy 452.745086 -291.91463) (xy 452.726294 -291.922329) (xy 452.716138 -291.922708) (xy 451.316598 -291.922708)
			(xy 451.306477 -291.922176) (xy 451.287765 -291.914457) (xy 451.273411 -291.900185) (xy 451.265583 -291.881518)
			(xy 451.265036 -291.8714) (xy 445.2239 -291.8714) (xy 445.223478 -291.881554) (xy 445.215683 -291.900306)
			(xy 445.201286 -291.91463) (xy 445.182494 -291.922329) (xy 445.172338 -291.922708) (xy 443.772798 -291.922708)
			(xy 443.762677 -291.922176) (xy 443.743965 -291.914457) (xy 443.729611 -291.900185) (xy 443.721783 -291.881518)
			(xy 443.721236 -291.8714) (xy 437.6801 -291.8714) (xy 437.679678 -291.881554) (xy 437.671883 -291.900306)
			(xy 437.657486 -291.91463) (xy 437.638694 -291.922329) (xy 437.628538 -291.922708) (xy 436.228998 -291.922708)
			(xy 436.218877 -291.922176) (xy 436.200165 -291.914457) (xy 436.185811 -291.900185) (xy 436.177983 -291.881518)
			(xy 436.177436 -291.8714) (xy 430.1363 -291.8714) (xy 430.135878 -291.881554) (xy 430.128083 -291.900306)
			(xy 430.113686 -291.91463) (xy 430.094894 -291.922329) (xy 430.084738 -291.922708) (xy 428.685198 -291.922708)
			(xy 428.675077 -291.922176) (xy 428.656365 -291.914457) (xy 428.642011 -291.900185) (xy 428.634183 -291.881518)
			(xy 428.633636 -291.8714) (xy 422.5925 -291.8714) (xy 422.592078 -291.881554) (xy 422.584283 -291.900306)
			(xy 422.569886 -291.91463) (xy 422.551094 -291.922329) (xy 422.540938 -291.922708) (xy 421.141398 -291.922708)
			(xy 421.131277 -291.922176) (xy 421.112565 -291.914457) (xy 421.098211 -291.900185) (xy 421.090383 -291.881518)
			(xy 421.089836 -291.8714) (xy 415.0487 -291.8714) (xy 415.048278 -291.881554) (xy 415.040483 -291.900306)
			(xy 415.026086 -291.91463) (xy 415.007294 -291.922329) (xy 414.997138 -291.922708) (xy 413.597598 -291.922708)
			(xy 413.587477 -291.922176) (xy 413.568765 -291.914457) (xy 413.554411 -291.900185) (xy 413.546583 -291.881518)
			(xy 413.546036 -291.8714) (xy 407.5049 -291.8714) (xy 407.504478 -291.881554) (xy 407.496683 -291.900306)
			(xy 407.482286 -291.91463) (xy 407.463494 -291.922329) (xy 407.453338 -291.922708) (xy 406.053798 -291.922708)
			(xy 406.043677 -291.922176) (xy 406.024965 -291.914457) (xy 406.010611 -291.900185) (xy 406.002783 -291.881518)
			(xy 406.002236 -291.8714) (xy 309.6387 -291.8714) (xy 309.638278 -291.881554) (xy 309.630483 -291.900306)
			(xy 309.616086 -291.91463) (xy 309.597294 -291.922329) (xy 309.587138 -291.922708) (xy 308.187598 -291.922708)
			(xy 308.177477 -291.922176) (xy 308.158765 -291.914457) (xy 308.144411 -291.900185) (xy 308.136583 -291.881518)
			(xy 308.136036 -291.8714) (xy 302.0949 -291.8714) (xy 302.094478 -291.881554) (xy 302.086683 -291.900306)
			(xy 302.072286 -291.91463) (xy 302.053494 -291.922329) (xy 302.043338 -291.922708) (xy 300.643798 -291.922708)
			(xy 300.633677 -291.922176) (xy 300.614965 -291.914457) (xy 300.600611 -291.900185) (xy 300.592783 -291.881518)
			(xy 300.592236 -291.8714) (xy 294.5511 -291.8714) (xy 294.550678 -291.881554) (xy 294.542883 -291.900306)
			(xy 294.528486 -291.91463) (xy 294.509694 -291.922329) (xy 294.499538 -291.922708) (xy 293.099998 -291.922708)
			(xy 293.089877 -291.922176) (xy 293.071165 -291.914457) (xy 293.056811 -291.900185) (xy 293.048983 -291.881518)
			(xy 293.048436 -291.8714) (xy 287.0073 -291.8714) (xy 287.006878 -291.881554) (xy 286.999083 -291.900306)
			(xy 286.984686 -291.91463) (xy 286.965894 -291.922329) (xy 286.955738 -291.922708) (xy 285.556198 -291.922708)
			(xy 285.546077 -291.922176) (xy 285.527365 -291.914457) (xy 285.513011 -291.900185) (xy 285.505183 -291.881518)
			(xy 285.504636 -291.8714) (xy 279.4635 -291.8714) (xy 279.463078 -291.881554) (xy 279.455283 -291.900306)
			(xy 279.440886 -291.91463) (xy 279.422094 -291.922329) (xy 279.411938 -291.922708) (xy 278.012398 -291.922708)
			(xy 278.002277 -291.922176) (xy 277.983565 -291.914457) (xy 277.969211 -291.900185) (xy 277.961383 -291.881518)
			(xy 277.960836 -291.8714) (xy 271.9197 -291.8714) (xy 271.919278 -291.881554) (xy 271.911483 -291.900306)
			(xy 271.897086 -291.91463) (xy 271.878294 -291.922329) (xy 271.868138 -291.922708) (xy 270.468598 -291.922708)
			(xy 270.458477 -291.922176) (xy 270.439765 -291.914457) (xy 270.425411 -291.900185) (xy 270.417583 -291.881518)
			(xy 270.417036 -291.8714) (xy 264.3759 -291.8714) (xy 264.375478 -291.881554) (xy 264.367683 -291.900306)
			(xy 264.353286 -291.91463) (xy 264.334494 -291.922329) (xy 264.324338 -291.922708) (xy 262.924798 -291.922708)
			(xy 262.914677 -291.922176) (xy 262.895965 -291.914457) (xy 262.881611 -291.900185) (xy 262.873783 -291.881518)
			(xy 262.873236 -291.8714) (xy 256.8321 -291.8714) (xy 256.831678 -291.881554) (xy 256.823883 -291.900306)
			(xy 256.809486 -291.91463) (xy 256.790694 -291.922329) (xy 256.780538 -291.922708) (xy 255.380998 -291.922708)
			(xy 255.370877 -291.922176) (xy 255.352165 -291.914457) (xy 255.337811 -291.900185) (xy 255.329983 -291.881518)
			(xy 255.329436 -291.8714) (xy 212.371432 -291.8714) (xy 212.370979 -291.88155) (xy 212.363189 -291.900296)
			(xy 212.348803 -291.914618) (xy 212.330022 -291.922324) (xy 212.31987 -291.922708) (xy 210.92033 -291.922708)
			(xy 210.910211 -291.92215) (xy 210.8915 -291.914441) (xy 210.877144 -291.900177) (xy 210.869315 -291.881516)
			(xy 210.868768 -291.8714) (xy 204.827632 -291.8714) (xy 204.827179 -291.88155) (xy 204.819389 -291.900296)
			(xy 204.805003 -291.914618) (xy 204.786222 -291.922324) (xy 204.77607 -291.922708) (xy 203.37653 -291.922708)
			(xy 203.366411 -291.92215) (xy 203.3477 -291.914441) (xy 203.333344 -291.900177) (xy 203.325515 -291.881516)
			(xy 203.324968 -291.8714) (xy 197.283832 -291.8714) (xy 197.283379 -291.88155) (xy 197.275589 -291.900296)
			(xy 197.261203 -291.914618) (xy 197.242422 -291.922324) (xy 197.23227 -291.922708) (xy 195.83273 -291.922708)
			(xy 195.822611 -291.92215) (xy 195.8039 -291.914441) (xy 195.789544 -291.900177) (xy 195.781715 -291.881516)
			(xy 195.781168 -291.8714) (xy 189.740032 -291.8714) (xy 189.739579 -291.88155) (xy 189.731789 -291.900296)
			(xy 189.717403 -291.914618) (xy 189.698622 -291.922324) (xy 189.68847 -291.922708) (xy 188.28893 -291.922708)
			(xy 188.278811 -291.92215) (xy 188.2601 -291.914441) (xy 188.245744 -291.900177) (xy 188.237915 -291.881516)
			(xy 188.237368 -291.8714) (xy 182.196232 -291.8714) (xy 182.195779 -291.88155) (xy 182.187989 -291.900296)
			(xy 182.173603 -291.914618) (xy 182.154822 -291.922324) (xy 182.14467 -291.922708) (xy 180.74513 -291.922708)
			(xy 180.735011 -291.92215) (xy 180.7163 -291.914441) (xy 180.701944 -291.900177) (xy 180.694115 -291.881516)
			(xy 180.693568 -291.8714) (xy 174.652432 -291.8714) (xy 174.651979 -291.88155) (xy 174.644189 -291.900296)
			(xy 174.629803 -291.914618) (xy 174.611022 -291.922324) (xy 174.60087 -291.922708) (xy 173.20133 -291.922708)
			(xy 173.191211 -291.92215) (xy 173.1725 -291.914441) (xy 173.158144 -291.900177) (xy 173.150315 -291.881516)
			(xy 173.149768 -291.8714) (xy 167.108632 -291.8714) (xy 167.108179 -291.88155) (xy 167.100389 -291.900296)
			(xy 167.086003 -291.914618) (xy 167.067222 -291.922324) (xy 167.05707 -291.922708) (xy 165.65753 -291.922708)
			(xy 165.647411 -291.92215) (xy 165.6287 -291.914441) (xy 165.614344 -291.900177) (xy 165.606515 -291.881516)
			(xy 165.605968 -291.8714) (xy 159.564832 -291.8714) (xy 159.564379 -291.88155) (xy 159.556589 -291.900296)
			(xy 159.542203 -291.914618) (xy 159.523422 -291.922324) (xy 159.51327 -291.922708) (xy 158.11373 -291.922708)
			(xy 158.103611 -291.92215) (xy 158.0849 -291.914441) (xy 158.070544 -291.900177) (xy 158.062715 -291.881516)
			(xy 158.062168 -291.8714) (xy 61.698632 -291.8714) (xy 61.698179 -291.88155) (xy 61.690389 -291.900296)
			(xy 61.676003 -291.914618) (xy 61.657222 -291.922324) (xy 61.64707 -291.922708) (xy 60.24753 -291.922708)
			(xy 60.237411 -291.92215) (xy 60.2187 -291.914441) (xy 60.204344 -291.900177) (xy 60.196515 -291.881516)
			(xy 60.195968 -291.8714) (xy 54.154832 -291.8714) (xy 54.154379 -291.88155) (xy 54.146589 -291.900296)
			(xy 54.132203 -291.914618) (xy 54.113422 -291.922324) (xy 54.10327 -291.922708) (xy 52.70373 -291.922708)
			(xy 52.693611 -291.92215) (xy 52.6749 -291.914441) (xy 52.660544 -291.900177) (xy 52.652715 -291.881516)
			(xy 52.652168 -291.8714) (xy 46.611032 -291.8714) (xy 46.610579 -291.88155) (xy 46.602789 -291.900296)
			(xy 46.588403 -291.914618) (xy 46.569622 -291.922324) (xy 46.55947 -291.922708) (xy 45.15993 -291.922708)
			(xy 45.149811 -291.92215) (xy 45.1311 -291.914441) (xy 45.116744 -291.900177) (xy 45.108915 -291.881516)
			(xy 45.108368 -291.8714) (xy 39.067232 -291.8714) (xy 39.066779 -291.88155) (xy 39.058989 -291.900296)
			(xy 39.044603 -291.914618) (xy 39.025822 -291.922324) (xy 39.01567 -291.922708) (xy 37.61613 -291.922708)
			(xy 37.606011 -291.92215) (xy 37.5873 -291.914441) (xy 37.572944 -291.900177) (xy 37.565115 -291.881516)
			(xy 37.564568 -291.8714) (xy 31.523432 -291.8714) (xy 31.522979 -291.88155) (xy 31.515189 -291.900296)
			(xy 31.500803 -291.914618) (xy 31.482022 -291.922324) (xy 31.47187 -291.922708) (xy 30.07233 -291.922708)
			(xy 30.062211 -291.92215) (xy 30.0435 -291.914441) (xy 30.029144 -291.900177) (xy 30.021315 -291.881516)
			(xy 30.020768 -291.8714) (xy 23.979632 -291.8714) (xy 23.979179 -291.88155) (xy 23.971389 -291.900296)
			(xy 23.957003 -291.914618) (xy 23.938222 -291.922324) (xy 23.92807 -291.922708) (xy 22.52853 -291.922708)
			(xy 22.518411 -291.92215) (xy 22.4997 -291.914441) (xy 22.485344 -291.900177) (xy 22.477515 -291.881516)
			(xy 22.476968 -291.8714) (xy 16.435832 -291.8714) (xy 16.435379 -291.88155) (xy 16.427589 -291.900296)
			(xy 16.413203 -291.914618) (xy 16.394422 -291.922324) (xy 16.38427 -291.922708) (xy 14.98473 -291.922708)
			(xy 14.974611 -291.92215) (xy 14.9559 -291.914441) (xy 14.941544 -291.900177) (xy 14.933715 -291.881516)
			(xy 14.933168 -291.8714) (xy 8.892032 -291.8714) (xy 8.891579 -291.88155) (xy 8.883789 -291.900296)
			(xy 8.869403 -291.914618) (xy 8.850622 -291.922324) (xy 8.84047 -291.922708) (xy 7.44093 -291.922708)
			(xy 7.430811 -291.92215) (xy 7.4121 -291.914441) (xy 7.397744 -291.900177) (xy 7.389915 -291.881516)
			(xy 7.389368 -291.8714) (xy 2.509012 -291.8714) (xy 2.509012 -292.721538) (xy 11.489436 -292.721538)
			(xy 11.489436 -292.312598) (xy 11.489932 -292.30244) (xy 11.497706 -292.283672) (xy 11.512072 -292.269306)
			(xy 11.53084 -292.261532) (xy 11.540998 -292.261036) (xy 12.940538 -292.261036) (xy 12.950698 -292.261502)
			(xy 12.969468 -292.269289) (xy 12.983831 -292.283663) (xy 12.991605 -292.302438) (xy 12.9921 -292.312598)
			(xy 12.9921 -292.721538) (xy 19.033236 -292.721538) (xy 19.033236 -292.312598) (xy 19.033732 -292.30244)
			(xy 19.041506 -292.283672) (xy 19.055872 -292.269306) (xy 19.07464 -292.261532) (xy 19.084798 -292.261036)
			(xy 20.484338 -292.261036) (xy 20.494498 -292.261502) (xy 20.513268 -292.269289) (xy 20.527631 -292.283663)
			(xy 20.535405 -292.302438) (xy 20.5359 -292.312598) (xy 20.5359 -292.721538) (xy 26.577036 -292.721538)
			(xy 26.577036 -292.312598) (xy 26.577532 -292.30244) (xy 26.585306 -292.283672) (xy 26.599672 -292.269306)
			(xy 26.61844 -292.261532) (xy 26.628598 -292.261036) (xy 28.028138 -292.261036) (xy 28.038298 -292.261502)
			(xy 28.057068 -292.269289) (xy 28.071431 -292.283663) (xy 28.079205 -292.302438) (xy 28.0797 -292.312598)
			(xy 28.0797 -292.721538) (xy 34.120836 -292.721538) (xy 34.120836 -292.312598) (xy 34.121332 -292.30244)
			(xy 34.129106 -292.283672) (xy 34.143472 -292.269306) (xy 34.16224 -292.261532) (xy 34.172398 -292.261036)
			(xy 35.571938 -292.261036) (xy 35.582098 -292.261502) (xy 35.600868 -292.269289) (xy 35.615231 -292.283663)
			(xy 35.623005 -292.302438) (xy 35.6235 -292.312598) (xy 35.6235 -292.721538) (xy 41.664636 -292.721538)
			(xy 41.664636 -292.312598) (xy 41.665132 -292.30244) (xy 41.672906 -292.283672) (xy 41.687272 -292.269306)
			(xy 41.70604 -292.261532) (xy 41.716198 -292.261036) (xy 43.115738 -292.261036) (xy 43.125898 -292.261502)
			(xy 43.144668 -292.269289) (xy 43.159031 -292.283663) (xy 43.166805 -292.302438) (xy 43.1673 -292.312598)
			(xy 43.1673 -292.721538) (xy 49.208436 -292.721538) (xy 49.208436 -292.312598) (xy 49.208932 -292.30244)
			(xy 49.216706 -292.283672) (xy 49.231072 -292.269306) (xy 49.24984 -292.261532) (xy 49.259998 -292.261036)
			(xy 50.659538 -292.261036) (xy 50.669698 -292.261502) (xy 50.688468 -292.269289) (xy 50.702831 -292.283663)
			(xy 50.710605 -292.302438) (xy 50.7111 -292.312598) (xy 50.7111 -292.721538) (xy 56.752236 -292.721538)
			(xy 56.752236 -292.312598) (xy 56.752732 -292.30244) (xy 56.760506 -292.283672) (xy 56.774872 -292.269306)
			(xy 56.79364 -292.261532) (xy 56.803798 -292.261036) (xy 58.203338 -292.261036) (xy 58.213498 -292.261502)
			(xy 58.232268 -292.269289) (xy 58.246631 -292.283663) (xy 58.254405 -292.302438) (xy 58.2549 -292.312598)
			(xy 58.2549 -292.721538) (xy 64.296036 -292.721538) (xy 64.296036 -292.312598) (xy 64.296532 -292.30244)
			(xy 64.304306 -292.283672) (xy 64.318672 -292.269306) (xy 64.33744 -292.261532) (xy 64.347598 -292.261036)
			(xy 65.747138 -292.261036) (xy 65.757298 -292.261502) (xy 65.776068 -292.269289) (xy 65.790431 -292.283663)
			(xy 65.798205 -292.302438) (xy 65.7987 -292.312598) (xy 65.7987 -292.721538) (xy 162.162236 -292.721538)
			(xy 162.162236 -292.312598) (xy 162.162732 -292.30244) (xy 162.170506 -292.283672) (xy 162.184872 -292.269306)
			(xy 162.20364 -292.261532) (xy 162.213798 -292.261036) (xy 163.613338 -292.261036) (xy 163.623498 -292.261502)
			(xy 163.642268 -292.269289) (xy 163.656631 -292.283663) (xy 163.664405 -292.302438) (xy 163.6649 -292.312598)
			(xy 163.6649 -292.721538) (xy 169.706036 -292.721538) (xy 169.706036 -292.312598) (xy 169.706532 -292.30244)
			(xy 169.714306 -292.283672) (xy 169.728672 -292.269306) (xy 169.74744 -292.261532) (xy 169.757598 -292.261036)
			(xy 171.157138 -292.261036) (xy 171.167298 -292.261502) (xy 171.186068 -292.269289) (xy 171.200431 -292.283663)
			(xy 171.208205 -292.302438) (xy 171.2087 -292.312598) (xy 171.2087 -292.721538) (xy 177.249836 -292.721538)
			(xy 177.249836 -292.312598) (xy 177.250332 -292.30244) (xy 177.258106 -292.283672) (xy 177.272472 -292.269306)
			(xy 177.29124 -292.261532) (xy 177.301398 -292.261036) (xy 178.700938 -292.261036) (xy 178.711098 -292.261502)
			(xy 178.729868 -292.269289) (xy 178.744231 -292.283663) (xy 178.752005 -292.302438) (xy 178.7525 -292.312598)
			(xy 178.7525 -292.721538) (xy 184.793636 -292.721538) (xy 184.793636 -292.312598) (xy 184.794132 -292.30244)
			(xy 184.801906 -292.283672) (xy 184.816272 -292.269306) (xy 184.83504 -292.261532) (xy 184.845198 -292.261036)
			(xy 186.244738 -292.261036) (xy 186.254898 -292.261502) (xy 186.273668 -292.269289) (xy 186.288031 -292.283663)
			(xy 186.295805 -292.302438) (xy 186.2963 -292.312598) (xy 186.2963 -292.721538) (xy 192.337436 -292.721538)
			(xy 192.337436 -292.312598) (xy 192.337932 -292.30244) (xy 192.345706 -292.283672) (xy 192.360072 -292.269306)
			(xy 192.37884 -292.261532) (xy 192.388998 -292.261036) (xy 193.788538 -292.261036) (xy 193.798698 -292.261502)
			(xy 193.817468 -292.269289) (xy 193.831831 -292.283663) (xy 193.839605 -292.302438) (xy 193.8401 -292.312598)
			(xy 193.8401 -292.721538) (xy 199.881236 -292.721538) (xy 199.881236 -292.312598) (xy 199.881732 -292.30244)
			(xy 199.889506 -292.283672) (xy 199.903872 -292.269306) (xy 199.92264 -292.261532) (xy 199.932798 -292.261036)
			(xy 201.332338 -292.261036) (xy 201.342498 -292.261502) (xy 201.361268 -292.269289) (xy 201.375631 -292.283663)
			(xy 201.383405 -292.302438) (xy 201.3839 -292.312598) (xy 201.3839 -292.721538) (xy 207.425036 -292.721538)
			(xy 207.425036 -292.312598) (xy 207.425532 -292.30244) (xy 207.433306 -292.283672) (xy 207.447672 -292.269306)
			(xy 207.46644 -292.261532) (xy 207.476598 -292.261036) (xy 208.876138 -292.261036) (xy 208.886298 -292.261502)
			(xy 208.905068 -292.269289) (xy 208.919431 -292.283663) (xy 208.927205 -292.302438) (xy 208.9277 -292.312598)
			(xy 208.9277 -292.721538) (xy 214.968836 -292.721538) (xy 214.968836 -292.312598) (xy 214.969332 -292.30244)
			(xy 214.977106 -292.283672) (xy 214.991472 -292.269306) (xy 215.01024 -292.261532) (xy 215.020398 -292.261036)
			(xy 216.419938 -292.261036) (xy 216.430098 -292.261502) (xy 216.448868 -292.269289) (xy 216.463231 -292.283663)
			(xy 216.471005 -292.302438) (xy 216.4715 -292.312598) (xy 216.4715 -292.721538) (xy 259.429504 -292.721538)
			(xy 259.429504 -292.312598) (xy 259.430031 -292.302444) (xy 259.4378 -292.283682) (xy 259.452155 -292.269318)
			(xy 259.470913 -292.261537) (xy 259.481066 -292.261036) (xy 260.880606 -292.261036) (xy 260.890764 -292.261529)
			(xy 260.909533 -292.269305) (xy 260.923898 -292.283671) (xy 260.931672 -292.30244) (xy 260.932168 -292.312598)
			(xy 260.932168 -292.721538) (xy 266.973304 -292.721538) (xy 266.973304 -292.312598) (xy 266.973831 -292.302444)
			(xy 266.9816 -292.283682) (xy 266.995955 -292.269318) (xy 267.014713 -292.261537) (xy 267.024866 -292.261036)
			(xy 268.424406 -292.261036) (xy 268.434564 -292.261529) (xy 268.453333 -292.269305) (xy 268.467698 -292.283671)
			(xy 268.475472 -292.30244) (xy 268.475968 -292.312598) (xy 268.475968 -292.721538) (xy 274.517104 -292.721538)
			(xy 274.517104 -292.312598) (xy 274.517631 -292.302444) (xy 274.5254 -292.283682) (xy 274.539755 -292.269318)
			(xy 274.558513 -292.261537) (xy 274.568666 -292.261036) (xy 275.968206 -292.261036) (xy 275.978364 -292.261529)
			(xy 275.997133 -292.269305) (xy 276.011498 -292.283671) (xy 276.019272 -292.30244) (xy 276.019768 -292.312598)
			(xy 276.019768 -292.721538) (xy 282.060904 -292.721538) (xy 282.060904 -292.312598) (xy 282.061431 -292.302444)
			(xy 282.0692 -292.283682) (xy 282.083555 -292.269318) (xy 282.102313 -292.261537) (xy 282.112466 -292.261036)
			(xy 283.512006 -292.261036) (xy 283.522164 -292.261529) (xy 283.540933 -292.269305) (xy 283.555298 -292.283671)
			(xy 283.563072 -292.30244) (xy 283.563568 -292.312598) (xy 283.563568 -292.721538) (xy 289.604704 -292.721538)
			(xy 289.604704 -292.312598) (xy 289.605231 -292.302444) (xy 289.613 -292.283682) (xy 289.627355 -292.269318)
			(xy 289.646113 -292.261537) (xy 289.656266 -292.261036) (xy 291.055806 -292.261036) (xy 291.065964 -292.261529)
			(xy 291.084733 -292.269305) (xy 291.099098 -292.283671) (xy 291.106872 -292.30244) (xy 291.107368 -292.312598)
			(xy 291.107368 -292.721538) (xy 297.148504 -292.721538) (xy 297.148504 -292.312598) (xy 297.149031 -292.302444)
			(xy 297.1568 -292.283682) (xy 297.171155 -292.269318) (xy 297.189913 -292.261537) (xy 297.200066 -292.261036)
			(xy 298.599606 -292.261036) (xy 298.609764 -292.261529) (xy 298.628533 -292.269305) (xy 298.642898 -292.283671)
			(xy 298.650672 -292.30244) (xy 298.651168 -292.312598) (xy 298.651168 -292.721538) (xy 304.692304 -292.721538)
			(xy 304.692304 -292.312598) (xy 304.692831 -292.302444) (xy 304.7006 -292.283682) (xy 304.714955 -292.269318)
			(xy 304.733713 -292.261537) (xy 304.743866 -292.261036) (xy 306.143406 -292.261036) (xy 306.153564 -292.261529)
			(xy 306.172333 -292.269305) (xy 306.186698 -292.283671) (xy 306.194472 -292.30244) (xy 306.194968 -292.312598)
			(xy 306.194968 -292.721538) (xy 312.236104 -292.721538) (xy 312.236104 -292.312598) (xy 312.236631 -292.302444)
			(xy 312.2444 -292.283682) (xy 312.258755 -292.269318) (xy 312.277513 -292.261537) (xy 312.287666 -292.261036)
			(xy 313.687206 -292.261036) (xy 313.697364 -292.261529) (xy 313.716133 -292.269305) (xy 313.730498 -292.283671)
			(xy 313.738272 -292.30244) (xy 313.738768 -292.312598) (xy 313.738768 -292.721538) (xy 410.102304 -292.721538)
			(xy 410.102304 -292.312598) (xy 410.102831 -292.302444) (xy 410.1106 -292.283682) (xy 410.124955 -292.269318)
			(xy 410.143713 -292.261537) (xy 410.153866 -292.261036) (xy 411.553406 -292.261036) (xy 411.563564 -292.261529)
			(xy 411.582333 -292.269305) (xy 411.596698 -292.283671) (xy 411.604472 -292.30244) (xy 411.604968 -292.312598)
			(xy 411.604968 -292.721538) (xy 417.646104 -292.721538) (xy 417.646104 -292.312598) (xy 417.646631 -292.302444)
			(xy 417.6544 -292.283682) (xy 417.668755 -292.269318) (xy 417.687513 -292.261537) (xy 417.697666 -292.261036)
			(xy 419.097206 -292.261036) (xy 419.107364 -292.261529) (xy 419.126133 -292.269305) (xy 419.140498 -292.283671)
			(xy 419.148272 -292.30244) (xy 419.148768 -292.312598) (xy 419.148768 -292.721538) (xy 425.189904 -292.721538)
			(xy 425.189904 -292.312598) (xy 425.190431 -292.302444) (xy 425.1982 -292.283682) (xy 425.212555 -292.269318)
			(xy 425.231313 -292.261537) (xy 425.241466 -292.261036) (xy 426.641006 -292.261036) (xy 426.651164 -292.261529)
			(xy 426.669933 -292.269305) (xy 426.684298 -292.283671) (xy 426.692072 -292.30244) (xy 426.692568 -292.312598)
			(xy 426.692568 -292.721538) (xy 432.733704 -292.721538) (xy 432.733704 -292.312598) (xy 432.734231 -292.302444)
			(xy 432.742 -292.283682) (xy 432.756355 -292.269318) (xy 432.775113 -292.261537) (xy 432.785266 -292.261036)
			(xy 434.184806 -292.261036) (xy 434.194964 -292.261529) (xy 434.213733 -292.269305) (xy 434.228098 -292.283671)
			(xy 434.235872 -292.30244) (xy 434.236368 -292.312598) (xy 434.236368 -292.721538) (xy 440.277504 -292.721538)
			(xy 440.277504 -292.312598) (xy 440.278031 -292.302444) (xy 440.2858 -292.283682) (xy 440.300155 -292.269318)
			(xy 440.318913 -292.261537) (xy 440.329066 -292.261036) (xy 441.728606 -292.261036) (xy 441.738764 -292.261529)
			(xy 441.757533 -292.269305) (xy 441.771898 -292.283671) (xy 441.779672 -292.30244) (xy 441.780168 -292.312598)
			(xy 441.780168 -292.721538) (xy 447.821304 -292.721538) (xy 447.821304 -292.312598) (xy 447.821831 -292.302444)
			(xy 447.8296 -292.283682) (xy 447.843955 -292.269318) (xy 447.862713 -292.261537) (xy 447.872866 -292.261036)
			(xy 449.272406 -292.261036) (xy 449.282564 -292.261529) (xy 449.301333 -292.269305) (xy 449.315698 -292.283671)
			(xy 449.323472 -292.30244) (xy 449.323968 -292.312598) (xy 449.323968 -292.721538) (xy 455.365104 -292.721538)
			(xy 455.365104 -292.312598) (xy 455.365631 -292.302444) (xy 455.3734 -292.283682) (xy 455.387755 -292.269318)
			(xy 455.406513 -292.261537) (xy 455.416666 -292.261036) (xy 456.816206 -292.261036) (xy 456.826364 -292.261529)
			(xy 456.845133 -292.269305) (xy 456.859498 -292.283671) (xy 456.867272 -292.30244) (xy 456.867768 -292.312598)
			(xy 456.867768 -292.721538) (xy 462.908904 -292.721538) (xy 462.908904 -292.312598) (xy 462.909431 -292.302444)
			(xy 462.9172 -292.283682) (xy 462.931555 -292.269318) (xy 462.950313 -292.261537) (xy 462.960466 -292.261036)
			(xy 464.360006 -292.261036) (xy 464.370164 -292.261529) (xy 464.388933 -292.269305) (xy 464.403298 -292.283671)
			(xy 464.411072 -292.30244) (xy 464.411568 -292.312598) (xy 464.411568 -292.721538) (xy 464.411098 -292.731697)
			(xy 464.403312 -292.750466) (xy 464.388939 -292.76483) (xy 464.370166 -292.772604) (xy 464.360006 -292.7731)
			(xy 462.960466 -292.7731) (xy 462.950311 -292.772595) (xy 462.931548 -292.764817) (xy 462.917185 -292.750455)
			(xy 462.909405 -292.731693) (xy 462.908904 -292.721538) (xy 456.867768 -292.721538) (xy 456.867298 -292.731697)
			(xy 456.859512 -292.750466) (xy 456.845139 -292.76483) (xy 456.826366 -292.772604) (xy 456.816206 -292.7731)
			(xy 455.416666 -292.7731) (xy 455.406511 -292.772595) (xy 455.387748 -292.764817) (xy 455.373385 -292.750455)
			(xy 455.365605 -292.731693) (xy 455.365104 -292.721538) (xy 449.323968 -292.721538) (xy 449.323498 -292.731697)
			(xy 449.315712 -292.750466) (xy 449.301339 -292.76483) (xy 449.282566 -292.772604) (xy 449.272406 -292.7731)
			(xy 447.872866 -292.7731) (xy 447.862711 -292.772595) (xy 447.843948 -292.764817) (xy 447.829585 -292.750455)
			(xy 447.821805 -292.731693) (xy 447.821304 -292.721538) (xy 441.780168 -292.721538) (xy 441.779698 -292.731697)
			(xy 441.771912 -292.750466) (xy 441.757539 -292.76483) (xy 441.738766 -292.772604) (xy 441.728606 -292.7731)
			(xy 440.329066 -292.7731) (xy 440.318911 -292.772595) (xy 440.300148 -292.764817) (xy 440.285785 -292.750455)
			(xy 440.278005 -292.731693) (xy 440.277504 -292.721538) (xy 434.236368 -292.721538) (xy 434.235898 -292.731697)
			(xy 434.228112 -292.750466) (xy 434.213739 -292.76483) (xy 434.194966 -292.772604) (xy 434.184806 -292.7731)
			(xy 432.785266 -292.7731) (xy 432.775111 -292.772595) (xy 432.756348 -292.764817) (xy 432.741985 -292.750455)
			(xy 432.734205 -292.731693) (xy 432.733704 -292.721538) (xy 426.692568 -292.721538) (xy 426.692098 -292.731697)
			(xy 426.684312 -292.750466) (xy 426.669939 -292.76483) (xy 426.651166 -292.772604) (xy 426.641006 -292.7731)
			(xy 425.241466 -292.7731) (xy 425.231311 -292.772595) (xy 425.212548 -292.764817) (xy 425.198185 -292.750455)
			(xy 425.190405 -292.731693) (xy 425.189904 -292.721538) (xy 419.148768 -292.721538) (xy 419.148298 -292.731697)
			(xy 419.140512 -292.750466) (xy 419.126139 -292.76483) (xy 419.107366 -292.772604) (xy 419.097206 -292.7731)
			(xy 417.697666 -292.7731) (xy 417.687511 -292.772595) (xy 417.668748 -292.764817) (xy 417.654385 -292.750455)
			(xy 417.646605 -292.731693) (xy 417.646104 -292.721538) (xy 411.604968 -292.721538) (xy 411.604498 -292.731697)
			(xy 411.596712 -292.750466) (xy 411.582339 -292.76483) (xy 411.563566 -292.772604) (xy 411.553406 -292.7731)
			(xy 410.153866 -292.7731) (xy 410.143711 -292.772595) (xy 410.124948 -292.764817) (xy 410.110585 -292.750455)
			(xy 410.102805 -292.731693) (xy 410.102304 -292.721538) (xy 313.738768 -292.721538) (xy 313.738298 -292.731697)
			(xy 313.730512 -292.750466) (xy 313.716139 -292.76483) (xy 313.697366 -292.772604) (xy 313.687206 -292.7731)
			(xy 312.287666 -292.7731) (xy 312.277511 -292.772595) (xy 312.258748 -292.764817) (xy 312.244385 -292.750455)
			(xy 312.236605 -292.731693) (xy 312.236104 -292.721538) (xy 306.194968 -292.721538) (xy 306.194498 -292.731697)
			(xy 306.186712 -292.750466) (xy 306.172339 -292.76483) (xy 306.153566 -292.772604) (xy 306.143406 -292.7731)
			(xy 304.743866 -292.7731) (xy 304.733711 -292.772595) (xy 304.714948 -292.764817) (xy 304.700585 -292.750455)
			(xy 304.692805 -292.731693) (xy 304.692304 -292.721538) (xy 298.651168 -292.721538) (xy 298.650698 -292.731697)
			(xy 298.642912 -292.750466) (xy 298.628539 -292.76483) (xy 298.609766 -292.772604) (xy 298.599606 -292.7731)
			(xy 297.200066 -292.7731) (xy 297.189911 -292.772595) (xy 297.171148 -292.764817) (xy 297.156785 -292.750455)
			(xy 297.149005 -292.731693) (xy 297.148504 -292.721538) (xy 291.107368 -292.721538) (xy 291.106898 -292.731697)
			(xy 291.099112 -292.750466) (xy 291.084739 -292.76483) (xy 291.065966 -292.772604) (xy 291.055806 -292.7731)
			(xy 289.656266 -292.7731) (xy 289.646111 -292.772595) (xy 289.627348 -292.764817) (xy 289.612985 -292.750455)
			(xy 289.605205 -292.731693) (xy 289.604704 -292.721538) (xy 283.563568 -292.721538) (xy 283.563098 -292.731697)
			(xy 283.555312 -292.750466) (xy 283.540939 -292.76483) (xy 283.522166 -292.772604) (xy 283.512006 -292.7731)
			(xy 282.112466 -292.7731) (xy 282.102311 -292.772595) (xy 282.083548 -292.764817) (xy 282.069185 -292.750455)
			(xy 282.061405 -292.731693) (xy 282.060904 -292.721538) (xy 276.019768 -292.721538) (xy 276.019298 -292.731697)
			(xy 276.011512 -292.750466) (xy 275.997139 -292.76483) (xy 275.978366 -292.772604) (xy 275.968206 -292.7731)
			(xy 274.568666 -292.7731) (xy 274.558511 -292.772595) (xy 274.539748 -292.764817) (xy 274.525385 -292.750455)
			(xy 274.517605 -292.731693) (xy 274.517104 -292.721538) (xy 268.475968 -292.721538) (xy 268.475498 -292.731697)
			(xy 268.467712 -292.750466) (xy 268.453339 -292.76483) (xy 268.434566 -292.772604) (xy 268.424406 -292.7731)
			(xy 267.024866 -292.7731) (xy 267.014711 -292.772595) (xy 266.995948 -292.764817) (xy 266.981585 -292.750455)
			(xy 266.973805 -292.731693) (xy 266.973304 -292.721538) (xy 260.932168 -292.721538) (xy 260.931698 -292.731697)
			(xy 260.923912 -292.750466) (xy 260.909539 -292.76483) (xy 260.890766 -292.772604) (xy 260.880606 -292.7731)
			(xy 259.481066 -292.7731) (xy 259.470911 -292.772595) (xy 259.452148 -292.764817) (xy 259.437785 -292.750455)
			(xy 259.430005 -292.731693) (xy 259.429504 -292.721538) (xy 216.4715 -292.721538) (xy 216.470999 -292.731694)
			(xy 216.463219 -292.750456) (xy 216.448856 -292.764819) (xy 216.430094 -292.772599) (xy 216.419938 -292.7731)
			(xy 215.020398 -292.7731) (xy 215.010245 -292.772569) (xy 214.991483 -292.764801) (xy 214.977119 -292.750447)
			(xy 214.969338 -292.731691) (xy 214.968836 -292.721538) (xy 208.9277 -292.721538) (xy 208.927199 -292.731694)
			(xy 208.919419 -292.750456) (xy 208.905056 -292.764819) (xy 208.886294 -292.772599) (xy 208.876138 -292.7731)
			(xy 207.476598 -292.7731) (xy 207.466445 -292.772569) (xy 207.447683 -292.764801) (xy 207.433319 -292.750447)
			(xy 207.425538 -292.731691) (xy 207.425036 -292.721538) (xy 201.3839 -292.721538) (xy 201.383399 -292.731694)
			(xy 201.375619 -292.750456) (xy 201.361256 -292.764819) (xy 201.342494 -292.772599) (xy 201.332338 -292.7731)
			(xy 199.932798 -292.7731) (xy 199.922645 -292.772569) (xy 199.903883 -292.764801) (xy 199.889519 -292.750447)
			(xy 199.881738 -292.731691) (xy 199.881236 -292.721538) (xy 193.8401 -292.721538) (xy 193.839599 -292.731694)
			(xy 193.831819 -292.750456) (xy 193.817456 -292.764819) (xy 193.798694 -292.772599) (xy 193.788538 -292.7731)
			(xy 192.388998 -292.7731) (xy 192.378845 -292.772569) (xy 192.360083 -292.764801) (xy 192.345719 -292.750447)
			(xy 192.337938 -292.731691) (xy 192.337436 -292.721538) (xy 186.2963 -292.721538) (xy 186.295799 -292.731694)
			(xy 186.288019 -292.750456) (xy 186.273656 -292.764819) (xy 186.254894 -292.772599) (xy 186.244738 -292.7731)
			(xy 184.845198 -292.7731) (xy 184.835045 -292.772569) (xy 184.816283 -292.764801) (xy 184.801919 -292.750447)
			(xy 184.794138 -292.731691) (xy 184.793636 -292.721538) (xy 178.7525 -292.721538) (xy 178.751999 -292.731694)
			(xy 178.744219 -292.750456) (xy 178.729856 -292.764819) (xy 178.711094 -292.772599) (xy 178.700938 -292.7731)
			(xy 177.301398 -292.7731) (xy 177.291245 -292.772569) (xy 177.272483 -292.764801) (xy 177.258119 -292.750447)
			(xy 177.250338 -292.731691) (xy 177.249836 -292.721538) (xy 171.2087 -292.721538) (xy 171.208199 -292.731694)
			(xy 171.200419 -292.750456) (xy 171.186056 -292.764819) (xy 171.167294 -292.772599) (xy 171.157138 -292.7731)
			(xy 169.757598 -292.7731) (xy 169.747445 -292.772569) (xy 169.728683 -292.764801) (xy 169.714319 -292.750447)
			(xy 169.706538 -292.731691) (xy 169.706036 -292.721538) (xy 163.6649 -292.721538) (xy 163.664399 -292.731694)
			(xy 163.656619 -292.750456) (xy 163.642256 -292.764819) (xy 163.623494 -292.772599) (xy 163.613338 -292.7731)
			(xy 162.213798 -292.7731) (xy 162.203645 -292.772569) (xy 162.184883 -292.764801) (xy 162.170519 -292.750447)
			(xy 162.162738 -292.731691) (xy 162.162236 -292.721538) (xy 65.7987 -292.721538) (xy 65.798199 -292.731694)
			(xy 65.790419 -292.750456) (xy 65.776056 -292.764819) (xy 65.757294 -292.772599) (xy 65.747138 -292.7731)
			(xy 64.347598 -292.7731) (xy 64.337445 -292.772569) (xy 64.318683 -292.764801) (xy 64.304319 -292.750447)
			(xy 64.296538 -292.731691) (xy 64.296036 -292.721538) (xy 58.2549 -292.721538) (xy 58.254399 -292.731694)
			(xy 58.246619 -292.750456) (xy 58.232256 -292.764819) (xy 58.213494 -292.772599) (xy 58.203338 -292.7731)
			(xy 56.803798 -292.7731) (xy 56.793645 -292.772569) (xy 56.774883 -292.764801) (xy 56.760519 -292.750447)
			(xy 56.752738 -292.731691) (xy 56.752236 -292.721538) (xy 50.7111 -292.721538) (xy 50.710599 -292.731694)
			(xy 50.702819 -292.750456) (xy 50.688456 -292.764819) (xy 50.669694 -292.772599) (xy 50.659538 -292.7731)
			(xy 49.259998 -292.7731) (xy 49.249845 -292.772569) (xy 49.231083 -292.764801) (xy 49.216719 -292.750447)
			(xy 49.208938 -292.731691) (xy 49.208436 -292.721538) (xy 43.1673 -292.721538) (xy 43.166799 -292.731694)
			(xy 43.159019 -292.750456) (xy 43.144656 -292.764819) (xy 43.125894 -292.772599) (xy 43.115738 -292.7731)
			(xy 41.716198 -292.7731) (xy 41.706045 -292.772569) (xy 41.687283 -292.764801) (xy 41.672919 -292.750447)
			(xy 41.665138 -292.731691) (xy 41.664636 -292.721538) (xy 35.6235 -292.721538) (xy 35.622999 -292.731694)
			(xy 35.615219 -292.750456) (xy 35.600856 -292.764819) (xy 35.582094 -292.772599) (xy 35.571938 -292.7731)
			(xy 34.172398 -292.7731) (xy 34.162245 -292.772569) (xy 34.143483 -292.764801) (xy 34.129119 -292.750447)
			(xy 34.121338 -292.731691) (xy 34.120836 -292.721538) (xy 28.0797 -292.721538) (xy 28.079199 -292.731694)
			(xy 28.071419 -292.750456) (xy 28.057056 -292.764819) (xy 28.038294 -292.772599) (xy 28.028138 -292.7731)
			(xy 26.628598 -292.7731) (xy 26.618445 -292.772569) (xy 26.599683 -292.764801) (xy 26.585319 -292.750447)
			(xy 26.577538 -292.731691) (xy 26.577036 -292.721538) (xy 20.5359 -292.721538) (xy 20.535399 -292.731694)
			(xy 20.527619 -292.750456) (xy 20.513256 -292.764819) (xy 20.494494 -292.772599) (xy 20.484338 -292.7731)
			(xy 19.084798 -292.7731) (xy 19.074645 -292.772569) (xy 19.055883 -292.764801) (xy 19.041519 -292.750447)
			(xy 19.033738 -292.731691) (xy 19.033236 -292.721538) (xy 12.9921 -292.721538) (xy 12.991599 -292.731694)
			(xy 12.983819 -292.750456) (xy 12.969456 -292.764819) (xy 12.950694 -292.772599) (xy 12.940538 -292.7731)
			(xy 11.540998 -292.7731) (xy 11.530845 -292.772569) (xy 11.512083 -292.764801) (xy 11.497719 -292.750447)
			(xy 11.489938 -292.731691) (xy 11.489436 -292.721538) (xy 2.509012 -292.721538) (xy 2.509012 -293.571422)
			(xy 7.389368 -293.571422) (xy 7.389368 -293.162482) (xy 7.38975 -293.152306) (xy 7.397547 -293.133505)
			(xy 7.411945 -293.11912) (xy 7.430753 -293.111341) (xy 7.44093 -293.11092) (xy 8.84047 -293.11092)
			(xy 8.850637 -293.111388) (xy 8.869428 -293.11916) (xy 8.883813 -293.133532) (xy 8.891602 -293.152315)
			(xy 8.892032 -293.162482) (xy 8.892032 -293.571422) (xy 11.489436 -293.571422) (xy 11.489436 -293.162482)
			(xy 11.489918 -293.152323) (xy 11.497698 -293.133554) (xy 11.512067 -293.119189) (xy 11.530839 -293.111415)
			(xy 11.540998 -293.11092) (xy 12.940538 -293.11092) (xy 12.950696 -293.111402) (xy 12.969463 -293.119185)
			(xy 12.983826 -293.133554) (xy 12.991602 -293.152324) (xy 12.9921 -293.162482) (xy 12.9921 -293.571422)
			(xy 14.933168 -293.571422) (xy 14.933168 -293.162482) (xy 14.93355 -293.152306) (xy 14.941347 -293.133505)
			(xy 14.955745 -293.11912) (xy 14.974553 -293.111341) (xy 14.98473 -293.11092) (xy 16.38427 -293.11092)
			(xy 16.394437 -293.111388) (xy 16.413228 -293.11916) (xy 16.427613 -293.133532) (xy 16.435402 -293.152315)
			(xy 16.435832 -293.162482) (xy 16.435832 -293.571422) (xy 19.033236 -293.571422) (xy 19.033236 -293.162482)
			(xy 19.033718 -293.152323) (xy 19.041498 -293.133554) (xy 19.055867 -293.119189) (xy 19.074639 -293.111415)
			(xy 19.084798 -293.11092) (xy 20.484338 -293.11092) (xy 20.494496 -293.111402) (xy 20.513263 -293.119185)
			(xy 20.527626 -293.133554) (xy 20.535402 -293.152324) (xy 20.5359 -293.162482) (xy 20.5359 -293.571422)
			(xy 22.476968 -293.571422) (xy 22.476968 -293.162482) (xy 22.47735 -293.152306) (xy 22.485147 -293.133505)
			(xy 22.499545 -293.11912) (xy 22.518353 -293.111341) (xy 22.52853 -293.11092) (xy 23.92807 -293.11092)
			(xy 23.938237 -293.111388) (xy 23.957028 -293.11916) (xy 23.971413 -293.133532) (xy 23.979202 -293.152315)
			(xy 23.979632 -293.162482) (xy 23.979632 -293.571422) (xy 26.577036 -293.571422) (xy 26.577036 -293.162482)
			(xy 26.577518 -293.152323) (xy 26.585298 -293.133554) (xy 26.599667 -293.119189) (xy 26.618439 -293.111415)
			(xy 26.628598 -293.11092) (xy 28.028138 -293.11092) (xy 28.038296 -293.111402) (xy 28.057063 -293.119185)
			(xy 28.071426 -293.133554) (xy 28.079202 -293.152324) (xy 28.0797 -293.162482) (xy 28.0797 -293.571422)
			(xy 30.020768 -293.571422) (xy 30.020768 -293.162482) (xy 30.02115 -293.152306) (xy 30.028947 -293.133505)
			(xy 30.043345 -293.11912) (xy 30.062153 -293.111341) (xy 30.07233 -293.11092) (xy 31.47187 -293.11092)
			(xy 31.482037 -293.111388) (xy 31.500828 -293.11916) (xy 31.515213 -293.133532) (xy 31.523002 -293.152315)
			(xy 31.523432 -293.162482) (xy 31.523432 -293.571422) (xy 34.120836 -293.571422) (xy 34.120836 -293.162482)
			(xy 34.121318 -293.152323) (xy 34.129098 -293.133554) (xy 34.143467 -293.119189) (xy 34.162239 -293.111415)
			(xy 34.172398 -293.11092) (xy 35.571938 -293.11092) (xy 35.582096 -293.111402) (xy 35.600863 -293.119185)
			(xy 35.615226 -293.133554) (xy 35.623002 -293.152324) (xy 35.6235 -293.162482) (xy 35.6235 -293.571422)
			(xy 37.564568 -293.571422) (xy 37.564568 -293.162482) (xy 37.56495 -293.152306) (xy 37.572747 -293.133505)
			(xy 37.587145 -293.11912) (xy 37.605953 -293.111341) (xy 37.61613 -293.11092) (xy 39.01567 -293.11092)
			(xy 39.025837 -293.111388) (xy 39.044628 -293.11916) (xy 39.059013 -293.133532) (xy 39.066802 -293.152315)
			(xy 39.067232 -293.162482) (xy 39.067232 -293.571422) (xy 41.664636 -293.571422) (xy 41.664636 -293.162482)
			(xy 41.665118 -293.152323) (xy 41.672898 -293.133554) (xy 41.687267 -293.119189) (xy 41.706039 -293.111415)
			(xy 41.716198 -293.11092) (xy 43.115738 -293.11092) (xy 43.125896 -293.111402) (xy 43.144663 -293.119185)
			(xy 43.159026 -293.133554) (xy 43.166802 -293.152324) (xy 43.1673 -293.162482) (xy 43.1673 -293.571422)
			(xy 45.108368 -293.571422) (xy 45.108368 -293.162482) (xy 45.10875 -293.152306) (xy 45.116547 -293.133505)
			(xy 45.130945 -293.11912) (xy 45.149753 -293.111341) (xy 45.15993 -293.11092) (xy 46.55947 -293.11092)
			(xy 46.569637 -293.111388) (xy 46.588428 -293.11916) (xy 46.602813 -293.133532) (xy 46.610602 -293.152315)
			(xy 46.611032 -293.162482) (xy 46.611032 -293.571422) (xy 49.208436 -293.571422) (xy 49.208436 -293.162482)
			(xy 49.208918 -293.152323) (xy 49.216698 -293.133554) (xy 49.231067 -293.119189) (xy 49.249839 -293.111415)
			(xy 49.259998 -293.11092) (xy 50.659538 -293.11092) (xy 50.669696 -293.111402) (xy 50.688463 -293.119185)
			(xy 50.702826 -293.133554) (xy 50.710602 -293.152324) (xy 50.7111 -293.162482) (xy 50.7111 -293.571422)
			(xy 52.652168 -293.571422) (xy 52.652168 -293.162482) (xy 52.65255 -293.152306) (xy 52.660347 -293.133505)
			(xy 52.674745 -293.11912) (xy 52.693553 -293.111341) (xy 52.70373 -293.11092) (xy 54.10327 -293.11092)
			(xy 54.113437 -293.111388) (xy 54.132228 -293.11916) (xy 54.146613 -293.133532) (xy 54.154402 -293.152315)
			(xy 54.154832 -293.162482) (xy 54.154832 -293.571422) (xy 56.752236 -293.571422) (xy 56.752236 -293.162482)
			(xy 56.752718 -293.152323) (xy 56.760498 -293.133554) (xy 56.774867 -293.119189) (xy 56.793639 -293.111415)
			(xy 56.803798 -293.11092) (xy 58.203338 -293.11092) (xy 58.213496 -293.111402) (xy 58.232263 -293.119185)
			(xy 58.246626 -293.133554) (xy 58.254402 -293.152324) (xy 58.2549 -293.162482) (xy 58.2549 -293.571422)
			(xy 60.195968 -293.571422) (xy 60.195968 -293.162482) (xy 60.19635 -293.152306) (xy 60.204147 -293.133505)
			(xy 60.218545 -293.11912) (xy 60.237353 -293.111341) (xy 60.24753 -293.11092) (xy 61.64707 -293.11092)
			(xy 61.657237 -293.111388) (xy 61.676028 -293.11916) (xy 61.690413 -293.133532) (xy 61.698202 -293.152315)
			(xy 61.698632 -293.162482) (xy 61.698632 -293.571422) (xy 64.296036 -293.571422) (xy 64.296036 -293.162482)
			(xy 64.296518 -293.152323) (xy 64.304298 -293.133554) (xy 64.318667 -293.119189) (xy 64.337439 -293.111415)
			(xy 64.347598 -293.11092) (xy 65.747138 -293.11092) (xy 65.757296 -293.111402) (xy 65.776063 -293.119185)
			(xy 65.790426 -293.133554) (xy 65.798202 -293.152324) (xy 65.7987 -293.162482) (xy 65.7987 -293.571422)
			(xy 158.062168 -293.571422) (xy 158.062168 -293.162482) (xy 158.06255 -293.152306) (xy 158.070347 -293.133505)
			(xy 158.084745 -293.11912) (xy 158.103553 -293.111341) (xy 158.11373 -293.11092) (xy 159.51327 -293.11092)
			(xy 159.523437 -293.111388) (xy 159.542228 -293.11916) (xy 159.556613 -293.133532) (xy 159.564402 -293.152315)
			(xy 159.564832 -293.162482) (xy 159.564832 -293.571422) (xy 162.162236 -293.571422) (xy 162.162236 -293.162482)
			(xy 162.162718 -293.152323) (xy 162.170498 -293.133554) (xy 162.184867 -293.119189) (xy 162.203639 -293.111415)
			(xy 162.213798 -293.11092) (xy 163.613338 -293.11092) (xy 163.623496 -293.111402) (xy 163.642263 -293.119185)
			(xy 163.656626 -293.133554) (xy 163.664402 -293.152324) (xy 163.6649 -293.162482) (xy 163.6649 -293.571422)
			(xy 165.605968 -293.571422) (xy 165.605968 -293.162482) (xy 165.60635 -293.152306) (xy 165.614147 -293.133505)
			(xy 165.628545 -293.11912) (xy 165.647353 -293.111341) (xy 165.65753 -293.11092) (xy 167.05707 -293.11092)
			(xy 167.067237 -293.111388) (xy 167.086028 -293.11916) (xy 167.100413 -293.133532) (xy 167.108202 -293.152315)
			(xy 167.108632 -293.162482) (xy 167.108632 -293.571422) (xy 169.706036 -293.571422) (xy 169.706036 -293.162482)
			(xy 169.706518 -293.152323) (xy 169.714298 -293.133554) (xy 169.728667 -293.119189) (xy 169.747439 -293.111415)
			(xy 169.757598 -293.11092) (xy 171.157138 -293.11092) (xy 171.167296 -293.111402) (xy 171.186063 -293.119185)
			(xy 171.200426 -293.133554) (xy 171.208202 -293.152324) (xy 171.2087 -293.162482) (xy 171.2087 -293.571422)
			(xy 173.149768 -293.571422) (xy 173.149768 -293.162482) (xy 173.15015 -293.152306) (xy 173.157947 -293.133505)
			(xy 173.172345 -293.11912) (xy 173.191153 -293.111341) (xy 173.20133 -293.11092) (xy 174.60087 -293.11092)
			(xy 174.611037 -293.111388) (xy 174.629828 -293.11916) (xy 174.644213 -293.133532) (xy 174.652002 -293.152315)
			(xy 174.652432 -293.162482) (xy 174.652432 -293.571422) (xy 177.249836 -293.571422) (xy 177.249836 -293.162482)
			(xy 177.250318 -293.152323) (xy 177.258098 -293.133554) (xy 177.272467 -293.119189) (xy 177.291239 -293.111415)
			(xy 177.301398 -293.11092) (xy 178.700938 -293.11092) (xy 178.711096 -293.111402) (xy 178.729863 -293.119185)
			(xy 178.744226 -293.133554) (xy 178.752002 -293.152324) (xy 178.7525 -293.162482) (xy 178.7525 -293.571422)
			(xy 180.693568 -293.571422) (xy 180.693568 -293.162482) (xy 180.69395 -293.152306) (xy 180.701747 -293.133505)
			(xy 180.716145 -293.11912) (xy 180.734953 -293.111341) (xy 180.74513 -293.11092) (xy 182.14467 -293.11092)
			(xy 182.154837 -293.111388) (xy 182.173628 -293.11916) (xy 182.188013 -293.133532) (xy 182.195802 -293.152315)
			(xy 182.196232 -293.162482) (xy 182.196232 -293.571422) (xy 184.793636 -293.571422) (xy 184.793636 -293.162482)
			(xy 184.794118 -293.152323) (xy 184.801898 -293.133554) (xy 184.816267 -293.119189) (xy 184.835039 -293.111415)
			(xy 184.845198 -293.11092) (xy 186.244738 -293.11092) (xy 186.254896 -293.111402) (xy 186.273663 -293.119185)
			(xy 186.288026 -293.133554) (xy 186.295802 -293.152324) (xy 186.2963 -293.162482) (xy 186.2963 -293.571422)
			(xy 188.237368 -293.571422) (xy 188.237368 -293.162482) (xy 188.23775 -293.152306) (xy 188.245547 -293.133505)
			(xy 188.259945 -293.11912) (xy 188.278753 -293.111341) (xy 188.28893 -293.11092) (xy 189.68847 -293.11092)
			(xy 189.698637 -293.111388) (xy 189.717428 -293.11916) (xy 189.731813 -293.133532) (xy 189.739602 -293.152315)
			(xy 189.740032 -293.162482) (xy 189.740032 -293.571422) (xy 192.337436 -293.571422) (xy 192.337436 -293.162482)
			(xy 192.337918 -293.152323) (xy 192.345698 -293.133554) (xy 192.360067 -293.119189) (xy 192.378839 -293.111415)
			(xy 192.388998 -293.11092) (xy 193.788538 -293.11092) (xy 193.798696 -293.111402) (xy 193.817463 -293.119185)
			(xy 193.831826 -293.133554) (xy 193.839602 -293.152324) (xy 193.8401 -293.162482) (xy 193.8401 -293.571422)
			(xy 195.781168 -293.571422) (xy 195.781168 -293.162482) (xy 195.78155 -293.152306) (xy 195.789347 -293.133505)
			(xy 195.803745 -293.11912) (xy 195.822553 -293.111341) (xy 195.83273 -293.11092) (xy 197.23227 -293.11092)
			(xy 197.242437 -293.111388) (xy 197.261228 -293.11916) (xy 197.275613 -293.133532) (xy 197.283402 -293.152315)
			(xy 197.283832 -293.162482) (xy 197.283832 -293.571422) (xy 199.881236 -293.571422) (xy 199.881236 -293.162482)
			(xy 199.881718 -293.152323) (xy 199.889498 -293.133554) (xy 199.903867 -293.119189) (xy 199.922639 -293.111415)
			(xy 199.932798 -293.11092) (xy 201.332338 -293.11092) (xy 201.342496 -293.111402) (xy 201.361263 -293.119185)
			(xy 201.375626 -293.133554) (xy 201.383402 -293.152324) (xy 201.3839 -293.162482) (xy 201.3839 -293.571422)
			(xy 203.324968 -293.571422) (xy 203.324968 -293.162482) (xy 203.32535 -293.152306) (xy 203.333147 -293.133505)
			(xy 203.347545 -293.11912) (xy 203.366353 -293.111341) (xy 203.37653 -293.11092) (xy 204.77607 -293.11092)
			(xy 204.786237 -293.111388) (xy 204.805028 -293.11916) (xy 204.819413 -293.133532) (xy 204.827202 -293.152315)
			(xy 204.827632 -293.162482) (xy 204.827632 -293.571422) (xy 207.425036 -293.571422) (xy 207.425036 -293.162482)
			(xy 207.425518 -293.152323) (xy 207.433298 -293.133554) (xy 207.447667 -293.119189) (xy 207.466439 -293.111415)
			(xy 207.476598 -293.11092) (xy 208.876138 -293.11092) (xy 208.886296 -293.111402) (xy 208.905063 -293.119185)
			(xy 208.919426 -293.133554) (xy 208.927202 -293.152324) (xy 208.9277 -293.162482) (xy 208.9277 -293.571422)
			(xy 210.868768 -293.571422) (xy 210.868768 -293.162482) (xy 210.86915 -293.152306) (xy 210.876947 -293.133505)
			(xy 210.891345 -293.11912) (xy 210.910153 -293.111341) (xy 210.92033 -293.11092) (xy 212.31987 -293.11092)
			(xy 212.330037 -293.111388) (xy 212.348828 -293.11916) (xy 212.363213 -293.133532) (xy 212.371002 -293.152315)
			(xy 212.371432 -293.162482) (xy 212.371432 -293.571422) (xy 214.968836 -293.571422) (xy 214.968836 -293.162482)
			(xy 214.969318 -293.152323) (xy 214.977098 -293.133554) (xy 214.991467 -293.119189) (xy 215.010239 -293.111415)
			(xy 215.020398 -293.11092) (xy 216.419938 -293.11092) (xy 216.430096 -293.111402) (xy 216.448863 -293.119185)
			(xy 216.463226 -293.133554) (xy 216.471002 -293.152324) (xy 216.4715 -293.162482) (xy 216.4715 -293.571422)
			(xy 255.329436 -293.571422) (xy 255.329436 -293.162482) (xy 255.329918 -293.152323) (xy 255.337698 -293.133554)
			(xy 255.352067 -293.119189) (xy 255.370839 -293.111415) (xy 255.380998 -293.11092) (xy 256.780538 -293.11092)
			(xy 256.790696 -293.111402) (xy 256.809463 -293.119185) (xy 256.823826 -293.133554) (xy 256.831602 -293.152324)
			(xy 256.8321 -293.162482) (xy 256.8321 -293.571422) (xy 259.429504 -293.571422) (xy 259.429504 -293.162482)
			(xy 259.430018 -293.152327) (xy 259.437792 -293.133564) (xy 259.452151 -293.119201) (xy 259.470911 -293.111421)
			(xy 259.481066 -293.11092) (xy 260.880606 -293.11092) (xy 260.890762 -293.111428) (xy 260.909528 -293.119201)
			(xy 260.923892 -293.133562) (xy 260.931669 -293.152326) (xy 260.932168 -293.162482) (xy 260.932168 -293.571422)
			(xy 262.873236 -293.571422) (xy 262.873236 -293.162482) (xy 262.873718 -293.152323) (xy 262.881498 -293.133554)
			(xy 262.895867 -293.119189) (xy 262.914639 -293.111415) (xy 262.924798 -293.11092) (xy 264.324338 -293.11092)
			(xy 264.334496 -293.111402) (xy 264.353263 -293.119185) (xy 264.367626 -293.133554) (xy 264.375402 -293.152324)
			(xy 264.3759 -293.162482) (xy 264.3759 -293.571422) (xy 266.973304 -293.571422) (xy 266.973304 -293.162482)
			(xy 266.973818 -293.152327) (xy 266.981592 -293.133564) (xy 266.995951 -293.119201) (xy 267.014711 -293.111421)
			(xy 267.024866 -293.11092) (xy 268.424406 -293.11092) (xy 268.434562 -293.111428) (xy 268.453328 -293.119201)
			(xy 268.467692 -293.133562) (xy 268.475469 -293.152326) (xy 268.475968 -293.162482) (xy 268.475968 -293.571422)
			(xy 270.417036 -293.571422) (xy 270.417036 -293.162482) (xy 270.417518 -293.152323) (xy 270.425298 -293.133554)
			(xy 270.439667 -293.119189) (xy 270.458439 -293.111415) (xy 270.468598 -293.11092) (xy 271.868138 -293.11092)
			(xy 271.878296 -293.111402) (xy 271.897063 -293.119185) (xy 271.911426 -293.133554) (xy 271.919202 -293.152324)
			(xy 271.9197 -293.162482) (xy 271.9197 -293.571422) (xy 274.517104 -293.571422) (xy 274.517104 -293.162482)
			(xy 274.517618 -293.152327) (xy 274.525392 -293.133564) (xy 274.539751 -293.119201) (xy 274.558511 -293.111421)
			(xy 274.568666 -293.11092) (xy 275.968206 -293.11092) (xy 275.978362 -293.111428) (xy 275.997128 -293.119201)
			(xy 276.011492 -293.133562) (xy 276.019269 -293.152326) (xy 276.019768 -293.162482) (xy 276.019768 -293.571422)
			(xy 277.960836 -293.571422) (xy 277.960836 -293.162482) (xy 277.961318 -293.152323) (xy 277.969098 -293.133554)
			(xy 277.983467 -293.119189) (xy 278.002239 -293.111415) (xy 278.012398 -293.11092) (xy 279.411938 -293.11092)
			(xy 279.422096 -293.111402) (xy 279.440863 -293.119185) (xy 279.455226 -293.133554) (xy 279.463002 -293.152324)
			(xy 279.4635 -293.162482) (xy 279.4635 -293.571422) (xy 282.060904 -293.571422) (xy 282.060904 -293.162482)
			(xy 282.061418 -293.152327) (xy 282.069192 -293.133564) (xy 282.083551 -293.119201) (xy 282.102311 -293.111421)
			(xy 282.112466 -293.11092) (xy 283.512006 -293.11092) (xy 283.522162 -293.111428) (xy 283.540928 -293.119201)
			(xy 283.555292 -293.133562) (xy 283.563069 -293.152326) (xy 283.563568 -293.162482) (xy 283.563568 -293.571422)
			(xy 285.504636 -293.571422) (xy 285.504636 -293.162482) (xy 285.505118 -293.152323) (xy 285.512898 -293.133554)
			(xy 285.527267 -293.119189) (xy 285.546039 -293.111415) (xy 285.556198 -293.11092) (xy 286.955738 -293.11092)
			(xy 286.965896 -293.111402) (xy 286.984663 -293.119185) (xy 286.999026 -293.133554) (xy 287.006802 -293.152324)
			(xy 287.0073 -293.162482) (xy 287.0073 -293.571422) (xy 289.604704 -293.571422) (xy 289.604704 -293.162482)
			(xy 289.605218 -293.152327) (xy 289.612992 -293.133564) (xy 289.627351 -293.119201) (xy 289.646111 -293.111421)
			(xy 289.656266 -293.11092) (xy 291.055806 -293.11092) (xy 291.065962 -293.111428) (xy 291.084728 -293.119201)
			(xy 291.099092 -293.133562) (xy 291.106869 -293.152326) (xy 291.107368 -293.162482) (xy 291.107368 -293.571422)
			(xy 293.048436 -293.571422) (xy 293.048436 -293.162482) (xy 293.048918 -293.152323) (xy 293.056698 -293.133554)
			(xy 293.071067 -293.119189) (xy 293.089839 -293.111415) (xy 293.099998 -293.11092) (xy 294.499538 -293.11092)
			(xy 294.509696 -293.111402) (xy 294.528463 -293.119185) (xy 294.542826 -293.133554) (xy 294.550602 -293.152324)
			(xy 294.5511 -293.162482) (xy 294.5511 -293.571422) (xy 297.148504 -293.571422) (xy 297.148504 -293.162482)
			(xy 297.149018 -293.152327) (xy 297.156792 -293.133564) (xy 297.171151 -293.119201) (xy 297.189911 -293.111421)
			(xy 297.200066 -293.11092) (xy 298.599606 -293.11092) (xy 298.609762 -293.111428) (xy 298.628528 -293.119201)
			(xy 298.642892 -293.133562) (xy 298.650669 -293.152326) (xy 298.651168 -293.162482) (xy 298.651168 -293.571422)
			(xy 300.592236 -293.571422) (xy 300.592236 -293.162482) (xy 300.592718 -293.152323) (xy 300.600498 -293.133554)
			(xy 300.614867 -293.119189) (xy 300.633639 -293.111415) (xy 300.643798 -293.11092) (xy 302.043338 -293.11092)
			(xy 302.053496 -293.111402) (xy 302.072263 -293.119185) (xy 302.086626 -293.133554) (xy 302.094402 -293.152324)
			(xy 302.0949 -293.162482) (xy 302.0949 -293.571422) (xy 304.692304 -293.571422) (xy 304.692304 -293.162482)
			(xy 304.692818 -293.152327) (xy 304.700592 -293.133564) (xy 304.714951 -293.119201) (xy 304.733711 -293.111421)
			(xy 304.743866 -293.11092) (xy 306.143406 -293.11092) (xy 306.153562 -293.111428) (xy 306.172328 -293.119201)
			(xy 306.186692 -293.133562) (xy 306.194469 -293.152326) (xy 306.194968 -293.162482) (xy 306.194968 -293.571422)
			(xy 308.136036 -293.571422) (xy 308.136036 -293.162482) (xy 308.136518 -293.152323) (xy 308.144298 -293.133554)
			(xy 308.158667 -293.119189) (xy 308.177439 -293.111415) (xy 308.187598 -293.11092) (xy 309.587138 -293.11092)
			(xy 309.597296 -293.111402) (xy 309.616063 -293.119185) (xy 309.630426 -293.133554) (xy 309.638202 -293.152324)
			(xy 309.6387 -293.162482) (xy 309.6387 -293.571422) (xy 312.236104 -293.571422) (xy 312.236104 -293.162482)
			(xy 312.236618 -293.152327) (xy 312.244392 -293.133564) (xy 312.258751 -293.119201) (xy 312.277511 -293.111421)
			(xy 312.287666 -293.11092) (xy 313.687206 -293.11092) (xy 313.697362 -293.111428) (xy 313.716128 -293.119201)
			(xy 313.730492 -293.133562) (xy 313.738269 -293.152326) (xy 313.738768 -293.162482) (xy 313.738768 -293.571422)
			(xy 406.002236 -293.571422) (xy 406.002236 -293.162482) (xy 406.002718 -293.152323) (xy 406.010498 -293.133554)
			(xy 406.024867 -293.119189) (xy 406.043639 -293.111415) (xy 406.053798 -293.11092) (xy 407.453338 -293.11092)
			(xy 407.463496 -293.111402) (xy 407.482263 -293.119185) (xy 407.496626 -293.133554) (xy 407.504402 -293.152324)
			(xy 407.5049 -293.162482) (xy 407.5049 -293.571422) (xy 410.102304 -293.571422) (xy 410.102304 -293.162482)
			(xy 410.102818 -293.152327) (xy 410.110592 -293.133564) (xy 410.124951 -293.119201) (xy 410.143711 -293.111421)
			(xy 410.153866 -293.11092) (xy 411.553406 -293.11092) (xy 411.563562 -293.111428) (xy 411.582328 -293.119201)
			(xy 411.596692 -293.133562) (xy 411.604469 -293.152326) (xy 411.604968 -293.162482) (xy 411.604968 -293.571422)
			(xy 413.546036 -293.571422) (xy 413.546036 -293.162482) (xy 413.546518 -293.152323) (xy 413.554298 -293.133554)
			(xy 413.568667 -293.119189) (xy 413.587439 -293.111415) (xy 413.597598 -293.11092) (xy 414.997138 -293.11092)
			(xy 415.007296 -293.111402) (xy 415.026063 -293.119185) (xy 415.040426 -293.133554) (xy 415.048202 -293.152324)
			(xy 415.0487 -293.162482) (xy 415.0487 -293.571422) (xy 417.646104 -293.571422) (xy 417.646104 -293.162482)
			(xy 417.646618 -293.152327) (xy 417.654392 -293.133564) (xy 417.668751 -293.119201) (xy 417.687511 -293.111421)
			(xy 417.697666 -293.11092) (xy 419.097206 -293.11092) (xy 419.107362 -293.111428) (xy 419.126128 -293.119201)
			(xy 419.140492 -293.133562) (xy 419.148269 -293.152326) (xy 419.148768 -293.162482) (xy 419.148768 -293.571422)
			(xy 421.089836 -293.571422) (xy 421.089836 -293.162482) (xy 421.090318 -293.152323) (xy 421.098098 -293.133554)
			(xy 421.112467 -293.119189) (xy 421.131239 -293.111415) (xy 421.141398 -293.11092) (xy 422.540938 -293.11092)
			(xy 422.551096 -293.111402) (xy 422.569863 -293.119185) (xy 422.584226 -293.133554) (xy 422.592002 -293.152324)
			(xy 422.5925 -293.162482) (xy 422.5925 -293.571422) (xy 425.189904 -293.571422) (xy 425.189904 -293.162482)
			(xy 425.190418 -293.152327) (xy 425.198192 -293.133564) (xy 425.212551 -293.119201) (xy 425.231311 -293.111421)
			(xy 425.241466 -293.11092) (xy 426.641006 -293.11092) (xy 426.651162 -293.111428) (xy 426.669928 -293.119201)
			(xy 426.684292 -293.133562) (xy 426.692069 -293.152326) (xy 426.692568 -293.162482) (xy 426.692568 -293.571422)
			(xy 428.633636 -293.571422) (xy 428.633636 -293.162482) (xy 428.634118 -293.152323) (xy 428.641898 -293.133554)
			(xy 428.656267 -293.119189) (xy 428.675039 -293.111415) (xy 428.685198 -293.11092) (xy 430.084738 -293.11092)
			(xy 430.094896 -293.111402) (xy 430.113663 -293.119185) (xy 430.128026 -293.133554) (xy 430.135802 -293.152324)
			(xy 430.1363 -293.162482) (xy 430.1363 -293.571422) (xy 432.733704 -293.571422) (xy 432.733704 -293.162482)
			(xy 432.734218 -293.152327) (xy 432.741992 -293.133564) (xy 432.756351 -293.119201) (xy 432.775111 -293.111421)
			(xy 432.785266 -293.11092) (xy 434.184806 -293.11092) (xy 434.194962 -293.111428) (xy 434.213728 -293.119201)
			(xy 434.228092 -293.133562) (xy 434.235869 -293.152326) (xy 434.236368 -293.162482) (xy 434.236368 -293.571422)
			(xy 436.177436 -293.571422) (xy 436.177436 -293.162482) (xy 436.177918 -293.152323) (xy 436.185698 -293.133554)
			(xy 436.200067 -293.119189) (xy 436.218839 -293.111415) (xy 436.228998 -293.11092) (xy 437.628538 -293.11092)
			(xy 437.638696 -293.111402) (xy 437.657463 -293.119185) (xy 437.671826 -293.133554) (xy 437.679602 -293.152324)
			(xy 437.6801 -293.162482) (xy 437.6801 -293.571422) (xy 440.277504 -293.571422) (xy 440.277504 -293.162482)
			(xy 440.278018 -293.152327) (xy 440.285792 -293.133564) (xy 440.300151 -293.119201) (xy 440.318911 -293.111421)
			(xy 440.329066 -293.11092) (xy 441.728606 -293.11092) (xy 441.738762 -293.111428) (xy 441.757528 -293.119201)
			(xy 441.771892 -293.133562) (xy 441.779669 -293.152326) (xy 441.780168 -293.162482) (xy 441.780168 -293.571422)
			(xy 443.721236 -293.571422) (xy 443.721236 -293.162482) (xy 443.721718 -293.152323) (xy 443.729498 -293.133554)
			(xy 443.743867 -293.119189) (xy 443.762639 -293.111415) (xy 443.772798 -293.11092) (xy 445.172338 -293.11092)
			(xy 445.182496 -293.111402) (xy 445.201263 -293.119185) (xy 445.215626 -293.133554) (xy 445.223402 -293.152324)
			(xy 445.2239 -293.162482) (xy 445.2239 -293.571422) (xy 447.821304 -293.571422) (xy 447.821304 -293.162482)
			(xy 447.821818 -293.152327) (xy 447.829592 -293.133564) (xy 447.843951 -293.119201) (xy 447.862711 -293.111421)
			(xy 447.872866 -293.11092) (xy 449.272406 -293.11092) (xy 449.282562 -293.111428) (xy 449.301328 -293.119201)
			(xy 449.315692 -293.133562) (xy 449.323469 -293.152326) (xy 449.323968 -293.162482) (xy 449.323968 -293.571422)
			(xy 451.265036 -293.571422) (xy 451.265036 -293.162482) (xy 451.265518 -293.152323) (xy 451.273298 -293.133554)
			(xy 451.287667 -293.119189) (xy 451.306439 -293.111415) (xy 451.316598 -293.11092) (xy 452.716138 -293.11092)
			(xy 452.726296 -293.111402) (xy 452.745063 -293.119185) (xy 452.759426 -293.133554) (xy 452.767202 -293.152324)
			(xy 452.7677 -293.162482) (xy 452.7677 -293.571422) (xy 455.365104 -293.571422) (xy 455.365104 -293.162482)
			(xy 455.365618 -293.152327) (xy 455.373392 -293.133564) (xy 455.387751 -293.119201) (xy 455.406511 -293.111421)
			(xy 455.416666 -293.11092) (xy 456.816206 -293.11092) (xy 456.826362 -293.111428) (xy 456.845128 -293.119201)
			(xy 456.859492 -293.133562) (xy 456.867269 -293.152326) (xy 456.867768 -293.162482) (xy 456.867768 -293.571422)
			(xy 458.808836 -293.571422) (xy 458.808836 -293.162482) (xy 458.809318 -293.152323) (xy 458.817098 -293.133554)
			(xy 458.831467 -293.119189) (xy 458.850239 -293.111415) (xy 458.860398 -293.11092) (xy 460.259938 -293.11092)
			(xy 460.270096 -293.111402) (xy 460.288863 -293.119185) (xy 460.303226 -293.133554) (xy 460.311002 -293.152324)
			(xy 460.3115 -293.162482) (xy 460.3115 -293.571422) (xy 462.908904 -293.571422) (xy 462.908904 -293.162482)
			(xy 462.909418 -293.152327) (xy 462.917192 -293.133564) (xy 462.931551 -293.119201) (xy 462.950311 -293.111421)
			(xy 462.960466 -293.11092) (xy 464.360006 -293.11092) (xy 464.370162 -293.111428) (xy 464.388928 -293.119201)
			(xy 464.403292 -293.133562) (xy 464.411069 -293.152326) (xy 464.411568 -293.162482) (xy 464.411568 -293.571422)
			(xy 464.411085 -293.58158) (xy 464.403304 -293.600349) (xy 464.388936 -293.614713) (xy 464.370165 -293.622488)
			(xy 464.360006 -293.622984) (xy 462.960466 -293.622984) (xy 462.950309 -293.622495) (xy 462.931543 -293.614714)
			(xy 462.91718 -293.600347) (xy 462.909403 -293.581579) (xy 462.908904 -293.571422) (xy 460.3115 -293.571422)
			(xy 460.310986 -293.581577) (xy 460.303211 -293.600339) (xy 460.288852 -293.614702) (xy 460.270092 -293.622483)
			(xy 460.259938 -293.622984) (xy 458.860398 -293.622984) (xy 458.850243 -293.622469) (xy 458.831478 -293.614698)
			(xy 458.817113 -293.600339) (xy 458.809335 -293.581577) (xy 458.808836 -293.571422) (xy 456.867768 -293.571422)
			(xy 456.867285 -293.58158) (xy 456.859504 -293.600349) (xy 456.845136 -293.614713) (xy 456.826365 -293.622488)
			(xy 456.816206 -293.622984) (xy 455.416666 -293.622984) (xy 455.406509 -293.622495) (xy 455.387743 -293.614714)
			(xy 455.37338 -293.600347) (xy 455.365603 -293.581579) (xy 455.365104 -293.571422) (xy 452.7677 -293.571422)
			(xy 452.767186 -293.581577) (xy 452.759411 -293.600339) (xy 452.745052 -293.614702) (xy 452.726292 -293.622483)
			(xy 452.716138 -293.622984) (xy 451.316598 -293.622984) (xy 451.306443 -293.622469) (xy 451.287678 -293.614698)
			(xy 451.273313 -293.600339) (xy 451.265535 -293.581577) (xy 451.265036 -293.571422) (xy 449.323968 -293.571422)
			(xy 449.323485 -293.58158) (xy 449.315704 -293.600349) (xy 449.301336 -293.614713) (xy 449.282565 -293.622488)
			(xy 449.272406 -293.622984) (xy 447.872866 -293.622984) (xy 447.862709 -293.622495) (xy 447.843943 -293.614714)
			(xy 447.82958 -293.600347) (xy 447.821803 -293.581579) (xy 447.821304 -293.571422) (xy 445.2239 -293.571422)
			(xy 445.223386 -293.581577) (xy 445.215611 -293.600339) (xy 445.201252 -293.614702) (xy 445.182492 -293.622483)
			(xy 445.172338 -293.622984) (xy 443.772798 -293.622984) (xy 443.762643 -293.622469) (xy 443.743878 -293.614698)
			(xy 443.729513 -293.600339) (xy 443.721735 -293.581577) (xy 443.721236 -293.571422) (xy 441.780168 -293.571422)
			(xy 441.779685 -293.58158) (xy 441.771904 -293.600349) (xy 441.757536 -293.614713) (xy 441.738765 -293.622488)
			(xy 441.728606 -293.622984) (xy 440.329066 -293.622984) (xy 440.318909 -293.622495) (xy 440.300143 -293.614714)
			(xy 440.28578 -293.600347) (xy 440.278003 -293.581579) (xy 440.277504 -293.571422) (xy 437.6801 -293.571422)
			(xy 437.679586 -293.581577) (xy 437.671811 -293.600339) (xy 437.657452 -293.614702) (xy 437.638692 -293.622483)
			(xy 437.628538 -293.622984) (xy 436.228998 -293.622984) (xy 436.218843 -293.622469) (xy 436.200078 -293.614698)
			(xy 436.185713 -293.600339) (xy 436.177935 -293.581577) (xy 436.177436 -293.571422) (xy 434.236368 -293.571422)
			(xy 434.235885 -293.58158) (xy 434.228104 -293.600349) (xy 434.213736 -293.614713) (xy 434.194965 -293.622488)
			(xy 434.184806 -293.622984) (xy 432.785266 -293.622984) (xy 432.775109 -293.622495) (xy 432.756343 -293.614714)
			(xy 432.74198 -293.600347) (xy 432.734203 -293.581579) (xy 432.733704 -293.571422) (xy 430.1363 -293.571422)
			(xy 430.135786 -293.581577) (xy 430.128011 -293.600339) (xy 430.113652 -293.614702) (xy 430.094892 -293.622483)
			(xy 430.084738 -293.622984) (xy 428.685198 -293.622984) (xy 428.675043 -293.622469) (xy 428.656278 -293.614698)
			(xy 428.641913 -293.600339) (xy 428.634135 -293.581577) (xy 428.633636 -293.571422) (xy 426.692568 -293.571422)
			(xy 426.692085 -293.58158) (xy 426.684304 -293.600349) (xy 426.669936 -293.614713) (xy 426.651165 -293.622488)
			(xy 426.641006 -293.622984) (xy 425.241466 -293.622984) (xy 425.231309 -293.622495) (xy 425.212543 -293.614714)
			(xy 425.19818 -293.600347) (xy 425.190403 -293.581579) (xy 425.189904 -293.571422) (xy 422.5925 -293.571422)
			(xy 422.591986 -293.581577) (xy 422.584211 -293.600339) (xy 422.569852 -293.614702) (xy 422.551092 -293.622483)
			(xy 422.540938 -293.622984) (xy 421.141398 -293.622984) (xy 421.131243 -293.622469) (xy 421.112478 -293.614698)
			(xy 421.098113 -293.600339) (xy 421.090335 -293.581577) (xy 421.089836 -293.571422) (xy 419.148768 -293.571422)
			(xy 419.148285 -293.58158) (xy 419.140504 -293.600349) (xy 419.126136 -293.614713) (xy 419.107365 -293.622488)
			(xy 419.097206 -293.622984) (xy 417.697666 -293.622984) (xy 417.687509 -293.622495) (xy 417.668743 -293.614714)
			(xy 417.65438 -293.600347) (xy 417.646603 -293.581579) (xy 417.646104 -293.571422) (xy 415.0487 -293.571422)
			(xy 415.048186 -293.581577) (xy 415.040411 -293.600339) (xy 415.026052 -293.614702) (xy 415.007292 -293.622483)
			(xy 414.997138 -293.622984) (xy 413.597598 -293.622984) (xy 413.587443 -293.622469) (xy 413.568678 -293.614698)
			(xy 413.554313 -293.600339) (xy 413.546535 -293.581577) (xy 413.546036 -293.571422) (xy 411.604968 -293.571422)
			(xy 411.604485 -293.58158) (xy 411.596704 -293.600349) (xy 411.582336 -293.614713) (xy 411.563565 -293.622488)
			(xy 411.553406 -293.622984) (xy 410.153866 -293.622984) (xy 410.143709 -293.622495) (xy 410.124943 -293.614714)
			(xy 410.11058 -293.600347) (xy 410.102803 -293.581579) (xy 410.102304 -293.571422) (xy 407.5049 -293.571422)
			(xy 407.504386 -293.581577) (xy 407.496611 -293.600339) (xy 407.482252 -293.614702) (xy 407.463492 -293.622483)
			(xy 407.453338 -293.622984) (xy 406.053798 -293.622984) (xy 406.043643 -293.622469) (xy 406.024878 -293.614698)
			(xy 406.010513 -293.600339) (xy 406.002735 -293.581577) (xy 406.002236 -293.571422) (xy 313.738768 -293.571422)
			(xy 313.738285 -293.58158) (xy 313.730504 -293.600349) (xy 313.716136 -293.614713) (xy 313.697365 -293.622488)
			(xy 313.687206 -293.622984) (xy 312.287666 -293.622984) (xy 312.277509 -293.622495) (xy 312.258743 -293.614714)
			(xy 312.24438 -293.600347) (xy 312.236603 -293.581579) (xy 312.236104 -293.571422) (xy 309.6387 -293.571422)
			(xy 309.638186 -293.581577) (xy 309.630411 -293.600339) (xy 309.616052 -293.614702) (xy 309.597292 -293.622483)
			(xy 309.587138 -293.622984) (xy 308.187598 -293.622984) (xy 308.177443 -293.622469) (xy 308.158678 -293.614698)
			(xy 308.144313 -293.600339) (xy 308.136535 -293.581577) (xy 308.136036 -293.571422) (xy 306.194968 -293.571422)
			(xy 306.194485 -293.58158) (xy 306.186704 -293.600349) (xy 306.172336 -293.614713) (xy 306.153565 -293.622488)
			(xy 306.143406 -293.622984) (xy 304.743866 -293.622984) (xy 304.733709 -293.622495) (xy 304.714943 -293.614714)
			(xy 304.70058 -293.600347) (xy 304.692803 -293.581579) (xy 304.692304 -293.571422) (xy 302.0949 -293.571422)
			(xy 302.094386 -293.581577) (xy 302.086611 -293.600339) (xy 302.072252 -293.614702) (xy 302.053492 -293.622483)
			(xy 302.043338 -293.622984) (xy 300.643798 -293.622984) (xy 300.633643 -293.622469) (xy 300.614878 -293.614698)
			(xy 300.600513 -293.600339) (xy 300.592735 -293.581577) (xy 300.592236 -293.571422) (xy 298.651168 -293.571422)
			(xy 298.650685 -293.58158) (xy 298.642904 -293.600349) (xy 298.628536 -293.614713) (xy 298.609765 -293.622488)
			(xy 298.599606 -293.622984) (xy 297.200066 -293.622984) (xy 297.189909 -293.622495) (xy 297.171143 -293.614714)
			(xy 297.15678 -293.600347) (xy 297.149003 -293.581579) (xy 297.148504 -293.571422) (xy 294.5511 -293.571422)
			(xy 294.550586 -293.581577) (xy 294.542811 -293.600339) (xy 294.528452 -293.614702) (xy 294.509692 -293.622483)
			(xy 294.499538 -293.622984) (xy 293.099998 -293.622984) (xy 293.089843 -293.622469) (xy 293.071078 -293.614698)
			(xy 293.056713 -293.600339) (xy 293.048935 -293.581577) (xy 293.048436 -293.571422) (xy 291.107368 -293.571422)
			(xy 291.106885 -293.58158) (xy 291.099104 -293.600349) (xy 291.084736 -293.614713) (xy 291.065965 -293.622488)
			(xy 291.055806 -293.622984) (xy 289.656266 -293.622984) (xy 289.646109 -293.622495) (xy 289.627343 -293.614714)
			(xy 289.61298 -293.600347) (xy 289.605203 -293.581579) (xy 289.604704 -293.571422) (xy 287.0073 -293.571422)
			(xy 287.006786 -293.581577) (xy 286.999011 -293.600339) (xy 286.984652 -293.614702) (xy 286.965892 -293.622483)
			(xy 286.955738 -293.622984) (xy 285.556198 -293.622984) (xy 285.546043 -293.622469) (xy 285.527278 -293.614698)
			(xy 285.512913 -293.600339) (xy 285.505135 -293.581577) (xy 285.504636 -293.571422) (xy 283.563568 -293.571422)
			(xy 283.563085 -293.58158) (xy 283.555304 -293.600349) (xy 283.540936 -293.614713) (xy 283.522165 -293.622488)
			(xy 283.512006 -293.622984) (xy 282.112466 -293.622984) (xy 282.102309 -293.622495) (xy 282.083543 -293.614714)
			(xy 282.06918 -293.600347) (xy 282.061403 -293.581579) (xy 282.060904 -293.571422) (xy 279.4635 -293.571422)
			(xy 279.462986 -293.581577) (xy 279.455211 -293.600339) (xy 279.440852 -293.614702) (xy 279.422092 -293.622483)
			(xy 279.411938 -293.622984) (xy 278.012398 -293.622984) (xy 278.002243 -293.622469) (xy 277.983478 -293.614698)
			(xy 277.969113 -293.600339) (xy 277.961335 -293.581577) (xy 277.960836 -293.571422) (xy 276.019768 -293.571422)
			(xy 276.019285 -293.58158) (xy 276.011504 -293.600349) (xy 275.997136 -293.614713) (xy 275.978365 -293.622488)
			(xy 275.968206 -293.622984) (xy 274.568666 -293.622984) (xy 274.558509 -293.622495) (xy 274.539743 -293.614714)
			(xy 274.52538 -293.600347) (xy 274.517603 -293.581579) (xy 274.517104 -293.571422) (xy 271.9197 -293.571422)
			(xy 271.919186 -293.581577) (xy 271.911411 -293.600339) (xy 271.897052 -293.614702) (xy 271.878292 -293.622483)
			(xy 271.868138 -293.622984) (xy 270.468598 -293.622984) (xy 270.458443 -293.622469) (xy 270.439678 -293.614698)
			(xy 270.425313 -293.600339) (xy 270.417535 -293.581577) (xy 270.417036 -293.571422) (xy 268.475968 -293.571422)
			(xy 268.475485 -293.58158) (xy 268.467704 -293.600349) (xy 268.453336 -293.614713) (xy 268.434565 -293.622488)
			(xy 268.424406 -293.622984) (xy 267.024866 -293.622984) (xy 267.014709 -293.622495) (xy 266.995943 -293.614714)
			(xy 266.98158 -293.600347) (xy 266.973803 -293.581579) (xy 266.973304 -293.571422) (xy 264.3759 -293.571422)
			(xy 264.375386 -293.581577) (xy 264.367611 -293.600339) (xy 264.353252 -293.614702) (xy 264.334492 -293.622483)
			(xy 264.324338 -293.622984) (xy 262.924798 -293.622984) (xy 262.914643 -293.622469) (xy 262.895878 -293.614698)
			(xy 262.881513 -293.600339) (xy 262.873735 -293.581577) (xy 262.873236 -293.571422) (xy 260.932168 -293.571422)
			(xy 260.931685 -293.58158) (xy 260.923904 -293.600349) (xy 260.909536 -293.614713) (xy 260.890765 -293.622488)
			(xy 260.880606 -293.622984) (xy 259.481066 -293.622984) (xy 259.470909 -293.622495) (xy 259.452143 -293.614714)
			(xy 259.43778 -293.600347) (xy 259.430003 -293.581579) (xy 259.429504 -293.571422) (xy 256.8321 -293.571422)
			(xy 256.831586 -293.581577) (xy 256.823811 -293.600339) (xy 256.809452 -293.614702) (xy 256.790692 -293.622483)
			(xy 256.780538 -293.622984) (xy 255.380998 -293.622984) (xy 255.370843 -293.622469) (xy 255.352078 -293.614698)
			(xy 255.337713 -293.600339) (xy 255.329935 -293.581577) (xy 255.329436 -293.571422) (xy 216.4715 -293.571422)
			(xy 216.470986 -293.581577) (xy 216.463211 -293.600339) (xy 216.448852 -293.614702) (xy 216.430092 -293.622483)
			(xy 216.419938 -293.622984) (xy 215.020398 -293.622984) (xy 215.010243 -293.622469) (xy 214.991478 -293.614698)
			(xy 214.977113 -293.600339) (xy 214.969335 -293.581577) (xy 214.968836 -293.571422) (xy 212.371432 -293.571422)
			(xy 212.371053 -293.581599) (xy 212.363255 -293.6004) (xy 212.348856 -293.614785) (xy 212.330047 -293.622563)
			(xy 212.31987 -293.622984) (xy 210.92033 -293.622984) (xy 210.910163 -293.622512) (xy 210.891373 -293.614741)
			(xy 210.876988 -293.60037) (xy 210.869198 -293.581588) (xy 210.868768 -293.571422) (xy 208.9277 -293.571422)
			(xy 208.927186 -293.581577) (xy 208.919411 -293.600339) (xy 208.905052 -293.614702) (xy 208.886292 -293.622483)
			(xy 208.876138 -293.622984) (xy 207.476598 -293.622984) (xy 207.466443 -293.622469) (xy 207.447678 -293.614698)
			(xy 207.433313 -293.600339) (xy 207.425535 -293.581577) (xy 207.425036 -293.571422) (xy 204.827632 -293.571422)
			(xy 204.827253 -293.581599) (xy 204.819455 -293.6004) (xy 204.805056 -293.614785) (xy 204.786247 -293.622563)
			(xy 204.77607 -293.622984) (xy 203.37653 -293.622984) (xy 203.366363 -293.622512) (xy 203.347573 -293.614741)
			(xy 203.333188 -293.60037) (xy 203.325398 -293.581588) (xy 203.324968 -293.571422) (xy 201.3839 -293.571422)
			(xy 201.383386 -293.581577) (xy 201.375611 -293.600339) (xy 201.361252 -293.614702) (xy 201.342492 -293.622483)
			(xy 201.332338 -293.622984) (xy 199.932798 -293.622984) (xy 199.922643 -293.622469) (xy 199.903878 -293.614698)
			(xy 199.889513 -293.600339) (xy 199.881735 -293.581577) (xy 199.881236 -293.571422) (xy 197.283832 -293.571422)
			(xy 197.283453 -293.581599) (xy 197.275655 -293.6004) (xy 197.261256 -293.614785) (xy 197.242447 -293.622563)
			(xy 197.23227 -293.622984) (xy 195.83273 -293.622984) (xy 195.822563 -293.622512) (xy 195.803773 -293.614741)
			(xy 195.789388 -293.60037) (xy 195.781598 -293.581588) (xy 195.781168 -293.571422) (xy 193.8401 -293.571422)
			(xy 193.839586 -293.581577) (xy 193.831811 -293.600339) (xy 193.817452 -293.614702) (xy 193.798692 -293.622483)
			(xy 193.788538 -293.622984) (xy 192.388998 -293.622984) (xy 192.378843 -293.622469) (xy 192.360078 -293.614698)
			(xy 192.345713 -293.600339) (xy 192.337935 -293.581577) (xy 192.337436 -293.571422) (xy 189.740032 -293.571422)
			(xy 189.739653 -293.581599) (xy 189.731855 -293.6004) (xy 189.717456 -293.614785) (xy 189.698647 -293.622563)
			(xy 189.68847 -293.622984) (xy 188.28893 -293.622984) (xy 188.278763 -293.622512) (xy 188.259973 -293.614741)
			(xy 188.245588 -293.60037) (xy 188.237798 -293.581588) (xy 188.237368 -293.571422) (xy 186.2963 -293.571422)
			(xy 186.295786 -293.581577) (xy 186.288011 -293.600339) (xy 186.273652 -293.614702) (xy 186.254892 -293.622483)
			(xy 186.244738 -293.622984) (xy 184.845198 -293.622984) (xy 184.835043 -293.622469) (xy 184.816278 -293.614698)
			(xy 184.801913 -293.600339) (xy 184.794135 -293.581577) (xy 184.793636 -293.571422) (xy 182.196232 -293.571422)
			(xy 182.195853 -293.581599) (xy 182.188055 -293.6004) (xy 182.173656 -293.614785) (xy 182.154847 -293.622563)
			(xy 182.14467 -293.622984) (xy 180.74513 -293.622984) (xy 180.734963 -293.622512) (xy 180.716173 -293.614741)
			(xy 180.701788 -293.60037) (xy 180.693998 -293.581588) (xy 180.693568 -293.571422) (xy 178.7525 -293.571422)
			(xy 178.751986 -293.581577) (xy 178.744211 -293.600339) (xy 178.729852 -293.614702) (xy 178.711092 -293.622483)
			(xy 178.700938 -293.622984) (xy 177.301398 -293.622984) (xy 177.291243 -293.622469) (xy 177.272478 -293.614698)
			(xy 177.258113 -293.600339) (xy 177.250335 -293.581577) (xy 177.249836 -293.571422) (xy 174.652432 -293.571422)
			(xy 174.652053 -293.581599) (xy 174.644255 -293.6004) (xy 174.629856 -293.614785) (xy 174.611047 -293.622563)
			(xy 174.60087 -293.622984) (xy 173.20133 -293.622984) (xy 173.191163 -293.622512) (xy 173.172373 -293.614741)
			(xy 173.157988 -293.60037) (xy 173.150198 -293.581588) (xy 173.149768 -293.571422) (xy 171.2087 -293.571422)
			(xy 171.208186 -293.581577) (xy 171.200411 -293.600339) (xy 171.186052 -293.614702) (xy 171.167292 -293.622483)
			(xy 171.157138 -293.622984) (xy 169.757598 -293.622984) (xy 169.747443 -293.622469) (xy 169.728678 -293.614698)
			(xy 169.714313 -293.600339) (xy 169.706535 -293.581577) (xy 169.706036 -293.571422) (xy 167.108632 -293.571422)
			(xy 167.108253 -293.581599) (xy 167.100455 -293.6004) (xy 167.086056 -293.614785) (xy 167.067247 -293.622563)
			(xy 167.05707 -293.622984) (xy 165.65753 -293.622984) (xy 165.647363 -293.622512) (xy 165.628573 -293.614741)
			(xy 165.614188 -293.60037) (xy 165.606398 -293.581588) (xy 165.605968 -293.571422) (xy 163.6649 -293.571422)
			(xy 163.664386 -293.581577) (xy 163.656611 -293.600339) (xy 163.642252 -293.614702) (xy 163.623492 -293.622483)
			(xy 163.613338 -293.622984) (xy 162.213798 -293.622984) (xy 162.203643 -293.622469) (xy 162.184878 -293.614698)
			(xy 162.170513 -293.600339) (xy 162.162735 -293.581577) (xy 162.162236 -293.571422) (xy 159.564832 -293.571422)
			(xy 159.564453 -293.581599) (xy 159.556655 -293.6004) (xy 159.542256 -293.614785) (xy 159.523447 -293.622563)
			(xy 159.51327 -293.622984) (xy 158.11373 -293.622984) (xy 158.103563 -293.622512) (xy 158.084773 -293.614741)
			(xy 158.070388 -293.60037) (xy 158.062598 -293.581588) (xy 158.062168 -293.571422) (xy 65.7987 -293.571422)
			(xy 65.798186 -293.581577) (xy 65.790411 -293.600339) (xy 65.776052 -293.614702) (xy 65.757292 -293.622483)
			(xy 65.747138 -293.622984) (xy 64.347598 -293.622984) (xy 64.337443 -293.622469) (xy 64.318678 -293.614698)
			(xy 64.304313 -293.600339) (xy 64.296535 -293.581577) (xy 64.296036 -293.571422) (xy 61.698632 -293.571422)
			(xy 61.698253 -293.581599) (xy 61.690455 -293.6004) (xy 61.676056 -293.614785) (xy 61.657247 -293.622563)
			(xy 61.64707 -293.622984) (xy 60.24753 -293.622984) (xy 60.237363 -293.622512) (xy 60.218573 -293.614741)
			(xy 60.204188 -293.60037) (xy 60.196398 -293.581588) (xy 60.195968 -293.571422) (xy 58.2549 -293.571422)
			(xy 58.254386 -293.581577) (xy 58.246611 -293.600339) (xy 58.232252 -293.614702) (xy 58.213492 -293.622483)
			(xy 58.203338 -293.622984) (xy 56.803798 -293.622984) (xy 56.793643 -293.622469) (xy 56.774878 -293.614698)
			(xy 56.760513 -293.600339) (xy 56.752735 -293.581577) (xy 56.752236 -293.571422) (xy 54.154832 -293.571422)
			(xy 54.154453 -293.581599) (xy 54.146655 -293.6004) (xy 54.132256 -293.614785) (xy 54.113447 -293.622563)
			(xy 54.10327 -293.622984) (xy 52.70373 -293.622984) (xy 52.693563 -293.622512) (xy 52.674773 -293.614741)
			(xy 52.660388 -293.60037) (xy 52.652598 -293.581588) (xy 52.652168 -293.571422) (xy 50.7111 -293.571422)
			(xy 50.710586 -293.581577) (xy 50.702811 -293.600339) (xy 50.688452 -293.614702) (xy 50.669692 -293.622483)
			(xy 50.659538 -293.622984) (xy 49.259998 -293.622984) (xy 49.249843 -293.622469) (xy 49.231078 -293.614698)
			(xy 49.216713 -293.600339) (xy 49.208935 -293.581577) (xy 49.208436 -293.571422) (xy 46.611032 -293.571422)
			(xy 46.610653 -293.581599) (xy 46.602855 -293.6004) (xy 46.588456 -293.614785) (xy 46.569647 -293.622563)
			(xy 46.55947 -293.622984) (xy 45.15993 -293.622984) (xy 45.149763 -293.622512) (xy 45.130973 -293.614741)
			(xy 45.116588 -293.60037) (xy 45.108798 -293.581588) (xy 45.108368 -293.571422) (xy 43.1673 -293.571422)
			(xy 43.166786 -293.581577) (xy 43.159011 -293.600339) (xy 43.144652 -293.614702) (xy 43.125892 -293.622483)
			(xy 43.115738 -293.622984) (xy 41.716198 -293.622984) (xy 41.706043 -293.622469) (xy 41.687278 -293.614698)
			(xy 41.672913 -293.600339) (xy 41.665135 -293.581577) (xy 41.664636 -293.571422) (xy 39.067232 -293.571422)
			(xy 39.066853 -293.581599) (xy 39.059055 -293.6004) (xy 39.044656 -293.614785) (xy 39.025847 -293.622563)
			(xy 39.01567 -293.622984) (xy 37.61613 -293.622984) (xy 37.605963 -293.622512) (xy 37.587173 -293.614741)
			(xy 37.572788 -293.60037) (xy 37.564998 -293.581588) (xy 37.564568 -293.571422) (xy 35.6235 -293.571422)
			(xy 35.622986 -293.581577) (xy 35.615211 -293.600339) (xy 35.600852 -293.614702) (xy 35.582092 -293.622483)
			(xy 35.571938 -293.622984) (xy 34.172398 -293.622984) (xy 34.162243 -293.622469) (xy 34.143478 -293.614698)
			(xy 34.129113 -293.600339) (xy 34.121335 -293.581577) (xy 34.120836 -293.571422) (xy 31.523432 -293.571422)
			(xy 31.523053 -293.581599) (xy 31.515255 -293.6004) (xy 31.500856 -293.614785) (xy 31.482047 -293.622563)
			(xy 31.47187 -293.622984) (xy 30.07233 -293.622984) (xy 30.062163 -293.622512) (xy 30.043373 -293.614741)
			(xy 30.028988 -293.60037) (xy 30.021198 -293.581588) (xy 30.020768 -293.571422) (xy 28.0797 -293.571422)
			(xy 28.079186 -293.581577) (xy 28.071411 -293.600339) (xy 28.057052 -293.614702) (xy 28.038292 -293.622483)
			(xy 28.028138 -293.622984) (xy 26.628598 -293.622984) (xy 26.618443 -293.622469) (xy 26.599678 -293.614698)
			(xy 26.585313 -293.600339) (xy 26.577535 -293.581577) (xy 26.577036 -293.571422) (xy 23.979632 -293.571422)
			(xy 23.979253 -293.581599) (xy 23.971455 -293.6004) (xy 23.957056 -293.614785) (xy 23.938247 -293.622563)
			(xy 23.92807 -293.622984) (xy 22.52853 -293.622984) (xy 22.518363 -293.622512) (xy 22.499573 -293.614741)
			(xy 22.485188 -293.60037) (xy 22.477398 -293.581588) (xy 22.476968 -293.571422) (xy 20.5359 -293.571422)
			(xy 20.535386 -293.581577) (xy 20.527611 -293.600339) (xy 20.513252 -293.614702) (xy 20.494492 -293.622483)
			(xy 20.484338 -293.622984) (xy 19.084798 -293.622984) (xy 19.074643 -293.622469) (xy 19.055878 -293.614698)
			(xy 19.041513 -293.600339) (xy 19.033735 -293.581577) (xy 19.033236 -293.571422) (xy 16.435832 -293.571422)
			(xy 16.435453 -293.581599) (xy 16.427655 -293.6004) (xy 16.413256 -293.614785) (xy 16.394447 -293.622563)
			(xy 16.38427 -293.622984) (xy 14.98473 -293.622984) (xy 14.974563 -293.622512) (xy 14.955773 -293.614741)
			(xy 14.941388 -293.60037) (xy 14.933598 -293.581588) (xy 14.933168 -293.571422) (xy 12.9921 -293.571422)
			(xy 12.991586 -293.581577) (xy 12.983811 -293.600339) (xy 12.969452 -293.614702) (xy 12.950692 -293.622483)
			(xy 12.940538 -293.622984) (xy 11.540998 -293.622984) (xy 11.530843 -293.622469) (xy 11.512078 -293.614698)
			(xy 11.497713 -293.600339) (xy 11.489935 -293.581577) (xy 11.489436 -293.571422) (xy 8.892032 -293.571422)
			(xy 8.891653 -293.581599) (xy 8.883855 -293.6004) (xy 8.869456 -293.614785) (xy 8.850647 -293.622563)
			(xy 8.84047 -293.622984) (xy 7.44093 -293.622984) (xy 7.430763 -293.622512) (xy 7.411973 -293.614741)
			(xy 7.397588 -293.60037) (xy 7.389798 -293.581588) (xy 7.389368 -293.571422) (xy 2.509012 -293.571422)
			(xy 2.509012 -294.421306) (xy 7.389368 -294.421306) (xy 7.389368 -294.012366) (xy 7.389806 -294.002202)
			(xy 7.397597 -293.983427) (xy 7.41198 -293.969062) (xy 7.430766 -293.961294) (xy 7.44093 -293.960804)
			(xy 8.84047 -293.960804) (xy 8.850622 -293.961357) (xy 8.869384 -293.969115) (xy 8.883749 -293.983463)
			(xy 8.891531 -294.002215) (xy 8.892032 -294.012366) (xy 8.892032 -294.421306) (xy 14.933168 -294.421306)
			(xy 14.933168 -294.012366) (xy 14.933606 -294.002202) (xy 14.941397 -293.983427) (xy 14.95578 -293.969062)
			(xy 14.974566 -293.961294) (xy 14.98473 -293.960804) (xy 16.38427 -293.960804) (xy 16.394422 -293.961357)
			(xy 16.413184 -293.969115) (xy 16.427549 -293.983463) (xy 16.435331 -294.002215) (xy 16.435832 -294.012366)
			(xy 16.435832 -294.421306) (xy 22.476968 -294.421306) (xy 22.476968 -294.012366) (xy 22.477406 -294.002202)
			(xy 22.485197 -293.983427) (xy 22.49958 -293.969062) (xy 22.518366 -293.961294) (xy 22.52853 -293.960804)
			(xy 23.92807 -293.960804) (xy 23.938222 -293.961357) (xy 23.956984 -293.969115) (xy 23.971349 -293.983463)
			(xy 23.979131 -294.002215) (xy 23.979632 -294.012366) (xy 23.979632 -294.421306) (xy 30.020768 -294.421306)
			(xy 30.020768 -294.012366) (xy 30.021206 -294.002202) (xy 30.028997 -293.983427) (xy 30.04338 -293.969062)
			(xy 30.062166 -293.961294) (xy 30.07233 -293.960804) (xy 31.47187 -293.960804) (xy 31.482022 -293.961357)
			(xy 31.500784 -293.969115) (xy 31.515149 -293.983463) (xy 31.522931 -294.002215) (xy 31.523432 -294.012366)
			(xy 31.523432 -294.421306) (xy 37.564568 -294.421306) (xy 37.564568 -294.012366) (xy 37.565006 -294.002202)
			(xy 37.572797 -293.983427) (xy 37.58718 -293.969062) (xy 37.605966 -293.961294) (xy 37.61613 -293.960804)
			(xy 39.01567 -293.960804) (xy 39.025822 -293.961357) (xy 39.044584 -293.969115) (xy 39.058949 -293.983463)
			(xy 39.066731 -294.002215) (xy 39.067232 -294.012366) (xy 39.067232 -294.421306) (xy 45.108368 -294.421306)
			(xy 45.108368 -294.012366) (xy 45.108806 -294.002202) (xy 45.116597 -293.983427) (xy 45.13098 -293.969062)
			(xy 45.149766 -293.961294) (xy 45.15993 -293.960804) (xy 46.55947 -293.960804) (xy 46.569622 -293.961357)
			(xy 46.588384 -293.969115) (xy 46.602749 -293.983463) (xy 46.610531 -294.002215) (xy 46.611032 -294.012366)
			(xy 46.611032 -294.421306) (xy 52.652168 -294.421306) (xy 52.652168 -294.012366) (xy 52.652606 -294.002202)
			(xy 52.660397 -293.983427) (xy 52.67478 -293.969062) (xy 52.693566 -293.961294) (xy 52.70373 -293.960804)
			(xy 54.10327 -293.960804) (xy 54.113422 -293.961357) (xy 54.132184 -293.969115) (xy 54.146549 -293.983463)
			(xy 54.154331 -294.002215) (xy 54.154832 -294.012366) (xy 54.154832 -294.421306) (xy 60.195968 -294.421306)
			(xy 60.195968 -294.012366) (xy 60.196406 -294.002202) (xy 60.204197 -293.983427) (xy 60.21858 -293.969062)
			(xy 60.237366 -293.961294) (xy 60.24753 -293.960804) (xy 61.64707 -293.960804) (xy 61.657222 -293.961357)
			(xy 61.675984 -293.969115) (xy 61.690349 -293.983463) (xy 61.698131 -294.002215) (xy 61.698632 -294.012366)
			(xy 61.698632 -294.421306) (xy 158.062168 -294.421306) (xy 158.062168 -294.012366) (xy 158.062606 -294.002202)
			(xy 158.070397 -293.983427) (xy 158.08478 -293.969062) (xy 158.103566 -293.961294) (xy 158.11373 -293.960804)
			(xy 159.51327 -293.960804) (xy 159.523422 -293.961357) (xy 159.542184 -293.969115) (xy 159.556549 -293.983463)
			(xy 159.564331 -294.002215) (xy 159.564832 -294.012366) (xy 159.564832 -294.421306) (xy 165.605968 -294.421306)
			(xy 165.605968 -294.012366) (xy 165.606406 -294.002202) (xy 165.614197 -293.983427) (xy 165.62858 -293.969062)
			(xy 165.647366 -293.961294) (xy 165.65753 -293.960804) (xy 167.05707 -293.960804) (xy 167.067222 -293.961357)
			(xy 167.085984 -293.969115) (xy 167.100349 -293.983463) (xy 167.108131 -294.002215) (xy 167.108632 -294.012366)
			(xy 167.108632 -294.421306) (xy 173.149768 -294.421306) (xy 173.149768 -294.012366) (xy 173.150206 -294.002202)
			(xy 173.157997 -293.983427) (xy 173.17238 -293.969062) (xy 173.191166 -293.961294) (xy 173.20133 -293.960804)
			(xy 174.60087 -293.960804) (xy 174.611022 -293.961357) (xy 174.629784 -293.969115) (xy 174.644149 -293.983463)
			(xy 174.651931 -294.002215) (xy 174.652432 -294.012366) (xy 174.652432 -294.421306) (xy 180.693568 -294.421306)
			(xy 180.693568 -294.012366) (xy 180.694006 -294.002202) (xy 180.701797 -293.983427) (xy 180.71618 -293.969062)
			(xy 180.734966 -293.961294) (xy 180.74513 -293.960804) (xy 182.14467 -293.960804) (xy 182.154822 -293.961357)
			(xy 182.173584 -293.969115) (xy 182.187949 -293.983463) (xy 182.195731 -294.002215) (xy 182.196232 -294.012366)
			(xy 182.196232 -294.421306) (xy 188.237368 -294.421306) (xy 188.237368 -294.012366) (xy 188.237806 -294.002202)
			(xy 188.245597 -293.983427) (xy 188.25998 -293.969062) (xy 188.278766 -293.961294) (xy 188.28893 -293.960804)
			(xy 189.68847 -293.960804) (xy 189.698622 -293.961357) (xy 189.717384 -293.969115) (xy 189.731749 -293.983463)
			(xy 189.739531 -294.002215) (xy 189.740032 -294.012366) (xy 189.740032 -294.421306) (xy 195.781168 -294.421306)
			(xy 195.781168 -294.012366) (xy 195.781606 -294.002202) (xy 195.789397 -293.983427) (xy 195.80378 -293.969062)
			(xy 195.822566 -293.961294) (xy 195.83273 -293.960804) (xy 197.23227 -293.960804) (xy 197.242422 -293.961357)
			(xy 197.261184 -293.969115) (xy 197.275549 -293.983463) (xy 197.283331 -294.002215) (xy 197.283832 -294.012366)
			(xy 197.283832 -294.421306) (xy 203.324968 -294.421306) (xy 203.324968 -294.012366) (xy 203.325406 -294.002202)
			(xy 203.333197 -293.983427) (xy 203.34758 -293.969062) (xy 203.366366 -293.961294) (xy 203.37653 -293.960804)
			(xy 204.77607 -293.960804) (xy 204.786222 -293.961357) (xy 204.804984 -293.969115) (xy 204.819349 -293.983463)
			(xy 204.827131 -294.002215) (xy 204.827632 -294.012366) (xy 204.827632 -294.421306) (xy 210.868768 -294.421306)
			(xy 210.868768 -294.012366) (xy 210.869206 -294.002202) (xy 210.876997 -293.983427) (xy 210.89138 -293.969062)
			(xy 210.910166 -293.961294) (xy 210.92033 -293.960804) (xy 212.31987 -293.960804) (xy 212.330022 -293.961357)
			(xy 212.348784 -293.969115) (xy 212.363149 -293.983463) (xy 212.370931 -294.002215) (xy 212.371432 -294.012366)
			(xy 212.371432 -294.421306) (xy 255.329436 -294.421306) (xy 255.329436 -294.012366) (xy 255.329905 -294.002206)
			(xy 255.337691 -293.983437) (xy 255.352064 -293.969073) (xy 255.370838 -293.961299) (xy 255.380998 -293.960804)
			(xy 256.780538 -293.960804) (xy 256.790694 -293.961301) (xy 256.809458 -293.969082) (xy 256.82382 -293.983446)
			(xy 256.831599 -294.00221) (xy 256.8321 -294.012366) (xy 256.8321 -294.421306) (xy 262.873236 -294.421306)
			(xy 262.873236 -294.012366) (xy 262.873705 -294.002206) (xy 262.881491 -293.983437) (xy 262.895864 -293.969073)
			(xy 262.914638 -293.961299) (xy 262.924798 -293.960804) (xy 264.324338 -293.960804) (xy 264.334494 -293.961301)
			(xy 264.353258 -293.969082) (xy 264.36762 -293.983446) (xy 264.375399 -294.00221) (xy 264.3759 -294.012366)
			(xy 264.3759 -294.421306) (xy 270.417036 -294.421306) (xy 270.417036 -294.012366) (xy 270.417505 -294.002206)
			(xy 270.425291 -293.983437) (xy 270.439664 -293.969073) (xy 270.458438 -293.961299) (xy 270.468598 -293.960804)
			(xy 271.868138 -293.960804) (xy 271.878294 -293.961301) (xy 271.897058 -293.969082) (xy 271.91142 -293.983446)
			(xy 271.919199 -294.00221) (xy 271.9197 -294.012366) (xy 271.9197 -294.421306) (xy 277.960836 -294.421306)
			(xy 277.960836 -294.012366) (xy 277.961305 -294.002206) (xy 277.969091 -293.983437) (xy 277.983464 -293.969073)
			(xy 278.002238 -293.961299) (xy 278.012398 -293.960804) (xy 279.411938 -293.960804) (xy 279.422094 -293.961301)
			(xy 279.440858 -293.969082) (xy 279.45522 -293.983446) (xy 279.462999 -294.00221) (xy 279.4635 -294.012366)
			(xy 279.4635 -294.421306) (xy 285.504636 -294.421306) (xy 285.504636 -294.012366) (xy 285.505105 -294.002206)
			(xy 285.512891 -293.983437) (xy 285.527264 -293.969073) (xy 285.546038 -293.961299) (xy 285.556198 -293.960804)
			(xy 286.955738 -293.960804) (xy 286.965894 -293.961301) (xy 286.984658 -293.969082) (xy 286.99902 -293.983446)
			(xy 287.006799 -294.00221) (xy 287.0073 -294.012366) (xy 287.0073 -294.421306) (xy 293.048436 -294.421306)
			(xy 293.048436 -294.012366) (xy 293.048905 -294.002206) (xy 293.056691 -293.983437) (xy 293.071064 -293.969073)
			(xy 293.089838 -293.961299) (xy 293.099998 -293.960804) (xy 294.499538 -293.960804) (xy 294.509694 -293.961301)
			(xy 294.528458 -293.969082) (xy 294.54282 -293.983446) (xy 294.550599 -294.00221) (xy 294.5511 -294.012366)
			(xy 294.5511 -294.421306) (xy 300.592236 -294.421306) (xy 300.592236 -294.012366) (xy 300.592705 -294.002206)
			(xy 300.600491 -293.983437) (xy 300.614864 -293.969073) (xy 300.633638 -293.961299) (xy 300.643798 -293.960804)
			(xy 302.043338 -293.960804) (xy 302.053494 -293.961301) (xy 302.072258 -293.969082) (xy 302.08662 -293.983446)
			(xy 302.094399 -294.00221) (xy 302.0949 -294.012366) (xy 302.0949 -294.421306) (xy 308.136036 -294.421306)
			(xy 308.136036 -294.012366) (xy 308.136505 -294.002206) (xy 308.144291 -293.983437) (xy 308.158664 -293.969073)
			(xy 308.177438 -293.961299) (xy 308.187598 -293.960804) (xy 309.587138 -293.960804) (xy 309.597294 -293.961301)
			(xy 309.616058 -293.969082) (xy 309.63042 -293.983446) (xy 309.638199 -294.00221) (xy 309.6387 -294.012366)
			(xy 309.6387 -294.421306) (xy 406.002236 -294.421306) (xy 406.002236 -294.012366) (xy 406.002705 -294.002206)
			(xy 406.010491 -293.983437) (xy 406.024864 -293.969073) (xy 406.043638 -293.961299) (xy 406.053798 -293.960804)
			(xy 407.453338 -293.960804) (xy 407.463494 -293.961301) (xy 407.482258 -293.969082) (xy 407.49662 -293.983446)
			(xy 407.504399 -294.00221) (xy 407.5049 -294.012366) (xy 407.5049 -294.421306) (xy 413.546036 -294.421306)
			(xy 413.546036 -294.012366) (xy 413.546505 -294.002206) (xy 413.554291 -293.983437) (xy 413.568664 -293.969073)
			(xy 413.587438 -293.961299) (xy 413.597598 -293.960804) (xy 414.997138 -293.960804) (xy 415.007294 -293.961301)
			(xy 415.026058 -293.969082) (xy 415.04042 -293.983446) (xy 415.048199 -294.00221) (xy 415.0487 -294.012366)
			(xy 415.0487 -294.421306) (xy 421.089836 -294.421306) (xy 421.089836 -294.012366) (xy 421.090305 -294.002206)
			(xy 421.098091 -293.983437) (xy 421.112464 -293.969073) (xy 421.131238 -293.961299) (xy 421.141398 -293.960804)
			(xy 422.540938 -293.960804) (xy 422.551094 -293.961301) (xy 422.569858 -293.969082) (xy 422.58422 -293.983446)
			(xy 422.591999 -294.00221) (xy 422.5925 -294.012366) (xy 422.5925 -294.421306) (xy 428.633636 -294.421306)
			(xy 428.633636 -294.012366) (xy 428.634105 -294.002206) (xy 428.641891 -293.983437) (xy 428.656264 -293.969073)
			(xy 428.675038 -293.961299) (xy 428.685198 -293.960804) (xy 430.084738 -293.960804) (xy 430.094894 -293.961301)
			(xy 430.113658 -293.969082) (xy 430.12802 -293.983446) (xy 430.135799 -294.00221) (xy 430.1363 -294.012366)
			(xy 430.1363 -294.421306) (xy 436.177436 -294.421306) (xy 436.177436 -294.012366) (xy 436.177905 -294.002206)
			(xy 436.185691 -293.983437) (xy 436.200064 -293.969073) (xy 436.218838 -293.961299) (xy 436.228998 -293.960804)
			(xy 437.628538 -293.960804) (xy 437.638694 -293.961301) (xy 437.657458 -293.969082) (xy 437.67182 -293.983446)
			(xy 437.679599 -294.00221) (xy 437.6801 -294.012366) (xy 437.6801 -294.421306) (xy 443.721236 -294.421306)
			(xy 443.721236 -294.012366) (xy 443.721705 -294.002206) (xy 443.729491 -293.983437) (xy 443.743864 -293.969073)
			(xy 443.762638 -293.961299) (xy 443.772798 -293.960804) (xy 445.172338 -293.960804) (xy 445.182494 -293.961301)
			(xy 445.201258 -293.969082) (xy 445.21562 -293.983446) (xy 445.223399 -294.00221) (xy 445.2239 -294.012366)
			(xy 445.2239 -294.421306) (xy 451.265036 -294.421306) (xy 451.265036 -294.012366) (xy 451.265505 -294.002206)
			(xy 451.273291 -293.983437) (xy 451.287664 -293.969073) (xy 451.306438 -293.961299) (xy 451.316598 -293.960804)
			(xy 452.716138 -293.960804) (xy 452.726294 -293.961301) (xy 452.745058 -293.969082) (xy 452.75942 -293.983446)
			(xy 452.767199 -294.00221) (xy 452.7677 -294.012366) (xy 452.7677 -294.421306) (xy 458.808836 -294.421306)
			(xy 458.808836 -294.012366) (xy 458.809305 -294.002206) (xy 458.817091 -293.983437) (xy 458.831464 -293.969073)
			(xy 458.850238 -293.961299) (xy 458.860398 -293.960804) (xy 460.259938 -293.960804) (xy 460.270094 -293.961301)
			(xy 460.288858 -293.969082) (xy 460.30322 -293.983446) (xy 460.310999 -294.00221) (xy 460.3115 -294.012366)
			(xy 460.3115 -294.421306) (xy 460.310972 -294.431459) (xy 460.303203 -294.450221) (xy 460.288848 -294.464585)
			(xy 460.270091 -294.472366) (xy 460.259938 -294.472868) (xy 458.860398 -294.472868) (xy 458.850241 -294.472368)
			(xy 458.831473 -294.464594) (xy 458.817108 -294.450231) (xy 458.809332 -294.431463) (xy 458.808836 -294.421306)
			(xy 452.7677 -294.421306) (xy 452.767172 -294.431459) (xy 452.759403 -294.450221) (xy 452.745048 -294.464585)
			(xy 452.726291 -294.472366) (xy 452.716138 -294.472868) (xy 451.316598 -294.472868) (xy 451.306441 -294.472368)
			(xy 451.287673 -294.464594) (xy 451.273308 -294.450231) (xy 451.265532 -294.431463) (xy 451.265036 -294.421306)
			(xy 445.2239 -294.421306) (xy 445.223372 -294.431459) (xy 445.215603 -294.450221) (xy 445.201248 -294.464585)
			(xy 445.182491 -294.472366) (xy 445.172338 -294.472868) (xy 443.772798 -294.472868) (xy 443.762641 -294.472368)
			(xy 443.743873 -294.464594) (xy 443.729508 -294.450231) (xy 443.721732 -294.431463) (xy 443.721236 -294.421306)
			(xy 437.6801 -294.421306) (xy 437.679572 -294.431459) (xy 437.671803 -294.450221) (xy 437.657448 -294.464585)
			(xy 437.638691 -294.472366) (xy 437.628538 -294.472868) (xy 436.228998 -294.472868) (xy 436.218841 -294.472368)
			(xy 436.200073 -294.464594) (xy 436.185708 -294.450231) (xy 436.177932 -294.431463) (xy 436.177436 -294.421306)
			(xy 430.1363 -294.421306) (xy 430.135772 -294.431459) (xy 430.128003 -294.450221) (xy 430.113648 -294.464585)
			(xy 430.094891 -294.472366) (xy 430.084738 -294.472868) (xy 428.685198 -294.472868) (xy 428.675041 -294.472368)
			(xy 428.656273 -294.464594) (xy 428.641908 -294.450231) (xy 428.634132 -294.431463) (xy 428.633636 -294.421306)
			(xy 422.5925 -294.421306) (xy 422.591972 -294.431459) (xy 422.584203 -294.450221) (xy 422.569848 -294.464585)
			(xy 422.551091 -294.472366) (xy 422.540938 -294.472868) (xy 421.141398 -294.472868) (xy 421.131241 -294.472368)
			(xy 421.112473 -294.464594) (xy 421.098108 -294.450231) (xy 421.090332 -294.431463) (xy 421.089836 -294.421306)
			(xy 415.0487 -294.421306) (xy 415.048172 -294.431459) (xy 415.040403 -294.450221) (xy 415.026048 -294.464585)
			(xy 415.007291 -294.472366) (xy 414.997138 -294.472868) (xy 413.597598 -294.472868) (xy 413.587441 -294.472368)
			(xy 413.568673 -294.464594) (xy 413.554308 -294.450231) (xy 413.546532 -294.431463) (xy 413.546036 -294.421306)
			(xy 407.5049 -294.421306) (xy 407.504372 -294.431459) (xy 407.496603 -294.450221) (xy 407.482248 -294.464585)
			(xy 407.463491 -294.472366) (xy 407.453338 -294.472868) (xy 406.053798 -294.472868) (xy 406.043641 -294.472368)
			(xy 406.024873 -294.464594) (xy 406.010508 -294.450231) (xy 406.002732 -294.431463) (xy 406.002236 -294.421306)
			(xy 309.6387 -294.421306) (xy 309.638172 -294.431459) (xy 309.630403 -294.450221) (xy 309.616048 -294.464585)
			(xy 309.597291 -294.472366) (xy 309.587138 -294.472868) (xy 308.187598 -294.472868) (xy 308.177441 -294.472368)
			(xy 308.158673 -294.464594) (xy 308.144308 -294.450231) (xy 308.136532 -294.431463) (xy 308.136036 -294.421306)
			(xy 302.0949 -294.421306) (xy 302.094372 -294.431459) (xy 302.086603 -294.450221) (xy 302.072248 -294.464585)
			(xy 302.053491 -294.472366) (xy 302.043338 -294.472868) (xy 300.643798 -294.472868) (xy 300.633641 -294.472368)
			(xy 300.614873 -294.464594) (xy 300.600508 -294.450231) (xy 300.592732 -294.431463) (xy 300.592236 -294.421306)
			(xy 294.5511 -294.421306) (xy 294.550572 -294.431459) (xy 294.542803 -294.450221) (xy 294.528448 -294.464585)
			(xy 294.509691 -294.472366) (xy 294.499538 -294.472868) (xy 293.099998 -294.472868) (xy 293.089841 -294.472368)
			(xy 293.071073 -294.464594) (xy 293.056708 -294.450231) (xy 293.048932 -294.431463) (xy 293.048436 -294.421306)
			(xy 287.0073 -294.421306) (xy 287.006772 -294.431459) (xy 286.999003 -294.450221) (xy 286.984648 -294.464585)
			(xy 286.965891 -294.472366) (xy 286.955738 -294.472868) (xy 285.556198 -294.472868) (xy 285.546041 -294.472368)
			(xy 285.527273 -294.464594) (xy 285.512908 -294.450231) (xy 285.505132 -294.431463) (xy 285.504636 -294.421306)
			(xy 279.4635 -294.421306) (xy 279.462972 -294.431459) (xy 279.455203 -294.450221) (xy 279.440848 -294.464585)
			(xy 279.422091 -294.472366) (xy 279.411938 -294.472868) (xy 278.012398 -294.472868) (xy 278.002241 -294.472368)
			(xy 277.983473 -294.464594) (xy 277.969108 -294.450231) (xy 277.961332 -294.431463) (xy 277.960836 -294.421306)
			(xy 271.9197 -294.421306) (xy 271.919172 -294.431459) (xy 271.911403 -294.450221) (xy 271.897048 -294.464585)
			(xy 271.878291 -294.472366) (xy 271.868138 -294.472868) (xy 270.468598 -294.472868) (xy 270.458441 -294.472368)
			(xy 270.439673 -294.464594) (xy 270.425308 -294.450231) (xy 270.417532 -294.431463) (xy 270.417036 -294.421306)
			(xy 264.3759 -294.421306) (xy 264.375372 -294.431459) (xy 264.367603 -294.450221) (xy 264.353248 -294.464585)
			(xy 264.334491 -294.472366) (xy 264.324338 -294.472868) (xy 262.924798 -294.472868) (xy 262.914641 -294.472368)
			(xy 262.895873 -294.464594) (xy 262.881508 -294.450231) (xy 262.873732 -294.431463) (xy 262.873236 -294.421306)
			(xy 256.8321 -294.421306) (xy 256.831572 -294.431459) (xy 256.823803 -294.450221) (xy 256.809448 -294.464585)
			(xy 256.790691 -294.472366) (xy 256.780538 -294.472868) (xy 255.380998 -294.472868) (xy 255.370841 -294.472368)
			(xy 255.352073 -294.464594) (xy 255.337708 -294.450231) (xy 255.329932 -294.431463) (xy 255.329436 -294.421306)
			(xy 212.371432 -294.421306) (xy 212.37104 -294.431482) (xy 212.363248 -294.450282) (xy 212.348852 -294.464668)
			(xy 212.330046 -294.472447) (xy 212.31987 -294.472868) (xy 210.92033 -294.472868) (xy 210.910161 -294.472412)
			(xy 210.891368 -294.464638) (xy 210.876983 -294.450262) (xy 210.869196 -294.431475) (xy 210.868768 -294.421306)
			(xy 204.827632 -294.421306) (xy 204.82724 -294.431482) (xy 204.819448 -294.450282) (xy 204.805052 -294.464668)
			(xy 204.786246 -294.472447) (xy 204.77607 -294.472868) (xy 203.37653 -294.472868) (xy 203.366361 -294.472412)
			(xy 203.347568 -294.464638) (xy 203.333183 -294.450262) (xy 203.325396 -294.431475) (xy 203.324968 -294.421306)
			(xy 197.283832 -294.421306) (xy 197.28344 -294.431482) (xy 197.275648 -294.450282) (xy 197.261252 -294.464668)
			(xy 197.242446 -294.472447) (xy 197.23227 -294.472868) (xy 195.83273 -294.472868) (xy 195.822561 -294.472412)
			(xy 195.803768 -294.464638) (xy 195.789383 -294.450262) (xy 195.781596 -294.431475) (xy 195.781168 -294.421306)
			(xy 189.740032 -294.421306) (xy 189.73964 -294.431482) (xy 189.731848 -294.450282) (xy 189.717452 -294.464668)
			(xy 189.698646 -294.472447) (xy 189.68847 -294.472868) (xy 188.28893 -294.472868) (xy 188.278761 -294.472412)
			(xy 188.259968 -294.464638) (xy 188.245583 -294.450262) (xy 188.237796 -294.431475) (xy 188.237368 -294.421306)
			(xy 182.196232 -294.421306) (xy 182.19584 -294.431482) (xy 182.188048 -294.450282) (xy 182.173652 -294.464668)
			(xy 182.154846 -294.472447) (xy 182.14467 -294.472868) (xy 180.74513 -294.472868) (xy 180.734961 -294.472412)
			(xy 180.716168 -294.464638) (xy 180.701783 -294.450262) (xy 180.693996 -294.431475) (xy 180.693568 -294.421306)
			(xy 174.652432 -294.421306) (xy 174.65204 -294.431482) (xy 174.644248 -294.450282) (xy 174.629852 -294.464668)
			(xy 174.611046 -294.472447) (xy 174.60087 -294.472868) (xy 173.20133 -294.472868) (xy 173.191161 -294.472412)
			(xy 173.172368 -294.464638) (xy 173.157983 -294.450262) (xy 173.150196 -294.431475) (xy 173.149768 -294.421306)
			(xy 167.108632 -294.421306) (xy 167.10824 -294.431482) (xy 167.100448 -294.450282) (xy 167.086052 -294.464668)
			(xy 167.067246 -294.472447) (xy 167.05707 -294.472868) (xy 165.65753 -294.472868) (xy 165.647361 -294.472412)
			(xy 165.628568 -294.464638) (xy 165.614183 -294.450262) (xy 165.606396 -294.431475) (xy 165.605968 -294.421306)
			(xy 159.564832 -294.421306) (xy 159.56444 -294.431482) (xy 159.556648 -294.450282) (xy 159.542252 -294.464668)
			(xy 159.523446 -294.472447) (xy 159.51327 -294.472868) (xy 158.11373 -294.472868) (xy 158.103561 -294.472412)
			(xy 158.084768 -294.464638) (xy 158.070383 -294.450262) (xy 158.062596 -294.431475) (xy 158.062168 -294.421306)
			(xy 61.698632 -294.421306) (xy 61.69824 -294.431482) (xy 61.690448 -294.450282) (xy 61.676052 -294.464668)
			(xy 61.657246 -294.472447) (xy 61.64707 -294.472868) (xy 60.24753 -294.472868) (xy 60.237361 -294.472412)
			(xy 60.218568 -294.464638) (xy 60.204183 -294.450262) (xy 60.196396 -294.431475) (xy 60.195968 -294.421306)
			(xy 54.154832 -294.421306) (xy 54.15444 -294.431482) (xy 54.146648 -294.450282) (xy 54.132252 -294.464668)
			(xy 54.113446 -294.472447) (xy 54.10327 -294.472868) (xy 52.70373 -294.472868) (xy 52.693561 -294.472412)
			(xy 52.674768 -294.464638) (xy 52.660383 -294.450262) (xy 52.652596 -294.431475) (xy 52.652168 -294.421306)
			(xy 46.611032 -294.421306) (xy 46.61064 -294.431482) (xy 46.602848 -294.450282) (xy 46.588452 -294.464668)
			(xy 46.569646 -294.472447) (xy 46.55947 -294.472868) (xy 45.15993 -294.472868) (xy 45.149761 -294.472412)
			(xy 45.130968 -294.464638) (xy 45.116583 -294.450262) (xy 45.108796 -294.431475) (xy 45.108368 -294.421306)
			(xy 39.067232 -294.421306) (xy 39.06684 -294.431482) (xy 39.059048 -294.450282) (xy 39.044652 -294.464668)
			(xy 39.025846 -294.472447) (xy 39.01567 -294.472868) (xy 37.61613 -294.472868) (xy 37.605961 -294.472412)
			(xy 37.587168 -294.464638) (xy 37.572783 -294.450262) (xy 37.564996 -294.431475) (xy 37.564568 -294.421306)
			(xy 31.523432 -294.421306) (xy 31.52304 -294.431482) (xy 31.515248 -294.450282) (xy 31.500852 -294.464668)
			(xy 31.482046 -294.472447) (xy 31.47187 -294.472868) (xy 30.07233 -294.472868) (xy 30.062161 -294.472412)
			(xy 30.043368 -294.464638) (xy 30.028983 -294.450262) (xy 30.021196 -294.431475) (xy 30.020768 -294.421306)
			(xy 23.979632 -294.421306) (xy 23.97924 -294.431482) (xy 23.971448 -294.450282) (xy 23.957052 -294.464668)
			(xy 23.938246 -294.472447) (xy 23.92807 -294.472868) (xy 22.52853 -294.472868) (xy 22.518361 -294.472412)
			(xy 22.499568 -294.464638) (xy 22.485183 -294.450262) (xy 22.477396 -294.431475) (xy 22.476968 -294.421306)
			(xy 16.435832 -294.421306) (xy 16.43544 -294.431482) (xy 16.427648 -294.450282) (xy 16.413252 -294.464668)
			(xy 16.394446 -294.472447) (xy 16.38427 -294.472868) (xy 14.98473 -294.472868) (xy 14.974561 -294.472412)
			(xy 14.955768 -294.464638) (xy 14.941383 -294.450262) (xy 14.933596 -294.431475) (xy 14.933168 -294.421306)
			(xy 8.892032 -294.421306) (xy 8.89164 -294.431482) (xy 8.883848 -294.450282) (xy 8.869452 -294.464668)
			(xy 8.850646 -294.472447) (xy 8.84047 -294.472868) (xy 7.44093 -294.472868) (xy 7.430761 -294.472412)
			(xy 7.411968 -294.464638) (xy 7.397583 -294.450262) (xy 7.389796 -294.431475) (xy 7.389368 -294.421306)
			(xy 2.509012 -294.421306) (xy 2.509012 -295.271444) (xy 11.489436 -295.271444) (xy 11.489436 -294.862504)
			(xy 11.489826 -294.852346) (xy 11.497627 -294.833586) (xy 11.512034 -294.819262) (xy 11.530837 -294.811568)
			(xy 11.540998 -294.811196) (xy 12.940538 -294.811196) (xy 12.950662 -294.811694) (xy 12.969375 -294.819426)
			(xy 12.983729 -294.833708) (xy 12.991554 -294.852383) (xy 12.9921 -294.862504) (xy 12.9921 -295.271444)
			(xy 19.033236 -295.271444) (xy 19.033236 -294.862504) (xy 19.033626 -294.852346) (xy 19.041427 -294.833586)
			(xy 19.055834 -294.819262) (xy 19.074637 -294.811568) (xy 19.084798 -294.811196) (xy 20.484338 -294.811196)
			(xy 20.494462 -294.811694) (xy 20.513175 -294.819426) (xy 20.527529 -294.833708) (xy 20.535354 -294.852383)
			(xy 20.5359 -294.862504) (xy 20.5359 -295.271444) (xy 26.577036 -295.271444) (xy 26.577036 -294.862504)
			(xy 26.577426 -294.852346) (xy 26.585227 -294.833586) (xy 26.599634 -294.819262) (xy 26.618437 -294.811568)
			(xy 26.628598 -294.811196) (xy 28.028138 -294.811196) (xy 28.038262 -294.811694) (xy 28.056975 -294.819426)
			(xy 28.071329 -294.833708) (xy 28.079154 -294.852383) (xy 28.0797 -294.862504) (xy 28.0797 -295.271444)
			(xy 34.120836 -295.271444) (xy 34.120836 -294.862504) (xy 34.121226 -294.852346) (xy 34.129027 -294.833586)
			(xy 34.143434 -294.819262) (xy 34.162237 -294.811568) (xy 34.172398 -294.811196) (xy 35.571938 -294.811196)
			(xy 35.582062 -294.811694) (xy 35.600775 -294.819426) (xy 35.615129 -294.833708) (xy 35.622954 -294.852383)
			(xy 35.6235 -294.862504) (xy 35.6235 -295.271444) (xy 41.664636 -295.271444) (xy 41.664636 -294.862504)
			(xy 41.665026 -294.852346) (xy 41.672827 -294.833586) (xy 41.687234 -294.819262) (xy 41.706037 -294.811568)
			(xy 41.716198 -294.811196) (xy 43.115738 -294.811196) (xy 43.125862 -294.811694) (xy 43.144575 -294.819426)
			(xy 43.158929 -294.833708) (xy 43.166754 -294.852383) (xy 43.1673 -294.862504) (xy 43.1673 -295.271444)
			(xy 49.208436 -295.271444) (xy 49.208436 -294.862504) (xy 49.208826 -294.852346) (xy 49.216627 -294.833586)
			(xy 49.231034 -294.819262) (xy 49.249837 -294.811568) (xy 49.259998 -294.811196) (xy 50.659538 -294.811196)
			(xy 50.669662 -294.811694) (xy 50.688375 -294.819426) (xy 50.702729 -294.833708) (xy 50.710554 -294.852383)
			(xy 50.7111 -294.862504) (xy 50.7111 -295.271444) (xy 56.752236 -295.271444) (xy 56.752236 -294.862504)
			(xy 56.752626 -294.852346) (xy 56.760427 -294.833586) (xy 56.774834 -294.819262) (xy 56.793637 -294.811568)
			(xy 56.803798 -294.811196) (xy 58.203338 -294.811196) (xy 58.213462 -294.811694) (xy 58.232175 -294.819426)
			(xy 58.246529 -294.833708) (xy 58.254354 -294.852383) (xy 58.2549 -294.862504) (xy 58.2549 -295.271444)
			(xy 64.296036 -295.271444) (xy 64.296036 -294.862504) (xy 64.296426 -294.852346) (xy 64.304227 -294.833586)
			(xy 64.318634 -294.819262) (xy 64.337437 -294.811568) (xy 64.347598 -294.811196) (xy 65.747138 -294.811196)
			(xy 65.757262 -294.811694) (xy 65.775975 -294.819426) (xy 65.790329 -294.833708) (xy 65.798154 -294.852383)
			(xy 65.7987 -294.862504) (xy 65.7987 -295.271444) (xy 162.162236 -295.271444) (xy 162.162236 -294.862504)
			(xy 162.162626 -294.852346) (xy 162.170427 -294.833586) (xy 162.184834 -294.819262) (xy 162.203637 -294.811568)
			(xy 162.213798 -294.811196) (xy 163.613338 -294.811196) (xy 163.623462 -294.811694) (xy 163.642175 -294.819426)
			(xy 163.656529 -294.833708) (xy 163.664354 -294.852383) (xy 163.6649 -294.862504) (xy 163.6649 -295.271444)
			(xy 169.706036 -295.271444) (xy 169.706036 -294.862504) (xy 169.706426 -294.852346) (xy 169.714227 -294.833586)
			(xy 169.728634 -294.819262) (xy 169.747437 -294.811568) (xy 169.757598 -294.811196) (xy 171.157138 -294.811196)
			(xy 171.167262 -294.811694) (xy 171.185975 -294.819426) (xy 171.200329 -294.833708) (xy 171.208154 -294.852383)
			(xy 171.2087 -294.862504) (xy 171.2087 -295.271444) (xy 177.249836 -295.271444) (xy 177.249836 -294.862504)
			(xy 177.250226 -294.852346) (xy 177.258027 -294.833586) (xy 177.272434 -294.819262) (xy 177.291237 -294.811568)
			(xy 177.301398 -294.811196) (xy 178.700938 -294.811196) (xy 178.711062 -294.811694) (xy 178.729775 -294.819426)
			(xy 178.744129 -294.833708) (xy 178.751954 -294.852383) (xy 178.7525 -294.862504) (xy 178.7525 -295.271444)
			(xy 184.793636 -295.271444) (xy 184.793636 -294.862504) (xy 184.794026 -294.852346) (xy 184.801827 -294.833586)
			(xy 184.816234 -294.819262) (xy 184.835037 -294.811568) (xy 184.845198 -294.811196) (xy 186.244738 -294.811196)
			(xy 186.254862 -294.811694) (xy 186.273575 -294.819426) (xy 186.287929 -294.833708) (xy 186.295754 -294.852383)
			(xy 186.2963 -294.862504) (xy 186.2963 -295.271444) (xy 192.337436 -295.271444) (xy 192.337436 -294.862504)
			(xy 192.337826 -294.852346) (xy 192.345627 -294.833586) (xy 192.360034 -294.819262) (xy 192.378837 -294.811568)
			(xy 192.388998 -294.811196) (xy 193.788538 -294.811196) (xy 193.798662 -294.811694) (xy 193.817375 -294.819426)
			(xy 193.831729 -294.833708) (xy 193.839554 -294.852383) (xy 193.8401 -294.862504) (xy 193.8401 -295.271444)
			(xy 199.881236 -295.271444) (xy 199.881236 -294.862504) (xy 199.881626 -294.852346) (xy 199.889427 -294.833586)
			(xy 199.903834 -294.819262) (xy 199.922637 -294.811568) (xy 199.932798 -294.811196) (xy 201.332338 -294.811196)
			(xy 201.342462 -294.811694) (xy 201.361175 -294.819426) (xy 201.375529 -294.833708) (xy 201.383354 -294.852383)
			(xy 201.3839 -294.862504) (xy 201.3839 -295.271444) (xy 207.425036 -295.271444) (xy 207.425036 -294.862504)
			(xy 207.425426 -294.852346) (xy 207.433227 -294.833586) (xy 207.447634 -294.819262) (xy 207.466437 -294.811568)
			(xy 207.476598 -294.811196) (xy 208.876138 -294.811196) (xy 208.886262 -294.811694) (xy 208.904975 -294.819426)
			(xy 208.919329 -294.833708) (xy 208.927154 -294.852383) (xy 208.9277 -294.862504) (xy 208.9277 -295.271444)
			(xy 214.968836 -295.271444) (xy 214.968836 -294.862504) (xy 214.969226 -294.852346) (xy 214.977027 -294.833586)
			(xy 214.991434 -294.819262) (xy 215.010237 -294.811568) (xy 215.020398 -294.811196) (xy 216.419938 -294.811196)
			(xy 216.430062 -294.811694) (xy 216.448775 -294.819426) (xy 216.463129 -294.833708) (xy 216.470954 -294.852383)
			(xy 216.4715 -294.862504) (xy 216.4715 -295.271444) (xy 259.429504 -295.271444) (xy 259.429504 -294.862504)
			(xy 259.429925 -294.85235) (xy 259.43772 -294.833597) (xy 259.452117 -294.819273) (xy 259.47091 -294.811574)
			(xy 259.481066 -294.811196) (xy 260.880606 -294.811196) (xy 260.890728 -294.81172) (xy 260.909441 -294.819442)
			(xy 260.923795 -294.833716) (xy 260.931622 -294.852385) (xy 260.932168 -294.862504) (xy 260.932168 -295.271444)
			(xy 266.973304 -295.271444) (xy 266.973304 -294.862504) (xy 266.973725 -294.85235) (xy 266.98152 -294.833597)
			(xy 266.995917 -294.819273) (xy 267.01471 -294.811574) (xy 267.024866 -294.811196) (xy 268.424406 -294.811196)
			(xy 268.434528 -294.81172) (xy 268.453241 -294.819442) (xy 268.467595 -294.833716) (xy 268.475422 -294.852385)
			(xy 268.475968 -294.862504) (xy 268.475968 -295.271444) (xy 274.517104 -295.271444) (xy 274.517104 -294.862504)
			(xy 274.517525 -294.85235) (xy 274.52532 -294.833597) (xy 274.539717 -294.819273) (xy 274.55851 -294.811574)
			(xy 274.568666 -294.811196) (xy 275.968206 -294.811196) (xy 275.978328 -294.81172) (xy 275.997041 -294.819442)
			(xy 276.011395 -294.833716) (xy 276.019222 -294.852385) (xy 276.019768 -294.862504) (xy 276.019768 -295.271444)
			(xy 282.060904 -295.271444) (xy 282.060904 -294.862504) (xy 282.061325 -294.85235) (xy 282.06912 -294.833597)
			(xy 282.083517 -294.819273) (xy 282.10231 -294.811574) (xy 282.112466 -294.811196) (xy 283.512006 -294.811196)
			(xy 283.522128 -294.81172) (xy 283.540841 -294.819442) (xy 283.555195 -294.833716) (xy 283.563022 -294.852385)
			(xy 283.563568 -294.862504) (xy 283.563568 -295.271444) (xy 289.604704 -295.271444) (xy 289.604704 -294.862504)
			(xy 289.605125 -294.85235) (xy 289.61292 -294.833597) (xy 289.627317 -294.819273) (xy 289.64611 -294.811574)
			(xy 289.656266 -294.811196) (xy 291.055806 -294.811196) (xy 291.065928 -294.81172) (xy 291.084641 -294.819442)
			(xy 291.098995 -294.833716) (xy 291.106822 -294.852385) (xy 291.107368 -294.862504) (xy 291.107368 -295.271444)
			(xy 297.148504 -295.271444) (xy 297.148504 -294.862504) (xy 297.148925 -294.85235) (xy 297.15672 -294.833597)
			(xy 297.171117 -294.819273) (xy 297.18991 -294.811574) (xy 297.200066 -294.811196) (xy 298.599606 -294.811196)
			(xy 298.609728 -294.81172) (xy 298.628441 -294.819442) (xy 298.642795 -294.833716) (xy 298.650622 -294.852385)
			(xy 298.651168 -294.862504) (xy 298.651168 -295.271444) (xy 304.692304 -295.271444) (xy 304.692304 -294.862504)
			(xy 304.692725 -294.85235) (xy 304.70052 -294.833597) (xy 304.714917 -294.819273) (xy 304.73371 -294.811574)
			(xy 304.743866 -294.811196) (xy 306.143406 -294.811196) (xy 306.153528 -294.81172) (xy 306.172241 -294.819442)
			(xy 306.186595 -294.833716) (xy 306.194422 -294.852385) (xy 306.194968 -294.862504) (xy 306.194968 -295.271444)
			(xy 312.236104 -295.271444) (xy 312.236104 -294.862504) (xy 312.236525 -294.85235) (xy 312.24432 -294.833597)
			(xy 312.258717 -294.819273) (xy 312.27751 -294.811574) (xy 312.287666 -294.811196) (xy 313.687206 -294.811196)
			(xy 313.697328 -294.81172) (xy 313.716041 -294.819442) (xy 313.730395 -294.833716) (xy 313.738222 -294.852385)
			(xy 313.738768 -294.862504) (xy 313.738768 -295.271444) (xy 410.102304 -295.271444) (xy 410.102304 -294.862504)
			(xy 410.102725 -294.85235) (xy 410.11052 -294.833597) (xy 410.124917 -294.819273) (xy 410.14371 -294.811574)
			(xy 410.153866 -294.811196) (xy 411.553406 -294.811196) (xy 411.563528 -294.81172) (xy 411.582241 -294.819442)
			(xy 411.596595 -294.833716) (xy 411.604422 -294.852385) (xy 411.604968 -294.862504) (xy 411.604968 -295.271444)
			(xy 417.646104 -295.271444) (xy 417.646104 -294.862504) (xy 417.646525 -294.85235) (xy 417.65432 -294.833597)
			(xy 417.668717 -294.819273) (xy 417.68751 -294.811574) (xy 417.697666 -294.811196) (xy 419.097206 -294.811196)
			(xy 419.107328 -294.81172) (xy 419.126041 -294.819442) (xy 419.140395 -294.833716) (xy 419.148222 -294.852385)
			(xy 419.148768 -294.862504) (xy 419.148768 -295.271444) (xy 425.189904 -295.271444) (xy 425.189904 -294.862504)
			(xy 425.190325 -294.85235) (xy 425.19812 -294.833597) (xy 425.212517 -294.819273) (xy 425.23131 -294.811574)
			(xy 425.241466 -294.811196) (xy 426.641006 -294.811196) (xy 426.651128 -294.81172) (xy 426.669841 -294.819442)
			(xy 426.684195 -294.833716) (xy 426.692022 -294.852385) (xy 426.692568 -294.862504) (xy 426.692568 -295.271444)
			(xy 432.733704 -295.271444) (xy 432.733704 -294.862504) (xy 432.734125 -294.85235) (xy 432.74192 -294.833597)
			(xy 432.756317 -294.819273) (xy 432.77511 -294.811574) (xy 432.785266 -294.811196) (xy 434.184806 -294.811196)
			(xy 434.194928 -294.81172) (xy 434.213641 -294.819442) (xy 434.227995 -294.833716) (xy 434.235822 -294.852385)
			(xy 434.236368 -294.862504) (xy 434.236368 -295.271444) (xy 440.277504 -295.271444) (xy 440.277504 -294.862504)
			(xy 440.277925 -294.85235) (xy 440.28572 -294.833597) (xy 440.300117 -294.819273) (xy 440.31891 -294.811574)
			(xy 440.329066 -294.811196) (xy 441.728606 -294.811196) (xy 441.738728 -294.81172) (xy 441.757441 -294.819442)
			(xy 441.771795 -294.833716) (xy 441.779622 -294.852385) (xy 441.780168 -294.862504) (xy 441.780168 -295.271444)
			(xy 447.821304 -295.271444) (xy 447.821304 -294.862504) (xy 447.821725 -294.85235) (xy 447.82952 -294.833597)
			(xy 447.843917 -294.819273) (xy 447.86271 -294.811574) (xy 447.872866 -294.811196) (xy 449.272406 -294.811196)
			(xy 449.282528 -294.81172) (xy 449.301241 -294.819442) (xy 449.315595 -294.833716) (xy 449.323422 -294.852385)
			(xy 449.323968 -294.862504) (xy 449.323968 -295.271444) (xy 455.365104 -295.271444) (xy 455.365104 -294.862504)
			(xy 455.365525 -294.85235) (xy 455.37332 -294.833597) (xy 455.387717 -294.819273) (xy 455.40651 -294.811574)
			(xy 455.416666 -294.811196) (xy 456.816206 -294.811196) (xy 456.826328 -294.81172) (xy 456.845041 -294.819442)
			(xy 456.859395 -294.833716) (xy 456.867222 -294.852385) (xy 456.867768 -294.862504) (xy 456.867768 -295.271444)
			(xy 462.908904 -295.271444) (xy 462.908904 -294.862504) (xy 462.909325 -294.85235) (xy 462.91712 -294.833597)
			(xy 462.931517 -294.819273) (xy 462.95031 -294.811574) (xy 462.960466 -294.811196) (xy 464.360006 -294.811196)
			(xy 464.370128 -294.81172) (xy 464.388841 -294.819442) (xy 464.403195 -294.833716) (xy 464.411022 -294.852385)
			(xy 464.411568 -294.862504) (xy 464.411568 -295.271444) (xy 464.411214 -295.281605) (xy 464.403398 -295.300364)
			(xy 464.38898 -295.314687) (xy 464.37017 -295.32238) (xy 464.360006 -295.322752) (xy 462.960466 -295.322752)
			(xy 462.950336 -295.322301) (xy 462.931613 -295.314561) (xy 462.917257 -295.300264) (xy 462.909441 -295.281572)
			(xy 462.908904 -295.271444) (xy 456.867768 -295.271444) (xy 456.867414 -295.281605) (xy 456.859598 -295.300364)
			(xy 456.84518 -295.314687) (xy 456.82637 -295.32238) (xy 456.816206 -295.322752) (xy 455.416666 -295.322752)
			(xy 455.406536 -295.322301) (xy 455.387813 -295.314561) (xy 455.373457 -295.300264) (xy 455.365641 -295.281572)
			(xy 455.365104 -295.271444) (xy 449.323968 -295.271444) (xy 449.323614 -295.281605) (xy 449.315798 -295.300364)
			(xy 449.30138 -295.314687) (xy 449.28257 -295.32238) (xy 449.272406 -295.322752) (xy 447.872866 -295.322752)
			(xy 447.862736 -295.322301) (xy 447.844013 -295.314561) (xy 447.829657 -295.300264) (xy 447.821841 -295.281572)
			(xy 447.821304 -295.271444) (xy 441.780168 -295.271444) (xy 441.779814 -295.281605) (xy 441.771998 -295.300364)
			(xy 441.75758 -295.314687) (xy 441.73877 -295.32238) (xy 441.728606 -295.322752) (xy 440.329066 -295.322752)
			(xy 440.318936 -295.322301) (xy 440.300213 -295.314561) (xy 440.285857 -295.300264) (xy 440.278041 -295.281572)
			(xy 440.277504 -295.271444) (xy 434.236368 -295.271444) (xy 434.236014 -295.281605) (xy 434.228198 -295.300364)
			(xy 434.21378 -295.314687) (xy 434.19497 -295.32238) (xy 434.184806 -295.322752) (xy 432.785266 -295.322752)
			(xy 432.775136 -295.322301) (xy 432.756413 -295.314561) (xy 432.742057 -295.300264) (xy 432.734241 -295.281572)
			(xy 432.733704 -295.271444) (xy 426.692568 -295.271444) (xy 426.692214 -295.281605) (xy 426.684398 -295.300364)
			(xy 426.66998 -295.314687) (xy 426.65117 -295.32238) (xy 426.641006 -295.322752) (xy 425.241466 -295.322752)
			(xy 425.231336 -295.322301) (xy 425.212613 -295.314561) (xy 425.198257 -295.300264) (xy 425.190441 -295.281572)
			(xy 425.189904 -295.271444) (xy 419.148768 -295.271444) (xy 419.148414 -295.281605) (xy 419.140598 -295.300364)
			(xy 419.12618 -295.314687) (xy 419.10737 -295.32238) (xy 419.097206 -295.322752) (xy 417.697666 -295.322752)
			(xy 417.687536 -295.322301) (xy 417.668813 -295.314561) (xy 417.654457 -295.300264) (xy 417.646641 -295.281572)
			(xy 417.646104 -295.271444) (xy 411.604968 -295.271444) (xy 411.604614 -295.281605) (xy 411.596798 -295.300364)
			(xy 411.58238 -295.314687) (xy 411.56357 -295.32238) (xy 411.553406 -295.322752) (xy 410.153866 -295.322752)
			(xy 410.143736 -295.322301) (xy 410.125013 -295.314561) (xy 410.110657 -295.300264) (xy 410.102841 -295.281572)
			(xy 410.102304 -295.271444) (xy 313.738768 -295.271444) (xy 313.738414 -295.281605) (xy 313.730598 -295.300364)
			(xy 313.71618 -295.314687) (xy 313.69737 -295.32238) (xy 313.687206 -295.322752) (xy 312.287666 -295.322752)
			(xy 312.277536 -295.322301) (xy 312.258813 -295.314561) (xy 312.244457 -295.300264) (xy 312.236641 -295.281572)
			(xy 312.236104 -295.271444) (xy 306.194968 -295.271444) (xy 306.194614 -295.281605) (xy 306.186798 -295.300364)
			(xy 306.17238 -295.314687) (xy 306.15357 -295.32238) (xy 306.143406 -295.322752) (xy 304.743866 -295.322752)
			(xy 304.733736 -295.322301) (xy 304.715013 -295.314561) (xy 304.700657 -295.300264) (xy 304.692841 -295.281572)
			(xy 304.692304 -295.271444) (xy 298.651168 -295.271444) (xy 298.650814 -295.281605) (xy 298.642998 -295.300364)
			(xy 298.62858 -295.314687) (xy 298.60977 -295.32238) (xy 298.599606 -295.322752) (xy 297.200066 -295.322752)
			(xy 297.189936 -295.322301) (xy 297.171213 -295.314561) (xy 297.156857 -295.300264) (xy 297.149041 -295.281572)
			(xy 297.148504 -295.271444) (xy 291.107368 -295.271444) (xy 291.107014 -295.281605) (xy 291.099198 -295.300364)
			(xy 291.08478 -295.314687) (xy 291.06597 -295.32238) (xy 291.055806 -295.322752) (xy 289.656266 -295.322752)
			(xy 289.646136 -295.322301) (xy 289.627413 -295.314561) (xy 289.613057 -295.300264) (xy 289.605241 -295.281572)
			(xy 289.604704 -295.271444) (xy 283.563568 -295.271444) (xy 283.563214 -295.281605) (xy 283.555398 -295.300364)
			(xy 283.54098 -295.314687) (xy 283.52217 -295.32238) (xy 283.512006 -295.322752) (xy 282.112466 -295.322752)
			(xy 282.102336 -295.322301) (xy 282.083613 -295.314561) (xy 282.069257 -295.300264) (xy 282.061441 -295.281572)
			(xy 282.060904 -295.271444) (xy 276.019768 -295.271444) (xy 276.019414 -295.281605) (xy 276.011598 -295.300364)
			(xy 275.99718 -295.314687) (xy 275.97837 -295.32238) (xy 275.968206 -295.322752) (xy 274.568666 -295.322752)
			(xy 274.558536 -295.322301) (xy 274.539813 -295.314561) (xy 274.525457 -295.300264) (xy 274.517641 -295.281572)
			(xy 274.517104 -295.271444) (xy 268.475968 -295.271444) (xy 268.475614 -295.281605) (xy 268.467798 -295.300364)
			(xy 268.45338 -295.314687) (xy 268.43457 -295.32238) (xy 268.424406 -295.322752) (xy 267.024866 -295.322752)
			(xy 267.014736 -295.322301) (xy 266.996013 -295.314561) (xy 266.981657 -295.300264) (xy 266.973841 -295.281572)
			(xy 266.973304 -295.271444) (xy 260.932168 -295.271444) (xy 260.931814 -295.281605) (xy 260.923998 -295.300364)
			(xy 260.90958 -295.314687) (xy 260.89077 -295.32238) (xy 260.880606 -295.322752) (xy 259.481066 -295.322752)
			(xy 259.470936 -295.322301) (xy 259.452213 -295.314561) (xy 259.437857 -295.300264) (xy 259.430041 -295.281572)
			(xy 259.429504 -295.271444) (xy 216.4715 -295.271444) (xy 216.471114 -295.281601) (xy 216.463304 -295.300354)
			(xy 216.448897 -295.314676) (xy 216.430097 -295.322374) (xy 216.419938 -295.322752) (xy 215.020398 -295.322752)
			(xy 215.01027 -295.322275) (xy 214.991548 -295.314545) (xy 214.977191 -295.300256) (xy 214.969373 -295.281569)
			(xy 214.968836 -295.271444) (xy 208.9277 -295.271444) (xy 208.927314 -295.281601) (xy 208.919504 -295.300354)
			(xy 208.905097 -295.314676) (xy 208.886297 -295.322374) (xy 208.876138 -295.322752) (xy 207.476598 -295.322752)
			(xy 207.46647 -295.322275) (xy 207.447748 -295.314545) (xy 207.433391 -295.300256) (xy 207.425573 -295.281569)
			(xy 207.425036 -295.271444) (xy 201.3839 -295.271444) (xy 201.383514 -295.281601) (xy 201.375704 -295.300354)
			(xy 201.361297 -295.314676) (xy 201.342497 -295.322374) (xy 201.332338 -295.322752) (xy 199.932798 -295.322752)
			(xy 199.92267 -295.322275) (xy 199.903948 -295.314545) (xy 199.889591 -295.300256) (xy 199.881773 -295.281569)
			(xy 199.881236 -295.271444) (xy 193.8401 -295.271444) (xy 193.839714 -295.281601) (xy 193.831904 -295.300354)
			(xy 193.817497 -295.314676) (xy 193.798697 -295.322374) (xy 193.788538 -295.322752) (xy 192.388998 -295.322752)
			(xy 192.37887 -295.322275) (xy 192.360148 -295.314545) (xy 192.345791 -295.300256) (xy 192.337973 -295.281569)
			(xy 192.337436 -295.271444) (xy 186.2963 -295.271444) (xy 186.295914 -295.281601) (xy 186.288104 -295.300354)
			(xy 186.273697 -295.314676) (xy 186.254897 -295.322374) (xy 186.244738 -295.322752) (xy 184.845198 -295.322752)
			(xy 184.83507 -295.322275) (xy 184.816348 -295.314545) (xy 184.801991 -295.300256) (xy 184.794173 -295.281569)
			(xy 184.793636 -295.271444) (xy 178.7525 -295.271444) (xy 178.752114 -295.281601) (xy 178.744304 -295.300354)
			(xy 178.729897 -295.314676) (xy 178.711097 -295.322374) (xy 178.700938 -295.322752) (xy 177.301398 -295.322752)
			(xy 177.29127 -295.322275) (xy 177.272548 -295.314545) (xy 177.258191 -295.300256) (xy 177.250373 -295.281569)
			(xy 177.249836 -295.271444) (xy 171.2087 -295.271444) (xy 171.208314 -295.281601) (xy 171.200504 -295.300354)
			(xy 171.186097 -295.314676) (xy 171.167297 -295.322374) (xy 171.157138 -295.322752) (xy 169.757598 -295.322752)
			(xy 169.74747 -295.322275) (xy 169.728748 -295.314545) (xy 169.714391 -295.300256) (xy 169.706573 -295.281569)
			(xy 169.706036 -295.271444) (xy 163.6649 -295.271444) (xy 163.664514 -295.281601) (xy 163.656704 -295.300354)
			(xy 163.642297 -295.314676) (xy 163.623497 -295.322374) (xy 163.613338 -295.322752) (xy 162.213798 -295.322752)
			(xy 162.20367 -295.322275) (xy 162.184948 -295.314545) (xy 162.170591 -295.300256) (xy 162.162773 -295.281569)
			(xy 162.162236 -295.271444) (xy 65.7987 -295.271444) (xy 65.798314 -295.281601) (xy 65.790504 -295.300354)
			(xy 65.776097 -295.314676) (xy 65.757297 -295.322374) (xy 65.747138 -295.322752) (xy 64.347598 -295.322752)
			(xy 64.33747 -295.322275) (xy 64.318748 -295.314545) (xy 64.304391 -295.300256) (xy 64.296573 -295.281569)
			(xy 64.296036 -295.271444) (xy 58.2549 -295.271444) (xy 58.254514 -295.281601) (xy 58.246704 -295.300354)
			(xy 58.232297 -295.314676) (xy 58.213497 -295.322374) (xy 58.203338 -295.322752) (xy 56.803798 -295.322752)
			(xy 56.79367 -295.322275) (xy 56.774948 -295.314545) (xy 56.760591 -295.300256) (xy 56.752773 -295.281569)
			(xy 56.752236 -295.271444) (xy 50.7111 -295.271444) (xy 50.710714 -295.281601) (xy 50.702904 -295.300354)
			(xy 50.688497 -295.314676) (xy 50.669697 -295.322374) (xy 50.659538 -295.322752) (xy 49.259998 -295.322752)
			(xy 49.24987 -295.322275) (xy 49.231148 -295.314545) (xy 49.216791 -295.300256) (xy 49.208973 -295.281569)
			(xy 49.208436 -295.271444) (xy 43.1673 -295.271444) (xy 43.166914 -295.281601) (xy 43.159104 -295.300354)
			(xy 43.144697 -295.314676) (xy 43.125897 -295.322374) (xy 43.115738 -295.322752) (xy 41.716198 -295.322752)
			(xy 41.70607 -295.322275) (xy 41.687348 -295.314545) (xy 41.672991 -295.300256) (xy 41.665173 -295.281569)
			(xy 41.664636 -295.271444) (xy 35.6235 -295.271444) (xy 35.623114 -295.281601) (xy 35.615304 -295.300354)
			(xy 35.600897 -295.314676) (xy 35.582097 -295.322374) (xy 35.571938 -295.322752) (xy 34.172398 -295.322752)
			(xy 34.16227 -295.322275) (xy 34.143548 -295.314545) (xy 34.129191 -295.300256) (xy 34.121373 -295.281569)
			(xy 34.120836 -295.271444) (xy 28.0797 -295.271444) (xy 28.079314 -295.281601) (xy 28.071504 -295.300354)
			(xy 28.057097 -295.314676) (xy 28.038297 -295.322374) (xy 28.028138 -295.322752) (xy 26.628598 -295.322752)
			(xy 26.61847 -295.322275) (xy 26.599748 -295.314545) (xy 26.585391 -295.300256) (xy 26.577573 -295.281569)
			(xy 26.577036 -295.271444) (xy 20.5359 -295.271444) (xy 20.535514 -295.281601) (xy 20.527704 -295.300354)
			(xy 20.513297 -295.314676) (xy 20.494497 -295.322374) (xy 20.484338 -295.322752) (xy 19.084798 -295.322752)
			(xy 19.07467 -295.322275) (xy 19.055948 -295.314545) (xy 19.041591 -295.300256) (xy 19.033773 -295.281569)
			(xy 19.033236 -295.271444) (xy 12.9921 -295.271444) (xy 12.991714 -295.281601) (xy 12.983904 -295.300354)
			(xy 12.969497 -295.314676) (xy 12.950697 -295.322374) (xy 12.940538 -295.322752) (xy 11.540998 -295.322752)
			(xy 11.53087 -295.322275) (xy 11.512148 -295.314545) (xy 11.497791 -295.300256) (xy 11.489973 -295.281569)
			(xy 11.489436 -295.271444) (xy 2.509012 -295.271444) (xy 2.509012 -296.121328) (xy 7.389368 -296.121328)
			(xy 7.389368 -295.712388) (xy 7.389811 -295.702237) (xy 7.397604 -295.68349) (xy 7.411994 -295.669169)
			(xy 7.430777 -295.661464) (xy 7.44093 -295.66108) (xy 8.84047 -295.66108) (xy 8.8506 -295.661552)
			(xy 8.869328 -295.669277) (xy 8.883687 -295.683569) (xy 8.8915 -295.702261) (xy 8.892032 -295.712388)
			(xy 8.892032 -296.121328) (xy 14.933168 -296.121328) (xy 14.933168 -295.712388) (xy 14.933611 -295.702237)
			(xy 14.941404 -295.68349) (xy 14.955794 -295.669169) (xy 14.974577 -295.661464) (xy 14.98473 -295.66108)
			(xy 16.38427 -295.66108) (xy 16.3944 -295.661552) (xy 16.413128 -295.669277) (xy 16.427487 -295.683569)
			(xy 16.4353 -295.702261) (xy 16.435832 -295.712388) (xy 16.435832 -296.121328) (xy 22.476968 -296.121328)
			(xy 22.476968 -295.712388) (xy 22.477411 -295.702237) (xy 22.485204 -295.68349) (xy 22.499594 -295.669169)
			(xy 22.518377 -295.661464) (xy 22.52853 -295.66108) (xy 23.92807 -295.66108) (xy 23.9382 -295.661552)
			(xy 23.956928 -295.669277) (xy 23.971287 -295.683569) (xy 23.9791 -295.702261) (xy 23.979632 -295.712388)
			(xy 23.979632 -296.121328) (xy 30.020768 -296.121328) (xy 30.020768 -295.712388) (xy 30.021211 -295.702237)
			(xy 30.029004 -295.68349) (xy 30.043394 -295.669169) (xy 30.062177 -295.661464) (xy 30.07233 -295.66108)
			(xy 31.47187 -295.66108) (xy 31.482 -295.661552) (xy 31.500728 -295.669277) (xy 31.515087 -295.683569)
			(xy 31.5229 -295.702261) (xy 31.523432 -295.712388) (xy 31.523432 -296.121328) (xy 37.564568 -296.121328)
			(xy 37.564568 -295.712388) (xy 37.565011 -295.702237) (xy 37.572804 -295.68349) (xy 37.587194 -295.669169)
			(xy 37.605977 -295.661464) (xy 37.61613 -295.66108) (xy 39.01567 -295.66108) (xy 39.0258 -295.661552)
			(xy 39.044528 -295.669277) (xy 39.058887 -295.683569) (xy 39.0667 -295.702261) (xy 39.067232 -295.712388)
			(xy 39.067232 -296.121328) (xy 45.108368 -296.121328) (xy 45.108368 -295.712388) (xy 45.108811 -295.702237)
			(xy 45.116604 -295.68349) (xy 45.130994 -295.669169) (xy 45.149777 -295.661464) (xy 45.15993 -295.66108)
			(xy 46.55947 -295.66108) (xy 46.5696 -295.661552) (xy 46.588328 -295.669277) (xy 46.602687 -295.683569)
			(xy 46.6105 -295.702261) (xy 46.611032 -295.712388) (xy 46.611032 -296.121328) (xy 52.652168 -296.121328)
			(xy 52.652168 -295.712388) (xy 52.652611 -295.702237) (xy 52.660404 -295.68349) (xy 52.674794 -295.669169)
			(xy 52.693577 -295.661464) (xy 52.70373 -295.66108) (xy 54.10327 -295.66108) (xy 54.1134 -295.661552)
			(xy 54.132128 -295.669277) (xy 54.146487 -295.683569) (xy 54.1543 -295.702261) (xy 54.154832 -295.712388)
			(xy 54.154832 -296.121328) (xy 60.195968 -296.121328) (xy 60.195968 -295.712388) (xy 60.196411 -295.702237)
			(xy 60.204204 -295.68349) (xy 60.218594 -295.669169) (xy 60.237377 -295.661464) (xy 60.24753 -295.66108)
			(xy 61.64707 -295.66108) (xy 61.6572 -295.661552) (xy 61.675928 -295.669277) (xy 61.690287 -295.683569)
			(xy 61.6981 -295.702261) (xy 61.698632 -295.712388) (xy 61.698632 -296.121328) (xy 61.698202 -296.13148)
			(xy 61.690403 -296.150227) (xy 61.67601 -296.164548) (xy 61.657224 -296.172253) (xy 61.64707 -296.172636)
			(xy 60.24753 -296.172636) (xy 60.237402 -296.172148) (xy 60.218677 -296.164426) (xy 60.204319 -296.150139)
			(xy 60.196503 -296.131453) (xy 60.195968 -296.121328) (xy 54.154832 -296.121328) (xy 54.154402 -296.13148)
			(xy 54.146603 -296.150227) (xy 54.13221 -296.164548) (xy 54.113424 -296.172253) (xy 54.10327 -296.172636)
			(xy 52.70373 -296.172636) (xy 52.693602 -296.172148) (xy 52.674877 -296.164426) (xy 52.660519 -296.150139)
			(xy 52.652703 -296.131453) (xy 52.652168 -296.121328) (xy 46.611032 -296.121328) (xy 46.610602 -296.13148)
			(xy 46.602803 -296.150227) (xy 46.58841 -296.164548) (xy 46.569624 -296.172253) (xy 46.55947 -296.172636)
			(xy 45.15993 -296.172636) (xy 45.149802 -296.172148) (xy 45.131077 -296.164426) (xy 45.116719 -296.150139)
			(xy 45.108903 -296.131453) (xy 45.108368 -296.121328) (xy 39.067232 -296.121328) (xy 39.066802 -296.13148)
			(xy 39.059003 -296.150227) (xy 39.04461 -296.164548) (xy 39.025824 -296.172253) (xy 39.01567 -296.172636)
			(xy 37.61613 -296.172636) (xy 37.606002 -296.172148) (xy 37.587277 -296.164426) (xy 37.572919 -296.150139)
			(xy 37.565103 -296.131453) (xy 37.564568 -296.121328) (xy 31.523432 -296.121328) (xy 31.523002 -296.13148)
			(xy 31.515203 -296.150227) (xy 31.50081 -296.164548) (xy 31.482024 -296.172253) (xy 31.47187 -296.172636)
			(xy 30.07233 -296.172636) (xy 30.062202 -296.172148) (xy 30.043477 -296.164426) (xy 30.029119 -296.150139)
			(xy 30.021303 -296.131453) (xy 30.020768 -296.121328) (xy 23.979632 -296.121328) (xy 23.979202 -296.13148)
			(xy 23.971403 -296.150227) (xy 23.95701 -296.164548) (xy 23.938224 -296.172253) (xy 23.92807 -296.172636)
			(xy 22.52853 -296.172636) (xy 22.518402 -296.172148) (xy 22.499677 -296.164426) (xy 22.485319 -296.150139)
			(xy 22.477503 -296.131453) (xy 22.476968 -296.121328) (xy 16.435832 -296.121328) (xy 16.435402 -296.13148)
			(xy 16.427603 -296.150227) (xy 16.41321 -296.164548) (xy 16.394424 -296.172253) (xy 16.38427 -296.172636)
			(xy 14.98473 -296.172636) (xy 14.974602 -296.172148) (xy 14.955877 -296.164426) (xy 14.941519 -296.150139)
			(xy 14.933703 -296.131453) (xy 14.933168 -296.121328) (xy 8.892032 -296.121328) (xy 8.891602 -296.13148)
			(xy 8.883803 -296.150227) (xy 8.86941 -296.164548) (xy 8.850624 -296.172253) (xy 8.84047 -296.172636)
			(xy 7.44093 -296.172636) (xy 7.430802 -296.172148) (xy 7.412077 -296.164426) (xy 7.397719 -296.150139)
			(xy 7.389903 -296.131453) (xy 7.389368 -296.121328) (xy 2.509012 -296.121328) (xy 2.509012 -296.971466)
			(xy 11.489436 -296.971466) (xy 11.489436 -296.562526) (xy 11.489885 -296.552356) (xy 11.497661 -296.533563)
			(xy 11.512039 -296.519177) (xy 11.530829 -296.511391) (xy 11.540998 -296.510964) (xy 12.940538 -296.510964)
			(xy 12.950701 -296.511403) (xy 12.969476 -296.519195) (xy 12.983841 -296.533577) (xy 12.99161 -296.552362)
			(xy 12.9921 -296.562526) (xy 12.9921 -296.971466) (xy 19.033236 -296.971466) (xy 19.033236 -296.562526)
			(xy 19.033685 -296.552356) (xy 19.041461 -296.533563) (xy 19.055839 -296.519177) (xy 19.074629 -296.511391)
			(xy 19.084798 -296.510964) (xy 20.484338 -296.510964) (xy 20.494501 -296.511403) (xy 20.513276 -296.519195)
			(xy 20.527641 -296.533577) (xy 20.53541 -296.552362) (xy 20.5359 -296.562526) (xy 20.5359 -296.971466)
			(xy 26.577036 -296.971466) (xy 26.577036 -296.562526) (xy 26.577485 -296.552356) (xy 26.585261 -296.533563)
			(xy 26.599639 -296.519177) (xy 26.618429 -296.511391) (xy 26.628598 -296.510964) (xy 28.028138 -296.510964)
			(xy 28.038301 -296.511403) (xy 28.057076 -296.519195) (xy 28.071441 -296.533577) (xy 28.07921 -296.552362)
			(xy 28.0797 -296.562526) (xy 28.0797 -296.971466) (xy 34.120836 -296.971466) (xy 34.120836 -296.562526)
			(xy 34.121285 -296.552356) (xy 34.129061 -296.533563) (xy 34.143439 -296.519177) (xy 34.162229 -296.511391)
			(xy 34.172398 -296.510964) (xy 35.571938 -296.510964) (xy 35.582101 -296.511403) (xy 35.600876 -296.519195)
			(xy 35.615241 -296.533577) (xy 35.62301 -296.552362) (xy 35.6235 -296.562526) (xy 35.6235 -296.971466)
			(xy 41.664636 -296.971466) (xy 41.664636 -296.562526) (xy 41.665085 -296.552356) (xy 41.672861 -296.533563)
			(xy 41.687239 -296.519177) (xy 41.706029 -296.511391) (xy 41.716198 -296.510964) (xy 43.115738 -296.510964)
			(xy 43.125901 -296.511403) (xy 43.144676 -296.519195) (xy 43.159041 -296.533577) (xy 43.16681 -296.552362)
			(xy 43.1673 -296.562526) (xy 43.1673 -296.971466) (xy 49.208436 -296.971466) (xy 49.208436 -296.562526)
			(xy 49.208885 -296.552356) (xy 49.216661 -296.533563) (xy 49.231039 -296.519177) (xy 49.249829 -296.511391)
			(xy 49.259998 -296.510964) (xy 50.659538 -296.510964) (xy 50.669701 -296.511403) (xy 50.688476 -296.519195)
			(xy 50.702841 -296.533577) (xy 50.71061 -296.552362) (xy 50.7111 -296.562526) (xy 50.7111 -296.971466)
			(xy 56.752236 -296.971466) (xy 56.752236 -296.562526) (xy 56.752685 -296.552356) (xy 56.760461 -296.533563)
			(xy 56.774839 -296.519177) (xy 56.793629 -296.511391) (xy 56.803798 -296.510964) (xy 58.203338 -296.510964)
			(xy 58.213501 -296.511403) (xy 58.232276 -296.519195) (xy 58.246641 -296.533577) (xy 58.25441 -296.552362)
			(xy 58.2549 -296.562526) (xy 58.2549 -296.971466) (xy 64.296036 -296.971466) (xy 64.296036 -296.562526)
			(xy 64.296485 -296.552356) (xy 64.304261 -296.533563) (xy 64.318639 -296.519177) (xy 64.337429 -296.511391)
			(xy 64.347598 -296.510964) (xy 65.747138 -296.510964) (xy 65.757301 -296.511403) (xy 65.776076 -296.519195)
			(xy 65.790441 -296.533577) (xy 65.79821 -296.552362) (xy 65.7987 -296.562526) (xy 65.7987 -296.971466)
			(xy 65.79814 -296.981617) (xy 65.790383 -297.000378) (xy 65.776038 -297.014743) (xy 65.757288 -297.022525)
			(xy 65.747138 -297.023028) (xy 64.347598 -297.023028) (xy 64.337422 -297.022637) (xy 64.318621 -297.014845)
			(xy 64.304235 -297.000449) (xy 64.296456 -296.981642) (xy 64.296036 -296.971466) (xy 58.2549 -296.971466)
			(xy 58.25434 -296.981617) (xy 58.246583 -297.000378) (xy 58.232238 -297.014743) (xy 58.213488 -297.022525)
			(xy 58.203338 -297.023028) (xy 56.803798 -297.023028) (xy 56.793622 -297.022637) (xy 56.774821 -297.014845)
			(xy 56.760435 -297.000449) (xy 56.752656 -296.981642) (xy 56.752236 -296.971466) (xy 50.7111 -296.971466)
			(xy 50.71054 -296.981617) (xy 50.702783 -297.000378) (xy 50.688438 -297.014743) (xy 50.669688 -297.022525)
			(xy 50.659538 -297.023028) (xy 49.259998 -297.023028) (xy 49.249822 -297.022637) (xy 49.231021 -297.014845)
			(xy 49.216635 -297.000449) (xy 49.208856 -296.981642) (xy 49.208436 -296.971466) (xy 43.1673 -296.971466)
			(xy 43.16674 -296.981617) (xy 43.158983 -297.000378) (xy 43.144638 -297.014743) (xy 43.125888 -297.022525)
			(xy 43.115738 -297.023028) (xy 41.716198 -297.023028) (xy 41.706022 -297.022637) (xy 41.687221 -297.014845)
			(xy 41.672835 -297.000449) (xy 41.665056 -296.981642) (xy 41.664636 -296.971466) (xy 35.6235 -296.971466)
			(xy 35.62294 -296.981617) (xy 35.615183 -297.000378) (xy 35.600838 -297.014743) (xy 35.582088 -297.022525)
			(xy 35.571938 -297.023028) (xy 34.172398 -297.023028) (xy 34.162222 -297.022637) (xy 34.143421 -297.014845)
			(xy 34.129035 -297.000449) (xy 34.121256 -296.981642) (xy 34.120836 -296.971466) (xy 28.0797 -296.971466)
			(xy 28.07914 -296.981617) (xy 28.071383 -297.000378) (xy 28.057038 -297.014743) (xy 28.038288 -297.022525)
			(xy 28.028138 -297.023028) (xy 26.628598 -297.023028) (xy 26.618422 -297.022637) (xy 26.599621 -297.014845)
			(xy 26.585235 -297.000449) (xy 26.577456 -296.981642) (xy 26.577036 -296.971466) (xy 20.5359 -296.971466)
			(xy 20.53534 -296.981617) (xy 20.527583 -297.000378) (xy 20.513238 -297.014743) (xy 20.494488 -297.022525)
			(xy 20.484338 -297.023028) (xy 19.084798 -297.023028) (xy 19.074622 -297.022637) (xy 19.055821 -297.014845)
			(xy 19.041435 -297.000449) (xy 19.033656 -296.981642) (xy 19.033236 -296.971466) (xy 12.9921 -296.971466)
			(xy 12.99154 -296.981617) (xy 12.983783 -297.000378) (xy 12.969438 -297.014743) (xy 12.950688 -297.022525)
			(xy 12.940538 -297.023028) (xy 11.540998 -297.023028) (xy 11.530822 -297.022637) (xy 11.512021 -297.014845)
			(xy 11.497635 -297.000449) (xy 11.489856 -296.981642) (xy 11.489436 -296.971466) (xy 2.509012 -296.971466)
			(xy 2.509012 -297.82135) (xy 7.389368 -297.82135) (xy 7.389368 -297.41241) (xy 7.389773 -297.402235)
			(xy 7.39756 -297.383435) (xy 7.411952 -297.369049) (xy 7.430755 -297.361269) (xy 7.44093 -297.360848)
			(xy 8.84047 -297.360848) (xy 8.850641 -297.361289) (xy 8.869437 -297.369066) (xy 8.883823 -297.383446)
			(xy 8.891607 -297.402239) (xy 8.892032 -297.41241) (xy 8.892032 -297.82135) (xy 14.933168 -297.82135)
			(xy 14.933168 -297.41241) (xy 14.933573 -297.402235) (xy 14.94136 -297.383435) (xy 14.955752 -297.369049)
			(xy 14.974555 -297.361269) (xy 14.98473 -297.360848) (xy 16.38427 -297.360848) (xy 16.394441 -297.361289)
			(xy 16.413237 -297.369066) (xy 16.427623 -297.383446) (xy 16.435407 -297.402239) (xy 16.435832 -297.41241)
			(xy 16.435832 -297.82135) (xy 22.476968 -297.82135) (xy 22.476968 -297.41241) (xy 22.477373 -297.402235)
			(xy 22.48516 -297.383435) (xy 22.499552 -297.369049) (xy 22.518355 -297.361269) (xy 22.52853 -297.360848)
			(xy 23.92807 -297.360848) (xy 23.938241 -297.361289) (xy 23.957037 -297.369066) (xy 23.971423 -297.383446)
			(xy 23.979207 -297.402239) (xy 23.979632 -297.41241) (xy 23.979632 -297.82135) (xy 30.020768 -297.82135)
			(xy 30.020768 -297.41241) (xy 30.021173 -297.402235) (xy 30.02896 -297.383435) (xy 30.043352 -297.369049)
			(xy 30.062155 -297.361269) (xy 30.07233 -297.360848) (xy 31.47187 -297.360848) (xy 31.482041 -297.361289)
			(xy 31.500837 -297.369066) (xy 31.515223 -297.383446) (xy 31.523007 -297.402239) (xy 31.523432 -297.41241)
			(xy 31.523432 -297.82135) (xy 37.564568 -297.82135) (xy 37.564568 -297.41241) (xy 37.564973 -297.402235)
			(xy 37.57276 -297.383435) (xy 37.587152 -297.369049) (xy 37.605955 -297.361269) (xy 37.61613 -297.360848)
			(xy 39.01567 -297.360848) (xy 39.025841 -297.361289) (xy 39.044637 -297.369066) (xy 39.059023 -297.383446)
			(xy 39.066807 -297.402239) (xy 39.067232 -297.41241) (xy 39.067232 -297.82135) (xy 45.108368 -297.82135)
			(xy 45.108368 -297.41241) (xy 45.108773 -297.402235) (xy 45.11656 -297.383435) (xy 45.130952 -297.369049)
			(xy 45.149755 -297.361269) (xy 45.15993 -297.360848) (xy 46.55947 -297.360848) (xy 46.569641 -297.361289)
			(xy 46.588437 -297.369066) (xy 46.602823 -297.383446) (xy 46.610607 -297.402239) (xy 46.611032 -297.41241)
			(xy 46.611032 -297.82135) (xy 52.652168 -297.82135) (xy 52.652168 -297.41241) (xy 52.652573 -297.402235)
			(xy 52.66036 -297.383435) (xy 52.674752 -297.369049) (xy 52.693555 -297.361269) (xy 52.70373 -297.360848)
			(xy 54.10327 -297.360848) (xy 54.113441 -297.361289) (xy 54.132237 -297.369066) (xy 54.146623 -297.383446)
			(xy 54.154407 -297.402239) (xy 54.154832 -297.41241) (xy 54.154832 -297.82135) (xy 60.195968 -297.82135)
			(xy 60.195968 -297.41241) (xy 60.196373 -297.402235) (xy 60.20416 -297.383435) (xy 60.218552 -297.369049)
			(xy 60.237355 -297.361269) (xy 60.24753 -297.360848) (xy 61.64707 -297.360848) (xy 61.657241 -297.361289)
			(xy 61.676037 -297.369066) (xy 61.690423 -297.383446) (xy 61.698207 -297.402239) (xy 61.698632 -297.41241)
			(xy 61.698632 -297.515026) (xy 88.21548 -297.515026) (xy 88.219461 -297.382006) (xy 88.23139 -297.249461)
			(xy 88.251225 -297.117868) (xy 88.278894 -296.987696) (xy 88.314298 -296.859411) (xy 88.357311 -296.733474)
			(xy 88.407778 -296.610335) (xy 88.465519 -296.490434) (xy 88.530328 -296.374201) (xy 88.601972 -296.262051)
			(xy 88.680194 -296.154387) (xy 88.764715 -296.051594) (xy 88.855233 -295.954039) (xy 88.951422 -295.862073)
			(xy 89.05294 -295.776023) (xy 89.159421 -295.696199) (xy 89.270486 -295.622886) (xy 89.385737 -295.556346)
			(xy 89.504761 -295.496817) (xy 89.627132 -295.444513) (xy 89.752411 -295.399621) (xy 89.880152 -295.362302)
			(xy 90.009895 -295.332689) (xy 90.141177 -295.310888) (xy 90.273528 -295.296978) (xy 90.406474 -295.291007)
			(xy 90.539539 -295.292998) (xy 90.672247 -295.302943) (xy 90.804123 -295.320807) (xy 90.934694 -295.346525)
			(xy 91.063494 -295.380006) (xy 91.19006 -295.42113) (xy 91.313941 -295.46975) (xy 91.434692 -295.525691)
			(xy 91.551882 -295.588753) (xy 91.665091 -295.658711) (xy 91.773913 -295.735315) (xy 91.877959 -295.818289)
			(xy 91.976857 -295.907337) (xy 92.070252 -296.00214) (xy 92.15781 -296.102358) (xy 92.239219 -296.207634)
			(xy 92.314185 -296.31759) (xy 92.382442 -296.431832) (xy 92.443744 -296.549952) (xy 92.497873 -296.671527)
			(xy 92.544634 -296.796121) (xy 92.58386 -296.923289) (xy 92.61541 -297.052575) (xy 92.639173 -297.183516)
			(xy 92.655062 -297.315644) (xy 92.66302 -297.448486) (xy 92.663518 -297.515026) (xy 131.195582 -297.515026)
			(xy 131.199563 -297.382006) (xy 131.211492 -297.249461) (xy 131.231327 -297.117868) (xy 131.258996 -296.987696)
			(xy 131.2944 -296.859411) (xy 131.337413 -296.733474) (xy 131.38788 -296.610335) (xy 131.445621 -296.490434)
			(xy 131.51043 -296.374201) (xy 131.582074 -296.262051) (xy 131.660296 -296.154387) (xy 131.744817 -296.051594)
			(xy 131.835335 -295.954039) (xy 131.931524 -295.862073) (xy 132.033042 -295.776023) (xy 132.139523 -295.696199)
			(xy 132.250588 -295.622886) (xy 132.365839 -295.556346) (xy 132.484863 -295.496817) (xy 132.607234 -295.444513)
			(xy 132.732513 -295.399621) (xy 132.860254 -295.362302) (xy 132.989997 -295.332689) (xy 133.121279 -295.310888)
			(xy 133.25363 -295.296978) (xy 133.386576 -295.291007) (xy 133.519641 -295.292998) (xy 133.652349 -295.302943)
			(xy 133.784225 -295.320807) (xy 133.914796 -295.346525) (xy 134.043596 -295.380006) (xy 134.170162 -295.42113)
			(xy 134.294043 -295.46975) (xy 134.414794 -295.525691) (xy 134.531984 -295.588753) (xy 134.645193 -295.658711)
			(xy 134.754015 -295.735315) (xy 134.858061 -295.818289) (xy 134.956959 -295.907337) (xy 135.050354 -296.00214)
			(xy 135.137912 -296.102358) (xy 135.152581 -296.121328) (xy 158.062168 -296.121328) (xy 158.062168 -295.712388)
			(xy 158.062611 -295.702237) (xy 158.070404 -295.68349) (xy 158.084794 -295.669169) (xy 158.103577 -295.661464)
			(xy 158.11373 -295.66108) (xy 159.51327 -295.66108) (xy 159.5234 -295.661552) (xy 159.542128 -295.669277)
			(xy 159.556487 -295.683569) (xy 159.5643 -295.702261) (xy 159.564832 -295.712388) (xy 159.564832 -296.121328)
			(xy 165.605968 -296.121328) (xy 165.605968 -295.712388) (xy 165.606411 -295.702237) (xy 165.614204 -295.68349)
			(xy 165.628594 -295.669169) (xy 165.647377 -295.661464) (xy 165.65753 -295.66108) (xy 167.05707 -295.66108)
			(xy 167.0672 -295.661552) (xy 167.085928 -295.669277) (xy 167.100287 -295.683569) (xy 167.1081 -295.702261)
			(xy 167.108632 -295.712388) (xy 167.108632 -296.121328) (xy 173.149768 -296.121328) (xy 173.149768 -295.712388)
			(xy 173.150211 -295.702237) (xy 173.158004 -295.68349) (xy 173.172394 -295.669169) (xy 173.191177 -295.661464)
			(xy 173.20133 -295.66108) (xy 174.60087 -295.66108) (xy 174.611 -295.661552) (xy 174.629728 -295.669277)
			(xy 174.644087 -295.683569) (xy 174.6519 -295.702261) (xy 174.652432 -295.712388) (xy 174.652432 -296.121328)
			(xy 180.693568 -296.121328) (xy 180.693568 -295.712388) (xy 180.694011 -295.702237) (xy 180.701804 -295.68349)
			(xy 180.716194 -295.669169) (xy 180.734977 -295.661464) (xy 180.74513 -295.66108) (xy 182.14467 -295.66108)
			(xy 182.1548 -295.661552) (xy 182.173528 -295.669277) (xy 182.187887 -295.683569) (xy 182.1957 -295.702261)
			(xy 182.196232 -295.712388) (xy 182.196232 -296.121328) (xy 188.237368 -296.121328) (xy 188.237368 -295.712388)
			(xy 188.237811 -295.702237) (xy 188.245604 -295.68349) (xy 188.259994 -295.669169) (xy 188.278777 -295.661464)
			(xy 188.28893 -295.66108) (xy 189.68847 -295.66108) (xy 189.6986 -295.661552) (xy 189.717328 -295.669277)
			(xy 189.731687 -295.683569) (xy 189.7395 -295.702261) (xy 189.740032 -295.712388) (xy 189.740032 -296.121328)
			(xy 195.781168 -296.121328) (xy 195.781168 -295.712388) (xy 195.781611 -295.702237) (xy 195.789404 -295.68349)
			(xy 195.803794 -295.669169) (xy 195.822577 -295.661464) (xy 195.83273 -295.66108) (xy 197.23227 -295.66108)
			(xy 197.2424 -295.661552) (xy 197.261128 -295.669277) (xy 197.275487 -295.683569) (xy 197.2833 -295.702261)
			(xy 197.283832 -295.712388) (xy 197.283832 -296.121328) (xy 203.324968 -296.121328) (xy 203.324968 -295.712388)
			(xy 203.325411 -295.702237) (xy 203.333204 -295.68349) (xy 203.347594 -295.669169) (xy 203.366377 -295.661464)
			(xy 203.37653 -295.66108) (xy 204.77607 -295.66108) (xy 204.7862 -295.661552) (xy 204.804928 -295.669277)
			(xy 204.819287 -295.683569) (xy 204.8271 -295.702261) (xy 204.827632 -295.712388) (xy 204.827632 -296.121328)
			(xy 210.868768 -296.121328) (xy 210.868768 -295.712388) (xy 210.869211 -295.702237) (xy 210.877004 -295.68349)
			(xy 210.891394 -295.669169) (xy 210.910177 -295.661464) (xy 210.92033 -295.66108) (xy 212.31987 -295.66108)
			(xy 212.33 -295.661552) (xy 212.348728 -295.669277) (xy 212.363087 -295.683569) (xy 212.3709 -295.702261)
			(xy 212.371432 -295.712388) (xy 212.371432 -296.121328) (xy 255.329436 -296.121328) (xy 255.329436 -295.712388)
			(xy 255.329812 -295.702229) (xy 255.337619 -295.683469) (xy 255.35203 -295.669145) (xy 255.370836 -295.661452)
			(xy 255.380998 -295.66108) (xy 256.780538 -295.66108) (xy 256.790672 -295.661497) (xy 256.809402 -295.669244)
			(xy 256.823758 -295.683552) (xy 256.831569 -295.702256) (xy 256.8321 -295.712388) (xy 256.8321 -296.121328)
			(xy 262.873236 -296.121328) (xy 262.873236 -295.712388) (xy 262.873612 -295.702229) (xy 262.881419 -295.683469)
			(xy 262.89583 -295.669145) (xy 262.914636 -295.661452) (xy 262.924798 -295.66108) (xy 264.324338 -295.66108)
			(xy 264.334472 -295.661497) (xy 264.353202 -295.669244) (xy 264.367558 -295.683552) (xy 264.375369 -295.702256)
			(xy 264.3759 -295.712388) (xy 264.3759 -296.121328) (xy 270.417036 -296.121328) (xy 270.417036 -295.712388)
			(xy 270.417412 -295.702229) (xy 270.425219 -295.683469) (xy 270.43963 -295.669145) (xy 270.458436 -295.661452)
			(xy 270.468598 -295.66108) (xy 271.868138 -295.66108) (xy 271.878272 -295.661497) (xy 271.897002 -295.669244)
			(xy 271.911358 -295.683552) (xy 271.919169 -295.702256) (xy 271.9197 -295.712388) (xy 271.9197 -296.121328)
			(xy 277.960836 -296.121328) (xy 277.960836 -295.712388) (xy 277.961212 -295.702229) (xy 277.969019 -295.683469)
			(xy 277.98343 -295.669145) (xy 278.002236 -295.661452) (xy 278.012398 -295.66108) (xy 279.411938 -295.66108)
			(xy 279.422072 -295.661497) (xy 279.440802 -295.669244) (xy 279.455158 -295.683552) (xy 279.462969 -295.702256)
			(xy 279.4635 -295.712388) (xy 279.4635 -296.121328) (xy 285.504636 -296.121328) (xy 285.504636 -295.712388)
			(xy 285.505012 -295.702229) (xy 285.512819 -295.683469) (xy 285.52723 -295.669145) (xy 285.546036 -295.661452)
			(xy 285.556198 -295.66108) (xy 286.955738 -295.66108) (xy 286.965872 -295.661497) (xy 286.984602 -295.669244)
			(xy 286.998958 -295.683552) (xy 287.006769 -295.702256) (xy 287.0073 -295.712388) (xy 287.0073 -296.121328)
			(xy 293.048436 -296.121328) (xy 293.048436 -295.712388) (xy 293.048812 -295.702229) (xy 293.056619 -295.683469)
			(xy 293.07103 -295.669145) (xy 293.089836 -295.661452) (xy 293.099998 -295.66108) (xy 294.499538 -295.66108)
			(xy 294.509672 -295.661497) (xy 294.528402 -295.669244) (xy 294.542758 -295.683552) (xy 294.550569 -295.702256)
			(xy 294.5511 -295.712388) (xy 294.5511 -296.121328) (xy 300.592236 -296.121328) (xy 300.592236 -295.712388)
			(xy 300.592612 -295.702229) (xy 300.600419 -295.683469) (xy 300.61483 -295.669145) (xy 300.633636 -295.661452)
			(xy 300.643798 -295.66108) (xy 302.043338 -295.66108) (xy 302.053472 -295.661497) (xy 302.072202 -295.669244)
			(xy 302.086558 -295.683552) (xy 302.094369 -295.702256) (xy 302.0949 -295.712388) (xy 302.0949 -296.121328)
			(xy 308.136036 -296.121328) (xy 308.136036 -295.712388) (xy 308.136412 -295.702229) (xy 308.144219 -295.683469)
			(xy 308.15863 -295.669145) (xy 308.177436 -295.661452) (xy 308.187598 -295.66108) (xy 309.587138 -295.66108)
			(xy 309.597272 -295.661497) (xy 309.616002 -295.669244) (xy 309.630358 -295.683552) (xy 309.638169 -295.702256)
			(xy 309.6387 -295.712388) (xy 309.6387 -296.121328) (xy 309.638301 -296.131484) (xy 309.630497 -296.150237)
			(xy 309.616093 -296.164559) (xy 309.597296 -296.172258) (xy 309.587138 -296.172636) (xy 308.187598 -296.172636)
			(xy 308.177468 -296.172174) (xy 308.158743 -296.164441) (xy 308.144385 -296.150147) (xy 308.136571 -296.131456)
			(xy 308.136036 -296.121328) (xy 302.0949 -296.121328) (xy 302.094501 -296.131484) (xy 302.086697 -296.150237)
			(xy 302.072293 -296.164559) (xy 302.053496 -296.172258) (xy 302.043338 -296.172636) (xy 300.643798 -296.172636)
			(xy 300.633668 -296.172174) (xy 300.614943 -296.164441) (xy 300.600585 -296.150147) (xy 300.592771 -296.131456)
			(xy 300.592236 -296.121328) (xy 294.5511 -296.121328) (xy 294.550701 -296.131484) (xy 294.542897 -296.150237)
			(xy 294.528493 -296.164559) (xy 294.509696 -296.172258) (xy 294.499538 -296.172636) (xy 293.099998 -296.172636)
			(xy 293.089868 -296.172174) (xy 293.071143 -296.164441) (xy 293.056785 -296.150147) (xy 293.048971 -296.131456)
			(xy 293.048436 -296.121328) (xy 287.0073 -296.121328) (xy 287.006901 -296.131484) (xy 286.999097 -296.150237)
			(xy 286.984693 -296.164559) (xy 286.965896 -296.172258) (xy 286.955738 -296.172636) (xy 285.556198 -296.172636)
			(xy 285.546068 -296.172174) (xy 285.527343 -296.164441) (xy 285.512985 -296.150147) (xy 285.505171 -296.131456)
			(xy 285.504636 -296.121328) (xy 279.4635 -296.121328) (xy 279.463101 -296.131484) (xy 279.455297 -296.150237)
			(xy 279.440893 -296.164559) (xy 279.422096 -296.172258) (xy 279.411938 -296.172636) (xy 278.012398 -296.172636)
			(xy 278.002268 -296.172174) (xy 277.983543 -296.164441) (xy 277.969185 -296.150147) (xy 277.961371 -296.131456)
			(xy 277.960836 -296.121328) (xy 271.9197 -296.121328) (xy 271.919301 -296.131484) (xy 271.911497 -296.150237)
			(xy 271.897093 -296.164559) (xy 271.878296 -296.172258) (xy 271.868138 -296.172636) (xy 270.468598 -296.172636)
			(xy 270.458468 -296.172174) (xy 270.439743 -296.164441) (xy 270.425385 -296.150147) (xy 270.417571 -296.131456)
			(xy 270.417036 -296.121328) (xy 264.3759 -296.121328) (xy 264.375501 -296.131484) (xy 264.367697 -296.150237)
			(xy 264.353293 -296.164559) (xy 264.334496 -296.172258) (xy 264.324338 -296.172636) (xy 262.924798 -296.172636)
			(xy 262.914668 -296.172174) (xy 262.895943 -296.164441) (xy 262.881585 -296.150147) (xy 262.873771 -296.131456)
			(xy 262.873236 -296.121328) (xy 256.8321 -296.121328) (xy 256.831701 -296.131484) (xy 256.823897 -296.150237)
			(xy 256.809493 -296.164559) (xy 256.790696 -296.172258) (xy 256.780538 -296.172636) (xy 255.380998 -296.172636)
			(xy 255.370868 -296.172174) (xy 255.352143 -296.164441) (xy 255.337785 -296.150147) (xy 255.329971 -296.131456)
			(xy 255.329436 -296.121328) (xy 212.371432 -296.121328) (xy 212.371002 -296.13148) (xy 212.363203 -296.150227)
			(xy 212.34881 -296.164548) (xy 212.330024 -296.172253) (xy 212.31987 -296.172636) (xy 210.92033 -296.172636)
			(xy 210.910202 -296.172148) (xy 210.891477 -296.164426) (xy 210.877119 -296.150139) (xy 210.869303 -296.131453)
			(xy 210.868768 -296.121328) (xy 204.827632 -296.121328) (xy 204.827202 -296.13148) (xy 204.819403 -296.150227)
			(xy 204.80501 -296.164548) (xy 204.786224 -296.172253) (xy 204.77607 -296.172636) (xy 203.37653 -296.172636)
			(xy 203.366402 -296.172148) (xy 203.347677 -296.164426) (xy 203.333319 -296.150139) (xy 203.325503 -296.131453)
			(xy 203.324968 -296.121328) (xy 197.283832 -296.121328) (xy 197.283402 -296.13148) (xy 197.275603 -296.150227)
			(xy 197.26121 -296.164548) (xy 197.242424 -296.172253) (xy 197.23227 -296.172636) (xy 195.83273 -296.172636)
			(xy 195.822602 -296.172148) (xy 195.803877 -296.164426) (xy 195.789519 -296.150139) (xy 195.781703 -296.131453)
			(xy 195.781168 -296.121328) (xy 189.740032 -296.121328) (xy 189.739602 -296.13148) (xy 189.731803 -296.150227)
			(xy 189.71741 -296.164548) (xy 189.698624 -296.172253) (xy 189.68847 -296.172636) (xy 188.28893 -296.172636)
			(xy 188.278802 -296.172148) (xy 188.260077 -296.164426) (xy 188.245719 -296.150139) (xy 188.237903 -296.131453)
			(xy 188.237368 -296.121328) (xy 182.196232 -296.121328) (xy 182.195802 -296.13148) (xy 182.188003 -296.150227)
			(xy 182.17361 -296.164548) (xy 182.154824 -296.172253) (xy 182.14467 -296.172636) (xy 180.74513 -296.172636)
			(xy 180.735002 -296.172148) (xy 180.716277 -296.164426) (xy 180.701919 -296.150139) (xy 180.694103 -296.131453)
			(xy 180.693568 -296.121328) (xy 174.652432 -296.121328) (xy 174.652002 -296.13148) (xy 174.644203 -296.150227)
			(xy 174.62981 -296.164548) (xy 174.611024 -296.172253) (xy 174.60087 -296.172636) (xy 173.20133 -296.172636)
			(xy 173.191202 -296.172148) (xy 173.172477 -296.164426) (xy 173.158119 -296.150139) (xy 173.150303 -296.131453)
			(xy 173.149768 -296.121328) (xy 167.108632 -296.121328) (xy 167.108202 -296.13148) (xy 167.100403 -296.150227)
			(xy 167.08601 -296.164548) (xy 167.067224 -296.172253) (xy 167.05707 -296.172636) (xy 165.65753 -296.172636)
			(xy 165.647402 -296.172148) (xy 165.628677 -296.164426) (xy 165.614319 -296.150139) (xy 165.606503 -296.131453)
			(xy 165.605968 -296.121328) (xy 159.564832 -296.121328) (xy 159.564402 -296.13148) (xy 159.556603 -296.150227)
			(xy 159.54221 -296.164548) (xy 159.523424 -296.172253) (xy 159.51327 -296.172636) (xy 158.11373 -296.172636)
			(xy 158.103602 -296.172148) (xy 158.084877 -296.164426) (xy 158.070519 -296.150139) (xy 158.062703 -296.131453)
			(xy 158.062168 -296.121328) (xy 135.152581 -296.121328) (xy 135.219321 -296.207634) (xy 135.294287 -296.31759)
			(xy 135.362544 -296.431832) (xy 135.423846 -296.549952) (xy 135.477975 -296.671527) (xy 135.524736 -296.796121)
			(xy 135.563962 -296.923289) (xy 135.575719 -296.971466) (xy 162.162236 -296.971466) (xy 162.162236 -296.562526)
			(xy 162.162685 -296.552356) (xy 162.170461 -296.533563) (xy 162.184839 -296.519177) (xy 162.203629 -296.511391)
			(xy 162.213798 -296.510964) (xy 163.613338 -296.510964) (xy 163.623501 -296.511403) (xy 163.642276 -296.519195)
			(xy 163.656641 -296.533577) (xy 163.66441 -296.552362) (xy 163.6649 -296.562526) (xy 163.6649 -296.971466)
			(xy 169.706036 -296.971466) (xy 169.706036 -296.562526) (xy 169.706485 -296.552356) (xy 169.714261 -296.533563)
			(xy 169.728639 -296.519177) (xy 169.747429 -296.511391) (xy 169.757598 -296.510964) (xy 171.157138 -296.510964)
			(xy 171.167301 -296.511403) (xy 171.186076 -296.519195) (xy 171.200441 -296.533577) (xy 171.20821 -296.552362)
			(xy 171.2087 -296.562526) (xy 171.2087 -296.971466) (xy 177.249836 -296.971466) (xy 177.249836 -296.562526)
			(xy 177.250285 -296.552356) (xy 177.258061 -296.533563) (xy 177.272439 -296.519177) (xy 177.291229 -296.511391)
			(xy 177.301398 -296.510964) (xy 178.700938 -296.510964) (xy 178.711101 -296.511403) (xy 178.729876 -296.519195)
			(xy 178.744241 -296.533577) (xy 178.75201 -296.552362) (xy 178.7525 -296.562526) (xy 178.7525 -296.971466)
			(xy 184.793636 -296.971466) (xy 184.793636 -296.562526) (xy 184.794085 -296.552356) (xy 184.801861 -296.533563)
			(xy 184.816239 -296.519177) (xy 184.835029 -296.511391) (xy 184.845198 -296.510964) (xy 186.244738 -296.510964)
			(xy 186.254901 -296.511403) (xy 186.273676 -296.519195) (xy 186.288041 -296.533577) (xy 186.29581 -296.552362)
			(xy 186.2963 -296.562526) (xy 186.2963 -296.971466) (xy 192.337436 -296.971466) (xy 192.337436 -296.562526)
			(xy 192.337885 -296.552356) (xy 192.345661 -296.533563) (xy 192.360039 -296.519177) (xy 192.378829 -296.511391)
			(xy 192.388998 -296.510964) (xy 193.788538 -296.510964) (xy 193.798701 -296.511403) (xy 193.817476 -296.519195)
			(xy 193.831841 -296.533577) (xy 193.83961 -296.552362) (xy 193.8401 -296.562526) (xy 193.8401 -296.971466)
			(xy 199.881236 -296.971466) (xy 199.881236 -296.562526) (xy 199.881685 -296.552356) (xy 199.889461 -296.533563)
			(xy 199.903839 -296.519177) (xy 199.922629 -296.511391) (xy 199.932798 -296.510964) (xy 201.332338 -296.510964)
			(xy 201.342501 -296.511403) (xy 201.361276 -296.519195) (xy 201.375641 -296.533577) (xy 201.38341 -296.552362)
			(xy 201.3839 -296.562526) (xy 201.3839 -296.971466) (xy 207.425036 -296.971466) (xy 207.425036 -296.562526)
			(xy 207.425485 -296.552356) (xy 207.433261 -296.533563) (xy 207.447639 -296.519177) (xy 207.466429 -296.511391)
			(xy 207.476598 -296.510964) (xy 208.876138 -296.510964) (xy 208.886301 -296.511403) (xy 208.905076 -296.519195)
			(xy 208.919441 -296.533577) (xy 208.92721 -296.552362) (xy 208.9277 -296.562526) (xy 208.9277 -296.971466)
			(xy 214.968836 -296.971466) (xy 214.968836 -296.562526) (xy 214.969285 -296.552356) (xy 214.977061 -296.533563)
			(xy 214.991439 -296.519177) (xy 215.010229 -296.511391) (xy 215.020398 -296.510964) (xy 216.419938 -296.510964)
			(xy 216.430101 -296.511403) (xy 216.448876 -296.519195) (xy 216.463241 -296.533577) (xy 216.47101 -296.552362)
			(xy 216.4715 -296.562526) (xy 216.4715 -296.971466) (xy 259.429504 -296.971466) (xy 259.429504 -296.562526)
			(xy 259.430054 -296.552374) (xy 259.437813 -296.533612) (xy 259.452162 -296.519247) (xy 259.470915 -296.511465)
			(xy 259.481066 -296.510964) (xy 260.880606 -296.510964) (xy 260.890781 -296.51136) (xy 260.909581 -296.519151)
			(xy 260.923967 -296.533546) (xy 260.931747 -296.552351) (xy 260.932168 -296.562526) (xy 260.932168 -296.971466)
			(xy 266.973304 -296.971466) (xy 266.973304 -296.562526) (xy 266.973854 -296.552374) (xy 266.981613 -296.533612)
			(xy 266.995962 -296.519247) (xy 267.014715 -296.511465) (xy 267.024866 -296.510964) (xy 268.424406 -296.510964)
			(xy 268.434581 -296.51136) (xy 268.453381 -296.519151) (xy 268.467767 -296.533546) (xy 268.475547 -296.552351)
			(xy 268.475968 -296.562526) (xy 268.475968 -296.971466) (xy 274.517104 -296.971466) (xy 274.517104 -296.562526)
			(xy 274.517654 -296.552374) (xy 274.525413 -296.533612) (xy 274.539762 -296.519247) (xy 274.558515 -296.511465)
			(xy 274.568666 -296.510964) (xy 275.968206 -296.510964) (xy 275.978381 -296.51136) (xy 275.997181 -296.519151)
			(xy 276.011567 -296.533546) (xy 276.019347 -296.552351) (xy 276.019768 -296.562526) (xy 276.019768 -296.971466)
			(xy 282.060904 -296.971466) (xy 282.060904 -296.562526) (xy 282.061454 -296.552374) (xy 282.069213 -296.533612)
			(xy 282.083562 -296.519247) (xy 282.102315 -296.511465) (xy 282.112466 -296.510964) (xy 283.512006 -296.510964)
			(xy 283.522181 -296.51136) (xy 283.540981 -296.519151) (xy 283.555367 -296.533546) (xy 283.563147 -296.552351)
			(xy 283.563568 -296.562526) (xy 283.563568 -296.971466) (xy 289.604704 -296.971466) (xy 289.604704 -296.562526)
			(xy 289.605254 -296.552374) (xy 289.613013 -296.533612) (xy 289.627362 -296.519247) (xy 289.646115 -296.511465)
			(xy 289.656266 -296.510964) (xy 291.055806 -296.510964) (xy 291.065981 -296.51136) (xy 291.084781 -296.519151)
			(xy 291.099167 -296.533546) (xy 291.106947 -296.552351) (xy 291.107368 -296.562526) (xy 291.107368 -296.971466)
			(xy 297.148504 -296.971466) (xy 297.148504 -296.562526) (xy 297.149054 -296.552374) (xy 297.156813 -296.533612)
			(xy 297.171162 -296.519247) (xy 297.189915 -296.511465) (xy 297.200066 -296.510964) (xy 298.599606 -296.510964)
			(xy 298.609781 -296.51136) (xy 298.628581 -296.519151) (xy 298.642967 -296.533546) (xy 298.650747 -296.552351)
			(xy 298.651168 -296.562526) (xy 298.651168 -296.971466) (xy 304.692304 -296.971466) (xy 304.692304 -296.562526)
			(xy 304.692854 -296.552374) (xy 304.700613 -296.533612) (xy 304.714962 -296.519247) (xy 304.733715 -296.511465)
			(xy 304.743866 -296.510964) (xy 306.143406 -296.510964) (xy 306.153581 -296.51136) (xy 306.172381 -296.519151)
			(xy 306.186767 -296.533546) (xy 306.194547 -296.552351) (xy 306.194968 -296.562526) (xy 306.194968 -296.971466)
			(xy 312.236104 -296.971466) (xy 312.236104 -296.562526) (xy 312.236654 -296.552374) (xy 312.244413 -296.533612)
			(xy 312.258762 -296.519247) (xy 312.277515 -296.511465) (xy 312.287666 -296.510964) (xy 313.687206 -296.510964)
			(xy 313.697381 -296.51136) (xy 313.716181 -296.519151) (xy 313.730567 -296.533546) (xy 313.738347 -296.552351)
			(xy 313.738768 -296.562526) (xy 313.738768 -296.971466) (xy 313.738308 -296.981635) (xy 313.730536 -297.000427)
			(xy 313.716161 -297.014813) (xy 313.697374 -297.0226) (xy 313.687206 -297.023028) (xy 312.287666 -297.023028)
			(xy 312.277502 -297.022594) (xy 312.258725 -297.014802) (xy 312.24436 -297.000417) (xy 312.236593 -296.981631)
			(xy 312.236104 -296.971466) (xy 306.194968 -296.971466) (xy 306.194508 -296.981635) (xy 306.186736 -297.000427)
			(xy 306.172361 -297.014813) (xy 306.153574 -297.0226) (xy 306.143406 -297.023028) (xy 304.743866 -297.023028)
			(xy 304.733702 -297.022594) (xy 304.714925 -297.014802) (xy 304.70056 -297.000417) (xy 304.692793 -296.981631)
			(xy 304.692304 -296.971466) (xy 298.651168 -296.971466) (xy 298.650708 -296.981635) (xy 298.642936 -297.000427)
			(xy 298.628561 -297.014813) (xy 298.609774 -297.0226) (xy 298.599606 -297.023028) (xy 297.200066 -297.023028)
			(xy 297.189902 -297.022594) (xy 297.171125 -297.014802) (xy 297.15676 -297.000417) (xy 297.148993 -296.981631)
			(xy 297.148504 -296.971466) (xy 291.107368 -296.971466) (xy 291.106908 -296.981635) (xy 291.099136 -297.000427)
			(xy 291.084761 -297.014813) (xy 291.065974 -297.0226) (xy 291.055806 -297.023028) (xy 289.656266 -297.023028)
			(xy 289.646102 -297.022594) (xy 289.627325 -297.014802) (xy 289.61296 -297.000417) (xy 289.605193 -296.981631)
			(xy 289.604704 -296.971466) (xy 283.563568 -296.971466) (xy 283.563108 -296.981635) (xy 283.555336 -297.000427)
			(xy 283.540961 -297.014813) (xy 283.522174 -297.0226) (xy 283.512006 -297.023028) (xy 282.112466 -297.023028)
			(xy 282.102302 -297.022594) (xy 282.083525 -297.014802) (xy 282.06916 -297.000417) (xy 282.061393 -296.981631)
			(xy 282.060904 -296.971466) (xy 276.019768 -296.971466) (xy 276.019308 -296.981635) (xy 276.011536 -297.000427)
			(xy 275.997161 -297.014813) (xy 275.978374 -297.0226) (xy 275.968206 -297.023028) (xy 274.568666 -297.023028)
			(xy 274.558502 -297.022594) (xy 274.539725 -297.014802) (xy 274.52536 -297.000417) (xy 274.517593 -296.981631)
			(xy 274.517104 -296.971466) (xy 268.475968 -296.971466) (xy 268.475508 -296.981635) (xy 268.467736 -297.000427)
			(xy 268.453361 -297.014813) (xy 268.434574 -297.0226) (xy 268.424406 -297.023028) (xy 267.024866 -297.023028)
			(xy 267.014702 -297.022594) (xy 266.995925 -297.014802) (xy 266.98156 -297.000417) (xy 266.973793 -296.981631)
			(xy 266.973304 -296.971466) (xy 260.932168 -296.971466) (xy 260.931708 -296.981635) (xy 260.923936 -297.000427)
			(xy 260.909561 -297.014813) (xy 260.890774 -297.0226) (xy 260.880606 -297.023028) (xy 259.481066 -297.023028)
			(xy 259.470902 -297.022594) (xy 259.452125 -297.014802) (xy 259.43776 -297.000417) (xy 259.429993 -296.981631)
			(xy 259.429504 -296.971466) (xy 216.4715 -296.971466) (xy 216.47094 -296.981617) (xy 216.463183 -297.000378)
			(xy 216.448838 -297.014743) (xy 216.430088 -297.022525) (xy 216.419938 -297.023028) (xy 215.020398 -297.023028)
			(xy 215.010222 -297.022637) (xy 214.991421 -297.014845) (xy 214.977035 -297.000449) (xy 214.969256 -296.981642)
			(xy 214.968836 -296.971466) (xy 208.9277 -296.971466) (xy 208.92714 -296.981617) (xy 208.919383 -297.000378)
			(xy 208.905038 -297.014743) (xy 208.886288 -297.022525) (xy 208.876138 -297.023028) (xy 207.476598 -297.023028)
			(xy 207.466422 -297.022637) (xy 207.447621 -297.014845) (xy 207.433235 -297.000449) (xy 207.425456 -296.981642)
			(xy 207.425036 -296.971466) (xy 201.3839 -296.971466) (xy 201.38334 -296.981617) (xy 201.375583 -297.000378)
			(xy 201.361238 -297.014743) (xy 201.342488 -297.022525) (xy 201.332338 -297.023028) (xy 199.932798 -297.023028)
			(xy 199.922622 -297.022637) (xy 199.903821 -297.014845) (xy 199.889435 -297.000449) (xy 199.881656 -296.981642)
			(xy 199.881236 -296.971466) (xy 193.8401 -296.971466) (xy 193.83954 -296.981617) (xy 193.831783 -297.000378)
			(xy 193.817438 -297.014743) (xy 193.798688 -297.022525) (xy 193.788538 -297.023028) (xy 192.388998 -297.023028)
			(xy 192.378822 -297.022637) (xy 192.360021 -297.014845) (xy 192.345635 -297.000449) (xy 192.337856 -296.981642)
			(xy 192.337436 -296.971466) (xy 186.2963 -296.971466) (xy 186.29574 -296.981617) (xy 186.287983 -297.000378)
			(xy 186.273638 -297.014743) (xy 186.254888 -297.022525) (xy 186.244738 -297.023028) (xy 184.845198 -297.023028)
			(xy 184.835022 -297.022637) (xy 184.816221 -297.014845) (xy 184.801835 -297.000449) (xy 184.794056 -296.981642)
			(xy 184.793636 -296.971466) (xy 178.7525 -296.971466) (xy 178.75194 -296.981617) (xy 178.744183 -297.000378)
			(xy 178.729838 -297.014743) (xy 178.711088 -297.022525) (xy 178.700938 -297.023028) (xy 177.301398 -297.023028)
			(xy 177.291222 -297.022637) (xy 177.272421 -297.014845) (xy 177.258035 -297.000449) (xy 177.250256 -296.981642)
			(xy 177.249836 -296.971466) (xy 171.2087 -296.971466) (xy 171.20814 -296.981617) (xy 171.200383 -297.000378)
			(xy 171.186038 -297.014743) (xy 171.167288 -297.022525) (xy 171.157138 -297.023028) (xy 169.757598 -297.023028)
			(xy 169.747422 -297.022637) (xy 169.728621 -297.014845) (xy 169.714235 -297.000449) (xy 169.706456 -296.981642)
			(xy 169.706036 -296.971466) (xy 163.6649 -296.971466) (xy 163.66434 -296.981617) (xy 163.656583 -297.000378)
			(xy 163.642238 -297.014743) (xy 163.623488 -297.022525) (xy 163.613338 -297.023028) (xy 162.213798 -297.023028)
			(xy 162.203622 -297.022637) (xy 162.184821 -297.014845) (xy 162.170435 -297.000449) (xy 162.162656 -296.981642)
			(xy 162.162236 -296.971466) (xy 135.575719 -296.971466) (xy 135.595512 -297.052575) (xy 135.619275 -297.183516)
			(xy 135.635164 -297.315644) (xy 135.643122 -297.448486) (xy 135.64362 -297.515026) (xy 135.643122 -297.581566)
			(xy 135.635164 -297.714408) (xy 135.622304 -297.82135) (xy 158.062168 -297.82135) (xy 158.062168 -297.41241)
			(xy 158.062573 -297.402235) (xy 158.07036 -297.383435) (xy 158.084752 -297.369049) (xy 158.103555 -297.361269)
			(xy 158.11373 -297.360848) (xy 159.51327 -297.360848) (xy 159.523441 -297.361289) (xy 159.542237 -297.369066)
			(xy 159.556623 -297.383446) (xy 159.564407 -297.402239) (xy 159.564832 -297.41241) (xy 159.564832 -297.82135)
			(xy 165.605968 -297.82135) (xy 165.605968 -297.41241) (xy 165.606373 -297.402235) (xy 165.61416 -297.383435)
			(xy 165.628552 -297.369049) (xy 165.647355 -297.361269) (xy 165.65753 -297.360848) (xy 167.05707 -297.360848)
			(xy 167.067241 -297.361289) (xy 167.086037 -297.369066) (xy 167.100423 -297.383446) (xy 167.108207 -297.402239)
			(xy 167.108632 -297.41241) (xy 167.108632 -297.82135) (xy 173.149768 -297.82135) (xy 173.149768 -297.41241)
			(xy 173.150173 -297.402235) (xy 173.15796 -297.383435) (xy 173.172352 -297.369049) (xy 173.191155 -297.361269)
			(xy 173.20133 -297.360848) (xy 174.60087 -297.360848) (xy 174.611041 -297.361289) (xy 174.629837 -297.369066)
			(xy 174.644223 -297.383446) (xy 174.652007 -297.402239) (xy 174.652432 -297.41241) (xy 174.652432 -297.82135)
			(xy 180.693568 -297.82135) (xy 180.693568 -297.41241) (xy 180.693973 -297.402235) (xy 180.70176 -297.383435)
			(xy 180.716152 -297.369049) (xy 180.734955 -297.361269) (xy 180.74513 -297.360848) (xy 182.14467 -297.360848)
			(xy 182.154841 -297.361289) (xy 182.173637 -297.369066) (xy 182.188023 -297.383446) (xy 182.195807 -297.402239)
			(xy 182.196232 -297.41241) (xy 182.196232 -297.82135) (xy 188.237368 -297.82135) (xy 188.237368 -297.41241)
			(xy 188.237773 -297.402235) (xy 188.24556 -297.383435) (xy 188.259952 -297.369049) (xy 188.278755 -297.361269)
			(xy 188.28893 -297.360848) (xy 189.68847 -297.360848) (xy 189.698641 -297.361289) (xy 189.717437 -297.369066)
			(xy 189.731823 -297.383446) (xy 189.739607 -297.402239) (xy 189.740032 -297.41241) (xy 189.740032 -297.82135)
			(xy 195.781168 -297.82135) (xy 195.781168 -297.41241) (xy 195.781573 -297.402235) (xy 195.78936 -297.383435)
			(xy 195.803752 -297.369049) (xy 195.822555 -297.361269) (xy 195.83273 -297.360848) (xy 197.23227 -297.360848)
			(xy 197.242441 -297.361289) (xy 197.261237 -297.369066) (xy 197.275623 -297.383446) (xy 197.283407 -297.402239)
			(xy 197.283832 -297.41241) (xy 197.283832 -297.82135) (xy 203.324968 -297.82135) (xy 203.324968 -297.41241)
			(xy 203.325373 -297.402235) (xy 203.33316 -297.383435) (xy 203.347552 -297.369049) (xy 203.366355 -297.361269)
			(xy 203.37653 -297.360848) (xy 204.77607 -297.360848) (xy 204.786241 -297.361289) (xy 204.805037 -297.369066)
			(xy 204.819423 -297.383446) (xy 204.827207 -297.402239) (xy 204.827632 -297.41241) (xy 204.827632 -297.82135)
			(xy 210.868768 -297.82135) (xy 210.868768 -297.41241) (xy 210.869173 -297.402235) (xy 210.87696 -297.383435)
			(xy 210.891352 -297.369049) (xy 210.910155 -297.361269) (xy 210.92033 -297.360848) (xy 212.31987 -297.360848)
			(xy 212.330041 -297.361289) (xy 212.348837 -297.369066) (xy 212.363223 -297.383446) (xy 212.371007 -297.402239)
			(xy 212.371432 -297.41241) (xy 212.371432 -297.82135) (xy 255.329436 -297.82135) (xy 255.329436 -297.41241)
			(xy 255.329872 -297.402239) (xy 255.337653 -297.383445) (xy 255.352035 -297.36906) (xy 255.370827 -297.361274)
			(xy 255.380998 -297.360848) (xy 256.780538 -297.360848) (xy 256.790699 -297.361303) (xy 256.809471 -297.369091)
			(xy 256.823836 -297.383469) (xy 256.831607 -297.402248) (xy 256.8321 -297.41241) (xy 256.8321 -297.82135)
			(xy 262.873236 -297.82135) (xy 262.873236 -297.41241) (xy 262.873672 -297.402239) (xy 262.881453 -297.383445)
			(xy 262.895835 -297.36906) (xy 262.914627 -297.361274) (xy 262.924798 -297.360848) (xy 264.324338 -297.360848)
			(xy 264.334499 -297.361303) (xy 264.353271 -297.369091) (xy 264.367636 -297.383469) (xy 264.375407 -297.402248)
			(xy 264.3759 -297.41241) (xy 264.3759 -297.82135) (xy 270.417036 -297.82135) (xy 270.417036 -297.41241)
			(xy 270.417472 -297.402239) (xy 270.425253 -297.383445) (xy 270.439635 -297.36906) (xy 270.458427 -297.361274)
			(xy 270.468598 -297.360848) (xy 271.868138 -297.360848) (xy 271.878299 -297.361303) (xy 271.897071 -297.369091)
			(xy 271.911436 -297.383469) (xy 271.919207 -297.402248) (xy 271.9197 -297.41241) (xy 271.9197 -297.82135)
			(xy 277.960836 -297.82135) (xy 277.960836 -297.41241) (xy 277.961272 -297.402239) (xy 277.969053 -297.383445)
			(xy 277.983435 -297.36906) (xy 278.002227 -297.361274) (xy 278.012398 -297.360848) (xy 279.411938 -297.360848)
			(xy 279.422099 -297.361303) (xy 279.440871 -297.369091) (xy 279.455236 -297.383469) (xy 279.463007 -297.402248)
			(xy 279.4635 -297.41241) (xy 279.4635 -297.82135) (xy 285.504636 -297.82135) (xy 285.504636 -297.41241)
			(xy 285.505072 -297.402239) (xy 285.512853 -297.383445) (xy 285.527235 -297.36906) (xy 285.546027 -297.361274)
			(xy 285.556198 -297.360848) (xy 286.955738 -297.360848) (xy 286.965899 -297.361303) (xy 286.984671 -297.369091)
			(xy 286.999036 -297.383469) (xy 287.006807 -297.402248) (xy 287.0073 -297.41241) (xy 287.0073 -297.82135)
			(xy 293.048436 -297.82135) (xy 293.048436 -297.41241) (xy 293.048872 -297.402239) (xy 293.056653 -297.383445)
			(xy 293.071035 -297.36906) (xy 293.089827 -297.361274) (xy 293.099998 -297.360848) (xy 294.499538 -297.360848)
			(xy 294.509699 -297.361303) (xy 294.528471 -297.369091) (xy 294.542836 -297.383469) (xy 294.550607 -297.402248)
			(xy 294.5511 -297.41241) (xy 294.5511 -297.82135) (xy 300.592236 -297.82135) (xy 300.592236 -297.41241)
			(xy 300.592672 -297.402239) (xy 300.600453 -297.383445) (xy 300.614835 -297.36906) (xy 300.633627 -297.361274)
			(xy 300.643798 -297.360848) (xy 302.043338 -297.360848) (xy 302.053499 -297.361303) (xy 302.072271 -297.369091)
			(xy 302.086636 -297.383469) (xy 302.094407 -297.402248) (xy 302.0949 -297.41241) (xy 302.0949 -297.82135)
			(xy 308.136036 -297.82135) (xy 308.136036 -297.41241) (xy 308.136472 -297.402239) (xy 308.144253 -297.383445)
			(xy 308.158635 -297.36906) (xy 308.177427 -297.361274) (xy 308.187598 -297.360848) (xy 309.587138 -297.360848)
			(xy 309.597299 -297.361303) (xy 309.616071 -297.369091) (xy 309.630436 -297.383469) (xy 309.638207 -297.402248)
			(xy 309.6387 -297.41241) (xy 309.6387 -297.515026) (xy 336.155548 -297.515026) (xy 336.159529 -297.382006)
			(xy 336.171458 -297.249461) (xy 336.191293 -297.117868) (xy 336.218962 -296.987696) (xy 336.254366 -296.859411)
			(xy 336.297379 -296.733474) (xy 336.347846 -296.610335) (xy 336.405587 -296.490434) (xy 336.470396 -296.374201)
			(xy 336.54204 -296.262051) (xy 336.620262 -296.154387) (xy 336.704783 -296.051594) (xy 336.795301 -295.954039)
			(xy 336.89149 -295.862073) (xy 336.993008 -295.776023) (xy 337.099489 -295.696199) (xy 337.210554 -295.622886)
			(xy 337.325805 -295.556346) (xy 337.444829 -295.496817) (xy 337.5672 -295.444513) (xy 337.692479 -295.399621)
			(xy 337.82022 -295.362302) (xy 337.949963 -295.332689) (xy 338.081245 -295.310888) (xy 338.213596 -295.296978)
			(xy 338.346542 -295.291007) (xy 338.479607 -295.292998) (xy 338.612315 -295.302943) (xy 338.744191 -295.320807)
			(xy 338.874762 -295.346525) (xy 339.003562 -295.380006) (xy 339.130128 -295.42113) (xy 339.254009 -295.46975)
			(xy 339.37476 -295.525691) (xy 339.49195 -295.588753) (xy 339.605159 -295.658711) (xy 339.713981 -295.735315)
			(xy 339.818027 -295.818289) (xy 339.916925 -295.907337) (xy 340.01032 -296.00214) (xy 340.097878 -296.102358)
			(xy 340.179287 -296.207634) (xy 340.254253 -296.31759) (xy 340.32251 -296.431832) (xy 340.383812 -296.549952)
			(xy 340.437941 -296.671527) (xy 340.484702 -296.796121) (xy 340.523928 -296.923289) (xy 340.555478 -297.052575)
			(xy 340.579241 -297.183516) (xy 340.59513 -297.315644) (xy 340.603088 -297.448486) (xy 340.603586 -297.515026)
			(xy 379.13565 -297.515026) (xy 379.139631 -297.382006) (xy 379.15156 -297.249461) (xy 379.171395 -297.117868)
			(xy 379.199064 -296.987696) (xy 379.234468 -296.859411) (xy 379.277481 -296.733474) (xy 379.327948 -296.610335)
			(xy 379.385689 -296.490434) (xy 379.450498 -296.374201) (xy 379.522142 -296.262051) (xy 379.600364 -296.154387)
			(xy 379.684885 -296.051594) (xy 379.775403 -295.954039) (xy 379.871592 -295.862073) (xy 379.97311 -295.776023)
			(xy 380.079591 -295.696199) (xy 380.190656 -295.622886) (xy 380.305907 -295.556346) (xy 380.424931 -295.496817)
			(xy 380.547302 -295.444513) (xy 380.672581 -295.399621) (xy 380.800322 -295.362302) (xy 380.930065 -295.332689)
			(xy 381.061347 -295.310888) (xy 381.193698 -295.296978) (xy 381.326644 -295.291007) (xy 381.459709 -295.292998)
			(xy 381.592417 -295.302943) (xy 381.724293 -295.320807) (xy 381.854864 -295.346525) (xy 381.983664 -295.380006)
			(xy 382.11023 -295.42113) (xy 382.234111 -295.46975) (xy 382.354862 -295.525691) (xy 382.472052 -295.588753)
			(xy 382.585261 -295.658711) (xy 382.694083 -295.735315) (xy 382.798129 -295.818289) (xy 382.897027 -295.907337)
			(xy 382.990422 -296.00214) (xy 383.07798 -296.102358) (xy 383.092649 -296.121328) (xy 406.002236 -296.121328)
			(xy 406.002236 -295.712388) (xy 406.002612 -295.702229) (xy 406.010419 -295.683469) (xy 406.02483 -295.669145)
			(xy 406.043636 -295.661452) (xy 406.053798 -295.66108) (xy 407.453338 -295.66108) (xy 407.463472 -295.661497)
			(xy 407.482202 -295.669244) (xy 407.496558 -295.683552) (xy 407.504369 -295.702256) (xy 407.5049 -295.712388)
			(xy 407.5049 -296.121328) (xy 413.546036 -296.121328) (xy 413.546036 -295.712388) (xy 413.546412 -295.702229)
			(xy 413.554219 -295.683469) (xy 413.56863 -295.669145) (xy 413.587436 -295.661452) (xy 413.597598 -295.66108)
			(xy 414.997138 -295.66108) (xy 415.007272 -295.661497) (xy 415.026002 -295.669244) (xy 415.040358 -295.683552)
			(xy 415.048169 -295.702256) (xy 415.0487 -295.712388) (xy 415.0487 -296.121328) (xy 421.089836 -296.121328)
			(xy 421.089836 -295.712388) (xy 421.090212 -295.702229) (xy 421.098019 -295.683469) (xy 421.11243 -295.669145)
			(xy 421.131236 -295.661452) (xy 421.141398 -295.66108) (xy 422.540938 -295.66108) (xy 422.551072 -295.661497)
			(xy 422.569802 -295.669244) (xy 422.584158 -295.683552) (xy 422.591969 -295.702256) (xy 422.5925 -295.712388)
			(xy 422.5925 -296.121328) (xy 428.633636 -296.121328) (xy 428.633636 -295.712388) (xy 428.634012 -295.702229)
			(xy 428.641819 -295.683469) (xy 428.65623 -295.669145) (xy 428.675036 -295.661452) (xy 428.685198 -295.66108)
			(xy 430.084738 -295.66108) (xy 430.094872 -295.661497) (xy 430.113602 -295.669244) (xy 430.127958 -295.683552)
			(xy 430.135769 -295.702256) (xy 430.1363 -295.712388) (xy 430.1363 -296.121328) (xy 436.177436 -296.121328)
			(xy 436.177436 -295.712388) (xy 436.177812 -295.702229) (xy 436.185619 -295.683469) (xy 436.20003 -295.669145)
			(xy 436.218836 -295.661452) (xy 436.228998 -295.66108) (xy 437.628538 -295.66108) (xy 437.638672 -295.661497)
			(xy 437.657402 -295.669244) (xy 437.671758 -295.683552) (xy 437.679569 -295.702256) (xy 437.6801 -295.712388)
			(xy 437.6801 -296.121328) (xy 443.721236 -296.121328) (xy 443.721236 -295.712388) (xy 443.721612 -295.702229)
			(xy 443.729419 -295.683469) (xy 443.74383 -295.669145) (xy 443.762636 -295.661452) (xy 443.772798 -295.66108)
			(xy 445.172338 -295.66108) (xy 445.182472 -295.661497) (xy 445.201202 -295.669244) (xy 445.215558 -295.683552)
			(xy 445.223369 -295.702256) (xy 445.2239 -295.712388) (xy 445.2239 -296.121328) (xy 451.265036 -296.121328)
			(xy 451.265036 -295.712388) (xy 451.265412 -295.702229) (xy 451.273219 -295.683469) (xy 451.28763 -295.669145)
			(xy 451.306436 -295.661452) (xy 451.316598 -295.66108) (xy 452.716138 -295.66108) (xy 452.726272 -295.661497)
			(xy 452.745002 -295.669244) (xy 452.759358 -295.683552) (xy 452.767169 -295.702256) (xy 452.7677 -295.712388)
			(xy 452.7677 -296.121328) (xy 458.808836 -296.121328) (xy 458.808836 -295.712388) (xy 458.809212 -295.702229)
			(xy 458.817019 -295.683469) (xy 458.83143 -295.669145) (xy 458.850236 -295.661452) (xy 458.860398 -295.66108)
			(xy 460.259938 -295.66108) (xy 460.270072 -295.661497) (xy 460.288802 -295.669244) (xy 460.303158 -295.683552)
			(xy 460.310969 -295.702256) (xy 460.3115 -295.712388) (xy 460.3115 -296.121328) (xy 460.311101 -296.131484)
			(xy 460.303297 -296.150237) (xy 460.288893 -296.164559) (xy 460.270096 -296.172258) (xy 460.259938 -296.172636)
			(xy 458.860398 -296.172636) (xy 458.850268 -296.172174) (xy 458.831543 -296.164441) (xy 458.817185 -296.150147)
			(xy 458.809371 -296.131456) (xy 458.808836 -296.121328) (xy 452.7677 -296.121328) (xy 452.767301 -296.131484)
			(xy 452.759497 -296.150237) (xy 452.745093 -296.164559) (xy 452.726296 -296.172258) (xy 452.716138 -296.172636)
			(xy 451.316598 -296.172636) (xy 451.306468 -296.172174) (xy 451.287743 -296.164441) (xy 451.273385 -296.150147)
			(xy 451.265571 -296.131456) (xy 451.265036 -296.121328) (xy 445.2239 -296.121328) (xy 445.223501 -296.131484)
			(xy 445.215697 -296.150237) (xy 445.201293 -296.164559) (xy 445.182496 -296.172258) (xy 445.172338 -296.172636)
			(xy 443.772798 -296.172636) (xy 443.762668 -296.172174) (xy 443.743943 -296.164441) (xy 443.729585 -296.150147)
			(xy 443.721771 -296.131456) (xy 443.721236 -296.121328) (xy 437.6801 -296.121328) (xy 437.679701 -296.131484)
			(xy 437.671897 -296.150237) (xy 437.657493 -296.164559) (xy 437.638696 -296.172258) (xy 437.628538 -296.172636)
			(xy 436.228998 -296.172636) (xy 436.218868 -296.172174) (xy 436.200143 -296.164441) (xy 436.185785 -296.150147)
			(xy 436.177971 -296.131456) (xy 436.177436 -296.121328) (xy 430.1363 -296.121328) (xy 430.135901 -296.131484)
			(xy 430.128097 -296.150237) (xy 430.113693 -296.164559) (xy 430.094896 -296.172258) (xy 430.084738 -296.172636)
			(xy 428.685198 -296.172636) (xy 428.675068 -296.172174) (xy 428.656343 -296.164441) (xy 428.641985 -296.150147)
			(xy 428.634171 -296.131456) (xy 428.633636 -296.121328) (xy 422.5925 -296.121328) (xy 422.592101 -296.131484)
			(xy 422.584297 -296.150237) (xy 422.569893 -296.164559) (xy 422.551096 -296.172258) (xy 422.540938 -296.172636)
			(xy 421.141398 -296.172636) (xy 421.131268 -296.172174) (xy 421.112543 -296.164441) (xy 421.098185 -296.150147)
			(xy 421.090371 -296.131456) (xy 421.089836 -296.121328) (xy 415.0487 -296.121328) (xy 415.048301 -296.131484)
			(xy 415.040497 -296.150237) (xy 415.026093 -296.164559) (xy 415.007296 -296.172258) (xy 414.997138 -296.172636)
			(xy 413.597598 -296.172636) (xy 413.587468 -296.172174) (xy 413.568743 -296.164441) (xy 413.554385 -296.150147)
			(xy 413.546571 -296.131456) (xy 413.546036 -296.121328) (xy 407.5049 -296.121328) (xy 407.504501 -296.131484)
			(xy 407.496697 -296.150237) (xy 407.482293 -296.164559) (xy 407.463496 -296.172258) (xy 407.453338 -296.172636)
			(xy 406.053798 -296.172636) (xy 406.043668 -296.172174) (xy 406.024943 -296.164441) (xy 406.010585 -296.150147)
			(xy 406.002771 -296.131456) (xy 406.002236 -296.121328) (xy 383.092649 -296.121328) (xy 383.159389 -296.207634)
			(xy 383.234355 -296.31759) (xy 383.302612 -296.431832) (xy 383.363914 -296.549952) (xy 383.418043 -296.671527)
			(xy 383.464804 -296.796121) (xy 383.50403 -296.923289) (xy 383.515787 -296.971466) (xy 410.102304 -296.971466)
			(xy 410.102304 -296.562526) (xy 410.102854 -296.552374) (xy 410.110613 -296.533612) (xy 410.124962 -296.519247)
			(xy 410.143715 -296.511465) (xy 410.153866 -296.510964) (xy 411.553406 -296.510964) (xy 411.563581 -296.51136)
			(xy 411.582381 -296.519151) (xy 411.596767 -296.533546) (xy 411.604547 -296.552351) (xy 411.604968 -296.562526)
			(xy 411.604968 -296.971466) (xy 417.646104 -296.971466) (xy 417.646104 -296.562526) (xy 417.646654 -296.552374)
			(xy 417.654413 -296.533612) (xy 417.668762 -296.519247) (xy 417.687515 -296.511465) (xy 417.697666 -296.510964)
			(xy 419.097206 -296.510964) (xy 419.107381 -296.51136) (xy 419.126181 -296.519151) (xy 419.140567 -296.533546)
			(xy 419.148347 -296.552351) (xy 419.148768 -296.562526) (xy 419.148768 -296.971466) (xy 425.189904 -296.971466)
			(xy 425.189904 -296.562526) (xy 425.190454 -296.552374) (xy 425.198213 -296.533612) (xy 425.212562 -296.519247)
			(xy 425.231315 -296.511465) (xy 425.241466 -296.510964) (xy 426.641006 -296.510964) (xy 426.651181 -296.51136)
			(xy 426.669981 -296.519151) (xy 426.684367 -296.533546) (xy 426.692147 -296.552351) (xy 426.692568 -296.562526)
			(xy 426.692568 -296.971466) (xy 432.733704 -296.971466) (xy 432.733704 -296.562526) (xy 432.734254 -296.552374)
			(xy 432.742013 -296.533612) (xy 432.756362 -296.519247) (xy 432.775115 -296.511465) (xy 432.785266 -296.510964)
			(xy 434.184806 -296.510964) (xy 434.194981 -296.51136) (xy 434.213781 -296.519151) (xy 434.228167 -296.533546)
			(xy 434.235947 -296.552351) (xy 434.236368 -296.562526) (xy 434.236368 -296.971466) (xy 440.277504 -296.971466)
			(xy 440.277504 -296.562526) (xy 440.278054 -296.552374) (xy 440.285813 -296.533612) (xy 440.300162 -296.519247)
			(xy 440.318915 -296.511465) (xy 440.329066 -296.510964) (xy 441.728606 -296.510964) (xy 441.738781 -296.51136)
			(xy 441.757581 -296.519151) (xy 441.771967 -296.533546) (xy 441.779747 -296.552351) (xy 441.780168 -296.562526)
			(xy 441.780168 -296.971466) (xy 447.821304 -296.971466) (xy 447.821304 -296.562526) (xy 447.821854 -296.552374)
			(xy 447.829613 -296.533612) (xy 447.843962 -296.519247) (xy 447.862715 -296.511465) (xy 447.872866 -296.510964)
			(xy 449.272406 -296.510964) (xy 449.282581 -296.51136) (xy 449.301381 -296.519151) (xy 449.315767 -296.533546)
			(xy 449.323547 -296.552351) (xy 449.323968 -296.562526) (xy 449.323968 -296.971466) (xy 455.365104 -296.971466)
			(xy 455.365104 -296.562526) (xy 455.365654 -296.552374) (xy 455.373413 -296.533612) (xy 455.387762 -296.519247)
			(xy 455.406515 -296.511465) (xy 455.416666 -296.510964) (xy 456.816206 -296.510964) (xy 456.826381 -296.51136)
			(xy 456.845181 -296.519151) (xy 456.859567 -296.533546) (xy 456.867347 -296.552351) (xy 456.867768 -296.562526)
			(xy 456.867768 -296.971466) (xy 462.908904 -296.971466) (xy 462.908904 -296.562526) (xy 462.909454 -296.552374)
			(xy 462.917213 -296.533612) (xy 462.931562 -296.519247) (xy 462.950315 -296.511465) (xy 462.960466 -296.510964)
			(xy 464.360006 -296.510964) (xy 464.370181 -296.51136) (xy 464.388981 -296.519151) (xy 464.403367 -296.533546)
			(xy 464.411147 -296.552351) (xy 464.411568 -296.562526) (xy 464.411568 -296.971466) (xy 464.411108 -296.981635)
			(xy 464.403336 -297.000427) (xy 464.388961 -297.014813) (xy 464.370174 -297.0226) (xy 464.360006 -297.023028)
			(xy 462.960466 -297.023028) (xy 462.950302 -297.022594) (xy 462.931525 -297.014802) (xy 462.91716 -297.000417)
			(xy 462.909393 -296.981631) (xy 462.908904 -296.971466) (xy 456.867768 -296.971466) (xy 456.867308 -296.981635)
			(xy 456.859536 -297.000427) (xy 456.845161 -297.014813) (xy 456.826374 -297.0226) (xy 456.816206 -297.023028)
			(xy 455.416666 -297.023028) (xy 455.406502 -297.022594) (xy 455.387725 -297.014802) (xy 455.37336 -297.000417)
			(xy 455.365593 -296.981631) (xy 455.365104 -296.971466) (xy 449.323968 -296.971466) (xy 449.323508 -296.981635)
			(xy 449.315736 -297.000427) (xy 449.301361 -297.014813) (xy 449.282574 -297.0226) (xy 449.272406 -297.023028)
			(xy 447.872866 -297.023028) (xy 447.862702 -297.022594) (xy 447.843925 -297.014802) (xy 447.82956 -297.000417)
			(xy 447.821793 -296.981631) (xy 447.821304 -296.971466) (xy 441.780168 -296.971466) (xy 441.779708 -296.981635)
			(xy 441.771936 -297.000427) (xy 441.757561 -297.014813) (xy 441.738774 -297.0226) (xy 441.728606 -297.023028)
			(xy 440.329066 -297.023028) (xy 440.318902 -297.022594) (xy 440.300125 -297.014802) (xy 440.28576 -297.000417)
			(xy 440.277993 -296.981631) (xy 440.277504 -296.971466) (xy 434.236368 -296.971466) (xy 434.235908 -296.981635)
			(xy 434.228136 -297.000427) (xy 434.213761 -297.014813) (xy 434.194974 -297.0226) (xy 434.184806 -297.023028)
			(xy 432.785266 -297.023028) (xy 432.775102 -297.022594) (xy 432.756325 -297.014802) (xy 432.74196 -297.000417)
			(xy 432.734193 -296.981631) (xy 432.733704 -296.971466) (xy 426.692568 -296.971466) (xy 426.692108 -296.981635)
			(xy 426.684336 -297.000427) (xy 426.669961 -297.014813) (xy 426.651174 -297.0226) (xy 426.641006 -297.023028)
			(xy 425.241466 -297.023028) (xy 425.231302 -297.022594) (xy 425.212525 -297.014802) (xy 425.19816 -297.000417)
			(xy 425.190393 -296.981631) (xy 425.189904 -296.971466) (xy 419.148768 -296.971466) (xy 419.148308 -296.981635)
			(xy 419.140536 -297.000427) (xy 419.126161 -297.014813) (xy 419.107374 -297.0226) (xy 419.097206 -297.023028)
			(xy 417.697666 -297.023028) (xy 417.687502 -297.022594) (xy 417.668725 -297.014802) (xy 417.65436 -297.000417)
			(xy 417.646593 -296.981631) (xy 417.646104 -296.971466) (xy 411.604968 -296.971466) (xy 411.604508 -296.981635)
			(xy 411.596736 -297.000427) (xy 411.582361 -297.014813) (xy 411.563574 -297.0226) (xy 411.553406 -297.023028)
			(xy 410.153866 -297.023028) (xy 410.143702 -297.022594) (xy 410.124925 -297.014802) (xy 410.11056 -297.000417)
			(xy 410.102793 -296.981631) (xy 410.102304 -296.971466) (xy 383.515787 -296.971466) (xy 383.53558 -297.052575)
			(xy 383.559343 -297.183516) (xy 383.575232 -297.315644) (xy 383.58319 -297.448486) (xy 383.583688 -297.515026)
			(xy 383.58319 -297.581566) (xy 383.575232 -297.714408) (xy 383.562372 -297.82135) (xy 406.002236 -297.82135)
			(xy 406.002236 -297.41241) (xy 406.002672 -297.402239) (xy 406.010453 -297.383445) (xy 406.024835 -297.36906)
			(xy 406.043627 -297.361274) (xy 406.053798 -297.360848) (xy 407.453338 -297.360848) (xy 407.463499 -297.361303)
			(xy 407.482271 -297.369091) (xy 407.496636 -297.383469) (xy 407.504407 -297.402248) (xy 407.5049 -297.41241)
			(xy 407.5049 -297.82135) (xy 413.546036 -297.82135) (xy 413.546036 -297.41241) (xy 413.546472 -297.402239)
			(xy 413.554253 -297.383445) (xy 413.568635 -297.36906) (xy 413.587427 -297.361274) (xy 413.597598 -297.360848)
			(xy 414.997138 -297.360848) (xy 415.007299 -297.361303) (xy 415.026071 -297.369091) (xy 415.040436 -297.383469)
			(xy 415.048207 -297.402248) (xy 415.0487 -297.41241) (xy 415.0487 -297.82135) (xy 421.089836 -297.82135)
			(xy 421.089836 -297.41241) (xy 421.090272 -297.402239) (xy 421.098053 -297.383445) (xy 421.112435 -297.36906)
			(xy 421.131227 -297.361274) (xy 421.141398 -297.360848) (xy 422.540938 -297.360848) (xy 422.551099 -297.361303)
			(xy 422.569871 -297.369091) (xy 422.584236 -297.383469) (xy 422.592007 -297.402248) (xy 422.5925 -297.41241)
			(xy 422.5925 -297.82135) (xy 428.633636 -297.82135) (xy 428.633636 -297.41241) (xy 428.634072 -297.402239)
			(xy 428.641853 -297.383445) (xy 428.656235 -297.36906) (xy 428.675027 -297.361274) (xy 428.685198 -297.360848)
			(xy 430.084738 -297.360848) (xy 430.094899 -297.361303) (xy 430.113671 -297.369091) (xy 430.128036 -297.383469)
			(xy 430.135807 -297.402248) (xy 430.1363 -297.41241) (xy 430.1363 -297.82135) (xy 436.177436 -297.82135)
			(xy 436.177436 -297.41241) (xy 436.177872 -297.402239) (xy 436.185653 -297.383445) (xy 436.200035 -297.36906)
			(xy 436.218827 -297.361274) (xy 436.228998 -297.360848) (xy 437.628538 -297.360848) (xy 437.638699 -297.361303)
			(xy 437.657471 -297.369091) (xy 437.671836 -297.383469) (xy 437.679607 -297.402248) (xy 437.6801 -297.41241)
			(xy 437.6801 -297.82135) (xy 443.721236 -297.82135) (xy 443.721236 -297.41241) (xy 443.721672 -297.402239)
			(xy 443.729453 -297.383445) (xy 443.743835 -297.36906) (xy 443.762627 -297.361274) (xy 443.772798 -297.360848)
			(xy 445.172338 -297.360848) (xy 445.182499 -297.361303) (xy 445.201271 -297.369091) (xy 445.215636 -297.383469)
			(xy 445.223407 -297.402248) (xy 445.2239 -297.41241) (xy 445.2239 -297.82135) (xy 451.265036 -297.82135)
			(xy 451.265036 -297.41241) (xy 451.265472 -297.402239) (xy 451.273253 -297.383445) (xy 451.287635 -297.36906)
			(xy 451.306427 -297.361274) (xy 451.316598 -297.360848) (xy 452.716138 -297.360848) (xy 452.726299 -297.361303)
			(xy 452.745071 -297.369091) (xy 452.759436 -297.383469) (xy 452.767207 -297.402248) (xy 452.7677 -297.41241)
			(xy 452.7677 -297.82135) (xy 458.808836 -297.82135) (xy 458.808836 -297.41241) (xy 458.809272 -297.402239)
			(xy 458.817053 -297.383445) (xy 458.831435 -297.36906) (xy 458.850227 -297.361274) (xy 458.860398 -297.360848)
			(xy 460.259938 -297.360848) (xy 460.270099 -297.361303) (xy 460.288871 -297.369091) (xy 460.303236 -297.383469)
			(xy 460.311007 -297.402248) (xy 460.3115 -297.41241) (xy 460.3115 -297.82135) (xy 460.310996 -297.831514)
			(xy 460.303235 -297.8503) (xy 460.288874 -297.864685) (xy 460.270101 -297.872479) (xy 460.259938 -297.872912)
			(xy 458.860398 -297.872912) (xy 458.85022 -297.872537) (xy 458.831416 -297.864742) (xy 458.817029 -297.850341)
			(xy 458.809253 -297.831528) (xy 458.808836 -297.82135) (xy 452.7677 -297.82135) (xy 452.767196 -297.831514)
			(xy 452.759435 -297.8503) (xy 452.745074 -297.864685) (xy 452.726301 -297.872479) (xy 452.716138 -297.872912)
			(xy 451.316598 -297.872912) (xy 451.30642 -297.872537) (xy 451.287616 -297.864742) (xy 451.273229 -297.850341)
			(xy 451.265453 -297.831528) (xy 451.265036 -297.82135) (xy 445.2239 -297.82135) (xy 445.223396 -297.831514)
			(xy 445.215635 -297.8503) (xy 445.201274 -297.864685) (xy 445.182501 -297.872479) (xy 445.172338 -297.872912)
			(xy 443.772798 -297.872912) (xy 443.76262 -297.872537) (xy 443.743816 -297.864742) (xy 443.729429 -297.850341)
			(xy 443.721653 -297.831528) (xy 443.721236 -297.82135) (xy 437.6801 -297.82135) (xy 437.679596 -297.831514)
			(xy 437.671835 -297.8503) (xy 437.657474 -297.864685) (xy 437.638701 -297.872479) (xy 437.628538 -297.872912)
			(xy 436.228998 -297.872912) (xy 436.21882 -297.872537) (xy 436.200016 -297.864742) (xy 436.185629 -297.850341)
			(xy 436.177853 -297.831528) (xy 436.177436 -297.82135) (xy 430.1363 -297.82135) (xy 430.135796 -297.831514)
			(xy 430.128035 -297.8503) (xy 430.113674 -297.864685) (xy 430.094901 -297.872479) (xy 430.084738 -297.872912)
			(xy 428.685198 -297.872912) (xy 428.67502 -297.872537) (xy 428.656216 -297.864742) (xy 428.641829 -297.850341)
			(xy 428.634053 -297.831528) (xy 428.633636 -297.82135) (xy 422.5925 -297.82135) (xy 422.591996 -297.831514)
			(xy 422.584235 -297.8503) (xy 422.569874 -297.864685) (xy 422.551101 -297.872479) (xy 422.540938 -297.872912)
			(xy 421.141398 -297.872912) (xy 421.13122 -297.872537) (xy 421.112416 -297.864742) (xy 421.098029 -297.850341)
			(xy 421.090253 -297.831528) (xy 421.089836 -297.82135) (xy 415.0487 -297.82135) (xy 415.048196 -297.831514)
			(xy 415.040435 -297.8503) (xy 415.026074 -297.864685) (xy 415.007301 -297.872479) (xy 414.997138 -297.872912)
			(xy 413.597598 -297.872912) (xy 413.58742 -297.872537) (xy 413.568616 -297.864742) (xy 413.554229 -297.850341)
			(xy 413.546453 -297.831528) (xy 413.546036 -297.82135) (xy 407.5049 -297.82135) (xy 407.504396 -297.831514)
			(xy 407.496635 -297.8503) (xy 407.482274 -297.864685) (xy 407.463501 -297.872479) (xy 407.453338 -297.872912)
			(xy 406.053798 -297.872912) (xy 406.04362 -297.872537) (xy 406.024816 -297.864742) (xy 406.010429 -297.850341)
			(xy 406.002653 -297.831528) (xy 406.002236 -297.82135) (xy 383.562372 -297.82135) (xy 383.559343 -297.846536)
			(xy 383.53558 -297.977477) (xy 383.50403 -298.106763) (xy 383.464804 -298.233931) (xy 383.418043 -298.358525)
			(xy 383.363914 -298.4801) (xy 383.302612 -298.59822) (xy 383.258836 -298.671488) (xy 410.102304 -298.671488)
			(xy 410.102304 -298.262548) (xy 410.102761 -298.252396) (xy 410.110542 -298.233644) (xy 410.124928 -298.219319)
			(xy 410.143713 -298.211619) (xy 410.153866 -298.21124) (xy 411.553406 -298.21124) (xy 411.563533 -298.211722)
			(xy 411.582254 -298.219452) (xy 411.59661 -298.233739) (xy 411.604429 -298.252423) (xy 411.604968 -298.262548)
			(xy 411.604968 -298.671488) (xy 417.646104 -298.671488) (xy 417.646104 -298.262548) (xy 417.646561 -298.252396)
			(xy 417.654342 -298.233644) (xy 417.668728 -298.219319) (xy 417.687513 -298.211619) (xy 417.697666 -298.21124)
			(xy 419.097206 -298.21124) (xy 419.107333 -298.211722) (xy 419.126054 -298.219452) (xy 419.14041 -298.233739)
			(xy 419.148229 -298.252423) (xy 419.148768 -298.262548) (xy 419.148768 -298.671488) (xy 425.189904 -298.671488)
			(xy 425.189904 -298.262548) (xy 425.190361 -298.252396) (xy 425.198142 -298.233644) (xy 425.212528 -298.219319)
			(xy 425.231313 -298.211619) (xy 425.241466 -298.21124) (xy 426.641006 -298.21124) (xy 426.651133 -298.211722)
			(xy 426.669854 -298.219452) (xy 426.68421 -298.233739) (xy 426.692029 -298.252423) (xy 426.692568 -298.262548)
			(xy 426.692568 -298.671488) (xy 432.733704 -298.671488) (xy 432.733704 -298.262548) (xy 432.734161 -298.252396)
			(xy 432.741942 -298.233644) (xy 432.756328 -298.219319) (xy 432.775113 -298.211619) (xy 432.785266 -298.21124)
			(xy 434.184806 -298.21124) (xy 434.194933 -298.211722) (xy 434.213654 -298.219452) (xy 434.22801 -298.233739)
			(xy 434.235829 -298.252423) (xy 434.236368 -298.262548) (xy 434.236368 -298.671488) (xy 440.277504 -298.671488)
			(xy 440.277504 -298.262548) (xy 440.277961 -298.252396) (xy 440.285742 -298.233644) (xy 440.300128 -298.219319)
			(xy 440.318913 -298.211619) (xy 440.329066 -298.21124) (xy 441.728606 -298.21124) (xy 441.738733 -298.211722)
			(xy 441.757454 -298.219452) (xy 441.77181 -298.233739) (xy 441.779629 -298.252423) (xy 441.780168 -298.262548)
			(xy 441.780168 -298.671488) (xy 447.821304 -298.671488) (xy 447.821304 -298.262548) (xy 447.821761 -298.252396)
			(xy 447.829542 -298.233644) (xy 447.843928 -298.219319) (xy 447.862713 -298.211619) (xy 447.872866 -298.21124)
			(xy 449.272406 -298.21124) (xy 449.282533 -298.211722) (xy 449.301254 -298.219452) (xy 449.31561 -298.233739)
			(xy 449.323429 -298.252423) (xy 449.323968 -298.262548) (xy 449.323968 -298.671488) (xy 455.365104 -298.671488)
			(xy 455.365104 -298.262548) (xy 455.365561 -298.252396) (xy 455.373342 -298.233644) (xy 455.387728 -298.219319)
			(xy 455.406513 -298.211619) (xy 455.416666 -298.21124) (xy 456.816206 -298.21124) (xy 456.826333 -298.211722)
			(xy 456.845054 -298.219452) (xy 456.85941 -298.233739) (xy 456.867229 -298.252423) (xy 456.867768 -298.262548)
			(xy 456.867768 -298.671488) (xy 462.908904 -298.671488) (xy 462.908904 -298.262548) (xy 462.909361 -298.252396)
			(xy 462.917142 -298.233644) (xy 462.931528 -298.219319) (xy 462.950313 -298.211619) (xy 462.960466 -298.21124)
			(xy 464.360006 -298.21124) (xy 464.370133 -298.211722) (xy 464.388854 -298.219452) (xy 464.40321 -298.233739)
			(xy 464.411029 -298.252423) (xy 464.411568 -298.262548) (xy 464.411568 -298.671488) (xy 464.411168 -298.681645)
			(xy 464.40337 -298.700404) (xy 464.388966 -298.714729) (xy 464.370166 -298.722423) (xy 464.360006 -298.722796)
			(xy 462.960466 -298.722796) (xy 462.950342 -298.722302) (xy 462.931626 -298.71457) (xy 462.917273 -298.700287)
			(xy 462.909448 -298.68161) (xy 462.908904 -298.671488) (xy 456.867768 -298.671488) (xy 456.867368 -298.681645)
			(xy 456.85957 -298.700404) (xy 456.845166 -298.714729) (xy 456.826366 -298.722423) (xy 456.816206 -298.722796)
			(xy 455.416666 -298.722796) (xy 455.406542 -298.722302) (xy 455.387826 -298.71457) (xy 455.373473 -298.700287)
			(xy 455.365648 -298.68161) (xy 455.365104 -298.671488) (xy 449.323968 -298.671488) (xy 449.323568 -298.681645)
			(xy 449.31577 -298.700404) (xy 449.301366 -298.714729) (xy 449.282566 -298.722423) (xy 449.272406 -298.722796)
			(xy 447.872866 -298.722796) (xy 447.862742 -298.722302) (xy 447.844026 -298.71457) (xy 447.829673 -298.700287)
			(xy 447.821848 -298.68161) (xy 447.821304 -298.671488) (xy 441.780168 -298.671488) (xy 441.779768 -298.681645)
			(xy 441.77197 -298.700404) (xy 441.757566 -298.714729) (xy 441.738766 -298.722423) (xy 441.728606 -298.722796)
			(xy 440.329066 -298.722796) (xy 440.318942 -298.722302) (xy 440.300226 -298.71457) (xy 440.285873 -298.700287)
			(xy 440.278048 -298.68161) (xy 440.277504 -298.671488) (xy 434.236368 -298.671488) (xy 434.235968 -298.681645)
			(xy 434.22817 -298.700404) (xy 434.213766 -298.714729) (xy 434.194966 -298.722423) (xy 434.184806 -298.722796)
			(xy 432.785266 -298.722796) (xy 432.775142 -298.722302) (xy 432.756426 -298.71457) (xy 432.742073 -298.700287)
			(xy 432.734248 -298.68161) (xy 432.733704 -298.671488) (xy 426.692568 -298.671488) (xy 426.692168 -298.681645)
			(xy 426.68437 -298.700404) (xy 426.669966 -298.714729) (xy 426.651166 -298.722423) (xy 426.641006 -298.722796)
			(xy 425.241466 -298.722796) (xy 425.231342 -298.722302) (xy 425.212626 -298.71457) (xy 425.198273 -298.700287)
			(xy 425.190448 -298.68161) (xy 425.189904 -298.671488) (xy 419.148768 -298.671488) (xy 419.148368 -298.681645)
			(xy 419.14057 -298.700404) (xy 419.126166 -298.714729) (xy 419.107366 -298.722423) (xy 419.097206 -298.722796)
			(xy 417.697666 -298.722796) (xy 417.687542 -298.722302) (xy 417.668826 -298.71457) (xy 417.654473 -298.700287)
			(xy 417.646648 -298.68161) (xy 417.646104 -298.671488) (xy 411.604968 -298.671488) (xy 411.604568 -298.681645)
			(xy 411.59677 -298.700404) (xy 411.582366 -298.714729) (xy 411.563566 -298.722423) (xy 411.553406 -298.722796)
			(xy 410.153866 -298.722796) (xy 410.143742 -298.722302) (xy 410.125026 -298.71457) (xy 410.110673 -298.700287)
			(xy 410.102848 -298.68161) (xy 410.102304 -298.671488) (xy 383.258836 -298.671488) (xy 383.234355 -298.712462)
			(xy 383.159389 -298.822418) (xy 383.07798 -298.927694) (xy 382.990422 -299.027912) (xy 382.897027 -299.122715)
			(xy 382.798129 -299.211763) (xy 382.694083 -299.294737) (xy 382.585261 -299.371341) (xy 382.472052 -299.441299)
			(xy 382.354862 -299.504361) (xy 382.318143 -299.521372) (xy 406.002236 -299.521372) (xy 406.002236 -299.112432)
			(xy 406.002648 -299.102275) (xy 406.01044 -299.083517) (xy 406.02484 -299.069191) (xy 406.043639 -299.061496)
			(xy 406.053798 -299.061124) (xy 407.453338 -299.061124) (xy 407.463465 -299.061595) (xy 407.482184 -299.069332)
			(xy 407.496539 -299.083623) (xy 407.504359 -299.102307) (xy 407.5049 -299.112432) (xy 407.5049 -299.521372)
			(xy 413.546036 -299.521372) (xy 413.546036 -299.112432) (xy 413.546448 -299.102275) (xy 413.55424 -299.083517)
			(xy 413.56864 -299.069191) (xy 413.587439 -299.061496) (xy 413.597598 -299.061124) (xy 414.997138 -299.061124)
			(xy 415.007265 -299.061595) (xy 415.025984 -299.069332) (xy 415.040339 -299.083623) (xy 415.048159 -299.102307)
			(xy 415.0487 -299.112432) (xy 415.0487 -299.521372) (xy 421.089836 -299.521372) (xy 421.089836 -299.112432)
			(xy 421.090248 -299.102275) (xy 421.09804 -299.083517) (xy 421.11244 -299.069191) (xy 421.131239 -299.061496)
			(xy 421.141398 -299.061124) (xy 422.540938 -299.061124) (xy 422.551065 -299.061595) (xy 422.569784 -299.069332)
			(xy 422.584139 -299.083623) (xy 422.591959 -299.102307) (xy 422.5925 -299.112432) (xy 422.5925 -299.521372)
			(xy 428.633636 -299.521372) (xy 428.633636 -299.112432) (xy 428.634048 -299.102275) (xy 428.64184 -299.083517)
			(xy 428.65624 -299.069191) (xy 428.675039 -299.061496) (xy 428.685198 -299.061124) (xy 430.084738 -299.061124)
			(xy 430.094865 -299.061595) (xy 430.113584 -299.069332) (xy 430.127939 -299.083623) (xy 430.135759 -299.102307)
			(xy 430.1363 -299.112432) (xy 430.1363 -299.521372) (xy 436.177436 -299.521372) (xy 436.177436 -299.112432)
			(xy 436.177848 -299.102275) (xy 436.18564 -299.083517) (xy 436.20004 -299.069191) (xy 436.218839 -299.061496)
			(xy 436.228998 -299.061124) (xy 437.628538 -299.061124) (xy 437.638665 -299.061595) (xy 437.657384 -299.069332)
			(xy 437.671739 -299.083623) (xy 437.679559 -299.102307) (xy 437.6801 -299.112432) (xy 437.6801 -299.521372)
			(xy 443.721236 -299.521372) (xy 443.721236 -299.112432) (xy 443.721648 -299.102275) (xy 443.72944 -299.083517)
			(xy 443.74384 -299.069191) (xy 443.762639 -299.061496) (xy 443.772798 -299.061124) (xy 445.172338 -299.061124)
			(xy 445.182465 -299.061595) (xy 445.201184 -299.069332) (xy 445.215539 -299.083623) (xy 445.223359 -299.102307)
			(xy 445.2239 -299.112432) (xy 445.2239 -299.521372) (xy 451.265036 -299.521372) (xy 451.265036 -299.112432)
			(xy 451.265448 -299.102275) (xy 451.27324 -299.083517) (xy 451.28764 -299.069191) (xy 451.306439 -299.061496)
			(xy 451.316598 -299.061124) (xy 452.716138 -299.061124) (xy 452.726265 -299.061595) (xy 452.744984 -299.069332)
			(xy 452.759339 -299.083623) (xy 452.767159 -299.102307) (xy 452.7677 -299.112432) (xy 452.7677 -299.521372)
			(xy 458.808836 -299.521372) (xy 458.808836 -299.112432) (xy 458.809248 -299.102275) (xy 458.81704 -299.083517)
			(xy 458.83144 -299.069191) (xy 458.850239 -299.061496) (xy 458.860398 -299.061124) (xy 460.259938 -299.061124)
			(xy 460.270065 -299.061595) (xy 460.288784 -299.069332) (xy 460.303139 -299.083623) (xy 460.310959 -299.102307)
			(xy 460.3115 -299.112432) (xy 460.3115 -299.521372) (xy 460.311056 -299.531524) (xy 460.303269 -299.550276)
			(xy 460.288879 -299.564601) (xy 460.270092 -299.572301) (xy 460.259938 -299.57268) (xy 458.860398 -299.57268)
			(xy 458.850274 -299.572176) (xy 458.831556 -299.564451) (xy 458.817201 -299.55017) (xy 458.809378 -299.531494)
			(xy 458.808836 -299.521372) (xy 452.7677 -299.521372) (xy 452.767256 -299.531524) (xy 452.759469 -299.550276)
			(xy 452.745079 -299.564601) (xy 452.726292 -299.572301) (xy 452.716138 -299.57268) (xy 451.316598 -299.57268)
			(xy 451.306474 -299.572176) (xy 451.287756 -299.564451) (xy 451.273401 -299.55017) (xy 451.265578 -299.531494)
			(xy 451.265036 -299.521372) (xy 445.2239 -299.521372) (xy 445.223456 -299.531524) (xy 445.215669 -299.550276)
			(xy 445.201279 -299.564601) (xy 445.182492 -299.572301) (xy 445.172338 -299.57268) (xy 443.772798 -299.57268)
			(xy 443.762674 -299.572176) (xy 443.743956 -299.564451) (xy 443.729601 -299.55017) (xy 443.721778 -299.531494)
			(xy 443.721236 -299.521372) (xy 437.6801 -299.521372) (xy 437.679656 -299.531524) (xy 437.671869 -299.550276)
			(xy 437.657479 -299.564601) (xy 437.638692 -299.572301) (xy 437.628538 -299.57268) (xy 436.228998 -299.57268)
			(xy 436.218874 -299.572176) (xy 436.200156 -299.564451) (xy 436.185801 -299.55017) (xy 436.177978 -299.531494)
			(xy 436.177436 -299.521372) (xy 430.1363 -299.521372) (xy 430.135856 -299.531524) (xy 430.128069 -299.550276)
			(xy 430.113679 -299.564601) (xy 430.094892 -299.572301) (xy 430.084738 -299.57268) (xy 428.685198 -299.57268)
			(xy 428.675074 -299.572176) (xy 428.656356 -299.564451) (xy 428.642001 -299.55017) (xy 428.634178 -299.531494)
			(xy 428.633636 -299.521372) (xy 422.5925 -299.521372) (xy 422.592056 -299.531524) (xy 422.584269 -299.550276)
			(xy 422.569879 -299.564601) (xy 422.551092 -299.572301) (xy 422.540938 -299.57268) (xy 421.141398 -299.57268)
			(xy 421.131274 -299.572176) (xy 421.112556 -299.564451) (xy 421.098201 -299.55017) (xy 421.090378 -299.531494)
			(xy 421.089836 -299.521372) (xy 415.0487 -299.521372) (xy 415.048256 -299.531524) (xy 415.040469 -299.550276)
			(xy 415.026079 -299.564601) (xy 415.007292 -299.572301) (xy 414.997138 -299.57268) (xy 413.597598 -299.57268)
			(xy 413.587474 -299.572176) (xy 413.568756 -299.564451) (xy 413.554401 -299.55017) (xy 413.546578 -299.531494)
			(xy 413.546036 -299.521372) (xy 407.5049 -299.521372) (xy 407.504456 -299.531524) (xy 407.496669 -299.550276)
			(xy 407.482279 -299.564601) (xy 407.463492 -299.572301) (xy 407.453338 -299.57268) (xy 406.053798 -299.57268)
			(xy 406.043674 -299.572176) (xy 406.024956 -299.564451) (xy 406.010601 -299.55017) (xy 406.002778 -299.531494)
			(xy 406.002236 -299.521372) (xy 382.318143 -299.521372) (xy 382.234111 -299.560302) (xy 382.11023 -299.608922)
			(xy 381.983664 -299.650046) (xy 381.854864 -299.683527) (xy 381.724293 -299.709245) (xy 381.592417 -299.727109)
			(xy 381.459709 -299.737054) (xy 381.326644 -299.739045) (xy 381.193698 -299.733074) (xy 381.061347 -299.719164)
			(xy 380.930065 -299.697363) (xy 380.800322 -299.66775) (xy 380.672581 -299.630431) (xy 380.547302 -299.585539)
			(xy 380.424931 -299.533235) (xy 380.305907 -299.473706) (xy 380.190656 -299.407166) (xy 380.079591 -299.333853)
			(xy 379.97311 -299.254029) (xy 379.871592 -299.167979) (xy 379.775403 -299.076013) (xy 379.684885 -298.978458)
			(xy 379.600364 -298.875665) (xy 379.522142 -298.768001) (xy 379.450498 -298.655851) (xy 379.385689 -298.539618)
			(xy 379.327948 -298.419717) (xy 379.277481 -298.296578) (xy 379.234468 -298.170641) (xy 379.199064 -298.042356)
			(xy 379.171395 -297.912184) (xy 379.15156 -297.780591) (xy 379.139631 -297.648046) (xy 379.13565 -297.515026)
			(xy 340.603586 -297.515026) (xy 340.603088 -297.581566) (xy 340.59513 -297.714408) (xy 340.579241 -297.846536)
			(xy 340.555478 -297.977477) (xy 340.523928 -298.106763) (xy 340.484702 -298.233931) (xy 340.437941 -298.358525)
			(xy 340.383812 -298.4801) (xy 340.32251 -298.59822) (xy 340.254253 -298.712462) (xy 340.179287 -298.822418)
			(xy 340.097878 -298.927694) (xy 340.01032 -299.027912) (xy 339.916925 -299.122715) (xy 339.818027 -299.211763)
			(xy 339.713981 -299.294737) (xy 339.605159 -299.371341) (xy 339.49195 -299.441299) (xy 339.37476 -299.504361)
			(xy 339.254009 -299.560302) (xy 339.130128 -299.608922) (xy 339.003562 -299.650046) (xy 338.874762 -299.683527)
			(xy 338.744191 -299.709245) (xy 338.612315 -299.727109) (xy 338.479607 -299.737054) (xy 338.346542 -299.739045)
			(xy 338.213596 -299.733074) (xy 338.081245 -299.719164) (xy 337.949963 -299.697363) (xy 337.82022 -299.66775)
			(xy 337.692479 -299.630431) (xy 337.5672 -299.585539) (xy 337.444829 -299.533235) (xy 337.325805 -299.473706)
			(xy 337.210554 -299.407166) (xy 337.099489 -299.333853) (xy 336.993008 -299.254029) (xy 336.89149 -299.167979)
			(xy 336.795301 -299.076013) (xy 336.704783 -298.978458) (xy 336.620262 -298.875665) (xy 336.54204 -298.768001)
			(xy 336.470396 -298.655851) (xy 336.405587 -298.539618) (xy 336.347846 -298.419717) (xy 336.297379 -298.296578)
			(xy 336.254366 -298.170641) (xy 336.218962 -298.042356) (xy 336.191293 -297.912184) (xy 336.171458 -297.780591)
			(xy 336.159529 -297.648046) (xy 336.155548 -297.515026) (xy 309.6387 -297.515026) (xy 309.6387 -297.82135)
			(xy 309.638196 -297.831514) (xy 309.630435 -297.8503) (xy 309.616074 -297.864685) (xy 309.597301 -297.872479)
			(xy 309.587138 -297.872912) (xy 308.187598 -297.872912) (xy 308.17742 -297.872537) (xy 308.158616 -297.864742)
			(xy 308.144229 -297.850341) (xy 308.136453 -297.831528) (xy 308.136036 -297.82135) (xy 302.0949 -297.82135)
			(xy 302.094396 -297.831514) (xy 302.086635 -297.8503) (xy 302.072274 -297.864685) (xy 302.053501 -297.872479)
			(xy 302.043338 -297.872912) (xy 300.643798 -297.872912) (xy 300.63362 -297.872537) (xy 300.614816 -297.864742)
			(xy 300.600429 -297.850341) (xy 300.592653 -297.831528) (xy 300.592236 -297.82135) (xy 294.5511 -297.82135)
			(xy 294.550596 -297.831514) (xy 294.542835 -297.8503) (xy 294.528474 -297.864685) (xy 294.509701 -297.872479)
			(xy 294.499538 -297.872912) (xy 293.099998 -297.872912) (xy 293.08982 -297.872537) (xy 293.071016 -297.864742)
			(xy 293.056629 -297.850341) (xy 293.048853 -297.831528) (xy 293.048436 -297.82135) (xy 287.0073 -297.82135)
			(xy 287.006796 -297.831514) (xy 286.999035 -297.8503) (xy 286.984674 -297.864685) (xy 286.965901 -297.872479)
			(xy 286.955738 -297.872912) (xy 285.556198 -297.872912) (xy 285.54602 -297.872537) (xy 285.527216 -297.864742)
			(xy 285.512829 -297.850341) (xy 285.505053 -297.831528) (xy 285.504636 -297.82135) (xy 279.4635 -297.82135)
			(xy 279.462996 -297.831514) (xy 279.455235 -297.8503) (xy 279.440874 -297.864685) (xy 279.422101 -297.872479)
			(xy 279.411938 -297.872912) (xy 278.012398 -297.872912) (xy 278.00222 -297.872537) (xy 277.983416 -297.864742)
			(xy 277.969029 -297.850341) (xy 277.961253 -297.831528) (xy 277.960836 -297.82135) (xy 271.9197 -297.82135)
			(xy 271.919196 -297.831514) (xy 271.911435 -297.8503) (xy 271.897074 -297.864685) (xy 271.878301 -297.872479)
			(xy 271.868138 -297.872912) (xy 270.468598 -297.872912) (xy 270.45842 -297.872537) (xy 270.439616 -297.864742)
			(xy 270.425229 -297.850341) (xy 270.417453 -297.831528) (xy 270.417036 -297.82135) (xy 264.3759 -297.82135)
			(xy 264.375396 -297.831514) (xy 264.367635 -297.8503) (xy 264.353274 -297.864685) (xy 264.334501 -297.872479)
			(xy 264.324338 -297.872912) (xy 262.924798 -297.872912) (xy 262.91462 -297.872537) (xy 262.895816 -297.864742)
			(xy 262.881429 -297.850341) (xy 262.873653 -297.831528) (xy 262.873236 -297.82135) (xy 256.8321 -297.82135)
			(xy 256.831596 -297.831514) (xy 256.823835 -297.8503) (xy 256.809474 -297.864685) (xy 256.790701 -297.872479)
			(xy 256.780538 -297.872912) (xy 255.380998 -297.872912) (xy 255.37082 -297.872537) (xy 255.352016 -297.864742)
			(xy 255.337629 -297.850341) (xy 255.329853 -297.831528) (xy 255.329436 -297.82135) (xy 212.371432 -297.82135)
			(xy 212.370995 -297.831522) (xy 212.36322 -297.850321) (xy 212.348838 -297.864709) (xy 212.330042 -297.872491)
			(xy 212.31987 -297.872912) (xy 210.92033 -297.872912) (xy 210.910154 -297.87251) (xy 210.891351 -297.864726)
			(xy 210.876963 -297.850333) (xy 210.869186 -297.831526) (xy 210.868768 -297.82135) (xy 204.827632 -297.82135)
			(xy 204.827195 -297.831522) (xy 204.81942 -297.850321) (xy 204.805038 -297.864709) (xy 204.786242 -297.872491)
			(xy 204.77607 -297.872912) (xy 203.37653 -297.872912) (xy 203.366354 -297.87251) (xy 203.347551 -297.864726)
			(xy 203.333163 -297.850333) (xy 203.325386 -297.831526) (xy 203.324968 -297.82135) (xy 197.283832 -297.82135)
			(xy 197.283395 -297.831522) (xy 197.27562 -297.850321) (xy 197.261238 -297.864709) (xy 197.242442 -297.872491)
			(xy 197.23227 -297.872912) (xy 195.83273 -297.872912) (xy 195.822554 -297.87251) (xy 195.803751 -297.864726)
			(xy 195.789363 -297.850333) (xy 195.781586 -297.831526) (xy 195.781168 -297.82135) (xy 189.740032 -297.82135)
			(xy 189.739595 -297.831522) (xy 189.73182 -297.850321) (xy 189.717438 -297.864709) (xy 189.698642 -297.872491)
			(xy 189.68847 -297.872912) (xy 188.28893 -297.872912) (xy 188.278754 -297.87251) (xy 188.259951 -297.864726)
			(xy 188.245563 -297.850333) (xy 188.237786 -297.831526) (xy 188.237368 -297.82135) (xy 182.196232 -297.82135)
			(xy 182.195795 -297.831522) (xy 182.18802 -297.850321) (xy 182.173638 -297.864709) (xy 182.154842 -297.872491)
			(xy 182.14467 -297.872912) (xy 180.74513 -297.872912) (xy 180.734954 -297.87251) (xy 180.716151 -297.864726)
			(xy 180.701763 -297.850333) (xy 180.693986 -297.831526) (xy 180.693568 -297.82135) (xy 174.652432 -297.82135)
			(xy 174.651995 -297.831522) (xy 174.64422 -297.850321) (xy 174.629838 -297.864709) (xy 174.611042 -297.872491)
			(xy 174.60087 -297.872912) (xy 173.20133 -297.872912) (xy 173.191154 -297.87251) (xy 173.172351 -297.864726)
			(xy 173.157963 -297.850333) (xy 173.150186 -297.831526) (xy 173.149768 -297.82135) (xy 167.108632 -297.82135)
			(xy 167.108195 -297.831522) (xy 167.10042 -297.850321) (xy 167.086038 -297.864709) (xy 167.067242 -297.872491)
			(xy 167.05707 -297.872912) (xy 165.65753 -297.872912) (xy 165.647354 -297.87251) (xy 165.628551 -297.864726)
			(xy 165.614163 -297.850333) (xy 165.606386 -297.831526) (xy 165.605968 -297.82135) (xy 159.564832 -297.82135)
			(xy 159.564395 -297.831522) (xy 159.55662 -297.850321) (xy 159.542238 -297.864709) (xy 159.523442 -297.872491)
			(xy 159.51327 -297.872912) (xy 158.11373 -297.872912) (xy 158.103554 -297.87251) (xy 158.084751 -297.864726)
			(xy 158.070363 -297.850333) (xy 158.062586 -297.831526) (xy 158.062168 -297.82135) (xy 135.622304 -297.82135)
			(xy 135.619275 -297.846536) (xy 135.595512 -297.977477) (xy 135.563962 -298.106763) (xy 135.524736 -298.233931)
			(xy 135.477975 -298.358525) (xy 135.423846 -298.4801) (xy 135.362544 -298.59822) (xy 135.318768 -298.671488)
			(xy 162.162236 -298.671488) (xy 162.162236 -298.262548) (xy 162.162662 -298.252393) (xy 162.170448 -298.233634)
			(xy 162.184845 -298.219308) (xy 162.203641 -298.211613) (xy 162.213798 -298.21124) (xy 163.613338 -298.21124)
			(xy 163.623467 -298.211695) (xy 163.642189 -298.219436) (xy 163.656544 -298.233731) (xy 163.664362 -298.252421)
			(xy 163.6649 -298.262548) (xy 163.6649 -298.671488) (xy 169.706036 -298.671488) (xy 169.706036 -298.262548)
			(xy 169.706462 -298.252393) (xy 169.714248 -298.233634) (xy 169.728645 -298.219308) (xy 169.747441 -298.211613)
			(xy 169.757598 -298.21124) (xy 171.157138 -298.21124) (xy 171.167267 -298.211695) (xy 171.185989 -298.219436)
			(xy 171.200344 -298.233731) (xy 171.208162 -298.252421) (xy 171.2087 -298.262548) (xy 171.2087 -298.671488)
			(xy 177.249836 -298.671488) (xy 177.249836 -298.262548) (xy 177.250262 -298.252393) (xy 177.258048 -298.233634)
			(xy 177.272445 -298.219308) (xy 177.291241 -298.211613) (xy 177.301398 -298.21124) (xy 178.700938 -298.21124)
			(xy 178.711067 -298.211695) (xy 178.729789 -298.219436) (xy 178.744144 -298.233731) (xy 178.751962 -298.252421)
			(xy 178.7525 -298.262548) (xy 178.7525 -298.671488) (xy 184.793636 -298.671488) (xy 184.793636 -298.262548)
			(xy 184.794062 -298.252393) (xy 184.801848 -298.233634) (xy 184.816245 -298.219308) (xy 184.835041 -298.211613)
			(xy 184.845198 -298.21124) (xy 186.244738 -298.21124) (xy 186.254867 -298.211695) (xy 186.273589 -298.219436)
			(xy 186.287944 -298.233731) (xy 186.295762 -298.252421) (xy 186.2963 -298.262548) (xy 186.2963 -298.671488)
			(xy 192.337436 -298.671488) (xy 192.337436 -298.262548) (xy 192.337862 -298.252393) (xy 192.345648 -298.233634)
			(xy 192.360045 -298.219308) (xy 192.378841 -298.211613) (xy 192.388998 -298.21124) (xy 193.788538 -298.21124)
			(xy 193.798667 -298.211695) (xy 193.817389 -298.219436) (xy 193.831744 -298.233731) (xy 193.839562 -298.252421)
			(xy 193.8401 -298.262548) (xy 193.8401 -298.671488) (xy 199.881236 -298.671488) (xy 199.881236 -298.262548)
			(xy 199.881662 -298.252393) (xy 199.889448 -298.233634) (xy 199.903845 -298.219308) (xy 199.922641 -298.211613)
			(xy 199.932798 -298.21124) (xy 201.332338 -298.21124) (xy 201.342467 -298.211695) (xy 201.361189 -298.219436)
			(xy 201.375544 -298.233731) (xy 201.383362 -298.252421) (xy 201.3839 -298.262548) (xy 201.3839 -298.671488)
			(xy 207.425036 -298.671488) (xy 207.425036 -298.262548) (xy 207.425462 -298.252393) (xy 207.433248 -298.233634)
			(xy 207.447645 -298.219308) (xy 207.466441 -298.211613) (xy 207.476598 -298.21124) (xy 208.876138 -298.21124)
			(xy 208.886267 -298.211695) (xy 208.904989 -298.219436) (xy 208.919344 -298.233731) (xy 208.927162 -298.252421)
			(xy 208.9277 -298.262548) (xy 208.9277 -298.671488) (xy 214.968836 -298.671488) (xy 214.968836 -298.262548)
			(xy 214.969262 -298.252393) (xy 214.977048 -298.233634) (xy 214.991445 -298.219308) (xy 215.010241 -298.211613)
			(xy 215.020398 -298.21124) (xy 216.419938 -298.21124) (xy 216.430067 -298.211695) (xy 216.448789 -298.219436)
			(xy 216.463144 -298.233731) (xy 216.470962 -298.252421) (xy 216.4715 -298.262548) (xy 216.4715 -298.671488)
			(xy 259.429504 -298.671488) (xy 259.429504 -298.262548) (xy 259.429961 -298.252396) (xy 259.437742 -298.233644)
			(xy 259.452128 -298.219319) (xy 259.470913 -298.211619) (xy 259.481066 -298.21124) (xy 260.880606 -298.21124)
			(xy 260.890733 -298.211722) (xy 260.909454 -298.219452) (xy 260.92381 -298.233739) (xy 260.931629 -298.252423)
			(xy 260.932168 -298.262548) (xy 260.932168 -298.671488) (xy 266.973304 -298.671488) (xy 266.973304 -298.262548)
			(xy 266.973761 -298.252396) (xy 266.981542 -298.233644) (xy 266.995928 -298.219319) (xy 267.014713 -298.211619)
			(xy 267.024866 -298.21124) (xy 268.424406 -298.21124) (xy 268.434533 -298.211722) (xy 268.453254 -298.219452)
			(xy 268.46761 -298.233739) (xy 268.475429 -298.252423) (xy 268.475968 -298.262548) (xy 268.475968 -298.671488)
			(xy 274.517104 -298.671488) (xy 274.517104 -298.262548) (xy 274.517561 -298.252396) (xy 274.525342 -298.233644)
			(xy 274.539728 -298.219319) (xy 274.558513 -298.211619) (xy 274.568666 -298.21124) (xy 275.968206 -298.21124)
			(xy 275.978333 -298.211722) (xy 275.997054 -298.219452) (xy 276.01141 -298.233739) (xy 276.019229 -298.252423)
			(xy 276.019768 -298.262548) (xy 276.019768 -298.671488) (xy 282.060904 -298.671488) (xy 282.060904 -298.262548)
			(xy 282.061361 -298.252396) (xy 282.069142 -298.233644) (xy 282.083528 -298.219319) (xy 282.102313 -298.211619)
			(xy 282.112466 -298.21124) (xy 283.512006 -298.21124) (xy 283.522133 -298.211722) (xy 283.540854 -298.219452)
			(xy 283.55521 -298.233739) (xy 283.563029 -298.252423) (xy 283.563568 -298.262548) (xy 283.563568 -298.671488)
			(xy 289.604704 -298.671488) (xy 289.604704 -298.262548) (xy 289.605161 -298.252396) (xy 289.612942 -298.233644)
			(xy 289.627328 -298.219319) (xy 289.646113 -298.211619) (xy 289.656266 -298.21124) (xy 291.055806 -298.21124)
			(xy 291.065933 -298.211722) (xy 291.084654 -298.219452) (xy 291.09901 -298.233739) (xy 291.106829 -298.252423)
			(xy 291.107368 -298.262548) (xy 291.107368 -298.671488) (xy 297.148504 -298.671488) (xy 297.148504 -298.262548)
			(xy 297.148961 -298.252396) (xy 297.156742 -298.233644) (xy 297.171128 -298.219319) (xy 297.189913 -298.211619)
			(xy 297.200066 -298.21124) (xy 298.599606 -298.21124) (xy 298.609733 -298.211722) (xy 298.628454 -298.219452)
			(xy 298.64281 -298.233739) (xy 298.650629 -298.252423) (xy 298.651168 -298.262548) (xy 298.651168 -298.671488)
			(xy 304.692304 -298.671488) (xy 304.692304 -298.262548) (xy 304.692761 -298.252396) (xy 304.700542 -298.233644)
			(xy 304.714928 -298.219319) (xy 304.733713 -298.211619) (xy 304.743866 -298.21124) (xy 306.143406 -298.21124)
			(xy 306.153533 -298.211722) (xy 306.172254 -298.219452) (xy 306.18661 -298.233739) (xy 306.194429 -298.252423)
			(xy 306.194968 -298.262548) (xy 306.194968 -298.671488) (xy 312.236104 -298.671488) (xy 312.236104 -298.262548)
			(xy 312.236561 -298.252396) (xy 312.244342 -298.233644) (xy 312.258728 -298.219319) (xy 312.277513 -298.211619)
			(xy 312.287666 -298.21124) (xy 313.687206 -298.21124) (xy 313.697333 -298.211722) (xy 313.716054 -298.219452)
			(xy 313.73041 -298.233739) (xy 313.738229 -298.252423) (xy 313.738768 -298.262548) (xy 313.738768 -298.671488)
			(xy 313.738368 -298.681645) (xy 313.73057 -298.700404) (xy 313.716166 -298.714729) (xy 313.697366 -298.722423)
			(xy 313.687206 -298.722796) (xy 312.287666 -298.722796) (xy 312.277542 -298.722302) (xy 312.258826 -298.71457)
			(xy 312.244473 -298.700287) (xy 312.236648 -298.68161) (xy 312.236104 -298.671488) (xy 306.194968 -298.671488)
			(xy 306.194568 -298.681645) (xy 306.18677 -298.700404) (xy 306.172366 -298.714729) (xy 306.153566 -298.722423)
			(xy 306.143406 -298.722796) (xy 304.743866 -298.722796) (xy 304.733742 -298.722302) (xy 304.715026 -298.71457)
			(xy 304.700673 -298.700287) (xy 304.692848 -298.68161) (xy 304.692304 -298.671488) (xy 298.651168 -298.671488)
			(xy 298.650768 -298.681645) (xy 298.64297 -298.700404) (xy 298.628566 -298.714729) (xy 298.609766 -298.722423)
			(xy 298.599606 -298.722796) (xy 297.200066 -298.722796) (xy 297.189942 -298.722302) (xy 297.171226 -298.71457)
			(xy 297.156873 -298.700287) (xy 297.149048 -298.68161) (xy 297.148504 -298.671488) (xy 291.107368 -298.671488)
			(xy 291.106968 -298.681645) (xy 291.09917 -298.700404) (xy 291.084766 -298.714729) (xy 291.065966 -298.722423)
			(xy 291.055806 -298.722796) (xy 289.656266 -298.722796) (xy 289.646142 -298.722302) (xy 289.627426 -298.71457)
			(xy 289.613073 -298.700287) (xy 289.605248 -298.68161) (xy 289.604704 -298.671488) (xy 283.563568 -298.671488)
			(xy 283.563168 -298.681645) (xy 283.55537 -298.700404) (xy 283.540966 -298.714729) (xy 283.522166 -298.722423)
			(xy 283.512006 -298.722796) (xy 282.112466 -298.722796) (xy 282.102342 -298.722302) (xy 282.083626 -298.71457)
			(xy 282.069273 -298.700287) (xy 282.061448 -298.68161) (xy 282.060904 -298.671488) (xy 276.019768 -298.671488)
			(xy 276.019368 -298.681645) (xy 276.01157 -298.700404) (xy 275.997166 -298.714729) (xy 275.978366 -298.722423)
			(xy 275.968206 -298.722796) (xy 274.568666 -298.722796) (xy 274.558542 -298.722302) (xy 274.539826 -298.71457)
			(xy 274.525473 -298.700287) (xy 274.517648 -298.68161) (xy 274.517104 -298.671488) (xy 268.475968 -298.671488)
			(xy 268.475568 -298.681645) (xy 268.46777 -298.700404) (xy 268.453366 -298.714729) (xy 268.434566 -298.722423)
			(xy 268.424406 -298.722796) (xy 267.024866 -298.722796) (xy 267.014742 -298.722302) (xy 266.996026 -298.71457)
			(xy 266.981673 -298.700287) (xy 266.973848 -298.68161) (xy 266.973304 -298.671488) (xy 260.932168 -298.671488)
			(xy 260.931768 -298.681645) (xy 260.92397 -298.700404) (xy 260.909566 -298.714729) (xy 260.890766 -298.722423)
			(xy 260.880606 -298.722796) (xy 259.481066 -298.722796) (xy 259.470942 -298.722302) (xy 259.452226 -298.71457)
			(xy 259.437873 -298.700287) (xy 259.430048 -298.68161) (xy 259.429504 -298.671488) (xy 216.4715 -298.671488)
			(xy 216.471069 -298.681641) (xy 216.463277 -298.700393) (xy 216.448883 -298.714717) (xy 216.430093 -298.722417)
			(xy 216.419938 -298.722796) (xy 215.020398 -298.722796) (xy 215.010276 -298.722276) (xy 214.991561 -298.714554)
			(xy 214.977206 -298.700279) (xy 214.969381 -298.681608) (xy 214.968836 -298.671488) (xy 208.9277 -298.671488)
			(xy 208.927269 -298.681641) (xy 208.919477 -298.700393) (xy 208.905083 -298.714717) (xy 208.886293 -298.722417)
			(xy 208.876138 -298.722796) (xy 207.476598 -298.722796) (xy 207.466476 -298.722276) (xy 207.447761 -298.714554)
			(xy 207.433406 -298.700279) (xy 207.425581 -298.681608) (xy 207.425036 -298.671488) (xy 201.3839 -298.671488)
			(xy 201.383469 -298.681641) (xy 201.375677 -298.700393) (xy 201.361283 -298.714717) (xy 201.342493 -298.722417)
			(xy 201.332338 -298.722796) (xy 199.932798 -298.722796) (xy 199.922676 -298.722276) (xy 199.903961 -298.714554)
			(xy 199.889606 -298.700279) (xy 199.881781 -298.681608) (xy 199.881236 -298.671488) (xy 193.8401 -298.671488)
			(xy 193.839669 -298.681641) (xy 193.831877 -298.700393) (xy 193.817483 -298.714717) (xy 193.798693 -298.722417)
			(xy 193.788538 -298.722796) (xy 192.388998 -298.722796) (xy 192.378876 -298.722276) (xy 192.360161 -298.714554)
			(xy 192.345806 -298.700279) (xy 192.337981 -298.681608) (xy 192.337436 -298.671488) (xy 186.2963 -298.671488)
			(xy 186.295869 -298.681641) (xy 186.288077 -298.700393) (xy 186.273683 -298.714717) (xy 186.254893 -298.722417)
			(xy 186.244738 -298.722796) (xy 184.845198 -298.722796) (xy 184.835076 -298.722276) (xy 184.816361 -298.714554)
			(xy 184.802006 -298.700279) (xy 184.794181 -298.681608) (xy 184.793636 -298.671488) (xy 178.7525 -298.671488)
			(xy 178.752069 -298.681641) (xy 178.744277 -298.700393) (xy 178.729883 -298.714717) (xy 178.711093 -298.722417)
			(xy 178.700938 -298.722796) (xy 177.301398 -298.722796) (xy 177.291276 -298.722276) (xy 177.272561 -298.714554)
			(xy 177.258206 -298.700279) (xy 177.250381 -298.681608) (xy 177.249836 -298.671488) (xy 171.2087 -298.671488)
			(xy 171.208269 -298.681641) (xy 171.200477 -298.700393) (xy 171.186083 -298.714717) (xy 171.167293 -298.722417)
			(xy 171.157138 -298.722796) (xy 169.757598 -298.722796) (xy 169.747476 -298.722276) (xy 169.728761 -298.714554)
			(xy 169.714406 -298.700279) (xy 169.706581 -298.681608) (xy 169.706036 -298.671488) (xy 163.6649 -298.671488)
			(xy 163.664469 -298.681641) (xy 163.656677 -298.700393) (xy 163.642283 -298.714717) (xy 163.623493 -298.722417)
			(xy 163.613338 -298.722796) (xy 162.213798 -298.722796) (xy 162.203676 -298.722276) (xy 162.184961 -298.714554)
			(xy 162.170606 -298.700279) (xy 162.162781 -298.681608) (xy 162.162236 -298.671488) (xy 135.318768 -298.671488)
			(xy 135.294287 -298.712462) (xy 135.219321 -298.822418) (xy 135.137912 -298.927694) (xy 135.050354 -299.027912)
			(xy 134.956959 -299.122715) (xy 134.858061 -299.211763) (xy 134.754015 -299.294737) (xy 134.645193 -299.371341)
			(xy 134.531984 -299.441299) (xy 134.414794 -299.504361) (xy 134.378075 -299.521372) (xy 158.062168 -299.521372)
			(xy 158.062168 -299.112432) (xy 158.062647 -299.102284) (xy 158.070426 -299.083538) (xy 158.084805 -299.069215)
			(xy 158.10358 -299.061508) (xy 158.11373 -299.061124) (xy 159.51327 -299.061124) (xy 159.523393 -299.06165)
			(xy 159.54211 -299.069365) (xy 159.556467 -299.08364) (xy 159.56429 -299.102312) (xy 159.564832 -299.112432)
			(xy 159.564832 -299.521372) (xy 165.605968 -299.521372) (xy 165.605968 -299.112432) (xy 165.606447 -299.102284)
			(xy 165.614226 -299.083538) (xy 165.628605 -299.069215) (xy 165.64738 -299.061508) (xy 165.65753 -299.061124)
			(xy 167.05707 -299.061124) (xy 167.067193 -299.06165) (xy 167.08591 -299.069365) (xy 167.100267 -299.08364)
			(xy 167.10809 -299.102312) (xy 167.108632 -299.112432) (xy 167.108632 -299.521372) (xy 173.149768 -299.521372)
			(xy 173.149768 -299.112432) (xy 173.150247 -299.102284) (xy 173.158026 -299.083538) (xy 173.172405 -299.069215)
			(xy 173.19118 -299.061508) (xy 173.20133 -299.061124) (xy 174.60087 -299.061124) (xy 174.610993 -299.06165)
			(xy 174.62971 -299.069365) (xy 174.644067 -299.08364) (xy 174.65189 -299.102312) (xy 174.652432 -299.112432)
			(xy 174.652432 -299.521372) (xy 180.693568 -299.521372) (xy 180.693568 -299.112432) (xy 180.694047 -299.102284)
			(xy 180.701826 -299.083538) (xy 180.716205 -299.069215) (xy 180.73498 -299.061508) (xy 180.74513 -299.061124)
			(xy 182.14467 -299.061124) (xy 182.154793 -299.06165) (xy 182.17351 -299.069365) (xy 182.187867 -299.08364)
			(xy 182.19569 -299.102312) (xy 182.196232 -299.112432) (xy 182.196232 -299.521372) (xy 188.237368 -299.521372)
			(xy 188.237368 -299.112432) (xy 188.237847 -299.102284) (xy 188.245626 -299.083538) (xy 188.260005 -299.069215)
			(xy 188.27878 -299.061508) (xy 188.28893 -299.061124) (xy 189.68847 -299.061124) (xy 189.698593 -299.06165)
			(xy 189.71731 -299.069365) (xy 189.731667 -299.08364) (xy 189.73949 -299.102312) (xy 189.740032 -299.112432)
			(xy 189.740032 -299.521372) (xy 195.781168 -299.521372) (xy 195.781168 -299.112432) (xy 195.781647 -299.102284)
			(xy 195.789426 -299.083538) (xy 195.803805 -299.069215) (xy 195.82258 -299.061508) (xy 195.83273 -299.061124)
			(xy 197.23227 -299.061124) (xy 197.242393 -299.06165) (xy 197.26111 -299.069365) (xy 197.275467 -299.08364)
			(xy 197.28329 -299.102312) (xy 197.283832 -299.112432) (xy 197.283832 -299.521372) (xy 203.324968 -299.521372)
			(xy 203.324968 -299.112432) (xy 203.325447 -299.102284) (xy 203.333226 -299.083538) (xy 203.347605 -299.069215)
			(xy 203.36638 -299.061508) (xy 203.37653 -299.061124) (xy 204.77607 -299.061124) (xy 204.786193 -299.06165)
			(xy 204.80491 -299.069365) (xy 204.819267 -299.08364) (xy 204.82709 -299.102312) (xy 204.827632 -299.112432)
			(xy 204.827632 -299.521372) (xy 210.868768 -299.521372) (xy 210.868768 -299.112432) (xy 210.869247 -299.102284)
			(xy 210.877026 -299.083538) (xy 210.891405 -299.069215) (xy 210.91018 -299.061508) (xy 210.92033 -299.061124)
			(xy 212.31987 -299.061124) (xy 212.329993 -299.06165) (xy 212.34871 -299.069365) (xy 212.363067 -299.08364)
			(xy 212.37089 -299.102312) (xy 212.371432 -299.112432) (xy 212.371432 -299.521372) (xy 255.329436 -299.521372)
			(xy 255.329436 -299.112432) (xy 255.329848 -299.102275) (xy 255.33764 -299.083517) (xy 255.35204 -299.069191)
			(xy 255.370839 -299.061496) (xy 255.380998 -299.061124) (xy 256.780538 -299.061124) (xy 256.790665 -299.061595)
			(xy 256.809384 -299.069332) (xy 256.823739 -299.083623) (xy 256.831559 -299.102307) (xy 256.8321 -299.112432)
			(xy 256.8321 -299.521372) (xy 262.873236 -299.521372) (xy 262.873236 -299.112432) (xy 262.873648 -299.102275)
			(xy 262.88144 -299.083517) (xy 262.89584 -299.069191) (xy 262.914639 -299.061496) (xy 262.924798 -299.061124)
			(xy 264.324338 -299.061124) (xy 264.334465 -299.061595) (xy 264.353184 -299.069332) (xy 264.367539 -299.083623)
			(xy 264.375359 -299.102307) (xy 264.3759 -299.112432) (xy 264.3759 -299.521372) (xy 270.417036 -299.521372)
			(xy 270.417036 -299.112432) (xy 270.417448 -299.102275) (xy 270.42524 -299.083517) (xy 270.43964 -299.069191)
			(xy 270.458439 -299.061496) (xy 270.468598 -299.061124) (xy 271.868138 -299.061124) (xy 271.878265 -299.061595)
			(xy 271.896984 -299.069332) (xy 271.911339 -299.083623) (xy 271.919159 -299.102307) (xy 271.9197 -299.112432)
			(xy 271.9197 -299.521372) (xy 277.960836 -299.521372) (xy 277.960836 -299.112432) (xy 277.961248 -299.102275)
			(xy 277.96904 -299.083517) (xy 277.98344 -299.069191) (xy 278.002239 -299.061496) (xy 278.012398 -299.061124)
			(xy 279.411938 -299.061124) (xy 279.422065 -299.061595) (xy 279.440784 -299.069332) (xy 279.455139 -299.083623)
			(xy 279.462959 -299.102307) (xy 279.4635 -299.112432) (xy 279.4635 -299.521372) (xy 285.504636 -299.521372)
			(xy 285.504636 -299.112432) (xy 285.505048 -299.102275) (xy 285.51284 -299.083517) (xy 285.52724 -299.069191)
			(xy 285.546039 -299.061496) (xy 285.556198 -299.061124) (xy 286.955738 -299.061124) (xy 286.965865 -299.061595)
			(xy 286.984584 -299.069332) (xy 286.998939 -299.083623) (xy 287.006759 -299.102307) (xy 287.0073 -299.112432)
			(xy 287.0073 -299.521372) (xy 293.048436 -299.521372) (xy 293.048436 -299.112432) (xy 293.048848 -299.102275)
			(xy 293.05664 -299.083517) (xy 293.07104 -299.069191) (xy 293.089839 -299.061496) (xy 293.099998 -299.061124)
			(xy 294.499538 -299.061124) (xy 294.509665 -299.061595) (xy 294.528384 -299.069332) (xy 294.542739 -299.083623)
			(xy 294.550559 -299.102307) (xy 294.5511 -299.112432) (xy 294.5511 -299.521372) (xy 300.592236 -299.521372)
			(xy 300.592236 -299.112432) (xy 300.592648 -299.102275) (xy 300.60044 -299.083517) (xy 300.61484 -299.069191)
			(xy 300.633639 -299.061496) (xy 300.643798 -299.061124) (xy 302.043338 -299.061124) (xy 302.053465 -299.061595)
			(xy 302.072184 -299.069332) (xy 302.086539 -299.083623) (xy 302.094359 -299.102307) (xy 302.0949 -299.112432)
			(xy 302.0949 -299.521372) (xy 308.136036 -299.521372) (xy 308.136036 -299.112432) (xy 308.136448 -299.102275)
			(xy 308.14424 -299.083517) (xy 308.15864 -299.069191) (xy 308.177439 -299.061496) (xy 308.187598 -299.061124)
			(xy 309.587138 -299.061124) (xy 309.597265 -299.061595) (xy 309.615984 -299.069332) (xy 309.630339 -299.083623)
			(xy 309.638159 -299.102307) (xy 309.6387 -299.112432) (xy 309.6387 -299.521372) (xy 309.638256 -299.531524)
			(xy 309.630469 -299.550276) (xy 309.616079 -299.564601) (xy 309.597292 -299.572301) (xy 309.587138 -299.57268)
			(xy 308.187598 -299.57268) (xy 308.177474 -299.572176) (xy 308.158756 -299.564451) (xy 308.144401 -299.55017)
			(xy 308.136578 -299.531494) (xy 308.136036 -299.521372) (xy 302.0949 -299.521372) (xy 302.094456 -299.531524)
			(xy 302.086669 -299.550276) (xy 302.072279 -299.564601) (xy 302.053492 -299.572301) (xy 302.043338 -299.57268)
			(xy 300.643798 -299.57268) (xy 300.633674 -299.572176) (xy 300.614956 -299.564451) (xy 300.600601 -299.55017)
			(xy 300.592778 -299.531494) (xy 300.592236 -299.521372) (xy 294.5511 -299.521372) (xy 294.550656 -299.531524)
			(xy 294.542869 -299.550276) (xy 294.528479 -299.564601) (xy 294.509692 -299.572301) (xy 294.499538 -299.57268)
			(xy 293.099998 -299.57268) (xy 293.089874 -299.572176) (xy 293.071156 -299.564451) (xy 293.056801 -299.55017)
			(xy 293.048978 -299.531494) (xy 293.048436 -299.521372) (xy 287.0073 -299.521372) (xy 287.006856 -299.531524)
			(xy 286.999069 -299.550276) (xy 286.984679 -299.564601) (xy 286.965892 -299.572301) (xy 286.955738 -299.57268)
			(xy 285.556198 -299.57268) (xy 285.546074 -299.572176) (xy 285.527356 -299.564451) (xy 285.513001 -299.55017)
			(xy 285.505178 -299.531494) (xy 285.504636 -299.521372) (xy 279.4635 -299.521372) (xy 279.463056 -299.531524)
			(xy 279.455269 -299.550276) (xy 279.440879 -299.564601) (xy 279.422092 -299.572301) (xy 279.411938 -299.57268)
			(xy 278.012398 -299.57268) (xy 278.002274 -299.572176) (xy 277.983556 -299.564451) (xy 277.969201 -299.55017)
			(xy 277.961378 -299.531494) (xy 277.960836 -299.521372) (xy 271.9197 -299.521372) (xy 271.919256 -299.531524)
			(xy 271.911469 -299.550276) (xy 271.897079 -299.564601) (xy 271.878292 -299.572301) (xy 271.868138 -299.57268)
			(xy 270.468598 -299.57268) (xy 270.458474 -299.572176) (xy 270.439756 -299.564451) (xy 270.425401 -299.55017)
			(xy 270.417578 -299.531494) (xy 270.417036 -299.521372) (xy 264.3759 -299.521372) (xy 264.375456 -299.531524)
			(xy 264.367669 -299.550276) (xy 264.353279 -299.564601) (xy 264.334492 -299.572301) (xy 264.324338 -299.57268)
			(xy 262.924798 -299.57268) (xy 262.914674 -299.572176) (xy 262.895956 -299.564451) (xy 262.881601 -299.55017)
			(xy 262.873778 -299.531494) (xy 262.873236 -299.521372) (xy 256.8321 -299.521372) (xy 256.831656 -299.531524)
			(xy 256.823869 -299.550276) (xy 256.809479 -299.564601) (xy 256.790692 -299.572301) (xy 256.780538 -299.57268)
			(xy 255.380998 -299.57268) (xy 255.370874 -299.572176) (xy 255.352156 -299.564451) (xy 255.337801 -299.55017)
			(xy 255.329978 -299.531494) (xy 255.329436 -299.521372) (xy 212.371432 -299.521372) (xy 212.370956 -299.53152)
			(xy 212.363176 -299.550266) (xy 212.348796 -299.564589) (xy 212.33002 -299.572296) (xy 212.31987 -299.57268)
			(xy 210.92033 -299.57268) (xy 210.910208 -299.57215) (xy 210.891491 -299.564435) (xy 210.877134 -299.550163)
			(xy 210.86931 -299.531491) (xy 210.868768 -299.521372) (xy 204.827632 -299.521372) (xy 204.827156 -299.53152)
			(xy 204.819376 -299.550266) (xy 204.804996 -299.564589) (xy 204.78622 -299.572296) (xy 204.77607 -299.57268)
			(xy 203.37653 -299.57268) (xy 203.366408 -299.57215) (xy 203.347691 -299.564435) (xy 203.333334 -299.550163)
			(xy 203.32551 -299.531491) (xy 203.324968 -299.521372) (xy 197.283832 -299.521372) (xy 197.283356 -299.53152)
			(xy 197.275576 -299.550266) (xy 197.261196 -299.564589) (xy 197.24242 -299.572296) (xy 197.23227 -299.57268)
			(xy 195.83273 -299.57268) (xy 195.822608 -299.57215) (xy 195.803891 -299.564435) (xy 195.789534 -299.550163)
			(xy 195.78171 -299.531491) (xy 195.781168 -299.521372) (xy 189.740032 -299.521372) (xy 189.739556 -299.53152)
			(xy 189.731776 -299.550266) (xy 189.717396 -299.564589) (xy 189.69862 -299.572296) (xy 189.68847 -299.57268)
			(xy 188.28893 -299.57268) (xy 188.278808 -299.57215) (xy 188.260091 -299.564435) (xy 188.245734 -299.550163)
			(xy 188.23791 -299.531491) (xy 188.237368 -299.521372) (xy 182.196232 -299.521372) (xy 182.195756 -299.53152)
			(xy 182.187976 -299.550266) (xy 182.173596 -299.564589) (xy 182.15482 -299.572296) (xy 182.14467 -299.57268)
			(xy 180.74513 -299.57268) (xy 180.735008 -299.57215) (xy 180.716291 -299.564435) (xy 180.701934 -299.550163)
			(xy 180.69411 -299.531491) (xy 180.693568 -299.521372) (xy 174.652432 -299.521372) (xy 174.651956 -299.53152)
			(xy 174.644176 -299.550266) (xy 174.629796 -299.564589) (xy 174.61102 -299.572296) (xy 174.60087 -299.57268)
			(xy 173.20133 -299.57268) (xy 173.191208 -299.57215) (xy 173.172491 -299.564435) (xy 173.158134 -299.550163)
			(xy 173.15031 -299.531491) (xy 173.149768 -299.521372) (xy 167.108632 -299.521372) (xy 167.108156 -299.53152)
			(xy 167.100376 -299.550266) (xy 167.085996 -299.564589) (xy 167.06722 -299.572296) (xy 167.05707 -299.57268)
			(xy 165.65753 -299.57268) (xy 165.647408 -299.57215) (xy 165.628691 -299.564435) (xy 165.614334 -299.550163)
			(xy 165.60651 -299.531491) (xy 165.605968 -299.521372) (xy 159.564832 -299.521372) (xy 159.564356 -299.53152)
			(xy 159.556576 -299.550266) (xy 159.542196 -299.564589) (xy 159.52342 -299.572296) (xy 159.51327 -299.57268)
			(xy 158.11373 -299.57268) (xy 158.103608 -299.57215) (xy 158.084891 -299.564435) (xy 158.070534 -299.550163)
			(xy 158.06271 -299.531491) (xy 158.062168 -299.521372) (xy 134.378075 -299.521372) (xy 134.294043 -299.560302)
			(xy 134.170162 -299.608922) (xy 134.043596 -299.650046) (xy 133.914796 -299.683527) (xy 133.784225 -299.709245)
			(xy 133.652349 -299.727109) (xy 133.519641 -299.737054) (xy 133.386576 -299.739045) (xy 133.25363 -299.733074)
			(xy 133.121279 -299.719164) (xy 132.989997 -299.697363) (xy 132.860254 -299.66775) (xy 132.732513 -299.630431)
			(xy 132.607234 -299.585539) (xy 132.484863 -299.533235) (xy 132.365839 -299.473706) (xy 132.250588 -299.407166)
			(xy 132.139523 -299.333853) (xy 132.033042 -299.254029) (xy 131.931524 -299.167979) (xy 131.835335 -299.076013)
			(xy 131.744817 -298.978458) (xy 131.660296 -298.875665) (xy 131.582074 -298.768001) (xy 131.51043 -298.655851)
			(xy 131.445621 -298.539618) (xy 131.38788 -298.419717) (xy 131.337413 -298.296578) (xy 131.2944 -298.170641)
			(xy 131.258996 -298.042356) (xy 131.231327 -297.912184) (xy 131.211492 -297.780591) (xy 131.199563 -297.648046)
			(xy 131.195582 -297.515026) (xy 92.663518 -297.515026) (xy 92.66302 -297.581566) (xy 92.655062 -297.714408)
			(xy 92.639173 -297.846536) (xy 92.61541 -297.977477) (xy 92.58386 -298.106763) (xy 92.544634 -298.233931)
			(xy 92.497873 -298.358525) (xy 92.443744 -298.4801) (xy 92.382442 -298.59822) (xy 92.314185 -298.712462)
			(xy 92.239219 -298.822418) (xy 92.15781 -298.927694) (xy 92.070252 -299.027912) (xy 91.976857 -299.122715)
			(xy 91.877959 -299.211763) (xy 91.773913 -299.294737) (xy 91.665091 -299.371341) (xy 91.551882 -299.441299)
			(xy 91.434692 -299.504361) (xy 91.313941 -299.560302) (xy 91.19006 -299.608922) (xy 91.063494 -299.650046)
			(xy 90.934694 -299.683527) (xy 90.804123 -299.709245) (xy 90.672247 -299.727109) (xy 90.539539 -299.737054)
			(xy 90.406474 -299.739045) (xy 90.273528 -299.733074) (xy 90.141177 -299.719164) (xy 90.009895 -299.697363)
			(xy 89.880152 -299.66775) (xy 89.752411 -299.630431) (xy 89.627132 -299.585539) (xy 89.504761 -299.533235)
			(xy 89.385737 -299.473706) (xy 89.270486 -299.407166) (xy 89.159421 -299.333853) (xy 89.05294 -299.254029)
			(xy 88.951422 -299.167979) (xy 88.855233 -299.076013) (xy 88.764715 -298.978458) (xy 88.680194 -298.875665)
			(xy 88.601972 -298.768001) (xy 88.530328 -298.655851) (xy 88.465519 -298.539618) (xy 88.407778 -298.419717)
			(xy 88.357311 -298.296578) (xy 88.314298 -298.170641) (xy 88.278894 -298.042356) (xy 88.251225 -297.912184)
			(xy 88.23139 -297.780591) (xy 88.219461 -297.648046) (xy 88.21548 -297.515026) (xy 61.698632 -297.515026)
			(xy 61.698632 -297.82135) (xy 61.698195 -297.831522) (xy 61.69042 -297.850321) (xy 61.676038 -297.864709)
			(xy 61.657242 -297.872491) (xy 61.64707 -297.872912) (xy 60.24753 -297.872912) (xy 60.237354 -297.87251)
			(xy 60.218551 -297.864726) (xy 60.204163 -297.850333) (xy 60.196386 -297.831526) (xy 60.195968 -297.82135)
			(xy 54.154832 -297.82135) (xy 54.154395 -297.831522) (xy 54.14662 -297.850321) (xy 54.132238 -297.864709)
			(xy 54.113442 -297.872491) (xy 54.10327 -297.872912) (xy 52.70373 -297.872912) (xy 52.693554 -297.87251)
			(xy 52.674751 -297.864726) (xy 52.660363 -297.850333) (xy 52.652586 -297.831526) (xy 52.652168 -297.82135)
			(xy 46.611032 -297.82135) (xy 46.610595 -297.831522) (xy 46.60282 -297.850321) (xy 46.588438 -297.864709)
			(xy 46.569642 -297.872491) (xy 46.55947 -297.872912) (xy 45.15993 -297.872912) (xy 45.149754 -297.87251)
			(xy 45.130951 -297.864726) (xy 45.116563 -297.850333) (xy 45.108786 -297.831526) (xy 45.108368 -297.82135)
			(xy 39.067232 -297.82135) (xy 39.066795 -297.831522) (xy 39.05902 -297.850321) (xy 39.044638 -297.864709)
			(xy 39.025842 -297.872491) (xy 39.01567 -297.872912) (xy 37.61613 -297.872912) (xy 37.605954 -297.87251)
			(xy 37.587151 -297.864726) (xy 37.572763 -297.850333) (xy 37.564986 -297.831526) (xy 37.564568 -297.82135)
			(xy 31.523432 -297.82135) (xy 31.522995 -297.831522) (xy 31.51522 -297.850321) (xy 31.500838 -297.864709)
			(xy 31.482042 -297.872491) (xy 31.47187 -297.872912) (xy 30.07233 -297.872912) (xy 30.062154 -297.87251)
			(xy 30.043351 -297.864726) (xy 30.028963 -297.850333) (xy 30.021186 -297.831526) (xy 30.020768 -297.82135)
			(xy 23.979632 -297.82135) (xy 23.979195 -297.831522) (xy 23.97142 -297.850321) (xy 23.957038 -297.864709)
			(xy 23.938242 -297.872491) (xy 23.92807 -297.872912) (xy 22.52853 -297.872912) (xy 22.518354 -297.87251)
			(xy 22.499551 -297.864726) (xy 22.485163 -297.850333) (xy 22.477386 -297.831526) (xy 22.476968 -297.82135)
			(xy 16.435832 -297.82135) (xy 16.435395 -297.831522) (xy 16.42762 -297.850321) (xy 16.413238 -297.864709)
			(xy 16.394442 -297.872491) (xy 16.38427 -297.872912) (xy 14.98473 -297.872912) (xy 14.974554 -297.87251)
			(xy 14.955751 -297.864726) (xy 14.941363 -297.850333) (xy 14.933586 -297.831526) (xy 14.933168 -297.82135)
			(xy 8.892032 -297.82135) (xy 8.891595 -297.831522) (xy 8.88382 -297.850321) (xy 8.869438 -297.864709)
			(xy 8.850642 -297.872491) (xy 8.84047 -297.872912) (xy 7.44093 -297.872912) (xy 7.430754 -297.87251)
			(xy 7.411951 -297.864726) (xy 7.397563 -297.850333) (xy 7.389786 -297.831526) (xy 7.389368 -297.82135)
			(xy 2.509012 -297.82135) (xy 2.509012 -298.671488) (xy 11.489436 -298.671488) (xy 11.489436 -298.262548)
			(xy 11.489862 -298.252393) (xy 11.497648 -298.233634) (xy 11.512045 -298.219308) (xy 11.530841 -298.211613)
			(xy 11.540998 -298.21124) (xy 12.940538 -298.21124) (xy 12.950667 -298.211695) (xy 12.969389 -298.219436)
			(xy 12.983744 -298.233731) (xy 12.991562 -298.252421) (xy 12.9921 -298.262548) (xy 12.9921 -298.671488)
			(xy 19.033236 -298.671488) (xy 19.033236 -298.262548) (xy 19.033662 -298.252393) (xy 19.041448 -298.233634)
			(xy 19.055845 -298.219308) (xy 19.074641 -298.211613) (xy 19.084798 -298.21124) (xy 20.484338 -298.21124)
			(xy 20.494467 -298.211695) (xy 20.513189 -298.219436) (xy 20.527544 -298.233731) (xy 20.535362 -298.252421)
			(xy 20.5359 -298.262548) (xy 20.5359 -298.671488) (xy 26.577036 -298.671488) (xy 26.577036 -298.262548)
			(xy 26.577462 -298.252393) (xy 26.585248 -298.233634) (xy 26.599645 -298.219308) (xy 26.618441 -298.211613)
			(xy 26.628598 -298.21124) (xy 28.028138 -298.21124) (xy 28.038267 -298.211695) (xy 28.056989 -298.219436)
			(xy 28.071344 -298.233731) (xy 28.079162 -298.252421) (xy 28.0797 -298.262548) (xy 28.0797 -298.671488)
			(xy 34.120836 -298.671488) (xy 34.120836 -298.262548) (xy 34.121262 -298.252393) (xy 34.129048 -298.233634)
			(xy 34.143445 -298.219308) (xy 34.162241 -298.211613) (xy 34.172398 -298.21124) (xy 35.571938 -298.21124)
			(xy 35.582067 -298.211695) (xy 35.600789 -298.219436) (xy 35.615144 -298.233731) (xy 35.622962 -298.252421)
			(xy 35.6235 -298.262548) (xy 35.6235 -298.671488) (xy 41.664636 -298.671488) (xy 41.664636 -298.262548)
			(xy 41.665062 -298.252393) (xy 41.672848 -298.233634) (xy 41.687245 -298.219308) (xy 41.706041 -298.211613)
			(xy 41.716198 -298.21124) (xy 43.115738 -298.21124) (xy 43.125867 -298.211695) (xy 43.144589 -298.219436)
			(xy 43.158944 -298.233731) (xy 43.166762 -298.252421) (xy 43.1673 -298.262548) (xy 43.1673 -298.671488)
			(xy 49.208436 -298.671488) (xy 49.208436 -298.262548) (xy 49.208862 -298.252393) (xy 49.216648 -298.233634)
			(xy 49.231045 -298.219308) (xy 49.249841 -298.211613) (xy 49.259998 -298.21124) (xy 50.659538 -298.21124)
			(xy 50.669667 -298.211695) (xy 50.688389 -298.219436) (xy 50.702744 -298.233731) (xy 50.710562 -298.252421)
			(xy 50.7111 -298.262548) (xy 50.7111 -298.671488) (xy 56.752236 -298.671488) (xy 56.752236 -298.262548)
			(xy 56.752662 -298.252393) (xy 56.760448 -298.233634) (xy 56.774845 -298.219308) (xy 56.793641 -298.211613)
			(xy 56.803798 -298.21124) (xy 58.203338 -298.21124) (xy 58.213467 -298.211695) (xy 58.232189 -298.219436)
			(xy 58.246544 -298.233731) (xy 58.254362 -298.252421) (xy 58.2549 -298.262548) (xy 58.2549 -298.671488)
			(xy 64.296036 -298.671488) (xy 64.296036 -298.262548) (xy 64.296462 -298.252393) (xy 64.304248 -298.233634)
			(xy 64.318645 -298.219308) (xy 64.337441 -298.211613) (xy 64.347598 -298.21124) (xy 65.747138 -298.21124)
			(xy 65.757267 -298.211695) (xy 65.775989 -298.219436) (xy 65.790344 -298.233731) (xy 65.798162 -298.252421)
			(xy 65.7987 -298.262548) (xy 65.7987 -298.671488) (xy 65.798269 -298.681641) (xy 65.790477 -298.700393)
			(xy 65.776083 -298.714717) (xy 65.757293 -298.722417) (xy 65.747138 -298.722796) (xy 64.347598 -298.722796)
			(xy 64.337476 -298.722276) (xy 64.318761 -298.714554) (xy 64.304406 -298.700279) (xy 64.296581 -298.681608)
			(xy 64.296036 -298.671488) (xy 58.2549 -298.671488) (xy 58.254469 -298.681641) (xy 58.246677 -298.700393)
			(xy 58.232283 -298.714717) (xy 58.213493 -298.722417) (xy 58.203338 -298.722796) (xy 56.803798 -298.722796)
			(xy 56.793676 -298.722276) (xy 56.774961 -298.714554) (xy 56.760606 -298.700279) (xy 56.752781 -298.681608)
			(xy 56.752236 -298.671488) (xy 50.7111 -298.671488) (xy 50.710669 -298.681641) (xy 50.702877 -298.700393)
			(xy 50.688483 -298.714717) (xy 50.669693 -298.722417) (xy 50.659538 -298.722796) (xy 49.259998 -298.722796)
			(xy 49.249876 -298.722276) (xy 49.231161 -298.714554) (xy 49.216806 -298.700279) (xy 49.208981 -298.681608)
			(xy 49.208436 -298.671488) (xy 43.1673 -298.671488) (xy 43.166869 -298.681641) (xy 43.159077 -298.700393)
			(xy 43.144683 -298.714717) (xy 43.125893 -298.722417) (xy 43.115738 -298.722796) (xy 41.716198 -298.722796)
			(xy 41.706076 -298.722276) (xy 41.687361 -298.714554) (xy 41.673006 -298.700279) (xy 41.665181 -298.681608)
			(xy 41.664636 -298.671488) (xy 35.6235 -298.671488) (xy 35.623069 -298.681641) (xy 35.615277 -298.700393)
			(xy 35.600883 -298.714717) (xy 35.582093 -298.722417) (xy 35.571938 -298.722796) (xy 34.172398 -298.722796)
			(xy 34.162276 -298.722276) (xy 34.143561 -298.714554) (xy 34.129206 -298.700279) (xy 34.121381 -298.681608)
			(xy 34.120836 -298.671488) (xy 28.0797 -298.671488) (xy 28.079269 -298.681641) (xy 28.071477 -298.700393)
			(xy 28.057083 -298.714717) (xy 28.038293 -298.722417) (xy 28.028138 -298.722796) (xy 26.628598 -298.722796)
			(xy 26.618476 -298.722276) (xy 26.599761 -298.714554) (xy 26.585406 -298.700279) (xy 26.577581 -298.681608)
			(xy 26.577036 -298.671488) (xy 20.5359 -298.671488) (xy 20.535469 -298.681641) (xy 20.527677 -298.700393)
			(xy 20.513283 -298.714717) (xy 20.494493 -298.722417) (xy 20.484338 -298.722796) (xy 19.084798 -298.722796)
			(xy 19.074676 -298.722276) (xy 19.055961 -298.714554) (xy 19.041606 -298.700279) (xy 19.033781 -298.681608)
			(xy 19.033236 -298.671488) (xy 12.9921 -298.671488) (xy 12.991669 -298.681641) (xy 12.983877 -298.700393)
			(xy 12.969483 -298.714717) (xy 12.950693 -298.722417) (xy 12.940538 -298.722796) (xy 11.540998 -298.722796)
			(xy 11.530876 -298.722276) (xy 11.512161 -298.714554) (xy 11.497806 -298.700279) (xy 11.489981 -298.681608)
			(xy 11.489436 -298.671488) (xy 2.509012 -298.671488) (xy 2.509012 -299.521372) (xy 7.389368 -299.521372)
			(xy 7.389368 -299.112432) (xy 7.389847 -299.102284) (xy 7.397626 -299.083538) (xy 7.412005 -299.069215)
			(xy 7.43078 -299.061508) (xy 7.44093 -299.061124) (xy 8.84047 -299.061124) (xy 8.850593 -299.06165)
			(xy 8.86931 -299.069365) (xy 8.883667 -299.08364) (xy 8.89149 -299.102312) (xy 8.892032 -299.112432)
			(xy 8.892032 -299.521372) (xy 14.933168 -299.521372) (xy 14.933168 -299.112432) (xy 14.933647 -299.102284)
			(xy 14.941426 -299.083538) (xy 14.955805 -299.069215) (xy 14.97458 -299.061508) (xy 14.98473 -299.061124)
			(xy 16.38427 -299.061124) (xy 16.394393 -299.06165) (xy 16.41311 -299.069365) (xy 16.427467 -299.08364)
			(xy 16.43529 -299.102312) (xy 16.435832 -299.112432) (xy 16.435832 -299.521372) (xy 22.476968 -299.521372)
			(xy 22.476968 -299.112432) (xy 22.477447 -299.102284) (xy 22.485226 -299.083538) (xy 22.499605 -299.069215)
			(xy 22.51838 -299.061508) (xy 22.52853 -299.061124) (xy 23.92807 -299.061124) (xy 23.938193 -299.06165)
			(xy 23.95691 -299.069365) (xy 23.971267 -299.08364) (xy 23.97909 -299.102312) (xy 23.979632 -299.112432)
			(xy 23.979632 -299.521372) (xy 30.020768 -299.521372) (xy 30.020768 -299.112432) (xy 30.021247 -299.102284)
			(xy 30.029026 -299.083538) (xy 30.043405 -299.069215) (xy 30.06218 -299.061508) (xy 30.07233 -299.061124)
			(xy 31.47187 -299.061124) (xy 31.481993 -299.06165) (xy 31.50071 -299.069365) (xy 31.515067 -299.08364)
			(xy 31.52289 -299.102312) (xy 31.523432 -299.112432) (xy 31.523432 -299.521372) (xy 37.564568 -299.521372)
			(xy 37.564568 -299.112432) (xy 37.565047 -299.102284) (xy 37.572826 -299.083538) (xy 37.587205 -299.069215)
			(xy 37.60598 -299.061508) (xy 37.61613 -299.061124) (xy 39.01567 -299.061124) (xy 39.025793 -299.06165)
			(xy 39.04451 -299.069365) (xy 39.058867 -299.08364) (xy 39.06669 -299.102312) (xy 39.067232 -299.112432)
			(xy 39.067232 -299.521372) (xy 45.108368 -299.521372) (xy 45.108368 -299.112432) (xy 45.108847 -299.102284)
			(xy 45.116626 -299.083538) (xy 45.131005 -299.069215) (xy 45.14978 -299.061508) (xy 45.15993 -299.061124)
			(xy 46.55947 -299.061124) (xy 46.569593 -299.06165) (xy 46.58831 -299.069365) (xy 46.602667 -299.08364)
			(xy 46.61049 -299.102312) (xy 46.611032 -299.112432) (xy 46.611032 -299.521372) (xy 52.652168 -299.521372)
			(xy 52.652168 -299.112432) (xy 52.652647 -299.102284) (xy 52.660426 -299.083538) (xy 52.674805 -299.069215)
			(xy 52.69358 -299.061508) (xy 52.70373 -299.061124) (xy 54.10327 -299.061124) (xy 54.113393 -299.06165)
			(xy 54.13211 -299.069365) (xy 54.146467 -299.08364) (xy 54.15429 -299.102312) (xy 54.154832 -299.112432)
			(xy 54.154832 -299.521372) (xy 60.195968 -299.521372) (xy 60.195968 -299.112432) (xy 60.196447 -299.102284)
			(xy 60.204226 -299.083538) (xy 60.218605 -299.069215) (xy 60.23738 -299.061508) (xy 60.24753 -299.061124)
			(xy 61.64707 -299.061124) (xy 61.657193 -299.06165) (xy 61.67591 -299.069365) (xy 61.690267 -299.08364)
			(xy 61.69809 -299.102312) (xy 61.698632 -299.112432) (xy 61.698632 -299.521372) (xy 61.698156 -299.53152)
			(xy 61.690376 -299.550266) (xy 61.675996 -299.564589) (xy 61.65722 -299.572296) (xy 61.64707 -299.57268)
			(xy 60.24753 -299.57268) (xy 60.237408 -299.57215) (xy 60.218691 -299.564435) (xy 60.204334 -299.550163)
			(xy 60.19651 -299.531491) (xy 60.195968 -299.521372) (xy 54.154832 -299.521372) (xy 54.154356 -299.53152)
			(xy 54.146576 -299.550266) (xy 54.132196 -299.564589) (xy 54.11342 -299.572296) (xy 54.10327 -299.57268)
			(xy 52.70373 -299.57268) (xy 52.693608 -299.57215) (xy 52.674891 -299.564435) (xy 52.660534 -299.550163)
			(xy 52.65271 -299.531491) (xy 52.652168 -299.521372) (xy 46.611032 -299.521372) (xy 46.610556 -299.53152)
			(xy 46.602776 -299.550266) (xy 46.588396 -299.564589) (xy 46.56962 -299.572296) (xy 46.55947 -299.57268)
			(xy 45.15993 -299.57268) (xy 45.149808 -299.57215) (xy 45.131091 -299.564435) (xy 45.116734 -299.550163)
			(xy 45.10891 -299.531491) (xy 45.108368 -299.521372) (xy 39.067232 -299.521372) (xy 39.066756 -299.53152)
			(xy 39.058976 -299.550266) (xy 39.044596 -299.564589) (xy 39.02582 -299.572296) (xy 39.01567 -299.57268)
			(xy 37.61613 -299.57268) (xy 37.606008 -299.57215) (xy 37.587291 -299.564435) (xy 37.572934 -299.550163)
			(xy 37.56511 -299.531491) (xy 37.564568 -299.521372) (xy 31.523432 -299.521372) (xy 31.522956 -299.53152)
			(xy 31.515176 -299.550266) (xy 31.500796 -299.564589) (xy 31.48202 -299.572296) (xy 31.47187 -299.57268)
			(xy 30.07233 -299.57268) (xy 30.062208 -299.57215) (xy 30.043491 -299.564435) (xy 30.029134 -299.550163)
			(xy 30.02131 -299.531491) (xy 30.020768 -299.521372) (xy 23.979632 -299.521372) (xy 23.979156 -299.53152)
			(xy 23.971376 -299.550266) (xy 23.956996 -299.564589) (xy 23.93822 -299.572296) (xy 23.92807 -299.57268)
			(xy 22.52853 -299.57268) (xy 22.518408 -299.57215) (xy 22.499691 -299.564435) (xy 22.485334 -299.550163)
			(xy 22.47751 -299.531491) (xy 22.476968 -299.521372) (xy 16.435832 -299.521372) (xy 16.435356 -299.53152)
			(xy 16.427576 -299.550266) (xy 16.413196 -299.564589) (xy 16.39442 -299.572296) (xy 16.38427 -299.57268)
			(xy 14.98473 -299.57268) (xy 14.974608 -299.57215) (xy 14.955891 -299.564435) (xy 14.941534 -299.550163)
			(xy 14.93371 -299.531491) (xy 14.933168 -299.521372) (xy 8.892032 -299.521372) (xy 8.891556 -299.53152)
			(xy 8.883776 -299.550266) (xy 8.869396 -299.564589) (xy 8.85062 -299.572296) (xy 8.84047 -299.57268)
			(xy 7.44093 -299.57268) (xy 7.430808 -299.57215) (xy 7.412091 -299.564435) (xy 7.397734 -299.550163)
			(xy 7.38991 -299.531491) (xy 7.389368 -299.521372) (xy 2.509012 -299.521372) (xy 2.509012 -300.37151)
			(xy 11.489436 -300.37151) (xy 11.489436 -299.96257) (xy 11.489909 -299.952411) (xy 11.497693 -299.933641)
			(xy 11.512065 -299.919277) (xy 11.530838 -299.911503) (xy 11.540998 -299.911008) (xy 12.940538 -299.911008)
			(xy 12.950695 -299.911502) (xy 12.969459 -299.919283) (xy 12.983822 -299.933648) (xy 12.9916 -299.952413)
			(xy 12.9921 -299.96257) (xy 12.9921 -300.37151) (xy 19.033236 -300.37151) (xy 19.033236 -299.96257)
			(xy 19.033709 -299.952411) (xy 19.041493 -299.933641) (xy 19.055865 -299.919277) (xy 19.074638 -299.911503)
			(xy 19.084798 -299.911008) (xy 20.484338 -299.911008) (xy 20.494495 -299.911502) (xy 20.513259 -299.919283)
			(xy 20.527622 -299.933648) (xy 20.5354 -299.952413) (xy 20.5359 -299.96257) (xy 20.5359 -300.37151)
			(xy 26.577036 -300.37151) (xy 26.577036 -299.96257) (xy 26.577509 -299.952411) (xy 26.585293 -299.933641)
			(xy 26.599665 -299.919277) (xy 26.618438 -299.911503) (xy 26.628598 -299.911008) (xy 28.028138 -299.911008)
			(xy 28.038295 -299.911502) (xy 28.057059 -299.919283) (xy 28.071422 -299.933648) (xy 28.0792 -299.952413)
			(xy 28.0797 -299.96257) (xy 28.0797 -300.37151) (xy 34.120836 -300.37151) (xy 34.120836 -299.96257)
			(xy 34.121309 -299.952411) (xy 34.129093 -299.933641) (xy 34.143465 -299.919277) (xy 34.162238 -299.911503)
			(xy 34.172398 -299.911008) (xy 35.571938 -299.911008) (xy 35.582095 -299.911502) (xy 35.600859 -299.919283)
			(xy 35.615222 -299.933648) (xy 35.623 -299.952413) (xy 35.6235 -299.96257) (xy 35.6235 -300.37151)
			(xy 41.664636 -300.37151) (xy 41.664636 -299.96257) (xy 41.665109 -299.952411) (xy 41.672893 -299.933641)
			(xy 41.687265 -299.919277) (xy 41.706038 -299.911503) (xy 41.716198 -299.911008) (xy 43.115738 -299.911008)
			(xy 43.125895 -299.911502) (xy 43.144659 -299.919283) (xy 43.159022 -299.933648) (xy 43.1668 -299.952413)
			(xy 43.1673 -299.96257) (xy 43.1673 -300.37151) (xy 49.208436 -300.37151) (xy 49.208436 -299.96257)
			(xy 49.208909 -299.952411) (xy 49.216693 -299.933641) (xy 49.231065 -299.919277) (xy 49.249838 -299.911503)
			(xy 49.259998 -299.911008) (xy 50.659538 -299.911008) (xy 50.669695 -299.911502) (xy 50.688459 -299.919283)
			(xy 50.702822 -299.933648) (xy 50.7106 -299.952413) (xy 50.7111 -299.96257) (xy 50.7111 -300.37151)
			(xy 56.752236 -300.37151) (xy 56.752236 -299.96257) (xy 56.752709 -299.952411) (xy 56.760493 -299.933641)
			(xy 56.774865 -299.919277) (xy 56.793638 -299.911503) (xy 56.803798 -299.911008) (xy 58.203338 -299.911008)
			(xy 58.213495 -299.911502) (xy 58.232259 -299.919283) (xy 58.246622 -299.933648) (xy 58.2544 -299.952413)
			(xy 58.2549 -299.96257) (xy 58.2549 -300.37151) (xy 64.296036 -300.37151) (xy 64.296036 -299.96257)
			(xy 64.296509 -299.952411) (xy 64.304293 -299.933641) (xy 64.318665 -299.919277) (xy 64.337438 -299.911503)
			(xy 64.347598 -299.911008) (xy 65.747138 -299.911008) (xy 65.757295 -299.911502) (xy 65.776059 -299.919283)
			(xy 65.790422 -299.933648) (xy 65.7982 -299.952413) (xy 65.7987 -299.96257) (xy 65.7987 -300.37151)
			(xy 162.162236 -300.37151) (xy 162.162236 -299.96257) (xy 162.162709 -299.952411) (xy 162.170493 -299.933641)
			(xy 162.184865 -299.919277) (xy 162.203638 -299.911503) (xy 162.213798 -299.911008) (xy 163.613338 -299.911008)
			(xy 163.623495 -299.911502) (xy 163.642259 -299.919283) (xy 163.656622 -299.933648) (xy 163.6644 -299.952413)
			(xy 163.6649 -299.96257) (xy 163.6649 -300.37151) (xy 169.706036 -300.37151) (xy 169.706036 -299.96257)
			(xy 169.706509 -299.952411) (xy 169.714293 -299.933641) (xy 169.728665 -299.919277) (xy 169.747438 -299.911503)
			(xy 169.757598 -299.911008) (xy 171.157138 -299.911008) (xy 171.167295 -299.911502) (xy 171.186059 -299.919283)
			(xy 171.200422 -299.933648) (xy 171.2082 -299.952413) (xy 171.2087 -299.96257) (xy 171.2087 -300.37151)
			(xy 177.249836 -300.37151) (xy 177.249836 -299.96257) (xy 177.250309 -299.952411) (xy 177.258093 -299.933641)
			(xy 177.272465 -299.919277) (xy 177.291238 -299.911503) (xy 177.301398 -299.911008) (xy 178.700938 -299.911008)
			(xy 178.711095 -299.911502) (xy 178.729859 -299.919283) (xy 178.744222 -299.933648) (xy 178.752 -299.952413)
			(xy 178.7525 -299.96257) (xy 178.7525 -300.37151) (xy 184.793636 -300.37151) (xy 184.793636 -299.96257)
			(xy 184.794109 -299.952411) (xy 184.801893 -299.933641) (xy 184.816265 -299.919277) (xy 184.835038 -299.911503)
			(xy 184.845198 -299.911008) (xy 186.244738 -299.911008) (xy 186.254895 -299.911502) (xy 186.273659 -299.919283)
			(xy 186.288022 -299.933648) (xy 186.2958 -299.952413) (xy 186.2963 -299.96257) (xy 186.2963 -300.37151)
			(xy 192.337436 -300.37151) (xy 192.337436 -299.96257) (xy 192.337909 -299.952411) (xy 192.345693 -299.933641)
			(xy 192.360065 -299.919277) (xy 192.378838 -299.911503) (xy 192.388998 -299.911008) (xy 193.788538 -299.911008)
			(xy 193.798695 -299.911502) (xy 193.817459 -299.919283) (xy 193.831822 -299.933648) (xy 193.8396 -299.952413)
			(xy 193.8401 -299.96257) (xy 193.8401 -300.37151) (xy 199.881236 -300.37151) (xy 199.881236 -299.96257)
			(xy 199.881709 -299.952411) (xy 199.889493 -299.933641) (xy 199.903865 -299.919277) (xy 199.922638 -299.911503)
			(xy 199.932798 -299.911008) (xy 201.332338 -299.911008) (xy 201.342495 -299.911502) (xy 201.361259 -299.919283)
			(xy 201.375622 -299.933648) (xy 201.3834 -299.952413) (xy 201.3839 -299.96257) (xy 201.3839 -300.37151)
			(xy 207.425036 -300.37151) (xy 207.425036 -299.96257) (xy 207.425509 -299.952411) (xy 207.433293 -299.933641)
			(xy 207.447665 -299.919277) (xy 207.466438 -299.911503) (xy 207.476598 -299.911008) (xy 208.876138 -299.911008)
			(xy 208.886295 -299.911502) (xy 208.905059 -299.919283) (xy 208.919422 -299.933648) (xy 208.9272 -299.952413)
			(xy 208.9277 -299.96257) (xy 208.9277 -300.37151) (xy 214.968836 -300.37151) (xy 214.968836 -299.96257)
			(xy 214.969309 -299.952411) (xy 214.977093 -299.933641) (xy 214.991465 -299.919277) (xy 215.010238 -299.911503)
			(xy 215.020398 -299.911008) (xy 216.419938 -299.911008) (xy 216.430095 -299.911502) (xy 216.448859 -299.919283)
			(xy 216.463222 -299.933648) (xy 216.471 -299.952413) (xy 216.4715 -299.96257) (xy 216.4715 -300.37151)
			(xy 259.429504 -300.37151) (xy 259.429504 -299.96257) (xy 259.430008 -299.952414) (xy 259.437786 -299.933651)
			(xy 259.452148 -299.919288) (xy 259.470911 -299.911509) (xy 259.481066 -299.911008) (xy 260.880606 -299.911008)
			(xy 260.89076 -299.911528) (xy 260.909524 -299.919299) (xy 260.923888 -299.933656) (xy 260.931667 -299.952416)
			(xy 260.932168 -299.96257) (xy 260.932168 -300.37151) (xy 266.973304 -300.37151) (xy 266.973304 -299.96257)
			(xy 266.973808 -299.952414) (xy 266.981586 -299.933651) (xy 266.995948 -299.919288) (xy 267.014711 -299.911509)
			(xy 267.024866 -299.911008) (xy 268.424406 -299.911008) (xy 268.43456 -299.911528) (xy 268.453324 -299.919299)
			(xy 268.467688 -299.933656) (xy 268.475467 -299.952416) (xy 268.475968 -299.96257) (xy 268.475968 -300.37151)
			(xy 274.517104 -300.37151) (xy 274.517104 -299.96257) (xy 274.517608 -299.952414) (xy 274.525386 -299.933651)
			(xy 274.539748 -299.919288) (xy 274.558511 -299.911509) (xy 274.568666 -299.911008) (xy 275.968206 -299.911008)
			(xy 275.97836 -299.911528) (xy 275.997124 -299.919299) (xy 276.011488 -299.933656) (xy 276.019267 -299.952416)
			(xy 276.019768 -299.96257) (xy 276.019768 -300.37151) (xy 282.060904 -300.37151) (xy 282.060904 -299.96257)
			(xy 282.061408 -299.952414) (xy 282.069186 -299.933651) (xy 282.083548 -299.919288) (xy 282.102311 -299.911509)
			(xy 282.112466 -299.911008) (xy 283.512006 -299.911008) (xy 283.52216 -299.911528) (xy 283.540924 -299.919299)
			(xy 283.555288 -299.933656) (xy 283.563067 -299.952416) (xy 283.563568 -299.96257) (xy 283.563568 -300.37151)
			(xy 289.604704 -300.37151) (xy 289.604704 -299.96257) (xy 289.605208 -299.952414) (xy 289.612986 -299.933651)
			(xy 289.627348 -299.919288) (xy 289.646111 -299.911509) (xy 289.656266 -299.911008) (xy 291.055806 -299.911008)
			(xy 291.06596 -299.911528) (xy 291.084724 -299.919299) (xy 291.099088 -299.933656) (xy 291.106867 -299.952416)
			(xy 291.107368 -299.96257) (xy 291.107368 -300.37151) (xy 297.148504 -300.37151) (xy 297.148504 -299.96257)
			(xy 297.149008 -299.952414) (xy 297.156786 -299.933651) (xy 297.171148 -299.919288) (xy 297.189911 -299.911509)
			(xy 297.200066 -299.911008) (xy 298.599606 -299.911008) (xy 298.60976 -299.911528) (xy 298.628524 -299.919299)
			(xy 298.642888 -299.933656) (xy 298.650667 -299.952416) (xy 298.651168 -299.96257) (xy 298.651168 -300.37151)
			(xy 304.692304 -300.37151) (xy 304.692304 -299.96257) (xy 304.692808 -299.952414) (xy 304.700586 -299.933651)
			(xy 304.714948 -299.919288) (xy 304.733711 -299.911509) (xy 304.743866 -299.911008) (xy 306.143406 -299.911008)
			(xy 306.15356 -299.911528) (xy 306.172324 -299.919299) (xy 306.186688 -299.933656) (xy 306.194467 -299.952416)
			(xy 306.194968 -299.96257) (xy 306.194968 -300.37151) (xy 312.236104 -300.37151) (xy 312.236104 -299.96257)
			(xy 312.236608 -299.952414) (xy 312.244386 -299.933651) (xy 312.258748 -299.919288) (xy 312.277511 -299.911509)
			(xy 312.287666 -299.911008) (xy 313.687206 -299.911008) (xy 313.69736 -299.911528) (xy 313.716124 -299.919299)
			(xy 313.730488 -299.933656) (xy 313.738267 -299.952416) (xy 313.738768 -299.96257) (xy 313.738768 -300.37151)
			(xy 410.102304 -300.37151) (xy 410.102304 -299.96257) (xy 410.102808 -299.952414) (xy 410.110586 -299.933651)
			(xy 410.124948 -299.919288) (xy 410.143711 -299.911509) (xy 410.153866 -299.911008) (xy 411.553406 -299.911008)
			(xy 411.56356 -299.911528) (xy 411.582324 -299.919299) (xy 411.596688 -299.933656) (xy 411.604467 -299.952416)
			(xy 411.604968 -299.96257) (xy 411.604968 -300.37151) (xy 417.646104 -300.37151) (xy 417.646104 -299.96257)
			(xy 417.646608 -299.952414) (xy 417.654386 -299.933651) (xy 417.668748 -299.919288) (xy 417.687511 -299.911509)
			(xy 417.697666 -299.911008) (xy 419.097206 -299.911008) (xy 419.10736 -299.911528) (xy 419.126124 -299.919299)
			(xy 419.140488 -299.933656) (xy 419.148267 -299.952416) (xy 419.148768 -299.96257) (xy 419.148768 -300.37151)
			(xy 425.189904 -300.37151) (xy 425.189904 -299.96257) (xy 425.190408 -299.952414) (xy 425.198186 -299.933651)
			(xy 425.212548 -299.919288) (xy 425.231311 -299.911509) (xy 425.241466 -299.911008) (xy 426.641006 -299.911008)
			(xy 426.65116 -299.911528) (xy 426.669924 -299.919299) (xy 426.684288 -299.933656) (xy 426.692067 -299.952416)
			(xy 426.692568 -299.96257) (xy 426.692568 -300.37151) (xy 432.733704 -300.37151) (xy 432.733704 -299.96257)
			(xy 432.734208 -299.952414) (xy 432.741986 -299.933651) (xy 432.756348 -299.919288) (xy 432.775111 -299.911509)
			(xy 432.785266 -299.911008) (xy 434.184806 -299.911008) (xy 434.19496 -299.911528) (xy 434.213724 -299.919299)
			(xy 434.228088 -299.933656) (xy 434.235867 -299.952416) (xy 434.236368 -299.96257) (xy 434.236368 -300.37151)
			(xy 440.277504 -300.37151) (xy 440.277504 -299.96257) (xy 440.278008 -299.952414) (xy 440.285786 -299.933651)
			(xy 440.300148 -299.919288) (xy 440.318911 -299.911509) (xy 440.329066 -299.911008) (xy 441.728606 -299.911008)
			(xy 441.73876 -299.911528) (xy 441.757524 -299.919299) (xy 441.771888 -299.933656) (xy 441.779667 -299.952416)
			(xy 441.780168 -299.96257) (xy 441.780168 -300.37151) (xy 447.821304 -300.37151) (xy 447.821304 -299.96257)
			(xy 447.821808 -299.952414) (xy 447.829586 -299.933651) (xy 447.843948 -299.919288) (xy 447.862711 -299.911509)
			(xy 447.872866 -299.911008) (xy 449.272406 -299.911008) (xy 449.28256 -299.911528) (xy 449.301324 -299.919299)
			(xy 449.315688 -299.933656) (xy 449.323467 -299.952416) (xy 449.323968 -299.96257) (xy 449.323968 -300.37151)
			(xy 455.365104 -300.37151) (xy 455.365104 -299.96257) (xy 455.365608 -299.952414) (xy 455.373386 -299.933651)
			(xy 455.387748 -299.919288) (xy 455.406511 -299.911509) (xy 455.416666 -299.911008) (xy 456.816206 -299.911008)
			(xy 456.82636 -299.911528) (xy 456.845124 -299.919299) (xy 456.859488 -299.933656) (xy 456.867267 -299.952416)
			(xy 456.867768 -299.96257) (xy 456.867768 -300.37151) (xy 462.908904 -300.37151) (xy 462.908904 -299.96257)
			(xy 462.909408 -299.952414) (xy 462.917186 -299.933651) (xy 462.931548 -299.919288) (xy 462.950311 -299.911509)
			(xy 462.960466 -299.911008) (xy 464.360006 -299.911008) (xy 464.37016 -299.911528) (xy 464.388924 -299.919299)
			(xy 464.403288 -299.933656) (xy 464.411067 -299.952416) (xy 464.411568 -299.96257) (xy 464.411568 -300.37151)
			(xy 464.411075 -300.381668) (xy 464.403298 -300.400436) (xy 464.388932 -300.4148) (xy 464.370164 -300.422576)
			(xy 464.360006 -300.423072) (xy 462.960466 -300.423072) (xy 462.950307 -300.422595) (xy 462.931539 -300.414811)
			(xy 462.917176 -300.400441) (xy 462.909401 -300.381669) (xy 462.908904 -300.37151) (xy 456.867768 -300.37151)
			(xy 456.867275 -300.381668) (xy 456.859498 -300.400436) (xy 456.845132 -300.4148) (xy 456.826364 -300.422576)
			(xy 456.816206 -300.423072) (xy 455.416666 -300.423072) (xy 455.406507 -300.422595) (xy 455.387739 -300.414811)
			(xy 455.373376 -300.400441) (xy 455.365601 -300.381669) (xy 455.365104 -300.37151) (xy 449.323968 -300.37151)
			(xy 449.323475 -300.381668) (xy 449.315698 -300.400436) (xy 449.301332 -300.4148) (xy 449.282564 -300.422576)
			(xy 449.272406 -300.423072) (xy 447.872866 -300.423072) (xy 447.862707 -300.422595) (xy 447.843939 -300.414811)
			(xy 447.829576 -300.400441) (xy 447.821801 -300.381669) (xy 447.821304 -300.37151) (xy 441.780168 -300.37151)
			(xy 441.779675 -300.381668) (xy 441.771898 -300.400436) (xy 441.757532 -300.4148) (xy 441.738764 -300.422576)
			(xy 441.728606 -300.423072) (xy 440.329066 -300.423072) (xy 440.318907 -300.422595) (xy 440.300139 -300.414811)
			(xy 440.285776 -300.400441) (xy 440.278001 -300.381669) (xy 440.277504 -300.37151) (xy 434.236368 -300.37151)
			(xy 434.235875 -300.381668) (xy 434.228098 -300.400436) (xy 434.213732 -300.4148) (xy 434.194964 -300.422576)
			(xy 434.184806 -300.423072) (xy 432.785266 -300.423072) (xy 432.775107 -300.422595) (xy 432.756339 -300.414811)
			(xy 432.741976 -300.400441) (xy 432.734201 -300.381669) (xy 432.733704 -300.37151) (xy 426.692568 -300.37151)
			(xy 426.692075 -300.381668) (xy 426.684298 -300.400436) (xy 426.669932 -300.4148) (xy 426.651164 -300.422576)
			(xy 426.641006 -300.423072) (xy 425.241466 -300.423072) (xy 425.231307 -300.422595) (xy 425.212539 -300.414811)
			(xy 425.198176 -300.400441) (xy 425.190401 -300.381669) (xy 425.189904 -300.37151) (xy 419.148768 -300.37151)
			(xy 419.148275 -300.381668) (xy 419.140498 -300.400436) (xy 419.126132 -300.4148) (xy 419.107364 -300.422576)
			(xy 419.097206 -300.423072) (xy 417.697666 -300.423072) (xy 417.687507 -300.422595) (xy 417.668739 -300.414811)
			(xy 417.654376 -300.400441) (xy 417.646601 -300.381669) (xy 417.646104 -300.37151) (xy 411.604968 -300.37151)
			(xy 411.604475 -300.381668) (xy 411.596698 -300.400436) (xy 411.582332 -300.4148) (xy 411.563564 -300.422576)
			(xy 411.553406 -300.423072) (xy 410.153866 -300.423072) (xy 410.143707 -300.422595) (xy 410.124939 -300.414811)
			(xy 410.110576 -300.400441) (xy 410.102801 -300.381669) (xy 410.102304 -300.37151) (xy 313.738768 -300.37151)
			(xy 313.738275 -300.381668) (xy 313.730498 -300.400436) (xy 313.716132 -300.4148) (xy 313.697364 -300.422576)
			(xy 313.687206 -300.423072) (xy 312.287666 -300.423072) (xy 312.277507 -300.422595) (xy 312.258739 -300.414811)
			(xy 312.244376 -300.400441) (xy 312.236601 -300.381669) (xy 312.236104 -300.37151) (xy 306.194968 -300.37151)
			(xy 306.194475 -300.381668) (xy 306.186698 -300.400436) (xy 306.172332 -300.4148) (xy 306.153564 -300.422576)
			(xy 306.143406 -300.423072) (xy 304.743866 -300.423072) (xy 304.733707 -300.422595) (xy 304.714939 -300.414811)
			(xy 304.700576 -300.400441) (xy 304.692801 -300.381669) (xy 304.692304 -300.37151) (xy 298.651168 -300.37151)
			(xy 298.650675 -300.381668) (xy 298.642898 -300.400436) (xy 298.628532 -300.4148) (xy 298.609764 -300.422576)
			(xy 298.599606 -300.423072) (xy 297.200066 -300.423072) (xy 297.189907 -300.422595) (xy 297.171139 -300.414811)
			(xy 297.156776 -300.400441) (xy 297.149001 -300.381669) (xy 297.148504 -300.37151) (xy 291.107368 -300.37151)
			(xy 291.106875 -300.381668) (xy 291.099098 -300.400436) (xy 291.084732 -300.4148) (xy 291.065964 -300.422576)
			(xy 291.055806 -300.423072) (xy 289.656266 -300.423072) (xy 289.646107 -300.422595) (xy 289.627339 -300.414811)
			(xy 289.612976 -300.400441) (xy 289.605201 -300.381669) (xy 289.604704 -300.37151) (xy 283.563568 -300.37151)
			(xy 283.563075 -300.381668) (xy 283.555298 -300.400436) (xy 283.540932 -300.4148) (xy 283.522164 -300.422576)
			(xy 283.512006 -300.423072) (xy 282.112466 -300.423072) (xy 282.102307 -300.422595) (xy 282.083539 -300.414811)
			(xy 282.069176 -300.400441) (xy 282.061401 -300.381669) (xy 282.060904 -300.37151) (xy 276.019768 -300.37151)
			(xy 276.019275 -300.381668) (xy 276.011498 -300.400436) (xy 275.997132 -300.4148) (xy 275.978364 -300.422576)
			(xy 275.968206 -300.423072) (xy 274.568666 -300.423072) (xy 274.558507 -300.422595) (xy 274.539739 -300.414811)
			(xy 274.525376 -300.400441) (xy 274.517601 -300.381669) (xy 274.517104 -300.37151) (xy 268.475968 -300.37151)
			(xy 268.475475 -300.381668) (xy 268.467698 -300.400436) (xy 268.453332 -300.4148) (xy 268.434564 -300.422576)
			(xy 268.424406 -300.423072) (xy 267.024866 -300.423072) (xy 267.014707 -300.422595) (xy 266.995939 -300.414811)
			(xy 266.981576 -300.400441) (xy 266.973801 -300.381669) (xy 266.973304 -300.37151) (xy 260.932168 -300.37151)
			(xy 260.931675 -300.381668) (xy 260.923898 -300.400436) (xy 260.909532 -300.4148) (xy 260.890764 -300.422576)
			(xy 260.880606 -300.423072) (xy 259.481066 -300.423072) (xy 259.470907 -300.422595) (xy 259.452139 -300.414811)
			(xy 259.437776 -300.400441) (xy 259.430001 -300.381669) (xy 259.429504 -300.37151) (xy 216.4715 -300.37151)
			(xy 216.470976 -300.381664) (xy 216.463205 -300.400426) (xy 216.448849 -300.414789) (xy 216.430091 -300.42257)
			(xy 216.419938 -300.423072) (xy 215.020398 -300.423072) (xy 215.010241 -300.422568) (xy 214.991474 -300.414795)
			(xy 214.977109 -300.400433) (xy 214.969333 -300.381667) (xy 214.968836 -300.37151) (xy 208.9277 -300.37151)
			(xy 208.927176 -300.381664) (xy 208.919405 -300.400426) (xy 208.905049 -300.414789) (xy 208.886291 -300.42257)
			(xy 208.876138 -300.423072) (xy 207.476598 -300.423072) (xy 207.466441 -300.422568) (xy 207.447674 -300.414795)
			(xy 207.433309 -300.400433) (xy 207.425533 -300.381667) (xy 207.425036 -300.37151) (xy 201.3839 -300.37151)
			(xy 201.383376 -300.381664) (xy 201.375605 -300.400426) (xy 201.361249 -300.414789) (xy 201.342491 -300.42257)
			(xy 201.332338 -300.423072) (xy 199.932798 -300.423072) (xy 199.922641 -300.422568) (xy 199.903874 -300.414795)
			(xy 199.889509 -300.400433) (xy 199.881733 -300.381667) (xy 199.881236 -300.37151) (xy 193.8401 -300.37151)
			(xy 193.839576 -300.381664) (xy 193.831805 -300.400426) (xy 193.817449 -300.414789) (xy 193.798691 -300.42257)
			(xy 193.788538 -300.423072) (xy 192.388998 -300.423072) (xy 192.378841 -300.422568) (xy 192.360074 -300.414795)
			(xy 192.345709 -300.400433) (xy 192.337933 -300.381667) (xy 192.337436 -300.37151) (xy 186.2963 -300.37151)
			(xy 186.295776 -300.381664) (xy 186.288005 -300.400426) (xy 186.273649 -300.414789) (xy 186.254891 -300.42257)
			(xy 186.244738 -300.423072) (xy 184.845198 -300.423072) (xy 184.835041 -300.422568) (xy 184.816274 -300.414795)
			(xy 184.801909 -300.400433) (xy 184.794133 -300.381667) (xy 184.793636 -300.37151) (xy 178.7525 -300.37151)
			(xy 178.751976 -300.381664) (xy 178.744205 -300.400426) (xy 178.729849 -300.414789) (xy 178.711091 -300.42257)
			(xy 178.700938 -300.423072) (xy 177.301398 -300.423072) (xy 177.291241 -300.422568) (xy 177.272474 -300.414795)
			(xy 177.258109 -300.400433) (xy 177.250333 -300.381667) (xy 177.249836 -300.37151) (xy 171.2087 -300.37151)
			(xy 171.208176 -300.381664) (xy 171.200405 -300.400426) (xy 171.186049 -300.414789) (xy 171.167291 -300.42257)
			(xy 171.157138 -300.423072) (xy 169.757598 -300.423072) (xy 169.747441 -300.422568) (xy 169.728674 -300.414795)
			(xy 169.714309 -300.400433) (xy 169.706533 -300.381667) (xy 169.706036 -300.37151) (xy 163.6649 -300.37151)
			(xy 163.664376 -300.381664) (xy 163.656605 -300.400426) (xy 163.642249 -300.414789) (xy 163.623491 -300.42257)
			(xy 163.613338 -300.423072) (xy 162.213798 -300.423072) (xy 162.203641 -300.422568) (xy 162.184874 -300.414795)
			(xy 162.170509 -300.400433) (xy 162.162733 -300.381667) (xy 162.162236 -300.37151) (xy 65.7987 -300.37151)
			(xy 65.798176 -300.381664) (xy 65.790405 -300.400426) (xy 65.776049 -300.414789) (xy 65.757291 -300.42257)
			(xy 65.747138 -300.423072) (xy 64.347598 -300.423072) (xy 64.337441 -300.422568) (xy 64.318674 -300.414795)
			(xy 64.304309 -300.400433) (xy 64.296533 -300.381667) (xy 64.296036 -300.37151) (xy 58.2549 -300.37151)
			(xy 58.254376 -300.381664) (xy 58.246605 -300.400426) (xy 58.232249 -300.414789) (xy 58.213491 -300.42257)
			(xy 58.203338 -300.423072) (xy 56.803798 -300.423072) (xy 56.793641 -300.422568) (xy 56.774874 -300.414795)
			(xy 56.760509 -300.400433) (xy 56.752733 -300.381667) (xy 56.752236 -300.37151) (xy 50.7111 -300.37151)
			(xy 50.710576 -300.381664) (xy 50.702805 -300.400426) (xy 50.688449 -300.414789) (xy 50.669691 -300.42257)
			(xy 50.659538 -300.423072) (xy 49.259998 -300.423072) (xy 49.249841 -300.422568) (xy 49.231074 -300.414795)
			(xy 49.216709 -300.400433) (xy 49.208933 -300.381667) (xy 49.208436 -300.37151) (xy 43.1673 -300.37151)
			(xy 43.166776 -300.381664) (xy 43.159005 -300.400426) (xy 43.144649 -300.414789) (xy 43.125891 -300.42257)
			(xy 43.115738 -300.423072) (xy 41.716198 -300.423072) (xy 41.706041 -300.422568) (xy 41.687274 -300.414795)
			(xy 41.672909 -300.400433) (xy 41.665133 -300.381667) (xy 41.664636 -300.37151) (xy 35.6235 -300.37151)
			(xy 35.622976 -300.381664) (xy 35.615205 -300.400426) (xy 35.600849 -300.414789) (xy 35.582091 -300.42257)
			(xy 35.571938 -300.423072) (xy 34.172398 -300.423072) (xy 34.162241 -300.422568) (xy 34.143474 -300.414795)
			(xy 34.129109 -300.400433) (xy 34.121333 -300.381667) (xy 34.120836 -300.37151) (xy 28.0797 -300.37151)
			(xy 28.079176 -300.381664) (xy 28.071405 -300.400426) (xy 28.057049 -300.414789) (xy 28.038291 -300.42257)
			(xy 28.028138 -300.423072) (xy 26.628598 -300.423072) (xy 26.618441 -300.422568) (xy 26.599674 -300.414795)
			(xy 26.585309 -300.400433) (xy 26.577533 -300.381667) (xy 26.577036 -300.37151) (xy 20.5359 -300.37151)
			(xy 20.535376 -300.381664) (xy 20.527605 -300.400426) (xy 20.513249 -300.414789) (xy 20.494491 -300.42257)
			(xy 20.484338 -300.423072) (xy 19.084798 -300.423072) (xy 19.074641 -300.422568) (xy 19.055874 -300.414795)
			(xy 19.041509 -300.400433) (xy 19.033733 -300.381667) (xy 19.033236 -300.37151) (xy 12.9921 -300.37151)
			(xy 12.991576 -300.381664) (xy 12.983805 -300.400426) (xy 12.969449 -300.414789) (xy 12.950691 -300.42257)
			(xy 12.940538 -300.423072) (xy 11.540998 -300.423072) (xy 11.530841 -300.422568) (xy 11.512074 -300.414795)
			(xy 11.497709 -300.400433) (xy 11.489933 -300.381667) (xy 11.489436 -300.37151) (xy 2.509012 -300.37151)
			(xy 2.509012 -301.221394) (xy 7.389368 -301.221394) (xy 7.389368 -300.812454) (xy 7.389797 -300.80229)
			(xy 7.397592 -300.783514) (xy 7.411978 -300.769149) (xy 7.430765 -300.761382) (xy 7.44093 -300.760892)
			(xy 8.84047 -300.760892) (xy 8.85062 -300.761457) (xy 8.86938 -300.769213) (xy 8.883745 -300.783556)
			(xy 8.891528 -300.802305) (xy 8.892032 -300.812454) (xy 8.892032 -301.221394) (xy 14.933168 -301.221394)
			(xy 14.933168 -300.812454) (xy 14.933597 -300.80229) (xy 14.941392 -300.783514) (xy 14.955778 -300.769149)
			(xy 14.974565 -300.761382) (xy 14.98473 -300.760892) (xy 16.38427 -300.760892) (xy 16.39442 -300.761457)
			(xy 16.41318 -300.769213) (xy 16.427545 -300.783556) (xy 16.435328 -300.802305) (xy 16.435832 -300.812454)
			(xy 16.435832 -301.221394) (xy 22.476968 -301.221394) (xy 22.476968 -300.812454) (xy 22.477397 -300.80229)
			(xy 22.485192 -300.783514) (xy 22.499578 -300.769149) (xy 22.518365 -300.761382) (xy 22.52853 -300.760892)
			(xy 23.92807 -300.760892) (xy 23.93822 -300.761457) (xy 23.95698 -300.769213) (xy 23.971345 -300.783556)
			(xy 23.979128 -300.802305) (xy 23.979632 -300.812454) (xy 23.979632 -301.221394) (xy 30.020768 -301.221394)
			(xy 30.020768 -300.812454) (xy 30.021197 -300.80229) (xy 30.028992 -300.783514) (xy 30.043378 -300.769149)
			(xy 30.062165 -300.761382) (xy 30.07233 -300.760892) (xy 31.47187 -300.760892) (xy 31.48202 -300.761457)
			(xy 31.50078 -300.769213) (xy 31.515145 -300.783556) (xy 31.522928 -300.802305) (xy 31.523432 -300.812454)
			(xy 31.523432 -301.221394) (xy 37.564568 -301.221394) (xy 37.564568 -300.812454) (xy 37.564997 -300.80229)
			(xy 37.572792 -300.783514) (xy 37.587178 -300.769149) (xy 37.605965 -300.761382) (xy 37.61613 -300.760892)
			(xy 39.01567 -300.760892) (xy 39.02582 -300.761457) (xy 39.04458 -300.769213) (xy 39.058945 -300.783556)
			(xy 39.066728 -300.802305) (xy 39.067232 -300.812454) (xy 39.067232 -301.221394) (xy 45.108368 -301.221394)
			(xy 45.108368 -300.812454) (xy 45.108797 -300.80229) (xy 45.116592 -300.783514) (xy 45.130978 -300.769149)
			(xy 45.149765 -300.761382) (xy 45.15993 -300.760892) (xy 46.55947 -300.760892) (xy 46.56962 -300.761457)
			(xy 46.58838 -300.769213) (xy 46.602745 -300.783556) (xy 46.610528 -300.802305) (xy 46.611032 -300.812454)
			(xy 46.611032 -301.221394) (xy 52.652168 -301.221394) (xy 52.652168 -300.812454) (xy 52.652597 -300.80229)
			(xy 52.660392 -300.783514) (xy 52.674778 -300.769149) (xy 52.693565 -300.761382) (xy 52.70373 -300.760892)
			(xy 54.10327 -300.760892) (xy 54.11342 -300.761457) (xy 54.13218 -300.769213) (xy 54.146545 -300.783556)
			(xy 54.154328 -300.802305) (xy 54.154832 -300.812454) (xy 54.154832 -301.221394) (xy 60.195968 -301.221394)
			(xy 60.195968 -300.812454) (xy 60.196397 -300.80229) (xy 60.204192 -300.783514) (xy 60.218578 -300.769149)
			(xy 60.237365 -300.761382) (xy 60.24753 -300.760892) (xy 61.64707 -300.760892) (xy 61.65722 -300.761457)
			(xy 61.67598 -300.769213) (xy 61.690345 -300.783556) (xy 61.698128 -300.802305) (xy 61.698632 -300.812454)
			(xy 61.698632 -301.221394) (xy 158.062168 -301.221394) (xy 158.062168 -300.812454) (xy 158.062597 -300.80229)
			(xy 158.070392 -300.783514) (xy 158.084778 -300.769149) (xy 158.103565 -300.761382) (xy 158.11373 -300.760892)
			(xy 159.51327 -300.760892) (xy 159.52342 -300.761457) (xy 159.54218 -300.769213) (xy 159.556545 -300.783556)
			(xy 159.564328 -300.802305) (xy 159.564832 -300.812454) (xy 159.564832 -301.221394) (xy 165.605968 -301.221394)
			(xy 165.605968 -300.812454) (xy 165.606397 -300.80229) (xy 165.614192 -300.783514) (xy 165.628578 -300.769149)
			(xy 165.647365 -300.761382) (xy 165.65753 -300.760892) (xy 167.05707 -300.760892) (xy 167.06722 -300.761457)
			(xy 167.08598 -300.769213) (xy 167.100345 -300.783556) (xy 167.108128 -300.802305) (xy 167.108632 -300.812454)
			(xy 167.108632 -301.221394) (xy 173.149768 -301.221394) (xy 173.149768 -300.812454) (xy 173.150197 -300.80229)
			(xy 173.157992 -300.783514) (xy 173.172378 -300.769149) (xy 173.191165 -300.761382) (xy 173.20133 -300.760892)
			(xy 174.60087 -300.760892) (xy 174.61102 -300.761457) (xy 174.62978 -300.769213) (xy 174.644145 -300.783556)
			(xy 174.651928 -300.802305) (xy 174.652432 -300.812454) (xy 174.652432 -301.221394) (xy 180.693568 -301.221394)
			(xy 180.693568 -300.812454) (xy 180.693997 -300.80229) (xy 180.701792 -300.783514) (xy 180.716178 -300.769149)
			(xy 180.734965 -300.761382) (xy 180.74513 -300.760892) (xy 182.14467 -300.760892) (xy 182.15482 -300.761457)
			(xy 182.17358 -300.769213) (xy 182.187945 -300.783556) (xy 182.195728 -300.802305) (xy 182.196232 -300.812454)
			(xy 182.196232 -301.221394) (xy 188.237368 -301.221394) (xy 188.237368 -300.812454) (xy 188.237797 -300.80229)
			(xy 188.245592 -300.783514) (xy 188.259978 -300.769149) (xy 188.278765 -300.761382) (xy 188.28893 -300.760892)
			(xy 189.68847 -300.760892) (xy 189.69862 -300.761457) (xy 189.71738 -300.769213) (xy 189.731745 -300.783556)
			(xy 189.739528 -300.802305) (xy 189.740032 -300.812454) (xy 189.740032 -301.221394) (xy 195.781168 -301.221394)
			(xy 195.781168 -300.812454) (xy 195.781597 -300.80229) (xy 195.789392 -300.783514) (xy 195.803778 -300.769149)
			(xy 195.822565 -300.761382) (xy 195.83273 -300.760892) (xy 197.23227 -300.760892) (xy 197.24242 -300.761457)
			(xy 197.26118 -300.769213) (xy 197.275545 -300.783556) (xy 197.283328 -300.802305) (xy 197.283832 -300.812454)
			(xy 197.283832 -301.221394) (xy 203.324968 -301.221394) (xy 203.324968 -300.812454) (xy 203.325397 -300.80229)
			(xy 203.333192 -300.783514) (xy 203.347578 -300.769149) (xy 203.366365 -300.761382) (xy 203.37653 -300.760892)
			(xy 204.77607 -300.760892) (xy 204.78622 -300.761457) (xy 204.80498 -300.769213) (xy 204.819345 -300.783556)
			(xy 204.827128 -300.802305) (xy 204.827632 -300.812454) (xy 204.827632 -301.221394) (xy 210.868768 -301.221394)
			(xy 210.868768 -300.812454) (xy 210.869197 -300.80229) (xy 210.876992 -300.783514) (xy 210.891378 -300.769149)
			(xy 210.910165 -300.761382) (xy 210.92033 -300.760892) (xy 212.31987 -300.760892) (xy 212.33002 -300.761457)
			(xy 212.34878 -300.769213) (xy 212.363145 -300.783556) (xy 212.370928 -300.802305) (xy 212.371432 -300.812454)
			(xy 212.371432 -301.221394) (xy 255.329436 -301.221394) (xy 255.329436 -300.812454) (xy 255.329896 -300.802294)
			(xy 255.337685 -300.783524) (xy 255.352061 -300.76916) (xy 255.370837 -300.761387) (xy 255.380998 -300.760892)
			(xy 256.780538 -300.760892) (xy 256.790693 -300.761401) (xy 256.809454 -300.769179) (xy 256.823816 -300.78354)
			(xy 256.831597 -300.8023) (xy 256.8321 -300.812454) (xy 256.8321 -301.221394) (xy 262.873236 -301.221394)
			(xy 262.873236 -300.812454) (xy 262.873696 -300.802294) (xy 262.881485 -300.783524) (xy 262.895861 -300.76916)
			(xy 262.914637 -300.761387) (xy 262.924798 -300.760892) (xy 264.324338 -300.760892) (xy 264.334493 -300.761401)
			(xy 264.353254 -300.769179) (xy 264.367616 -300.78354) (xy 264.375397 -300.8023) (xy 264.3759 -300.812454)
			(xy 264.3759 -301.221394) (xy 270.417036 -301.221394) (xy 270.417036 -300.812454) (xy 270.417496 -300.802294)
			(xy 270.425285 -300.783524) (xy 270.439661 -300.76916) (xy 270.458437 -300.761387) (xy 270.468598 -300.760892)
			(xy 271.868138 -300.760892) (xy 271.878293 -300.761401) (xy 271.897054 -300.769179) (xy 271.911416 -300.78354)
			(xy 271.919197 -300.8023) (xy 271.9197 -300.812454) (xy 271.9197 -301.221394) (xy 277.960836 -301.221394)
			(xy 277.960836 -300.812454) (xy 277.961296 -300.802294) (xy 277.969085 -300.783524) (xy 277.983461 -300.76916)
			(xy 278.002237 -300.761387) (xy 278.012398 -300.760892) (xy 279.411938 -300.760892) (xy 279.422093 -300.761401)
			(xy 279.440854 -300.769179) (xy 279.455216 -300.78354) (xy 279.462997 -300.8023) (xy 279.4635 -300.812454)
			(xy 279.4635 -301.221394) (xy 285.504636 -301.221394) (xy 285.504636 -300.812454) (xy 285.505096 -300.802294)
			(xy 285.512885 -300.783524) (xy 285.527261 -300.76916) (xy 285.546037 -300.761387) (xy 285.556198 -300.760892)
			(xy 286.955738 -300.760892) (xy 286.965893 -300.761401) (xy 286.984654 -300.769179) (xy 286.999016 -300.78354)
			(xy 287.006797 -300.8023) (xy 287.0073 -300.812454) (xy 287.0073 -301.221394) (xy 293.048436 -301.221394)
			(xy 293.048436 -300.812454) (xy 293.048896 -300.802294) (xy 293.056685 -300.783524) (xy 293.071061 -300.76916)
			(xy 293.089837 -300.761387) (xy 293.099998 -300.760892) (xy 294.499538 -300.760892) (xy 294.509693 -300.761401)
			(xy 294.528454 -300.769179) (xy 294.542816 -300.78354) (xy 294.550597 -300.8023) (xy 294.5511 -300.812454)
			(xy 294.5511 -301.221394) (xy 300.592236 -301.221394) (xy 300.592236 -300.812454) (xy 300.592696 -300.802294)
			(xy 300.600485 -300.783524) (xy 300.614861 -300.76916) (xy 300.633637 -300.761387) (xy 300.643798 -300.760892)
			(xy 302.043338 -300.760892) (xy 302.053493 -300.761401) (xy 302.072254 -300.769179) (xy 302.086616 -300.78354)
			(xy 302.094397 -300.8023) (xy 302.0949 -300.812454) (xy 302.0949 -301.221394) (xy 308.136036 -301.221394)
			(xy 308.136036 -300.812454) (xy 308.136496 -300.802294) (xy 308.144285 -300.783524) (xy 308.158661 -300.76916)
			(xy 308.177437 -300.761387) (xy 308.187598 -300.760892) (xy 309.587138 -300.760892) (xy 309.597293 -300.761401)
			(xy 309.616054 -300.769179) (xy 309.630416 -300.78354) (xy 309.638197 -300.8023) (xy 309.6387 -300.812454)
			(xy 309.6387 -301.221394) (xy 406.002236 -301.221394) (xy 406.002236 -300.812454) (xy 406.002696 -300.802294)
			(xy 406.010485 -300.783524) (xy 406.024861 -300.76916) (xy 406.043637 -300.761387) (xy 406.053798 -300.760892)
			(xy 407.453338 -300.760892) (xy 407.463493 -300.761401) (xy 407.482254 -300.769179) (xy 407.496616 -300.78354)
			(xy 407.504397 -300.8023) (xy 407.5049 -300.812454) (xy 407.5049 -301.221394) (xy 413.546036 -301.221394)
			(xy 413.546036 -300.812454) (xy 413.546496 -300.802294) (xy 413.554285 -300.783524) (xy 413.568661 -300.76916)
			(xy 413.587437 -300.761387) (xy 413.597598 -300.760892) (xy 414.997138 -300.760892) (xy 415.007293 -300.761401)
			(xy 415.026054 -300.769179) (xy 415.040416 -300.78354) (xy 415.048197 -300.8023) (xy 415.0487 -300.812454)
			(xy 415.0487 -301.221394) (xy 421.089836 -301.221394) (xy 421.089836 -300.812454) (xy 421.090296 -300.802294)
			(xy 421.098085 -300.783524) (xy 421.112461 -300.76916) (xy 421.131237 -300.761387) (xy 421.141398 -300.760892)
			(xy 422.540938 -300.760892) (xy 422.551093 -300.761401) (xy 422.569854 -300.769179) (xy 422.584216 -300.78354)
			(xy 422.591997 -300.8023) (xy 422.5925 -300.812454) (xy 422.5925 -301.221394) (xy 428.633636 -301.221394)
			(xy 428.633636 -300.812454) (xy 428.634096 -300.802294) (xy 428.641885 -300.783524) (xy 428.656261 -300.76916)
			(xy 428.675037 -300.761387) (xy 428.685198 -300.760892) (xy 430.084738 -300.760892) (xy 430.094893 -300.761401)
			(xy 430.113654 -300.769179) (xy 430.128016 -300.78354) (xy 430.135797 -300.8023) (xy 430.1363 -300.812454)
			(xy 430.1363 -301.221394) (xy 436.177436 -301.221394) (xy 436.177436 -300.812454) (xy 436.177896 -300.802294)
			(xy 436.185685 -300.783524) (xy 436.200061 -300.76916) (xy 436.218837 -300.761387) (xy 436.228998 -300.760892)
			(xy 437.628538 -300.760892) (xy 437.638693 -300.761401) (xy 437.657454 -300.769179) (xy 437.671816 -300.78354)
			(xy 437.679597 -300.8023) (xy 437.6801 -300.812454) (xy 437.6801 -301.221394) (xy 443.721236 -301.221394)
			(xy 443.721236 -300.812454) (xy 443.721696 -300.802294) (xy 443.729485 -300.783524) (xy 443.743861 -300.76916)
			(xy 443.762637 -300.761387) (xy 443.772798 -300.760892) (xy 445.172338 -300.760892) (xy 445.182493 -300.761401)
			(xy 445.201254 -300.769179) (xy 445.215616 -300.78354) (xy 445.223397 -300.8023) (xy 445.2239 -300.812454)
			(xy 445.2239 -301.221394) (xy 451.265036 -301.221394) (xy 451.265036 -300.812454) (xy 451.265496 -300.802294)
			(xy 451.273285 -300.783524) (xy 451.287661 -300.76916) (xy 451.306437 -300.761387) (xy 451.316598 -300.760892)
			(xy 452.716138 -300.760892) (xy 452.726293 -300.761401) (xy 452.745054 -300.769179) (xy 452.759416 -300.78354)
			(xy 452.767197 -300.8023) (xy 452.7677 -300.812454) (xy 452.7677 -301.221394) (xy 458.808836 -301.221394)
			(xy 458.808836 -300.812454) (xy 458.809296 -300.802294) (xy 458.817085 -300.783524) (xy 458.831461 -300.76916)
			(xy 458.850237 -300.761387) (xy 458.860398 -300.760892) (xy 460.259938 -300.760892) (xy 460.270093 -300.761401)
			(xy 460.288854 -300.769179) (xy 460.303216 -300.78354) (xy 460.310997 -300.8023) (xy 460.3115 -300.812454)
			(xy 460.3115 -301.221394) (xy 460.310963 -301.231547) (xy 460.303197 -301.250308) (xy 460.288845 -301.264673)
			(xy 460.27009 -301.272454) (xy 460.259938 -301.272956) (xy 458.860398 -301.272956) (xy 458.850226 -301.272538)
			(xy 458.83143 -301.264751) (xy 458.817045 -301.250364) (xy 458.809261 -301.231567) (xy 458.808836 -301.221394)
			(xy 452.7677 -301.221394) (xy 452.767163 -301.231547) (xy 452.759397 -301.250308) (xy 452.745045 -301.264673)
			(xy 452.72629 -301.272454) (xy 452.716138 -301.272956) (xy 451.316598 -301.272956) (xy 451.306426 -301.272538)
			(xy 451.28763 -301.264751) (xy 451.273245 -301.250364) (xy 451.265461 -301.231567) (xy 451.265036 -301.221394)
			(xy 445.2239 -301.221394) (xy 445.223363 -301.231547) (xy 445.215597 -301.250308) (xy 445.201245 -301.264673)
			(xy 445.18249 -301.272454) (xy 445.172338 -301.272956) (xy 443.772798 -301.272956) (xy 443.762626 -301.272538)
			(xy 443.74383 -301.264751) (xy 443.729445 -301.250364) (xy 443.721661 -301.231567) (xy 443.721236 -301.221394)
			(xy 437.6801 -301.221394) (xy 437.679563 -301.231547) (xy 437.671797 -301.250308) (xy 437.657445 -301.264673)
			(xy 437.63869 -301.272454) (xy 437.628538 -301.272956) (xy 436.228998 -301.272956) (xy 436.218826 -301.272538)
			(xy 436.20003 -301.264751) (xy 436.185645 -301.250364) (xy 436.177861 -301.231567) (xy 436.177436 -301.221394)
			(xy 430.1363 -301.221394) (xy 430.135763 -301.231547) (xy 430.127997 -301.250308) (xy 430.113645 -301.264673)
			(xy 430.09489 -301.272454) (xy 430.084738 -301.272956) (xy 428.685198 -301.272956) (xy 428.675026 -301.272538)
			(xy 428.65623 -301.264751) (xy 428.641845 -301.250364) (xy 428.634061 -301.231567) (xy 428.633636 -301.221394)
			(xy 422.5925 -301.221394) (xy 422.591963 -301.231547) (xy 422.584197 -301.250308) (xy 422.569845 -301.264673)
			(xy 422.55109 -301.272454) (xy 422.540938 -301.272956) (xy 421.141398 -301.272956) (xy 421.131226 -301.272538)
			(xy 421.11243 -301.264751) (xy 421.098045 -301.250364) (xy 421.090261 -301.231567) (xy 421.089836 -301.221394)
			(xy 415.0487 -301.221394) (xy 415.048163 -301.231547) (xy 415.040397 -301.250308) (xy 415.026045 -301.264673)
			(xy 415.00729 -301.272454) (xy 414.997138 -301.272956) (xy 413.597598 -301.272956) (xy 413.587426 -301.272538)
			(xy 413.56863 -301.264751) (xy 413.554245 -301.250364) (xy 413.546461 -301.231567) (xy 413.546036 -301.221394)
			(xy 407.5049 -301.221394) (xy 407.504363 -301.231547) (xy 407.496597 -301.250308) (xy 407.482245 -301.264673)
			(xy 407.46349 -301.272454) (xy 407.453338 -301.272956) (xy 406.053798 -301.272956) (xy 406.043626 -301.272538)
			(xy 406.02483 -301.264751) (xy 406.010445 -301.250364) (xy 406.002661 -301.231567) (xy 406.002236 -301.221394)
			(xy 309.6387 -301.221394) (xy 309.638163 -301.231547) (xy 309.630397 -301.250308) (xy 309.616045 -301.264673)
			(xy 309.59729 -301.272454) (xy 309.587138 -301.272956) (xy 308.187598 -301.272956) (xy 308.177426 -301.272538)
			(xy 308.15863 -301.264751) (xy 308.144245 -301.250364) (xy 308.136461 -301.231567) (xy 308.136036 -301.221394)
			(xy 302.0949 -301.221394) (xy 302.094363 -301.231547) (xy 302.086597 -301.250308) (xy 302.072245 -301.264673)
			(xy 302.05349 -301.272454) (xy 302.043338 -301.272956) (xy 300.643798 -301.272956) (xy 300.633626 -301.272538)
			(xy 300.61483 -301.264751) (xy 300.600445 -301.250364) (xy 300.592661 -301.231567) (xy 300.592236 -301.221394)
			(xy 294.5511 -301.221394) (xy 294.550563 -301.231547) (xy 294.542797 -301.250308) (xy 294.528445 -301.264673)
			(xy 294.50969 -301.272454) (xy 294.499538 -301.272956) (xy 293.099998 -301.272956) (xy 293.089826 -301.272538)
			(xy 293.07103 -301.264751) (xy 293.056645 -301.250364) (xy 293.048861 -301.231567) (xy 293.048436 -301.221394)
			(xy 287.0073 -301.221394) (xy 287.006763 -301.231547) (xy 286.998997 -301.250308) (xy 286.984645 -301.264673)
			(xy 286.96589 -301.272454) (xy 286.955738 -301.272956) (xy 285.556198 -301.272956) (xy 285.546026 -301.272538)
			(xy 285.52723 -301.264751) (xy 285.512845 -301.250364) (xy 285.505061 -301.231567) (xy 285.504636 -301.221394)
			(xy 279.4635 -301.221394) (xy 279.462963 -301.231547) (xy 279.455197 -301.250308) (xy 279.440845 -301.264673)
			(xy 279.42209 -301.272454) (xy 279.411938 -301.272956) (xy 278.012398 -301.272956) (xy 278.002226 -301.272538)
			(xy 277.98343 -301.264751) (xy 277.969045 -301.250364) (xy 277.961261 -301.231567) (xy 277.960836 -301.221394)
			(xy 271.9197 -301.221394) (xy 271.919163 -301.231547) (xy 271.911397 -301.250308) (xy 271.897045 -301.264673)
			(xy 271.87829 -301.272454) (xy 271.868138 -301.272956) (xy 270.468598 -301.272956) (xy 270.458426 -301.272538)
			(xy 270.43963 -301.264751) (xy 270.425245 -301.250364) (xy 270.417461 -301.231567) (xy 270.417036 -301.221394)
			(xy 264.3759 -301.221394) (xy 264.375363 -301.231547) (xy 264.367597 -301.250308) (xy 264.353245 -301.264673)
			(xy 264.33449 -301.272454) (xy 264.324338 -301.272956) (xy 262.924798 -301.272956) (xy 262.914626 -301.272538)
			(xy 262.89583 -301.264751) (xy 262.881445 -301.250364) (xy 262.873661 -301.231567) (xy 262.873236 -301.221394)
			(xy 256.8321 -301.221394) (xy 256.831563 -301.231547) (xy 256.823797 -301.250308) (xy 256.809445 -301.264673)
			(xy 256.79069 -301.272454) (xy 256.780538 -301.272956) (xy 255.380998 -301.272956) (xy 255.370826 -301.272538)
			(xy 255.35203 -301.264751) (xy 255.337645 -301.250364) (xy 255.329861 -301.231567) (xy 255.329436 -301.221394)
			(xy 212.371432 -301.221394) (xy 212.371031 -301.231569) (xy 212.363242 -301.250369) (xy 212.348849 -301.264755)
			(xy 212.330045 -301.272535) (xy 212.31987 -301.272956) (xy 210.92033 -301.272956) (xy 210.91016 -301.272511)
			(xy 210.891364 -301.264735) (xy 210.876978 -301.250356) (xy 210.869193 -301.231564) (xy 210.868768 -301.221394)
			(xy 204.827632 -301.221394) (xy 204.827231 -301.231569) (xy 204.819442 -301.250369) (xy 204.805049 -301.264755)
			(xy 204.786245 -301.272535) (xy 204.77607 -301.272956) (xy 203.37653 -301.272956) (xy 203.36636 -301.272511)
			(xy 203.347564 -301.264735) (xy 203.333178 -301.250356) (xy 203.325393 -301.231564) (xy 203.324968 -301.221394)
			(xy 197.283832 -301.221394) (xy 197.283431 -301.231569) (xy 197.275642 -301.250369) (xy 197.261249 -301.264755)
			(xy 197.242445 -301.272535) (xy 197.23227 -301.272956) (xy 195.83273 -301.272956) (xy 195.82256 -301.272511)
			(xy 195.803764 -301.264735) (xy 195.789378 -301.250356) (xy 195.781593 -301.231564) (xy 195.781168 -301.221394)
			(xy 189.740032 -301.221394) (xy 189.739631 -301.231569) (xy 189.731842 -301.250369) (xy 189.717449 -301.264755)
			(xy 189.698645 -301.272535) (xy 189.68847 -301.272956) (xy 188.28893 -301.272956) (xy 188.27876 -301.272511)
			(xy 188.259964 -301.264735) (xy 188.245578 -301.250356) (xy 188.237793 -301.231564) (xy 188.237368 -301.221394)
			(xy 182.196232 -301.221394) (xy 182.195831 -301.231569) (xy 182.188042 -301.250369) (xy 182.173649 -301.264755)
			(xy 182.154845 -301.272535) (xy 182.14467 -301.272956) (xy 180.74513 -301.272956) (xy 180.73496 -301.272511)
			(xy 180.716164 -301.264735) (xy 180.701778 -301.250356) (xy 180.693993 -301.231564) (xy 180.693568 -301.221394)
			(xy 174.652432 -301.221394) (xy 174.652031 -301.231569) (xy 174.644242 -301.250369) (xy 174.629849 -301.264755)
			(xy 174.611045 -301.272535) (xy 174.60087 -301.272956) (xy 173.20133 -301.272956) (xy 173.19116 -301.272511)
			(xy 173.172364 -301.264735) (xy 173.157978 -301.250356) (xy 173.150193 -301.231564) (xy 173.149768 -301.221394)
			(xy 167.108632 -301.221394) (xy 167.108231 -301.231569) (xy 167.100442 -301.250369) (xy 167.086049 -301.264755)
			(xy 167.067245 -301.272535) (xy 167.05707 -301.272956) (xy 165.65753 -301.272956) (xy 165.64736 -301.272511)
			(xy 165.628564 -301.264735) (xy 165.614178 -301.250356) (xy 165.606393 -301.231564) (xy 165.605968 -301.221394)
			(xy 159.564832 -301.221394) (xy 159.564431 -301.231569) (xy 159.556642 -301.250369) (xy 159.542249 -301.264755)
			(xy 159.523445 -301.272535) (xy 159.51327 -301.272956) (xy 158.11373 -301.272956) (xy 158.10356 -301.272511)
			(xy 158.084764 -301.264735) (xy 158.070378 -301.250356) (xy 158.062593 -301.231564) (xy 158.062168 -301.221394)
			(xy 61.698632 -301.221394) (xy 61.698231 -301.231569) (xy 61.690442 -301.250369) (xy 61.676049 -301.264755)
			(xy 61.657245 -301.272535) (xy 61.64707 -301.272956) (xy 60.24753 -301.272956) (xy 60.23736 -301.272511)
			(xy 60.218564 -301.264735) (xy 60.204178 -301.250356) (xy 60.196393 -301.231564) (xy 60.195968 -301.221394)
			(xy 54.154832 -301.221394) (xy 54.154431 -301.231569) (xy 54.146642 -301.250369) (xy 54.132249 -301.264755)
			(xy 54.113445 -301.272535) (xy 54.10327 -301.272956) (xy 52.70373 -301.272956) (xy 52.69356 -301.272511)
			(xy 52.674764 -301.264735) (xy 52.660378 -301.250356) (xy 52.652593 -301.231564) (xy 52.652168 -301.221394)
			(xy 46.611032 -301.221394) (xy 46.610631 -301.231569) (xy 46.602842 -301.250369) (xy 46.588449 -301.264755)
			(xy 46.569645 -301.272535) (xy 46.55947 -301.272956) (xy 45.15993 -301.272956) (xy 45.14976 -301.272511)
			(xy 45.130964 -301.264735) (xy 45.116578 -301.250356) (xy 45.108793 -301.231564) (xy 45.108368 -301.221394)
			(xy 39.067232 -301.221394) (xy 39.066831 -301.231569) (xy 39.059042 -301.250369) (xy 39.044649 -301.264755)
			(xy 39.025845 -301.272535) (xy 39.01567 -301.272956) (xy 37.61613 -301.272956) (xy 37.60596 -301.272511)
			(xy 37.587164 -301.264735) (xy 37.572778 -301.250356) (xy 37.564993 -301.231564) (xy 37.564568 -301.221394)
			(xy 31.523432 -301.221394) (xy 31.523031 -301.231569) (xy 31.515242 -301.250369) (xy 31.500849 -301.264755)
			(xy 31.482045 -301.272535) (xy 31.47187 -301.272956) (xy 30.07233 -301.272956) (xy 30.06216 -301.272511)
			(xy 30.043364 -301.264735) (xy 30.028978 -301.250356) (xy 30.021193 -301.231564) (xy 30.020768 -301.221394)
			(xy 23.979632 -301.221394) (xy 23.979231 -301.231569) (xy 23.971442 -301.250369) (xy 23.957049 -301.264755)
			(xy 23.938245 -301.272535) (xy 23.92807 -301.272956) (xy 22.52853 -301.272956) (xy 22.51836 -301.272511)
			(xy 22.499564 -301.264735) (xy 22.485178 -301.250356) (xy 22.477393 -301.231564) (xy 22.476968 -301.221394)
			(xy 16.435832 -301.221394) (xy 16.435431 -301.231569) (xy 16.427642 -301.250369) (xy 16.413249 -301.264755)
			(xy 16.394445 -301.272535) (xy 16.38427 -301.272956) (xy 14.98473 -301.272956) (xy 14.97456 -301.272511)
			(xy 14.955764 -301.264735) (xy 14.941378 -301.250356) (xy 14.933593 -301.231564) (xy 14.933168 -301.221394)
			(xy 8.892032 -301.221394) (xy 8.891631 -301.231569) (xy 8.883842 -301.250369) (xy 8.869449 -301.264755)
			(xy 8.850645 -301.272535) (xy 8.84047 -301.272956) (xy 7.44093 -301.272956) (xy 7.43076 -301.272511)
			(xy 7.411964 -301.264735) (xy 7.397578 -301.250356) (xy 7.389793 -301.231564) (xy 7.389368 -301.221394)
			(xy 2.509012 -301.221394) (xy 2.509012 -302.071532) (xy 11.489436 -302.071532) (xy 11.489436 -301.662592)
			(xy 11.489816 -301.652433) (xy 11.497621 -301.633673) (xy 11.512031 -301.619349) (xy 11.530837 -301.611656)
			(xy 11.540998 -301.611284) (xy 12.940538 -301.611284) (xy 12.950673 -301.611697) (xy 12.969403 -301.619445)
			(xy 12.983759 -301.633754) (xy 12.99157 -301.652459) (xy 12.9921 -301.662592) (xy 12.9921 -302.071532)
			(xy 19.033236 -302.071532) (xy 19.033236 -301.662592) (xy 19.033616 -301.652433) (xy 19.041421 -301.633673)
			(xy 19.055831 -301.619349) (xy 19.074637 -301.611656) (xy 19.084798 -301.611284) (xy 20.484338 -301.611284)
			(xy 20.494473 -301.611697) (xy 20.513203 -301.619445) (xy 20.527559 -301.633754) (xy 20.53537 -301.652459)
			(xy 20.5359 -301.662592) (xy 20.5359 -302.071532) (xy 26.577036 -302.071532) (xy 26.577036 -301.662592)
			(xy 26.577416 -301.652433) (xy 26.585221 -301.633673) (xy 26.599631 -301.619349) (xy 26.618437 -301.611656)
			(xy 26.628598 -301.611284) (xy 28.028138 -301.611284) (xy 28.038273 -301.611697) (xy 28.057003 -301.619445)
			(xy 28.071359 -301.633754) (xy 28.07917 -301.652459) (xy 28.0797 -301.662592) (xy 28.0797 -302.071532)
			(xy 34.120836 -302.071532) (xy 34.120836 -301.662592) (xy 34.121216 -301.652433) (xy 34.129021 -301.633673)
			(xy 34.143431 -301.619349) (xy 34.162237 -301.611656) (xy 34.172398 -301.611284) (xy 35.571938 -301.611284)
			(xy 35.582073 -301.611697) (xy 35.600803 -301.619445) (xy 35.615159 -301.633754) (xy 35.62297 -301.652459)
			(xy 35.6235 -301.662592) (xy 35.6235 -302.071532) (xy 41.664636 -302.071532) (xy 41.664636 -301.662592)
			(xy 41.665016 -301.652433) (xy 41.672821 -301.633673) (xy 41.687231 -301.619349) (xy 41.706037 -301.611656)
			(xy 41.716198 -301.611284) (xy 43.115738 -301.611284) (xy 43.125873 -301.611697) (xy 43.144603 -301.619445)
			(xy 43.158959 -301.633754) (xy 43.16677 -301.652459) (xy 43.1673 -301.662592) (xy 43.1673 -302.071532)
			(xy 49.208436 -302.071532) (xy 49.208436 -301.662592) (xy 49.208816 -301.652433) (xy 49.216621 -301.633673)
			(xy 49.231031 -301.619349) (xy 49.249837 -301.611656) (xy 49.259998 -301.611284) (xy 50.659538 -301.611284)
			(xy 50.669673 -301.611697) (xy 50.688403 -301.619445) (xy 50.702759 -301.633754) (xy 50.71057 -301.652459)
			(xy 50.7111 -301.662592) (xy 50.7111 -302.071532) (xy 56.752236 -302.071532) (xy 56.752236 -301.662592)
			(xy 56.752616 -301.652433) (xy 56.760421 -301.633673) (xy 56.774831 -301.619349) (xy 56.793637 -301.611656)
			(xy 56.803798 -301.611284) (xy 58.203338 -301.611284) (xy 58.213473 -301.611697) (xy 58.232203 -301.619445)
			(xy 58.246559 -301.633754) (xy 58.25437 -301.652459) (xy 58.2549 -301.662592) (xy 58.2549 -302.071532)
			(xy 64.296036 -302.071532) (xy 64.296036 -301.662592) (xy 64.296416 -301.652433) (xy 64.304221 -301.633673)
			(xy 64.318631 -301.619349) (xy 64.337437 -301.611656) (xy 64.347598 -301.611284) (xy 65.747138 -301.611284)
			(xy 65.757273 -301.611697) (xy 65.776003 -301.619445) (xy 65.790359 -301.633754) (xy 65.79817 -301.652459)
			(xy 65.7987 -301.662592) (xy 65.7987 -302.071532) (xy 162.162236 -302.071532) (xy 162.162236 -301.662592)
			(xy 162.162616 -301.652433) (xy 162.170421 -301.633673) (xy 162.184831 -301.619349) (xy 162.203637 -301.611656)
			(xy 162.213798 -301.611284) (xy 163.613338 -301.611284) (xy 163.623473 -301.611697) (xy 163.642203 -301.619445)
			(xy 163.656559 -301.633754) (xy 163.66437 -301.652459) (xy 163.6649 -301.662592) (xy 163.6649 -302.071532)
			(xy 169.706036 -302.071532) (xy 169.706036 -301.662592) (xy 169.706416 -301.652433) (xy 169.714221 -301.633673)
			(xy 169.728631 -301.619349) (xy 169.747437 -301.611656) (xy 169.757598 -301.611284) (xy 171.157138 -301.611284)
			(xy 171.167273 -301.611697) (xy 171.186003 -301.619445) (xy 171.200359 -301.633754) (xy 171.20817 -301.652459)
			(xy 171.2087 -301.662592) (xy 171.2087 -302.071532) (xy 177.249836 -302.071532) (xy 177.249836 -301.662592)
			(xy 177.250216 -301.652433) (xy 177.258021 -301.633673) (xy 177.272431 -301.619349) (xy 177.291237 -301.611656)
			(xy 177.301398 -301.611284) (xy 178.700938 -301.611284) (xy 178.711073 -301.611697) (xy 178.729803 -301.619445)
			(xy 178.744159 -301.633754) (xy 178.75197 -301.652459) (xy 178.7525 -301.662592) (xy 178.7525 -302.071532)
			(xy 184.793636 -302.071532) (xy 184.793636 -301.662592) (xy 184.794016 -301.652433) (xy 184.801821 -301.633673)
			(xy 184.816231 -301.619349) (xy 184.835037 -301.611656) (xy 184.845198 -301.611284) (xy 186.244738 -301.611284)
			(xy 186.254873 -301.611697) (xy 186.273603 -301.619445) (xy 186.287959 -301.633754) (xy 186.29577 -301.652459)
			(xy 186.2963 -301.662592) (xy 186.2963 -302.071532) (xy 192.337436 -302.071532) (xy 192.337436 -301.662592)
			(xy 192.337816 -301.652433) (xy 192.345621 -301.633673) (xy 192.360031 -301.619349) (xy 192.378837 -301.611656)
			(xy 192.388998 -301.611284) (xy 193.788538 -301.611284) (xy 193.798673 -301.611697) (xy 193.817403 -301.619445)
			(xy 193.831759 -301.633754) (xy 193.83957 -301.652459) (xy 193.8401 -301.662592) (xy 193.8401 -302.071532)
			(xy 199.881236 -302.071532) (xy 199.881236 -301.662592) (xy 199.881616 -301.652433) (xy 199.889421 -301.633673)
			(xy 199.903831 -301.619349) (xy 199.922637 -301.611656) (xy 199.932798 -301.611284) (xy 201.332338 -301.611284)
			(xy 201.342473 -301.611697) (xy 201.361203 -301.619445) (xy 201.375559 -301.633754) (xy 201.38337 -301.652459)
			(xy 201.3839 -301.662592) (xy 201.3839 -302.071532) (xy 207.425036 -302.071532) (xy 207.425036 -301.662592)
			(xy 207.425416 -301.652433) (xy 207.433221 -301.633673) (xy 207.447631 -301.619349) (xy 207.466437 -301.611656)
			(xy 207.476598 -301.611284) (xy 208.876138 -301.611284) (xy 208.886273 -301.611697) (xy 208.905003 -301.619445)
			(xy 208.919359 -301.633754) (xy 208.92717 -301.652459) (xy 208.9277 -301.662592) (xy 208.9277 -302.071532)
			(xy 214.968836 -302.071532) (xy 214.968836 -301.662592) (xy 214.969216 -301.652433) (xy 214.977021 -301.633673)
			(xy 214.991431 -301.619349) (xy 215.010237 -301.611656) (xy 215.020398 -301.611284) (xy 216.419938 -301.611284)
			(xy 216.430073 -301.611697) (xy 216.448803 -301.619445) (xy 216.463159 -301.633754) (xy 216.47097 -301.652459)
			(xy 216.4715 -301.662592) (xy 216.4715 -302.071532) (xy 259.429504 -302.071532) (xy 259.429504 -301.662592)
			(xy 259.429915 -301.652437) (xy 259.437714 -301.633684) (xy 259.452114 -301.61936) (xy 259.470909 -301.611662)
			(xy 259.481066 -301.611284) (xy 260.880606 -301.611284) (xy 260.890738 -301.611723) (xy 260.909468 -301.619461)
			(xy 260.923826 -301.633762) (xy 260.931637 -301.652462) (xy 260.932168 -301.662592) (xy 260.932168 -302.071532)
			(xy 266.973304 -302.071532) (xy 266.973304 -301.662592) (xy 266.973715 -301.652437) (xy 266.981514 -301.633684)
			(xy 266.995914 -301.61936) (xy 267.014709 -301.611662) (xy 267.024866 -301.611284) (xy 268.424406 -301.611284)
			(xy 268.434538 -301.611723) (xy 268.453268 -301.619461) (xy 268.467626 -301.633762) (xy 268.475437 -301.652462)
			(xy 268.475968 -301.662592) (xy 268.475968 -302.071532) (xy 274.517104 -302.071532) (xy 274.517104 -301.662592)
			(xy 274.517515 -301.652437) (xy 274.525314 -301.633684) (xy 274.539714 -301.61936) (xy 274.558509 -301.611662)
			(xy 274.568666 -301.611284) (xy 275.968206 -301.611284) (xy 275.978338 -301.611723) (xy 275.997068 -301.619461)
			(xy 276.011426 -301.633762) (xy 276.019237 -301.652462) (xy 276.019768 -301.662592) (xy 276.019768 -302.071532)
			(xy 282.060904 -302.071532) (xy 282.060904 -301.662592) (xy 282.061315 -301.652437) (xy 282.069114 -301.633684)
			(xy 282.083514 -301.61936) (xy 282.102309 -301.611662) (xy 282.112466 -301.611284) (xy 283.512006 -301.611284)
			(xy 283.522138 -301.611723) (xy 283.540868 -301.619461) (xy 283.555226 -301.633762) (xy 283.563037 -301.652462)
			(xy 283.563568 -301.662592) (xy 283.563568 -302.071532) (xy 289.604704 -302.071532) (xy 289.604704 -301.662592)
			(xy 289.605115 -301.652437) (xy 289.612914 -301.633684) (xy 289.627314 -301.61936) (xy 289.646109 -301.611662)
			(xy 289.656266 -301.611284) (xy 291.055806 -301.611284) (xy 291.065938 -301.611723) (xy 291.084668 -301.619461)
			(xy 291.099026 -301.633762) (xy 291.106837 -301.652462) (xy 291.107368 -301.662592) (xy 291.107368 -302.071532)
			(xy 297.148504 -302.071532) (xy 297.148504 -301.662592) (xy 297.148915 -301.652437) (xy 297.156714 -301.633684)
			(xy 297.171114 -301.61936) (xy 297.189909 -301.611662) (xy 297.200066 -301.611284) (xy 298.599606 -301.611284)
			(xy 298.609738 -301.611723) (xy 298.628468 -301.619461) (xy 298.642826 -301.633762) (xy 298.650637 -301.652462)
			(xy 298.651168 -301.662592) (xy 298.651168 -302.071532) (xy 304.692304 -302.071532) (xy 304.692304 -301.662592)
			(xy 304.692715 -301.652437) (xy 304.700514 -301.633684) (xy 304.714914 -301.61936) (xy 304.733709 -301.611662)
			(xy 304.743866 -301.611284) (xy 306.143406 -301.611284) (xy 306.153538 -301.611723) (xy 306.172268 -301.619461)
			(xy 306.186626 -301.633762) (xy 306.194437 -301.652462) (xy 306.194968 -301.662592) (xy 306.194968 -302.071532)
			(xy 312.236104 -302.071532) (xy 312.236104 -301.662592) (xy 312.236515 -301.652437) (xy 312.244314 -301.633684)
			(xy 312.258714 -301.61936) (xy 312.277509 -301.611662) (xy 312.287666 -301.611284) (xy 313.687206 -301.611284)
			(xy 313.697338 -301.611723) (xy 313.716068 -301.619461) (xy 313.730426 -301.633762) (xy 313.738237 -301.652462)
			(xy 313.738768 -301.662592) (xy 313.738768 -302.071532) (xy 410.102304 -302.071532) (xy 410.102304 -301.662592)
			(xy 410.102715 -301.652437) (xy 410.110514 -301.633684) (xy 410.124914 -301.61936) (xy 410.143709 -301.611662)
			(xy 410.153866 -301.611284) (xy 411.553406 -301.611284) (xy 411.563538 -301.611723) (xy 411.582268 -301.619461)
			(xy 411.596626 -301.633762) (xy 411.604437 -301.652462) (xy 411.604968 -301.662592) (xy 411.604968 -302.071532)
			(xy 417.646104 -302.071532) (xy 417.646104 -301.662592) (xy 417.646515 -301.652437) (xy 417.654314 -301.633684)
			(xy 417.668714 -301.61936) (xy 417.687509 -301.611662) (xy 417.697666 -301.611284) (xy 419.097206 -301.611284)
			(xy 419.107338 -301.611723) (xy 419.126068 -301.619461) (xy 419.140426 -301.633762) (xy 419.148237 -301.652462)
			(xy 419.148768 -301.662592) (xy 419.148768 -302.071532) (xy 425.189904 -302.071532) (xy 425.189904 -301.662592)
			(xy 425.190315 -301.652437) (xy 425.198114 -301.633684) (xy 425.212514 -301.61936) (xy 425.231309 -301.611662)
			(xy 425.241466 -301.611284) (xy 426.641006 -301.611284) (xy 426.651138 -301.611723) (xy 426.669868 -301.619461)
			(xy 426.684226 -301.633762) (xy 426.692037 -301.652462) (xy 426.692568 -301.662592) (xy 426.692568 -302.071532)
			(xy 432.733704 -302.071532) (xy 432.733704 -301.662592) (xy 432.734115 -301.652437) (xy 432.741914 -301.633684)
			(xy 432.756314 -301.61936) (xy 432.775109 -301.611662) (xy 432.785266 -301.611284) (xy 434.184806 -301.611284)
			(xy 434.194938 -301.611723) (xy 434.213668 -301.619461) (xy 434.228026 -301.633762) (xy 434.235837 -301.652462)
			(xy 434.236368 -301.662592) (xy 434.236368 -302.071532) (xy 440.277504 -302.071532) (xy 440.277504 -301.662592)
			(xy 440.277915 -301.652437) (xy 440.285714 -301.633684) (xy 440.300114 -301.61936) (xy 440.318909 -301.611662)
			(xy 440.329066 -301.611284) (xy 441.728606 -301.611284) (xy 441.738738 -301.611723) (xy 441.757468 -301.619461)
			(xy 441.771826 -301.633762) (xy 441.779637 -301.652462) (xy 441.780168 -301.662592) (xy 441.780168 -302.071532)
			(xy 447.821304 -302.071532) (xy 447.821304 -301.662592) (xy 447.821715 -301.652437) (xy 447.829514 -301.633684)
			(xy 447.843914 -301.61936) (xy 447.862709 -301.611662) (xy 447.872866 -301.611284) (xy 449.272406 -301.611284)
			(xy 449.282538 -301.611723) (xy 449.301268 -301.619461) (xy 449.315626 -301.633762) (xy 449.323437 -301.652462)
			(xy 449.323968 -301.662592) (xy 449.323968 -302.071532) (xy 455.365104 -302.071532) (xy 455.365104 -301.662592)
			(xy 455.365515 -301.652437) (xy 455.373314 -301.633684) (xy 455.387714 -301.61936) (xy 455.406509 -301.611662)
			(xy 455.416666 -301.611284) (xy 456.816206 -301.611284) (xy 456.826338 -301.611723) (xy 456.845068 -301.619461)
			(xy 456.859426 -301.633762) (xy 456.867237 -301.652462) (xy 456.867768 -301.662592) (xy 456.867768 -302.071532)
			(xy 462.908904 -302.071532) (xy 462.908904 -301.662592) (xy 462.909315 -301.652437) (xy 462.917114 -301.633684)
			(xy 462.931514 -301.61936) (xy 462.950309 -301.611662) (xy 462.960466 -301.611284) (xy 464.360006 -301.611284)
			(xy 464.370138 -301.611723) (xy 464.388868 -301.619461) (xy 464.403226 -301.633762) (xy 464.411037 -301.652462)
			(xy 464.411568 -301.662592) (xy 464.411568 -302.071532) (xy 464.411204 -302.081692) (xy 464.403392 -302.100452)
			(xy 464.388977 -302.114775) (xy 464.370169 -302.122468) (xy 464.360006 -302.12284) (xy 462.960466 -302.12284)
			(xy 462.950335 -302.122401) (xy 462.931609 -302.114658) (xy 462.917253 -302.100357) (xy 462.909439 -302.081661)
			(xy 462.908904 -302.071532) (xy 456.867768 -302.071532) (xy 456.867404 -302.081692) (xy 456.859592 -302.100452)
			(xy 456.845177 -302.114775) (xy 456.826369 -302.122468) (xy 456.816206 -302.12284) (xy 455.416666 -302.12284)
			(xy 455.406535 -302.122401) (xy 455.387809 -302.114658) (xy 455.373453 -302.100357) (xy 455.365639 -302.081661)
			(xy 455.365104 -302.071532) (xy 449.323968 -302.071532) (xy 449.323604 -302.081692) (xy 449.315792 -302.100452)
			(xy 449.301377 -302.114775) (xy 449.282569 -302.122468) (xy 449.272406 -302.12284) (xy 447.872866 -302.12284)
			(xy 447.862735 -302.122401) (xy 447.844009 -302.114658) (xy 447.829653 -302.100357) (xy 447.821839 -302.081661)
			(xy 447.821304 -302.071532) (xy 441.780168 -302.071532) (xy 441.779804 -302.081692) (xy 441.771992 -302.100452)
			(xy 441.757577 -302.114775) (xy 441.738769 -302.122468) (xy 441.728606 -302.12284) (xy 440.329066 -302.12284)
			(xy 440.318935 -302.122401) (xy 440.300209 -302.114658) (xy 440.285853 -302.100357) (xy 440.278039 -302.081661)
			(xy 440.277504 -302.071532) (xy 434.236368 -302.071532) (xy 434.236004 -302.081692) (xy 434.228192 -302.100452)
			(xy 434.213777 -302.114775) (xy 434.194969 -302.122468) (xy 434.184806 -302.12284) (xy 432.785266 -302.12284)
			(xy 432.775135 -302.122401) (xy 432.756409 -302.114658) (xy 432.742053 -302.100357) (xy 432.734239 -302.081661)
			(xy 432.733704 -302.071532) (xy 426.692568 -302.071532) (xy 426.692204 -302.081692) (xy 426.684392 -302.100452)
			(xy 426.669977 -302.114775) (xy 426.651169 -302.122468) (xy 426.641006 -302.12284) (xy 425.241466 -302.12284)
			(xy 425.231335 -302.122401) (xy 425.212609 -302.114658) (xy 425.198253 -302.100357) (xy 425.190439 -302.081661)
			(xy 425.189904 -302.071532) (xy 419.148768 -302.071532) (xy 419.148404 -302.081692) (xy 419.140592 -302.100452)
			(xy 419.126177 -302.114775) (xy 419.107369 -302.122468) (xy 419.097206 -302.12284) (xy 417.697666 -302.12284)
			(xy 417.687535 -302.122401) (xy 417.668809 -302.114658) (xy 417.654453 -302.100357) (xy 417.646639 -302.081661)
			(xy 417.646104 -302.071532) (xy 411.604968 -302.071532) (xy 411.604604 -302.081692) (xy 411.596792 -302.100452)
			(xy 411.582377 -302.114775) (xy 411.563569 -302.122468) (xy 411.553406 -302.12284) (xy 410.153866 -302.12284)
			(xy 410.143735 -302.122401) (xy 410.125009 -302.114658) (xy 410.110653 -302.100357) (xy 410.102839 -302.081661)
			(xy 410.102304 -302.071532) (xy 313.738768 -302.071532) (xy 313.738404 -302.081692) (xy 313.730592 -302.100452)
			(xy 313.716177 -302.114775) (xy 313.697369 -302.122468) (xy 313.687206 -302.12284) (xy 312.287666 -302.12284)
			(xy 312.277535 -302.122401) (xy 312.258809 -302.114658) (xy 312.244453 -302.100357) (xy 312.236639 -302.081661)
			(xy 312.236104 -302.071532) (xy 306.194968 -302.071532) (xy 306.194604 -302.081692) (xy 306.186792 -302.100452)
			(xy 306.172377 -302.114775) (xy 306.153569 -302.122468) (xy 306.143406 -302.12284) (xy 304.743866 -302.12284)
			(xy 304.733735 -302.122401) (xy 304.715009 -302.114658) (xy 304.700653 -302.100357) (xy 304.692839 -302.081661)
			(xy 304.692304 -302.071532) (xy 298.651168 -302.071532) (xy 298.650804 -302.081692) (xy 298.642992 -302.100452)
			(xy 298.628577 -302.114775) (xy 298.609769 -302.122468) (xy 298.599606 -302.12284) (xy 297.200066 -302.12284)
			(xy 297.189935 -302.122401) (xy 297.171209 -302.114658) (xy 297.156853 -302.100357) (xy 297.149039 -302.081661)
			(xy 297.148504 -302.071532) (xy 291.107368 -302.071532) (xy 291.107004 -302.081692) (xy 291.099192 -302.100452)
			(xy 291.084777 -302.114775) (xy 291.065969 -302.122468) (xy 291.055806 -302.12284) (xy 289.656266 -302.12284)
			(xy 289.646135 -302.122401) (xy 289.627409 -302.114658) (xy 289.613053 -302.100357) (xy 289.605239 -302.081661)
			(xy 289.604704 -302.071532) (xy 283.563568 -302.071532) (xy 283.563204 -302.081692) (xy 283.555392 -302.100452)
			(xy 283.540977 -302.114775) (xy 283.522169 -302.122468) (xy 283.512006 -302.12284) (xy 282.112466 -302.12284)
			(xy 282.102335 -302.122401) (xy 282.083609 -302.114658) (xy 282.069253 -302.100357) (xy 282.061439 -302.081661)
			(xy 282.060904 -302.071532) (xy 276.019768 -302.071532) (xy 276.019404 -302.081692) (xy 276.011592 -302.100452)
			(xy 275.997177 -302.114775) (xy 275.978369 -302.122468) (xy 275.968206 -302.12284) (xy 274.568666 -302.12284)
			(xy 274.558535 -302.122401) (xy 274.539809 -302.114658) (xy 274.525453 -302.100357) (xy 274.517639 -302.081661)
			(xy 274.517104 -302.071532) (xy 268.475968 -302.071532) (xy 268.475604 -302.081692) (xy 268.467792 -302.100452)
			(xy 268.453377 -302.114775) (xy 268.434569 -302.122468) (xy 268.424406 -302.12284) (xy 267.024866 -302.12284)
			(xy 267.014735 -302.122401) (xy 266.996009 -302.114658) (xy 266.981653 -302.100357) (xy 266.973839 -302.081661)
			(xy 266.973304 -302.071532) (xy 260.932168 -302.071532) (xy 260.931804 -302.081692) (xy 260.923992 -302.100452)
			(xy 260.909577 -302.114775) (xy 260.890769 -302.122468) (xy 260.880606 -302.12284) (xy 259.481066 -302.12284)
			(xy 259.470935 -302.122401) (xy 259.452209 -302.114658) (xy 259.437853 -302.100357) (xy 259.430039 -302.081661)
			(xy 259.429504 -302.071532) (xy 216.4715 -302.071532) (xy 216.471105 -302.081688) (xy 216.463298 -302.100441)
			(xy 216.448894 -302.114764) (xy 216.430097 -302.122462) (xy 216.419938 -302.12284) (xy 215.020398 -302.12284)
			(xy 215.010269 -302.122374) (xy 214.991544 -302.114642) (xy 214.977187 -302.100349) (xy 214.969371 -302.081659)
			(xy 214.968836 -302.071532) (xy 208.9277 -302.071532) (xy 208.927305 -302.081688) (xy 208.919498 -302.100441)
			(xy 208.905094 -302.114764) (xy 208.886297 -302.122462) (xy 208.876138 -302.12284) (xy 207.476598 -302.12284)
			(xy 207.466469 -302.122374) (xy 207.447744 -302.114642) (xy 207.433387 -302.100349) (xy 207.425571 -302.081659)
			(xy 207.425036 -302.071532) (xy 201.3839 -302.071532) (xy 201.383505 -302.081688) (xy 201.375698 -302.100441)
			(xy 201.361294 -302.114764) (xy 201.342497 -302.122462) (xy 201.332338 -302.12284) (xy 199.932798 -302.12284)
			(xy 199.922669 -302.122374) (xy 199.903944 -302.114642) (xy 199.889587 -302.100349) (xy 199.881771 -302.081659)
			(xy 199.881236 -302.071532) (xy 193.8401 -302.071532) (xy 193.839705 -302.081688) (xy 193.831898 -302.100441)
			(xy 193.817494 -302.114764) (xy 193.798697 -302.122462) (xy 193.788538 -302.12284) (xy 192.388998 -302.12284)
			(xy 192.378869 -302.122374) (xy 192.360144 -302.114642) (xy 192.345787 -302.100349) (xy 192.337971 -302.081659)
			(xy 192.337436 -302.071532) (xy 186.2963 -302.071532) (xy 186.295905 -302.081688) (xy 186.288098 -302.100441)
			(xy 186.273694 -302.114764) (xy 186.254897 -302.122462) (xy 186.244738 -302.12284) (xy 184.845198 -302.12284)
			(xy 184.835069 -302.122374) (xy 184.816344 -302.114642) (xy 184.801987 -302.100349) (xy 184.794171 -302.081659)
			(xy 184.793636 -302.071532) (xy 178.7525 -302.071532) (xy 178.752105 -302.081688) (xy 178.744298 -302.100441)
			(xy 178.729894 -302.114764) (xy 178.711097 -302.122462) (xy 178.700938 -302.12284) (xy 177.301398 -302.12284)
			(xy 177.291269 -302.122374) (xy 177.272544 -302.114642) (xy 177.258187 -302.100349) (xy 177.250371 -302.081659)
			(xy 177.249836 -302.071532) (xy 171.2087 -302.071532) (xy 171.208305 -302.081688) (xy 171.200498 -302.100441)
			(xy 171.186094 -302.114764) (xy 171.167297 -302.122462) (xy 171.157138 -302.12284) (xy 169.757598 -302.12284)
			(xy 169.747469 -302.122374) (xy 169.728744 -302.114642) (xy 169.714387 -302.100349) (xy 169.706571 -302.081659)
			(xy 169.706036 -302.071532) (xy 163.6649 -302.071532) (xy 163.664505 -302.081688) (xy 163.656698 -302.100441)
			(xy 163.642294 -302.114764) (xy 163.623497 -302.122462) (xy 163.613338 -302.12284) (xy 162.213798 -302.12284)
			(xy 162.203669 -302.122374) (xy 162.184944 -302.114642) (xy 162.170587 -302.100349) (xy 162.162771 -302.081659)
			(xy 162.162236 -302.071532) (xy 65.7987 -302.071532) (xy 65.798305 -302.081688) (xy 65.790498 -302.100441)
			(xy 65.776094 -302.114764) (xy 65.757297 -302.122462) (xy 65.747138 -302.12284) (xy 64.347598 -302.12284)
			(xy 64.337469 -302.122374) (xy 64.318744 -302.114642) (xy 64.304387 -302.100349) (xy 64.296571 -302.081659)
			(xy 64.296036 -302.071532) (xy 58.2549 -302.071532) (xy 58.254505 -302.081688) (xy 58.246698 -302.100441)
			(xy 58.232294 -302.114764) (xy 58.213497 -302.122462) (xy 58.203338 -302.12284) (xy 56.803798 -302.12284)
			(xy 56.793669 -302.122374) (xy 56.774944 -302.114642) (xy 56.760587 -302.100349) (xy 56.752771 -302.081659)
			(xy 56.752236 -302.071532) (xy 50.7111 -302.071532) (xy 50.710705 -302.081688) (xy 50.702898 -302.100441)
			(xy 50.688494 -302.114764) (xy 50.669697 -302.122462) (xy 50.659538 -302.12284) (xy 49.259998 -302.12284)
			(xy 49.249869 -302.122374) (xy 49.231144 -302.114642) (xy 49.216787 -302.100349) (xy 49.208971 -302.081659)
			(xy 49.208436 -302.071532) (xy 43.1673 -302.071532) (xy 43.166905 -302.081688) (xy 43.159098 -302.100441)
			(xy 43.144694 -302.114764) (xy 43.125897 -302.122462) (xy 43.115738 -302.12284) (xy 41.716198 -302.12284)
			(xy 41.706069 -302.122374) (xy 41.687344 -302.114642) (xy 41.672987 -302.100349) (xy 41.665171 -302.081659)
			(xy 41.664636 -302.071532) (xy 35.6235 -302.071532) (xy 35.623105 -302.081688) (xy 35.615298 -302.100441)
			(xy 35.600894 -302.114764) (xy 35.582097 -302.122462) (xy 35.571938 -302.12284) (xy 34.172398 -302.12284)
			(xy 34.162269 -302.122374) (xy 34.143544 -302.114642) (xy 34.129187 -302.100349) (xy 34.121371 -302.081659)
			(xy 34.120836 -302.071532) (xy 28.0797 -302.071532) (xy 28.079305 -302.081688) (xy 28.071498 -302.100441)
			(xy 28.057094 -302.114764) (xy 28.038297 -302.122462) (xy 28.028138 -302.12284) (xy 26.628598 -302.12284)
			(xy 26.618469 -302.122374) (xy 26.599744 -302.114642) (xy 26.585387 -302.100349) (xy 26.577571 -302.081659)
			(xy 26.577036 -302.071532) (xy 20.5359 -302.071532) (xy 20.535505 -302.081688) (xy 20.527698 -302.100441)
			(xy 20.513294 -302.114764) (xy 20.494497 -302.122462) (xy 20.484338 -302.12284) (xy 19.084798 -302.12284)
			(xy 19.074669 -302.122374) (xy 19.055944 -302.114642) (xy 19.041587 -302.100349) (xy 19.033771 -302.081659)
			(xy 19.033236 -302.071532) (xy 12.9921 -302.071532) (xy 12.991705 -302.081688) (xy 12.983898 -302.100441)
			(xy 12.969494 -302.114764) (xy 12.950697 -302.122462) (xy 12.940538 -302.12284) (xy 11.540998 -302.12284)
			(xy 11.530869 -302.122374) (xy 11.512144 -302.114642) (xy 11.497787 -302.100349) (xy 11.489971 -302.081659)
			(xy 11.489436 -302.071532) (xy 2.509012 -302.071532) (xy 2.509012 -302.921416) (xy 7.389368 -302.921416)
			(xy 7.389368 -302.512476) (xy 7.389801 -302.502324) (xy 7.397599 -302.483577) (xy 7.411991 -302.469256)
			(xy 7.430776 -302.461551) (xy 7.44093 -302.461168) (xy 8.84047 -302.461168) (xy 8.850598 -302.461652)
			(xy 8.869324 -302.469375) (xy 8.883683 -302.483663) (xy 8.891498 -302.50235) (xy 8.892032 -302.512476)
			(xy 8.892032 -302.921416) (xy 11.489436 -302.921416) (xy 11.489436 -302.512476) (xy 11.489803 -302.502316)
			(xy 11.497613 -302.483556) (xy 11.512027 -302.469232) (xy 11.530835 -302.46154) (xy 11.540998 -302.461168)
			(xy 12.940538 -302.461168) (xy 12.950671 -302.461596) (xy 12.969398 -302.469342) (xy 12.983754 -302.483646)
			(xy 12.991567 -302.502345) (xy 12.9921 -302.512476) (xy 12.9921 -302.921416) (xy 14.933168 -302.921416)
			(xy 14.933168 -302.512476) (xy 14.933601 -302.502324) (xy 14.941399 -302.483577) (xy 14.955791 -302.469256)
			(xy 14.974576 -302.461551) (xy 14.98473 -302.461168) (xy 16.38427 -302.461168) (xy 16.394398 -302.461652)
			(xy 16.413124 -302.469375) (xy 16.427483 -302.483663) (xy 16.435298 -302.50235) (xy 16.435832 -302.512476)
			(xy 16.435832 -302.921416) (xy 19.033236 -302.921416) (xy 19.033236 -302.512476) (xy 19.033603 -302.502316)
			(xy 19.041413 -302.483556) (xy 19.055827 -302.469232) (xy 19.074635 -302.46154) (xy 19.084798 -302.461168)
			(xy 20.484338 -302.461168) (xy 20.494471 -302.461596) (xy 20.513198 -302.469342) (xy 20.527554 -302.483646)
			(xy 20.535367 -302.502345) (xy 20.5359 -302.512476) (xy 20.5359 -302.921416) (xy 22.476968 -302.921416)
			(xy 22.476968 -302.512476) (xy 22.477401 -302.502324) (xy 22.485199 -302.483577) (xy 22.499591 -302.469256)
			(xy 22.518376 -302.461551) (xy 22.52853 -302.461168) (xy 23.92807 -302.461168) (xy 23.938198 -302.461652)
			(xy 23.956924 -302.469375) (xy 23.971283 -302.483663) (xy 23.979098 -302.50235) (xy 23.979632 -302.512476)
			(xy 23.979632 -302.921416) (xy 26.577036 -302.921416) (xy 26.577036 -302.512476) (xy 26.577403 -302.502316)
			(xy 26.585213 -302.483556) (xy 26.599627 -302.469232) (xy 26.618435 -302.46154) (xy 26.628598 -302.461168)
			(xy 28.028138 -302.461168) (xy 28.038271 -302.461596) (xy 28.056998 -302.469342) (xy 28.071354 -302.483646)
			(xy 28.079167 -302.502345) (xy 28.0797 -302.512476) (xy 28.0797 -302.921416) (xy 30.020768 -302.921416)
			(xy 30.020768 -302.512476) (xy 30.021201 -302.502324) (xy 30.028999 -302.483577) (xy 30.043391 -302.469256)
			(xy 30.062176 -302.461551) (xy 30.07233 -302.461168) (xy 31.47187 -302.461168) (xy 31.481998 -302.461652)
			(xy 31.500724 -302.469375) (xy 31.515083 -302.483663) (xy 31.522898 -302.50235) (xy 31.523432 -302.512476)
			(xy 31.523432 -302.921416) (xy 34.120836 -302.921416) (xy 34.120836 -302.512476) (xy 34.121203 -302.502316)
			(xy 34.129013 -302.483556) (xy 34.143427 -302.469232) (xy 34.162235 -302.46154) (xy 34.172398 -302.461168)
			(xy 35.571938 -302.461168) (xy 35.582071 -302.461596) (xy 35.600798 -302.469342) (xy 35.615154 -302.483646)
			(xy 35.622967 -302.502345) (xy 35.6235 -302.512476) (xy 35.6235 -302.921416) (xy 37.564568 -302.921416)
			(xy 37.564568 -302.512476) (xy 37.565001 -302.502324) (xy 37.572799 -302.483577) (xy 37.587191 -302.469256)
			(xy 37.605976 -302.461551) (xy 37.61613 -302.461168) (xy 39.01567 -302.461168) (xy 39.025798 -302.461652)
			(xy 39.044524 -302.469375) (xy 39.058883 -302.483663) (xy 39.066698 -302.50235) (xy 39.067232 -302.512476)
			(xy 39.067232 -302.921416) (xy 41.664636 -302.921416) (xy 41.664636 -302.512476) (xy 41.665003 -302.502316)
			(xy 41.672813 -302.483556) (xy 41.687227 -302.469232) (xy 41.706035 -302.46154) (xy 41.716198 -302.461168)
			(xy 43.115738 -302.461168) (xy 43.125871 -302.461596) (xy 43.144598 -302.469342) (xy 43.158954 -302.483646)
			(xy 43.166767 -302.502345) (xy 43.1673 -302.512476) (xy 43.1673 -302.921416) (xy 45.108368 -302.921416)
			(xy 45.108368 -302.512476) (xy 45.108801 -302.502324) (xy 45.116599 -302.483577) (xy 45.130991 -302.469256)
			(xy 45.149776 -302.461551) (xy 45.15993 -302.461168) (xy 46.55947 -302.461168) (xy 46.569598 -302.461652)
			(xy 46.588324 -302.469375) (xy 46.602683 -302.483663) (xy 46.610498 -302.50235) (xy 46.611032 -302.512476)
			(xy 46.611032 -302.921416) (xy 49.208436 -302.921416) (xy 49.208436 -302.512476) (xy 49.208803 -302.502316)
			(xy 49.216613 -302.483556) (xy 49.231027 -302.469232) (xy 49.249835 -302.46154) (xy 49.259998 -302.461168)
			(xy 50.659538 -302.461168) (xy 50.669671 -302.461596) (xy 50.688398 -302.469342) (xy 50.702754 -302.483646)
			(xy 50.710567 -302.502345) (xy 50.7111 -302.512476) (xy 50.7111 -302.921416) (xy 52.652168 -302.921416)
			(xy 52.652168 -302.512476) (xy 52.652601 -302.502324) (xy 52.660399 -302.483577) (xy 52.674791 -302.469256)
			(xy 52.693576 -302.461551) (xy 52.70373 -302.461168) (xy 54.10327 -302.461168) (xy 54.113398 -302.461652)
			(xy 54.132124 -302.469375) (xy 54.146483 -302.483663) (xy 54.154298 -302.50235) (xy 54.154832 -302.512476)
			(xy 54.154832 -302.921416) (xy 56.752236 -302.921416) (xy 56.752236 -302.512476) (xy 56.752603 -302.502316)
			(xy 56.760413 -302.483556) (xy 56.774827 -302.469232) (xy 56.793635 -302.46154) (xy 56.803798 -302.461168)
			(xy 58.203338 -302.461168) (xy 58.213471 -302.461596) (xy 58.232198 -302.469342) (xy 58.246554 -302.483646)
			(xy 58.254367 -302.502345) (xy 58.2549 -302.512476) (xy 58.2549 -302.921416) (xy 60.195968 -302.921416)
			(xy 60.195968 -302.512476) (xy 60.196401 -302.502324) (xy 60.204199 -302.483577) (xy 60.218591 -302.469256)
			(xy 60.237376 -302.461551) (xy 60.24753 -302.461168) (xy 61.64707 -302.461168) (xy 61.657198 -302.461652)
			(xy 61.675924 -302.469375) (xy 61.690283 -302.483663) (xy 61.698098 -302.50235) (xy 61.698632 -302.512476)
			(xy 61.698632 -302.921416) (xy 64.296036 -302.921416) (xy 64.296036 -302.512476) (xy 64.296403 -302.502316)
			(xy 64.304213 -302.483556) (xy 64.318627 -302.469232) (xy 64.337435 -302.46154) (xy 64.347598 -302.461168)
			(xy 65.747138 -302.461168) (xy 65.757271 -302.461596) (xy 65.775998 -302.469342) (xy 65.790354 -302.483646)
			(xy 65.798167 -302.502345) (xy 65.7987 -302.512476) (xy 65.7987 -302.921416) (xy 158.062168 -302.921416)
			(xy 158.062168 -302.512476) (xy 158.062601 -302.502324) (xy 158.070399 -302.483577) (xy 158.084791 -302.469256)
			(xy 158.103576 -302.461551) (xy 158.11373 -302.461168) (xy 159.51327 -302.461168) (xy 159.523398 -302.461652)
			(xy 159.542124 -302.469375) (xy 159.556483 -302.483663) (xy 159.564298 -302.50235) (xy 159.564832 -302.512476)
			(xy 159.564832 -302.921416) (xy 162.162236 -302.921416) (xy 162.162236 -302.512476) (xy 162.162603 -302.502316)
			(xy 162.170413 -302.483556) (xy 162.184827 -302.469232) (xy 162.203635 -302.46154) (xy 162.213798 -302.461168)
			(xy 163.613338 -302.461168) (xy 163.623471 -302.461596) (xy 163.642198 -302.469342) (xy 163.656554 -302.483646)
			(xy 163.664367 -302.502345) (xy 163.6649 -302.512476) (xy 163.6649 -302.921416) (xy 165.605968 -302.921416)
			(xy 165.605968 -302.512476) (xy 165.606401 -302.502324) (xy 165.614199 -302.483577) (xy 165.628591 -302.469256)
			(xy 165.647376 -302.461551) (xy 165.65753 -302.461168) (xy 167.05707 -302.461168) (xy 167.067198 -302.461652)
			(xy 167.085924 -302.469375) (xy 167.100283 -302.483663) (xy 167.108098 -302.50235) (xy 167.108632 -302.512476)
			(xy 167.108632 -302.921416) (xy 169.706036 -302.921416) (xy 169.706036 -302.512476) (xy 169.706403 -302.502316)
			(xy 169.714213 -302.483556) (xy 169.728627 -302.469232) (xy 169.747435 -302.46154) (xy 169.757598 -302.461168)
			(xy 171.157138 -302.461168) (xy 171.167271 -302.461596) (xy 171.185998 -302.469342) (xy 171.200354 -302.483646)
			(xy 171.208167 -302.502345) (xy 171.2087 -302.512476) (xy 171.2087 -302.921416) (xy 173.149768 -302.921416)
			(xy 173.149768 -302.512476) (xy 173.150201 -302.502324) (xy 173.157999 -302.483577) (xy 173.172391 -302.469256)
			(xy 173.191176 -302.461551) (xy 173.20133 -302.461168) (xy 174.60087 -302.461168) (xy 174.610998 -302.461652)
			(xy 174.629724 -302.469375) (xy 174.644083 -302.483663) (xy 174.651898 -302.50235) (xy 174.652432 -302.512476)
			(xy 174.652432 -302.921416) (xy 177.249836 -302.921416) (xy 177.249836 -302.512476) (xy 177.250203 -302.502316)
			(xy 177.258013 -302.483556) (xy 177.272427 -302.469232) (xy 177.291235 -302.46154) (xy 177.301398 -302.461168)
			(xy 178.700938 -302.461168) (xy 178.711071 -302.461596) (xy 178.729798 -302.469342) (xy 178.744154 -302.483646)
			(xy 178.751967 -302.502345) (xy 178.7525 -302.512476) (xy 178.7525 -302.921416) (xy 180.693568 -302.921416)
			(xy 180.693568 -302.512476) (xy 180.694001 -302.502324) (xy 180.701799 -302.483577) (xy 180.716191 -302.469256)
			(xy 180.734976 -302.461551) (xy 180.74513 -302.461168) (xy 182.14467 -302.461168) (xy 182.154798 -302.461652)
			(xy 182.173524 -302.469375) (xy 182.187883 -302.483663) (xy 182.195698 -302.50235) (xy 182.196232 -302.512476)
			(xy 182.196232 -302.921416) (xy 184.793636 -302.921416) (xy 184.793636 -302.512476) (xy 184.794003 -302.502316)
			(xy 184.801813 -302.483556) (xy 184.816227 -302.469232) (xy 184.835035 -302.46154) (xy 184.845198 -302.461168)
			(xy 186.244738 -302.461168) (xy 186.254871 -302.461596) (xy 186.273598 -302.469342) (xy 186.287954 -302.483646)
			(xy 186.295767 -302.502345) (xy 186.2963 -302.512476) (xy 186.2963 -302.921416) (xy 188.237368 -302.921416)
			(xy 188.237368 -302.512476) (xy 188.237801 -302.502324) (xy 188.245599 -302.483577) (xy 188.259991 -302.469256)
			(xy 188.278776 -302.461551) (xy 188.28893 -302.461168) (xy 189.68847 -302.461168) (xy 189.698598 -302.461652)
			(xy 189.717324 -302.469375) (xy 189.731683 -302.483663) (xy 189.739498 -302.50235) (xy 189.740032 -302.512476)
			(xy 189.740032 -302.921416) (xy 192.337436 -302.921416) (xy 192.337436 -302.512476) (xy 192.337803 -302.502316)
			(xy 192.345613 -302.483556) (xy 192.360027 -302.469232) (xy 192.378835 -302.46154) (xy 192.388998 -302.461168)
			(xy 193.788538 -302.461168) (xy 193.798671 -302.461596) (xy 193.817398 -302.469342) (xy 193.831754 -302.483646)
			(xy 193.839567 -302.502345) (xy 193.8401 -302.512476) (xy 193.8401 -302.921416) (xy 195.781168 -302.921416)
			(xy 195.781168 -302.512476) (xy 195.781601 -302.502324) (xy 195.789399 -302.483577) (xy 195.803791 -302.469256)
			(xy 195.822576 -302.461551) (xy 195.83273 -302.461168) (xy 197.23227 -302.461168) (xy 197.242398 -302.461652)
			(xy 197.261124 -302.469375) (xy 197.275483 -302.483663) (xy 197.283298 -302.50235) (xy 197.283832 -302.512476)
			(xy 197.283832 -302.921416) (xy 199.881236 -302.921416) (xy 199.881236 -302.512476) (xy 199.881603 -302.502316)
			(xy 199.889413 -302.483556) (xy 199.903827 -302.469232) (xy 199.922635 -302.46154) (xy 199.932798 -302.461168)
			(xy 201.332338 -302.461168) (xy 201.342471 -302.461596) (xy 201.361198 -302.469342) (xy 201.375554 -302.483646)
			(xy 201.383367 -302.502345) (xy 201.3839 -302.512476) (xy 201.3839 -302.921416) (xy 203.324968 -302.921416)
			(xy 203.324968 -302.512476) (xy 203.325401 -302.502324) (xy 203.333199 -302.483577) (xy 203.347591 -302.469256)
			(xy 203.366376 -302.461551) (xy 203.37653 -302.461168) (xy 204.77607 -302.461168) (xy 204.786198 -302.461652)
			(xy 204.804924 -302.469375) (xy 204.819283 -302.483663) (xy 204.827098 -302.50235) (xy 204.827632 -302.512476)
			(xy 204.827632 -302.921416) (xy 207.425036 -302.921416) (xy 207.425036 -302.512476) (xy 207.425403 -302.502316)
			(xy 207.433213 -302.483556) (xy 207.447627 -302.469232) (xy 207.466435 -302.46154) (xy 207.476598 -302.461168)
			(xy 208.876138 -302.461168) (xy 208.886271 -302.461596) (xy 208.904998 -302.469342) (xy 208.919354 -302.483646)
			(xy 208.927167 -302.502345) (xy 208.9277 -302.512476) (xy 208.9277 -302.921416) (xy 210.868768 -302.921416)
			(xy 210.868768 -302.512476) (xy 210.869201 -302.502324) (xy 210.876999 -302.483577) (xy 210.891391 -302.469256)
			(xy 210.910176 -302.461551) (xy 210.92033 -302.461168) (xy 212.31987 -302.461168) (xy 212.329998 -302.461652)
			(xy 212.348724 -302.469375) (xy 212.363083 -302.483663) (xy 212.370898 -302.50235) (xy 212.371432 -302.512476)
			(xy 212.371432 -302.921416) (xy 214.968836 -302.921416) (xy 214.968836 -302.512476) (xy 214.969203 -302.502316)
			(xy 214.977013 -302.483556) (xy 214.991427 -302.469232) (xy 215.010235 -302.46154) (xy 215.020398 -302.461168)
			(xy 216.419938 -302.461168) (xy 216.430071 -302.461596) (xy 216.448798 -302.469342) (xy 216.463154 -302.483646)
			(xy 216.470967 -302.502345) (xy 216.4715 -302.512476) (xy 216.4715 -302.921416) (xy 255.329436 -302.921416)
			(xy 255.329436 -302.512476) (xy 255.329803 -302.502316) (xy 255.337613 -302.483556) (xy 255.352027 -302.469232)
			(xy 255.370835 -302.46154) (xy 255.380998 -302.461168) (xy 256.780538 -302.461168) (xy 256.790671 -302.461596)
			(xy 256.809398 -302.469342) (xy 256.823754 -302.483646) (xy 256.831567 -302.502345) (xy 256.8321 -302.512476)
			(xy 256.8321 -302.921416) (xy 259.429504 -302.921416) (xy 259.429504 -302.512476) (xy 259.429902 -302.50232)
			(xy 259.437706 -302.483566) (xy 259.45211 -302.469243) (xy 259.470908 -302.461545) (xy 259.481066 -302.461168)
			(xy 260.880606 -302.461168) (xy 260.890737 -302.461623) (xy 260.909463 -302.469358) (xy 260.92382 -302.483654)
			(xy 260.931634 -302.502348) (xy 260.932168 -302.512476) (xy 260.932168 -302.921416) (xy 262.873236 -302.921416)
			(xy 262.873236 -302.512476) (xy 262.873603 -302.502316) (xy 262.881413 -302.483556) (xy 262.895827 -302.469232)
			(xy 262.914635 -302.46154) (xy 262.924798 -302.461168) (xy 264.324338 -302.461168) (xy 264.334471 -302.461596)
			(xy 264.353198 -302.469342) (xy 264.367554 -302.483646) (xy 264.375367 -302.502345) (xy 264.3759 -302.512476)
			(xy 264.3759 -302.921416) (xy 266.973304 -302.921416) (xy 266.973304 -302.512476) (xy 266.973702 -302.50232)
			(xy 266.981506 -302.483566) (xy 266.99591 -302.469243) (xy 267.014708 -302.461545) (xy 267.024866 -302.461168)
			(xy 268.424406 -302.461168) (xy 268.434537 -302.461623) (xy 268.453263 -302.469358) (xy 268.46762 -302.483654)
			(xy 268.475434 -302.502348) (xy 268.475968 -302.512476) (xy 268.475968 -302.921416) (xy 270.417036 -302.921416)
			(xy 270.417036 -302.512476) (xy 270.417403 -302.502316) (xy 270.425213 -302.483556) (xy 270.439627 -302.469232)
			(xy 270.458435 -302.46154) (xy 270.468598 -302.461168) (xy 271.868138 -302.461168) (xy 271.878271 -302.461596)
			(xy 271.896998 -302.469342) (xy 271.911354 -302.483646) (xy 271.919167 -302.502345) (xy 271.9197 -302.512476)
			(xy 271.9197 -302.921416) (xy 274.517104 -302.921416) (xy 274.517104 -302.512476) (xy 274.517502 -302.50232)
			(xy 274.525306 -302.483566) (xy 274.53971 -302.469243) (xy 274.558508 -302.461545) (xy 274.568666 -302.461168)
			(xy 275.968206 -302.461168) (xy 275.978337 -302.461623) (xy 275.997063 -302.469358) (xy 276.01142 -302.483654)
			(xy 276.019234 -302.502348) (xy 276.019768 -302.512476) (xy 276.019768 -302.921416) (xy 277.960836 -302.921416)
			(xy 277.960836 -302.512476) (xy 277.961203 -302.502316) (xy 277.969013 -302.483556) (xy 277.983427 -302.469232)
			(xy 278.002235 -302.46154) (xy 278.012398 -302.461168) (xy 279.411938 -302.461168) (xy 279.422071 -302.461596)
			(xy 279.440798 -302.469342) (xy 279.455154 -302.483646) (xy 279.462967 -302.502345) (xy 279.4635 -302.512476)
			(xy 279.4635 -302.921416) (xy 282.060904 -302.921416) (xy 282.060904 -302.512476) (xy 282.061302 -302.50232)
			(xy 282.069106 -302.483566) (xy 282.08351 -302.469243) (xy 282.102308 -302.461545) (xy 282.112466 -302.461168)
			(xy 283.512006 -302.461168) (xy 283.522137 -302.461623) (xy 283.540863 -302.469358) (xy 283.55522 -302.483654)
			(xy 283.563034 -302.502348) (xy 283.563568 -302.512476) (xy 283.563568 -302.921416) (xy 285.504636 -302.921416)
			(xy 285.504636 -302.512476) (xy 285.505003 -302.502316) (xy 285.512813 -302.483556) (xy 285.527227 -302.469232)
			(xy 285.546035 -302.46154) (xy 285.556198 -302.461168) (xy 286.955738 -302.461168) (xy 286.965871 -302.461596)
			(xy 286.984598 -302.469342) (xy 286.998954 -302.483646) (xy 287.006767 -302.502345) (xy 287.0073 -302.512476)
			(xy 287.0073 -302.921416) (xy 289.604704 -302.921416) (xy 289.604704 -302.512476) (xy 289.605102 -302.50232)
			(xy 289.612906 -302.483566) (xy 289.62731 -302.469243) (xy 289.646108 -302.461545) (xy 289.656266 -302.461168)
			(xy 291.055806 -302.461168) (xy 291.065937 -302.461623) (xy 291.084663 -302.469358) (xy 291.09902 -302.483654)
			(xy 291.106834 -302.502348) (xy 291.107368 -302.512476) (xy 291.107368 -302.921416) (xy 293.048436 -302.921416)
			(xy 293.048436 -302.512476) (xy 293.048803 -302.502316) (xy 293.056613 -302.483556) (xy 293.071027 -302.469232)
			(xy 293.089835 -302.46154) (xy 293.099998 -302.461168) (xy 294.499538 -302.461168) (xy 294.509671 -302.461596)
			(xy 294.528398 -302.469342) (xy 294.542754 -302.483646) (xy 294.550567 -302.502345) (xy 294.5511 -302.512476)
			(xy 294.5511 -302.921416) (xy 297.148504 -302.921416) (xy 297.148504 -302.512476) (xy 297.148902 -302.50232)
			(xy 297.156706 -302.483566) (xy 297.17111 -302.469243) (xy 297.189908 -302.461545) (xy 297.200066 -302.461168)
			(xy 298.599606 -302.461168) (xy 298.609737 -302.461623) (xy 298.628463 -302.469358) (xy 298.64282 -302.483654)
			(xy 298.650634 -302.502348) (xy 298.651168 -302.512476) (xy 298.651168 -302.921416) (xy 300.592236 -302.921416)
			(xy 300.592236 -302.512476) (xy 300.592603 -302.502316) (xy 300.600413 -302.483556) (xy 300.614827 -302.469232)
			(xy 300.633635 -302.46154) (xy 300.643798 -302.461168) (xy 302.043338 -302.461168) (xy 302.053471 -302.461596)
			(xy 302.072198 -302.469342) (xy 302.086554 -302.483646) (xy 302.094367 -302.502345) (xy 302.0949 -302.512476)
			(xy 302.0949 -302.921416) (xy 304.692304 -302.921416) (xy 304.692304 -302.512476) (xy 304.692702 -302.50232)
			(xy 304.700506 -302.483566) (xy 304.71491 -302.469243) (xy 304.733708 -302.461545) (xy 304.743866 -302.461168)
			(xy 306.143406 -302.461168) (xy 306.153537 -302.461623) (xy 306.172263 -302.469358) (xy 306.18662 -302.483654)
			(xy 306.194434 -302.502348) (xy 306.194968 -302.512476) (xy 306.194968 -302.921416) (xy 308.136036 -302.921416)
			(xy 308.136036 -302.512476) (xy 308.136403 -302.502316) (xy 308.144213 -302.483556) (xy 308.158627 -302.469232)
			(xy 308.177435 -302.46154) (xy 308.187598 -302.461168) (xy 309.587138 -302.461168) (xy 309.597271 -302.461596)
			(xy 309.615998 -302.469342) (xy 309.630354 -302.483646) (xy 309.638167 -302.502345) (xy 309.6387 -302.512476)
			(xy 309.6387 -302.921416) (xy 312.236104 -302.921416) (xy 312.236104 -302.512476) (xy 312.236502 -302.50232)
			(xy 312.244306 -302.483566) (xy 312.25871 -302.469243) (xy 312.277508 -302.461545) (xy 312.287666 -302.461168)
			(xy 313.687206 -302.461168) (xy 313.697337 -302.461623) (xy 313.716063 -302.469358) (xy 313.73042 -302.483654)
			(xy 313.738234 -302.502348) (xy 313.738768 -302.512476) (xy 313.738768 -302.921416) (xy 406.002236 -302.921416)
			(xy 406.002236 -302.512476) (xy 406.002603 -302.502316) (xy 406.010413 -302.483556) (xy 406.024827 -302.469232)
			(xy 406.043635 -302.46154) (xy 406.053798 -302.461168) (xy 407.453338 -302.461168) (xy 407.463471 -302.461596)
			(xy 407.482198 -302.469342) (xy 407.496554 -302.483646) (xy 407.504367 -302.502345) (xy 407.5049 -302.512476)
			(xy 407.5049 -302.921416) (xy 410.102304 -302.921416) (xy 410.102304 -302.512476) (xy 410.102702 -302.50232)
			(xy 410.110506 -302.483566) (xy 410.12491 -302.469243) (xy 410.143708 -302.461545) (xy 410.153866 -302.461168)
			(xy 411.553406 -302.461168) (xy 411.563537 -302.461623) (xy 411.582263 -302.469358) (xy 411.59662 -302.483654)
			(xy 411.604434 -302.502348) (xy 411.604968 -302.512476) (xy 411.604968 -302.921416) (xy 413.546036 -302.921416)
			(xy 413.546036 -302.512476) (xy 413.546403 -302.502316) (xy 413.554213 -302.483556) (xy 413.568627 -302.469232)
			(xy 413.587435 -302.46154) (xy 413.597598 -302.461168) (xy 414.997138 -302.461168) (xy 415.007271 -302.461596)
			(xy 415.025998 -302.469342) (xy 415.040354 -302.483646) (xy 415.048167 -302.502345) (xy 415.0487 -302.512476)
			(xy 415.0487 -302.921416) (xy 417.646104 -302.921416) (xy 417.646104 -302.512476) (xy 417.646502 -302.50232)
			(xy 417.654306 -302.483566) (xy 417.66871 -302.469243) (xy 417.687508 -302.461545) (xy 417.697666 -302.461168)
			(xy 419.097206 -302.461168) (xy 419.107337 -302.461623) (xy 419.126063 -302.469358) (xy 419.14042 -302.483654)
			(xy 419.148234 -302.502348) (xy 419.148768 -302.512476) (xy 419.148768 -302.921416) (xy 421.089836 -302.921416)
			(xy 421.089836 -302.512476) (xy 421.090203 -302.502316) (xy 421.098013 -302.483556) (xy 421.112427 -302.469232)
			(xy 421.131235 -302.46154) (xy 421.141398 -302.461168) (xy 422.540938 -302.461168) (xy 422.551071 -302.461596)
			(xy 422.569798 -302.469342) (xy 422.584154 -302.483646) (xy 422.591967 -302.502345) (xy 422.5925 -302.512476)
			(xy 422.5925 -302.921416) (xy 425.189904 -302.921416) (xy 425.189904 -302.512476) (xy 425.190302 -302.50232)
			(xy 425.198106 -302.483566) (xy 425.21251 -302.469243) (xy 425.231308 -302.461545) (xy 425.241466 -302.461168)
			(xy 426.641006 -302.461168) (xy 426.651137 -302.461623) (xy 426.669863 -302.469358) (xy 426.68422 -302.483654)
			(xy 426.692034 -302.502348) (xy 426.692568 -302.512476) (xy 426.692568 -302.921416) (xy 428.633636 -302.921416)
			(xy 428.633636 -302.512476) (xy 428.634003 -302.502316) (xy 428.641813 -302.483556) (xy 428.656227 -302.469232)
			(xy 428.675035 -302.46154) (xy 428.685198 -302.461168) (xy 430.084738 -302.461168) (xy 430.094871 -302.461596)
			(xy 430.113598 -302.469342) (xy 430.127954 -302.483646) (xy 430.135767 -302.502345) (xy 430.1363 -302.512476)
			(xy 430.1363 -302.921416) (xy 432.733704 -302.921416) (xy 432.733704 -302.512476) (xy 432.734102 -302.50232)
			(xy 432.741906 -302.483566) (xy 432.75631 -302.469243) (xy 432.775108 -302.461545) (xy 432.785266 -302.461168)
			(xy 434.184806 -302.461168) (xy 434.194937 -302.461623) (xy 434.213663 -302.469358) (xy 434.22802 -302.483654)
			(xy 434.235834 -302.502348) (xy 434.236368 -302.512476) (xy 434.236368 -302.921416) (xy 436.177436 -302.921416)
			(xy 436.177436 -302.512476) (xy 436.177803 -302.502316) (xy 436.185613 -302.483556) (xy 436.200027 -302.469232)
			(xy 436.218835 -302.46154) (xy 436.228998 -302.461168) (xy 437.628538 -302.461168) (xy 437.638671 -302.461596)
			(xy 437.657398 -302.469342) (xy 437.671754 -302.483646) (xy 437.679567 -302.502345) (xy 437.6801 -302.512476)
			(xy 437.6801 -302.921416) (xy 440.277504 -302.921416) (xy 440.277504 -302.512476) (xy 440.277902 -302.50232)
			(xy 440.285706 -302.483566) (xy 440.30011 -302.469243) (xy 440.318908 -302.461545) (xy 440.329066 -302.461168)
			(xy 441.728606 -302.461168) (xy 441.738737 -302.461623) (xy 441.757463 -302.469358) (xy 441.77182 -302.483654)
			(xy 441.779634 -302.502348) (xy 441.780168 -302.512476) (xy 441.780168 -302.921416) (xy 443.721236 -302.921416)
			(xy 443.721236 -302.512476) (xy 443.721603 -302.502316) (xy 443.729413 -302.483556) (xy 443.743827 -302.469232)
			(xy 443.762635 -302.46154) (xy 443.772798 -302.461168) (xy 445.172338 -302.461168) (xy 445.182471 -302.461596)
			(xy 445.201198 -302.469342) (xy 445.215554 -302.483646) (xy 445.223367 -302.502345) (xy 445.2239 -302.512476)
			(xy 445.2239 -302.921416) (xy 447.821304 -302.921416) (xy 447.821304 -302.512476) (xy 447.821702 -302.50232)
			(xy 447.829506 -302.483566) (xy 447.84391 -302.469243) (xy 447.862708 -302.461545) (xy 447.872866 -302.461168)
			(xy 449.272406 -302.461168) (xy 449.282537 -302.461623) (xy 449.301263 -302.469358) (xy 449.31562 -302.483654)
			(xy 449.323434 -302.502348) (xy 449.323968 -302.512476) (xy 449.323968 -302.921416) (xy 451.265036 -302.921416)
			(xy 451.265036 -302.512476) (xy 451.265403 -302.502316) (xy 451.273213 -302.483556) (xy 451.287627 -302.469232)
			(xy 451.306435 -302.46154) (xy 451.316598 -302.461168) (xy 452.716138 -302.461168) (xy 452.726271 -302.461596)
			(xy 452.744998 -302.469342) (xy 452.759354 -302.483646) (xy 452.767167 -302.502345) (xy 452.7677 -302.512476)
			(xy 452.7677 -302.921416) (xy 455.365104 -302.921416) (xy 455.365104 -302.512476) (xy 455.365502 -302.50232)
			(xy 455.373306 -302.483566) (xy 455.38771 -302.469243) (xy 455.406508 -302.461545) (xy 455.416666 -302.461168)
			(xy 456.816206 -302.461168) (xy 456.826337 -302.461623) (xy 456.845063 -302.469358) (xy 456.85942 -302.483654)
			(xy 456.867234 -302.502348) (xy 456.867768 -302.512476) (xy 456.867768 -302.921416) (xy 458.808836 -302.921416)
			(xy 458.808836 -302.512476) (xy 458.809203 -302.502316) (xy 458.817013 -302.483556) (xy 458.831427 -302.469232)
			(xy 458.850235 -302.46154) (xy 458.860398 -302.461168) (xy 460.259938 -302.461168) (xy 460.270071 -302.461596)
			(xy 460.288798 -302.469342) (xy 460.303154 -302.483646) (xy 460.310967 -302.502345) (xy 460.3115 -302.512476)
			(xy 460.3115 -302.921416) (xy 462.908904 -302.921416) (xy 462.908904 -302.512476) (xy 462.909302 -302.50232)
			(xy 462.917106 -302.483566) (xy 462.93151 -302.469243) (xy 462.950308 -302.461545) (xy 462.960466 -302.461168)
			(xy 464.360006 -302.461168) (xy 464.370137 -302.461623) (xy 464.388863 -302.469358) (xy 464.40322 -302.483654)
			(xy 464.411034 -302.502348) (xy 464.411568 -302.512476) (xy 464.411568 -302.921416) (xy 464.411191 -302.931575)
			(xy 464.403384 -302.950334) (xy 464.388973 -302.964658) (xy 464.370168 -302.972352) (xy 464.360006 -302.972724)
			(xy 462.960466 -302.972724) (xy 462.950333 -302.9723) (xy 462.931604 -302.964555) (xy 462.917248 -302.950249)
			(xy 462.909436 -302.931547) (xy 462.908904 -302.921416) (xy 460.3115 -302.921416) (xy 460.311092 -302.931571)
			(xy 460.303291 -302.950324) (xy 460.28889 -302.964647) (xy 460.270095 -302.972346) (xy 460.259938 -302.972724)
			(xy 458.860398 -302.972724) (xy 458.850267 -302.972274) (xy 458.831539 -302.964539) (xy 458.817181 -302.950241)
			(xy 458.809369 -302.931545) (xy 458.808836 -302.921416) (xy 456.867768 -302.921416) (xy 456.867391 -302.931575)
			(xy 456.859584 -302.950334) (xy 456.845173 -302.964658) (xy 456.826368 -302.972352) (xy 456.816206 -302.972724)
			(xy 455.416666 -302.972724) (xy 455.406533 -302.9723) (xy 455.387804 -302.964555) (xy 455.373448 -302.950249)
			(xy 455.365636 -302.931547) (xy 455.365104 -302.921416) (xy 452.7677 -302.921416) (xy 452.767292 -302.931571)
			(xy 452.759491 -302.950324) (xy 452.74509 -302.964647) (xy 452.726295 -302.972346) (xy 452.716138 -302.972724)
			(xy 451.316598 -302.972724) (xy 451.306467 -302.972274) (xy 451.287739 -302.964539) (xy 451.273381 -302.950241)
			(xy 451.265569 -302.931545) (xy 451.265036 -302.921416) (xy 449.323968 -302.921416) (xy 449.323591 -302.931575)
			(xy 449.315784 -302.950334) (xy 449.301373 -302.964658) (xy 449.282568 -302.972352) (xy 449.272406 -302.972724)
			(xy 447.872866 -302.972724) (xy 447.862733 -302.9723) (xy 447.844004 -302.964555) (xy 447.829648 -302.950249)
			(xy 447.821836 -302.931547) (xy 447.821304 -302.921416) (xy 445.2239 -302.921416) (xy 445.223492 -302.931571)
			(xy 445.215691 -302.950324) (xy 445.20129 -302.964647) (xy 445.182495 -302.972346) (xy 445.172338 -302.972724)
			(xy 443.772798 -302.972724) (xy 443.762667 -302.972274) (xy 443.743939 -302.964539) (xy 443.729581 -302.950241)
			(xy 443.721769 -302.931545) (xy 443.721236 -302.921416) (xy 441.780168 -302.921416) (xy 441.779791 -302.931575)
			(xy 441.771984 -302.950334) (xy 441.757573 -302.964658) (xy 441.738768 -302.972352) (xy 441.728606 -302.972724)
			(xy 440.329066 -302.972724) (xy 440.318933 -302.9723) (xy 440.300204 -302.964555) (xy 440.285848 -302.950249)
			(xy 440.278036 -302.931547) (xy 440.277504 -302.921416) (xy 437.6801 -302.921416) (xy 437.679692 -302.931571)
			(xy 437.671891 -302.950324) (xy 437.65749 -302.964647) (xy 437.638695 -302.972346) (xy 437.628538 -302.972724)
			(xy 436.228998 -302.972724) (xy 436.218867 -302.972274) (xy 436.200139 -302.964539) (xy 436.185781 -302.950241)
			(xy 436.177969 -302.931545) (xy 436.177436 -302.921416) (xy 434.236368 -302.921416) (xy 434.235991 -302.931575)
			(xy 434.228184 -302.950334) (xy 434.213773 -302.964658) (xy 434.194968 -302.972352) (xy 434.184806 -302.972724)
			(xy 432.785266 -302.972724) (xy 432.775133 -302.9723) (xy 432.756404 -302.964555) (xy 432.742048 -302.950249)
			(xy 432.734236 -302.931547) (xy 432.733704 -302.921416) (xy 430.1363 -302.921416) (xy 430.135892 -302.931571)
			(xy 430.128091 -302.950324) (xy 430.11369 -302.964647) (xy 430.094895 -302.972346) (xy 430.084738 -302.972724)
			(xy 428.685198 -302.972724) (xy 428.675067 -302.972274) (xy 428.656339 -302.964539) (xy 428.641981 -302.950241)
			(xy 428.634169 -302.931545) (xy 428.633636 -302.921416) (xy 426.692568 -302.921416) (xy 426.692191 -302.931575)
			(xy 426.684384 -302.950334) (xy 426.669973 -302.964658) (xy 426.651168 -302.972352) (xy 426.641006 -302.972724)
			(xy 425.241466 -302.972724) (xy 425.231333 -302.9723) (xy 425.212604 -302.964555) (xy 425.198248 -302.950249)
			(xy 425.190436 -302.931547) (xy 425.189904 -302.921416) (xy 422.5925 -302.921416) (xy 422.592092 -302.931571)
			(xy 422.584291 -302.950324) (xy 422.56989 -302.964647) (xy 422.551095 -302.972346) (xy 422.540938 -302.972724)
			(xy 421.141398 -302.972724) (xy 421.131267 -302.972274) (xy 421.112539 -302.964539) (xy 421.098181 -302.950241)
			(xy 421.090369 -302.931545) (xy 421.089836 -302.921416) (xy 419.148768 -302.921416) (xy 419.148391 -302.931575)
			(xy 419.140584 -302.950334) (xy 419.126173 -302.964658) (xy 419.107368 -302.972352) (xy 419.097206 -302.972724)
			(xy 417.697666 -302.972724) (xy 417.687533 -302.9723) (xy 417.668804 -302.964555) (xy 417.654448 -302.950249)
			(xy 417.646636 -302.931547) (xy 417.646104 -302.921416) (xy 415.0487 -302.921416) (xy 415.048292 -302.931571)
			(xy 415.040491 -302.950324) (xy 415.02609 -302.964647) (xy 415.007295 -302.972346) (xy 414.997138 -302.972724)
			(xy 413.597598 -302.972724) (xy 413.587467 -302.972274) (xy 413.568739 -302.964539) (xy 413.554381 -302.950241)
			(xy 413.546569 -302.931545) (xy 413.546036 -302.921416) (xy 411.604968 -302.921416) (xy 411.604591 -302.931575)
			(xy 411.596784 -302.950334) (xy 411.582373 -302.964658) (xy 411.563568 -302.972352) (xy 411.553406 -302.972724)
			(xy 410.153866 -302.972724) (xy 410.143733 -302.9723) (xy 410.125004 -302.964555) (xy 410.110648 -302.950249)
			(xy 410.102836 -302.931547) (xy 410.102304 -302.921416) (xy 407.5049 -302.921416) (xy 407.504492 -302.931571)
			(xy 407.496691 -302.950324) (xy 407.48229 -302.964647) (xy 407.463495 -302.972346) (xy 407.453338 -302.972724)
			(xy 406.053798 -302.972724) (xy 406.043667 -302.972274) (xy 406.024939 -302.964539) (xy 406.010581 -302.950241)
			(xy 406.002769 -302.931545) (xy 406.002236 -302.921416) (xy 313.738768 -302.921416) (xy 313.738391 -302.931575)
			(xy 313.730584 -302.950334) (xy 313.716173 -302.964658) (xy 313.697368 -302.972352) (xy 313.687206 -302.972724)
			(xy 312.287666 -302.972724) (xy 312.277533 -302.9723) (xy 312.258804 -302.964555) (xy 312.244448 -302.950249)
			(xy 312.236636 -302.931547) (xy 312.236104 -302.921416) (xy 309.6387 -302.921416) (xy 309.638292 -302.931571)
			(xy 309.630491 -302.950324) (xy 309.61609 -302.964647) (xy 309.597295 -302.972346) (xy 309.587138 -302.972724)
			(xy 308.187598 -302.972724) (xy 308.177467 -302.972274) (xy 308.158739 -302.964539) (xy 308.144381 -302.950241)
			(xy 308.136569 -302.931545) (xy 308.136036 -302.921416) (xy 306.194968 -302.921416) (xy 306.194591 -302.931575)
			(xy 306.186784 -302.950334) (xy 306.172373 -302.964658) (xy 306.153568 -302.972352) (xy 306.143406 -302.972724)
			(xy 304.743866 -302.972724) (xy 304.733733 -302.9723) (xy 304.715004 -302.964555) (xy 304.700648 -302.950249)
			(xy 304.692836 -302.931547) (xy 304.692304 -302.921416) (xy 302.0949 -302.921416) (xy 302.094492 -302.931571)
			(xy 302.086691 -302.950324) (xy 302.07229 -302.964647) (xy 302.053495 -302.972346) (xy 302.043338 -302.972724)
			(xy 300.643798 -302.972724) (xy 300.633667 -302.972274) (xy 300.614939 -302.964539) (xy 300.600581 -302.950241)
			(xy 300.592769 -302.931545) (xy 300.592236 -302.921416) (xy 298.651168 -302.921416) (xy 298.650791 -302.931575)
			(xy 298.642984 -302.950334) (xy 298.628573 -302.964658) (xy 298.609768 -302.972352) (xy 298.599606 -302.972724)
			(xy 297.200066 -302.972724) (xy 297.189933 -302.9723) (xy 297.171204 -302.964555) (xy 297.156848 -302.950249)
			(xy 297.149036 -302.931547) (xy 297.148504 -302.921416) (xy 294.5511 -302.921416) (xy 294.550692 -302.931571)
			(xy 294.542891 -302.950324) (xy 294.52849 -302.964647) (xy 294.509695 -302.972346) (xy 294.499538 -302.972724)
			(xy 293.099998 -302.972724) (xy 293.089867 -302.972274) (xy 293.071139 -302.964539) (xy 293.056781 -302.950241)
			(xy 293.048969 -302.931545) (xy 293.048436 -302.921416) (xy 291.107368 -302.921416) (xy 291.106991 -302.931575)
			(xy 291.099184 -302.950334) (xy 291.084773 -302.964658) (xy 291.065968 -302.972352) (xy 291.055806 -302.972724)
			(xy 289.656266 -302.972724) (xy 289.646133 -302.9723) (xy 289.627404 -302.964555) (xy 289.613048 -302.950249)
			(xy 289.605236 -302.931547) (xy 289.604704 -302.921416) (xy 287.0073 -302.921416) (xy 287.006892 -302.931571)
			(xy 286.999091 -302.950324) (xy 286.98469 -302.964647) (xy 286.965895 -302.972346) (xy 286.955738 -302.972724)
			(xy 285.556198 -302.972724) (xy 285.546067 -302.972274) (xy 285.527339 -302.964539) (xy 285.512981 -302.950241)
			(xy 285.505169 -302.931545) (xy 285.504636 -302.921416) (xy 283.563568 -302.921416) (xy 283.563191 -302.931575)
			(xy 283.555384 -302.950334) (xy 283.540973 -302.964658) (xy 283.522168 -302.972352) (xy 283.512006 -302.972724)
			(xy 282.112466 -302.972724) (xy 282.102333 -302.9723) (xy 282.083604 -302.964555) (xy 282.069248 -302.950249)
			(xy 282.061436 -302.931547) (xy 282.060904 -302.921416) (xy 279.4635 -302.921416) (xy 279.463092 -302.931571)
			(xy 279.455291 -302.950324) (xy 279.44089 -302.964647) (xy 279.422095 -302.972346) (xy 279.411938 -302.972724)
			(xy 278.012398 -302.972724) (xy 278.002267 -302.972274) (xy 277.983539 -302.964539) (xy 277.969181 -302.950241)
			(xy 277.961369 -302.931545) (xy 277.960836 -302.921416) (xy 276.019768 -302.921416) (xy 276.019391 -302.931575)
			(xy 276.011584 -302.950334) (xy 275.997173 -302.964658) (xy 275.978368 -302.972352) (xy 275.968206 -302.972724)
			(xy 274.568666 -302.972724) (xy 274.558533 -302.9723) (xy 274.539804 -302.964555) (xy 274.525448 -302.950249)
			(xy 274.517636 -302.931547) (xy 274.517104 -302.921416) (xy 271.9197 -302.921416) (xy 271.919292 -302.931571)
			(xy 271.911491 -302.950324) (xy 271.89709 -302.964647) (xy 271.878295 -302.972346) (xy 271.868138 -302.972724)
			(xy 270.468598 -302.972724) (xy 270.458467 -302.972274) (xy 270.439739 -302.964539) (xy 270.425381 -302.950241)
			(xy 270.417569 -302.931545) (xy 270.417036 -302.921416) (xy 268.475968 -302.921416) (xy 268.475591 -302.931575)
			(xy 268.467784 -302.950334) (xy 268.453373 -302.964658) (xy 268.434568 -302.972352) (xy 268.424406 -302.972724)
			(xy 267.024866 -302.972724) (xy 267.014733 -302.9723) (xy 266.996004 -302.964555) (xy 266.981648 -302.950249)
			(xy 266.973836 -302.931547) (xy 266.973304 -302.921416) (xy 264.3759 -302.921416) (xy 264.375492 -302.931571)
			(xy 264.367691 -302.950324) (xy 264.35329 -302.964647) (xy 264.334495 -302.972346) (xy 264.324338 -302.972724)
			(xy 262.924798 -302.972724) (xy 262.914667 -302.972274) (xy 262.895939 -302.964539) (xy 262.881581 -302.950241)
			(xy 262.873769 -302.931545) (xy 262.873236 -302.921416) (xy 260.932168 -302.921416) (xy 260.931791 -302.931575)
			(xy 260.923984 -302.950334) (xy 260.909573 -302.964658) (xy 260.890768 -302.972352) (xy 260.880606 -302.972724)
			(xy 259.481066 -302.972724) (xy 259.470933 -302.9723) (xy 259.452204 -302.964555) (xy 259.437848 -302.950249)
			(xy 259.430036 -302.931547) (xy 259.429504 -302.921416) (xy 256.8321 -302.921416) (xy 256.831692 -302.931571)
			(xy 256.823891 -302.950324) (xy 256.80949 -302.964647) (xy 256.790695 -302.972346) (xy 256.780538 -302.972724)
			(xy 255.380998 -302.972724) (xy 255.370867 -302.972274) (xy 255.352139 -302.964539) (xy 255.337781 -302.950241)
			(xy 255.329969 -302.931545) (xy 255.329436 -302.921416) (xy 216.4715 -302.921416) (xy 216.471092 -302.931571)
			(xy 216.463291 -302.950324) (xy 216.44889 -302.964647) (xy 216.430095 -302.972346) (xy 216.419938 -302.972724)
			(xy 215.020398 -302.972724) (xy 215.010267 -302.972274) (xy 214.991539 -302.964539) (xy 214.977181 -302.950241)
			(xy 214.969369 -302.931545) (xy 214.968836 -302.921416) (xy 212.371432 -302.921416) (xy 212.370992 -302.931567)
			(xy 212.363197 -302.950314) (xy 212.348807 -302.964636) (xy 212.330023 -302.972341) (xy 212.31987 -302.972724)
			(xy 210.92033 -302.972724) (xy 210.910201 -302.972248) (xy 210.891473 -302.964523) (xy 210.877115 -302.950233)
			(xy 210.869301 -302.931543) (xy 210.868768 -302.921416) (xy 208.9277 -302.921416) (xy 208.927292 -302.931571)
			(xy 208.919491 -302.950324) (xy 208.90509 -302.964647) (xy 208.886295 -302.972346) (xy 208.876138 -302.972724)
			(xy 207.476598 -302.972724) (xy 207.466467 -302.972274) (xy 207.447739 -302.964539) (xy 207.433381 -302.950241)
			(xy 207.425569 -302.931545) (xy 207.425036 -302.921416) (xy 204.827632 -302.921416) (xy 204.827192 -302.931567)
			(xy 204.819397 -302.950314) (xy 204.805007 -302.964636) (xy 204.786223 -302.972341) (xy 204.77607 -302.972724)
			(xy 203.37653 -302.972724) (xy 203.366401 -302.972248) (xy 203.347673 -302.964523) (xy 203.333315 -302.950233)
			(xy 203.325501 -302.931543) (xy 203.324968 -302.921416) (xy 201.3839 -302.921416) (xy 201.383492 -302.931571)
			(xy 201.375691 -302.950324) (xy 201.36129 -302.964647) (xy 201.342495 -302.972346) (xy 201.332338 -302.972724)
			(xy 199.932798 -302.972724) (xy 199.922667 -302.972274) (xy 199.903939 -302.964539) (xy 199.889581 -302.950241)
			(xy 199.881769 -302.931545) (xy 199.881236 -302.921416) (xy 197.283832 -302.921416) (xy 197.283392 -302.931567)
			(xy 197.275597 -302.950314) (xy 197.261207 -302.964636) (xy 197.242423 -302.972341) (xy 197.23227 -302.972724)
			(xy 195.83273 -302.972724) (xy 195.822601 -302.972248) (xy 195.803873 -302.964523) (xy 195.789515 -302.950233)
			(xy 195.781701 -302.931543) (xy 195.781168 -302.921416) (xy 193.8401 -302.921416) (xy 193.839692 -302.931571)
			(xy 193.831891 -302.950324) (xy 193.81749 -302.964647) (xy 193.798695 -302.972346) (xy 193.788538 -302.972724)
			(xy 192.388998 -302.972724) (xy 192.378867 -302.972274) (xy 192.360139 -302.964539) (xy 192.345781 -302.950241)
			(xy 192.337969 -302.931545) (xy 192.337436 -302.921416) (xy 189.740032 -302.921416) (xy 189.739592 -302.931567)
			(xy 189.731797 -302.950314) (xy 189.717407 -302.964636) (xy 189.698623 -302.972341) (xy 189.68847 -302.972724)
			(xy 188.28893 -302.972724) (xy 188.278801 -302.972248) (xy 188.260073 -302.964523) (xy 188.245715 -302.950233)
			(xy 188.237901 -302.931543) (xy 188.237368 -302.921416) (xy 186.2963 -302.921416) (xy 186.295892 -302.931571)
			(xy 186.288091 -302.950324) (xy 186.27369 -302.964647) (xy 186.254895 -302.972346) (xy 186.244738 -302.972724)
			(xy 184.845198 -302.972724) (xy 184.835067 -302.972274) (xy 184.816339 -302.964539) (xy 184.801981 -302.950241)
			(xy 184.794169 -302.931545) (xy 184.793636 -302.921416) (xy 182.196232 -302.921416) (xy 182.195792 -302.931567)
			(xy 182.187997 -302.950314) (xy 182.173607 -302.964636) (xy 182.154823 -302.972341) (xy 182.14467 -302.972724)
			(xy 180.74513 -302.972724) (xy 180.735001 -302.972248) (xy 180.716273 -302.964523) (xy 180.701915 -302.950233)
			(xy 180.694101 -302.931543) (xy 180.693568 -302.921416) (xy 178.7525 -302.921416) (xy 178.752092 -302.931571)
			(xy 178.744291 -302.950324) (xy 178.72989 -302.964647) (xy 178.711095 -302.972346) (xy 178.700938 -302.972724)
			(xy 177.301398 -302.972724) (xy 177.291267 -302.972274) (xy 177.272539 -302.964539) (xy 177.258181 -302.950241)
			(xy 177.250369 -302.931545) (xy 177.249836 -302.921416) (xy 174.652432 -302.921416) (xy 174.651992 -302.931567)
			(xy 174.644197 -302.950314) (xy 174.629807 -302.964636) (xy 174.611023 -302.972341) (xy 174.60087 -302.972724)
			(xy 173.20133 -302.972724) (xy 173.191201 -302.972248) (xy 173.172473 -302.964523) (xy 173.158115 -302.950233)
			(xy 173.150301 -302.931543) (xy 173.149768 -302.921416) (xy 171.2087 -302.921416) (xy 171.208292 -302.931571)
			(xy 171.200491 -302.950324) (xy 171.18609 -302.964647) (xy 171.167295 -302.972346) (xy 171.157138 -302.972724)
			(xy 169.757598 -302.972724) (xy 169.747467 -302.972274) (xy 169.728739 -302.964539) (xy 169.714381 -302.950241)
			(xy 169.706569 -302.931545) (xy 169.706036 -302.921416) (xy 167.108632 -302.921416) (xy 167.108192 -302.931567)
			(xy 167.100397 -302.950314) (xy 167.086007 -302.964636) (xy 167.067223 -302.972341) (xy 167.05707 -302.972724)
			(xy 165.65753 -302.972724) (xy 165.647401 -302.972248) (xy 165.628673 -302.964523) (xy 165.614315 -302.950233)
			(xy 165.606501 -302.931543) (xy 165.605968 -302.921416) (xy 163.6649 -302.921416) (xy 163.664492 -302.931571)
			(xy 163.656691 -302.950324) (xy 163.64229 -302.964647) (xy 163.623495 -302.972346) (xy 163.613338 -302.972724)
			(xy 162.213798 -302.972724) (xy 162.203667 -302.972274) (xy 162.184939 -302.964539) (xy 162.170581 -302.950241)
			(xy 162.162769 -302.931545) (xy 162.162236 -302.921416) (xy 159.564832 -302.921416) (xy 159.564392 -302.931567)
			(xy 159.556597 -302.950314) (xy 159.542207 -302.964636) (xy 159.523423 -302.972341) (xy 159.51327 -302.972724)
			(xy 158.11373 -302.972724) (xy 158.103601 -302.972248) (xy 158.084873 -302.964523) (xy 158.070515 -302.950233)
			(xy 158.062701 -302.931543) (xy 158.062168 -302.921416) (xy 65.7987 -302.921416) (xy 65.798292 -302.931571)
			(xy 65.790491 -302.950324) (xy 65.77609 -302.964647) (xy 65.757295 -302.972346) (xy 65.747138 -302.972724)
			(xy 64.347598 -302.972724) (xy 64.337467 -302.972274) (xy 64.318739 -302.964539) (xy 64.304381 -302.950241)
			(xy 64.296569 -302.931545) (xy 64.296036 -302.921416) (xy 61.698632 -302.921416) (xy 61.698192 -302.931567)
			(xy 61.690397 -302.950314) (xy 61.676007 -302.964636) (xy 61.657223 -302.972341) (xy 61.64707 -302.972724)
			(xy 60.24753 -302.972724) (xy 60.237401 -302.972248) (xy 60.218673 -302.964523) (xy 60.204315 -302.950233)
			(xy 60.196501 -302.931543) (xy 60.195968 -302.921416) (xy 58.2549 -302.921416) (xy 58.254492 -302.931571)
			(xy 58.246691 -302.950324) (xy 58.23229 -302.964647) (xy 58.213495 -302.972346) (xy 58.203338 -302.972724)
			(xy 56.803798 -302.972724) (xy 56.793667 -302.972274) (xy 56.774939 -302.964539) (xy 56.760581 -302.950241)
			(xy 56.752769 -302.931545) (xy 56.752236 -302.921416) (xy 54.154832 -302.921416) (xy 54.154392 -302.931567)
			(xy 54.146597 -302.950314) (xy 54.132207 -302.964636) (xy 54.113423 -302.972341) (xy 54.10327 -302.972724)
			(xy 52.70373 -302.972724) (xy 52.693601 -302.972248) (xy 52.674873 -302.964523) (xy 52.660515 -302.950233)
			(xy 52.652701 -302.931543) (xy 52.652168 -302.921416) (xy 50.7111 -302.921416) (xy 50.710692 -302.931571)
			(xy 50.702891 -302.950324) (xy 50.68849 -302.964647) (xy 50.669695 -302.972346) (xy 50.659538 -302.972724)
			(xy 49.259998 -302.972724) (xy 49.249867 -302.972274) (xy 49.231139 -302.964539) (xy 49.216781 -302.950241)
			(xy 49.208969 -302.931545) (xy 49.208436 -302.921416) (xy 46.611032 -302.921416) (xy 46.610592 -302.931567)
			(xy 46.602797 -302.950314) (xy 46.588407 -302.964636) (xy 46.569623 -302.972341) (xy 46.55947 -302.972724)
			(xy 45.15993 -302.972724) (xy 45.149801 -302.972248) (xy 45.131073 -302.964523) (xy 45.116715 -302.950233)
			(xy 45.108901 -302.931543) (xy 45.108368 -302.921416) (xy 43.1673 -302.921416) (xy 43.166892 -302.931571)
			(xy 43.159091 -302.950324) (xy 43.14469 -302.964647) (xy 43.125895 -302.972346) (xy 43.115738 -302.972724)
			(xy 41.716198 -302.972724) (xy 41.706067 -302.972274) (xy 41.687339 -302.964539) (xy 41.672981 -302.950241)
			(xy 41.665169 -302.931545) (xy 41.664636 -302.921416) (xy 39.067232 -302.921416) (xy 39.066792 -302.931567)
			(xy 39.058997 -302.950314) (xy 39.044607 -302.964636) (xy 39.025823 -302.972341) (xy 39.01567 -302.972724)
			(xy 37.61613 -302.972724) (xy 37.606001 -302.972248) (xy 37.587273 -302.964523) (xy 37.572915 -302.950233)
			(xy 37.565101 -302.931543) (xy 37.564568 -302.921416) (xy 35.6235 -302.921416) (xy 35.623092 -302.931571)
			(xy 35.615291 -302.950324) (xy 35.60089 -302.964647) (xy 35.582095 -302.972346) (xy 35.571938 -302.972724)
			(xy 34.172398 -302.972724) (xy 34.162267 -302.972274) (xy 34.143539 -302.964539) (xy 34.129181 -302.950241)
			(xy 34.121369 -302.931545) (xy 34.120836 -302.921416) (xy 31.523432 -302.921416) (xy 31.522992 -302.931567)
			(xy 31.515197 -302.950314) (xy 31.500807 -302.964636) (xy 31.482023 -302.972341) (xy 31.47187 -302.972724)
			(xy 30.07233 -302.972724) (xy 30.062201 -302.972248) (xy 30.043473 -302.964523) (xy 30.029115 -302.950233)
			(xy 30.021301 -302.931543) (xy 30.020768 -302.921416) (xy 28.0797 -302.921416) (xy 28.079292 -302.931571)
			(xy 28.071491 -302.950324) (xy 28.05709 -302.964647) (xy 28.038295 -302.972346) (xy 28.028138 -302.972724)
			(xy 26.628598 -302.972724) (xy 26.618467 -302.972274) (xy 26.599739 -302.964539) (xy 26.585381 -302.950241)
			(xy 26.577569 -302.931545) (xy 26.577036 -302.921416) (xy 23.979632 -302.921416) (xy 23.979192 -302.931567)
			(xy 23.971397 -302.950314) (xy 23.957007 -302.964636) (xy 23.938223 -302.972341) (xy 23.92807 -302.972724)
			(xy 22.52853 -302.972724) (xy 22.518401 -302.972248) (xy 22.499673 -302.964523) (xy 22.485315 -302.950233)
			(xy 22.477501 -302.931543) (xy 22.476968 -302.921416) (xy 20.5359 -302.921416) (xy 20.535492 -302.931571)
			(xy 20.527691 -302.950324) (xy 20.51329 -302.964647) (xy 20.494495 -302.972346) (xy 20.484338 -302.972724)
			(xy 19.084798 -302.972724) (xy 19.074667 -302.972274) (xy 19.055939 -302.964539) (xy 19.041581 -302.950241)
			(xy 19.033769 -302.931545) (xy 19.033236 -302.921416) (xy 16.435832 -302.921416) (xy 16.435392 -302.931567)
			(xy 16.427597 -302.950314) (xy 16.413207 -302.964636) (xy 16.394423 -302.972341) (xy 16.38427 -302.972724)
			(xy 14.98473 -302.972724) (xy 14.974601 -302.972248) (xy 14.955873 -302.964523) (xy 14.941515 -302.950233)
			(xy 14.933701 -302.931543) (xy 14.933168 -302.921416) (xy 12.9921 -302.921416) (xy 12.991692 -302.931571)
			(xy 12.983891 -302.950324) (xy 12.96949 -302.964647) (xy 12.950695 -302.972346) (xy 12.940538 -302.972724)
			(xy 11.540998 -302.972724) (xy 11.530867 -302.972274) (xy 11.512139 -302.964539) (xy 11.497781 -302.950241)
			(xy 11.489969 -302.931545) (xy 11.489436 -302.921416) (xy 8.892032 -302.921416) (xy 8.891592 -302.931567)
			(xy 8.883797 -302.950314) (xy 8.869407 -302.964636) (xy 8.850623 -302.972341) (xy 8.84047 -302.972724)
			(xy 7.44093 -302.972724) (xy 7.430801 -302.972248) (xy 7.412073 -302.964523) (xy 7.397715 -302.950233)
			(xy 7.389901 -302.931543) (xy 7.389368 -302.921416) (xy 2.509012 -302.921416) (xy 2.509012 -303.7713)
			(xy 7.389368 -303.7713) (xy 7.389368 -303.36236) (xy 7.389788 -303.352207) (xy 7.397591 -303.33346)
			(xy 7.411987 -303.319139) (xy 7.430775 -303.311435) (xy 7.44093 -303.311052) (xy 8.84047 -303.311052)
			(xy 8.850596 -303.311551) (xy 8.869319 -303.319271) (xy 8.883677 -303.333554) (xy 8.891495 -303.352236)
			(xy 8.892032 -303.36236) (xy 8.892032 -303.7713) (xy 14.933168 -303.7713) (xy 14.933168 -303.36236)
			(xy 14.933588 -303.352207) (xy 14.941391 -303.33346) (xy 14.955787 -303.319139) (xy 14.974575 -303.311435)
			(xy 14.98473 -303.311052) (xy 16.38427 -303.311052) (xy 16.394396 -303.311551) (xy 16.413119 -303.319271)
			(xy 16.427477 -303.333554) (xy 16.435295 -303.352236) (xy 16.435832 -303.36236) (xy 16.435832 -303.7713)
			(xy 22.476968 -303.7713) (xy 22.476968 -303.36236) (xy 22.477388 -303.352207) (xy 22.485191 -303.33346)
			(xy 22.499587 -303.319139) (xy 22.518375 -303.311435) (xy 22.52853 -303.311052) (xy 23.92807 -303.311052)
			(xy 23.938196 -303.311551) (xy 23.956919 -303.319271) (xy 23.971277 -303.333554) (xy 23.979095 -303.352236)
			(xy 23.979632 -303.36236) (xy 23.979632 -303.7713) (xy 30.020768 -303.7713) (xy 30.020768 -303.36236)
			(xy 30.021188 -303.352207) (xy 30.028991 -303.33346) (xy 30.043387 -303.319139) (xy 30.062175 -303.311435)
			(xy 30.07233 -303.311052) (xy 31.47187 -303.311052) (xy 31.481996 -303.311551) (xy 31.500719 -303.319271)
			(xy 31.515077 -303.333554) (xy 31.522895 -303.352236) (xy 31.523432 -303.36236) (xy 31.523432 -303.7713)
			(xy 37.564568 -303.7713) (xy 37.564568 -303.36236) (xy 37.564988 -303.352207) (xy 37.572791 -303.33346)
			(xy 37.587187 -303.319139) (xy 37.605975 -303.311435) (xy 37.61613 -303.311052) (xy 39.01567 -303.311052)
			(xy 39.025796 -303.311551) (xy 39.044519 -303.319271) (xy 39.058877 -303.333554) (xy 39.066695 -303.352236)
			(xy 39.067232 -303.36236) (xy 39.067232 -303.7713) (xy 45.108368 -303.7713) (xy 45.108368 -303.36236)
			(xy 45.108788 -303.352207) (xy 45.116591 -303.33346) (xy 45.130987 -303.319139) (xy 45.149775 -303.311435)
			(xy 45.15993 -303.311052) (xy 46.55947 -303.311052) (xy 46.569596 -303.311551) (xy 46.588319 -303.319271)
			(xy 46.602677 -303.333554) (xy 46.610495 -303.352236) (xy 46.611032 -303.36236) (xy 46.611032 -303.7713)
			(xy 52.652168 -303.7713) (xy 52.652168 -303.36236) (xy 52.652588 -303.352207) (xy 52.660391 -303.33346)
			(xy 52.674787 -303.319139) (xy 52.693575 -303.311435) (xy 52.70373 -303.311052) (xy 54.10327 -303.311052)
			(xy 54.113396 -303.311551) (xy 54.132119 -303.319271) (xy 54.146477 -303.333554) (xy 54.154295 -303.352236)
			(xy 54.154832 -303.36236) (xy 54.154832 -303.7713) (xy 60.195968 -303.7713) (xy 60.195968 -303.36236)
			(xy 60.196388 -303.352207) (xy 60.204191 -303.33346) (xy 60.218587 -303.319139) (xy 60.237375 -303.311435)
			(xy 60.24753 -303.311052) (xy 61.64707 -303.311052) (xy 61.657196 -303.311551) (xy 61.675919 -303.319271)
			(xy 61.690277 -303.333554) (xy 61.698095 -303.352236) (xy 61.698632 -303.36236) (xy 61.698632 -303.7713)
			(xy 158.062168 -303.7713) (xy 158.062168 -303.36236) (xy 158.062588 -303.352207) (xy 158.070391 -303.33346)
			(xy 158.084787 -303.319139) (xy 158.103575 -303.311435) (xy 158.11373 -303.311052) (xy 159.51327 -303.311052)
			(xy 159.523396 -303.311551) (xy 159.542119 -303.319271) (xy 159.556477 -303.333554) (xy 159.564295 -303.352236)
			(xy 159.564832 -303.36236) (xy 159.564832 -303.7713) (xy 165.605968 -303.7713) (xy 165.605968 -303.36236)
			(xy 165.606388 -303.352207) (xy 165.614191 -303.33346) (xy 165.628587 -303.319139) (xy 165.647375 -303.311435)
			(xy 165.65753 -303.311052) (xy 167.05707 -303.311052) (xy 167.067196 -303.311551) (xy 167.085919 -303.319271)
			(xy 167.100277 -303.333554) (xy 167.108095 -303.352236) (xy 167.108632 -303.36236) (xy 167.108632 -303.7713)
			(xy 173.149768 -303.7713) (xy 173.149768 -303.36236) (xy 173.150188 -303.352207) (xy 173.157991 -303.33346)
			(xy 173.172387 -303.319139) (xy 173.191175 -303.311435) (xy 173.20133 -303.311052) (xy 174.60087 -303.311052)
			(xy 174.610996 -303.311551) (xy 174.629719 -303.319271) (xy 174.644077 -303.333554) (xy 174.651895 -303.352236)
			(xy 174.652432 -303.36236) (xy 174.652432 -303.7713) (xy 180.693568 -303.7713) (xy 180.693568 -303.36236)
			(xy 180.693988 -303.352207) (xy 180.701791 -303.33346) (xy 180.716187 -303.319139) (xy 180.734975 -303.311435)
			(xy 180.74513 -303.311052) (xy 182.14467 -303.311052) (xy 182.154796 -303.311551) (xy 182.173519 -303.319271)
			(xy 182.187877 -303.333554) (xy 182.195695 -303.352236) (xy 182.196232 -303.36236) (xy 182.196232 -303.7713)
			(xy 188.237368 -303.7713) (xy 188.237368 -303.36236) (xy 188.237788 -303.352207) (xy 188.245591 -303.33346)
			(xy 188.259987 -303.319139) (xy 188.278775 -303.311435) (xy 188.28893 -303.311052) (xy 189.68847 -303.311052)
			(xy 189.698596 -303.311551) (xy 189.717319 -303.319271) (xy 189.731677 -303.333554) (xy 189.739495 -303.352236)
			(xy 189.740032 -303.36236) (xy 189.740032 -303.7713) (xy 195.781168 -303.7713) (xy 195.781168 -303.36236)
			(xy 195.781588 -303.352207) (xy 195.789391 -303.33346) (xy 195.803787 -303.319139) (xy 195.822575 -303.311435)
			(xy 195.83273 -303.311052) (xy 197.23227 -303.311052) (xy 197.242396 -303.311551) (xy 197.261119 -303.319271)
			(xy 197.275477 -303.333554) (xy 197.283295 -303.352236) (xy 197.283832 -303.36236) (xy 197.283832 -303.7713)
			(xy 203.324968 -303.7713) (xy 203.324968 -303.36236) (xy 203.325388 -303.352207) (xy 203.333191 -303.33346)
			(xy 203.347587 -303.319139) (xy 203.366375 -303.311435) (xy 203.37653 -303.311052) (xy 204.77607 -303.311052)
			(xy 204.786196 -303.311551) (xy 204.804919 -303.319271) (xy 204.819277 -303.333554) (xy 204.827095 -303.352236)
			(xy 204.827632 -303.36236) (xy 204.827632 -303.7713) (xy 210.868768 -303.7713) (xy 210.868768 -303.36236)
			(xy 210.869188 -303.352207) (xy 210.876991 -303.33346) (xy 210.891387 -303.319139) (xy 210.910175 -303.311435)
			(xy 210.92033 -303.311052) (xy 212.31987 -303.311052) (xy 212.329996 -303.311551) (xy 212.348719 -303.319271)
			(xy 212.363077 -303.333554) (xy 212.370895 -303.352236) (xy 212.371432 -303.36236) (xy 212.371432 -303.7713)
			(xy 255.329436 -303.7713) (xy 255.329436 -303.36236) (xy 255.32979 -303.352199) (xy 255.337605 -303.333439)
			(xy 255.352023 -303.319115) (xy 255.370834 -303.311424) (xy 255.380998 -303.311052) (xy 256.780538 -303.311052)
			(xy 256.790669 -303.311496) (xy 256.809393 -303.319238) (xy 256.823748 -303.333538) (xy 256.831564 -303.352231)
			(xy 256.8321 -303.36236) (xy 256.8321 -303.7713) (xy 262.873236 -303.7713) (xy 262.873236 -303.36236)
			(xy 262.87359 -303.352199) (xy 262.881405 -303.333439) (xy 262.895823 -303.319115) (xy 262.914634 -303.311424)
			(xy 262.924798 -303.311052) (xy 264.324338 -303.311052) (xy 264.334469 -303.311496) (xy 264.353193 -303.319238)
			(xy 264.367548 -303.333538) (xy 264.375364 -303.352231) (xy 264.3759 -303.36236) (xy 264.3759 -303.7713)
			(xy 270.417036 -303.7713) (xy 270.417036 -303.36236) (xy 270.41739 -303.352199) (xy 270.425205 -303.333439)
			(xy 270.439623 -303.319115) (xy 270.458434 -303.311424) (xy 270.468598 -303.311052) (xy 271.868138 -303.311052)
			(xy 271.878269 -303.311496) (xy 271.896993 -303.319238) (xy 271.911348 -303.333538) (xy 271.919164 -303.352231)
			(xy 271.9197 -303.36236) (xy 271.9197 -303.7713) (xy 277.960836 -303.7713) (xy 277.960836 -303.36236)
			(xy 277.96119 -303.352199) (xy 277.969005 -303.333439) (xy 277.983423 -303.319115) (xy 278.002234 -303.311424)
			(xy 278.012398 -303.311052) (xy 279.411938 -303.311052) (xy 279.422069 -303.311496) (xy 279.440793 -303.319238)
			(xy 279.455148 -303.333538) (xy 279.462964 -303.352231) (xy 279.4635 -303.36236) (xy 279.4635 -303.7713)
			(xy 285.504636 -303.7713) (xy 285.504636 -303.36236) (xy 285.50499 -303.352199) (xy 285.512805 -303.333439)
			(xy 285.527223 -303.319115) (xy 285.546034 -303.311424) (xy 285.556198 -303.311052) (xy 286.955738 -303.311052)
			(xy 286.965869 -303.311496) (xy 286.984593 -303.319238) (xy 286.998948 -303.333538) (xy 287.006764 -303.352231)
			(xy 287.0073 -303.36236) (xy 287.0073 -303.7713) (xy 293.048436 -303.7713) (xy 293.048436 -303.36236)
			(xy 293.04879 -303.352199) (xy 293.056605 -303.333439) (xy 293.071023 -303.319115) (xy 293.089834 -303.311424)
			(xy 293.099998 -303.311052) (xy 294.499538 -303.311052) (xy 294.509669 -303.311496) (xy 294.528393 -303.319238)
			(xy 294.542748 -303.333538) (xy 294.550564 -303.352231) (xy 294.5511 -303.36236) (xy 294.5511 -303.7713)
			(xy 300.592236 -303.7713) (xy 300.592236 -303.36236) (xy 300.59259 -303.352199) (xy 300.600405 -303.333439)
			(xy 300.614823 -303.319115) (xy 300.633634 -303.311424) (xy 300.643798 -303.311052) (xy 302.043338 -303.311052)
			(xy 302.053469 -303.311496) (xy 302.072193 -303.319238) (xy 302.086548 -303.333538) (xy 302.094364 -303.352231)
			(xy 302.0949 -303.36236) (xy 302.0949 -303.7713) (xy 308.136036 -303.7713) (xy 308.136036 -303.36236)
			(xy 308.13639 -303.352199) (xy 308.144205 -303.333439) (xy 308.158623 -303.319115) (xy 308.177434 -303.311424)
			(xy 308.187598 -303.311052) (xy 309.587138 -303.311052) (xy 309.597269 -303.311496) (xy 309.615993 -303.319238)
			(xy 309.630348 -303.333538) (xy 309.638164 -303.352231) (xy 309.6387 -303.36236) (xy 309.6387 -303.7713)
			(xy 406.002236 -303.7713) (xy 406.002236 -303.36236) (xy 406.00259 -303.352199) (xy 406.010405 -303.333439)
			(xy 406.024823 -303.319115) (xy 406.043634 -303.311424) (xy 406.053798 -303.311052) (xy 407.453338 -303.311052)
			(xy 407.463469 -303.311496) (xy 407.482193 -303.319238) (xy 407.496548 -303.333538) (xy 407.504364 -303.352231)
			(xy 407.5049 -303.36236) (xy 407.5049 -303.7713) (xy 413.546036 -303.7713) (xy 413.546036 -303.36236)
			(xy 413.54639 -303.352199) (xy 413.554205 -303.333439) (xy 413.568623 -303.319115) (xy 413.587434 -303.311424)
			(xy 413.597598 -303.311052) (xy 414.997138 -303.311052) (xy 415.007269 -303.311496) (xy 415.025993 -303.319238)
			(xy 415.040348 -303.333538) (xy 415.048164 -303.352231) (xy 415.0487 -303.36236) (xy 415.0487 -303.7713)
			(xy 421.089836 -303.7713) (xy 421.089836 -303.36236) (xy 421.09019 -303.352199) (xy 421.098005 -303.333439)
			(xy 421.112423 -303.319115) (xy 421.131234 -303.311424) (xy 421.141398 -303.311052) (xy 422.540938 -303.311052)
			(xy 422.551069 -303.311496) (xy 422.569793 -303.319238) (xy 422.584148 -303.333538) (xy 422.591964 -303.352231)
			(xy 422.5925 -303.36236) (xy 422.5925 -303.7713) (xy 428.633636 -303.7713) (xy 428.633636 -303.36236)
			(xy 428.63399 -303.352199) (xy 428.641805 -303.333439) (xy 428.656223 -303.319115) (xy 428.675034 -303.311424)
			(xy 428.685198 -303.311052) (xy 430.084738 -303.311052) (xy 430.094869 -303.311496) (xy 430.113593 -303.319238)
			(xy 430.127948 -303.333538) (xy 430.135764 -303.352231) (xy 430.1363 -303.36236) (xy 430.1363 -303.7713)
			(xy 436.177436 -303.7713) (xy 436.177436 -303.36236) (xy 436.17779 -303.352199) (xy 436.185605 -303.333439)
			(xy 436.200023 -303.319115) (xy 436.218834 -303.311424) (xy 436.228998 -303.311052) (xy 437.628538 -303.311052)
			(xy 437.638669 -303.311496) (xy 437.657393 -303.319238) (xy 437.671748 -303.333538) (xy 437.679564 -303.352231)
			(xy 437.6801 -303.36236) (xy 437.6801 -303.7713) (xy 443.721236 -303.7713) (xy 443.721236 -303.36236)
			(xy 443.72159 -303.352199) (xy 443.729405 -303.333439) (xy 443.743823 -303.319115) (xy 443.762634 -303.311424)
			(xy 443.772798 -303.311052) (xy 445.172338 -303.311052) (xy 445.182469 -303.311496) (xy 445.201193 -303.319238)
			(xy 445.215548 -303.333538) (xy 445.223364 -303.352231) (xy 445.2239 -303.36236) (xy 445.2239 -303.7713)
			(xy 451.265036 -303.7713) (xy 451.265036 -303.36236) (xy 451.26539 -303.352199) (xy 451.273205 -303.333439)
			(xy 451.287623 -303.319115) (xy 451.306434 -303.311424) (xy 451.316598 -303.311052) (xy 452.716138 -303.311052)
			(xy 452.726269 -303.311496) (xy 452.744993 -303.319238) (xy 452.759348 -303.333538) (xy 452.767164 -303.352231)
			(xy 452.7677 -303.36236) (xy 452.7677 -303.7713) (xy 458.808836 -303.7713) (xy 458.808836 -303.36236)
			(xy 458.80919 -303.352199) (xy 458.817005 -303.333439) (xy 458.831423 -303.319115) (xy 458.850234 -303.311424)
			(xy 458.860398 -303.311052) (xy 460.259938 -303.311052) (xy 460.270069 -303.311496) (xy 460.288793 -303.319238)
			(xy 460.303148 -303.333538) (xy 460.310964 -303.352231) (xy 460.3115 -303.36236) (xy 460.3115 -303.7713)
			(xy 460.311078 -303.781454) (xy 460.303283 -303.800206) (xy 460.288886 -303.81453) (xy 460.270094 -303.822229)
			(xy 460.259938 -303.822608) (xy 458.860398 -303.822608) (xy 458.850277 -303.822076) (xy 458.831565 -303.814357)
			(xy 458.817211 -303.800085) (xy 458.809383 -303.781418) (xy 458.808836 -303.7713) (xy 452.7677 -303.7713)
			(xy 452.767278 -303.781454) (xy 452.759483 -303.800206) (xy 452.745086 -303.81453) (xy 452.726294 -303.822229)
			(xy 452.716138 -303.822608) (xy 451.316598 -303.822608) (xy 451.306477 -303.822076) (xy 451.287765 -303.814357)
			(xy 451.273411 -303.800085) (xy 451.265583 -303.781418) (xy 451.265036 -303.7713) (xy 445.2239 -303.7713)
			(xy 445.223478 -303.781454) (xy 445.215683 -303.800206) (xy 445.201286 -303.81453) (xy 445.182494 -303.822229)
			(xy 445.172338 -303.822608) (xy 443.772798 -303.822608) (xy 443.762677 -303.822076) (xy 443.743965 -303.814357)
			(xy 443.729611 -303.800085) (xy 443.721783 -303.781418) (xy 443.721236 -303.7713) (xy 437.6801 -303.7713)
			(xy 437.679678 -303.781454) (xy 437.671883 -303.800206) (xy 437.657486 -303.81453) (xy 437.638694 -303.822229)
			(xy 437.628538 -303.822608) (xy 436.228998 -303.822608) (xy 436.218877 -303.822076) (xy 436.200165 -303.814357)
			(xy 436.185811 -303.800085) (xy 436.177983 -303.781418) (xy 436.177436 -303.7713) (xy 430.1363 -303.7713)
			(xy 430.135878 -303.781454) (xy 430.128083 -303.800206) (xy 430.113686 -303.81453) (xy 430.094894 -303.822229)
			(xy 430.084738 -303.822608) (xy 428.685198 -303.822608) (xy 428.675077 -303.822076) (xy 428.656365 -303.814357)
			(xy 428.642011 -303.800085) (xy 428.634183 -303.781418) (xy 428.633636 -303.7713) (xy 422.5925 -303.7713)
			(xy 422.592078 -303.781454) (xy 422.584283 -303.800206) (xy 422.569886 -303.81453) (xy 422.551094 -303.822229)
			(xy 422.540938 -303.822608) (xy 421.141398 -303.822608) (xy 421.131277 -303.822076) (xy 421.112565 -303.814357)
			(xy 421.098211 -303.800085) (xy 421.090383 -303.781418) (xy 421.089836 -303.7713) (xy 415.0487 -303.7713)
			(xy 415.048278 -303.781454) (xy 415.040483 -303.800206) (xy 415.026086 -303.81453) (xy 415.007294 -303.822229)
			(xy 414.997138 -303.822608) (xy 413.597598 -303.822608) (xy 413.587477 -303.822076) (xy 413.568765 -303.814357)
			(xy 413.554411 -303.800085) (xy 413.546583 -303.781418) (xy 413.546036 -303.7713) (xy 407.5049 -303.7713)
			(xy 407.504478 -303.781454) (xy 407.496683 -303.800206) (xy 407.482286 -303.81453) (xy 407.463494 -303.822229)
			(xy 407.453338 -303.822608) (xy 406.053798 -303.822608) (xy 406.043677 -303.822076) (xy 406.024965 -303.814357)
			(xy 406.010611 -303.800085) (xy 406.002783 -303.781418) (xy 406.002236 -303.7713) (xy 309.6387 -303.7713)
			(xy 309.638278 -303.781454) (xy 309.630483 -303.800206) (xy 309.616086 -303.81453) (xy 309.597294 -303.822229)
			(xy 309.587138 -303.822608) (xy 308.187598 -303.822608) (xy 308.177477 -303.822076) (xy 308.158765 -303.814357)
			(xy 308.144411 -303.800085) (xy 308.136583 -303.781418) (xy 308.136036 -303.7713) (xy 302.0949 -303.7713)
			(xy 302.094478 -303.781454) (xy 302.086683 -303.800206) (xy 302.072286 -303.81453) (xy 302.053494 -303.822229)
			(xy 302.043338 -303.822608) (xy 300.643798 -303.822608) (xy 300.633677 -303.822076) (xy 300.614965 -303.814357)
			(xy 300.600611 -303.800085) (xy 300.592783 -303.781418) (xy 300.592236 -303.7713) (xy 294.5511 -303.7713)
			(xy 294.550678 -303.781454) (xy 294.542883 -303.800206) (xy 294.528486 -303.81453) (xy 294.509694 -303.822229)
			(xy 294.499538 -303.822608) (xy 293.099998 -303.822608) (xy 293.089877 -303.822076) (xy 293.071165 -303.814357)
			(xy 293.056811 -303.800085) (xy 293.048983 -303.781418) (xy 293.048436 -303.7713) (xy 287.0073 -303.7713)
			(xy 287.006878 -303.781454) (xy 286.999083 -303.800206) (xy 286.984686 -303.81453) (xy 286.965894 -303.822229)
			(xy 286.955738 -303.822608) (xy 285.556198 -303.822608) (xy 285.546077 -303.822076) (xy 285.527365 -303.814357)
			(xy 285.513011 -303.800085) (xy 285.505183 -303.781418) (xy 285.504636 -303.7713) (xy 279.4635 -303.7713)
			(xy 279.463078 -303.781454) (xy 279.455283 -303.800206) (xy 279.440886 -303.81453) (xy 279.422094 -303.822229)
			(xy 279.411938 -303.822608) (xy 278.012398 -303.822608) (xy 278.002277 -303.822076) (xy 277.983565 -303.814357)
			(xy 277.969211 -303.800085) (xy 277.961383 -303.781418) (xy 277.960836 -303.7713) (xy 271.9197 -303.7713)
			(xy 271.919278 -303.781454) (xy 271.911483 -303.800206) (xy 271.897086 -303.81453) (xy 271.878294 -303.822229)
			(xy 271.868138 -303.822608) (xy 270.468598 -303.822608) (xy 270.458477 -303.822076) (xy 270.439765 -303.814357)
			(xy 270.425411 -303.800085) (xy 270.417583 -303.781418) (xy 270.417036 -303.7713) (xy 264.3759 -303.7713)
			(xy 264.375478 -303.781454) (xy 264.367683 -303.800206) (xy 264.353286 -303.81453) (xy 264.334494 -303.822229)
			(xy 264.324338 -303.822608) (xy 262.924798 -303.822608) (xy 262.914677 -303.822076) (xy 262.895965 -303.814357)
			(xy 262.881611 -303.800085) (xy 262.873783 -303.781418) (xy 262.873236 -303.7713) (xy 256.8321 -303.7713)
			(xy 256.831678 -303.781454) (xy 256.823883 -303.800206) (xy 256.809486 -303.81453) (xy 256.790694 -303.822229)
			(xy 256.780538 -303.822608) (xy 255.380998 -303.822608) (xy 255.370877 -303.822076) (xy 255.352165 -303.814357)
			(xy 255.337811 -303.800085) (xy 255.329983 -303.781418) (xy 255.329436 -303.7713) (xy 212.371432 -303.7713)
			(xy 212.370979 -303.78145) (xy 212.363189 -303.800196) (xy 212.348803 -303.814518) (xy 212.330022 -303.822224)
			(xy 212.31987 -303.822608) (xy 210.92033 -303.822608) (xy 210.910211 -303.82205) (xy 210.8915 -303.814341)
			(xy 210.877144 -303.800077) (xy 210.869315 -303.781416) (xy 210.868768 -303.7713) (xy 204.827632 -303.7713)
			(xy 204.827179 -303.78145) (xy 204.819389 -303.800196) (xy 204.805003 -303.814518) (xy 204.786222 -303.822224)
			(xy 204.77607 -303.822608) (xy 203.37653 -303.822608) (xy 203.366411 -303.82205) (xy 203.3477 -303.814341)
			(xy 203.333344 -303.800077) (xy 203.325515 -303.781416) (xy 203.324968 -303.7713) (xy 197.283832 -303.7713)
			(xy 197.283379 -303.78145) (xy 197.275589 -303.800196) (xy 197.261203 -303.814518) (xy 197.242422 -303.822224)
			(xy 197.23227 -303.822608) (xy 195.83273 -303.822608) (xy 195.822611 -303.82205) (xy 195.8039 -303.814341)
			(xy 195.789544 -303.800077) (xy 195.781715 -303.781416) (xy 195.781168 -303.7713) (xy 189.740032 -303.7713)
			(xy 189.739579 -303.78145) (xy 189.731789 -303.800196) (xy 189.717403 -303.814518) (xy 189.698622 -303.822224)
			(xy 189.68847 -303.822608) (xy 188.28893 -303.822608) (xy 188.278811 -303.82205) (xy 188.2601 -303.814341)
			(xy 188.245744 -303.800077) (xy 188.237915 -303.781416) (xy 188.237368 -303.7713) (xy 182.196232 -303.7713)
			(xy 182.195779 -303.78145) (xy 182.187989 -303.800196) (xy 182.173603 -303.814518) (xy 182.154822 -303.822224)
			(xy 182.14467 -303.822608) (xy 180.74513 -303.822608) (xy 180.735011 -303.82205) (xy 180.7163 -303.814341)
			(xy 180.701944 -303.800077) (xy 180.694115 -303.781416) (xy 180.693568 -303.7713) (xy 174.652432 -303.7713)
			(xy 174.651979 -303.78145) (xy 174.644189 -303.800196) (xy 174.629803 -303.814518) (xy 174.611022 -303.822224)
			(xy 174.60087 -303.822608) (xy 173.20133 -303.822608) (xy 173.191211 -303.82205) (xy 173.1725 -303.814341)
			(xy 173.158144 -303.800077) (xy 173.150315 -303.781416) (xy 173.149768 -303.7713) (xy 167.108632 -303.7713)
			(xy 167.108179 -303.78145) (xy 167.100389 -303.800196) (xy 167.086003 -303.814518) (xy 167.067222 -303.822224)
			(xy 167.05707 -303.822608) (xy 165.65753 -303.822608) (xy 165.647411 -303.82205) (xy 165.6287 -303.814341)
			(xy 165.614344 -303.800077) (xy 165.606515 -303.781416) (xy 165.605968 -303.7713) (xy 159.564832 -303.7713)
			(xy 159.564379 -303.78145) (xy 159.556589 -303.800196) (xy 159.542203 -303.814518) (xy 159.523422 -303.822224)
			(xy 159.51327 -303.822608) (xy 158.11373 -303.822608) (xy 158.103611 -303.82205) (xy 158.0849 -303.814341)
			(xy 158.070544 -303.800077) (xy 158.062715 -303.781416) (xy 158.062168 -303.7713) (xy 61.698632 -303.7713)
			(xy 61.698179 -303.78145) (xy 61.690389 -303.800196) (xy 61.676003 -303.814518) (xy 61.657222 -303.822224)
			(xy 61.64707 -303.822608) (xy 60.24753 -303.822608) (xy 60.237411 -303.82205) (xy 60.2187 -303.814341)
			(xy 60.204344 -303.800077) (xy 60.196515 -303.781416) (xy 60.195968 -303.7713) (xy 54.154832 -303.7713)
			(xy 54.154379 -303.78145) (xy 54.146589 -303.800196) (xy 54.132203 -303.814518) (xy 54.113422 -303.822224)
			(xy 54.10327 -303.822608) (xy 52.70373 -303.822608) (xy 52.693611 -303.82205) (xy 52.6749 -303.814341)
			(xy 52.660544 -303.800077) (xy 52.652715 -303.781416) (xy 52.652168 -303.7713) (xy 46.611032 -303.7713)
			(xy 46.610579 -303.78145) (xy 46.602789 -303.800196) (xy 46.588403 -303.814518) (xy 46.569622 -303.822224)
			(xy 46.55947 -303.822608) (xy 45.15993 -303.822608) (xy 45.149811 -303.82205) (xy 45.1311 -303.814341)
			(xy 45.116744 -303.800077) (xy 45.108915 -303.781416) (xy 45.108368 -303.7713) (xy 39.067232 -303.7713)
			(xy 39.066779 -303.78145) (xy 39.058989 -303.800196) (xy 39.044603 -303.814518) (xy 39.025822 -303.822224)
			(xy 39.01567 -303.822608) (xy 37.61613 -303.822608) (xy 37.606011 -303.82205) (xy 37.5873 -303.814341)
			(xy 37.572944 -303.800077) (xy 37.565115 -303.781416) (xy 37.564568 -303.7713) (xy 31.523432 -303.7713)
			(xy 31.522979 -303.78145) (xy 31.515189 -303.800196) (xy 31.500803 -303.814518) (xy 31.482022 -303.822224)
			(xy 31.47187 -303.822608) (xy 30.07233 -303.822608) (xy 30.062211 -303.82205) (xy 30.0435 -303.814341)
			(xy 30.029144 -303.800077) (xy 30.021315 -303.781416) (xy 30.020768 -303.7713) (xy 23.979632 -303.7713)
			(xy 23.979179 -303.78145) (xy 23.971389 -303.800196) (xy 23.957003 -303.814518) (xy 23.938222 -303.822224)
			(xy 23.92807 -303.822608) (xy 22.52853 -303.822608) (xy 22.518411 -303.82205) (xy 22.4997 -303.814341)
			(xy 22.485344 -303.800077) (xy 22.477515 -303.781416) (xy 22.476968 -303.7713) (xy 16.435832 -303.7713)
			(xy 16.435379 -303.78145) (xy 16.427589 -303.800196) (xy 16.413203 -303.814518) (xy 16.394422 -303.822224)
			(xy 16.38427 -303.822608) (xy 14.98473 -303.822608) (xy 14.974611 -303.82205) (xy 14.9559 -303.814341)
			(xy 14.941544 -303.800077) (xy 14.933715 -303.781416) (xy 14.933168 -303.7713) (xy 8.892032 -303.7713)
			(xy 8.891579 -303.78145) (xy 8.883789 -303.800196) (xy 8.869403 -303.814518) (xy 8.850622 -303.822224)
			(xy 8.84047 -303.822608) (xy 7.44093 -303.822608) (xy 7.430811 -303.82205) (xy 7.4121 -303.814341)
			(xy 7.397744 -303.800077) (xy 7.389915 -303.781416) (xy 7.389368 -303.7713) (xy 2.509012 -303.7713)
			(xy 2.509012 -304.621438) (xy 11.489436 -304.621438) (xy 11.489436 -304.212498) (xy 11.489932 -304.20234)
			(xy 11.497706 -304.183572) (xy 11.512072 -304.169206) (xy 11.53084 -304.161432) (xy 11.540998 -304.160936)
			(xy 12.940538 -304.160936) (xy 12.950698 -304.161402) (xy 12.969468 -304.169189) (xy 12.983831 -304.183563)
			(xy 12.991605 -304.202338) (xy 12.9921 -304.212498) (xy 12.9921 -304.621438) (xy 19.033236 -304.621438)
			(xy 19.033236 -304.212498) (xy 19.033732 -304.20234) (xy 19.041506 -304.183572) (xy 19.055872 -304.169206)
			(xy 19.07464 -304.161432) (xy 19.084798 -304.160936) (xy 20.484338 -304.160936) (xy 20.494498 -304.161402)
			(xy 20.513268 -304.169189) (xy 20.527631 -304.183563) (xy 20.535405 -304.202338) (xy 20.5359 -304.212498)
			(xy 20.5359 -304.621438) (xy 26.577036 -304.621438) (xy 26.577036 -304.212498) (xy 26.577532 -304.20234)
			(xy 26.585306 -304.183572) (xy 26.599672 -304.169206) (xy 26.61844 -304.161432) (xy 26.628598 -304.160936)
			(xy 28.028138 -304.160936) (xy 28.038298 -304.161402) (xy 28.057068 -304.169189) (xy 28.071431 -304.183563)
			(xy 28.079205 -304.202338) (xy 28.0797 -304.212498) (xy 28.0797 -304.621438) (xy 34.120836 -304.621438)
			(xy 34.120836 -304.212498) (xy 34.121332 -304.20234) (xy 34.129106 -304.183572) (xy 34.143472 -304.169206)
			(xy 34.16224 -304.161432) (xy 34.172398 -304.160936) (xy 35.571938 -304.160936) (xy 35.582098 -304.161402)
			(xy 35.600868 -304.169189) (xy 35.615231 -304.183563) (xy 35.623005 -304.202338) (xy 35.6235 -304.212498)
			(xy 35.6235 -304.621438) (xy 41.664636 -304.621438) (xy 41.664636 -304.212498) (xy 41.665132 -304.20234)
			(xy 41.672906 -304.183572) (xy 41.687272 -304.169206) (xy 41.70604 -304.161432) (xy 41.716198 -304.160936)
			(xy 43.115738 -304.160936) (xy 43.125898 -304.161402) (xy 43.144668 -304.169189) (xy 43.159031 -304.183563)
			(xy 43.166805 -304.202338) (xy 43.1673 -304.212498) (xy 43.1673 -304.621438) (xy 49.208436 -304.621438)
			(xy 49.208436 -304.212498) (xy 49.208932 -304.20234) (xy 49.216706 -304.183572) (xy 49.231072 -304.169206)
			(xy 49.24984 -304.161432) (xy 49.259998 -304.160936) (xy 50.659538 -304.160936) (xy 50.669698 -304.161402)
			(xy 50.688468 -304.169189) (xy 50.702831 -304.183563) (xy 50.710605 -304.202338) (xy 50.7111 -304.212498)
			(xy 50.7111 -304.621438) (xy 56.752236 -304.621438) (xy 56.752236 -304.212498) (xy 56.752732 -304.20234)
			(xy 56.760506 -304.183572) (xy 56.774872 -304.169206) (xy 56.79364 -304.161432) (xy 56.803798 -304.160936)
			(xy 58.203338 -304.160936) (xy 58.213498 -304.161402) (xy 58.232268 -304.169189) (xy 58.246631 -304.183563)
			(xy 58.254405 -304.202338) (xy 58.2549 -304.212498) (xy 58.2549 -304.621438) (xy 64.296036 -304.621438)
			(xy 64.296036 -304.212498) (xy 64.296532 -304.20234) (xy 64.304306 -304.183572) (xy 64.318672 -304.169206)
			(xy 64.33744 -304.161432) (xy 64.347598 -304.160936) (xy 65.747138 -304.160936) (xy 65.757298 -304.161402)
			(xy 65.776068 -304.169189) (xy 65.790431 -304.183563) (xy 65.798205 -304.202338) (xy 65.7987 -304.212498)
			(xy 65.7987 -304.621438) (xy 162.162236 -304.621438) (xy 162.162236 -304.212498) (xy 162.162732 -304.20234)
			(xy 162.170506 -304.183572) (xy 162.184872 -304.169206) (xy 162.20364 -304.161432) (xy 162.213798 -304.160936)
			(xy 163.613338 -304.160936) (xy 163.623498 -304.161402) (xy 163.642268 -304.169189) (xy 163.656631 -304.183563)
			(xy 163.664405 -304.202338) (xy 163.6649 -304.212498) (xy 163.6649 -304.621438) (xy 169.706036 -304.621438)
			(xy 169.706036 -304.212498) (xy 169.706532 -304.20234) (xy 169.714306 -304.183572) (xy 169.728672 -304.169206)
			(xy 169.74744 -304.161432) (xy 169.757598 -304.160936) (xy 171.157138 -304.160936) (xy 171.167298 -304.161402)
			(xy 171.186068 -304.169189) (xy 171.200431 -304.183563) (xy 171.208205 -304.202338) (xy 171.2087 -304.212498)
			(xy 171.2087 -304.621438) (xy 177.249836 -304.621438) (xy 177.249836 -304.212498) (xy 177.250332 -304.20234)
			(xy 177.258106 -304.183572) (xy 177.272472 -304.169206) (xy 177.29124 -304.161432) (xy 177.301398 -304.160936)
			(xy 178.700938 -304.160936) (xy 178.711098 -304.161402) (xy 178.729868 -304.169189) (xy 178.744231 -304.183563)
			(xy 178.752005 -304.202338) (xy 178.7525 -304.212498) (xy 178.7525 -304.621438) (xy 184.793636 -304.621438)
			(xy 184.793636 -304.212498) (xy 184.794132 -304.20234) (xy 184.801906 -304.183572) (xy 184.816272 -304.169206)
			(xy 184.83504 -304.161432) (xy 184.845198 -304.160936) (xy 186.244738 -304.160936) (xy 186.254898 -304.161402)
			(xy 186.273668 -304.169189) (xy 186.288031 -304.183563) (xy 186.295805 -304.202338) (xy 186.2963 -304.212498)
			(xy 186.2963 -304.621438) (xy 192.337436 -304.621438) (xy 192.337436 -304.212498) (xy 192.337932 -304.20234)
			(xy 192.345706 -304.183572) (xy 192.360072 -304.169206) (xy 192.37884 -304.161432) (xy 192.388998 -304.160936)
			(xy 193.788538 -304.160936) (xy 193.798698 -304.161402) (xy 193.817468 -304.169189) (xy 193.831831 -304.183563)
			(xy 193.839605 -304.202338) (xy 193.8401 -304.212498) (xy 193.8401 -304.621438) (xy 199.881236 -304.621438)
			(xy 199.881236 -304.212498) (xy 199.881732 -304.20234) (xy 199.889506 -304.183572) (xy 199.903872 -304.169206)
			(xy 199.92264 -304.161432) (xy 199.932798 -304.160936) (xy 201.332338 -304.160936) (xy 201.342498 -304.161402)
			(xy 201.361268 -304.169189) (xy 201.375631 -304.183563) (xy 201.383405 -304.202338) (xy 201.3839 -304.212498)
			(xy 201.3839 -304.621438) (xy 207.425036 -304.621438) (xy 207.425036 -304.212498) (xy 207.425532 -304.20234)
			(xy 207.433306 -304.183572) (xy 207.447672 -304.169206) (xy 207.46644 -304.161432) (xy 207.476598 -304.160936)
			(xy 208.876138 -304.160936) (xy 208.886298 -304.161402) (xy 208.905068 -304.169189) (xy 208.919431 -304.183563)
			(xy 208.927205 -304.202338) (xy 208.9277 -304.212498) (xy 208.9277 -304.621438) (xy 214.968836 -304.621438)
			(xy 214.968836 -304.212498) (xy 214.969332 -304.20234) (xy 214.977106 -304.183572) (xy 214.991472 -304.169206)
			(xy 215.01024 -304.161432) (xy 215.020398 -304.160936) (xy 216.419938 -304.160936) (xy 216.430098 -304.161402)
			(xy 216.448868 -304.169189) (xy 216.463231 -304.183563) (xy 216.471005 -304.202338) (xy 216.4715 -304.212498)
			(xy 216.4715 -304.621438) (xy 259.429504 -304.621438) (xy 259.429504 -304.212498) (xy 259.430031 -304.202344)
			(xy 259.4378 -304.183582) (xy 259.452155 -304.169218) (xy 259.470913 -304.161437) (xy 259.481066 -304.160936)
			(xy 260.880606 -304.160936) (xy 260.890764 -304.161429) (xy 260.909533 -304.169205) (xy 260.923898 -304.183571)
			(xy 260.931672 -304.20234) (xy 260.932168 -304.212498) (xy 260.932168 -304.621438) (xy 266.973304 -304.621438)
			(xy 266.973304 -304.212498) (xy 266.973831 -304.202344) (xy 266.9816 -304.183582) (xy 266.995955 -304.169218)
			(xy 267.014713 -304.161437) (xy 267.024866 -304.160936) (xy 268.424406 -304.160936) (xy 268.434564 -304.161429)
			(xy 268.453333 -304.169205) (xy 268.467698 -304.183571) (xy 268.475472 -304.20234) (xy 268.475968 -304.212498)
			(xy 268.475968 -304.621438) (xy 274.517104 -304.621438) (xy 274.517104 -304.212498) (xy 274.517631 -304.202344)
			(xy 274.5254 -304.183582) (xy 274.539755 -304.169218) (xy 274.558513 -304.161437) (xy 274.568666 -304.160936)
			(xy 275.968206 -304.160936) (xy 275.978364 -304.161429) (xy 275.997133 -304.169205) (xy 276.011498 -304.183571)
			(xy 276.019272 -304.20234) (xy 276.019768 -304.212498) (xy 276.019768 -304.621438) (xy 282.060904 -304.621438)
			(xy 282.060904 -304.212498) (xy 282.061431 -304.202344) (xy 282.0692 -304.183582) (xy 282.083555 -304.169218)
			(xy 282.102313 -304.161437) (xy 282.112466 -304.160936) (xy 283.512006 -304.160936) (xy 283.522164 -304.161429)
			(xy 283.540933 -304.169205) (xy 283.555298 -304.183571) (xy 283.563072 -304.20234) (xy 283.563568 -304.212498)
			(xy 283.563568 -304.621438) (xy 289.604704 -304.621438) (xy 289.604704 -304.212498) (xy 289.605231 -304.202344)
			(xy 289.613 -304.183582) (xy 289.627355 -304.169218) (xy 289.646113 -304.161437) (xy 289.656266 -304.160936)
			(xy 291.055806 -304.160936) (xy 291.065964 -304.161429) (xy 291.084733 -304.169205) (xy 291.099098 -304.183571)
			(xy 291.106872 -304.20234) (xy 291.107368 -304.212498) (xy 291.107368 -304.621438) (xy 297.148504 -304.621438)
			(xy 297.148504 -304.212498) (xy 297.149031 -304.202344) (xy 297.1568 -304.183582) (xy 297.171155 -304.169218)
			(xy 297.189913 -304.161437) (xy 297.200066 -304.160936) (xy 298.599606 -304.160936) (xy 298.609764 -304.161429)
			(xy 298.628533 -304.169205) (xy 298.642898 -304.183571) (xy 298.650672 -304.20234) (xy 298.651168 -304.212498)
			(xy 298.651168 -304.621438) (xy 304.692304 -304.621438) (xy 304.692304 -304.212498) (xy 304.692831 -304.202344)
			(xy 304.7006 -304.183582) (xy 304.714955 -304.169218) (xy 304.733713 -304.161437) (xy 304.743866 -304.160936)
			(xy 306.143406 -304.160936) (xy 306.153564 -304.161429) (xy 306.172333 -304.169205) (xy 306.186698 -304.183571)
			(xy 306.194472 -304.20234) (xy 306.194968 -304.212498) (xy 306.194968 -304.621438) (xy 312.236104 -304.621438)
			(xy 312.236104 -304.212498) (xy 312.236631 -304.202344) (xy 312.2444 -304.183582) (xy 312.258755 -304.169218)
			(xy 312.277513 -304.161437) (xy 312.287666 -304.160936) (xy 313.687206 -304.160936) (xy 313.697364 -304.161429)
			(xy 313.716133 -304.169205) (xy 313.730498 -304.183571) (xy 313.738272 -304.20234) (xy 313.738768 -304.212498)
			(xy 313.738768 -304.621438) (xy 410.102304 -304.621438) (xy 410.102304 -304.212498) (xy 410.102831 -304.202344)
			(xy 410.1106 -304.183582) (xy 410.124955 -304.169218) (xy 410.143713 -304.161437) (xy 410.153866 -304.160936)
			(xy 411.553406 -304.160936) (xy 411.563564 -304.161429) (xy 411.582333 -304.169205) (xy 411.596698 -304.183571)
			(xy 411.604472 -304.20234) (xy 411.604968 -304.212498) (xy 411.604968 -304.621438) (xy 417.646104 -304.621438)
			(xy 417.646104 -304.212498) (xy 417.646631 -304.202344) (xy 417.6544 -304.183582) (xy 417.668755 -304.169218)
			(xy 417.687513 -304.161437) (xy 417.697666 -304.160936) (xy 419.097206 -304.160936) (xy 419.107364 -304.161429)
			(xy 419.126133 -304.169205) (xy 419.140498 -304.183571) (xy 419.148272 -304.20234) (xy 419.148768 -304.212498)
			(xy 419.148768 -304.621438) (xy 425.189904 -304.621438) (xy 425.189904 -304.212498) (xy 425.190431 -304.202344)
			(xy 425.1982 -304.183582) (xy 425.212555 -304.169218) (xy 425.231313 -304.161437) (xy 425.241466 -304.160936)
			(xy 426.641006 -304.160936) (xy 426.651164 -304.161429) (xy 426.669933 -304.169205) (xy 426.684298 -304.183571)
			(xy 426.692072 -304.20234) (xy 426.692568 -304.212498) (xy 426.692568 -304.621438) (xy 432.733704 -304.621438)
			(xy 432.733704 -304.212498) (xy 432.734231 -304.202344) (xy 432.742 -304.183582) (xy 432.756355 -304.169218)
			(xy 432.775113 -304.161437) (xy 432.785266 -304.160936) (xy 434.184806 -304.160936) (xy 434.194964 -304.161429)
			(xy 434.213733 -304.169205) (xy 434.228098 -304.183571) (xy 434.235872 -304.20234) (xy 434.236368 -304.212498)
			(xy 434.236368 -304.621438) (xy 440.277504 -304.621438) (xy 440.277504 -304.212498) (xy 440.278031 -304.202344)
			(xy 440.2858 -304.183582) (xy 440.300155 -304.169218) (xy 440.318913 -304.161437) (xy 440.329066 -304.160936)
			(xy 441.728606 -304.160936) (xy 441.738764 -304.161429) (xy 441.757533 -304.169205) (xy 441.771898 -304.183571)
			(xy 441.779672 -304.20234) (xy 441.780168 -304.212498) (xy 441.780168 -304.621438) (xy 447.821304 -304.621438)
			(xy 447.821304 -304.212498) (xy 447.821831 -304.202344) (xy 447.8296 -304.183582) (xy 447.843955 -304.169218)
			(xy 447.862713 -304.161437) (xy 447.872866 -304.160936) (xy 449.272406 -304.160936) (xy 449.282564 -304.161429)
			(xy 449.301333 -304.169205) (xy 449.315698 -304.183571) (xy 449.323472 -304.20234) (xy 449.323968 -304.212498)
			(xy 449.323968 -304.621438) (xy 455.365104 -304.621438) (xy 455.365104 -304.212498) (xy 455.365631 -304.202344)
			(xy 455.3734 -304.183582) (xy 455.387755 -304.169218) (xy 455.406513 -304.161437) (xy 455.416666 -304.160936)
			(xy 456.816206 -304.160936) (xy 456.826364 -304.161429) (xy 456.845133 -304.169205) (xy 456.859498 -304.183571)
			(xy 456.867272 -304.20234) (xy 456.867768 -304.212498) (xy 456.867768 -304.621438) (xy 462.908904 -304.621438)
			(xy 462.908904 -304.212498) (xy 462.909431 -304.202344) (xy 462.9172 -304.183582) (xy 462.931555 -304.169218)
			(xy 462.950313 -304.161437) (xy 462.960466 -304.160936) (xy 464.360006 -304.160936) (xy 464.370164 -304.161429)
			(xy 464.388933 -304.169205) (xy 464.403298 -304.183571) (xy 464.411072 -304.20234) (xy 464.411568 -304.212498)
			(xy 464.411568 -304.621438) (xy 464.411098 -304.631597) (xy 464.403312 -304.650366) (xy 464.388939 -304.66473)
			(xy 464.370166 -304.672504) (xy 464.360006 -304.673) (xy 462.960466 -304.673) (xy 462.950311 -304.672495)
			(xy 462.931548 -304.664717) (xy 462.917185 -304.650355) (xy 462.909405 -304.631593) (xy 462.908904 -304.621438)
			(xy 456.867768 -304.621438) (xy 456.867298 -304.631597) (xy 456.859512 -304.650366) (xy 456.845139 -304.66473)
			(xy 456.826366 -304.672504) (xy 456.816206 -304.673) (xy 455.416666 -304.673) (xy 455.406511 -304.672495)
			(xy 455.387748 -304.664717) (xy 455.373385 -304.650355) (xy 455.365605 -304.631593) (xy 455.365104 -304.621438)
			(xy 449.323968 -304.621438) (xy 449.323498 -304.631597) (xy 449.315712 -304.650366) (xy 449.301339 -304.66473)
			(xy 449.282566 -304.672504) (xy 449.272406 -304.673) (xy 447.872866 -304.673) (xy 447.862711 -304.672495)
			(xy 447.843948 -304.664717) (xy 447.829585 -304.650355) (xy 447.821805 -304.631593) (xy 447.821304 -304.621438)
			(xy 441.780168 -304.621438) (xy 441.779698 -304.631597) (xy 441.771912 -304.650366) (xy 441.757539 -304.66473)
			(xy 441.738766 -304.672504) (xy 441.728606 -304.673) (xy 440.329066 -304.673) (xy 440.318911 -304.672495)
			(xy 440.300148 -304.664717) (xy 440.285785 -304.650355) (xy 440.278005 -304.631593) (xy 440.277504 -304.621438)
			(xy 434.236368 -304.621438) (xy 434.235898 -304.631597) (xy 434.228112 -304.650366) (xy 434.213739 -304.66473)
			(xy 434.194966 -304.672504) (xy 434.184806 -304.673) (xy 432.785266 -304.673) (xy 432.775111 -304.672495)
			(xy 432.756348 -304.664717) (xy 432.741985 -304.650355) (xy 432.734205 -304.631593) (xy 432.733704 -304.621438)
			(xy 426.692568 -304.621438) (xy 426.692098 -304.631597) (xy 426.684312 -304.650366) (xy 426.669939 -304.66473)
			(xy 426.651166 -304.672504) (xy 426.641006 -304.673) (xy 425.241466 -304.673) (xy 425.231311 -304.672495)
			(xy 425.212548 -304.664717) (xy 425.198185 -304.650355) (xy 425.190405 -304.631593) (xy 425.189904 -304.621438)
			(xy 419.148768 -304.621438) (xy 419.148298 -304.631597) (xy 419.140512 -304.650366) (xy 419.126139 -304.66473)
			(xy 419.107366 -304.672504) (xy 419.097206 -304.673) (xy 417.697666 -304.673) (xy 417.687511 -304.672495)
			(xy 417.668748 -304.664717) (xy 417.654385 -304.650355) (xy 417.646605 -304.631593) (xy 417.646104 -304.621438)
			(xy 411.604968 -304.621438) (xy 411.604498 -304.631597) (xy 411.596712 -304.650366) (xy 411.582339 -304.66473)
			(xy 411.563566 -304.672504) (xy 411.553406 -304.673) (xy 410.153866 -304.673) (xy 410.143711 -304.672495)
			(xy 410.124948 -304.664717) (xy 410.110585 -304.650355) (xy 410.102805 -304.631593) (xy 410.102304 -304.621438)
			(xy 313.738768 -304.621438) (xy 313.738298 -304.631597) (xy 313.730512 -304.650366) (xy 313.716139 -304.66473)
			(xy 313.697366 -304.672504) (xy 313.687206 -304.673) (xy 312.287666 -304.673) (xy 312.277511 -304.672495)
			(xy 312.258748 -304.664717) (xy 312.244385 -304.650355) (xy 312.236605 -304.631593) (xy 312.236104 -304.621438)
			(xy 306.194968 -304.621438) (xy 306.194498 -304.631597) (xy 306.186712 -304.650366) (xy 306.172339 -304.66473)
			(xy 306.153566 -304.672504) (xy 306.143406 -304.673) (xy 304.743866 -304.673) (xy 304.733711 -304.672495)
			(xy 304.714948 -304.664717) (xy 304.700585 -304.650355) (xy 304.692805 -304.631593) (xy 304.692304 -304.621438)
			(xy 298.651168 -304.621438) (xy 298.650698 -304.631597) (xy 298.642912 -304.650366) (xy 298.628539 -304.66473)
			(xy 298.609766 -304.672504) (xy 298.599606 -304.673) (xy 297.200066 -304.673) (xy 297.189911 -304.672495)
			(xy 297.171148 -304.664717) (xy 297.156785 -304.650355) (xy 297.149005 -304.631593) (xy 297.148504 -304.621438)
			(xy 291.107368 -304.621438) (xy 291.106898 -304.631597) (xy 291.099112 -304.650366) (xy 291.084739 -304.66473)
			(xy 291.065966 -304.672504) (xy 291.055806 -304.673) (xy 289.656266 -304.673) (xy 289.646111 -304.672495)
			(xy 289.627348 -304.664717) (xy 289.612985 -304.650355) (xy 289.605205 -304.631593) (xy 289.604704 -304.621438)
			(xy 283.563568 -304.621438) (xy 283.563098 -304.631597) (xy 283.555312 -304.650366) (xy 283.540939 -304.66473)
			(xy 283.522166 -304.672504) (xy 283.512006 -304.673) (xy 282.112466 -304.673) (xy 282.102311 -304.672495)
			(xy 282.083548 -304.664717) (xy 282.069185 -304.650355) (xy 282.061405 -304.631593) (xy 282.060904 -304.621438)
			(xy 276.019768 -304.621438) (xy 276.019298 -304.631597) (xy 276.011512 -304.650366) (xy 275.997139 -304.66473)
			(xy 275.978366 -304.672504) (xy 275.968206 -304.673) (xy 274.568666 -304.673) (xy 274.558511 -304.672495)
			(xy 274.539748 -304.664717) (xy 274.525385 -304.650355) (xy 274.517605 -304.631593) (xy 274.517104 -304.621438)
			(xy 268.475968 -304.621438) (xy 268.475498 -304.631597) (xy 268.467712 -304.650366) (xy 268.453339 -304.66473)
			(xy 268.434566 -304.672504) (xy 268.424406 -304.673) (xy 267.024866 -304.673) (xy 267.014711 -304.672495)
			(xy 266.995948 -304.664717) (xy 266.981585 -304.650355) (xy 266.973805 -304.631593) (xy 266.973304 -304.621438)
			(xy 260.932168 -304.621438) (xy 260.931698 -304.631597) (xy 260.923912 -304.650366) (xy 260.909539 -304.66473)
			(xy 260.890766 -304.672504) (xy 260.880606 -304.673) (xy 259.481066 -304.673) (xy 259.470911 -304.672495)
			(xy 259.452148 -304.664717) (xy 259.437785 -304.650355) (xy 259.430005 -304.631593) (xy 259.429504 -304.621438)
			(xy 216.4715 -304.621438) (xy 216.470999 -304.631594) (xy 216.463219 -304.650356) (xy 216.448856 -304.664719)
			(xy 216.430094 -304.672499) (xy 216.419938 -304.673) (xy 215.020398 -304.673) (xy 215.010245 -304.672469)
			(xy 214.991483 -304.664701) (xy 214.977119 -304.650347) (xy 214.969338 -304.631591) (xy 214.968836 -304.621438)
			(xy 208.9277 -304.621438) (xy 208.927199 -304.631594) (xy 208.919419 -304.650356) (xy 208.905056 -304.664719)
			(xy 208.886294 -304.672499) (xy 208.876138 -304.673) (xy 207.476598 -304.673) (xy 207.466445 -304.672469)
			(xy 207.447683 -304.664701) (xy 207.433319 -304.650347) (xy 207.425538 -304.631591) (xy 207.425036 -304.621438)
			(xy 201.3839 -304.621438) (xy 201.383399 -304.631594) (xy 201.375619 -304.650356) (xy 201.361256 -304.664719)
			(xy 201.342494 -304.672499) (xy 201.332338 -304.673) (xy 199.932798 -304.673) (xy 199.922645 -304.672469)
			(xy 199.903883 -304.664701) (xy 199.889519 -304.650347) (xy 199.881738 -304.631591) (xy 199.881236 -304.621438)
			(xy 193.8401 -304.621438) (xy 193.839599 -304.631594) (xy 193.831819 -304.650356) (xy 193.817456 -304.664719)
			(xy 193.798694 -304.672499) (xy 193.788538 -304.673) (xy 192.388998 -304.673) (xy 192.378845 -304.672469)
			(xy 192.360083 -304.664701) (xy 192.345719 -304.650347) (xy 192.337938 -304.631591) (xy 192.337436 -304.621438)
			(xy 186.2963 -304.621438) (xy 186.295799 -304.631594) (xy 186.288019 -304.650356) (xy 186.273656 -304.664719)
			(xy 186.254894 -304.672499) (xy 186.244738 -304.673) (xy 184.845198 -304.673) (xy 184.835045 -304.672469)
			(xy 184.816283 -304.664701) (xy 184.801919 -304.650347) (xy 184.794138 -304.631591) (xy 184.793636 -304.621438)
			(xy 178.7525 -304.621438) (xy 178.751999 -304.631594) (xy 178.744219 -304.650356) (xy 178.729856 -304.664719)
			(xy 178.711094 -304.672499) (xy 178.700938 -304.673) (xy 177.301398 -304.673) (xy 177.291245 -304.672469)
			(xy 177.272483 -304.664701) (xy 177.258119 -304.650347) (xy 177.250338 -304.631591) (xy 177.249836 -304.621438)
			(xy 171.2087 -304.621438) (xy 171.208199 -304.631594) (xy 171.200419 -304.650356) (xy 171.186056 -304.664719)
			(xy 171.167294 -304.672499) (xy 171.157138 -304.673) (xy 169.757598 -304.673) (xy 169.747445 -304.672469)
			(xy 169.728683 -304.664701) (xy 169.714319 -304.650347) (xy 169.706538 -304.631591) (xy 169.706036 -304.621438)
			(xy 163.6649 -304.621438) (xy 163.664399 -304.631594) (xy 163.656619 -304.650356) (xy 163.642256 -304.664719)
			(xy 163.623494 -304.672499) (xy 163.613338 -304.673) (xy 162.213798 -304.673) (xy 162.203645 -304.672469)
			(xy 162.184883 -304.664701) (xy 162.170519 -304.650347) (xy 162.162738 -304.631591) (xy 162.162236 -304.621438)
			(xy 65.7987 -304.621438) (xy 65.798199 -304.631594) (xy 65.790419 -304.650356) (xy 65.776056 -304.664719)
			(xy 65.757294 -304.672499) (xy 65.747138 -304.673) (xy 64.347598 -304.673) (xy 64.337445 -304.672469)
			(xy 64.318683 -304.664701) (xy 64.304319 -304.650347) (xy 64.296538 -304.631591) (xy 64.296036 -304.621438)
			(xy 58.2549 -304.621438) (xy 58.254399 -304.631594) (xy 58.246619 -304.650356) (xy 58.232256 -304.664719)
			(xy 58.213494 -304.672499) (xy 58.203338 -304.673) (xy 56.803798 -304.673) (xy 56.793645 -304.672469)
			(xy 56.774883 -304.664701) (xy 56.760519 -304.650347) (xy 56.752738 -304.631591) (xy 56.752236 -304.621438)
			(xy 50.7111 -304.621438) (xy 50.710599 -304.631594) (xy 50.702819 -304.650356) (xy 50.688456 -304.664719)
			(xy 50.669694 -304.672499) (xy 50.659538 -304.673) (xy 49.259998 -304.673) (xy 49.249845 -304.672469)
			(xy 49.231083 -304.664701) (xy 49.216719 -304.650347) (xy 49.208938 -304.631591) (xy 49.208436 -304.621438)
			(xy 43.1673 -304.621438) (xy 43.166799 -304.631594) (xy 43.159019 -304.650356) (xy 43.144656 -304.664719)
			(xy 43.125894 -304.672499) (xy 43.115738 -304.673) (xy 41.716198 -304.673) (xy 41.706045 -304.672469)
			(xy 41.687283 -304.664701) (xy 41.672919 -304.650347) (xy 41.665138 -304.631591) (xy 41.664636 -304.621438)
			(xy 35.6235 -304.621438) (xy 35.622999 -304.631594) (xy 35.615219 -304.650356) (xy 35.600856 -304.664719)
			(xy 35.582094 -304.672499) (xy 35.571938 -304.673) (xy 34.172398 -304.673) (xy 34.162245 -304.672469)
			(xy 34.143483 -304.664701) (xy 34.129119 -304.650347) (xy 34.121338 -304.631591) (xy 34.120836 -304.621438)
			(xy 28.0797 -304.621438) (xy 28.079199 -304.631594) (xy 28.071419 -304.650356) (xy 28.057056 -304.664719)
			(xy 28.038294 -304.672499) (xy 28.028138 -304.673) (xy 26.628598 -304.673) (xy 26.618445 -304.672469)
			(xy 26.599683 -304.664701) (xy 26.585319 -304.650347) (xy 26.577538 -304.631591) (xy 26.577036 -304.621438)
			(xy 20.5359 -304.621438) (xy 20.535399 -304.631594) (xy 20.527619 -304.650356) (xy 20.513256 -304.664719)
			(xy 20.494494 -304.672499) (xy 20.484338 -304.673) (xy 19.084798 -304.673) (xy 19.074645 -304.672469)
			(xy 19.055883 -304.664701) (xy 19.041519 -304.650347) (xy 19.033738 -304.631591) (xy 19.033236 -304.621438)
			(xy 12.9921 -304.621438) (xy 12.991599 -304.631594) (xy 12.983819 -304.650356) (xy 12.969456 -304.664719)
			(xy 12.950694 -304.672499) (xy 12.940538 -304.673) (xy 11.540998 -304.673) (xy 11.530845 -304.672469)
			(xy 11.512083 -304.664701) (xy 11.497719 -304.650347) (xy 11.489938 -304.631591) (xy 11.489436 -304.621438)
			(xy 2.509012 -304.621438) (xy 2.509012 -305.471322) (xy 7.389368 -305.471322) (xy 7.389368 -305.062382)
			(xy 7.38975 -305.052206) (xy 7.397547 -305.033405) (xy 7.411945 -305.01902) (xy 7.430753 -305.011241)
			(xy 7.44093 -305.01082) (xy 8.84047 -305.01082) (xy 8.850637 -305.011288) (xy 8.869428 -305.01906)
			(xy 8.883813 -305.033432) (xy 8.891602 -305.052215) (xy 8.892032 -305.062382) (xy 8.892032 -305.471322)
			(xy 14.933168 -305.471322) (xy 14.933168 -305.062382) (xy 14.93355 -305.052206) (xy 14.941347 -305.033405)
			(xy 14.955745 -305.01902) (xy 14.974553 -305.011241) (xy 14.98473 -305.01082) (xy 16.38427 -305.01082)
			(xy 16.394437 -305.011288) (xy 16.413228 -305.01906) (xy 16.427613 -305.033432) (xy 16.435402 -305.052215)
			(xy 16.435832 -305.062382) (xy 16.435832 -305.471322) (xy 22.476968 -305.471322) (xy 22.476968 -305.062382)
			(xy 22.47735 -305.052206) (xy 22.485147 -305.033405) (xy 22.499545 -305.01902) (xy 22.518353 -305.011241)
			(xy 22.52853 -305.01082) (xy 23.92807 -305.01082) (xy 23.938237 -305.011288) (xy 23.957028 -305.01906)
			(xy 23.971413 -305.033432) (xy 23.979202 -305.052215) (xy 23.979632 -305.062382) (xy 23.979632 -305.471322)
			(xy 30.020768 -305.471322) (xy 30.020768 -305.062382) (xy 30.02115 -305.052206) (xy 30.028947 -305.033405)
			(xy 30.043345 -305.01902) (xy 30.062153 -305.011241) (xy 30.07233 -305.01082) (xy 31.47187 -305.01082)
			(xy 31.482037 -305.011288) (xy 31.500828 -305.01906) (xy 31.515213 -305.033432) (xy 31.523002 -305.052215)
			(xy 31.523432 -305.062382) (xy 31.523432 -305.471322) (xy 37.564568 -305.471322) (xy 37.564568 -305.062382)
			(xy 37.56495 -305.052206) (xy 37.572747 -305.033405) (xy 37.587145 -305.01902) (xy 37.605953 -305.011241)
			(xy 37.61613 -305.01082) (xy 39.01567 -305.01082) (xy 39.025837 -305.011288) (xy 39.044628 -305.01906)
			(xy 39.059013 -305.033432) (xy 39.066802 -305.052215) (xy 39.067232 -305.062382) (xy 39.067232 -305.471322)
			(xy 45.108368 -305.471322) (xy 45.108368 -305.062382) (xy 45.10875 -305.052206) (xy 45.116547 -305.033405)
			(xy 45.130945 -305.01902) (xy 45.149753 -305.011241) (xy 45.15993 -305.01082) (xy 46.55947 -305.01082)
			(xy 46.569637 -305.011288) (xy 46.588428 -305.01906) (xy 46.602813 -305.033432) (xy 46.610602 -305.052215)
			(xy 46.611032 -305.062382) (xy 46.611032 -305.471322) (xy 52.652168 -305.471322) (xy 52.652168 -305.062382)
			(xy 52.65255 -305.052206) (xy 52.660347 -305.033405) (xy 52.674745 -305.01902) (xy 52.693553 -305.011241)
			(xy 52.70373 -305.01082) (xy 54.10327 -305.01082) (xy 54.113437 -305.011288) (xy 54.132228 -305.01906)
			(xy 54.146613 -305.033432) (xy 54.154402 -305.052215) (xy 54.154832 -305.062382) (xy 54.154832 -305.471322)
			(xy 60.195968 -305.471322) (xy 60.195968 -305.062382) (xy 60.19635 -305.052206) (xy 60.204147 -305.033405)
			(xy 60.218545 -305.01902) (xy 60.237353 -305.011241) (xy 60.24753 -305.01082) (xy 61.64707 -305.01082)
			(xy 61.657237 -305.011288) (xy 61.676028 -305.01906) (xy 61.690413 -305.033432) (xy 61.698202 -305.052215)
			(xy 61.698632 -305.062382) (xy 61.698632 -305.471322) (xy 158.062168 -305.471322) (xy 158.062168 -305.062382)
			(xy 158.06255 -305.052206) (xy 158.070347 -305.033405) (xy 158.084745 -305.01902) (xy 158.103553 -305.011241)
			(xy 158.11373 -305.01082) (xy 159.51327 -305.01082) (xy 159.523437 -305.011288) (xy 159.542228 -305.01906)
			(xy 159.556613 -305.033432) (xy 159.564402 -305.052215) (xy 159.564832 -305.062382) (xy 159.564832 -305.471322)
			(xy 165.605968 -305.471322) (xy 165.605968 -305.062382) (xy 165.60635 -305.052206) (xy 165.614147 -305.033405)
			(xy 165.628545 -305.01902) (xy 165.647353 -305.011241) (xy 165.65753 -305.01082) (xy 167.05707 -305.01082)
			(xy 167.067237 -305.011288) (xy 167.086028 -305.01906) (xy 167.100413 -305.033432) (xy 167.108202 -305.052215)
			(xy 167.108632 -305.062382) (xy 167.108632 -305.471322) (xy 173.149768 -305.471322) (xy 173.149768 -305.062382)
			(xy 173.15015 -305.052206) (xy 173.157947 -305.033405) (xy 173.172345 -305.01902) (xy 173.191153 -305.011241)
			(xy 173.20133 -305.01082) (xy 174.60087 -305.01082) (xy 174.611037 -305.011288) (xy 174.629828 -305.01906)
			(xy 174.644213 -305.033432) (xy 174.652002 -305.052215) (xy 174.652432 -305.062382) (xy 174.652432 -305.471322)
			(xy 180.693568 -305.471322) (xy 180.693568 -305.062382) (xy 180.69395 -305.052206) (xy 180.701747 -305.033405)
			(xy 180.716145 -305.01902) (xy 180.734953 -305.011241) (xy 180.74513 -305.01082) (xy 182.14467 -305.01082)
			(xy 182.154837 -305.011288) (xy 182.173628 -305.01906) (xy 182.188013 -305.033432) (xy 182.195802 -305.052215)
			(xy 182.196232 -305.062382) (xy 182.196232 -305.471322) (xy 188.237368 -305.471322) (xy 188.237368 -305.062382)
			(xy 188.23775 -305.052206) (xy 188.245547 -305.033405) (xy 188.259945 -305.01902) (xy 188.278753 -305.011241)
			(xy 188.28893 -305.01082) (xy 189.68847 -305.01082) (xy 189.698637 -305.011288) (xy 189.717428 -305.01906)
			(xy 189.731813 -305.033432) (xy 189.739602 -305.052215) (xy 189.740032 -305.062382) (xy 189.740032 -305.471322)
			(xy 195.781168 -305.471322) (xy 195.781168 -305.062382) (xy 195.78155 -305.052206) (xy 195.789347 -305.033405)
			(xy 195.803745 -305.01902) (xy 195.822553 -305.011241) (xy 195.83273 -305.01082) (xy 197.23227 -305.01082)
			(xy 197.242437 -305.011288) (xy 197.261228 -305.01906) (xy 197.275613 -305.033432) (xy 197.283402 -305.052215)
			(xy 197.283832 -305.062382) (xy 197.283832 -305.471322) (xy 203.324968 -305.471322) (xy 203.324968 -305.062382)
			(xy 203.32535 -305.052206) (xy 203.333147 -305.033405) (xy 203.347545 -305.01902) (xy 203.366353 -305.011241)
			(xy 203.37653 -305.01082) (xy 204.77607 -305.01082) (xy 204.786237 -305.011288) (xy 204.805028 -305.01906)
			(xy 204.819413 -305.033432) (xy 204.827202 -305.052215) (xy 204.827632 -305.062382) (xy 204.827632 -305.471322)
			(xy 210.868768 -305.471322) (xy 210.868768 -305.062382) (xy 210.86915 -305.052206) (xy 210.876947 -305.033405)
			(xy 210.891345 -305.01902) (xy 210.910153 -305.011241) (xy 210.92033 -305.01082) (xy 212.31987 -305.01082)
			(xy 212.330037 -305.011288) (xy 212.348828 -305.01906) (xy 212.363213 -305.033432) (xy 212.371002 -305.052215)
			(xy 212.371432 -305.062382) (xy 212.371432 -305.471322) (xy 255.329436 -305.471322) (xy 255.329436 -305.062382)
			(xy 255.329918 -305.052223) (xy 255.337698 -305.033454) (xy 255.352067 -305.019089) (xy 255.370839 -305.011315)
			(xy 255.380998 -305.01082) (xy 256.780538 -305.01082) (xy 256.790696 -305.011302) (xy 256.809463 -305.019085)
			(xy 256.823826 -305.033454) (xy 256.831602 -305.052224) (xy 256.8321 -305.062382) (xy 256.8321 -305.471322)
			(xy 262.873236 -305.471322) (xy 262.873236 -305.062382) (xy 262.873718 -305.052223) (xy 262.881498 -305.033454)
			(xy 262.895867 -305.019089) (xy 262.914639 -305.011315) (xy 262.924798 -305.01082) (xy 264.324338 -305.01082)
			(xy 264.334496 -305.011302) (xy 264.353263 -305.019085) (xy 264.367626 -305.033454) (xy 264.375402 -305.052224)
			(xy 264.3759 -305.062382) (xy 264.3759 -305.471322) (xy 270.417036 -305.471322) (xy 270.417036 -305.062382)
			(xy 270.417518 -305.052223) (xy 270.425298 -305.033454) (xy 270.439667 -305.019089) (xy 270.458439 -305.011315)
			(xy 270.468598 -305.01082) (xy 271.868138 -305.01082) (xy 271.878296 -305.011302) (xy 271.897063 -305.019085)
			(xy 271.911426 -305.033454) (xy 271.919202 -305.052224) (xy 271.9197 -305.062382) (xy 271.9197 -305.471322)
			(xy 277.960836 -305.471322) (xy 277.960836 -305.062382) (xy 277.961318 -305.052223) (xy 277.969098 -305.033454)
			(xy 277.983467 -305.019089) (xy 278.002239 -305.011315) (xy 278.012398 -305.01082) (xy 279.411938 -305.01082)
			(xy 279.422096 -305.011302) (xy 279.440863 -305.019085) (xy 279.455226 -305.033454) (xy 279.463002 -305.052224)
			(xy 279.4635 -305.062382) (xy 279.4635 -305.471322) (xy 285.504636 -305.471322) (xy 285.504636 -305.062382)
			(xy 285.505118 -305.052223) (xy 285.512898 -305.033454) (xy 285.527267 -305.019089) (xy 285.546039 -305.011315)
			(xy 285.556198 -305.01082) (xy 286.955738 -305.01082) (xy 286.965896 -305.011302) (xy 286.984663 -305.019085)
			(xy 286.999026 -305.033454) (xy 287.006802 -305.052224) (xy 287.0073 -305.062382) (xy 287.0073 -305.471322)
			(xy 293.048436 -305.471322) (xy 293.048436 -305.062382) (xy 293.048918 -305.052223) (xy 293.056698 -305.033454)
			(xy 293.071067 -305.019089) (xy 293.089839 -305.011315) (xy 293.099998 -305.01082) (xy 294.499538 -305.01082)
			(xy 294.509696 -305.011302) (xy 294.528463 -305.019085) (xy 294.542826 -305.033454) (xy 294.550602 -305.052224)
			(xy 294.5511 -305.062382) (xy 294.5511 -305.471322) (xy 300.592236 -305.471322) (xy 300.592236 -305.062382)
			(xy 300.592718 -305.052223) (xy 300.600498 -305.033454) (xy 300.614867 -305.019089) (xy 300.633639 -305.011315)
			(xy 300.643798 -305.01082) (xy 302.043338 -305.01082) (xy 302.053496 -305.011302) (xy 302.072263 -305.019085)
			(xy 302.086626 -305.033454) (xy 302.094402 -305.052224) (xy 302.0949 -305.062382) (xy 302.0949 -305.471322)
			(xy 308.136036 -305.471322) (xy 308.136036 -305.062382) (xy 308.136518 -305.052223) (xy 308.144298 -305.033454)
			(xy 308.158667 -305.019089) (xy 308.177439 -305.011315) (xy 308.187598 -305.01082) (xy 309.587138 -305.01082)
			(xy 309.597296 -305.011302) (xy 309.616063 -305.019085) (xy 309.630426 -305.033454) (xy 309.638202 -305.052224)
			(xy 309.6387 -305.062382) (xy 309.6387 -305.471322) (xy 406.002236 -305.471322) (xy 406.002236 -305.062382)
			(xy 406.002718 -305.052223) (xy 406.010498 -305.033454) (xy 406.024867 -305.019089) (xy 406.043639 -305.011315)
			(xy 406.053798 -305.01082) (xy 407.453338 -305.01082) (xy 407.463496 -305.011302) (xy 407.482263 -305.019085)
			(xy 407.496626 -305.033454) (xy 407.504402 -305.052224) (xy 407.5049 -305.062382) (xy 407.5049 -305.471322)
			(xy 413.546036 -305.471322) (xy 413.546036 -305.062382) (xy 413.546518 -305.052223) (xy 413.554298 -305.033454)
			(xy 413.568667 -305.019089) (xy 413.587439 -305.011315) (xy 413.597598 -305.01082) (xy 414.997138 -305.01082)
			(xy 415.007296 -305.011302) (xy 415.026063 -305.019085) (xy 415.040426 -305.033454) (xy 415.048202 -305.052224)
			(xy 415.0487 -305.062382) (xy 415.0487 -305.471322) (xy 421.089836 -305.471322) (xy 421.089836 -305.062382)
			(xy 421.090318 -305.052223) (xy 421.098098 -305.033454) (xy 421.112467 -305.019089) (xy 421.131239 -305.011315)
			(xy 421.141398 -305.01082) (xy 422.540938 -305.01082) (xy 422.551096 -305.011302) (xy 422.569863 -305.019085)
			(xy 422.584226 -305.033454) (xy 422.592002 -305.052224) (xy 422.5925 -305.062382) (xy 422.5925 -305.471322)
			(xy 428.633636 -305.471322) (xy 428.633636 -305.062382) (xy 428.634118 -305.052223) (xy 428.641898 -305.033454)
			(xy 428.656267 -305.019089) (xy 428.675039 -305.011315) (xy 428.685198 -305.01082) (xy 430.084738 -305.01082)
			(xy 430.094896 -305.011302) (xy 430.113663 -305.019085) (xy 430.128026 -305.033454) (xy 430.135802 -305.052224)
			(xy 430.1363 -305.062382) (xy 430.1363 -305.471322) (xy 436.177436 -305.471322) (xy 436.177436 -305.062382)
			(xy 436.177918 -305.052223) (xy 436.185698 -305.033454) (xy 436.200067 -305.019089) (xy 436.218839 -305.011315)
			(xy 436.228998 -305.01082) (xy 437.628538 -305.01082) (xy 437.638696 -305.011302) (xy 437.657463 -305.019085)
			(xy 437.671826 -305.033454) (xy 437.679602 -305.052224) (xy 437.6801 -305.062382) (xy 437.6801 -305.471322)
			(xy 443.721236 -305.471322) (xy 443.721236 -305.062382) (xy 443.721718 -305.052223) (xy 443.729498 -305.033454)
			(xy 443.743867 -305.019089) (xy 443.762639 -305.011315) (xy 443.772798 -305.01082) (xy 445.172338 -305.01082)
			(xy 445.182496 -305.011302) (xy 445.201263 -305.019085) (xy 445.215626 -305.033454) (xy 445.223402 -305.052224)
			(xy 445.2239 -305.062382) (xy 445.2239 -305.471322) (xy 451.265036 -305.471322) (xy 451.265036 -305.062382)
			(xy 451.265518 -305.052223) (xy 451.273298 -305.033454) (xy 451.287667 -305.019089) (xy 451.306439 -305.011315)
			(xy 451.316598 -305.01082) (xy 452.716138 -305.01082) (xy 452.726296 -305.011302) (xy 452.745063 -305.019085)
			(xy 452.759426 -305.033454) (xy 452.767202 -305.052224) (xy 452.7677 -305.062382) (xy 452.7677 -305.471322)
			(xy 458.808836 -305.471322) (xy 458.808836 -305.062382) (xy 458.809318 -305.052223) (xy 458.817098 -305.033454)
			(xy 458.831467 -305.019089) (xy 458.850239 -305.011315) (xy 458.860398 -305.01082) (xy 460.259938 -305.01082)
			(xy 460.270096 -305.011302) (xy 460.288863 -305.019085) (xy 460.303226 -305.033454) (xy 460.311002 -305.052224)
			(xy 460.3115 -305.062382) (xy 460.3115 -305.471322) (xy 460.310986 -305.481477) (xy 460.303211 -305.500239)
			(xy 460.288852 -305.514602) (xy 460.270092 -305.522383) (xy 460.259938 -305.522884) (xy 458.860398 -305.522884)
			(xy 458.850243 -305.522369) (xy 458.831478 -305.514598) (xy 458.817113 -305.500239) (xy 458.809335 -305.481477)
			(xy 458.808836 -305.471322) (xy 452.7677 -305.471322) (xy 452.767186 -305.481477) (xy 452.759411 -305.500239)
			(xy 452.745052 -305.514602) (xy 452.726292 -305.522383) (xy 452.716138 -305.522884) (xy 451.316598 -305.522884)
			(xy 451.306443 -305.522369) (xy 451.287678 -305.514598) (xy 451.273313 -305.500239) (xy 451.265535 -305.481477)
			(xy 451.265036 -305.471322) (xy 445.2239 -305.471322) (xy 445.223386 -305.481477) (xy 445.215611 -305.500239)
			(xy 445.201252 -305.514602) (xy 445.182492 -305.522383) (xy 445.172338 -305.522884) (xy 443.772798 -305.522884)
			(xy 443.762643 -305.522369) (xy 443.743878 -305.514598) (xy 443.729513 -305.500239) (xy 443.721735 -305.481477)
			(xy 443.721236 -305.471322) (xy 437.6801 -305.471322) (xy 437.679586 -305.481477) (xy 437.671811 -305.500239)
			(xy 437.657452 -305.514602) (xy 437.638692 -305.522383) (xy 437.628538 -305.522884) (xy 436.228998 -305.522884)
			(xy 436.218843 -305.522369) (xy 436.200078 -305.514598) (xy 436.185713 -305.500239) (xy 436.177935 -305.481477)
			(xy 436.177436 -305.471322) (xy 430.1363 -305.471322) (xy 430.135786 -305.481477) (xy 430.128011 -305.500239)
			(xy 430.113652 -305.514602) (xy 430.094892 -305.522383) (xy 430.084738 -305.522884) (xy 428.685198 -305.522884)
			(xy 428.675043 -305.522369) (xy 428.656278 -305.514598) (xy 428.641913 -305.500239) (xy 428.634135 -305.481477)
			(xy 428.633636 -305.471322) (xy 422.5925 -305.471322) (xy 422.591986 -305.481477) (xy 422.584211 -305.500239)
			(xy 422.569852 -305.514602) (xy 422.551092 -305.522383) (xy 422.540938 -305.522884) (xy 421.141398 -305.522884)
			(xy 421.131243 -305.522369) (xy 421.112478 -305.514598) (xy 421.098113 -305.500239) (xy 421.090335 -305.481477)
			(xy 421.089836 -305.471322) (xy 415.0487 -305.471322) (xy 415.048186 -305.481477) (xy 415.040411 -305.500239)
			(xy 415.026052 -305.514602) (xy 415.007292 -305.522383) (xy 414.997138 -305.522884) (xy 413.597598 -305.522884)
			(xy 413.587443 -305.522369) (xy 413.568678 -305.514598) (xy 413.554313 -305.500239) (xy 413.546535 -305.481477)
			(xy 413.546036 -305.471322) (xy 407.5049 -305.471322) (xy 407.504386 -305.481477) (xy 407.496611 -305.500239)
			(xy 407.482252 -305.514602) (xy 407.463492 -305.522383) (xy 407.453338 -305.522884) (xy 406.053798 -305.522884)
			(xy 406.043643 -305.522369) (xy 406.024878 -305.514598) (xy 406.010513 -305.500239) (xy 406.002735 -305.481477)
			(xy 406.002236 -305.471322) (xy 309.6387 -305.471322) (xy 309.638186 -305.481477) (xy 309.630411 -305.500239)
			(xy 309.616052 -305.514602) (xy 309.597292 -305.522383) (xy 309.587138 -305.522884) (xy 308.187598 -305.522884)
			(xy 308.177443 -305.522369) (xy 308.158678 -305.514598) (xy 308.144313 -305.500239) (xy 308.136535 -305.481477)
			(xy 308.136036 -305.471322) (xy 302.0949 -305.471322) (xy 302.094386 -305.481477) (xy 302.086611 -305.500239)
			(xy 302.072252 -305.514602) (xy 302.053492 -305.522383) (xy 302.043338 -305.522884) (xy 300.643798 -305.522884)
			(xy 300.633643 -305.522369) (xy 300.614878 -305.514598) (xy 300.600513 -305.500239) (xy 300.592735 -305.481477)
			(xy 300.592236 -305.471322) (xy 294.5511 -305.471322) (xy 294.550586 -305.481477) (xy 294.542811 -305.500239)
			(xy 294.528452 -305.514602) (xy 294.509692 -305.522383) (xy 294.499538 -305.522884) (xy 293.099998 -305.522884)
			(xy 293.089843 -305.522369) (xy 293.071078 -305.514598) (xy 293.056713 -305.500239) (xy 293.048935 -305.481477)
			(xy 293.048436 -305.471322) (xy 287.0073 -305.471322) (xy 287.006786 -305.481477) (xy 286.999011 -305.500239)
			(xy 286.984652 -305.514602) (xy 286.965892 -305.522383) (xy 286.955738 -305.522884) (xy 285.556198 -305.522884)
			(xy 285.546043 -305.522369) (xy 285.527278 -305.514598) (xy 285.512913 -305.500239) (xy 285.505135 -305.481477)
			(xy 285.504636 -305.471322) (xy 279.4635 -305.471322) (xy 279.462986 -305.481477) (xy 279.455211 -305.500239)
			(xy 279.440852 -305.514602) (xy 279.422092 -305.522383) (xy 279.411938 -305.522884) (xy 278.012398 -305.522884)
			(xy 278.002243 -305.522369) (xy 277.983478 -305.514598) (xy 277.969113 -305.500239) (xy 277.961335 -305.481477)
			(xy 277.960836 -305.471322) (xy 271.9197 -305.471322) (xy 271.919186 -305.481477) (xy 271.911411 -305.500239)
			(xy 271.897052 -305.514602) (xy 271.878292 -305.522383) (xy 271.868138 -305.522884) (xy 270.468598 -305.522884)
			(xy 270.458443 -305.522369) (xy 270.439678 -305.514598) (xy 270.425313 -305.500239) (xy 270.417535 -305.481477)
			(xy 270.417036 -305.471322) (xy 264.3759 -305.471322) (xy 264.375386 -305.481477) (xy 264.367611 -305.500239)
			(xy 264.353252 -305.514602) (xy 264.334492 -305.522383) (xy 264.324338 -305.522884) (xy 262.924798 -305.522884)
			(xy 262.914643 -305.522369) (xy 262.895878 -305.514598) (xy 262.881513 -305.500239) (xy 262.873735 -305.481477)
			(xy 262.873236 -305.471322) (xy 256.8321 -305.471322) (xy 256.831586 -305.481477) (xy 256.823811 -305.500239)
			(xy 256.809452 -305.514602) (xy 256.790692 -305.522383) (xy 256.780538 -305.522884) (xy 255.380998 -305.522884)
			(xy 255.370843 -305.522369) (xy 255.352078 -305.514598) (xy 255.337713 -305.500239) (xy 255.329935 -305.481477)
			(xy 255.329436 -305.471322) (xy 212.371432 -305.471322) (xy 212.371053 -305.481499) (xy 212.363255 -305.5003)
			(xy 212.348856 -305.514685) (xy 212.330047 -305.522463) (xy 212.31987 -305.522884) (xy 210.92033 -305.522884)
			(xy 210.910163 -305.522412) (xy 210.891373 -305.514641) (xy 210.876988 -305.50027) (xy 210.869198 -305.481488)
			(xy 210.868768 -305.471322) (xy 204.827632 -305.471322) (xy 204.827253 -305.481499) (xy 204.819455 -305.5003)
			(xy 204.805056 -305.514685) (xy 204.786247 -305.522463) (xy 204.77607 -305.522884) (xy 203.37653 -305.522884)
			(xy 203.366363 -305.522412) (xy 203.347573 -305.514641) (xy 203.333188 -305.50027) (xy 203.325398 -305.481488)
			(xy 203.324968 -305.471322) (xy 197.283832 -305.471322) (xy 197.283453 -305.481499) (xy 197.275655 -305.5003)
			(xy 197.261256 -305.514685) (xy 197.242447 -305.522463) (xy 197.23227 -305.522884) (xy 195.83273 -305.522884)
			(xy 195.822563 -305.522412) (xy 195.803773 -305.514641) (xy 195.789388 -305.50027) (xy 195.781598 -305.481488)
			(xy 195.781168 -305.471322) (xy 189.740032 -305.471322) (xy 189.739653 -305.481499) (xy 189.731855 -305.5003)
			(xy 189.717456 -305.514685) (xy 189.698647 -305.522463) (xy 189.68847 -305.522884) (xy 188.28893 -305.522884)
			(xy 188.278763 -305.522412) (xy 188.259973 -305.514641) (xy 188.245588 -305.50027) (xy 188.237798 -305.481488)
			(xy 188.237368 -305.471322) (xy 182.196232 -305.471322) (xy 182.195853 -305.481499) (xy 182.188055 -305.5003)
			(xy 182.173656 -305.514685) (xy 182.154847 -305.522463) (xy 182.14467 -305.522884) (xy 180.74513 -305.522884)
			(xy 180.734963 -305.522412) (xy 180.716173 -305.514641) (xy 180.701788 -305.50027) (xy 180.693998 -305.481488)
			(xy 180.693568 -305.471322) (xy 174.652432 -305.471322) (xy 174.652053 -305.481499) (xy 174.644255 -305.5003)
			(xy 174.629856 -305.514685) (xy 174.611047 -305.522463) (xy 174.60087 -305.522884) (xy 173.20133 -305.522884)
			(xy 173.191163 -305.522412) (xy 173.172373 -305.514641) (xy 173.157988 -305.50027) (xy 173.150198 -305.481488)
			(xy 173.149768 -305.471322) (xy 167.108632 -305.471322) (xy 167.108253 -305.481499) (xy 167.100455 -305.5003)
			(xy 167.086056 -305.514685) (xy 167.067247 -305.522463) (xy 167.05707 -305.522884) (xy 165.65753 -305.522884)
			(xy 165.647363 -305.522412) (xy 165.628573 -305.514641) (xy 165.614188 -305.50027) (xy 165.606398 -305.481488)
			(xy 165.605968 -305.471322) (xy 159.564832 -305.471322) (xy 159.564453 -305.481499) (xy 159.556655 -305.5003)
			(xy 159.542256 -305.514685) (xy 159.523447 -305.522463) (xy 159.51327 -305.522884) (xy 158.11373 -305.522884)
			(xy 158.103563 -305.522412) (xy 158.084773 -305.514641) (xy 158.070388 -305.50027) (xy 158.062598 -305.481488)
			(xy 158.062168 -305.471322) (xy 61.698632 -305.471322) (xy 61.698253 -305.481499) (xy 61.690455 -305.5003)
			(xy 61.676056 -305.514685) (xy 61.657247 -305.522463) (xy 61.64707 -305.522884) (xy 60.24753 -305.522884)
			(xy 60.237363 -305.522412) (xy 60.218573 -305.514641) (xy 60.204188 -305.50027) (xy 60.196398 -305.481488)
			(xy 60.195968 -305.471322) (xy 54.154832 -305.471322) (xy 54.154453 -305.481499) (xy 54.146655 -305.5003)
			(xy 54.132256 -305.514685) (xy 54.113447 -305.522463) (xy 54.10327 -305.522884) (xy 52.70373 -305.522884)
			(xy 52.693563 -305.522412) (xy 52.674773 -305.514641) (xy 52.660388 -305.50027) (xy 52.652598 -305.481488)
			(xy 52.652168 -305.471322) (xy 46.611032 -305.471322) (xy 46.610653 -305.481499) (xy 46.602855 -305.5003)
			(xy 46.588456 -305.514685) (xy 46.569647 -305.522463) (xy 46.55947 -305.522884) (xy 45.15993 -305.522884)
			(xy 45.149763 -305.522412) (xy 45.130973 -305.514641) (xy 45.116588 -305.50027) (xy 45.108798 -305.481488)
			(xy 45.108368 -305.471322) (xy 39.067232 -305.471322) (xy 39.066853 -305.481499) (xy 39.059055 -305.5003)
			(xy 39.044656 -305.514685) (xy 39.025847 -305.522463) (xy 39.01567 -305.522884) (xy 37.61613 -305.522884)
			(xy 37.605963 -305.522412) (xy 37.587173 -305.514641) (xy 37.572788 -305.50027) (xy 37.564998 -305.481488)
			(xy 37.564568 -305.471322) (xy 31.523432 -305.471322) (xy 31.523053 -305.481499) (xy 31.515255 -305.5003)
			(xy 31.500856 -305.514685) (xy 31.482047 -305.522463) (xy 31.47187 -305.522884) (xy 30.07233 -305.522884)
			(xy 30.062163 -305.522412) (xy 30.043373 -305.514641) (xy 30.028988 -305.50027) (xy 30.021198 -305.481488)
			(xy 30.020768 -305.471322) (xy 23.979632 -305.471322) (xy 23.979253 -305.481499) (xy 23.971455 -305.5003)
			(xy 23.957056 -305.514685) (xy 23.938247 -305.522463) (xy 23.92807 -305.522884) (xy 22.52853 -305.522884)
			(xy 22.518363 -305.522412) (xy 22.499573 -305.514641) (xy 22.485188 -305.50027) (xy 22.477398 -305.481488)
			(xy 22.476968 -305.471322) (xy 16.435832 -305.471322) (xy 16.435453 -305.481499) (xy 16.427655 -305.5003)
			(xy 16.413256 -305.514685) (xy 16.394447 -305.522463) (xy 16.38427 -305.522884) (xy 14.98473 -305.522884)
			(xy 14.974563 -305.522412) (xy 14.955773 -305.514641) (xy 14.941388 -305.50027) (xy 14.933598 -305.481488)
			(xy 14.933168 -305.471322) (xy 8.892032 -305.471322) (xy 8.891653 -305.481499) (xy 8.883855 -305.5003)
			(xy 8.869456 -305.514685) (xy 8.850647 -305.522463) (xy 8.84047 -305.522884) (xy 7.44093 -305.522884)
			(xy 7.430763 -305.522412) (xy 7.411973 -305.514641) (xy 7.397588 -305.50027) (xy 7.389798 -305.481488)
			(xy 7.389368 -305.471322) (xy 2.509012 -305.471322) (xy 2.509012 -306.32146) (xy 11.489436 -306.32146)
			(xy 11.489436 -305.91252) (xy 11.489839 -305.902363) (xy 11.497634 -305.883604) (xy 11.512038 -305.869278)
			(xy 11.530838 -305.861584) (xy 11.540998 -305.861212) (xy 12.940538 -305.861212) (xy 12.950664 -305.861695)
			(xy 12.96938 -305.86943) (xy 12.983734 -305.883716) (xy 12.991557 -305.902397) (xy 12.9921 -305.91252)
			(xy 12.9921 -306.32146) (xy 19.033236 -306.32146) (xy 19.033236 -305.91252) (xy 19.033639 -305.902363)
			(xy 19.041434 -305.883604) (xy 19.055838 -305.869278) (xy 19.074638 -305.861584) (xy 19.084798 -305.861212)
			(xy 20.484338 -305.861212) (xy 20.494464 -305.861695) (xy 20.51318 -305.86943) (xy 20.527534 -305.883716)
			(xy 20.535357 -305.902397) (xy 20.5359 -305.91252) (xy 20.5359 -306.32146) (xy 26.577036 -306.32146)
			(xy 26.577036 -305.91252) (xy 26.577439 -305.902363) (xy 26.585234 -305.883604) (xy 26.599638 -305.869278)
			(xy 26.618438 -305.861584) (xy 26.628598 -305.861212) (xy 28.028138 -305.861212) (xy 28.038264 -305.861695)
			(xy 28.05698 -305.86943) (xy 28.071334 -305.883716) (xy 28.079157 -305.902397) (xy 28.0797 -305.91252)
			(xy 28.0797 -306.32146) (xy 34.120836 -306.32146) (xy 34.120836 -305.91252) (xy 34.121239 -305.902363)
			(xy 34.129034 -305.883604) (xy 34.143438 -305.869278) (xy 34.162238 -305.861584) (xy 34.172398 -305.861212)
			(xy 35.571938 -305.861212) (xy 35.582064 -305.861695) (xy 35.60078 -305.86943) (xy 35.615134 -305.883716)
			(xy 35.622957 -305.902397) (xy 35.6235 -305.91252) (xy 35.6235 -306.32146) (xy 41.664636 -306.32146)
			(xy 41.664636 -305.91252) (xy 41.665039 -305.902363) (xy 41.672834 -305.883604) (xy 41.687238 -305.869278)
			(xy 41.706038 -305.861584) (xy 41.716198 -305.861212) (xy 43.115738 -305.861212) (xy 43.125864 -305.861695)
			(xy 43.14458 -305.86943) (xy 43.158934 -305.883716) (xy 43.166757 -305.902397) (xy 43.1673 -305.91252)
			(xy 43.1673 -306.32146) (xy 49.208436 -306.32146) (xy 49.208436 -305.91252) (xy 49.208839 -305.902363)
			(xy 49.216634 -305.883604) (xy 49.231038 -305.869278) (xy 49.249838 -305.861584) (xy 49.259998 -305.861212)
			(xy 50.659538 -305.861212) (xy 50.669664 -305.861695) (xy 50.68838 -305.86943) (xy 50.702734 -305.883716)
			(xy 50.710557 -305.902397) (xy 50.7111 -305.91252) (xy 50.7111 -306.32146) (xy 56.752236 -306.32146)
			(xy 56.752236 -305.91252) (xy 56.752639 -305.902363) (xy 56.760434 -305.883604) (xy 56.774838 -305.869278)
			(xy 56.793638 -305.861584) (xy 56.803798 -305.861212) (xy 58.203338 -305.861212) (xy 58.213464 -305.861695)
			(xy 58.23218 -305.86943) (xy 58.246534 -305.883716) (xy 58.254357 -305.902397) (xy 58.2549 -305.91252)
			(xy 58.2549 -306.32146) (xy 64.296036 -306.32146) (xy 64.296036 -305.91252) (xy 64.296439 -305.902363)
			(xy 64.304234 -305.883604) (xy 64.318638 -305.869278) (xy 64.337438 -305.861584) (xy 64.347598 -305.861212)
			(xy 65.747138 -305.861212) (xy 65.757264 -305.861695) (xy 65.77598 -305.86943) (xy 65.790334 -305.883716)
			(xy 65.798157 -305.902397) (xy 65.7987 -305.91252) (xy 65.7987 -306.32146) (xy 162.162236 -306.32146)
			(xy 162.162236 -305.91252) (xy 162.162639 -305.902363) (xy 162.170434 -305.883604) (xy 162.184838 -305.869278)
			(xy 162.203638 -305.861584) (xy 162.213798 -305.861212) (xy 163.613338 -305.861212) (xy 163.623464 -305.861695)
			(xy 163.64218 -305.86943) (xy 163.656534 -305.883716) (xy 163.664357 -305.902397) (xy 163.6649 -305.91252)
			(xy 163.6649 -306.32146) (xy 169.706036 -306.32146) (xy 169.706036 -305.91252) (xy 169.706439 -305.902363)
			(xy 169.714234 -305.883604) (xy 169.728638 -305.869278) (xy 169.747438 -305.861584) (xy 169.757598 -305.861212)
			(xy 171.157138 -305.861212) (xy 171.167264 -305.861695) (xy 171.18598 -305.86943) (xy 171.200334 -305.883716)
			(xy 171.208157 -305.902397) (xy 171.2087 -305.91252) (xy 171.2087 -306.32146) (xy 177.249836 -306.32146)
			(xy 177.249836 -305.91252) (xy 177.250239 -305.902363) (xy 177.258034 -305.883604) (xy 177.272438 -305.869278)
			(xy 177.291238 -305.861584) (xy 177.301398 -305.861212) (xy 178.700938 -305.861212) (xy 178.711064 -305.861695)
			(xy 178.72978 -305.86943) (xy 178.744134 -305.883716) (xy 178.751957 -305.902397) (xy 178.7525 -305.91252)
			(xy 178.7525 -306.32146) (xy 184.793636 -306.32146) (xy 184.793636 -305.91252) (xy 184.794039 -305.902363)
			(xy 184.801834 -305.883604) (xy 184.816238 -305.869278) (xy 184.835038 -305.861584) (xy 184.845198 -305.861212)
			(xy 186.244738 -305.861212) (xy 186.254864 -305.861695) (xy 186.27358 -305.86943) (xy 186.287934 -305.883716)
			(xy 186.295757 -305.902397) (xy 186.2963 -305.91252) (xy 186.2963 -306.32146) (xy 192.337436 -306.32146)
			(xy 192.337436 -305.91252) (xy 192.337839 -305.902363) (xy 192.345634 -305.883604) (xy 192.360038 -305.869278)
			(xy 192.378838 -305.861584) (xy 192.388998 -305.861212) (xy 193.788538 -305.861212) (xy 193.798664 -305.861695)
			(xy 193.81738 -305.86943) (xy 193.831734 -305.883716) (xy 193.839557 -305.902397) (xy 193.8401 -305.91252)
			(xy 193.8401 -306.32146) (xy 199.881236 -306.32146) (xy 199.881236 -305.91252) (xy 199.881639 -305.902363)
			(xy 199.889434 -305.883604) (xy 199.903838 -305.869278) (xy 199.922638 -305.861584) (xy 199.932798 -305.861212)
			(xy 201.332338 -305.861212) (xy 201.342464 -305.861695) (xy 201.36118 -305.86943) (xy 201.375534 -305.883716)
			(xy 201.383357 -305.902397) (xy 201.3839 -305.91252) (xy 201.3839 -306.32146) (xy 207.425036 -306.32146)
			(xy 207.425036 -305.91252) (xy 207.425439 -305.902363) (xy 207.433234 -305.883604) (xy 207.447638 -305.869278)
			(xy 207.466438 -305.861584) (xy 207.476598 -305.861212) (xy 208.876138 -305.861212) (xy 208.886264 -305.861695)
			(xy 208.90498 -305.86943) (xy 208.919334 -305.883716) (xy 208.927157 -305.902397) (xy 208.9277 -305.91252)
			(xy 208.9277 -306.32146) (xy 214.968836 -306.32146) (xy 214.968836 -305.91252) (xy 214.969239 -305.902363)
			(xy 214.977034 -305.883604) (xy 214.991438 -305.869278) (xy 215.010238 -305.861584) (xy 215.020398 -305.861212)
			(xy 216.419938 -305.861212) (xy 216.430064 -305.861695) (xy 216.44878 -305.86943) (xy 216.463134 -305.883716)
			(xy 216.470957 -305.902397) (xy 216.4715 -305.91252) (xy 216.4715 -306.32146) (xy 259.429504 -306.32146)
			(xy 259.429504 -305.91252) (xy 259.429938 -305.902367) (xy 259.437728 -305.883614) (xy 259.452121 -305.86929)
			(xy 259.470911 -305.86159) (xy 259.481066 -305.861212) (xy 260.880606 -305.861212) (xy 260.89073 -305.861721)
			(xy 260.909446 -305.869446) (xy 260.923801 -305.883724) (xy 260.931624 -305.902399) (xy 260.932168 -305.91252)
			(xy 260.932168 -306.32146) (xy 266.973304 -306.32146) (xy 266.973304 -305.91252) (xy 266.973738 -305.902367)
			(xy 266.981528 -305.883614) (xy 266.995921 -305.86929) (xy 267.014711 -305.86159) (xy 267.024866 -305.861212)
			(xy 268.424406 -305.861212) (xy 268.43453 -305.861721) (xy 268.453246 -305.869446) (xy 268.467601 -305.883724)
			(xy 268.475424 -305.902399) (xy 268.475968 -305.91252) (xy 268.475968 -306.32146) (xy 274.517104 -306.32146)
			(xy 274.517104 -305.91252) (xy 274.517538 -305.902367) (xy 274.525328 -305.883614) (xy 274.539721 -305.86929)
			(xy 274.558511 -305.86159) (xy 274.568666 -305.861212) (xy 275.968206 -305.861212) (xy 275.97833 -305.861721)
			(xy 275.997046 -305.869446) (xy 276.011401 -305.883724) (xy 276.019224 -305.902399) (xy 276.019768 -305.91252)
			(xy 276.019768 -306.32146) (xy 282.060904 -306.32146) (xy 282.060904 -305.91252) (xy 282.061338 -305.902367)
			(xy 282.069128 -305.883614) (xy 282.083521 -305.86929) (xy 282.102311 -305.86159) (xy 282.112466 -305.861212)
			(xy 283.512006 -305.861212) (xy 283.52213 -305.861721) (xy 283.540846 -305.869446) (xy 283.555201 -305.883724)
			(xy 283.563024 -305.902399) (xy 283.563568 -305.91252) (xy 283.563568 -306.32146) (xy 289.604704 -306.32146)
			(xy 289.604704 -305.91252) (xy 289.605138 -305.902367) (xy 289.612928 -305.883614) (xy 289.627321 -305.86929)
			(xy 289.646111 -305.86159) (xy 289.656266 -305.861212) (xy 291.055806 -305.861212) (xy 291.06593 -305.861721)
			(xy 291.084646 -305.869446) (xy 291.099001 -305.883724) (xy 291.106824 -305.902399) (xy 291.107368 -305.91252)
			(xy 291.107368 -306.32146) (xy 297.148504 -306.32146) (xy 297.148504 -305.91252) (xy 297.148938 -305.902367)
			(xy 297.156728 -305.883614) (xy 297.171121 -305.86929) (xy 297.189911 -305.86159) (xy 297.200066 -305.861212)
			(xy 298.599606 -305.861212) (xy 298.60973 -305.861721) (xy 298.628446 -305.869446) (xy 298.642801 -305.883724)
			(xy 298.650624 -305.902399) (xy 298.651168 -305.91252) (xy 298.651168 -306.32146) (xy 304.692304 -306.32146)
			(xy 304.692304 -305.91252) (xy 304.692738 -305.902367) (xy 304.700528 -305.883614) (xy 304.714921 -305.86929)
			(xy 304.733711 -305.86159) (xy 304.743866 -305.861212) (xy 306.143406 -305.861212) (xy 306.15353 -305.861721)
			(xy 306.172246 -305.869446) (xy 306.186601 -305.883724) (xy 306.194424 -305.902399) (xy 306.194968 -305.91252)
			(xy 306.194968 -306.32146) (xy 312.236104 -306.32146) (xy 312.236104 -305.91252) (xy 312.236538 -305.902367)
			(xy 312.244328 -305.883614) (xy 312.258721 -305.86929) (xy 312.277511 -305.86159) (xy 312.287666 -305.861212)
			(xy 313.687206 -305.861212) (xy 313.69733 -305.861721) (xy 313.716046 -305.869446) (xy 313.730401 -305.883724)
			(xy 313.738224 -305.902399) (xy 313.738768 -305.91252) (xy 313.738768 -306.32146) (xy 410.102304 -306.32146)
			(xy 410.102304 -305.91252) (xy 410.102738 -305.902367) (xy 410.110528 -305.883614) (xy 410.124921 -305.86929)
			(xy 410.143711 -305.86159) (xy 410.153866 -305.861212) (xy 411.553406 -305.861212) (xy 411.56353 -305.861721)
			(xy 411.582246 -305.869446) (xy 411.596601 -305.883724) (xy 411.604424 -305.902399) (xy 411.604968 -305.91252)
			(xy 411.604968 -306.32146) (xy 417.646104 -306.32146) (xy 417.646104 -305.91252) (xy 417.646538 -305.902367)
			(xy 417.654328 -305.883614) (xy 417.668721 -305.86929) (xy 417.687511 -305.86159) (xy 417.697666 -305.861212)
			(xy 419.097206 -305.861212) (xy 419.10733 -305.861721) (xy 419.126046 -305.869446) (xy 419.140401 -305.883724)
			(xy 419.148224 -305.902399) (xy 419.148768 -305.91252) (xy 419.148768 -306.32146) (xy 425.189904 -306.32146)
			(xy 425.189904 -305.91252) (xy 425.190338 -305.902367) (xy 425.198128 -305.883614) (xy 425.212521 -305.86929)
			(xy 425.231311 -305.86159) (xy 425.241466 -305.861212) (xy 426.641006 -305.861212) (xy 426.65113 -305.861721)
			(xy 426.669846 -305.869446) (xy 426.684201 -305.883724) (xy 426.692024 -305.902399) (xy 426.692568 -305.91252)
			(xy 426.692568 -306.32146) (xy 432.733704 -306.32146) (xy 432.733704 -305.91252) (xy 432.734138 -305.902367)
			(xy 432.741928 -305.883614) (xy 432.756321 -305.86929) (xy 432.775111 -305.86159) (xy 432.785266 -305.861212)
			(xy 434.184806 -305.861212) (xy 434.19493 -305.861721) (xy 434.213646 -305.869446) (xy 434.228001 -305.883724)
			(xy 434.235824 -305.902399) (xy 434.236368 -305.91252) (xy 434.236368 -306.32146) (xy 440.277504 -306.32146)
			(xy 440.277504 -305.91252) (xy 440.277938 -305.902367) (xy 440.285728 -305.883614) (xy 440.300121 -305.86929)
			(xy 440.318911 -305.86159) (xy 440.329066 -305.861212) (xy 441.728606 -305.861212) (xy 441.73873 -305.861721)
			(xy 441.757446 -305.869446) (xy 441.771801 -305.883724) (xy 441.779624 -305.902399) (xy 441.780168 -305.91252)
			(xy 441.780168 -306.32146) (xy 447.821304 -306.32146) (xy 447.821304 -305.91252) (xy 447.821738 -305.902367)
			(xy 447.829528 -305.883614) (xy 447.843921 -305.86929) (xy 447.862711 -305.86159) (xy 447.872866 -305.861212)
			(xy 449.272406 -305.861212) (xy 449.28253 -305.861721) (xy 449.301246 -305.869446) (xy 449.315601 -305.883724)
			(xy 449.323424 -305.902399) (xy 449.323968 -305.91252) (xy 449.323968 -306.32146) (xy 455.365104 -306.32146)
			(xy 455.365104 -305.91252) (xy 455.365538 -305.902367) (xy 455.373328 -305.883614) (xy 455.387721 -305.86929)
			(xy 455.406511 -305.86159) (xy 455.416666 -305.861212) (xy 456.816206 -305.861212) (xy 456.82633 -305.861721)
			(xy 456.845046 -305.869446) (xy 456.859401 -305.883724) (xy 456.867224 -305.902399) (xy 456.867768 -305.91252)
			(xy 456.867768 -306.32146) (xy 462.908904 -306.32146) (xy 462.908904 -305.91252) (xy 462.909338 -305.902367)
			(xy 462.917128 -305.883614) (xy 462.931521 -305.86929) (xy 462.950311 -305.86159) (xy 462.960466 -305.861212)
			(xy 464.360006 -305.861212) (xy 464.37013 -305.861721) (xy 464.388846 -305.869446) (xy 464.403201 -305.883724)
			(xy 464.411024 -305.902399) (xy 464.411568 -305.91252) (xy 464.411568 -306.32146) (xy 464.411145 -306.331615)
			(xy 464.403357 -306.350373) (xy 464.388959 -306.364699) (xy 464.370163 -306.372394) (xy 464.360006 -306.372768)
			(xy 462.960466 -306.372768) (xy 462.950338 -306.372302) (xy 462.931618 -306.364564) (xy 462.917263 -306.350272)
			(xy 462.909443 -306.331586) (xy 462.908904 -306.32146) (xy 456.867768 -306.32146) (xy 456.867345 -306.331615)
			(xy 456.859557 -306.350373) (xy 456.845159 -306.364699) (xy 456.826363 -306.372394) (xy 456.816206 -306.372768)
			(xy 455.416666 -306.372768) (xy 455.406538 -306.372302) (xy 455.387818 -306.364564) (xy 455.373463 -306.350272)
			(xy 455.365643 -306.331586) (xy 455.365104 -306.32146) (xy 449.323968 -306.32146) (xy 449.323545 -306.331615)
			(xy 449.315757 -306.350373) (xy 449.301359 -306.364699) (xy 449.282563 -306.372394) (xy 449.272406 -306.372768)
			(xy 447.872866 -306.372768) (xy 447.862738 -306.372302) (xy 447.844018 -306.364564) (xy 447.829663 -306.350272)
			(xy 447.821843 -306.331586) (xy 447.821304 -306.32146) (xy 441.780168 -306.32146) (xy 441.779745 -306.331615)
			(xy 441.771957 -306.350373) (xy 441.757559 -306.364699) (xy 441.738763 -306.372394) (xy 441.728606 -306.372768)
			(xy 440.329066 -306.372768) (xy 440.318938 -306.372302) (xy 440.300218 -306.364564) (xy 440.285863 -306.350272)
			(xy 440.278043 -306.331586) (xy 440.277504 -306.32146) (xy 434.236368 -306.32146) (xy 434.235945 -306.331615)
			(xy 434.228157 -306.350373) (xy 434.213759 -306.364699) (xy 434.194963 -306.372394) (xy 434.184806 -306.372768)
			(xy 432.785266 -306.372768) (xy 432.775138 -306.372302) (xy 432.756418 -306.364564) (xy 432.742063 -306.350272)
			(xy 432.734243 -306.331586) (xy 432.733704 -306.32146) (xy 426.692568 -306.32146) (xy 426.692145 -306.331615)
			(xy 426.684357 -306.350373) (xy 426.669959 -306.364699) (xy 426.651163 -306.372394) (xy 426.641006 -306.372768)
			(xy 425.241466 -306.372768) (xy 425.231338 -306.372302) (xy 425.212618 -306.364564) (xy 425.198263 -306.350272)
			(xy 425.190443 -306.331586) (xy 425.189904 -306.32146) (xy 419.148768 -306.32146) (xy 419.148345 -306.331615)
			(xy 419.140557 -306.350373) (xy 419.126159 -306.364699) (xy 419.107363 -306.372394) (xy 419.097206 -306.372768)
			(xy 417.697666 -306.372768) (xy 417.687538 -306.372302) (xy 417.668818 -306.364564) (xy 417.654463 -306.350272)
			(xy 417.646643 -306.331586) (xy 417.646104 -306.32146) (xy 411.604968 -306.32146) (xy 411.604545 -306.331615)
			(xy 411.596757 -306.350373) (xy 411.582359 -306.364699) (xy 411.563563 -306.372394) (xy 411.553406 -306.372768)
			(xy 410.153866 -306.372768) (xy 410.143738 -306.372302) (xy 410.125018 -306.364564) (xy 410.110663 -306.350272)
			(xy 410.102843 -306.331586) (xy 410.102304 -306.32146) (xy 313.738768 -306.32146) (xy 313.738345 -306.331615)
			(xy 313.730557 -306.350373) (xy 313.716159 -306.364699) (xy 313.697363 -306.372394) (xy 313.687206 -306.372768)
			(xy 312.287666 -306.372768) (xy 312.277538 -306.372302) (xy 312.258818 -306.364564) (xy 312.244463 -306.350272)
			(xy 312.236643 -306.331586) (xy 312.236104 -306.32146) (xy 306.194968 -306.32146) (xy 306.194545 -306.331615)
			(xy 306.186757 -306.350373) (xy 306.172359 -306.364699) (xy 306.153563 -306.372394) (xy 306.143406 -306.372768)
			(xy 304.743866 -306.372768) (xy 304.733738 -306.372302) (xy 304.715018 -306.364564) (xy 304.700663 -306.350272)
			(xy 304.692843 -306.331586) (xy 304.692304 -306.32146) (xy 298.651168 -306.32146) (xy 298.650745 -306.331615)
			(xy 298.642957 -306.350373) (xy 298.628559 -306.364699) (xy 298.609763 -306.372394) (xy 298.599606 -306.372768)
			(xy 297.200066 -306.372768) (xy 297.189938 -306.372302) (xy 297.171218 -306.364564) (xy 297.156863 -306.350272)
			(xy 297.149043 -306.331586) (xy 297.148504 -306.32146) (xy 291.107368 -306.32146) (xy 291.106945 -306.331615)
			(xy 291.099157 -306.350373) (xy 291.084759 -306.364699) (xy 291.065963 -306.372394) (xy 291.055806 -306.372768)
			(xy 289.656266 -306.372768) (xy 289.646138 -306.372302) (xy 289.627418 -306.364564) (xy 289.613063 -306.350272)
			(xy 289.605243 -306.331586) (xy 289.604704 -306.32146) (xy 283.563568 -306.32146) (xy 283.563145 -306.331615)
			(xy 283.555357 -306.350373) (xy 283.540959 -306.364699) (xy 283.522163 -306.372394) (xy 283.512006 -306.372768)
			(xy 282.112466 -306.372768) (xy 282.102338 -306.372302) (xy 282.083618 -306.364564) (xy 282.069263 -306.350272)
			(xy 282.061443 -306.331586) (xy 282.060904 -306.32146) (xy 276.019768 -306.32146) (xy 276.019345 -306.331615)
			(xy 276.011557 -306.350373) (xy 275.997159 -306.364699) (xy 275.978363 -306.372394) (xy 275.968206 -306.372768)
			(xy 274.568666 -306.372768) (xy 274.558538 -306.372302) (xy 274.539818 -306.364564) (xy 274.525463 -306.350272)
			(xy 274.517643 -306.331586) (xy 274.517104 -306.32146) (xy 268.475968 -306.32146) (xy 268.475545 -306.331615)
			(xy 268.467757 -306.350373) (xy 268.453359 -306.364699) (xy 268.434563 -306.372394) (xy 268.424406 -306.372768)
			(xy 267.024866 -306.372768) (xy 267.014738 -306.372302) (xy 266.996018 -306.364564) (xy 266.981663 -306.350272)
			(xy 266.973843 -306.331586) (xy 266.973304 -306.32146) (xy 260.932168 -306.32146) (xy 260.931745 -306.331615)
			(xy 260.923957 -306.350373) (xy 260.909559 -306.364699) (xy 260.890763 -306.372394) (xy 260.880606 -306.372768)
			(xy 259.481066 -306.372768) (xy 259.470938 -306.372302) (xy 259.452218 -306.364564) (xy 259.437863 -306.350272)
			(xy 259.430043 -306.331586) (xy 259.429504 -306.32146) (xy 216.4715 -306.32146) (xy 216.471045 -306.331612)
			(xy 216.463263 -306.350363) (xy 216.448876 -306.364688) (xy 216.430091 -306.372389) (xy 216.419938 -306.372768)
			(xy 215.020398 -306.372768) (xy 215.010272 -306.372275) (xy 214.991553 -306.364548) (xy 214.977197 -306.350264)
			(xy 214.969376 -306.331583) (xy 214.968836 -306.32146) (xy 208.9277 -306.32146) (xy 208.927245 -306.331612)
			(xy 208.919463 -306.350363) (xy 208.905076 -306.364688) (xy 208.886291 -306.372389) (xy 208.876138 -306.372768)
			(xy 207.476598 -306.372768) (xy 207.466472 -306.372275) (xy 207.447753 -306.364548) (xy 207.433397 -306.350264)
			(xy 207.425576 -306.331583) (xy 207.425036 -306.32146) (xy 201.3839 -306.32146) (xy 201.383445 -306.331612)
			(xy 201.375663 -306.350363) (xy 201.361276 -306.364688) (xy 201.342491 -306.372389) (xy 201.332338 -306.372768)
			(xy 199.932798 -306.372768) (xy 199.922672 -306.372275) (xy 199.903953 -306.364548) (xy 199.889597 -306.350264)
			(xy 199.881776 -306.331583) (xy 199.881236 -306.32146) (xy 193.8401 -306.32146) (xy 193.839645 -306.331612)
			(xy 193.831863 -306.350363) (xy 193.817476 -306.364688) (xy 193.798691 -306.372389) (xy 193.788538 -306.372768)
			(xy 192.388998 -306.372768) (xy 192.378872 -306.372275) (xy 192.360153 -306.364548) (xy 192.345797 -306.350264)
			(xy 192.337976 -306.331583) (xy 192.337436 -306.32146) (xy 186.2963 -306.32146) (xy 186.295845 -306.331612)
			(xy 186.288063 -306.350363) (xy 186.273676 -306.364688) (xy 186.254891 -306.372389) (xy 186.244738 -306.372768)
			(xy 184.845198 -306.372768) (xy 184.835072 -306.372275) (xy 184.816353 -306.364548) (xy 184.801997 -306.350264)
			(xy 184.794176 -306.331583) (xy 184.793636 -306.32146) (xy 178.7525 -306.32146) (xy 178.752045 -306.331612)
			(xy 178.744263 -306.350363) (xy 178.729876 -306.364688) (xy 178.711091 -306.372389) (xy 178.700938 -306.372768)
			(xy 177.301398 -306.372768) (xy 177.291272 -306.372275) (xy 177.272553 -306.364548) (xy 177.258197 -306.350264)
			(xy 177.250376 -306.331583) (xy 177.249836 -306.32146) (xy 171.2087 -306.32146) (xy 171.208245 -306.331612)
			(xy 171.200463 -306.350363) (xy 171.186076 -306.364688) (xy 171.167291 -306.372389) (xy 171.157138 -306.372768)
			(xy 169.757598 -306.372768) (xy 169.747472 -306.372275) (xy 169.728753 -306.364548) (xy 169.714397 -306.350264)
			(xy 169.706576 -306.331583) (xy 169.706036 -306.32146) (xy 163.6649 -306.32146) (xy 163.664445 -306.331612)
			(xy 163.656663 -306.350363) (xy 163.642276 -306.364688) (xy 163.623491 -306.372389) (xy 163.613338 -306.372768)
			(xy 162.213798 -306.372768) (xy 162.203672 -306.372275) (xy 162.184953 -306.364548) (xy 162.170597 -306.350264)
			(xy 162.162776 -306.331583) (xy 162.162236 -306.32146) (xy 65.7987 -306.32146) (xy 65.798245 -306.331612)
			(xy 65.790463 -306.350363) (xy 65.776076 -306.364688) (xy 65.757291 -306.372389) (xy 65.747138 -306.372768)
			(xy 64.347598 -306.372768) (xy 64.337472 -306.372275) (xy 64.318753 -306.364548) (xy 64.304397 -306.350264)
			(xy 64.296576 -306.331583) (xy 64.296036 -306.32146) (xy 58.2549 -306.32146) (xy 58.254445 -306.331612)
			(xy 58.246663 -306.350363) (xy 58.232276 -306.364688) (xy 58.213491 -306.372389) (xy 58.203338 -306.372768)
			(xy 56.803798 -306.372768) (xy 56.793672 -306.372275) (xy 56.774953 -306.364548) (xy 56.760597 -306.350264)
			(xy 56.752776 -306.331583) (xy 56.752236 -306.32146) (xy 50.7111 -306.32146) (xy 50.710645 -306.331612)
			(xy 50.702863 -306.350363) (xy 50.688476 -306.364688) (xy 50.669691 -306.372389) (xy 50.659538 -306.372768)
			(xy 49.259998 -306.372768) (xy 49.249872 -306.372275) (xy 49.231153 -306.364548) (xy 49.216797 -306.350264)
			(xy 49.208976 -306.331583) (xy 49.208436 -306.32146) (xy 43.1673 -306.32146) (xy 43.166845 -306.331612)
			(xy 43.159063 -306.350363) (xy 43.144676 -306.364688) (xy 43.125891 -306.372389) (xy 43.115738 -306.372768)
			(xy 41.716198 -306.372768) (xy 41.706072 -306.372275) (xy 41.687353 -306.364548) (xy 41.672997 -306.350264)
			(xy 41.665176 -306.331583) (xy 41.664636 -306.32146) (xy 35.6235 -306.32146) (xy 35.623045 -306.331612)
			(xy 35.615263 -306.350363) (xy 35.600876 -306.364688) (xy 35.582091 -306.372389) (xy 35.571938 -306.372768)
			(xy 34.172398 -306.372768) (xy 34.162272 -306.372275) (xy 34.143553 -306.364548) (xy 34.129197 -306.350264)
			(xy 34.121376 -306.331583) (xy 34.120836 -306.32146) (xy 28.0797 -306.32146) (xy 28.079245 -306.331612)
			(xy 28.071463 -306.350363) (xy 28.057076 -306.364688) (xy 28.038291 -306.372389) (xy 28.028138 -306.372768)
			(xy 26.628598 -306.372768) (xy 26.618472 -306.372275) (xy 26.599753 -306.364548) (xy 26.585397 -306.350264)
			(xy 26.577576 -306.331583) (xy 26.577036 -306.32146) (xy 20.5359 -306.32146) (xy 20.535445 -306.331612)
			(xy 20.527663 -306.350363) (xy 20.513276 -306.364688) (xy 20.494491 -306.372389) (xy 20.484338 -306.372768)
			(xy 19.084798 -306.372768) (xy 19.074672 -306.372275) (xy 19.055953 -306.364548) (xy 19.041597 -306.350264)
			(xy 19.033776 -306.331583) (xy 19.033236 -306.32146) (xy 12.9921 -306.32146) (xy 12.991645 -306.331612)
			(xy 12.983863 -306.350363) (xy 12.969476 -306.364688) (xy 12.950691 -306.372389) (xy 12.940538 -306.372768)
			(xy 11.540998 -306.372768) (xy 11.530872 -306.372275) (xy 11.512153 -306.364548) (xy 11.497797 -306.350264)
			(xy 11.489976 -306.331583) (xy 11.489436 -306.32146) (xy 2.509012 -306.32146) (xy 2.509012 -307.171344)
			(xy 7.389368 -307.171344) (xy 7.389368 -306.762404) (xy 7.389824 -306.752254) (xy 7.397613 -306.733508)
			(xy 7.411998 -306.719186) (xy 7.430778 -306.71148) (xy 7.44093 -306.711096) (xy 8.84047 -306.711096)
			(xy 8.850589 -306.71165) (xy 8.869302 -306.719359) (xy 8.883657 -306.733625) (xy 8.891486 -306.752288)
			(xy 8.892032 -306.762404) (xy 8.892032 -307.171344) (xy 14.933168 -307.171344) (xy 14.933168 -306.762404)
			(xy 14.933624 -306.752254) (xy 14.941413 -306.733508) (xy 14.955798 -306.719186) (xy 14.974578 -306.71148)
			(xy 14.98473 -306.711096) (xy 16.38427 -306.711096) (xy 16.394389 -306.71165) (xy 16.413102 -306.719359)
			(xy 16.427457 -306.733625) (xy 16.435286 -306.752288) (xy 16.435832 -306.762404) (xy 16.435832 -307.171344)
			(xy 22.476968 -307.171344) (xy 22.476968 -306.762404) (xy 22.477424 -306.752254) (xy 22.485213 -306.733508)
			(xy 22.499598 -306.719186) (xy 22.518378 -306.71148) (xy 22.52853 -306.711096) (xy 23.92807 -306.711096)
			(xy 23.938189 -306.71165) (xy 23.956902 -306.719359) (xy 23.971257 -306.733625) (xy 23.979086 -306.752288)
			(xy 23.979632 -306.762404) (xy 23.979632 -307.171344) (xy 30.020768 -307.171344) (xy 30.020768 -306.762404)
			(xy 30.021224 -306.752254) (xy 30.029013 -306.733508) (xy 30.043398 -306.719186) (xy 30.062178 -306.71148)
			(xy 30.07233 -306.711096) (xy 31.47187 -306.711096) (xy 31.481989 -306.71165) (xy 31.500702 -306.719359)
			(xy 31.515057 -306.733625) (xy 31.522886 -306.752288) (xy 31.523432 -306.762404) (xy 31.523432 -307.171344)
			(xy 37.564568 -307.171344) (xy 37.564568 -306.762404) (xy 37.565024 -306.752254) (xy 37.572813 -306.733508)
			(xy 37.587198 -306.719186) (xy 37.605978 -306.71148) (xy 37.61613 -306.711096) (xy 39.01567 -306.711096)
			(xy 39.025789 -306.71165) (xy 39.044502 -306.719359) (xy 39.058857 -306.733625) (xy 39.066686 -306.752288)
			(xy 39.067232 -306.762404) (xy 39.067232 -307.171344) (xy 45.108368 -307.171344) (xy 45.108368 -306.762404)
			(xy 45.108824 -306.752254) (xy 45.116613 -306.733508) (xy 45.130998 -306.719186) (xy 45.149778 -306.71148)
			(xy 45.15993 -306.711096) (xy 46.55947 -306.711096) (xy 46.569589 -306.71165) (xy 46.588302 -306.719359)
			(xy 46.602657 -306.733625) (xy 46.610486 -306.752288) (xy 46.611032 -306.762404) (xy 46.611032 -307.171344)
			(xy 52.652168 -307.171344) (xy 52.652168 -306.762404) (xy 52.652624 -306.752254) (xy 52.660413 -306.733508)
			(xy 52.674798 -306.719186) (xy 52.693578 -306.71148) (xy 52.70373 -306.711096) (xy 54.10327 -306.711096)
			(xy 54.113389 -306.71165) (xy 54.132102 -306.719359) (xy 54.146457 -306.733625) (xy 54.154286 -306.752288)
			(xy 54.154832 -306.762404) (xy 54.154832 -307.171344) (xy 60.195968 -307.171344) (xy 60.195968 -306.762404)
			(xy 60.196424 -306.752254) (xy 60.204213 -306.733508) (xy 60.218598 -306.719186) (xy 60.237378 -306.71148)
			(xy 60.24753 -306.711096) (xy 61.64707 -306.711096) (xy 61.657189 -306.71165) (xy 61.675902 -306.719359)
			(xy 61.690257 -306.733625) (xy 61.698086 -306.752288) (xy 61.698632 -306.762404) (xy 61.698632 -307.171344)
			(xy 158.062168 -307.171344) (xy 158.062168 -306.762404) (xy 158.062624 -306.752254) (xy 158.070413 -306.733508)
			(xy 158.084798 -306.719186) (xy 158.103578 -306.71148) (xy 158.11373 -306.711096) (xy 159.51327 -306.711096)
			(xy 159.523389 -306.71165) (xy 159.542102 -306.719359) (xy 159.556457 -306.733625) (xy 159.564286 -306.752288)
			(xy 159.564832 -306.762404) (xy 159.564832 -307.171344) (xy 165.605968 -307.171344) (xy 165.605968 -306.762404)
			(xy 165.606424 -306.752254) (xy 165.614213 -306.733508) (xy 165.628598 -306.719186) (xy 165.647378 -306.71148)
			(xy 165.65753 -306.711096) (xy 167.05707 -306.711096) (xy 167.067189 -306.71165) (xy 167.085902 -306.719359)
			(xy 167.100257 -306.733625) (xy 167.108086 -306.752288) (xy 167.108632 -306.762404) (xy 167.108632 -307.171344)
			(xy 173.149768 -307.171344) (xy 173.149768 -306.762404) (xy 173.150224 -306.752254) (xy 173.158013 -306.733508)
			(xy 173.172398 -306.719186) (xy 173.191178 -306.71148) (xy 173.20133 -306.711096) (xy 174.60087 -306.711096)
			(xy 174.610989 -306.71165) (xy 174.629702 -306.719359) (xy 174.644057 -306.733625) (xy 174.651886 -306.752288)
			(xy 174.652432 -306.762404) (xy 174.652432 -307.171344) (xy 180.693568 -307.171344) (xy 180.693568 -306.762404)
			(xy 180.694024 -306.752254) (xy 180.701813 -306.733508) (xy 180.716198 -306.719186) (xy 180.734978 -306.71148)
			(xy 180.74513 -306.711096) (xy 182.14467 -306.711096) (xy 182.154789 -306.71165) (xy 182.173502 -306.719359)
			(xy 182.187857 -306.733625) (xy 182.195686 -306.752288) (xy 182.196232 -306.762404) (xy 182.196232 -307.171344)
			(xy 188.237368 -307.171344) (xy 188.237368 -306.762404) (xy 188.237824 -306.752254) (xy 188.245613 -306.733508)
			(xy 188.259998 -306.719186) (xy 188.278778 -306.71148) (xy 188.28893 -306.711096) (xy 189.68847 -306.711096)
			(xy 189.698589 -306.71165) (xy 189.717302 -306.719359) (xy 189.731657 -306.733625) (xy 189.739486 -306.752288)
			(xy 189.740032 -306.762404) (xy 189.740032 -307.171344) (xy 195.781168 -307.171344) (xy 195.781168 -306.762404)
			(xy 195.781624 -306.752254) (xy 195.789413 -306.733508) (xy 195.803798 -306.719186) (xy 195.822578 -306.71148)
			(xy 195.83273 -306.711096) (xy 197.23227 -306.711096) (xy 197.242389 -306.71165) (xy 197.261102 -306.719359)
			(xy 197.275457 -306.733625) (xy 197.283286 -306.752288) (xy 197.283832 -306.762404) (xy 197.283832 -307.171344)
			(xy 203.324968 -307.171344) (xy 203.324968 -306.762404) (xy 203.325424 -306.752254) (xy 203.333213 -306.733508)
			(xy 203.347598 -306.719186) (xy 203.366378 -306.71148) (xy 203.37653 -306.711096) (xy 204.77607 -306.711096)
			(xy 204.786189 -306.71165) (xy 204.804902 -306.719359) (xy 204.819257 -306.733625) (xy 204.827086 -306.752288)
			(xy 204.827632 -306.762404) (xy 204.827632 -307.171344) (xy 210.868768 -307.171344) (xy 210.868768 -306.762404)
			(xy 210.869224 -306.752254) (xy 210.877013 -306.733508) (xy 210.891398 -306.719186) (xy 210.910178 -306.71148)
			(xy 210.92033 -306.711096) (xy 212.31987 -306.711096) (xy 212.329989 -306.71165) (xy 212.348702 -306.719359)
			(xy 212.363057 -306.733625) (xy 212.370886 -306.752288) (xy 212.371432 -306.762404) (xy 212.371432 -307.171344)
			(xy 255.329436 -307.171344) (xy 255.329436 -306.762404) (xy 255.329826 -306.752246) (xy 255.337627 -306.733486)
			(xy 255.352034 -306.719162) (xy 255.370837 -306.711468) (xy 255.380998 -306.711096) (xy 256.780538 -306.711096)
			(xy 256.790662 -306.711594) (xy 256.809375 -306.719326) (xy 256.823729 -306.733608) (xy 256.831554 -306.752283)
			(xy 256.8321 -306.762404) (xy 256.8321 -307.171344) (xy 262.873236 -307.171344) (xy 262.873236 -306.762404)
			(xy 262.873626 -306.752246) (xy 262.881427 -306.733486) (xy 262.895834 -306.719162) (xy 262.914637 -306.711468)
			(xy 262.924798 -306.711096) (xy 264.324338 -306.711096) (xy 264.334462 -306.711594) (xy 264.353175 -306.719326)
			(xy 264.367529 -306.733608) (xy 264.375354 -306.752283) (xy 264.3759 -306.762404) (xy 264.3759 -307.171344)
			(xy 270.417036 -307.171344) (xy 270.417036 -306.762404) (xy 270.417426 -306.752246) (xy 270.425227 -306.733486)
			(xy 270.439634 -306.719162) (xy 270.458437 -306.711468) (xy 270.468598 -306.711096) (xy 271.868138 -306.711096)
			(xy 271.878262 -306.711594) (xy 271.896975 -306.719326) (xy 271.911329 -306.733608) (xy 271.919154 -306.752283)
			(xy 271.9197 -306.762404) (xy 271.9197 -307.171344) (xy 277.960836 -307.171344) (xy 277.960836 -306.762404)
			(xy 277.961226 -306.752246) (xy 277.969027 -306.733486) (xy 277.983434 -306.719162) (xy 278.002237 -306.711468)
			(xy 278.012398 -306.711096) (xy 279.411938 -306.711096) (xy 279.422062 -306.711594) (xy 279.440775 -306.719326)
			(xy 279.455129 -306.733608) (xy 279.462954 -306.752283) (xy 279.4635 -306.762404) (xy 279.4635 -307.171344)
			(xy 285.504636 -307.171344) (xy 285.504636 -306.762404) (xy 285.505026 -306.752246) (xy 285.512827 -306.733486)
			(xy 285.527234 -306.719162) (xy 285.546037 -306.711468) (xy 285.556198 -306.711096) (xy 286.955738 -306.711096)
			(xy 286.965862 -306.711594) (xy 286.984575 -306.719326) (xy 286.998929 -306.733608) (xy 287.006754 -306.752283)
			(xy 287.0073 -306.762404) (xy 287.0073 -307.171344) (xy 293.048436 -307.171344) (xy 293.048436 -306.762404)
			(xy 293.048826 -306.752246) (xy 293.056627 -306.733486) (xy 293.071034 -306.719162) (xy 293.089837 -306.711468)
			(xy 293.099998 -306.711096) (xy 294.499538 -306.711096) (xy 294.509662 -306.711594) (xy 294.528375 -306.719326)
			(xy 294.542729 -306.733608) (xy 294.550554 -306.752283) (xy 294.5511 -306.762404) (xy 294.5511 -307.171344)
			(xy 300.592236 -307.171344) (xy 300.592236 -306.762404) (xy 300.592626 -306.752246) (xy 300.600427 -306.733486)
			(xy 300.614834 -306.719162) (xy 300.633637 -306.711468) (xy 300.643798 -306.711096) (xy 302.043338 -306.711096)
			(xy 302.053462 -306.711594) (xy 302.072175 -306.719326) (xy 302.086529 -306.733608) (xy 302.094354 -306.752283)
			(xy 302.0949 -306.762404) (xy 302.0949 -307.171344) (xy 308.136036 -307.171344) (xy 308.136036 -306.762404)
			(xy 308.136426 -306.752246) (xy 308.144227 -306.733486) (xy 308.158634 -306.719162) (xy 308.177437 -306.711468)
			(xy 308.187598 -306.711096) (xy 309.587138 -306.711096) (xy 309.597262 -306.711594) (xy 309.615975 -306.719326)
			(xy 309.630329 -306.733608) (xy 309.638154 -306.752283) (xy 309.6387 -306.762404) (xy 309.6387 -307.171344)
			(xy 406.002236 -307.171344) (xy 406.002236 -306.762404) (xy 406.002626 -306.752246) (xy 406.010427 -306.733486)
			(xy 406.024834 -306.719162) (xy 406.043637 -306.711468) (xy 406.053798 -306.711096) (xy 407.453338 -306.711096)
			(xy 407.463462 -306.711594) (xy 407.482175 -306.719326) (xy 407.496529 -306.733608) (xy 407.504354 -306.752283)
			(xy 407.5049 -306.762404) (xy 407.5049 -307.171344) (xy 413.546036 -307.171344) (xy 413.546036 -306.762404)
			(xy 413.546426 -306.752246) (xy 413.554227 -306.733486) (xy 413.568634 -306.719162) (xy 413.587437 -306.711468)
			(xy 413.597598 -306.711096) (xy 414.997138 -306.711096) (xy 415.007262 -306.711594) (xy 415.025975 -306.719326)
			(xy 415.040329 -306.733608) (xy 415.048154 -306.752283) (xy 415.0487 -306.762404) (xy 415.0487 -307.171344)
			(xy 421.089836 -307.171344) (xy 421.089836 -306.762404) (xy 421.090226 -306.752246) (xy 421.098027 -306.733486)
			(xy 421.112434 -306.719162) (xy 421.131237 -306.711468) (xy 421.141398 -306.711096) (xy 422.540938 -306.711096)
			(xy 422.551062 -306.711594) (xy 422.569775 -306.719326) (xy 422.584129 -306.733608) (xy 422.591954 -306.752283)
			(xy 422.5925 -306.762404) (xy 422.5925 -307.171344) (xy 428.633636 -307.171344) (xy 428.633636 -306.762404)
			(xy 428.634026 -306.752246) (xy 428.641827 -306.733486) (xy 428.656234 -306.719162) (xy 428.675037 -306.711468)
			(xy 428.685198 -306.711096) (xy 430.084738 -306.711096) (xy 430.094862 -306.711594) (xy 430.113575 -306.719326)
			(xy 430.127929 -306.733608) (xy 430.135754 -306.752283) (xy 430.1363 -306.762404) (xy 430.1363 -307.171344)
			(xy 436.177436 -307.171344) (xy 436.177436 -306.762404) (xy 436.177826 -306.752246) (xy 436.185627 -306.733486)
			(xy 436.200034 -306.719162) (xy 436.218837 -306.711468) (xy 436.228998 -306.711096) (xy 437.628538 -306.711096)
			(xy 437.638662 -306.711594) (xy 437.657375 -306.719326) (xy 437.671729 -306.733608) (xy 437.679554 -306.752283)
			(xy 437.6801 -306.762404) (xy 437.6801 -307.171344) (xy 443.721236 -307.171344) (xy 443.721236 -306.762404)
			(xy 443.721626 -306.752246) (xy 443.729427 -306.733486) (xy 443.743834 -306.719162) (xy 443.762637 -306.711468)
			(xy 443.772798 -306.711096) (xy 445.172338 -306.711096) (xy 445.182462 -306.711594) (xy 445.201175 -306.719326)
			(xy 445.215529 -306.733608) (xy 445.223354 -306.752283) (xy 445.2239 -306.762404) (xy 445.2239 -307.171344)
			(xy 451.265036 -307.171344) (xy 451.265036 -306.762404) (xy 451.265426 -306.752246) (xy 451.273227 -306.733486)
			(xy 451.287634 -306.719162) (xy 451.306437 -306.711468) (xy 451.316598 -306.711096) (xy 452.716138 -306.711096)
			(xy 452.726262 -306.711594) (xy 452.744975 -306.719326) (xy 452.759329 -306.733608) (xy 452.767154 -306.752283)
			(xy 452.7677 -306.762404) (xy 452.7677 -307.171344) (xy 458.808836 -307.171344) (xy 458.808836 -306.762404)
			(xy 458.809226 -306.752246) (xy 458.817027 -306.733486) (xy 458.831434 -306.719162) (xy 458.850237 -306.711468)
			(xy 458.860398 -306.711096) (xy 460.259938 -306.711096) (xy 460.270062 -306.711594) (xy 460.288775 -306.719326)
			(xy 460.303129 -306.733608) (xy 460.310954 -306.752283) (xy 460.3115 -306.762404) (xy 460.3115 -307.171344)
			(xy 460.311114 -307.181501) (xy 460.303304 -307.200254) (xy 460.288897 -307.214576) (xy 460.270097 -307.222274)
			(xy 460.259938 -307.222652) (xy 458.860398 -307.222652) (xy 458.85027 -307.222175) (xy 458.831548 -307.214445)
			(xy 458.817191 -307.200156) (xy 458.809373 -307.181469) (xy 458.808836 -307.171344) (xy 452.7677 -307.171344)
			(xy 452.767314 -307.181501) (xy 452.759504 -307.200254) (xy 452.745097 -307.214576) (xy 452.726297 -307.222274)
			(xy 452.716138 -307.222652) (xy 451.316598 -307.222652) (xy 451.30647 -307.222175) (xy 451.287748 -307.214445)
			(xy 451.273391 -307.200156) (xy 451.265573 -307.181469) (xy 451.265036 -307.171344) (xy 445.2239 -307.171344)
			(xy 445.223514 -307.181501) (xy 445.215704 -307.200254) (xy 445.201297 -307.214576) (xy 445.182497 -307.222274)
			(xy 445.172338 -307.222652) (xy 443.772798 -307.222652) (xy 443.76267 -307.222175) (xy 443.743948 -307.214445)
			(xy 443.729591 -307.200156) (xy 443.721773 -307.181469) (xy 443.721236 -307.171344) (xy 437.6801 -307.171344)
			(xy 437.679714 -307.181501) (xy 437.671904 -307.200254) (xy 437.657497 -307.214576) (xy 437.638697 -307.222274)
			(xy 437.628538 -307.222652) (xy 436.228998 -307.222652) (xy 436.21887 -307.222175) (xy 436.200148 -307.214445)
			(xy 436.185791 -307.200156) (xy 436.177973 -307.181469) (xy 436.177436 -307.171344) (xy 430.1363 -307.171344)
			(xy 430.135914 -307.181501) (xy 430.128104 -307.200254) (xy 430.113697 -307.214576) (xy 430.094897 -307.222274)
			(xy 430.084738 -307.222652) (xy 428.685198 -307.222652) (xy 428.67507 -307.222175) (xy 428.656348 -307.214445)
			(xy 428.641991 -307.200156) (xy 428.634173 -307.181469) (xy 428.633636 -307.171344) (xy 422.5925 -307.171344)
			(xy 422.592114 -307.181501) (xy 422.584304 -307.200254) (xy 422.569897 -307.214576) (xy 422.551097 -307.222274)
			(xy 422.540938 -307.222652) (xy 421.141398 -307.222652) (xy 421.13127 -307.222175) (xy 421.112548 -307.214445)
			(xy 421.098191 -307.200156) (xy 421.090373 -307.181469) (xy 421.089836 -307.171344) (xy 415.0487 -307.171344)
			(xy 415.048314 -307.181501) (xy 415.040504 -307.200254) (xy 415.026097 -307.214576) (xy 415.007297 -307.222274)
			(xy 414.997138 -307.222652) (xy 413.597598 -307.222652) (xy 413.58747 -307.222175) (xy 413.568748 -307.214445)
			(xy 413.554391 -307.200156) (xy 413.546573 -307.181469) (xy 413.546036 -307.171344) (xy 407.5049 -307.171344)
			(xy 407.504514 -307.181501) (xy 407.496704 -307.200254) (xy 407.482297 -307.214576) (xy 407.463497 -307.222274)
			(xy 407.453338 -307.222652) (xy 406.053798 -307.222652) (xy 406.04367 -307.222175) (xy 406.024948 -307.214445)
			(xy 406.010591 -307.200156) (xy 406.002773 -307.181469) (xy 406.002236 -307.171344) (xy 309.6387 -307.171344)
			(xy 309.638314 -307.181501) (xy 309.630504 -307.200254) (xy 309.616097 -307.214576) (xy 309.597297 -307.222274)
			(xy 309.587138 -307.222652) (xy 308.187598 -307.222652) (xy 308.17747 -307.222175) (xy 308.158748 -307.214445)
			(xy 308.144391 -307.200156) (xy 308.136573 -307.181469) (xy 308.136036 -307.171344) (xy 302.0949 -307.171344)
			(xy 302.094514 -307.181501) (xy 302.086704 -307.200254) (xy 302.072297 -307.214576) (xy 302.053497 -307.222274)
			(xy 302.043338 -307.222652) (xy 300.643798 -307.222652) (xy 300.63367 -307.222175) (xy 300.614948 -307.214445)
			(xy 300.600591 -307.200156) (xy 300.592773 -307.181469) (xy 300.592236 -307.171344) (xy 294.5511 -307.171344)
			(xy 294.550714 -307.181501) (xy 294.542904 -307.200254) (xy 294.528497 -307.214576) (xy 294.509697 -307.222274)
			(xy 294.499538 -307.222652) (xy 293.099998 -307.222652) (xy 293.08987 -307.222175) (xy 293.071148 -307.214445)
			(xy 293.056791 -307.200156) (xy 293.048973 -307.181469) (xy 293.048436 -307.171344) (xy 287.0073 -307.171344)
			(xy 287.006914 -307.181501) (xy 286.999104 -307.200254) (xy 286.984697 -307.214576) (xy 286.965897 -307.222274)
			(xy 286.955738 -307.222652) (xy 285.556198 -307.222652) (xy 285.54607 -307.222175) (xy 285.527348 -307.214445)
			(xy 285.512991 -307.200156) (xy 285.505173 -307.181469) (xy 285.504636 -307.171344) (xy 279.4635 -307.171344)
			(xy 279.463114 -307.181501) (xy 279.455304 -307.200254) (xy 279.440897 -307.214576) (xy 279.422097 -307.222274)
			(xy 279.411938 -307.222652) (xy 278.012398 -307.222652) (xy 278.00227 -307.222175) (xy 277.983548 -307.214445)
			(xy 277.969191 -307.200156) (xy 277.961373 -307.181469) (xy 277.960836 -307.171344) (xy 271.9197 -307.171344)
			(xy 271.919314 -307.181501) (xy 271.911504 -307.200254) (xy 271.897097 -307.214576) (xy 271.878297 -307.222274)
			(xy 271.868138 -307.222652) (xy 270.468598 -307.222652) (xy 270.45847 -307.222175) (xy 270.439748 -307.214445)
			(xy 270.425391 -307.200156) (xy 270.417573 -307.181469) (xy 270.417036 -307.171344) (xy 264.3759 -307.171344)
			(xy 264.375514 -307.181501) (xy 264.367704 -307.200254) (xy 264.353297 -307.214576) (xy 264.334497 -307.222274)
			(xy 264.324338 -307.222652) (xy 262.924798 -307.222652) (xy 262.91467 -307.222175) (xy 262.895948 -307.214445)
			(xy 262.881591 -307.200156) (xy 262.873773 -307.181469) (xy 262.873236 -307.171344) (xy 256.8321 -307.171344)
			(xy 256.831714 -307.181501) (xy 256.823904 -307.200254) (xy 256.809497 -307.214576) (xy 256.790697 -307.222274)
			(xy 256.780538 -307.222652) (xy 255.380998 -307.222652) (xy 255.37087 -307.222175) (xy 255.352148 -307.214445)
			(xy 255.337791 -307.200156) (xy 255.329973 -307.181469) (xy 255.329436 -307.171344) (xy 212.371432 -307.171344)
			(xy 212.371015 -307.181497) (xy 212.363211 -307.200244) (xy 212.348814 -307.214565) (xy 212.330025 -307.222269)
			(xy 212.31987 -307.222652) (xy 210.92033 -307.222652) (xy 210.910204 -307.222149) (xy 210.891482 -307.214429)
			(xy 210.877124 -307.200148) (xy 210.869306 -307.181467) (xy 210.868768 -307.171344) (xy 204.827632 -307.171344)
			(xy 204.827215 -307.181497) (xy 204.819411 -307.200244) (xy 204.805014 -307.214565) (xy 204.786225 -307.222269)
			(xy 204.77607 -307.222652) (xy 203.37653 -307.222652) (xy 203.366404 -307.222149) (xy 203.347682 -307.214429)
			(xy 203.333324 -307.200148) (xy 203.325506 -307.181467) (xy 203.324968 -307.171344) (xy 197.283832 -307.171344)
			(xy 197.283415 -307.181497) (xy 197.275611 -307.200244) (xy 197.261214 -307.214565) (xy 197.242425 -307.222269)
			(xy 197.23227 -307.222652) (xy 195.83273 -307.222652) (xy 195.822604 -307.222149) (xy 195.803882 -307.214429)
			(xy 195.789524 -307.200148) (xy 195.781706 -307.181467) (xy 195.781168 -307.171344) (xy 189.740032 -307.171344)
			(xy 189.739615 -307.181497) (xy 189.731811 -307.200244) (xy 189.717414 -307.214565) (xy 189.698625 -307.222269)
			(xy 189.68847 -307.222652) (xy 188.28893 -307.222652) (xy 188.278804 -307.222149) (xy 188.260082 -307.214429)
			(xy 188.245724 -307.200148) (xy 188.237906 -307.181467) (xy 188.237368 -307.171344) (xy 182.196232 -307.171344)
			(xy 182.195815 -307.181497) (xy 182.188011 -307.200244) (xy 182.173614 -307.214565) (xy 182.154825 -307.222269)
			(xy 182.14467 -307.222652) (xy 180.74513 -307.222652) (xy 180.735004 -307.222149) (xy 180.716282 -307.214429)
			(xy 180.701924 -307.200148) (xy 180.694106 -307.181467) (xy 180.693568 -307.171344) (xy 174.652432 -307.171344)
			(xy 174.652015 -307.181497) (xy 174.644211 -307.200244) (xy 174.629814 -307.214565) (xy 174.611025 -307.222269)
			(xy 174.60087 -307.222652) (xy 173.20133 -307.222652) (xy 173.191204 -307.222149) (xy 173.172482 -307.214429)
			(xy 173.158124 -307.200148) (xy 173.150306 -307.181467) (xy 173.149768 -307.171344) (xy 167.108632 -307.171344)
			(xy 167.108215 -307.181497) (xy 167.100411 -307.200244) (xy 167.086014 -307.214565) (xy 167.067225 -307.222269)
			(xy 167.05707 -307.222652) (xy 165.65753 -307.222652) (xy 165.647404 -307.222149) (xy 165.628682 -307.214429)
			(xy 165.614324 -307.200148) (xy 165.606506 -307.181467) (xy 165.605968 -307.171344) (xy 159.564832 -307.171344)
			(xy 159.564415 -307.181497) (xy 159.556611 -307.200244) (xy 159.542214 -307.214565) (xy 159.523425 -307.222269)
			(xy 159.51327 -307.222652) (xy 158.11373 -307.222652) (xy 158.103604 -307.222149) (xy 158.084882 -307.214429)
			(xy 158.070524 -307.200148) (xy 158.062706 -307.181467) (xy 158.062168 -307.171344) (xy 61.698632 -307.171344)
			(xy 61.698215 -307.181497) (xy 61.690411 -307.200244) (xy 61.676014 -307.214565) (xy 61.657225 -307.222269)
			(xy 61.64707 -307.222652) (xy 60.24753 -307.222652) (xy 60.237404 -307.222149) (xy 60.218682 -307.214429)
			(xy 60.204324 -307.200148) (xy 60.196506 -307.181467) (xy 60.195968 -307.171344) (xy 54.154832 -307.171344)
			(xy 54.154415 -307.181497) (xy 54.146611 -307.200244) (xy 54.132214 -307.214565) (xy 54.113425 -307.222269)
			(xy 54.10327 -307.222652) (xy 52.70373 -307.222652) (xy 52.693604 -307.222149) (xy 52.674882 -307.214429)
			(xy 52.660524 -307.200148) (xy 52.652706 -307.181467) (xy 52.652168 -307.171344) (xy 46.611032 -307.171344)
			(xy 46.610615 -307.181497) (xy 46.602811 -307.200244) (xy 46.588414 -307.214565) (xy 46.569625 -307.222269)
			(xy 46.55947 -307.222652) (xy 45.15993 -307.222652) (xy 45.149804 -307.222149) (xy 45.131082 -307.214429)
			(xy 45.116724 -307.200148) (xy 45.108906 -307.181467) (xy 45.108368 -307.171344) (xy 39.067232 -307.171344)
			(xy 39.066815 -307.181497) (xy 39.059011 -307.200244) (xy 39.044614 -307.214565) (xy 39.025825 -307.222269)
			(xy 39.01567 -307.222652) (xy 37.61613 -307.222652) (xy 37.606004 -307.222149) (xy 37.587282 -307.214429)
			(xy 37.572924 -307.200148) (xy 37.565106 -307.181467) (xy 37.564568 -307.171344) (xy 31.523432 -307.171344)
			(xy 31.523015 -307.181497) (xy 31.515211 -307.200244) (xy 31.500814 -307.214565) (xy 31.482025 -307.222269)
			(xy 31.47187 -307.222652) (xy 30.07233 -307.222652) (xy 30.062204 -307.222149) (xy 30.043482 -307.214429)
			(xy 30.029124 -307.200148) (xy 30.021306 -307.181467) (xy 30.020768 -307.171344) (xy 23.979632 -307.171344)
			(xy 23.979215 -307.181497) (xy 23.971411 -307.200244) (xy 23.957014 -307.214565) (xy 23.938225 -307.222269)
			(xy 23.92807 -307.222652) (xy 22.52853 -307.222652) (xy 22.518404 -307.222149) (xy 22.499682 -307.214429)
			(xy 22.485324 -307.200148) (xy 22.477506 -307.181467) (xy 22.476968 -307.171344) (xy 16.435832 -307.171344)
			(xy 16.435415 -307.181497) (xy 16.427611 -307.200244) (xy 16.413214 -307.214565) (xy 16.394425 -307.222269)
			(xy 16.38427 -307.222652) (xy 14.98473 -307.222652) (xy 14.974604 -307.222149) (xy 14.955882 -307.214429)
			(xy 14.941524 -307.200148) (xy 14.933706 -307.181467) (xy 14.933168 -307.171344) (xy 8.892032 -307.171344)
			(xy 8.891615 -307.181497) (xy 8.883811 -307.200244) (xy 8.869414 -307.214565) (xy 8.850625 -307.222269)
			(xy 8.84047 -307.222652) (xy 7.44093 -307.222652) (xy 7.430804 -307.222149) (xy 7.412082 -307.214429)
			(xy 7.397724 -307.200148) (xy 7.389906 -307.181467) (xy 7.389368 -307.171344) (xy 2.509012 -307.171344)
			(xy 2.509012 -308.021482) (xy 11.489436 -308.021482) (xy 11.489436 -307.612542) (xy 11.489898 -307.602373)
			(xy 11.497669 -307.58358) (xy 11.512043 -307.569194) (xy 11.53083 -307.561407) (xy 11.540998 -307.56098)
			(xy 12.940538 -307.56098) (xy 12.950717 -307.561334) (xy 12.969521 -307.569139) (xy 12.983906 -307.583546)
			(xy 12.991682 -307.602362) (xy 12.9921 -307.612542) (xy 12.9921 -308.021482) (xy 19.033236 -308.021482)
			(xy 19.033236 -307.612542) (xy 19.033698 -307.602373) (xy 19.041469 -307.58358) (xy 19.055843 -307.569194)
			(xy 19.07463 -307.561407) (xy 19.084798 -307.56098) (xy 20.484338 -307.56098) (xy 20.494517 -307.561334)
			(xy 20.513321 -307.569139) (xy 20.527706 -307.583546) (xy 20.535482 -307.602362) (xy 20.5359 -307.612542)
			(xy 20.5359 -308.021482) (xy 26.577036 -308.021482) (xy 26.577036 -307.612542) (xy 26.577498 -307.602373)
			(xy 26.585269 -307.58358) (xy 26.599643 -307.569194) (xy 26.61843 -307.561407) (xy 26.628598 -307.56098)
			(xy 28.028138 -307.56098) (xy 28.038317 -307.561334) (xy 28.057121 -307.569139) (xy 28.071506 -307.583546)
			(xy 28.079282 -307.602362) (xy 28.0797 -307.612542) (xy 28.0797 -308.021482) (xy 34.120836 -308.021482)
			(xy 34.120836 -307.612542) (xy 34.121298 -307.602373) (xy 34.129069 -307.58358) (xy 34.143443 -307.569194)
			(xy 34.16223 -307.561407) (xy 34.172398 -307.56098) (xy 35.571938 -307.56098) (xy 35.582117 -307.561334)
			(xy 35.600921 -307.569139) (xy 35.615306 -307.583546) (xy 35.623082 -307.602362) (xy 35.6235 -307.612542)
			(xy 35.6235 -308.021482) (xy 41.664636 -308.021482) (xy 41.664636 -307.612542) (xy 41.665098 -307.602373)
			(xy 41.672869 -307.58358) (xy 41.687243 -307.569194) (xy 41.70603 -307.561407) (xy 41.716198 -307.56098)
			(xy 43.115738 -307.56098) (xy 43.125917 -307.561334) (xy 43.144721 -307.569139) (xy 43.159106 -307.583546)
			(xy 43.166882 -307.602362) (xy 43.1673 -307.612542) (xy 43.1673 -308.021482) (xy 49.208436 -308.021482)
			(xy 49.208436 -307.612542) (xy 49.208898 -307.602373) (xy 49.216669 -307.58358) (xy 49.231043 -307.569194)
			(xy 49.24983 -307.561407) (xy 49.259998 -307.56098) (xy 50.659538 -307.56098) (xy 50.669717 -307.561334)
			(xy 50.688521 -307.569139) (xy 50.702906 -307.583546) (xy 50.710682 -307.602362) (xy 50.7111 -307.612542)
			(xy 50.7111 -308.021482) (xy 56.752236 -308.021482) (xy 56.752236 -307.612542) (xy 56.752698 -307.602373)
			(xy 56.760469 -307.58358) (xy 56.774843 -307.569194) (xy 56.79363 -307.561407) (xy 56.803798 -307.56098)
			(xy 58.203338 -307.56098) (xy 58.213517 -307.561334) (xy 58.232321 -307.569139) (xy 58.246706 -307.583546)
			(xy 58.254482 -307.602362) (xy 58.2549 -307.612542) (xy 58.2549 -308.021482) (xy 64.296036 -308.021482)
			(xy 64.296036 -307.612542) (xy 64.296498 -307.602373) (xy 64.304269 -307.58358) (xy 64.318643 -307.569194)
			(xy 64.33743 -307.561407) (xy 64.347598 -307.56098) (xy 65.747138 -307.56098) (xy 65.757317 -307.561334)
			(xy 65.776121 -307.569139) (xy 65.790506 -307.583546) (xy 65.798282 -307.602362) (xy 65.7987 -307.612542)
			(xy 65.7987 -308.021482) (xy 162.162236 -308.021482) (xy 162.162236 -307.612542) (xy 162.162698 -307.602373)
			(xy 162.170469 -307.58358) (xy 162.184843 -307.569194) (xy 162.20363 -307.561407) (xy 162.213798 -307.56098)
			(xy 163.613338 -307.56098) (xy 163.623517 -307.561334) (xy 163.642321 -307.569139) (xy 163.656706 -307.583546)
			(xy 163.664482 -307.602362) (xy 163.6649 -307.612542) (xy 163.6649 -308.021482) (xy 169.706036 -308.021482)
			(xy 169.706036 -307.612542) (xy 169.706498 -307.602373) (xy 169.714269 -307.58358) (xy 169.728643 -307.569194)
			(xy 169.74743 -307.561407) (xy 169.757598 -307.56098) (xy 171.157138 -307.56098) (xy 171.167317 -307.561334)
			(xy 171.186121 -307.569139) (xy 171.200506 -307.583546) (xy 171.208282 -307.602362) (xy 171.2087 -307.612542)
			(xy 171.2087 -308.021482) (xy 177.249836 -308.021482) (xy 177.249836 -307.612542) (xy 177.250298 -307.602373)
			(xy 177.258069 -307.58358) (xy 177.272443 -307.569194) (xy 177.29123 -307.561407) (xy 177.301398 -307.56098)
			(xy 178.700938 -307.56098) (xy 178.711117 -307.561334) (xy 178.729921 -307.569139) (xy 178.744306 -307.583546)
			(xy 178.752082 -307.602362) (xy 178.7525 -307.612542) (xy 178.7525 -308.021482) (xy 184.793636 -308.021482)
			(xy 184.793636 -307.612542) (xy 184.794098 -307.602373) (xy 184.801869 -307.58358) (xy 184.816243 -307.569194)
			(xy 184.83503 -307.561407) (xy 184.845198 -307.56098) (xy 186.244738 -307.56098) (xy 186.254917 -307.561334)
			(xy 186.273721 -307.569139) (xy 186.288106 -307.583546) (xy 186.295882 -307.602362) (xy 186.2963 -307.612542)
			(xy 186.2963 -308.021482) (xy 192.337436 -308.021482) (xy 192.337436 -307.612542) (xy 192.337898 -307.602373)
			(xy 192.345669 -307.58358) (xy 192.360043 -307.569194) (xy 192.37883 -307.561407) (xy 192.388998 -307.56098)
			(xy 193.788538 -307.56098) (xy 193.798717 -307.561334) (xy 193.817521 -307.569139) (xy 193.831906 -307.583546)
			(xy 193.839682 -307.602362) (xy 193.8401 -307.612542) (xy 193.8401 -308.021482) (xy 199.881236 -308.021482)
			(xy 199.881236 -307.612542) (xy 199.881698 -307.602373) (xy 199.889469 -307.58358) (xy 199.903843 -307.569194)
			(xy 199.92263 -307.561407) (xy 199.932798 -307.56098) (xy 201.332338 -307.56098) (xy 201.342517 -307.561334)
			(xy 201.361321 -307.569139) (xy 201.375706 -307.583546) (xy 201.383482 -307.602362) (xy 201.3839 -307.612542)
			(xy 201.3839 -308.021482) (xy 207.425036 -308.021482) (xy 207.425036 -307.612542) (xy 207.425498 -307.602373)
			(xy 207.433269 -307.58358) (xy 207.447643 -307.569194) (xy 207.46643 -307.561407) (xy 207.476598 -307.56098)
			(xy 208.876138 -307.56098) (xy 208.886317 -307.561334) (xy 208.905121 -307.569139) (xy 208.919506 -307.583546)
			(xy 208.927282 -307.602362) (xy 208.9277 -307.612542) (xy 208.9277 -308.021482) (xy 214.968836 -308.021482)
			(xy 214.968836 -307.612542) (xy 214.969298 -307.602373) (xy 214.977069 -307.58358) (xy 214.991443 -307.569194)
			(xy 215.01023 -307.561407) (xy 215.020398 -307.56098) (xy 216.419938 -307.56098) (xy 216.430117 -307.561334)
			(xy 216.448921 -307.569139) (xy 216.463306 -307.583546) (xy 216.471082 -307.602362) (xy 216.4715 -307.612542)
			(xy 216.4715 -308.021482) (xy 259.429504 -308.021482) (xy 259.429504 -307.612542) (xy 259.429997 -307.602377)
			(xy 259.437762 -307.58359) (xy 259.452126 -307.569205) (xy 259.470902 -307.561412) (xy 259.481066 -307.56098)
			(xy 260.880606 -307.56098) (xy 260.890783 -307.56136) (xy 260.909586 -307.569155) (xy 260.923972 -307.583554)
			(xy 260.931749 -307.602364) (xy 260.932168 -307.612542) (xy 260.932168 -308.021482) (xy 266.973304 -308.021482)
			(xy 266.973304 -307.612542) (xy 266.973797 -307.602377) (xy 266.981562 -307.58359) (xy 266.995926 -307.569205)
			(xy 267.014702 -307.561412) (xy 267.024866 -307.56098) (xy 268.424406 -307.56098) (xy 268.434583 -307.56136)
			(xy 268.453386 -307.569155) (xy 268.467772 -307.583554) (xy 268.475549 -307.602364) (xy 268.475968 -307.612542)
			(xy 268.475968 -308.021482) (xy 274.517104 -308.021482) (xy 274.517104 -307.612542) (xy 274.517597 -307.602377)
			(xy 274.525362 -307.58359) (xy 274.539726 -307.569205) (xy 274.558502 -307.561412) (xy 274.568666 -307.56098)
			(xy 275.968206 -307.56098) (xy 275.978383 -307.56136) (xy 275.997186 -307.569155) (xy 276.011572 -307.583554)
			(xy 276.019349 -307.602364) (xy 276.019768 -307.612542) (xy 276.019768 -308.021482) (xy 282.060904 -308.021482)
			(xy 282.060904 -307.612542) (xy 282.061397 -307.602377) (xy 282.069162 -307.58359) (xy 282.083526 -307.569205)
			(xy 282.102302 -307.561412) (xy 282.112466 -307.56098) (xy 283.512006 -307.56098) (xy 283.522183 -307.56136)
			(xy 283.540986 -307.569155) (xy 283.555372 -307.583554) (xy 283.563149 -307.602364) (xy 283.563568 -307.612542)
			(xy 283.563568 -308.021482) (xy 289.604704 -308.021482) (xy 289.604704 -307.612542) (xy 289.605197 -307.602377)
			(xy 289.612962 -307.58359) (xy 289.627326 -307.569205) (xy 289.646102 -307.561412) (xy 289.656266 -307.56098)
			(xy 291.055806 -307.56098) (xy 291.065983 -307.56136) (xy 291.084786 -307.569155) (xy 291.099172 -307.583554)
			(xy 291.106949 -307.602364) (xy 291.107368 -307.612542) (xy 291.107368 -308.021482) (xy 297.148504 -308.021482)
			(xy 297.148504 -307.612542) (xy 297.148997 -307.602377) (xy 297.156762 -307.58359) (xy 297.171126 -307.569205)
			(xy 297.189902 -307.561412) (xy 297.200066 -307.56098) (xy 298.599606 -307.56098) (xy 298.609783 -307.56136)
			(xy 298.628586 -307.569155) (xy 298.642972 -307.583554) (xy 298.650749 -307.602364) (xy 298.651168 -307.612542)
			(xy 298.651168 -308.021482) (xy 304.692304 -308.021482) (xy 304.692304 -307.612542) (xy 304.692797 -307.602377)
			(xy 304.700562 -307.58359) (xy 304.714926 -307.569205) (xy 304.733702 -307.561412) (xy 304.743866 -307.56098)
			(xy 306.143406 -307.56098) (xy 306.153583 -307.56136) (xy 306.172386 -307.569155) (xy 306.186772 -307.583554)
			(xy 306.194549 -307.602364) (xy 306.194968 -307.612542) (xy 306.194968 -308.021482) (xy 312.236104 -308.021482)
			(xy 312.236104 -307.612542) (xy 312.236597 -307.602377) (xy 312.244362 -307.58359) (xy 312.258726 -307.569205)
			(xy 312.277502 -307.561412) (xy 312.287666 -307.56098) (xy 313.687206 -307.56098) (xy 313.697383 -307.56136)
			(xy 313.716186 -307.569155) (xy 313.730572 -307.583554) (xy 313.738349 -307.602364) (xy 313.738768 -307.612542)
			(xy 313.738768 -308.021482) (xy 410.102304 -308.021482) (xy 410.102304 -307.612542) (xy 410.102797 -307.602377)
			(xy 410.110562 -307.58359) (xy 410.124926 -307.569205) (xy 410.143702 -307.561412) (xy 410.153866 -307.56098)
			(xy 411.553406 -307.56098) (xy 411.563583 -307.56136) (xy 411.582386 -307.569155) (xy 411.596772 -307.583554)
			(xy 411.604549 -307.602364) (xy 411.604968 -307.612542) (xy 411.604968 -308.021482) (xy 417.646104 -308.021482)
			(xy 417.646104 -307.612542) (xy 417.646597 -307.602377) (xy 417.654362 -307.58359) (xy 417.668726 -307.569205)
			(xy 417.687502 -307.561412) (xy 417.697666 -307.56098) (xy 419.097206 -307.56098) (xy 419.107383 -307.56136)
			(xy 419.126186 -307.569155) (xy 419.140572 -307.583554) (xy 419.148349 -307.602364) (xy 419.148768 -307.612542)
			(xy 419.148768 -308.021482) (xy 425.189904 -308.021482) (xy 425.189904 -307.612542) (xy 425.190397 -307.602377)
			(xy 425.198162 -307.58359) (xy 425.212526 -307.569205) (xy 425.231302 -307.561412) (xy 425.241466 -307.56098)
			(xy 426.641006 -307.56098) (xy 426.651183 -307.56136) (xy 426.669986 -307.569155) (xy 426.684372 -307.583554)
			(xy 426.692149 -307.602364) (xy 426.692568 -307.612542) (xy 426.692568 -308.021482) (xy 432.733704 -308.021482)
			(xy 432.733704 -307.612542) (xy 432.734197 -307.602377) (xy 432.741962 -307.58359) (xy 432.756326 -307.569205)
			(xy 432.775102 -307.561412) (xy 432.785266 -307.56098) (xy 434.184806 -307.56098) (xy 434.194983 -307.56136)
			(xy 434.213786 -307.569155) (xy 434.228172 -307.583554) (xy 434.235949 -307.602364) (xy 434.236368 -307.612542)
			(xy 434.236368 -308.021482) (xy 440.277504 -308.021482) (xy 440.277504 -307.612542) (xy 440.277997 -307.602377)
			(xy 440.285762 -307.58359) (xy 440.300126 -307.569205) (xy 440.318902 -307.561412) (xy 440.329066 -307.56098)
			(xy 441.728606 -307.56098) (xy 441.738783 -307.56136) (xy 441.757586 -307.569155) (xy 441.771972 -307.583554)
			(xy 441.779749 -307.602364) (xy 441.780168 -307.612542) (xy 441.780168 -308.021482) (xy 447.821304 -308.021482)
			(xy 447.821304 -307.612542) (xy 447.821797 -307.602377) (xy 447.829562 -307.58359) (xy 447.843926 -307.569205)
			(xy 447.862702 -307.561412) (xy 447.872866 -307.56098) (xy 449.272406 -307.56098) (xy 449.282583 -307.56136)
			(xy 449.301386 -307.569155) (xy 449.315772 -307.583554) (xy 449.323549 -307.602364) (xy 449.323968 -307.612542)
			(xy 449.323968 -308.021482) (xy 455.365104 -308.021482) (xy 455.365104 -307.612542) (xy 455.365597 -307.602377)
			(xy 455.373362 -307.58359) (xy 455.387726 -307.569205) (xy 455.406502 -307.561412) (xy 455.416666 -307.56098)
			(xy 456.816206 -307.56098) (xy 456.826383 -307.56136) (xy 456.845186 -307.569155) (xy 456.859572 -307.583554)
			(xy 456.867349 -307.602364) (xy 456.867768 -307.612542) (xy 456.867768 -308.021482) (xy 462.908904 -308.021482)
			(xy 462.908904 -307.612542) (xy 462.909397 -307.602377) (xy 462.917162 -307.58359) (xy 462.931526 -307.569205)
			(xy 462.950302 -307.561412) (xy 462.960466 -307.56098) (xy 464.360006 -307.56098) (xy 464.370183 -307.56136)
			(xy 464.388986 -307.569155) (xy 464.403372 -307.583554) (xy 464.411149 -307.602364) (xy 464.411568 -307.612542)
			(xy 464.411568 -308.021482) (xy 464.411122 -308.031652) (xy 464.403344 -308.050445) (xy 464.388965 -308.06483)
			(xy 464.370176 -308.072617) (xy 464.360006 -308.073044) (xy 462.960466 -308.073044) (xy 462.950304 -308.072594)
			(xy 462.93153 -308.064805) (xy 462.917166 -308.050426) (xy 462.909396 -308.031645) (xy 462.908904 -308.021482)
			(xy 456.867768 -308.021482) (xy 456.867322 -308.031652) (xy 456.859544 -308.050445) (xy 456.845165 -308.06483)
			(xy 456.826376 -308.072617) (xy 456.816206 -308.073044) (xy 455.416666 -308.073044) (xy 455.406504 -308.072594)
			(xy 455.38773 -308.064805) (xy 455.373366 -308.050426) (xy 455.365596 -308.031645) (xy 455.365104 -308.021482)
			(xy 449.323968 -308.021482) (xy 449.323522 -308.031652) (xy 449.315744 -308.050445) (xy 449.301365 -308.06483)
			(xy 449.282576 -308.072617) (xy 449.272406 -308.073044) (xy 447.872866 -308.073044) (xy 447.862704 -308.072594)
			(xy 447.84393 -308.064805) (xy 447.829566 -308.050426) (xy 447.821796 -308.031645) (xy 447.821304 -308.021482)
			(xy 441.780168 -308.021482) (xy 441.779722 -308.031652) (xy 441.771944 -308.050445) (xy 441.757565 -308.06483)
			(xy 441.738776 -308.072617) (xy 441.728606 -308.073044) (xy 440.329066 -308.073044) (xy 440.318904 -308.072594)
			(xy 440.30013 -308.064805) (xy 440.285766 -308.050426) (xy 440.277996 -308.031645) (xy 440.277504 -308.021482)
			(xy 434.236368 -308.021482) (xy 434.235922 -308.031652) (xy 434.228144 -308.050445) (xy 434.213765 -308.06483)
			(xy 434.194976 -308.072617) (xy 434.184806 -308.073044) (xy 432.785266 -308.073044) (xy 432.775104 -308.072594)
			(xy 432.75633 -308.064805) (xy 432.741966 -308.050426) (xy 432.734196 -308.031645) (xy 432.733704 -308.021482)
			(xy 426.692568 -308.021482) (xy 426.692122 -308.031652) (xy 426.684344 -308.050445) (xy 426.669965 -308.06483)
			(xy 426.651176 -308.072617) (xy 426.641006 -308.073044) (xy 425.241466 -308.073044) (xy 425.231304 -308.072594)
			(xy 425.21253 -308.064805) (xy 425.198166 -308.050426) (xy 425.190396 -308.031645) (xy 425.189904 -308.021482)
			(xy 419.148768 -308.021482) (xy 419.148322 -308.031652) (xy 419.140544 -308.050445) (xy 419.126165 -308.06483)
			(xy 419.107376 -308.072617) (xy 419.097206 -308.073044) (xy 417.697666 -308.073044) (xy 417.687504 -308.072594)
			(xy 417.66873 -308.064805) (xy 417.654366 -308.050426) (xy 417.646596 -308.031645) (xy 417.646104 -308.021482)
			(xy 411.604968 -308.021482) (xy 411.604522 -308.031652) (xy 411.596744 -308.050445) (xy 411.582365 -308.06483)
			(xy 411.563576 -308.072617) (xy 411.553406 -308.073044) (xy 410.153866 -308.073044) (xy 410.143704 -308.072594)
			(xy 410.12493 -308.064805) (xy 410.110566 -308.050426) (xy 410.102796 -308.031645) (xy 410.102304 -308.021482)
			(xy 313.738768 -308.021482) (xy 313.738322 -308.031652) (xy 313.730544 -308.050445) (xy 313.716165 -308.06483)
			(xy 313.697376 -308.072617) (xy 313.687206 -308.073044) (xy 312.287666 -308.073044) (xy 312.277504 -308.072594)
			(xy 312.25873 -308.064805) (xy 312.244366 -308.050426) (xy 312.236596 -308.031645) (xy 312.236104 -308.021482)
			(xy 306.194968 -308.021482) (xy 306.194522 -308.031652) (xy 306.186744 -308.050445) (xy 306.172365 -308.06483)
			(xy 306.153576 -308.072617) (xy 306.143406 -308.073044) (xy 304.743866 -308.073044) (xy 304.733704 -308.072594)
			(xy 304.71493 -308.064805) (xy 304.700566 -308.050426) (xy 304.692796 -308.031645) (xy 304.692304 -308.021482)
			(xy 298.651168 -308.021482) (xy 298.650722 -308.031652) (xy 298.642944 -308.050445) (xy 298.628565 -308.06483)
			(xy 298.609776 -308.072617) (xy 298.599606 -308.073044) (xy 297.200066 -308.073044) (xy 297.189904 -308.072594)
			(xy 297.17113 -308.064805) (xy 297.156766 -308.050426) (xy 297.148996 -308.031645) (xy 297.148504 -308.021482)
			(xy 291.107368 -308.021482) (xy 291.106922 -308.031652) (xy 291.099144 -308.050445) (xy 291.084765 -308.06483)
			(xy 291.065976 -308.072617) (xy 291.055806 -308.073044) (xy 289.656266 -308.073044) (xy 289.646104 -308.072594)
			(xy 289.62733 -308.064805) (xy 289.612966 -308.050426) (xy 289.605196 -308.031645) (xy 289.604704 -308.021482)
			(xy 283.563568 -308.021482) (xy 283.563122 -308.031652) (xy 283.555344 -308.050445) (xy 283.540965 -308.06483)
			(xy 283.522176 -308.072617) (xy 283.512006 -308.073044) (xy 282.112466 -308.073044) (xy 282.102304 -308.072594)
			(xy 282.08353 -308.064805) (xy 282.069166 -308.050426) (xy 282.061396 -308.031645) (xy 282.060904 -308.021482)
			(xy 276.019768 -308.021482) (xy 276.019322 -308.031652) (xy 276.011544 -308.050445) (xy 275.997165 -308.06483)
			(xy 275.978376 -308.072617) (xy 275.968206 -308.073044) (xy 274.568666 -308.073044) (xy 274.558504 -308.072594)
			(xy 274.53973 -308.064805) (xy 274.525366 -308.050426) (xy 274.517596 -308.031645) (xy 274.517104 -308.021482)
			(xy 268.475968 -308.021482) (xy 268.475522 -308.031652) (xy 268.467744 -308.050445) (xy 268.453365 -308.06483)
			(xy 268.434576 -308.072617) (xy 268.424406 -308.073044) (xy 267.024866 -308.073044) (xy 267.014704 -308.072594)
			(xy 266.99593 -308.064805) (xy 266.981566 -308.050426) (xy 266.973796 -308.031645) (xy 266.973304 -308.021482)
			(xy 260.932168 -308.021482) (xy 260.931722 -308.031652) (xy 260.923944 -308.050445) (xy 260.909565 -308.06483)
			(xy 260.890776 -308.072617) (xy 260.880606 -308.073044) (xy 259.481066 -308.073044) (xy 259.470904 -308.072594)
			(xy 259.45213 -308.064805) (xy 259.437766 -308.050426) (xy 259.429996 -308.031645) (xy 259.429504 -308.021482)
			(xy 216.4715 -308.021482) (xy 216.470953 -308.031634) (xy 216.463191 -308.050395) (xy 216.448842 -308.06476)
			(xy 216.430089 -308.072542) (xy 216.419938 -308.073044) (xy 215.020398 -308.073044) (xy 215.010224 -308.072637)
			(xy 214.991426 -308.064848) (xy 214.97704 -308.050457) (xy 214.969259 -308.031656) (xy 214.968836 -308.021482)
			(xy 208.9277 -308.021482) (xy 208.927153 -308.031634) (xy 208.919391 -308.050395) (xy 208.905042 -308.06476)
			(xy 208.886289 -308.072542) (xy 208.876138 -308.073044) (xy 207.476598 -308.073044) (xy 207.466424 -308.072637)
			(xy 207.447626 -308.064848) (xy 207.43324 -308.050457) (xy 207.425459 -308.031656) (xy 207.425036 -308.021482)
			(xy 201.3839 -308.021482) (xy 201.383353 -308.031634) (xy 201.375591 -308.050395) (xy 201.361242 -308.06476)
			(xy 201.342489 -308.072542) (xy 201.332338 -308.073044) (xy 199.932798 -308.073044) (xy 199.922624 -308.072637)
			(xy 199.903826 -308.064848) (xy 199.88944 -308.050457) (xy 199.881659 -308.031656) (xy 199.881236 -308.021482)
			(xy 193.8401 -308.021482) (xy 193.839553 -308.031634) (xy 193.831791 -308.050395) (xy 193.817442 -308.06476)
			(xy 193.798689 -308.072542) (xy 193.788538 -308.073044) (xy 192.388998 -308.073044) (xy 192.378824 -308.072637)
			(xy 192.360026 -308.064848) (xy 192.34564 -308.050457) (xy 192.337859 -308.031656) (xy 192.337436 -308.021482)
			(xy 186.2963 -308.021482) (xy 186.295753 -308.031634) (xy 186.287991 -308.050395) (xy 186.273642 -308.06476)
			(xy 186.254889 -308.072542) (xy 186.244738 -308.073044) (xy 184.845198 -308.073044) (xy 184.835024 -308.072637)
			(xy 184.816226 -308.064848) (xy 184.80184 -308.050457) (xy 184.794059 -308.031656) (xy 184.793636 -308.021482)
			(xy 178.7525 -308.021482) (xy 178.751953 -308.031634) (xy 178.744191 -308.050395) (xy 178.729842 -308.06476)
			(xy 178.711089 -308.072542) (xy 178.700938 -308.073044) (xy 177.301398 -308.073044) (xy 177.291224 -308.072637)
			(xy 177.272426 -308.064848) (xy 177.25804 -308.050457) (xy 177.250259 -308.031656) (xy 177.249836 -308.021482)
			(xy 171.2087 -308.021482) (xy 171.208153 -308.031634) (xy 171.200391 -308.050395) (xy 171.186042 -308.06476)
			(xy 171.167289 -308.072542) (xy 171.157138 -308.073044) (xy 169.757598 -308.073044) (xy 169.747424 -308.072637)
			(xy 169.728626 -308.064848) (xy 169.71424 -308.050457) (xy 169.706459 -308.031656) (xy 169.706036 -308.021482)
			(xy 163.6649 -308.021482) (xy 163.664353 -308.031634) (xy 163.656591 -308.050395) (xy 163.642242 -308.06476)
			(xy 163.623489 -308.072542) (xy 163.613338 -308.073044) (xy 162.213798 -308.073044) (xy 162.203624 -308.072637)
			(xy 162.184826 -308.064848) (xy 162.17044 -308.050457) (xy 162.162659 -308.031656) (xy 162.162236 -308.021482)
			(xy 65.7987 -308.021482) (xy 65.798153 -308.031634) (xy 65.790391 -308.050395) (xy 65.776042 -308.06476)
			(xy 65.757289 -308.072542) (xy 65.747138 -308.073044) (xy 64.347598 -308.073044) (xy 64.337424 -308.072637)
			(xy 64.318626 -308.064848) (xy 64.30424 -308.050457) (xy 64.296459 -308.031656) (xy 64.296036 -308.021482)
			(xy 58.2549 -308.021482) (xy 58.254353 -308.031634) (xy 58.246591 -308.050395) (xy 58.232242 -308.06476)
			(xy 58.213489 -308.072542) (xy 58.203338 -308.073044) (xy 56.803798 -308.073044) (xy 56.793624 -308.072637)
			(xy 56.774826 -308.064848) (xy 56.76044 -308.050457) (xy 56.752659 -308.031656) (xy 56.752236 -308.021482)
			(xy 50.7111 -308.021482) (xy 50.710553 -308.031634) (xy 50.702791 -308.050395) (xy 50.688442 -308.06476)
			(xy 50.669689 -308.072542) (xy 50.659538 -308.073044) (xy 49.259998 -308.073044) (xy 49.249824 -308.072637)
			(xy 49.231026 -308.064848) (xy 49.21664 -308.050457) (xy 49.208859 -308.031656) (xy 49.208436 -308.021482)
			(xy 43.1673 -308.021482) (xy 43.166753 -308.031634) (xy 43.158991 -308.050395) (xy 43.144642 -308.06476)
			(xy 43.125889 -308.072542) (xy 43.115738 -308.073044) (xy 41.716198 -308.073044) (xy 41.706024 -308.072637)
			(xy 41.687226 -308.064848) (xy 41.67284 -308.050457) (xy 41.665059 -308.031656) (xy 41.664636 -308.021482)
			(xy 35.6235 -308.021482) (xy 35.622953 -308.031634) (xy 35.615191 -308.050395) (xy 35.600842 -308.06476)
			(xy 35.582089 -308.072542) (xy 35.571938 -308.073044) (xy 34.172398 -308.073044) (xy 34.162224 -308.072637)
			(xy 34.143426 -308.064848) (xy 34.12904 -308.050457) (xy 34.121259 -308.031656) (xy 34.120836 -308.021482)
			(xy 28.0797 -308.021482) (xy 28.079153 -308.031634) (xy 28.071391 -308.050395) (xy 28.057042 -308.06476)
			(xy 28.038289 -308.072542) (xy 28.028138 -308.073044) (xy 26.628598 -308.073044) (xy 26.618424 -308.072637)
			(xy 26.599626 -308.064848) (xy 26.58524 -308.050457) (xy 26.577459 -308.031656) (xy 26.577036 -308.021482)
			(xy 20.5359 -308.021482) (xy 20.535353 -308.031634) (xy 20.527591 -308.050395) (xy 20.513242 -308.06476)
			(xy 20.494489 -308.072542) (xy 20.484338 -308.073044) (xy 19.084798 -308.073044) (xy 19.074624 -308.072637)
			(xy 19.055826 -308.064848) (xy 19.04144 -308.050457) (xy 19.033659 -308.031656) (xy 19.033236 -308.021482)
			(xy 12.9921 -308.021482) (xy 12.991553 -308.031634) (xy 12.983791 -308.050395) (xy 12.969442 -308.06476)
			(xy 12.950689 -308.072542) (xy 12.940538 -308.073044) (xy 11.540998 -308.073044) (xy 11.530824 -308.072637)
			(xy 11.512026 -308.064848) (xy 11.49764 -308.050457) (xy 11.489859 -308.031656) (xy 11.489436 -308.021482)
			(xy 2.509012 -308.021482) (xy 2.509012 -308.871366) (xy 7.389368 -308.871366) (xy 7.389368 -308.462426)
			(xy 7.389786 -308.452252) (xy 7.397568 -308.433453) (xy 7.411956 -308.419066) (xy 7.430756 -308.411285)
			(xy 7.44093 -308.410864) (xy 8.84047 -308.410864) (xy 8.850643 -308.411289) (xy 8.869442 -308.419069)
			(xy 8.883829 -308.433455) (xy 8.89161 -308.452253) (xy 8.892032 -308.462426) (xy 8.892032 -308.871366)
			(xy 14.933168 -308.871366) (xy 14.933168 -308.462426) (xy 14.933586 -308.452252) (xy 14.941368 -308.433453)
			(xy 14.955756 -308.419066) (xy 14.974556 -308.411285) (xy 14.98473 -308.410864) (xy 16.38427 -308.410864)
			(xy 16.394443 -308.411289) (xy 16.413242 -308.419069) (xy 16.427629 -308.433455) (xy 16.43541 -308.452253)
			(xy 16.435832 -308.462426) (xy 16.435832 -308.871366) (xy 22.476968 -308.871366) (xy 22.476968 -308.462426)
			(xy 22.477386 -308.452252) (xy 22.485168 -308.433453) (xy 22.499556 -308.419066) (xy 22.518356 -308.411285)
			(xy 22.52853 -308.410864) (xy 23.92807 -308.410864) (xy 23.938243 -308.411289) (xy 23.957042 -308.419069)
			(xy 23.971429 -308.433455) (xy 23.97921 -308.452253) (xy 23.979632 -308.462426) (xy 23.979632 -308.871366)
			(xy 30.020768 -308.871366) (xy 30.020768 -308.462426) (xy 30.021186 -308.452252) (xy 30.028968 -308.433453)
			(xy 30.043356 -308.419066) (xy 30.062156 -308.411285) (xy 30.07233 -308.410864) (xy 31.47187 -308.410864)
			(xy 31.482043 -308.411289) (xy 31.500842 -308.419069) (xy 31.515229 -308.433455) (xy 31.52301 -308.452253)
			(xy 31.523432 -308.462426) (xy 31.523432 -308.871366) (xy 37.564568 -308.871366) (xy 37.564568 -308.462426)
			(xy 37.564986 -308.452252) (xy 37.572768 -308.433453) (xy 37.587156 -308.419066) (xy 37.605956 -308.411285)
			(xy 37.61613 -308.410864) (xy 39.01567 -308.410864) (xy 39.025843 -308.411289) (xy 39.044642 -308.419069)
			(xy 39.059029 -308.433455) (xy 39.06681 -308.452253) (xy 39.067232 -308.462426) (xy 39.067232 -308.871366)
			(xy 45.108368 -308.871366) (xy 45.108368 -308.462426) (xy 45.108786 -308.452252) (xy 45.116568 -308.433453)
			(xy 45.130956 -308.419066) (xy 45.149756 -308.411285) (xy 45.15993 -308.410864) (xy 46.55947 -308.410864)
			(xy 46.569643 -308.411289) (xy 46.588442 -308.419069) (xy 46.602829 -308.433455) (xy 46.61061 -308.452253)
			(xy 46.611032 -308.462426) (xy 46.611032 -308.871366) (xy 52.652168 -308.871366) (xy 52.652168 -308.462426)
			(xy 52.652586 -308.452252) (xy 52.660368 -308.433453) (xy 52.674756 -308.419066) (xy 52.693556 -308.411285)
			(xy 52.70373 -308.410864) (xy 54.10327 -308.410864) (xy 54.113443 -308.411289) (xy 54.132242 -308.419069)
			(xy 54.146629 -308.433455) (xy 54.15441 -308.452253) (xy 54.154832 -308.462426) (xy 54.154832 -308.871366)
			(xy 60.195968 -308.871366) (xy 60.195968 -308.462426) (xy 60.196386 -308.452252) (xy 60.204168 -308.433453)
			(xy 60.218556 -308.419066) (xy 60.237356 -308.411285) (xy 60.24753 -308.410864) (xy 61.64707 -308.410864)
			(xy 61.657243 -308.411289) (xy 61.676042 -308.419069) (xy 61.690429 -308.433455) (xy 61.69821 -308.452253)
			(xy 61.698632 -308.462426) (xy 61.698632 -308.871366) (xy 158.062168 -308.871366) (xy 158.062168 -308.462426)
			(xy 158.062586 -308.452252) (xy 158.070368 -308.433453) (xy 158.084756 -308.419066) (xy 158.103556 -308.411285)
			(xy 158.11373 -308.410864) (xy 159.51327 -308.410864) (xy 159.523443 -308.411289) (xy 159.542242 -308.419069)
			(xy 159.556629 -308.433455) (xy 159.56441 -308.452253) (xy 159.564832 -308.462426) (xy 159.564832 -308.871366)
			(xy 165.605968 -308.871366) (xy 165.605968 -308.462426) (xy 165.606386 -308.452252) (xy 165.614168 -308.433453)
			(xy 165.628556 -308.419066) (xy 165.647356 -308.411285) (xy 165.65753 -308.410864) (xy 167.05707 -308.410864)
			(xy 167.067243 -308.411289) (xy 167.086042 -308.419069) (xy 167.100429 -308.433455) (xy 167.10821 -308.452253)
			(xy 167.108632 -308.462426) (xy 167.108632 -308.871366) (xy 173.149768 -308.871366) (xy 173.149768 -308.462426)
			(xy 173.150186 -308.452252) (xy 173.157968 -308.433453) (xy 173.172356 -308.419066) (xy 173.191156 -308.411285)
			(xy 173.20133 -308.410864) (xy 174.60087 -308.410864) (xy 174.611043 -308.411289) (xy 174.629842 -308.419069)
			(xy 174.644229 -308.433455) (xy 174.65201 -308.452253) (xy 174.652432 -308.462426) (xy 174.652432 -308.871366)
			(xy 180.693568 -308.871366) (xy 180.693568 -308.462426) (xy 180.693986 -308.452252) (xy 180.701768 -308.433453)
			(xy 180.716156 -308.419066) (xy 180.734956 -308.411285) (xy 180.74513 -308.410864) (xy 182.14467 -308.410864)
			(xy 182.154843 -308.411289) (xy 182.173642 -308.419069) (xy 182.188029 -308.433455) (xy 182.19581 -308.452253)
			(xy 182.196232 -308.462426) (xy 182.196232 -308.871366) (xy 188.237368 -308.871366) (xy 188.237368 -308.462426)
			(xy 188.237786 -308.452252) (xy 188.245568 -308.433453) (xy 188.259956 -308.419066) (xy 188.278756 -308.411285)
			(xy 188.28893 -308.410864) (xy 189.68847 -308.410864) (xy 189.698643 -308.411289) (xy 189.717442 -308.419069)
			(xy 189.731829 -308.433455) (xy 189.73961 -308.452253) (xy 189.740032 -308.462426) (xy 189.740032 -308.871366)
			(xy 195.781168 -308.871366) (xy 195.781168 -308.462426) (xy 195.781586 -308.452252) (xy 195.789368 -308.433453)
			(xy 195.803756 -308.419066) (xy 195.822556 -308.411285) (xy 195.83273 -308.410864) (xy 197.23227 -308.410864)
			(xy 197.242443 -308.411289) (xy 197.261242 -308.419069) (xy 197.275629 -308.433455) (xy 197.28341 -308.452253)
			(xy 197.283832 -308.462426) (xy 197.283832 -308.871366) (xy 203.324968 -308.871366) (xy 203.324968 -308.462426)
			(xy 203.325386 -308.452252) (xy 203.333168 -308.433453) (xy 203.347556 -308.419066) (xy 203.366356 -308.411285)
			(xy 203.37653 -308.410864) (xy 204.77607 -308.410864) (xy 204.786243 -308.411289) (xy 204.805042 -308.419069)
			(xy 204.819429 -308.433455) (xy 204.82721 -308.452253) (xy 204.827632 -308.462426) (xy 204.827632 -308.871366)
			(xy 210.868768 -308.871366) (xy 210.868768 -308.462426) (xy 210.869186 -308.452252) (xy 210.876968 -308.433453)
			(xy 210.891356 -308.419066) (xy 210.910156 -308.411285) (xy 210.92033 -308.410864) (xy 212.31987 -308.410864)
			(xy 212.330043 -308.411289) (xy 212.348842 -308.419069) (xy 212.363229 -308.433455) (xy 212.37101 -308.452253)
			(xy 212.371432 -308.462426) (xy 212.371432 -308.871366) (xy 255.329436 -308.871366) (xy 255.329436 -308.462426)
			(xy 255.329885 -308.452256) (xy 255.337661 -308.433463) (xy 255.352039 -308.419077) (xy 255.370829 -308.411291)
			(xy 255.380998 -308.410864) (xy 256.780538 -308.410864) (xy 256.790701 -308.411303) (xy 256.809476 -308.419095)
			(xy 256.823841 -308.433477) (xy 256.83161 -308.452262) (xy 256.8321 -308.462426) (xy 256.8321 -308.871366)
			(xy 262.873236 -308.871366) (xy 262.873236 -308.462426) (xy 262.873685 -308.452256) (xy 262.881461 -308.433463)
			(xy 262.895839 -308.419077) (xy 262.914629 -308.411291) (xy 262.924798 -308.410864) (xy 264.324338 -308.410864)
			(xy 264.334501 -308.411303) (xy 264.353276 -308.419095) (xy 264.367641 -308.433477) (xy 264.37541 -308.452262)
			(xy 264.3759 -308.462426) (xy 264.3759 -308.871366) (xy 270.417036 -308.871366) (xy 270.417036 -308.462426)
			(xy 270.417485 -308.452256) (xy 270.425261 -308.433463) (xy 270.439639 -308.419077) (xy 270.458429 -308.411291)
			(xy 270.468598 -308.410864) (xy 271.868138 -308.410864) (xy 271.878301 -308.411303) (xy 271.897076 -308.419095)
			(xy 271.911441 -308.433477) (xy 271.91921 -308.452262) (xy 271.9197 -308.462426) (xy 271.9197 -308.871366)
			(xy 277.960836 -308.871366) (xy 277.960836 -308.462426) (xy 277.961285 -308.452256) (xy 277.969061 -308.433463)
			(xy 277.983439 -308.419077) (xy 278.002229 -308.411291) (xy 278.012398 -308.410864) (xy 279.411938 -308.410864)
			(xy 279.422101 -308.411303) (xy 279.440876 -308.419095) (xy 279.455241 -308.433477) (xy 279.46301 -308.452262)
			(xy 279.4635 -308.462426) (xy 279.4635 -308.871366) (xy 285.504636 -308.871366) (xy 285.504636 -308.462426)
			(xy 285.505085 -308.452256) (xy 285.512861 -308.433463) (xy 285.527239 -308.419077) (xy 285.546029 -308.411291)
			(xy 285.556198 -308.410864) (xy 286.955738 -308.410864) (xy 286.965901 -308.411303) (xy 286.984676 -308.419095)
			(xy 286.999041 -308.433477) (xy 287.00681 -308.452262) (xy 287.0073 -308.462426) (xy 287.0073 -308.871366)
			(xy 293.048436 -308.871366) (xy 293.048436 -308.462426) (xy 293.048885 -308.452256) (xy 293.056661 -308.433463)
			(xy 293.071039 -308.419077) (xy 293.089829 -308.411291) (xy 293.099998 -308.410864) (xy 294.499538 -308.410864)
			(xy 294.509701 -308.411303) (xy 294.528476 -308.419095) (xy 294.542841 -308.433477) (xy 294.55061 -308.452262)
			(xy 294.5511 -308.462426) (xy 294.5511 -308.871366) (xy 300.592236 -308.871366) (xy 300.592236 -308.462426)
			(xy 300.592685 -308.452256) (xy 300.600461 -308.433463) (xy 300.614839 -308.419077) (xy 300.633629 -308.411291)
			(xy 300.643798 -308.410864) (xy 302.043338 -308.410864) (xy 302.053501 -308.411303) (xy 302.072276 -308.419095)
			(xy 302.086641 -308.433477) (xy 302.09441 -308.452262) (xy 302.0949 -308.462426) (xy 302.0949 -308.871366)
			(xy 308.136036 -308.871366) (xy 308.136036 -308.462426) (xy 308.136485 -308.452256) (xy 308.144261 -308.433463)
			(xy 308.158639 -308.419077) (xy 308.177429 -308.411291) (xy 308.187598 -308.410864) (xy 309.587138 -308.410864)
			(xy 309.597301 -308.411303) (xy 309.616076 -308.419095) (xy 309.630441 -308.433477) (xy 309.63821 -308.452262)
			(xy 309.6387 -308.462426) (xy 309.6387 -308.871366) (xy 406.002236 -308.871366) (xy 406.002236 -308.462426)
			(xy 406.002685 -308.452256) (xy 406.010461 -308.433463) (xy 406.024839 -308.419077) (xy 406.043629 -308.411291)
			(xy 406.053798 -308.410864) (xy 407.453338 -308.410864) (xy 407.463501 -308.411303) (xy 407.482276 -308.419095)
			(xy 407.496641 -308.433477) (xy 407.50441 -308.452262) (xy 407.5049 -308.462426) (xy 407.5049 -308.871366)
			(xy 413.546036 -308.871366) (xy 413.546036 -308.462426) (xy 413.546485 -308.452256) (xy 413.554261 -308.433463)
			(xy 413.568639 -308.419077) (xy 413.587429 -308.411291) (xy 413.597598 -308.410864) (xy 414.997138 -308.410864)
			(xy 415.007301 -308.411303) (xy 415.026076 -308.419095) (xy 415.040441 -308.433477) (xy 415.04821 -308.452262)
			(xy 415.0487 -308.462426) (xy 415.0487 -308.871366) (xy 421.089836 -308.871366) (xy 421.089836 -308.462426)
			(xy 421.090285 -308.452256) (xy 421.098061 -308.433463) (xy 421.112439 -308.419077) (xy 421.131229 -308.411291)
			(xy 421.141398 -308.410864) (xy 422.540938 -308.410864) (xy 422.551101 -308.411303) (xy 422.569876 -308.419095)
			(xy 422.584241 -308.433477) (xy 422.59201 -308.452262) (xy 422.5925 -308.462426) (xy 422.5925 -308.871366)
			(xy 428.633636 -308.871366) (xy 428.633636 -308.462426) (xy 428.634085 -308.452256) (xy 428.641861 -308.433463)
			(xy 428.656239 -308.419077) (xy 428.675029 -308.411291) (xy 428.685198 -308.410864) (xy 430.084738 -308.410864)
			(xy 430.094901 -308.411303) (xy 430.113676 -308.419095) (xy 430.128041 -308.433477) (xy 430.13581 -308.452262)
			(xy 430.1363 -308.462426) (xy 430.1363 -308.871366) (xy 436.177436 -308.871366) (xy 436.177436 -308.462426)
			(xy 436.177885 -308.452256) (xy 436.185661 -308.433463) (xy 436.200039 -308.419077) (xy 436.218829 -308.411291)
			(xy 436.228998 -308.410864) (xy 437.628538 -308.410864) (xy 437.638701 -308.411303) (xy 437.657476 -308.419095)
			(xy 437.671841 -308.433477) (xy 437.67961 -308.452262) (xy 437.6801 -308.462426) (xy 437.6801 -308.871366)
			(xy 443.721236 -308.871366) (xy 443.721236 -308.462426) (xy 443.721685 -308.452256) (xy 443.729461 -308.433463)
			(xy 443.743839 -308.419077) (xy 443.762629 -308.411291) (xy 443.772798 -308.410864) (xy 445.172338 -308.410864)
			(xy 445.182501 -308.411303) (xy 445.201276 -308.419095) (xy 445.215641 -308.433477) (xy 445.22341 -308.452262)
			(xy 445.2239 -308.462426) (xy 445.2239 -308.871366) (xy 451.265036 -308.871366) (xy 451.265036 -308.462426)
			(xy 451.265485 -308.452256) (xy 451.273261 -308.433463) (xy 451.287639 -308.419077) (xy 451.306429 -308.411291)
			(xy 451.316598 -308.410864) (xy 452.716138 -308.410864) (xy 452.726301 -308.411303) (xy 452.745076 -308.419095)
			(xy 452.759441 -308.433477) (xy 452.76721 -308.452262) (xy 452.7677 -308.462426) (xy 452.7677 -308.871366)
			(xy 458.808836 -308.871366) (xy 458.808836 -308.462426) (xy 458.809285 -308.452256) (xy 458.817061 -308.433463)
			(xy 458.831439 -308.419077) (xy 458.850229 -308.411291) (xy 458.860398 -308.410864) (xy 460.259938 -308.410864)
			(xy 460.270101 -308.411303) (xy 460.288876 -308.419095) (xy 460.303241 -308.433477) (xy 460.31101 -308.452262)
			(xy 460.3115 -308.462426) (xy 460.3115 -308.871366) (xy 460.31094 -308.881517) (xy 460.303183 -308.900278)
			(xy 460.288838 -308.914643) (xy 460.270088 -308.922425) (xy 460.259938 -308.922928) (xy 458.860398 -308.922928)
			(xy 458.850222 -308.922537) (xy 458.831421 -308.914745) (xy 458.817035 -308.900349) (xy 458.809256 -308.881542)
			(xy 458.808836 -308.871366) (xy 452.7677 -308.871366) (xy 452.76714 -308.881517) (xy 452.759383 -308.900278)
			(xy 452.745038 -308.914643) (xy 452.726288 -308.922425) (xy 452.716138 -308.922928) (xy 451.316598 -308.922928)
			(xy 451.306422 -308.922537) (xy 451.287621 -308.914745) (xy 451.273235 -308.900349) (xy 451.265456 -308.881542)
			(xy 451.265036 -308.871366) (xy 445.2239 -308.871366) (xy 445.22334 -308.881517) (xy 445.215583 -308.900278)
			(xy 445.201238 -308.914643) (xy 445.182488 -308.922425) (xy 445.172338 -308.922928) (xy 443.772798 -308.922928)
			(xy 443.762622 -308.922537) (xy 443.743821 -308.914745) (xy 443.729435 -308.900349) (xy 443.721656 -308.881542)
			(xy 443.721236 -308.871366) (xy 437.6801 -308.871366) (xy 437.67954 -308.881517) (xy 437.671783 -308.900278)
			(xy 437.657438 -308.914643) (xy 437.638688 -308.922425) (xy 437.628538 -308.922928) (xy 436.228998 -308.922928)
			(xy 436.218822 -308.922537) (xy 436.200021 -308.914745) (xy 436.185635 -308.900349) (xy 436.177856 -308.881542)
			(xy 436.177436 -308.871366) (xy 430.1363 -308.871366) (xy 430.13574 -308.881517) (xy 430.127983 -308.900278)
			(xy 430.113638 -308.914643) (xy 430.094888 -308.922425) (xy 430.084738 -308.922928) (xy 428.685198 -308.922928)
			(xy 428.675022 -308.922537) (xy 428.656221 -308.914745) (xy 428.641835 -308.900349) (xy 428.634056 -308.881542)
			(xy 428.633636 -308.871366) (xy 422.5925 -308.871366) (xy 422.59194 -308.881517) (xy 422.584183 -308.900278)
			(xy 422.569838 -308.914643) (xy 422.551088 -308.922425) (xy 422.540938 -308.922928) (xy 421.141398 -308.922928)
			(xy 421.131222 -308.922537) (xy 421.112421 -308.914745) (xy 421.098035 -308.900349) (xy 421.090256 -308.881542)
			(xy 421.089836 -308.871366) (xy 415.0487 -308.871366) (xy 415.04814 -308.881517) (xy 415.040383 -308.900278)
			(xy 415.026038 -308.914643) (xy 415.007288 -308.922425) (xy 414.997138 -308.922928) (xy 413.597598 -308.922928)
			(xy 413.587422 -308.922537) (xy 413.568621 -308.914745) (xy 413.554235 -308.900349) (xy 413.546456 -308.881542)
			(xy 413.546036 -308.871366) (xy 407.5049 -308.871366) (xy 407.50434 -308.881517) (xy 407.496583 -308.900278)
			(xy 407.482238 -308.914643) (xy 407.463488 -308.922425) (xy 407.453338 -308.922928) (xy 406.053798 -308.922928)
			(xy 406.043622 -308.922537) (xy 406.024821 -308.914745) (xy 406.010435 -308.900349) (xy 406.002656 -308.881542)
			(xy 406.002236 -308.871366) (xy 309.6387 -308.871366) (xy 309.63814 -308.881517) (xy 309.630383 -308.900278)
			(xy 309.616038 -308.914643) (xy 309.597288 -308.922425) (xy 309.587138 -308.922928) (xy 308.187598 -308.922928)
			(xy 308.177422 -308.922537) (xy 308.158621 -308.914745) (xy 308.144235 -308.900349) (xy 308.136456 -308.881542)
			(xy 308.136036 -308.871366) (xy 302.0949 -308.871366) (xy 302.09434 -308.881517) (xy 302.086583 -308.900278)
			(xy 302.072238 -308.914643) (xy 302.053488 -308.922425) (xy 302.043338 -308.922928) (xy 300.643798 -308.922928)
			(xy 300.633622 -308.922537) (xy 300.614821 -308.914745) (xy 300.600435 -308.900349) (xy 300.592656 -308.881542)
			(xy 300.592236 -308.871366) (xy 294.5511 -308.871366) (xy 294.55054 -308.881517) (xy 294.542783 -308.900278)
			(xy 294.528438 -308.914643) (xy 294.509688 -308.922425) (xy 294.499538 -308.922928) (xy 293.099998 -308.922928)
			(xy 293.089822 -308.922537) (xy 293.071021 -308.914745) (xy 293.056635 -308.900349) (xy 293.048856 -308.881542)
			(xy 293.048436 -308.871366) (xy 287.0073 -308.871366) (xy 287.00674 -308.881517) (xy 286.998983 -308.900278)
			(xy 286.984638 -308.914643) (xy 286.965888 -308.922425) (xy 286.955738 -308.922928) (xy 285.556198 -308.922928)
			(xy 285.546022 -308.922537) (xy 285.527221 -308.914745) (xy 285.512835 -308.900349) (xy 285.505056 -308.881542)
			(xy 285.504636 -308.871366) (xy 279.4635 -308.871366) (xy 279.46294 -308.881517) (xy 279.455183 -308.900278)
			(xy 279.440838 -308.914643) (xy 279.422088 -308.922425) (xy 279.411938 -308.922928) (xy 278.012398 -308.922928)
			(xy 278.002222 -308.922537) (xy 277.983421 -308.914745) (xy 277.969035 -308.900349) (xy 277.961256 -308.881542)
			(xy 277.960836 -308.871366) (xy 271.9197 -308.871366) (xy 271.91914 -308.881517) (xy 271.911383 -308.900278)
			(xy 271.897038 -308.914643) (xy 271.878288 -308.922425) (xy 271.868138 -308.922928) (xy 270.468598 -308.922928)
			(xy 270.458422 -308.922537) (xy 270.439621 -308.914745) (xy 270.425235 -308.900349) (xy 270.417456 -308.881542)
			(xy 270.417036 -308.871366) (xy 264.3759 -308.871366) (xy 264.37534 -308.881517) (xy 264.367583 -308.900278)
			(xy 264.353238 -308.914643) (xy 264.334488 -308.922425) (xy 264.324338 -308.922928) (xy 262.924798 -308.922928)
			(xy 262.914622 -308.922537) (xy 262.895821 -308.914745) (xy 262.881435 -308.900349) (xy 262.873656 -308.881542)
			(xy 262.873236 -308.871366) (xy 256.8321 -308.871366) (xy 256.83154 -308.881517) (xy 256.823783 -308.900278)
			(xy 256.809438 -308.914643) (xy 256.790688 -308.922425) (xy 256.780538 -308.922928) (xy 255.380998 -308.922928)
			(xy 255.370822 -308.922537) (xy 255.352021 -308.914745) (xy 255.337635 -308.900349) (xy 255.329856 -308.881542)
			(xy 255.329436 -308.871366) (xy 212.371432 -308.871366) (xy 212.371007 -308.881539) (xy 212.363228 -308.900339)
			(xy 212.348842 -308.914726) (xy 212.330043 -308.922507) (xy 212.31987 -308.922928) (xy 210.92033 -308.922928)
			(xy 210.910156 -308.922511) (xy 210.891356 -308.914729) (xy 210.876969 -308.900341) (xy 210.869189 -308.88154)
			(xy 210.868768 -308.871366) (xy 204.827632 -308.871366) (xy 204.827207 -308.881539) (xy 204.819428 -308.900339)
			(xy 204.805042 -308.914726) (xy 204.786243 -308.922507) (xy 204.77607 -308.922928) (xy 203.37653 -308.922928)
			(xy 203.366356 -308.922511) (xy 203.347556 -308.914729) (xy 203.333169 -308.900341) (xy 203.325389 -308.88154)
			(xy 203.324968 -308.871366) (xy 197.283832 -308.871366) (xy 197.283407 -308.881539) (xy 197.275628 -308.900339)
			(xy 197.261242 -308.914726) (xy 197.242443 -308.922507) (xy 197.23227 -308.922928) (xy 195.83273 -308.922928)
			(xy 195.822556 -308.922511) (xy 195.803756 -308.914729) (xy 195.789369 -308.900341) (xy 195.781589 -308.88154)
			(xy 195.781168 -308.871366) (xy 189.740032 -308.871366) (xy 189.739607 -308.881539) (xy 189.731828 -308.900339)
			(xy 189.717442 -308.914726) (xy 189.698643 -308.922507) (xy 189.68847 -308.922928) (xy 188.28893 -308.922928)
			(xy 188.278756 -308.922511) (xy 188.259956 -308.914729) (xy 188.245569 -308.900341) (xy 188.237789 -308.88154)
			(xy 188.237368 -308.871366) (xy 182.196232 -308.871366) (xy 182.195807 -308.881539) (xy 182.188028 -308.900339)
			(xy 182.173642 -308.914726) (xy 182.154843 -308.922507) (xy 182.14467 -308.922928) (xy 180.74513 -308.922928)
			(xy 180.734956 -308.922511) (xy 180.716156 -308.914729) (xy 180.701769 -308.900341) (xy 180.693989 -308.88154)
			(xy 180.693568 -308.871366) (xy 174.652432 -308.871366) (xy 174.652007 -308.881539) (xy 174.644228 -308.900339)
			(xy 174.629842 -308.914726) (xy 174.611043 -308.922507) (xy 174.60087 -308.922928) (xy 173.20133 -308.922928)
			(xy 173.191156 -308.922511) (xy 173.172356 -308.914729) (xy 173.157969 -308.900341) (xy 173.150189 -308.88154)
			(xy 173.149768 -308.871366) (xy 167.108632 -308.871366) (xy 167.108207 -308.881539) (xy 167.100428 -308.900339)
			(xy 167.086042 -308.914726) (xy 167.067243 -308.922507) (xy 167.05707 -308.922928) (xy 165.65753 -308.922928)
			(xy 165.647356 -308.922511) (xy 165.628556 -308.914729) (xy 165.614169 -308.900341) (xy 165.606389 -308.88154)
			(xy 165.605968 -308.871366) (xy 159.564832 -308.871366) (xy 159.564407 -308.881539) (xy 159.556628 -308.900339)
			(xy 159.542242 -308.914726) (xy 159.523443 -308.922507) (xy 159.51327 -308.922928) (xy 158.11373 -308.922928)
			(xy 158.103556 -308.922511) (xy 158.084756 -308.914729) (xy 158.070369 -308.900341) (xy 158.062589 -308.88154)
			(xy 158.062168 -308.871366) (xy 61.698632 -308.871366) (xy 61.698207 -308.881539) (xy 61.690428 -308.900339)
			(xy 61.676042 -308.914726) (xy 61.657243 -308.922507) (xy 61.64707 -308.922928) (xy 60.24753 -308.922928)
			(xy 60.237356 -308.922511) (xy 60.218556 -308.914729) (xy 60.204169 -308.900341) (xy 60.196389 -308.88154)
			(xy 60.195968 -308.871366) (xy 54.154832 -308.871366) (xy 54.154407 -308.881539) (xy 54.146628 -308.900339)
			(xy 54.132242 -308.914726) (xy 54.113443 -308.922507) (xy 54.10327 -308.922928) (xy 52.70373 -308.922928)
			(xy 52.693556 -308.922511) (xy 52.674756 -308.914729) (xy 52.660369 -308.900341) (xy 52.652589 -308.88154)
			(xy 52.652168 -308.871366) (xy 46.611032 -308.871366) (xy 46.610607 -308.881539) (xy 46.602828 -308.900339)
			(xy 46.588442 -308.914726) (xy 46.569643 -308.922507) (xy 46.55947 -308.922928) (xy 45.15993 -308.922928)
			(xy 45.149756 -308.922511) (xy 45.130956 -308.914729) (xy 45.116569 -308.900341) (xy 45.108789 -308.88154)
			(xy 45.108368 -308.871366) (xy 39.067232 -308.871366) (xy 39.066807 -308.881539) (xy 39.059028 -308.900339)
			(xy 39.044642 -308.914726) (xy 39.025843 -308.922507) (xy 39.01567 -308.922928) (xy 37.61613 -308.922928)
			(xy 37.605956 -308.922511) (xy 37.587156 -308.914729) (xy 37.572769 -308.900341) (xy 37.564989 -308.88154)
			(xy 37.564568 -308.871366) (xy 31.523432 -308.871366) (xy 31.523007 -308.881539) (xy 31.515228 -308.900339)
			(xy 31.500842 -308.914726) (xy 31.482043 -308.922507) (xy 31.47187 -308.922928) (xy 30.07233 -308.922928)
			(xy 30.062156 -308.922511) (xy 30.043356 -308.914729) (xy 30.028969 -308.900341) (xy 30.021189 -308.88154)
			(xy 30.020768 -308.871366) (xy 23.979632 -308.871366) (xy 23.979207 -308.881539) (xy 23.971428 -308.900339)
			(xy 23.957042 -308.914726) (xy 23.938243 -308.922507) (xy 23.92807 -308.922928) (xy 22.52853 -308.922928)
			(xy 22.518356 -308.922511) (xy 22.499556 -308.914729) (xy 22.485169 -308.900341) (xy 22.477389 -308.88154)
			(xy 22.476968 -308.871366) (xy 16.435832 -308.871366) (xy 16.435407 -308.881539) (xy 16.427628 -308.900339)
			(xy 16.413242 -308.914726) (xy 16.394443 -308.922507) (xy 16.38427 -308.922928) (xy 14.98473 -308.922928)
			(xy 14.974556 -308.922511) (xy 14.955756 -308.914729) (xy 14.941369 -308.900341) (xy 14.933589 -308.88154)
			(xy 14.933168 -308.871366) (xy 8.892032 -308.871366) (xy 8.891607 -308.881539) (xy 8.883828 -308.900339)
			(xy 8.869442 -308.914726) (xy 8.850643 -308.922507) (xy 8.84047 -308.922928) (xy 7.44093 -308.922928)
			(xy 7.430756 -308.922511) (xy 7.411956 -308.914729) (xy 7.397569 -308.900341) (xy 7.389789 -308.88154)
			(xy 7.389368 -308.871366) (xy 2.509012 -308.871366) (xy 2.509012 -309.721504) (xy 11.489436 -309.721504)
			(xy 11.489436 -309.312564) (xy 11.489793 -309.302403) (xy 11.497607 -309.283643) (xy 11.512024 -309.26932)
			(xy 11.530834 -309.261628) (xy 11.540998 -309.261256) (xy 12.940538 -309.261256) (xy 12.950669 -309.261696)
			(xy 12.969394 -309.269439) (xy 12.98375 -309.28374) (xy 12.991565 -309.302435) (xy 12.9921 -309.312564)
			(xy 12.9921 -309.721504) (xy 19.033236 -309.721504) (xy 19.033236 -309.312564) (xy 19.033593 -309.302403)
			(xy 19.041407 -309.283643) (xy 19.055824 -309.26932) (xy 19.074634 -309.261628) (xy 19.084798 -309.261256)
			(xy 20.484338 -309.261256) (xy 20.494469 -309.261696) (xy 20.513194 -309.269439) (xy 20.52755 -309.28374)
			(xy 20.535365 -309.302435) (xy 20.5359 -309.312564) (xy 20.5359 -309.721504) (xy 26.577036 -309.721504)
			(xy 26.577036 -309.312564) (xy 26.577393 -309.302403) (xy 26.585207 -309.283643) (xy 26.599624 -309.26932)
			(xy 26.618434 -309.261628) (xy 26.628598 -309.261256) (xy 28.028138 -309.261256) (xy 28.038269 -309.261696)
			(xy 28.056994 -309.269439) (xy 28.07135 -309.28374) (xy 28.079165 -309.302435) (xy 28.0797 -309.312564)
			(xy 28.0797 -309.721504) (xy 34.120836 -309.721504) (xy 34.120836 -309.312564) (xy 34.121193 -309.302403)
			(xy 34.129007 -309.283643) (xy 34.143424 -309.26932) (xy 34.162234 -309.261628) (xy 34.172398 -309.261256)
			(xy 35.571938 -309.261256) (xy 35.582069 -309.261696) (xy 35.600794 -309.269439) (xy 35.61515 -309.28374)
			(xy 35.622965 -309.302435) (xy 35.6235 -309.312564) (xy 35.6235 -309.721504) (xy 41.664636 -309.721504)
			(xy 41.664636 -309.312564) (xy 41.664993 -309.302403) (xy 41.672807 -309.283643) (xy 41.687224 -309.26932)
			(xy 41.706034 -309.261628) (xy 41.716198 -309.261256) (xy 43.115738 -309.261256) (xy 43.125869 -309.261696)
			(xy 43.144594 -309.269439) (xy 43.15895 -309.28374) (xy 43.166765 -309.302435) (xy 43.1673 -309.312564)
			(xy 43.1673 -309.721504) (xy 49.208436 -309.721504) (xy 49.208436 -309.312564) (xy 49.208793 -309.302403)
			(xy 49.216607 -309.283643) (xy 49.231024 -309.26932) (xy 49.249834 -309.261628) (xy 49.259998 -309.261256)
			(xy 50.659538 -309.261256) (xy 50.669669 -309.261696) (xy 50.688394 -309.269439) (xy 50.70275 -309.28374)
			(xy 50.710565 -309.302435) (xy 50.7111 -309.312564) (xy 50.7111 -309.721504) (xy 56.752236 -309.721504)
			(xy 56.752236 -309.312564) (xy 56.752593 -309.302403) (xy 56.760407 -309.283643) (xy 56.774824 -309.26932)
			(xy 56.793634 -309.261628) (xy 56.803798 -309.261256) (xy 58.203338 -309.261256) (xy 58.213469 -309.261696)
			(xy 58.232194 -309.269439) (xy 58.24655 -309.28374) (xy 58.254365 -309.302435) (xy 58.2549 -309.312564)
			(xy 58.2549 -309.721504) (xy 64.296036 -309.721504) (xy 64.296036 -309.312564) (xy 64.296393 -309.302403)
			(xy 64.304207 -309.283643) (xy 64.318624 -309.26932) (xy 64.337434 -309.261628) (xy 64.347598 -309.261256)
			(xy 65.747138 -309.261256) (xy 65.757269 -309.261696) (xy 65.775994 -309.269439) (xy 65.79035 -309.28374)
			(xy 65.798165 -309.302435) (xy 65.7987 -309.312564) (xy 65.7987 -309.721504) (xy 162.162236 -309.721504)
			(xy 162.162236 -309.312564) (xy 162.162593 -309.302403) (xy 162.170407 -309.283643) (xy 162.184824 -309.26932)
			(xy 162.203634 -309.261628) (xy 162.213798 -309.261256) (xy 163.613338 -309.261256) (xy 163.623469 -309.261696)
			(xy 163.642194 -309.269439) (xy 163.65655 -309.28374) (xy 163.664365 -309.302435) (xy 163.6649 -309.312564)
			(xy 163.6649 -309.721504) (xy 169.706036 -309.721504) (xy 169.706036 -309.312564) (xy 169.706393 -309.302403)
			(xy 169.714207 -309.283643) (xy 169.728624 -309.26932) (xy 169.747434 -309.261628) (xy 169.757598 -309.261256)
			(xy 171.157138 -309.261256) (xy 171.167269 -309.261696) (xy 171.185994 -309.269439) (xy 171.20035 -309.28374)
			(xy 171.208165 -309.302435) (xy 171.2087 -309.312564) (xy 171.2087 -309.721504) (xy 177.249836 -309.721504)
			(xy 177.249836 -309.312564) (xy 177.250193 -309.302403) (xy 177.258007 -309.283643) (xy 177.272424 -309.26932)
			(xy 177.291234 -309.261628) (xy 177.301398 -309.261256) (xy 178.700938 -309.261256) (xy 178.711069 -309.261696)
			(xy 178.729794 -309.269439) (xy 178.74415 -309.28374) (xy 178.751965 -309.302435) (xy 178.7525 -309.312564)
			(xy 178.7525 -309.721504) (xy 184.793636 -309.721504) (xy 184.793636 -309.312564) (xy 184.793993 -309.302403)
			(xy 184.801807 -309.283643) (xy 184.816224 -309.26932) (xy 184.835034 -309.261628) (xy 184.845198 -309.261256)
			(xy 186.244738 -309.261256) (xy 186.254869 -309.261696) (xy 186.273594 -309.269439) (xy 186.28795 -309.28374)
			(xy 186.295765 -309.302435) (xy 186.2963 -309.312564) (xy 186.2963 -309.721504) (xy 192.337436 -309.721504)
			(xy 192.337436 -309.312564) (xy 192.337793 -309.302403) (xy 192.345607 -309.283643) (xy 192.360024 -309.26932)
			(xy 192.378834 -309.261628) (xy 192.388998 -309.261256) (xy 193.788538 -309.261256) (xy 193.798669 -309.261696)
			(xy 193.817394 -309.269439) (xy 193.83175 -309.28374) (xy 193.839565 -309.302435) (xy 193.8401 -309.312564)
			(xy 193.8401 -309.721504) (xy 199.881236 -309.721504) (xy 199.881236 -309.312564) (xy 199.881593 -309.302403)
			(xy 199.889407 -309.283643) (xy 199.903824 -309.26932) (xy 199.922634 -309.261628) (xy 199.932798 -309.261256)
			(xy 201.332338 -309.261256) (xy 201.342469 -309.261696) (xy 201.361194 -309.269439) (xy 201.37555 -309.28374)
			(xy 201.383365 -309.302435) (xy 201.3839 -309.312564) (xy 201.3839 -309.721504) (xy 207.425036 -309.721504)
			(xy 207.425036 -309.312564) (xy 207.425393 -309.302403) (xy 207.433207 -309.283643) (xy 207.447624 -309.26932)
			(xy 207.466434 -309.261628) (xy 207.476598 -309.261256) (xy 208.876138 -309.261256) (xy 208.886269 -309.261696)
			(xy 208.904994 -309.269439) (xy 208.91935 -309.28374) (xy 208.927165 -309.302435) (xy 208.9277 -309.312564)
			(xy 208.9277 -309.721504) (xy 214.968836 -309.721504) (xy 214.968836 -309.312564) (xy 214.969193 -309.302403)
			(xy 214.977007 -309.283643) (xy 214.991424 -309.26932) (xy 215.010234 -309.261628) (xy 215.020398 -309.261256)
			(xy 216.419938 -309.261256) (xy 216.430069 -309.261696) (xy 216.448794 -309.269439) (xy 216.46315 -309.28374)
			(xy 216.470965 -309.302435) (xy 216.4715 -309.312564) (xy 216.4715 -309.721504) (xy 259.429504 -309.721504)
			(xy 259.429504 -309.312564) (xy 259.429892 -309.302407) (xy 259.4377 -309.283653) (xy 259.452107 -309.269331)
			(xy 259.470907 -309.261633) (xy 259.481066 -309.261256) (xy 260.880606 -309.261256) (xy 260.890735 -309.261722)
			(xy 260.909459 -309.269455) (xy 260.923816 -309.283748) (xy 260.931632 -309.302437) (xy 260.932168 -309.312564)
			(xy 260.932168 -309.721504) (xy 266.973304 -309.721504) (xy 266.973304 -309.312564) (xy 266.973692 -309.302407)
			(xy 266.9815 -309.283653) (xy 266.995907 -309.269331) (xy 267.014707 -309.261633) (xy 267.024866 -309.261256)
			(xy 268.424406 -309.261256) (xy 268.434535 -309.261722) (xy 268.453259 -309.269455) (xy 268.467616 -309.283748)
			(xy 268.475432 -309.302437) (xy 268.475968 -309.312564) (xy 268.475968 -309.721504) (xy 274.517104 -309.721504)
			(xy 274.517104 -309.312564) (xy 274.517492 -309.302407) (xy 274.5253 -309.283653) (xy 274.539707 -309.269331)
			(xy 274.558507 -309.261633) (xy 274.568666 -309.261256) (xy 275.968206 -309.261256) (xy 275.978335 -309.261722)
			(xy 275.997059 -309.269455) (xy 276.011416 -309.283748) (xy 276.019232 -309.302437) (xy 276.019768 -309.312564)
			(xy 276.019768 -309.721504) (xy 282.060904 -309.721504) (xy 282.060904 -309.312564) (xy 282.061292 -309.302407)
			(xy 282.0691 -309.283653) (xy 282.083507 -309.269331) (xy 282.102307 -309.261633) (xy 282.112466 -309.261256)
			(xy 283.512006 -309.261256) (xy 283.522135 -309.261722) (xy 283.540859 -309.269455) (xy 283.555216 -309.283748)
			(xy 283.563032 -309.302437) (xy 283.563568 -309.312564) (xy 283.563568 -309.721504) (xy 289.604704 -309.721504)
			(xy 289.604704 -309.312564) (xy 289.605092 -309.302407) (xy 289.6129 -309.283653) (xy 289.627307 -309.269331)
			(xy 289.646107 -309.261633) (xy 289.656266 -309.261256) (xy 291.055806 -309.261256) (xy 291.065935 -309.261722)
			(xy 291.084659 -309.269455) (xy 291.099016 -309.283748) (xy 291.106832 -309.302437) (xy 291.107368 -309.312564)
			(xy 291.107368 -309.721504) (xy 297.148504 -309.721504) (xy 297.148504 -309.312564) (xy 297.148892 -309.302407)
			(xy 297.1567 -309.283653) (xy 297.171107 -309.269331) (xy 297.189907 -309.261633) (xy 297.200066 -309.261256)
			(xy 298.599606 -309.261256) (xy 298.609735 -309.261722) (xy 298.628459 -309.269455) (xy 298.642816 -309.283748)
			(xy 298.650632 -309.302437) (xy 298.651168 -309.312564) (xy 298.651168 -309.721504) (xy 304.692304 -309.721504)
			(xy 304.692304 -309.312564) (xy 304.692692 -309.302407) (xy 304.7005 -309.283653) (xy 304.714907 -309.269331)
			(xy 304.733707 -309.261633) (xy 304.743866 -309.261256) (xy 306.143406 -309.261256) (xy 306.153535 -309.261722)
			(xy 306.172259 -309.269455) (xy 306.186616 -309.283748) (xy 306.194432 -309.302437) (xy 306.194968 -309.312564)
			(xy 306.194968 -309.721504) (xy 312.236104 -309.721504) (xy 312.236104 -309.312564) (xy 312.236492 -309.302407)
			(xy 312.2443 -309.283653) (xy 312.258707 -309.269331) (xy 312.277507 -309.261633) (xy 312.287666 -309.261256)
			(xy 313.687206 -309.261256) (xy 313.697335 -309.261722) (xy 313.716059 -309.269455) (xy 313.730416 -309.283748)
			(xy 313.738232 -309.302437) (xy 313.738768 -309.312564) (xy 313.738768 -309.721504) (xy 410.102304 -309.721504)
			(xy 410.102304 -309.312564) (xy 410.102692 -309.302407) (xy 410.1105 -309.283653) (xy 410.124907 -309.269331)
			(xy 410.143707 -309.261633) (xy 410.153866 -309.261256) (xy 411.553406 -309.261256) (xy 411.563535 -309.261722)
			(xy 411.582259 -309.269455) (xy 411.596616 -309.283748) (xy 411.604432 -309.302437) (xy 411.604968 -309.312564)
			(xy 411.604968 -309.721504) (xy 417.646104 -309.721504) (xy 417.646104 -309.312564) (xy 417.646492 -309.302407)
			(xy 417.6543 -309.283653) (xy 417.668707 -309.269331) (xy 417.687507 -309.261633) (xy 417.697666 -309.261256)
			(xy 419.097206 -309.261256) (xy 419.107335 -309.261722) (xy 419.126059 -309.269455) (xy 419.140416 -309.283748)
			(xy 419.148232 -309.302437) (xy 419.148768 -309.312564) (xy 419.148768 -309.721504) (xy 425.189904 -309.721504)
			(xy 425.189904 -309.312564) (xy 425.190292 -309.302407) (xy 425.1981 -309.283653) (xy 425.212507 -309.269331)
			(xy 425.231307 -309.261633) (xy 425.241466 -309.261256) (xy 426.641006 -309.261256) (xy 426.651135 -309.261722)
			(xy 426.669859 -309.269455) (xy 426.684216 -309.283748) (xy 426.692032 -309.302437) (xy 426.692568 -309.312564)
			(xy 426.692568 -309.721504) (xy 432.733704 -309.721504) (xy 432.733704 -309.312564) (xy 432.734092 -309.302407)
			(xy 432.7419 -309.283653) (xy 432.756307 -309.269331) (xy 432.775107 -309.261633) (xy 432.785266 -309.261256)
			(xy 434.184806 -309.261256) (xy 434.194935 -309.261722) (xy 434.213659 -309.269455) (xy 434.228016 -309.283748)
			(xy 434.235832 -309.302437) (xy 434.236368 -309.312564) (xy 434.236368 -309.721504) (xy 440.277504 -309.721504)
			(xy 440.277504 -309.312564) (xy 440.277892 -309.302407) (xy 440.2857 -309.283653) (xy 440.300107 -309.269331)
			(xy 440.318907 -309.261633) (xy 440.329066 -309.261256) (xy 441.728606 -309.261256) (xy 441.738735 -309.261722)
			(xy 441.757459 -309.269455) (xy 441.771816 -309.283748) (xy 441.779632 -309.302437) (xy 441.780168 -309.312564)
			(xy 441.780168 -309.721504) (xy 447.821304 -309.721504) (xy 447.821304 -309.312564) (xy 447.821692 -309.302407)
			(xy 447.8295 -309.283653) (xy 447.843907 -309.269331) (xy 447.862707 -309.261633) (xy 447.872866 -309.261256)
			(xy 449.272406 -309.261256) (xy 449.282535 -309.261722) (xy 449.301259 -309.269455) (xy 449.315616 -309.283748)
			(xy 449.323432 -309.302437) (xy 449.323968 -309.312564) (xy 449.323968 -309.721504) (xy 455.365104 -309.721504)
			(xy 455.365104 -309.312564) (xy 455.365492 -309.302407) (xy 455.3733 -309.283653) (xy 455.387707 -309.269331)
			(xy 455.406507 -309.261633) (xy 455.416666 -309.261256) (xy 456.816206 -309.261256) (xy 456.826335 -309.261722)
			(xy 456.845059 -309.269455) (xy 456.859416 -309.283748) (xy 456.867232 -309.302437) (xy 456.867768 -309.312564)
			(xy 456.867768 -309.721504) (xy 462.908904 -309.721504) (xy 462.908904 -309.312564) (xy 462.909292 -309.302407)
			(xy 462.9171 -309.283653) (xy 462.931507 -309.269331) (xy 462.950307 -309.261633) (xy 462.960466 -309.261256)
			(xy 464.360006 -309.261256) (xy 464.370135 -309.261722) (xy 464.388859 -309.269455) (xy 464.403216 -309.283748)
			(xy 464.411032 -309.302437) (xy 464.411568 -309.312564) (xy 464.411568 -309.721504) (xy 464.411181 -309.731662)
			(xy 464.403378 -309.750421) (xy 464.38897 -309.764745) (xy 464.370167 -309.772439) (xy 464.360006 -309.772812)
			(xy 462.960466 -309.772812) (xy 462.950344 -309.772303) (xy 462.931631 -309.764574) (xy 462.917278 -309.750295)
			(xy 462.909451 -309.731624) (xy 462.908904 -309.721504) (xy 456.867768 -309.721504) (xy 456.867381 -309.731662)
			(xy 456.859578 -309.750421) (xy 456.84517 -309.764745) (xy 456.826367 -309.772439) (xy 456.816206 -309.772812)
			(xy 455.416666 -309.772812) (xy 455.406544 -309.772303) (xy 455.387831 -309.764574) (xy 455.373478 -309.750295)
			(xy 455.365651 -309.731624) (xy 455.365104 -309.721504) (xy 449.323968 -309.721504) (xy 449.323581 -309.731662)
			(xy 449.315778 -309.750421) (xy 449.30137 -309.764745) (xy 449.282567 -309.772439) (xy 449.272406 -309.772812)
			(xy 447.872866 -309.772812) (xy 447.862744 -309.772303) (xy 447.844031 -309.764574) (xy 447.829678 -309.750295)
			(xy 447.821851 -309.731624) (xy 447.821304 -309.721504) (xy 441.780168 -309.721504) (xy 441.779781 -309.731662)
			(xy 441.771978 -309.750421) (xy 441.75757 -309.764745) (xy 441.738767 -309.772439) (xy 441.728606 -309.772812)
			(xy 440.329066 -309.772812) (xy 440.318944 -309.772303) (xy 440.300231 -309.764574) (xy 440.285878 -309.750295)
			(xy 440.278051 -309.731624) (xy 440.277504 -309.721504) (xy 434.236368 -309.721504) (xy 434.235981 -309.731662)
			(xy 434.228178 -309.750421) (xy 434.21377 -309.764745) (xy 434.194967 -309.772439) (xy 434.184806 -309.772812)
			(xy 432.785266 -309.772812) (xy 432.775144 -309.772303) (xy 432.756431 -309.764574) (xy 432.742078 -309.750295)
			(xy 432.734251 -309.731624) (xy 432.733704 -309.721504) (xy 426.692568 -309.721504) (xy 426.692181 -309.731662)
			(xy 426.684378 -309.750421) (xy 426.66997 -309.764745) (xy 426.651167 -309.772439) (xy 426.641006 -309.772812)
			(xy 425.241466 -309.772812) (xy 425.231344 -309.772303) (xy 425.212631 -309.764574) (xy 425.198278 -309.750295)
			(xy 425.190451 -309.731624) (xy 425.189904 -309.721504) (xy 419.148768 -309.721504) (xy 419.148381 -309.731662)
			(xy 419.140578 -309.750421) (xy 419.12617 -309.764745) (xy 419.107367 -309.772439) (xy 419.097206 -309.772812)
			(xy 417.697666 -309.772812) (xy 417.687544 -309.772303) (xy 417.668831 -309.764574) (xy 417.654478 -309.750295)
			(xy 417.646651 -309.731624) (xy 417.646104 -309.721504) (xy 411.604968 -309.721504) (xy 411.604581 -309.731662)
			(xy 411.596778 -309.750421) (xy 411.58237 -309.764745) (xy 411.563567 -309.772439) (xy 411.553406 -309.772812)
			(xy 410.153866 -309.772812) (xy 410.143744 -309.772303) (xy 410.125031 -309.764574) (xy 410.110678 -309.750295)
			(xy 410.102851 -309.731624) (xy 410.102304 -309.721504) (xy 313.738768 -309.721504) (xy 313.738381 -309.731662)
			(xy 313.730578 -309.750421) (xy 313.71617 -309.764745) (xy 313.697367 -309.772439) (xy 313.687206 -309.772812)
			(xy 312.287666 -309.772812) (xy 312.277544 -309.772303) (xy 312.258831 -309.764574) (xy 312.244478 -309.750295)
			(xy 312.236651 -309.731624) (xy 312.236104 -309.721504) (xy 306.194968 -309.721504) (xy 306.194581 -309.731662)
			(xy 306.186778 -309.750421) (xy 306.17237 -309.764745) (xy 306.153567 -309.772439) (xy 306.143406 -309.772812)
			(xy 304.743866 -309.772812) (xy 304.733744 -309.772303) (xy 304.715031 -309.764574) (xy 304.700678 -309.750295)
			(xy 304.692851 -309.731624) (xy 304.692304 -309.721504) (xy 298.651168 -309.721504) (xy 298.650781 -309.731662)
			(xy 298.642978 -309.750421) (xy 298.62857 -309.764745) (xy 298.609767 -309.772439) (xy 298.599606 -309.772812)
			(xy 297.200066 -309.772812) (xy 297.189944 -309.772303) (xy 297.171231 -309.764574) (xy 297.156878 -309.750295)
			(xy 297.149051 -309.731624) (xy 297.148504 -309.721504) (xy 291.107368 -309.721504) (xy 291.106981 -309.731662)
			(xy 291.099178 -309.750421) (xy 291.08477 -309.764745) (xy 291.065967 -309.772439) (xy 291.055806 -309.772812)
			(xy 289.656266 -309.772812) (xy 289.646144 -309.772303) (xy 289.627431 -309.764574) (xy 289.613078 -309.750295)
			(xy 289.605251 -309.731624) (xy 289.604704 -309.721504) (xy 283.563568 -309.721504) (xy 283.563181 -309.731662)
			(xy 283.555378 -309.750421) (xy 283.54097 -309.764745) (xy 283.522167 -309.772439) (xy 283.512006 -309.772812)
			(xy 282.112466 -309.772812) (xy 282.102344 -309.772303) (xy 282.083631 -309.764574) (xy 282.069278 -309.750295)
			(xy 282.061451 -309.731624) (xy 282.060904 -309.721504) (xy 276.019768 -309.721504) (xy 276.019381 -309.731662)
			(xy 276.011578 -309.750421) (xy 275.99717 -309.764745) (xy 275.978367 -309.772439) (xy 275.968206 -309.772812)
			(xy 274.568666 -309.772812) (xy 274.558544 -309.772303) (xy 274.539831 -309.764574) (xy 274.525478 -309.750295)
			(xy 274.517651 -309.731624) (xy 274.517104 -309.721504) (xy 268.475968 -309.721504) (xy 268.475581 -309.731662)
			(xy 268.467778 -309.750421) (xy 268.45337 -309.764745) (xy 268.434567 -309.772439) (xy 268.424406 -309.772812)
			(xy 267.024866 -309.772812) (xy 267.014744 -309.772303) (xy 266.996031 -309.764574) (xy 266.981678 -309.750295)
			(xy 266.973851 -309.731624) (xy 266.973304 -309.721504) (xy 260.932168 -309.721504) (xy 260.931781 -309.731662)
			(xy 260.923978 -309.750421) (xy 260.90957 -309.764745) (xy 260.890767 -309.772439) (xy 260.880606 -309.772812)
			(xy 259.481066 -309.772812) (xy 259.470944 -309.772303) (xy 259.452231 -309.764574) (xy 259.437878 -309.750295)
			(xy 259.430051 -309.731624) (xy 259.429504 -309.721504) (xy 216.4715 -309.721504) (xy 216.471082 -309.731658)
			(xy 216.463285 -309.750411) (xy 216.448887 -309.764734) (xy 216.430094 -309.772434) (xy 216.419938 -309.772812)
			(xy 215.020398 -309.772812) (xy 215.010278 -309.772277) (xy 214.991566 -309.764558) (xy 214.977212 -309.750287)
			(xy 214.969384 -309.731621) (xy 214.968836 -309.721504) (xy 208.9277 -309.721504) (xy 208.927282 -309.731658)
			(xy 208.919485 -309.750411) (xy 208.905087 -309.764734) (xy 208.886294 -309.772434) (xy 208.876138 -309.772812)
			(xy 207.476598 -309.772812) (xy 207.466478 -309.772277) (xy 207.447766 -309.764558) (xy 207.433412 -309.750287)
			(xy 207.425584 -309.731621) (xy 207.425036 -309.721504) (xy 201.3839 -309.721504) (xy 201.383482 -309.731658)
			(xy 201.375685 -309.750411) (xy 201.361287 -309.764734) (xy 201.342494 -309.772434) (xy 201.332338 -309.772812)
			(xy 199.932798 -309.772812) (xy 199.922678 -309.772277) (xy 199.903966 -309.764558) (xy 199.889612 -309.750287)
			(xy 199.881784 -309.731621) (xy 199.881236 -309.721504) (xy 193.8401 -309.721504) (xy 193.839682 -309.731658)
			(xy 193.831885 -309.750411) (xy 193.817487 -309.764734) (xy 193.798694 -309.772434) (xy 193.788538 -309.772812)
			(xy 192.388998 -309.772812) (xy 192.378878 -309.772277) (xy 192.360166 -309.764558) (xy 192.345812 -309.750287)
			(xy 192.337984 -309.731621) (xy 192.337436 -309.721504) (xy 186.2963 -309.721504) (xy 186.295882 -309.731658)
			(xy 186.288085 -309.750411) (xy 186.273687 -309.764734) (xy 186.254894 -309.772434) (xy 186.244738 -309.772812)
			(xy 184.845198 -309.772812) (xy 184.835078 -309.772277) (xy 184.816366 -309.764558) (xy 184.802012 -309.750287)
			(xy 184.794184 -309.731621) (xy 184.793636 -309.721504) (xy 178.7525 -309.721504) (xy 178.752082 -309.731658)
			(xy 178.744285 -309.750411) (xy 178.729887 -309.764734) (xy 178.711094 -309.772434) (xy 178.700938 -309.772812)
			(xy 177.301398 -309.772812) (xy 177.291278 -309.772277) (xy 177.272566 -309.764558) (xy 177.258212 -309.750287)
			(xy 177.250384 -309.731621) (xy 177.249836 -309.721504) (xy 171.2087 -309.721504) (xy 171.208282 -309.731658)
			(xy 171.200485 -309.750411) (xy 171.186087 -309.764734) (xy 171.167294 -309.772434) (xy 171.157138 -309.772812)
			(xy 169.757598 -309.772812) (xy 169.747478 -309.772277) (xy 169.728766 -309.764558) (xy 169.714412 -309.750287)
			(xy 169.706584 -309.731621) (xy 169.706036 -309.721504) (xy 163.6649 -309.721504) (xy 163.664482 -309.731658)
			(xy 163.656685 -309.750411) (xy 163.642287 -309.764734) (xy 163.623494 -309.772434) (xy 163.613338 -309.772812)
			(xy 162.213798 -309.772812) (xy 162.203678 -309.772277) (xy 162.184966 -309.764558) (xy 162.170612 -309.750287)
			(xy 162.162784 -309.731621) (xy 162.162236 -309.721504) (xy 65.7987 -309.721504) (xy 65.798282 -309.731658)
			(xy 65.790485 -309.750411) (xy 65.776087 -309.764734) (xy 65.757294 -309.772434) (xy 65.747138 -309.772812)
			(xy 64.347598 -309.772812) (xy 64.337478 -309.772277) (xy 64.318766 -309.764558) (xy 64.304412 -309.750287)
			(xy 64.296584 -309.731621) (xy 64.296036 -309.721504) (xy 58.2549 -309.721504) (xy 58.254482 -309.731658)
			(xy 58.246685 -309.750411) (xy 58.232287 -309.764734) (xy 58.213494 -309.772434) (xy 58.203338 -309.772812)
			(xy 56.803798 -309.772812) (xy 56.793678 -309.772277) (xy 56.774966 -309.764558) (xy 56.760612 -309.750287)
			(xy 56.752784 -309.731621) (xy 56.752236 -309.721504) (xy 50.7111 -309.721504) (xy 50.710682 -309.731658)
			(xy 50.702885 -309.750411) (xy 50.688487 -309.764734) (xy 50.669694 -309.772434) (xy 50.659538 -309.772812)
			(xy 49.259998 -309.772812) (xy 49.249878 -309.772277) (xy 49.231166 -309.764558) (xy 49.216812 -309.750287)
			(xy 49.208984 -309.731621) (xy 49.208436 -309.721504) (xy 43.1673 -309.721504) (xy 43.166882 -309.731658)
			(xy 43.159085 -309.750411) (xy 43.144687 -309.764734) (xy 43.125894 -309.772434) (xy 43.115738 -309.772812)
			(xy 41.716198 -309.772812) (xy 41.706078 -309.772277) (xy 41.687366 -309.764558) (xy 41.673012 -309.750287)
			(xy 41.665184 -309.731621) (xy 41.664636 -309.721504) (xy 35.6235 -309.721504) (xy 35.623082 -309.731658)
			(xy 35.615285 -309.750411) (xy 35.600887 -309.764734) (xy 35.582094 -309.772434) (xy 35.571938 -309.772812)
			(xy 34.172398 -309.772812) (xy 34.162278 -309.772277) (xy 34.143566 -309.764558) (xy 34.129212 -309.750287)
			(xy 34.121384 -309.731621) (xy 34.120836 -309.721504) (xy 28.0797 -309.721504) (xy 28.079282 -309.731658)
			(xy 28.071485 -309.750411) (xy 28.057087 -309.764734) (xy 28.038294 -309.772434) (xy 28.028138 -309.772812)
			(xy 26.628598 -309.772812) (xy 26.618478 -309.772277) (xy 26.599766 -309.764558) (xy 26.585412 -309.750287)
			(xy 26.577584 -309.731621) (xy 26.577036 -309.721504) (xy 20.5359 -309.721504) (xy 20.535482 -309.731658)
			(xy 20.527685 -309.750411) (xy 20.513287 -309.764734) (xy 20.494494 -309.772434) (xy 20.484338 -309.772812)
			(xy 19.084798 -309.772812) (xy 19.074678 -309.772277) (xy 19.055966 -309.764558) (xy 19.041612 -309.750287)
			(xy 19.033784 -309.731621) (xy 19.033236 -309.721504) (xy 12.9921 -309.721504) (xy 12.991682 -309.731658)
			(xy 12.983885 -309.750411) (xy 12.969487 -309.764734) (xy 12.950694 -309.772434) (xy 12.940538 -309.772812)
			(xy 11.540998 -309.772812) (xy 11.530878 -309.772277) (xy 11.512166 -309.764558) (xy 11.497812 -309.750287)
			(xy 11.489984 -309.731621) (xy 11.489436 -309.721504) (xy 2.509012 -309.721504) (xy 2.509012 -310.571388)
			(xy 7.389368 -310.571388) (xy 7.389368 -310.162448) (xy 7.38986 -310.152301) (xy 7.397634 -310.133556)
			(xy 7.412009 -310.119232) (xy 7.430782 -310.111525) (xy 7.44093 -310.11114) (xy 8.84047 -310.11114)
			(xy 8.850595 -310.111651) (xy 8.869315 -310.119369) (xy 8.883673 -310.133648) (xy 8.891493 -310.152326)
			(xy 8.892032 -310.162448) (xy 8.892032 -310.571388) (xy 14.933168 -310.571388) (xy 14.933168 -310.162448)
			(xy 14.93366 -310.152301) (xy 14.941434 -310.133556) (xy 14.955809 -310.119232) (xy 14.974582 -310.111525)
			(xy 14.98473 -310.11114) (xy 16.38427 -310.11114) (xy 16.394395 -310.111651) (xy 16.413115 -310.119369)
			(xy 16.427473 -310.133648) (xy 16.435293 -310.152326) (xy 16.435832 -310.162448) (xy 16.435832 -310.571388)
			(xy 22.476968 -310.571388) (xy 22.476968 -310.162448) (xy 22.47746 -310.152301) (xy 22.485234 -310.133556)
			(xy 22.499609 -310.119232) (xy 22.518382 -310.111525) (xy 22.52853 -310.11114) (xy 23.92807 -310.11114)
			(xy 23.938195 -310.111651) (xy 23.956915 -310.119369) (xy 23.971273 -310.133648) (xy 23.979093 -310.152326)
			(xy 23.979632 -310.162448) (xy 23.979632 -310.571388) (xy 30.020768 -310.571388) (xy 30.020768 -310.162448)
			(xy 30.02126 -310.152301) (xy 30.029034 -310.133556) (xy 30.043409 -310.119232) (xy 30.062182 -310.111525)
			(xy 30.07233 -310.11114) (xy 31.47187 -310.11114) (xy 31.481995 -310.111651) (xy 31.500715 -310.119369)
			(xy 31.515073 -310.133648) (xy 31.522893 -310.152326) (xy 31.523432 -310.162448) (xy 31.523432 -310.571388)
			(xy 37.564568 -310.571388) (xy 37.564568 -310.162448) (xy 37.56506 -310.152301) (xy 37.572834 -310.133556)
			(xy 37.587209 -310.119232) (xy 37.605982 -310.111525) (xy 37.61613 -310.11114) (xy 39.01567 -310.11114)
			(xy 39.025795 -310.111651) (xy 39.044515 -310.119369) (xy 39.058873 -310.133648) (xy 39.066693 -310.152326)
			(xy 39.067232 -310.162448) (xy 39.067232 -310.571388) (xy 45.108368 -310.571388) (xy 45.108368 -310.162448)
			(xy 45.10886 -310.152301) (xy 45.116634 -310.133556) (xy 45.131009 -310.119232) (xy 45.149782 -310.111525)
			(xy 45.15993 -310.11114) (xy 46.55947 -310.11114) (xy 46.569595 -310.111651) (xy 46.588315 -310.119369)
			(xy 46.602673 -310.133648) (xy 46.610493 -310.152326) (xy 46.611032 -310.162448) (xy 46.611032 -310.571388)
			(xy 52.652168 -310.571388) (xy 52.652168 -310.162448) (xy 52.65266 -310.152301) (xy 52.660434 -310.133556)
			(xy 52.674809 -310.119232) (xy 52.693582 -310.111525) (xy 52.70373 -310.11114) (xy 54.10327 -310.11114)
			(xy 54.113395 -310.111651) (xy 54.132115 -310.119369) (xy 54.146473 -310.133648) (xy 54.154293 -310.152326)
			(xy 54.154832 -310.162448) (xy 54.154832 -310.571388) (xy 60.195968 -310.571388) (xy 60.195968 -310.162448)
			(xy 60.19646 -310.152301) (xy 60.204234 -310.133556) (xy 60.218609 -310.119232) (xy 60.237382 -310.111525)
			(xy 60.24753 -310.11114) (xy 61.64707 -310.11114) (xy 61.657195 -310.111651) (xy 61.675915 -310.119369)
			(xy 61.690273 -310.133648) (xy 61.698093 -310.152326) (xy 61.698632 -310.162448) (xy 61.698632 -310.571388)
			(xy 158.062168 -310.571388) (xy 158.062168 -310.162448) (xy 158.06266 -310.152301) (xy 158.070434 -310.133556)
			(xy 158.084809 -310.119232) (xy 158.103582 -310.111525) (xy 158.11373 -310.11114) (xy 159.51327 -310.11114)
			(xy 159.523395 -310.111651) (xy 159.542115 -310.119369) (xy 159.556473 -310.133648) (xy 159.564293 -310.152326)
			(xy 159.564832 -310.162448) (xy 159.564832 -310.571388) (xy 165.605968 -310.571388) (xy 165.605968 -310.162448)
			(xy 165.60646 -310.152301) (xy 165.614234 -310.133556) (xy 165.628609 -310.119232) (xy 165.647382 -310.111525)
			(xy 165.65753 -310.11114) (xy 167.05707 -310.11114) (xy 167.067195 -310.111651) (xy 167.085915 -310.119369)
			(xy 167.100273 -310.133648) (xy 167.108093 -310.152326) (xy 167.108632 -310.162448) (xy 167.108632 -310.571388)
			(xy 173.149768 -310.571388) (xy 173.149768 -310.162448) (xy 173.15026 -310.152301) (xy 173.158034 -310.133556)
			(xy 173.172409 -310.119232) (xy 173.191182 -310.111525) (xy 173.20133 -310.11114) (xy 174.60087 -310.11114)
			(xy 174.610995 -310.111651) (xy 174.629715 -310.119369) (xy 174.644073 -310.133648) (xy 174.651893 -310.152326)
			(xy 174.652432 -310.162448) (xy 174.652432 -310.571388) (xy 180.693568 -310.571388) (xy 180.693568 -310.162448)
			(xy 180.69406 -310.152301) (xy 180.701834 -310.133556) (xy 180.716209 -310.119232) (xy 180.734982 -310.111525)
			(xy 180.74513 -310.11114) (xy 182.14467 -310.11114) (xy 182.154795 -310.111651) (xy 182.173515 -310.119369)
			(xy 182.187873 -310.133648) (xy 182.195693 -310.152326) (xy 182.196232 -310.162448) (xy 182.196232 -310.571388)
			(xy 188.237368 -310.571388) (xy 188.237368 -310.162448) (xy 188.23786 -310.152301) (xy 188.245634 -310.133556)
			(xy 188.260009 -310.119232) (xy 188.278782 -310.111525) (xy 188.28893 -310.11114) (xy 189.68847 -310.11114)
			(xy 189.698595 -310.111651) (xy 189.717315 -310.119369) (xy 189.731673 -310.133648) (xy 189.739493 -310.152326)
			(xy 189.740032 -310.162448) (xy 189.740032 -310.571388) (xy 195.781168 -310.571388) (xy 195.781168 -310.162448)
			(xy 195.78166 -310.152301) (xy 195.789434 -310.133556) (xy 195.803809 -310.119232) (xy 195.822582 -310.111525)
			(xy 195.83273 -310.11114) (xy 197.23227 -310.11114) (xy 197.242395 -310.111651) (xy 197.261115 -310.119369)
			(xy 197.275473 -310.133648) (xy 197.283293 -310.152326) (xy 197.283832 -310.162448) (xy 197.283832 -310.571388)
			(xy 203.324968 -310.571388) (xy 203.324968 -310.162448) (xy 203.32546 -310.152301) (xy 203.333234 -310.133556)
			(xy 203.347609 -310.119232) (xy 203.366382 -310.111525) (xy 203.37653 -310.11114) (xy 204.77607 -310.11114)
			(xy 204.786195 -310.111651) (xy 204.804915 -310.119369) (xy 204.819273 -310.133648) (xy 204.827093 -310.152326)
			(xy 204.827632 -310.162448) (xy 204.827632 -310.571388) (xy 210.868768 -310.571388) (xy 210.868768 -310.162448)
			(xy 210.86926 -310.152301) (xy 210.877034 -310.133556) (xy 210.891409 -310.119232) (xy 210.910182 -310.111525)
			(xy 210.92033 -310.11114) (xy 212.31987 -310.11114) (xy 212.329995 -310.111651) (xy 212.348715 -310.119369)
			(xy 212.363073 -310.133648) (xy 212.370893 -310.152326) (xy 212.371432 -310.162448) (xy 212.371432 -310.571388)
			(xy 255.329436 -310.571388) (xy 255.329436 -310.162448) (xy 255.329862 -310.152293) (xy 255.337648 -310.133534)
			(xy 255.352045 -310.119208) (xy 255.370841 -310.111513) (xy 255.380998 -310.11114) (xy 256.780538 -310.11114)
			(xy 256.790667 -310.111595) (xy 256.809389 -310.119336) (xy 256.823744 -310.133631) (xy 256.831562 -310.152321)
			(xy 256.8321 -310.162448) (xy 256.8321 -310.571388) (xy 262.873236 -310.571388) (xy 262.873236 -310.162448)
			(xy 262.873662 -310.152293) (xy 262.881448 -310.133534) (xy 262.895845 -310.119208) (xy 262.914641 -310.111513)
			(xy 262.924798 -310.11114) (xy 264.324338 -310.11114) (xy 264.334467 -310.111595) (xy 264.353189 -310.119336)
			(xy 264.367544 -310.133631) (xy 264.375362 -310.152321) (xy 264.3759 -310.162448) (xy 264.3759 -310.571388)
			(xy 270.417036 -310.571388) (xy 270.417036 -310.162448) (xy 270.417462 -310.152293) (xy 270.425248 -310.133534)
			(xy 270.439645 -310.119208) (xy 270.458441 -310.111513) (xy 270.468598 -310.11114) (xy 271.868138 -310.11114)
			(xy 271.878267 -310.111595) (xy 271.896989 -310.119336) (xy 271.911344 -310.133631) (xy 271.919162 -310.152321)
			(xy 271.9197 -310.162448) (xy 271.9197 -310.571388) (xy 277.960836 -310.571388) (xy 277.960836 -310.162448)
			(xy 277.961262 -310.152293) (xy 277.969048 -310.133534) (xy 277.983445 -310.119208) (xy 278.002241 -310.111513)
			(xy 278.012398 -310.11114) (xy 279.411938 -310.11114) (xy 279.422067 -310.111595) (xy 279.440789 -310.119336)
			(xy 279.455144 -310.133631) (xy 279.462962 -310.152321) (xy 279.4635 -310.162448) (xy 279.4635 -310.571388)
			(xy 285.504636 -310.571388) (xy 285.504636 -310.162448) (xy 285.505062 -310.152293) (xy 285.512848 -310.133534)
			(xy 285.527245 -310.119208) (xy 285.546041 -310.111513) (xy 285.556198 -310.11114) (xy 286.955738 -310.11114)
			(xy 286.965867 -310.111595) (xy 286.984589 -310.119336) (xy 286.998944 -310.133631) (xy 287.006762 -310.152321)
			(xy 287.0073 -310.162448) (xy 287.0073 -310.571388) (xy 293.048436 -310.571388) (xy 293.048436 -310.162448)
			(xy 293.048862 -310.152293) (xy 293.056648 -310.133534) (xy 293.071045 -310.119208) (xy 293.089841 -310.111513)
			(xy 293.099998 -310.11114) (xy 294.499538 -310.11114) (xy 294.509667 -310.111595) (xy 294.528389 -310.119336)
			(xy 294.542744 -310.133631) (xy 294.550562 -310.152321) (xy 294.5511 -310.162448) (xy 294.5511 -310.571388)
			(xy 300.592236 -310.571388) (xy 300.592236 -310.162448) (xy 300.592662 -310.152293) (xy 300.600448 -310.133534)
			(xy 300.614845 -310.119208) (xy 300.633641 -310.111513) (xy 300.643798 -310.11114) (xy 302.043338 -310.11114)
			(xy 302.053467 -310.111595) (xy 302.072189 -310.119336) (xy 302.086544 -310.133631) (xy 302.094362 -310.152321)
			(xy 302.0949 -310.162448) (xy 302.0949 -310.571388) (xy 308.136036 -310.571388) (xy 308.136036 -310.162448)
			(xy 308.136462 -310.152293) (xy 308.144248 -310.133534) (xy 308.158645 -310.119208) (xy 308.177441 -310.111513)
			(xy 308.187598 -310.11114) (xy 309.587138 -310.11114) (xy 309.597267 -310.111595) (xy 309.615989 -310.119336)
			(xy 309.630344 -310.133631) (xy 309.638162 -310.152321) (xy 309.6387 -310.162448) (xy 309.6387 -310.571388)
			(xy 406.002236 -310.571388) (xy 406.002236 -310.162448) (xy 406.002662 -310.152293) (xy 406.010448 -310.133534)
			(xy 406.024845 -310.119208) (xy 406.043641 -310.111513) (xy 406.053798 -310.11114) (xy 407.453338 -310.11114)
			(xy 407.463467 -310.111595) (xy 407.482189 -310.119336) (xy 407.496544 -310.133631) (xy 407.504362 -310.152321)
			(xy 407.5049 -310.162448) (xy 407.5049 -310.571388) (xy 413.546036 -310.571388) (xy 413.546036 -310.162448)
			(xy 413.546462 -310.152293) (xy 413.554248 -310.133534) (xy 413.568645 -310.119208) (xy 413.587441 -310.111513)
			(xy 413.597598 -310.11114) (xy 414.997138 -310.11114) (xy 415.007267 -310.111595) (xy 415.025989 -310.119336)
			(xy 415.040344 -310.133631) (xy 415.048162 -310.152321) (xy 415.0487 -310.162448) (xy 415.0487 -310.571388)
			(xy 421.089836 -310.571388) (xy 421.089836 -310.162448) (xy 421.090262 -310.152293) (xy 421.098048 -310.133534)
			(xy 421.112445 -310.119208) (xy 421.131241 -310.111513) (xy 421.141398 -310.11114) (xy 422.540938 -310.11114)
			(xy 422.551067 -310.111595) (xy 422.569789 -310.119336) (xy 422.584144 -310.133631) (xy 422.591962 -310.152321)
			(xy 422.5925 -310.162448) (xy 422.5925 -310.571388) (xy 428.633636 -310.571388) (xy 428.633636 -310.162448)
			(xy 428.634062 -310.152293) (xy 428.641848 -310.133534) (xy 428.656245 -310.119208) (xy 428.675041 -310.111513)
			(xy 428.685198 -310.11114) (xy 430.084738 -310.11114) (xy 430.094867 -310.111595) (xy 430.113589 -310.119336)
			(xy 430.127944 -310.133631) (xy 430.135762 -310.152321) (xy 430.1363 -310.162448) (xy 430.1363 -310.571388)
			(xy 436.177436 -310.571388) (xy 436.177436 -310.162448) (xy 436.177862 -310.152293) (xy 436.185648 -310.133534)
			(xy 436.200045 -310.119208) (xy 436.218841 -310.111513) (xy 436.228998 -310.11114) (xy 437.628538 -310.11114)
			(xy 437.638667 -310.111595) (xy 437.657389 -310.119336) (xy 437.671744 -310.133631) (xy 437.679562 -310.152321)
			(xy 437.6801 -310.162448) (xy 437.6801 -310.571388) (xy 443.721236 -310.571388) (xy 443.721236 -310.162448)
			(xy 443.721662 -310.152293) (xy 443.729448 -310.133534) (xy 443.743845 -310.119208) (xy 443.762641 -310.111513)
			(xy 443.772798 -310.11114) (xy 445.172338 -310.11114) (xy 445.182467 -310.111595) (xy 445.201189 -310.119336)
			(xy 445.215544 -310.133631) (xy 445.223362 -310.152321) (xy 445.2239 -310.162448) (xy 445.2239 -310.571388)
			(xy 451.265036 -310.571388) (xy 451.265036 -310.162448) (xy 451.265462 -310.152293) (xy 451.273248 -310.133534)
			(xy 451.287645 -310.119208) (xy 451.306441 -310.111513) (xy 451.316598 -310.11114) (xy 452.716138 -310.11114)
			(xy 452.726267 -310.111595) (xy 452.744989 -310.119336) (xy 452.759344 -310.133631) (xy 452.767162 -310.152321)
			(xy 452.7677 -310.162448) (xy 452.7677 -310.571388) (xy 458.808836 -310.571388) (xy 458.808836 -310.162448)
			(xy 458.809262 -310.152293) (xy 458.817048 -310.133534) (xy 458.831445 -310.119208) (xy 458.850241 -310.111513)
			(xy 458.860398 -310.11114) (xy 460.259938 -310.11114) (xy 460.270067 -310.111595) (xy 460.288789 -310.119336)
			(xy 460.303144 -310.133631) (xy 460.310962 -310.152321) (xy 460.3115 -310.162448) (xy 460.3115 -310.571388)
			(xy 460.311069 -310.581541) (xy 460.303277 -310.600293) (xy 460.288883 -310.614617) (xy 460.270093 -310.622317)
			(xy 460.259938 -310.622696) (xy 458.860398 -310.622696) (xy 458.850276 -310.622176) (xy 458.831561 -310.614454)
			(xy 458.817206 -310.600179) (xy 458.809381 -310.581508) (xy 458.808836 -310.571388) (xy 452.7677 -310.571388)
			(xy 452.767269 -310.581541) (xy 452.759477 -310.600293) (xy 452.745083 -310.614617) (xy 452.726293 -310.622317)
			(xy 452.716138 -310.622696) (xy 451.316598 -310.622696) (xy 451.306476 -310.622176) (xy 451.287761 -310.614454)
			(xy 451.273406 -310.600179) (xy 451.265581 -310.581508) (xy 451.265036 -310.571388) (xy 445.2239 -310.571388)
			(xy 445.223469 -310.581541) (xy 445.215677 -310.600293) (xy 445.201283 -310.614617) (xy 445.182493 -310.622317)
			(xy 445.172338 -310.622696) (xy 443.772798 -310.622696) (xy 443.762676 -310.622176) (xy 443.743961 -310.614454)
			(xy 443.729606 -310.600179) (xy 443.721781 -310.581508) (xy 443.721236 -310.571388) (xy 437.6801 -310.571388)
			(xy 437.679669 -310.581541) (xy 437.671877 -310.600293) (xy 437.657483 -310.614617) (xy 437.638693 -310.622317)
			(xy 437.628538 -310.622696) (xy 436.228998 -310.622696) (xy 436.218876 -310.622176) (xy 436.200161 -310.614454)
			(xy 436.185806 -310.600179) (xy 436.177981 -310.581508) (xy 436.177436 -310.571388) (xy 430.1363 -310.571388)
			(xy 430.135869 -310.581541) (xy 430.128077 -310.600293) (xy 430.113683 -310.614617) (xy 430.094893 -310.622317)
			(xy 430.084738 -310.622696) (xy 428.685198 -310.622696) (xy 428.675076 -310.622176) (xy 428.656361 -310.614454)
			(xy 428.642006 -310.600179) (xy 428.634181 -310.581508) (xy 428.633636 -310.571388) (xy 422.5925 -310.571388)
			(xy 422.592069 -310.581541) (xy 422.584277 -310.600293) (xy 422.569883 -310.614617) (xy 422.551093 -310.622317)
			(xy 422.540938 -310.622696) (xy 421.141398 -310.622696) (xy 421.131276 -310.622176) (xy 421.112561 -310.614454)
			(xy 421.098206 -310.600179) (xy 421.090381 -310.581508) (xy 421.089836 -310.571388) (xy 415.0487 -310.571388)
			(xy 415.048269 -310.581541) (xy 415.040477 -310.600293) (xy 415.026083 -310.614617) (xy 415.007293 -310.622317)
			(xy 414.997138 -310.622696) (xy 413.597598 -310.622696) (xy 413.587476 -310.622176) (xy 413.568761 -310.614454)
			(xy 413.554406 -310.600179) (xy 413.546581 -310.581508) (xy 413.546036 -310.571388) (xy 407.5049 -310.571388)
			(xy 407.504469 -310.581541) (xy 407.496677 -310.600293) (xy 407.482283 -310.614617) (xy 407.463493 -310.622317)
			(xy 407.453338 -310.622696) (xy 406.053798 -310.622696) (xy 406.043676 -310.622176) (xy 406.024961 -310.614454)
			(xy 406.010606 -310.600179) (xy 406.002781 -310.581508) (xy 406.002236 -310.571388) (xy 309.6387 -310.571388)
			(xy 309.638269 -310.581541) (xy 309.630477 -310.600293) (xy 309.616083 -310.614617) (xy 309.597293 -310.622317)
			(xy 309.587138 -310.622696) (xy 308.187598 -310.622696) (xy 308.177476 -310.622176) (xy 308.158761 -310.614454)
			(xy 308.144406 -310.600179) (xy 308.136581 -310.581508) (xy 308.136036 -310.571388) (xy 302.0949 -310.571388)
			(xy 302.094469 -310.581541) (xy 302.086677 -310.600293) (xy 302.072283 -310.614617) (xy 302.053493 -310.622317)
			(xy 302.043338 -310.622696) (xy 300.643798 -310.622696) (xy 300.633676 -310.622176) (xy 300.614961 -310.614454)
			(xy 300.600606 -310.600179) (xy 300.592781 -310.581508) (xy 300.592236 -310.571388) (xy 294.5511 -310.571388)
			(xy 294.550669 -310.581541) (xy 294.542877 -310.600293) (xy 294.528483 -310.614617) (xy 294.509693 -310.622317)
			(xy 294.499538 -310.622696) (xy 293.099998 -310.622696) (xy 293.089876 -310.622176) (xy 293.071161 -310.614454)
			(xy 293.056806 -310.600179) (xy 293.048981 -310.581508) (xy 293.048436 -310.571388) (xy 287.0073 -310.571388)
			(xy 287.006869 -310.581541) (xy 286.999077 -310.600293) (xy 286.984683 -310.614617) (xy 286.965893 -310.622317)
			(xy 286.955738 -310.622696) (xy 285.556198 -310.622696) (xy 285.546076 -310.622176) (xy 285.527361 -310.614454)
			(xy 285.513006 -310.600179) (xy 285.505181 -310.581508) (xy 285.504636 -310.571388) (xy 279.4635 -310.571388)
			(xy 279.463069 -310.581541) (xy 279.455277 -310.600293) (xy 279.440883 -310.614617) (xy 279.422093 -310.622317)
			(xy 279.411938 -310.622696) (xy 278.012398 -310.622696) (xy 278.002276 -310.622176) (xy 277.983561 -310.614454)
			(xy 277.969206 -310.600179) (xy 277.961381 -310.581508) (xy 277.960836 -310.571388) (xy 271.9197 -310.571388)
			(xy 271.919269 -310.581541) (xy 271.911477 -310.600293) (xy 271.897083 -310.614617) (xy 271.878293 -310.622317)
			(xy 271.868138 -310.622696) (xy 270.468598 -310.622696) (xy 270.458476 -310.622176) (xy 270.439761 -310.614454)
			(xy 270.425406 -310.600179) (xy 270.417581 -310.581508) (xy 270.417036 -310.571388) (xy 264.3759 -310.571388)
			(xy 264.375469 -310.581541) (xy 264.367677 -310.600293) (xy 264.353283 -310.614617) (xy 264.334493 -310.622317)
			(xy 264.324338 -310.622696) (xy 262.924798 -310.622696) (xy 262.914676 -310.622176) (xy 262.895961 -310.614454)
			(xy 262.881606 -310.600179) (xy 262.873781 -310.581508) (xy 262.873236 -310.571388) (xy 256.8321 -310.571388)
			(xy 256.831669 -310.581541) (xy 256.823877 -310.600293) (xy 256.809483 -310.614617) (xy 256.790693 -310.622317)
			(xy 256.780538 -310.622696) (xy 255.380998 -310.622696) (xy 255.370876 -310.622176) (xy 255.352161 -310.614454)
			(xy 255.337806 -310.600179) (xy 255.329981 -310.581508) (xy 255.329436 -310.571388) (xy 212.371432 -310.571388)
			(xy 212.370969 -310.581537) (xy 212.363184 -310.600283) (xy 212.3488 -310.614606) (xy 212.330021 -310.622312)
			(xy 212.31987 -310.622696) (xy 210.92033 -310.622696) (xy 210.91021 -310.62215) (xy 210.891496 -310.614439)
			(xy 210.87714 -310.600171) (xy 210.869313 -310.581505) (xy 210.868768 -310.571388) (xy 204.827632 -310.571388)
			(xy 204.827169 -310.581537) (xy 204.819384 -310.600283) (xy 204.805 -310.614606) (xy 204.786221 -310.622312)
			(xy 204.77607 -310.622696) (xy 203.37653 -310.622696) (xy 203.36641 -310.62215) (xy 203.347696 -310.614439)
			(xy 203.33334 -310.600171) (xy 203.325513 -310.581505) (xy 203.324968 -310.571388) (xy 197.283832 -310.571388)
			(xy 197.283369 -310.581537) (xy 197.275584 -310.600283) (xy 197.2612 -310.614606) (xy 197.242421 -310.622312)
			(xy 197.23227 -310.622696) (xy 195.83273 -310.622696) (xy 195.82261 -310.62215) (xy 195.803896 -310.614439)
			(xy 195.78954 -310.600171) (xy 195.781713 -310.581505) (xy 195.781168 -310.571388) (xy 189.740032 -310.571388)
			(xy 189.739569 -310.581537) (xy 189.731784 -310.600283) (xy 189.7174 -310.614606) (xy 189.698621 -310.622312)
			(xy 189.68847 -310.622696) (xy 188.28893 -310.622696) (xy 188.27881 -310.62215) (xy 188.260096 -310.614439)
			(xy 188.24574 -310.600171) (xy 188.237913 -310.581505) (xy 188.237368 -310.571388) (xy 182.196232 -310.571388)
			(xy 182.195769 -310.581537) (xy 182.187984 -310.600283) (xy 182.1736 -310.614606) (xy 182.154821 -310.622312)
			(xy 182.14467 -310.622696) (xy 180.74513 -310.622696) (xy 180.73501 -310.62215) (xy 180.716296 -310.614439)
			(xy 180.70194 -310.600171) (xy 180.694113 -310.581505) (xy 180.693568 -310.571388) (xy 174.652432 -310.571388)
			(xy 174.651969 -310.581537) (xy 174.644184 -310.600283) (xy 174.6298 -310.614606) (xy 174.611021 -310.622312)
			(xy 174.60087 -310.622696) (xy 173.20133 -310.622696) (xy 173.19121 -310.62215) (xy 173.172496 -310.614439)
			(xy 173.15814 -310.600171) (xy 173.150313 -310.581505) (xy 173.149768 -310.571388) (xy 167.108632 -310.571388)
			(xy 167.108169 -310.581537) (xy 167.100384 -310.600283) (xy 167.086 -310.614606) (xy 167.067221 -310.622312)
			(xy 167.05707 -310.622696) (xy 165.65753 -310.622696) (xy 165.64741 -310.62215) (xy 165.628696 -310.614439)
			(xy 165.61434 -310.600171) (xy 165.606513 -310.581505) (xy 165.605968 -310.571388) (xy 159.564832 -310.571388)
			(xy 159.564369 -310.581537) (xy 159.556584 -310.600283) (xy 159.5422 -310.614606) (xy 159.523421 -310.622312)
			(xy 159.51327 -310.622696) (xy 158.11373 -310.622696) (xy 158.10361 -310.62215) (xy 158.084896 -310.614439)
			(xy 158.07054 -310.600171) (xy 158.062713 -310.581505) (xy 158.062168 -310.571388) (xy 61.698632 -310.571388)
			(xy 61.698169 -310.581537) (xy 61.690384 -310.600283) (xy 61.676 -310.614606) (xy 61.657221 -310.622312)
			(xy 61.64707 -310.622696) (xy 60.24753 -310.622696) (xy 60.23741 -310.62215) (xy 60.218696 -310.614439)
			(xy 60.20434 -310.600171) (xy 60.196513 -310.581505) (xy 60.195968 -310.571388) (xy 54.154832 -310.571388)
			(xy 54.154369 -310.581537) (xy 54.146584 -310.600283) (xy 54.1322 -310.614606) (xy 54.113421 -310.622312)
			(xy 54.10327 -310.622696) (xy 52.70373 -310.622696) (xy 52.69361 -310.62215) (xy 52.674896 -310.614439)
			(xy 52.66054 -310.600171) (xy 52.652713 -310.581505) (xy 52.652168 -310.571388) (xy 46.611032 -310.571388)
			(xy 46.610569 -310.581537) (xy 46.602784 -310.600283) (xy 46.5884 -310.614606) (xy 46.569621 -310.622312)
			(xy 46.55947 -310.622696) (xy 45.15993 -310.622696) (xy 45.14981 -310.62215) (xy 45.131096 -310.614439)
			(xy 45.11674 -310.600171) (xy 45.108913 -310.581505) (xy 45.108368 -310.571388) (xy 39.067232 -310.571388)
			(xy 39.066769 -310.581537) (xy 39.058984 -310.600283) (xy 39.0446 -310.614606) (xy 39.025821 -310.622312)
			(xy 39.01567 -310.622696) (xy 37.61613 -310.622696) (xy 37.60601 -310.62215) (xy 37.587296 -310.614439)
			(xy 37.57294 -310.600171) (xy 37.565113 -310.581505) (xy 37.564568 -310.571388) (xy 31.523432 -310.571388)
			(xy 31.522969 -310.581537) (xy 31.515184 -310.600283) (xy 31.5008 -310.614606) (xy 31.482021 -310.622312)
			(xy 31.47187 -310.622696) (xy 30.07233 -310.622696) (xy 30.06221 -310.62215) (xy 30.043496 -310.614439)
			(xy 30.02914 -310.600171) (xy 30.021313 -310.581505) (xy 30.020768 -310.571388) (xy 23.979632 -310.571388)
			(xy 23.979169 -310.581537) (xy 23.971384 -310.600283) (xy 23.957 -310.614606) (xy 23.938221 -310.622312)
			(xy 23.92807 -310.622696) (xy 22.52853 -310.622696) (xy 22.51841 -310.62215) (xy 22.499696 -310.614439)
			(xy 22.48534 -310.600171) (xy 22.477513 -310.581505) (xy 22.476968 -310.571388) (xy 16.435832 -310.571388)
			(xy 16.435369 -310.581537) (xy 16.427584 -310.600283) (xy 16.4132 -310.614606) (xy 16.394421 -310.622312)
			(xy 16.38427 -310.622696) (xy 14.98473 -310.622696) (xy 14.97461 -310.62215) (xy 14.955896 -310.614439)
			(xy 14.94154 -310.600171) (xy 14.933713 -310.581505) (xy 14.933168 -310.571388) (xy 8.892032 -310.571388)
			(xy 8.891569 -310.581537) (xy 8.883784 -310.600283) (xy 8.8694 -310.614606) (xy 8.850621 -310.622312)
			(xy 8.84047 -310.622696) (xy 7.44093 -310.622696) (xy 7.43081 -310.62215) (xy 7.412096 -310.614439)
			(xy 7.39774 -310.600171) (xy 7.389913 -310.581505) (xy 7.389368 -310.571388) (xy 2.509012 -310.571388)
			(xy 2.509012 -311.421526) (xy 11.489436 -311.421526) (xy 11.489436 -311.012586) (xy 11.489922 -311.002428)
			(xy 11.497701 -310.983659) (xy 11.512069 -310.969294) (xy 11.53084 -310.96152) (xy 11.540998 -310.961024)
			(xy 12.940538 -310.961024) (xy 12.950696 -310.961502) (xy 12.969464 -310.969286) (xy 12.983827 -310.983656)
			(xy 12.991603 -311.002427) (xy 12.9921 -311.012586) (xy 12.9921 -311.421526) (xy 19.033236 -311.421526)
			(xy 19.033236 -311.012586) (xy 19.033722 -311.002428) (xy 19.041501 -310.983659) (xy 19.055869 -310.969294)
			(xy 19.07464 -310.96152) (xy 19.084798 -310.961024) (xy 20.484338 -310.961024) (xy 20.494496 -310.961502)
			(xy 20.513264 -310.969286) (xy 20.527627 -310.983656) (xy 20.535403 -311.002427) (xy 20.5359 -311.012586)
			(xy 20.5359 -311.421526) (xy 26.577036 -311.421526) (xy 26.577036 -311.012586) (xy 26.577522 -311.002428)
			(xy 26.585301 -310.983659) (xy 26.599669 -310.969294) (xy 26.61844 -310.96152) (xy 26.628598 -310.961024)
			(xy 28.028138 -310.961024) (xy 28.038296 -310.961502) (xy 28.057064 -310.969286) (xy 28.071427 -310.983656)
			(xy 28.079203 -311.002427) (xy 28.0797 -311.012586) (xy 28.0797 -311.421526) (xy 34.120836 -311.421526)
			(xy 34.120836 -311.012586) (xy 34.121322 -311.002428) (xy 34.129101 -310.983659) (xy 34.143469 -310.969294)
			(xy 34.16224 -310.96152) (xy 34.172398 -310.961024) (xy 35.571938 -310.961024) (xy 35.582096 -310.961502)
			(xy 35.600864 -310.969286) (xy 35.615227 -310.983656) (xy 35.623003 -311.002427) (xy 35.6235 -311.012586)
			(xy 35.6235 -311.421526) (xy 41.664636 -311.421526) (xy 41.664636 -311.012586) (xy 41.665122 -311.002428)
			(xy 41.672901 -310.983659) (xy 41.687269 -310.969294) (xy 41.70604 -310.96152) (xy 41.716198 -310.961024)
			(xy 43.115738 -310.961024) (xy 43.125896 -310.961502) (xy 43.144664 -310.969286) (xy 43.159027 -310.983656)
			(xy 43.166803 -311.002427) (xy 43.1673 -311.012586) (xy 43.1673 -311.421526) (xy 49.208436 -311.421526)
			(xy 49.208436 -311.012586) (xy 49.208922 -311.002428) (xy 49.216701 -310.983659) (xy 49.231069 -310.969294)
			(xy 49.24984 -310.96152) (xy 49.259998 -310.961024) (xy 50.659538 -310.961024) (xy 50.669696 -310.961502)
			(xy 50.688464 -310.969286) (xy 50.702827 -310.983656) (xy 50.710603 -311.002427) (xy 50.7111 -311.012586)
			(xy 50.7111 -311.421526) (xy 56.752236 -311.421526) (xy 56.752236 -311.012586) (xy 56.752722 -311.002428)
			(xy 56.760501 -310.983659) (xy 56.774869 -310.969294) (xy 56.79364 -310.96152) (xy 56.803798 -310.961024)
			(xy 58.203338 -310.961024) (xy 58.213496 -310.961502) (xy 58.232264 -310.969286) (xy 58.246627 -310.983656)
			(xy 58.254403 -311.002427) (xy 58.2549 -311.012586) (xy 58.2549 -311.421526) (xy 64.296036 -311.421526)
			(xy 64.296036 -311.012586) (xy 64.296522 -311.002428) (xy 64.304301 -310.983659) (xy 64.318669 -310.969294)
			(xy 64.33744 -310.96152) (xy 64.347598 -310.961024) (xy 65.747138 -310.961024) (xy 65.757296 -310.961502)
			(xy 65.776064 -310.969286) (xy 65.790427 -310.983656) (xy 65.798203 -311.002427) (xy 65.7987 -311.012586)
			(xy 65.7987 -311.421526) (xy 162.162236 -311.421526) (xy 162.162236 -311.012586) (xy 162.162722 -311.002428)
			(xy 162.170501 -310.983659) (xy 162.184869 -310.969294) (xy 162.20364 -310.96152) (xy 162.213798 -310.961024)
			(xy 163.613338 -310.961024) (xy 163.623496 -310.961502) (xy 163.642264 -310.969286) (xy 163.656627 -310.983656)
			(xy 163.664403 -311.002427) (xy 163.6649 -311.012586) (xy 163.6649 -311.421526) (xy 169.706036 -311.421526)
			(xy 169.706036 -311.012586) (xy 169.706522 -311.002428) (xy 169.714301 -310.983659) (xy 169.728669 -310.969294)
			(xy 169.74744 -310.96152) (xy 169.757598 -310.961024) (xy 171.157138 -310.961024) (xy 171.167296 -310.961502)
			(xy 171.186064 -310.969286) (xy 171.200427 -310.983656) (xy 171.208203 -311.002427) (xy 171.2087 -311.012586)
			(xy 171.2087 -311.421526) (xy 177.249836 -311.421526) (xy 177.249836 -311.012586) (xy 177.250322 -311.002428)
			(xy 177.258101 -310.983659) (xy 177.272469 -310.969294) (xy 177.29124 -310.96152) (xy 177.301398 -310.961024)
			(xy 178.700938 -310.961024) (xy 178.711096 -310.961502) (xy 178.729864 -310.969286) (xy 178.744227 -310.983656)
			(xy 178.752003 -311.002427) (xy 178.7525 -311.012586) (xy 178.7525 -311.421526) (xy 184.793636 -311.421526)
			(xy 184.793636 -311.012586) (xy 184.794122 -311.002428) (xy 184.801901 -310.983659) (xy 184.816269 -310.969294)
			(xy 184.83504 -310.96152) (xy 184.845198 -310.961024) (xy 186.244738 -310.961024) (xy 186.254896 -310.961502)
			(xy 186.273664 -310.969286) (xy 186.288027 -310.983656) (xy 186.295803 -311.002427) (xy 186.2963 -311.012586)
			(xy 186.2963 -311.421526) (xy 192.337436 -311.421526) (xy 192.337436 -311.012586) (xy 192.337922 -311.002428)
			(xy 192.345701 -310.983659) (xy 192.360069 -310.969294) (xy 192.37884 -310.96152) (xy 192.388998 -310.961024)
			(xy 193.788538 -310.961024) (xy 193.798696 -310.961502) (xy 193.817464 -310.969286) (xy 193.831827 -310.983656)
			(xy 193.839603 -311.002427) (xy 193.8401 -311.012586) (xy 193.8401 -311.421526) (xy 199.881236 -311.421526)
			(xy 199.881236 -311.012586) (xy 199.881722 -311.002428) (xy 199.889501 -310.983659) (xy 199.903869 -310.969294)
			(xy 199.92264 -310.96152) (xy 199.932798 -310.961024) (xy 201.332338 -310.961024) (xy 201.342496 -310.961502)
			(xy 201.361264 -310.969286) (xy 201.375627 -310.983656) (xy 201.383403 -311.002427) (xy 201.3839 -311.012586)
			(xy 201.3839 -311.421526) (xy 207.425036 -311.421526) (xy 207.425036 -311.012586) (xy 207.425522 -311.002428)
			(xy 207.433301 -310.983659) (xy 207.447669 -310.969294) (xy 207.46644 -310.96152) (xy 207.476598 -310.961024)
			(xy 208.876138 -310.961024) (xy 208.886296 -310.961502) (xy 208.905064 -310.969286) (xy 208.919427 -310.983656)
			(xy 208.927203 -311.002427) (xy 208.9277 -311.012586) (xy 208.9277 -311.421526) (xy 214.968836 -311.421526)
			(xy 214.968836 -311.012586) (xy 214.969322 -311.002428) (xy 214.977101 -310.983659) (xy 214.991469 -310.969294)
			(xy 215.01024 -310.96152) (xy 215.020398 -310.961024) (xy 216.419938 -310.961024) (xy 216.430096 -310.961502)
			(xy 216.448864 -310.969286) (xy 216.463227 -310.983656) (xy 216.471003 -311.002427) (xy 216.4715 -311.012586)
			(xy 216.4715 -311.421526) (xy 259.429504 -311.421526) (xy 259.429504 -311.012586) (xy 259.430021 -311.002432)
			(xy 259.437794 -310.983669) (xy 259.452152 -310.969305) (xy 259.470912 -310.961525) (xy 259.481066 -310.961024)
			(xy 260.880606 -310.961024) (xy 260.890762 -310.961528) (xy 260.909529 -310.969302) (xy 260.923893 -310.983664)
			(xy 260.93167 -311.00243) (xy 260.932168 -311.012586) (xy 260.932168 -311.421526) (xy 266.973304 -311.421526)
			(xy 266.973304 -311.012586) (xy 266.973821 -311.002432) (xy 266.981594 -310.983669) (xy 266.995952 -310.969305)
			(xy 267.014712 -310.961525) (xy 267.024866 -310.961024) (xy 268.424406 -310.961024) (xy 268.434562 -310.961528)
			(xy 268.453329 -310.969302) (xy 268.467693 -310.983664) (xy 268.47547 -311.00243) (xy 268.475968 -311.012586)
			(xy 268.475968 -311.421526) (xy 274.517104 -311.421526) (xy 274.517104 -311.012586) (xy 274.517621 -311.002432)
			(xy 274.525394 -310.983669) (xy 274.539752 -310.969305) (xy 274.558512 -310.961525) (xy 274.568666 -310.961024)
			(xy 275.968206 -310.961024) (xy 275.978362 -310.961528) (xy 275.997129 -310.969302) (xy 276.011493 -310.983664)
			(xy 276.01927 -311.00243) (xy 276.019768 -311.012586) (xy 276.019768 -311.421526) (xy 282.060904 -311.421526)
			(xy 282.060904 -311.012586) (xy 282.061421 -311.002432) (xy 282.069194 -310.983669) (xy 282.083552 -310.969305)
			(xy 282.102312 -310.961525) (xy 282.112466 -310.961024) (xy 283.512006 -310.961024) (xy 283.522162 -310.961528)
			(xy 283.540929 -310.969302) (xy 283.555293 -310.983664) (xy 283.56307 -311.00243) (xy 283.563568 -311.012586)
			(xy 283.563568 -311.421526) (xy 289.604704 -311.421526) (xy 289.604704 -311.012586) (xy 289.605221 -311.002432)
			(xy 289.612994 -310.983669) (xy 289.627352 -310.969305) (xy 289.646112 -310.961525) (xy 289.656266 -310.961024)
			(xy 291.055806 -310.961024) (xy 291.065962 -310.961528) (xy 291.084729 -310.969302) (xy 291.099093 -310.983664)
			(xy 291.10687 -311.00243) (xy 291.107368 -311.012586) (xy 291.107368 -311.421526) (xy 297.148504 -311.421526)
			(xy 297.148504 -311.012586) (xy 297.149021 -311.002432) (xy 297.156794 -310.983669) (xy 297.171152 -310.969305)
			(xy 297.189912 -310.961525) (xy 297.200066 -310.961024) (xy 298.599606 -310.961024) (xy 298.609762 -310.961528)
			(xy 298.628529 -310.969302) (xy 298.642893 -310.983664) (xy 298.65067 -311.00243) (xy 298.651168 -311.012586)
			(xy 298.651168 -311.421526) (xy 304.692304 -311.421526) (xy 304.692304 -311.012586) (xy 304.692821 -311.002432)
			(xy 304.700594 -310.983669) (xy 304.714952 -310.969305) (xy 304.733712 -310.961525) (xy 304.743866 -310.961024)
			(xy 306.143406 -310.961024) (xy 306.153562 -310.961528) (xy 306.172329 -310.969302) (xy 306.186693 -310.983664)
			(xy 306.19447 -311.00243) (xy 306.194968 -311.012586) (xy 306.194968 -311.421526) (xy 312.236104 -311.421526)
			(xy 312.236104 -311.012586) (xy 312.236621 -311.002432) (xy 312.244394 -310.983669) (xy 312.258752 -310.969305)
			(xy 312.277512 -310.961525) (xy 312.287666 -310.961024) (xy 313.687206 -310.961024) (xy 313.697362 -310.961528)
			(xy 313.716129 -310.969302) (xy 313.730493 -310.983664) (xy 313.73827 -311.00243) (xy 313.738768 -311.012586)
			(xy 313.738768 -311.421526) (xy 410.102304 -311.421526) (xy 410.102304 -311.012586) (xy 410.102821 -311.002432)
			(xy 410.110594 -310.983669) (xy 410.124952 -310.969305) (xy 410.143712 -310.961525) (xy 410.153866 -310.961024)
			(xy 411.553406 -310.961024) (xy 411.563562 -310.961528) (xy 411.582329 -310.969302) (xy 411.596693 -310.983664)
			(xy 411.60447 -311.00243) (xy 411.604968 -311.012586) (xy 411.604968 -311.421526) (xy 417.646104 -311.421526)
			(xy 417.646104 -311.012586) (xy 417.646621 -311.002432) (xy 417.654394 -310.983669) (xy 417.668752 -310.969305)
			(xy 417.687512 -310.961525) (xy 417.697666 -310.961024) (xy 419.097206 -310.961024) (xy 419.107362 -310.961528)
			(xy 419.126129 -310.969302) (xy 419.140493 -310.983664) (xy 419.14827 -311.00243) (xy 419.148768 -311.012586)
			(xy 419.148768 -311.421526) (xy 425.189904 -311.421526) (xy 425.189904 -311.012586) (xy 425.190421 -311.002432)
			(xy 425.198194 -310.983669) (xy 425.212552 -310.969305) (xy 425.231312 -310.961525) (xy 425.241466 -310.961024)
			(xy 426.641006 -310.961024) (xy 426.651162 -310.961528) (xy 426.669929 -310.969302) (xy 426.684293 -310.983664)
			(xy 426.69207 -311.00243) (xy 426.692568 -311.012586) (xy 426.692568 -311.421526) (xy 432.733704 -311.421526)
			(xy 432.733704 -311.012586) (xy 432.734221 -311.002432) (xy 432.741994 -310.983669) (xy 432.756352 -310.969305)
			(xy 432.775112 -310.961525) (xy 432.785266 -310.961024) (xy 434.184806 -310.961024) (xy 434.194962 -310.961528)
			(xy 434.213729 -310.969302) (xy 434.228093 -310.983664) (xy 434.23587 -311.00243) (xy 434.236368 -311.012586)
			(xy 434.236368 -311.421526) (xy 440.277504 -311.421526) (xy 440.277504 -311.012586) (xy 440.278021 -311.002432)
			(xy 440.285794 -310.983669) (xy 440.300152 -310.969305) (xy 440.318912 -310.961525) (xy 440.329066 -310.961024)
			(xy 441.728606 -310.961024) (xy 441.738762 -310.961528) (xy 441.757529 -310.969302) (xy 441.771893 -310.983664)
			(xy 441.77967 -311.00243) (xy 441.780168 -311.012586) (xy 441.780168 -311.421526) (xy 447.821304 -311.421526)
			(xy 447.821304 -311.012586) (xy 447.821821 -311.002432) (xy 447.829594 -310.983669) (xy 447.843952 -310.969305)
			(xy 447.862712 -310.961525) (xy 447.872866 -310.961024) (xy 449.272406 -310.961024) (xy 449.282562 -310.961528)
			(xy 449.301329 -310.969302) (xy 449.315693 -310.983664) (xy 449.32347 -311.00243) (xy 449.323968 -311.012586)
			(xy 449.323968 -311.421526) (xy 455.365104 -311.421526) (xy 455.365104 -311.012586) (xy 455.365621 -311.002432)
			(xy 455.373394 -310.983669) (xy 455.387752 -310.969305) (xy 455.406512 -310.961525) (xy 455.416666 -310.961024)
			(xy 456.816206 -310.961024) (xy 456.826362 -310.961528) (xy 456.845129 -310.969302) (xy 456.859493 -310.983664)
			(xy 456.86727 -311.00243) (xy 456.867768 -311.012586) (xy 456.867768 -311.421526) (xy 462.908904 -311.421526)
			(xy 462.908904 -311.012586) (xy 462.909421 -311.002432) (xy 462.917194 -310.983669) (xy 462.931552 -310.969305)
			(xy 462.950312 -310.961525) (xy 462.960466 -310.961024) (xy 464.360006 -310.961024) (xy 464.370162 -310.961528)
			(xy 464.388929 -310.969302) (xy 464.403293 -310.983664) (xy 464.41107 -311.00243) (xy 464.411568 -311.012586)
			(xy 464.411568 -311.421526) (xy 464.411088 -311.431685) (xy 464.403306 -311.450453) (xy 464.388937 -311.464818)
			(xy 464.370165 -311.472592) (xy 464.360006 -311.473088) (xy 462.960466 -311.473088) (xy 462.950309 -311.472595)
			(xy 462.931544 -311.464814) (xy 462.917181 -311.450449) (xy 462.909403 -311.431683) (xy 462.908904 -311.421526)
			(xy 456.867768 -311.421526) (xy 456.867288 -311.431685) (xy 456.859506 -311.450453) (xy 456.845137 -311.464818)
			(xy 456.826365 -311.472592) (xy 456.816206 -311.473088) (xy 455.416666 -311.473088) (xy 455.406509 -311.472595)
			(xy 455.387744 -311.464814) (xy 455.373381 -311.450449) (xy 455.365603 -311.431683) (xy 455.365104 -311.421526)
			(xy 449.323968 -311.421526) (xy 449.323488 -311.431685) (xy 449.315706 -311.450453) (xy 449.301337 -311.464818)
			(xy 449.282565 -311.472592) (xy 449.272406 -311.473088) (xy 447.872866 -311.473088) (xy 447.862709 -311.472595)
			(xy 447.843944 -311.464814) (xy 447.829581 -311.450449) (xy 447.821803 -311.431683) (xy 447.821304 -311.421526)
			(xy 441.780168 -311.421526) (xy 441.779688 -311.431685) (xy 441.771906 -311.450453) (xy 441.757537 -311.464818)
			(xy 441.738765 -311.472592) (xy 441.728606 -311.473088) (xy 440.329066 -311.473088) (xy 440.318909 -311.472595)
			(xy 440.300144 -311.464814) (xy 440.285781 -311.450449) (xy 440.278003 -311.431683) (xy 440.277504 -311.421526)
			(xy 434.236368 -311.421526) (xy 434.235888 -311.431685) (xy 434.228106 -311.450453) (xy 434.213737 -311.464818)
			(xy 434.194965 -311.472592) (xy 434.184806 -311.473088) (xy 432.785266 -311.473088) (xy 432.775109 -311.472595)
			(xy 432.756344 -311.464814) (xy 432.741981 -311.450449) (xy 432.734203 -311.431683) (xy 432.733704 -311.421526)
			(xy 426.692568 -311.421526) (xy 426.692088 -311.431685) (xy 426.684306 -311.450453) (xy 426.669937 -311.464818)
			(xy 426.651165 -311.472592) (xy 426.641006 -311.473088) (xy 425.241466 -311.473088) (xy 425.231309 -311.472595)
			(xy 425.212544 -311.464814) (xy 425.198181 -311.450449) (xy 425.190403 -311.431683) (xy 425.189904 -311.421526)
			(xy 419.148768 -311.421526) (xy 419.148288 -311.431685) (xy 419.140506 -311.450453) (xy 419.126137 -311.464818)
			(xy 419.107365 -311.472592) (xy 419.097206 -311.473088) (xy 417.697666 -311.473088) (xy 417.687509 -311.472595)
			(xy 417.668744 -311.464814) (xy 417.654381 -311.450449) (xy 417.646603 -311.431683) (xy 417.646104 -311.421526)
			(xy 411.604968 -311.421526) (xy 411.604488 -311.431685) (xy 411.596706 -311.450453) (xy 411.582337 -311.464818)
			(xy 411.563565 -311.472592) (xy 411.553406 -311.473088) (xy 410.153866 -311.473088) (xy 410.143709 -311.472595)
			(xy 410.124944 -311.464814) (xy 410.110581 -311.450449) (xy 410.102803 -311.431683) (xy 410.102304 -311.421526)
			(xy 313.738768 -311.421526) (xy 313.738288 -311.431685) (xy 313.730506 -311.450453) (xy 313.716137 -311.464818)
			(xy 313.697365 -311.472592) (xy 313.687206 -311.473088) (xy 312.287666 -311.473088) (xy 312.277509 -311.472595)
			(xy 312.258744 -311.464814) (xy 312.244381 -311.450449) (xy 312.236603 -311.431683) (xy 312.236104 -311.421526)
			(xy 306.194968 -311.421526) (xy 306.194488 -311.431685) (xy 306.186706 -311.450453) (xy 306.172337 -311.464818)
			(xy 306.153565 -311.472592) (xy 306.143406 -311.473088) (xy 304.743866 -311.473088) (xy 304.733709 -311.472595)
			(xy 304.714944 -311.464814) (xy 304.700581 -311.450449) (xy 304.692803 -311.431683) (xy 304.692304 -311.421526)
			(xy 298.651168 -311.421526) (xy 298.650688 -311.431685) (xy 298.642906 -311.450453) (xy 298.628537 -311.464818)
			(xy 298.609765 -311.472592) (xy 298.599606 -311.473088) (xy 297.200066 -311.473088) (xy 297.189909 -311.472595)
			(xy 297.171144 -311.464814) (xy 297.156781 -311.450449) (xy 297.149003 -311.431683) (xy 297.148504 -311.421526)
			(xy 291.107368 -311.421526) (xy 291.106888 -311.431685) (xy 291.099106 -311.450453) (xy 291.084737 -311.464818)
			(xy 291.065965 -311.472592) (xy 291.055806 -311.473088) (xy 289.656266 -311.473088) (xy 289.646109 -311.472595)
			(xy 289.627344 -311.464814) (xy 289.612981 -311.450449) (xy 289.605203 -311.431683) (xy 289.604704 -311.421526)
			(xy 283.563568 -311.421526) (xy 283.563088 -311.431685) (xy 283.555306 -311.450453) (xy 283.540937 -311.464818)
			(xy 283.522165 -311.472592) (xy 283.512006 -311.473088) (xy 282.112466 -311.473088) (xy 282.102309 -311.472595)
			(xy 282.083544 -311.464814) (xy 282.069181 -311.450449) (xy 282.061403 -311.431683) (xy 282.060904 -311.421526)
			(xy 276.019768 -311.421526) (xy 276.019288 -311.431685) (xy 276.011506 -311.450453) (xy 275.997137 -311.464818)
			(xy 275.978365 -311.472592) (xy 275.968206 -311.473088) (xy 274.568666 -311.473088) (xy 274.558509 -311.472595)
			(xy 274.539744 -311.464814) (xy 274.525381 -311.450449) (xy 274.517603 -311.431683) (xy 274.517104 -311.421526)
			(xy 268.475968 -311.421526) (xy 268.475488 -311.431685) (xy 268.467706 -311.450453) (xy 268.453337 -311.464818)
			(xy 268.434565 -311.472592) (xy 268.424406 -311.473088) (xy 267.024866 -311.473088) (xy 267.014709 -311.472595)
			(xy 266.995944 -311.464814) (xy 266.981581 -311.450449) (xy 266.973803 -311.431683) (xy 266.973304 -311.421526)
			(xy 260.932168 -311.421526) (xy 260.931688 -311.431685) (xy 260.923906 -311.450453) (xy 260.909537 -311.464818)
			(xy 260.890765 -311.472592) (xy 260.880606 -311.473088) (xy 259.481066 -311.473088) (xy 259.470909 -311.472595)
			(xy 259.452144 -311.464814) (xy 259.437781 -311.450449) (xy 259.430003 -311.431683) (xy 259.429504 -311.421526)
			(xy 216.4715 -311.421526) (xy 216.470989 -311.431681) (xy 216.463213 -311.450443) (xy 216.448853 -311.464806)
			(xy 216.430093 -311.472587) (xy 216.419938 -311.473088) (xy 215.020398 -311.473088) (xy 215.010243 -311.472569)
			(xy 214.991479 -311.464799) (xy 214.977115 -311.450441) (xy 214.969336 -311.43168) (xy 214.968836 -311.421526)
			(xy 208.9277 -311.421526) (xy 208.927189 -311.431681) (xy 208.919413 -311.450443) (xy 208.905053 -311.464806)
			(xy 208.886293 -311.472587) (xy 208.876138 -311.473088) (xy 207.476598 -311.473088) (xy 207.466443 -311.472569)
			(xy 207.447679 -311.464799) (xy 207.433315 -311.450441) (xy 207.425536 -311.43168) (xy 207.425036 -311.421526)
			(xy 201.3839 -311.421526) (xy 201.383389 -311.431681) (xy 201.375613 -311.450443) (xy 201.361253 -311.464806)
			(xy 201.342493 -311.472587) (xy 201.332338 -311.473088) (xy 199.932798 -311.473088) (xy 199.922643 -311.472569)
			(xy 199.903879 -311.464799) (xy 199.889515 -311.450441) (xy 199.881736 -311.43168) (xy 199.881236 -311.421526)
			(xy 193.8401 -311.421526) (xy 193.839589 -311.431681) (xy 193.831813 -311.450443) (xy 193.817453 -311.464806)
			(xy 193.798693 -311.472587) (xy 193.788538 -311.473088) (xy 192.388998 -311.473088) (xy 192.378843 -311.472569)
			(xy 192.360079 -311.464799) (xy 192.345715 -311.450441) (xy 192.337936 -311.43168) (xy 192.337436 -311.421526)
			(xy 186.2963 -311.421526) (xy 186.295789 -311.431681) (xy 186.288013 -311.450443) (xy 186.273653 -311.464806)
			(xy 186.254893 -311.472587) (xy 186.244738 -311.473088) (xy 184.845198 -311.473088) (xy 184.835043 -311.472569)
			(xy 184.816279 -311.464799) (xy 184.801915 -311.450441) (xy 184.794136 -311.43168) (xy 184.793636 -311.421526)
			(xy 178.7525 -311.421526) (xy 178.751989 -311.431681) (xy 178.744213 -311.450443) (xy 178.729853 -311.464806)
			(xy 178.711093 -311.472587) (xy 178.700938 -311.473088) (xy 177.301398 -311.473088) (xy 177.291243 -311.472569)
			(xy 177.272479 -311.464799) (xy 177.258115 -311.450441) (xy 177.250336 -311.43168) (xy 177.249836 -311.421526)
			(xy 171.2087 -311.421526) (xy 171.208189 -311.431681) (xy 171.200413 -311.450443) (xy 171.186053 -311.464806)
			(xy 171.167293 -311.472587) (xy 171.157138 -311.473088) (xy 169.757598 -311.473088) (xy 169.747443 -311.472569)
			(xy 169.728679 -311.464799) (xy 169.714315 -311.450441) (xy 169.706536 -311.43168) (xy 169.706036 -311.421526)
			(xy 163.6649 -311.421526) (xy 163.664389 -311.431681) (xy 163.656613 -311.450443) (xy 163.642253 -311.464806)
			(xy 163.623493 -311.472587) (xy 163.613338 -311.473088) (xy 162.213798 -311.473088) (xy 162.203643 -311.472569)
			(xy 162.184879 -311.464799) (xy 162.170515 -311.450441) (xy 162.162736 -311.43168) (xy 162.162236 -311.421526)
			(xy 65.7987 -311.421526) (xy 65.798189 -311.431681) (xy 65.790413 -311.450443) (xy 65.776053 -311.464806)
			(xy 65.757293 -311.472587) (xy 65.747138 -311.473088) (xy 64.347598 -311.473088) (xy 64.337443 -311.472569)
			(xy 64.318679 -311.464799) (xy 64.304315 -311.450441) (xy 64.296536 -311.43168) (xy 64.296036 -311.421526)
			(xy 58.2549 -311.421526) (xy 58.254389 -311.431681) (xy 58.246613 -311.450443) (xy 58.232253 -311.464806)
			(xy 58.213493 -311.472587) (xy 58.203338 -311.473088) (xy 56.803798 -311.473088) (xy 56.793643 -311.472569)
			(xy 56.774879 -311.464799) (xy 56.760515 -311.450441) (xy 56.752736 -311.43168) (xy 56.752236 -311.421526)
			(xy 50.7111 -311.421526) (xy 50.710589 -311.431681) (xy 50.702813 -311.450443) (xy 50.688453 -311.464806)
			(xy 50.669693 -311.472587) (xy 50.659538 -311.473088) (xy 49.259998 -311.473088) (xy 49.249843 -311.472569)
			(xy 49.231079 -311.464799) (xy 49.216715 -311.450441) (xy 49.208936 -311.43168) (xy 49.208436 -311.421526)
			(xy 43.1673 -311.421526) (xy 43.166789 -311.431681) (xy 43.159013 -311.450443) (xy 43.144653 -311.464806)
			(xy 43.125893 -311.472587) (xy 43.115738 -311.473088) (xy 41.716198 -311.473088) (xy 41.706043 -311.472569)
			(xy 41.687279 -311.464799) (xy 41.672915 -311.450441) (xy 41.665136 -311.43168) (xy 41.664636 -311.421526)
			(xy 35.6235 -311.421526) (xy 35.622989 -311.431681) (xy 35.615213 -311.450443) (xy 35.600853 -311.464806)
			(xy 35.582093 -311.472587) (xy 35.571938 -311.473088) (xy 34.172398 -311.473088) (xy 34.162243 -311.472569)
			(xy 34.143479 -311.464799) (xy 34.129115 -311.450441) (xy 34.121336 -311.43168) (xy 34.120836 -311.421526)
			(xy 28.0797 -311.421526) (xy 28.079189 -311.431681) (xy 28.071413 -311.450443) (xy 28.057053 -311.464806)
			(xy 28.038293 -311.472587) (xy 28.028138 -311.473088) (xy 26.628598 -311.473088) (xy 26.618443 -311.472569)
			(xy 26.599679 -311.464799) (xy 26.585315 -311.450441) (xy 26.577536 -311.43168) (xy 26.577036 -311.421526)
			(xy 20.5359 -311.421526) (xy 20.535389 -311.431681) (xy 20.527613 -311.450443) (xy 20.513253 -311.464806)
			(xy 20.494493 -311.472587) (xy 20.484338 -311.473088) (xy 19.084798 -311.473088) (xy 19.074643 -311.472569)
			(xy 19.055879 -311.464799) (xy 19.041515 -311.450441) (xy 19.033736 -311.43168) (xy 19.033236 -311.421526)
			(xy 12.9921 -311.421526) (xy 12.991589 -311.431681) (xy 12.983813 -311.450443) (xy 12.969453 -311.464806)
			(xy 12.950693 -311.472587) (xy 12.940538 -311.473088) (xy 11.540998 -311.473088) (xy 11.530843 -311.472569)
			(xy 11.512079 -311.464799) (xy 11.497715 -311.450441) (xy 11.489936 -311.43168) (xy 11.489436 -311.421526)
			(xy 2.509012 -311.421526) (xy 2.509012 -312.27141) (xy 7.389368 -312.27141) (xy 7.389368 -311.86247)
			(xy 7.389809 -311.852307) (xy 7.397599 -311.833531) (xy 7.411981 -311.819166) (xy 7.430766 -311.811398)
			(xy 7.44093 -311.810908) (xy 8.84047 -311.810908) (xy 8.850622 -311.811457) (xy 8.869385 -311.819216)
			(xy 8.88375 -311.833565) (xy 8.891531 -311.852318) (xy 8.892032 -311.86247) (xy 8.892032 -312.27141)
			(xy 11.489436 -312.27141) (xy 11.489436 -311.86247) (xy 11.489909 -311.852311) (xy 11.497693 -311.833541)
			(xy 11.512065 -311.819177) (xy 11.530838 -311.811403) (xy 11.540998 -311.810908) (xy 12.940538 -311.810908)
			(xy 12.950695 -311.811402) (xy 12.969459 -311.819183) (xy 12.983822 -311.833548) (xy 12.9916 -311.852313)
			(xy 12.9921 -311.86247) (xy 12.9921 -312.27141) (xy 14.933168 -312.27141) (xy 14.933168 -311.86247)
			(xy 14.933609 -311.852307) (xy 14.941399 -311.833531) (xy 14.955781 -311.819166) (xy 14.974566 -311.811398)
			(xy 14.98473 -311.810908) (xy 16.38427 -311.810908) (xy 16.394422 -311.811457) (xy 16.413185 -311.819216)
			(xy 16.42755 -311.833565) (xy 16.435331 -311.852318) (xy 16.435832 -311.86247) (xy 16.435832 -312.27141)
			(xy 19.033236 -312.27141) (xy 19.033236 -311.86247) (xy 19.033709 -311.852311) (xy 19.041493 -311.833541)
			(xy 19.055865 -311.819177) (xy 19.074638 -311.811403) (xy 19.084798 -311.810908) (xy 20.484338 -311.810908)
			(xy 20.494495 -311.811402) (xy 20.513259 -311.819183) (xy 20.527622 -311.833548) (xy 20.5354 -311.852313)
			(xy 20.5359 -311.86247) (xy 20.5359 -312.27141) (xy 22.476968 -312.27141) (xy 22.476968 -311.86247)
			(xy 22.477409 -311.852307) (xy 22.485199 -311.833531) (xy 22.499581 -311.819166) (xy 22.518366 -311.811398)
			(xy 22.52853 -311.810908) (xy 23.92807 -311.810908) (xy 23.938222 -311.811457) (xy 23.956985 -311.819216)
			(xy 23.97135 -311.833565) (xy 23.979131 -311.852318) (xy 23.979632 -311.86247) (xy 23.979632 -312.27141)
			(xy 26.577036 -312.27141) (xy 26.577036 -311.86247) (xy 26.577509 -311.852311) (xy 26.585293 -311.833541)
			(xy 26.599665 -311.819177) (xy 26.618438 -311.811403) (xy 26.628598 -311.810908) (xy 28.028138 -311.810908)
			(xy 28.038295 -311.811402) (xy 28.057059 -311.819183) (xy 28.071422 -311.833548) (xy 28.0792 -311.852313)
			(xy 28.0797 -311.86247) (xy 28.0797 -312.27141) (xy 30.020768 -312.27141) (xy 30.020768 -311.86247)
			(xy 30.021209 -311.852307) (xy 30.028999 -311.833531) (xy 30.043381 -311.819166) (xy 30.062166 -311.811398)
			(xy 30.07233 -311.810908) (xy 31.47187 -311.810908) (xy 31.482022 -311.811457) (xy 31.500785 -311.819216)
			(xy 31.51515 -311.833565) (xy 31.522931 -311.852318) (xy 31.523432 -311.86247) (xy 31.523432 -312.27141)
			(xy 34.120836 -312.27141) (xy 34.120836 -311.86247) (xy 34.121309 -311.852311) (xy 34.129093 -311.833541)
			(xy 34.143465 -311.819177) (xy 34.162238 -311.811403) (xy 34.172398 -311.810908) (xy 35.571938 -311.810908)
			(xy 35.582095 -311.811402) (xy 35.600859 -311.819183) (xy 35.615222 -311.833548) (xy 35.623 -311.852313)
			(xy 35.6235 -311.86247) (xy 35.6235 -312.27141) (xy 37.564568 -312.27141) (xy 37.564568 -311.86247)
			(xy 37.565009 -311.852307) (xy 37.572799 -311.833531) (xy 37.587181 -311.819166) (xy 37.605966 -311.811398)
			(xy 37.61613 -311.810908) (xy 39.01567 -311.810908) (xy 39.025822 -311.811457) (xy 39.044585 -311.819216)
			(xy 39.05895 -311.833565) (xy 39.066731 -311.852318) (xy 39.067232 -311.86247) (xy 39.067232 -312.27141)
			(xy 41.664636 -312.27141) (xy 41.664636 -311.86247) (xy 41.665109 -311.852311) (xy 41.672893 -311.833541)
			(xy 41.687265 -311.819177) (xy 41.706038 -311.811403) (xy 41.716198 -311.810908) (xy 43.115738 -311.810908)
			(xy 43.125895 -311.811402) (xy 43.144659 -311.819183) (xy 43.159022 -311.833548) (xy 43.1668 -311.852313)
			(xy 43.1673 -311.86247) (xy 43.1673 -312.27141) (xy 45.108368 -312.27141) (xy 45.108368 -311.86247)
			(xy 45.108809 -311.852307) (xy 45.116599 -311.833531) (xy 45.130981 -311.819166) (xy 45.149766 -311.811398)
			(xy 45.15993 -311.810908) (xy 46.55947 -311.810908) (xy 46.569622 -311.811457) (xy 46.588385 -311.819216)
			(xy 46.60275 -311.833565) (xy 46.610531 -311.852318) (xy 46.611032 -311.86247) (xy 46.611032 -312.27141)
			(xy 49.208436 -312.27141) (xy 49.208436 -311.86247) (xy 49.208909 -311.852311) (xy 49.216693 -311.833541)
			(xy 49.231065 -311.819177) (xy 49.249838 -311.811403) (xy 49.259998 -311.810908) (xy 50.659538 -311.810908)
			(xy 50.669695 -311.811402) (xy 50.688459 -311.819183) (xy 50.702822 -311.833548) (xy 50.7106 -311.852313)
			(xy 50.7111 -311.86247) (xy 50.7111 -312.27141) (xy 52.652168 -312.27141) (xy 52.652168 -311.86247)
			(xy 52.652609 -311.852307) (xy 52.660399 -311.833531) (xy 52.674781 -311.819166) (xy 52.693566 -311.811398)
			(xy 52.70373 -311.810908) (xy 54.10327 -311.810908) (xy 54.113422 -311.811457) (xy 54.132185 -311.819216)
			(xy 54.14655 -311.833565) (xy 54.154331 -311.852318) (xy 54.154832 -311.86247) (xy 54.154832 -312.27141)
			(xy 56.752236 -312.27141) (xy 56.752236 -311.86247) (xy 56.752709 -311.852311) (xy 56.760493 -311.833541)
			(xy 56.774865 -311.819177) (xy 56.793638 -311.811403) (xy 56.803798 -311.810908) (xy 58.203338 -311.810908)
			(xy 58.213495 -311.811402) (xy 58.232259 -311.819183) (xy 58.246622 -311.833548) (xy 58.2544 -311.852313)
			(xy 58.2549 -311.86247) (xy 58.2549 -312.27141) (xy 60.195968 -312.27141) (xy 60.195968 -311.86247)
			(xy 60.196409 -311.852307) (xy 60.204199 -311.833531) (xy 60.218581 -311.819166) (xy 60.237366 -311.811398)
			(xy 60.24753 -311.810908) (xy 61.64707 -311.810908) (xy 61.657222 -311.811457) (xy 61.675985 -311.819216)
			(xy 61.69035 -311.833565) (xy 61.698131 -311.852318) (xy 61.698632 -311.86247) (xy 61.698632 -312.27141)
			(xy 64.296036 -312.27141) (xy 64.296036 -311.86247) (xy 64.296509 -311.852311) (xy 64.304293 -311.833541)
			(xy 64.318665 -311.819177) (xy 64.337438 -311.811403) (xy 64.347598 -311.810908) (xy 65.747138 -311.810908)
			(xy 65.757295 -311.811402) (xy 65.776059 -311.819183) (xy 65.790422 -311.833548) (xy 65.7982 -311.852313)
			(xy 65.7987 -311.86247) (xy 65.7987 -312.27141) (xy 158.062168 -312.27141) (xy 158.062168 -311.86247)
			(xy 158.062609 -311.852307) (xy 158.070399 -311.833531) (xy 158.084781 -311.819166) (xy 158.103566 -311.811398)
			(xy 158.11373 -311.810908) (xy 159.51327 -311.810908) (xy 159.523422 -311.811457) (xy 159.542185 -311.819216)
			(xy 159.55655 -311.833565) (xy 159.564331 -311.852318) (xy 159.564832 -311.86247) (xy 159.564832 -312.27141)
			(xy 162.162236 -312.27141) (xy 162.162236 -311.86247) (xy 162.162709 -311.852311) (xy 162.170493 -311.833541)
			(xy 162.184865 -311.819177) (xy 162.203638 -311.811403) (xy 162.213798 -311.810908) (xy 163.613338 -311.810908)
			(xy 163.623495 -311.811402) (xy 163.642259 -311.819183) (xy 163.656622 -311.833548) (xy 163.6644 -311.852313)
			(xy 163.6649 -311.86247) (xy 163.6649 -312.27141) (xy 165.605968 -312.27141) (xy 165.605968 -311.86247)
			(xy 165.606409 -311.852307) (xy 165.614199 -311.833531) (xy 165.628581 -311.819166) (xy 165.647366 -311.811398)
			(xy 165.65753 -311.810908) (xy 167.05707 -311.810908) (xy 167.067222 -311.811457) (xy 167.085985 -311.819216)
			(xy 167.10035 -311.833565) (xy 167.108131 -311.852318) (xy 167.108632 -311.86247) (xy 167.108632 -312.27141)
			(xy 169.706036 -312.27141) (xy 169.706036 -311.86247) (xy 169.706509 -311.852311) (xy 169.714293 -311.833541)
			(xy 169.728665 -311.819177) (xy 169.747438 -311.811403) (xy 169.757598 -311.810908) (xy 171.157138 -311.810908)
			(xy 171.167295 -311.811402) (xy 171.186059 -311.819183) (xy 171.200422 -311.833548) (xy 171.2082 -311.852313)
			(xy 171.2087 -311.86247) (xy 171.2087 -312.27141) (xy 173.149768 -312.27141) (xy 173.149768 -311.86247)
			(xy 173.150209 -311.852307) (xy 173.157999 -311.833531) (xy 173.172381 -311.819166) (xy 173.191166 -311.811398)
			(xy 173.20133 -311.810908) (xy 174.60087 -311.810908) (xy 174.611022 -311.811457) (xy 174.629785 -311.819216)
			(xy 174.64415 -311.833565) (xy 174.651931 -311.852318) (xy 174.652432 -311.86247) (xy 174.652432 -312.27141)
			(xy 177.249836 -312.27141) (xy 177.249836 -311.86247) (xy 177.250309 -311.852311) (xy 177.258093 -311.833541)
			(xy 177.272465 -311.819177) (xy 177.291238 -311.811403) (xy 177.301398 -311.810908) (xy 178.700938 -311.810908)
			(xy 178.711095 -311.811402) (xy 178.729859 -311.819183) (xy 178.744222 -311.833548) (xy 178.752 -311.852313)
			(xy 178.7525 -311.86247) (xy 178.7525 -312.27141) (xy 180.693568 -312.27141) (xy 180.693568 -311.86247)
			(xy 180.694009 -311.852307) (xy 180.701799 -311.833531) (xy 180.716181 -311.819166) (xy 180.734966 -311.811398)
			(xy 180.74513 -311.810908) (xy 182.14467 -311.810908) (xy 182.154822 -311.811457) (xy 182.173585 -311.819216)
			(xy 182.18795 -311.833565) (xy 182.195731 -311.852318) (xy 182.196232 -311.86247) (xy 182.196232 -312.27141)
			(xy 184.793636 -312.27141) (xy 184.793636 -311.86247) (xy 184.794109 -311.852311) (xy 184.801893 -311.833541)
			(xy 184.816265 -311.819177) (xy 184.835038 -311.811403) (xy 184.845198 -311.810908) (xy 186.244738 -311.810908)
			(xy 186.254895 -311.811402) (xy 186.273659 -311.819183) (xy 186.288022 -311.833548) (xy 186.2958 -311.852313)
			(xy 186.2963 -311.86247) (xy 186.2963 -312.27141) (xy 188.237368 -312.27141) (xy 188.237368 -311.86247)
			(xy 188.237809 -311.852307) (xy 188.245599 -311.833531) (xy 188.259981 -311.819166) (xy 188.278766 -311.811398)
			(xy 188.28893 -311.810908) (xy 189.68847 -311.810908) (xy 189.698622 -311.811457) (xy 189.717385 -311.819216)
			(xy 189.73175 -311.833565) (xy 189.739531 -311.852318) (xy 189.740032 -311.86247) (xy 189.740032 -312.27141)
			(xy 192.337436 -312.27141) (xy 192.337436 -311.86247) (xy 192.337909 -311.852311) (xy 192.345693 -311.833541)
			(xy 192.360065 -311.819177) (xy 192.378838 -311.811403) (xy 192.388998 -311.810908) (xy 193.788538 -311.810908)
			(xy 193.798695 -311.811402) (xy 193.817459 -311.819183) (xy 193.831822 -311.833548) (xy 193.8396 -311.852313)
			(xy 193.8401 -311.86247) (xy 193.8401 -312.27141) (xy 195.781168 -312.27141) (xy 195.781168 -311.86247)
			(xy 195.781609 -311.852307) (xy 195.789399 -311.833531) (xy 195.803781 -311.819166) (xy 195.822566 -311.811398)
			(xy 195.83273 -311.810908) (xy 197.23227 -311.810908) (xy 197.242422 -311.811457) (xy 197.261185 -311.819216)
			(xy 197.27555 -311.833565) (xy 197.283331 -311.852318) (xy 197.283832 -311.86247) (xy 197.283832 -312.27141)
			(xy 199.881236 -312.27141) (xy 199.881236 -311.86247) (xy 199.881709 -311.852311) (xy 199.889493 -311.833541)
			(xy 199.903865 -311.819177) (xy 199.922638 -311.811403) (xy 199.932798 -311.810908) (xy 201.332338 -311.810908)
			(xy 201.342495 -311.811402) (xy 201.361259 -311.819183) (xy 201.375622 -311.833548) (xy 201.3834 -311.852313)
			(xy 201.3839 -311.86247) (xy 201.3839 -312.27141) (xy 203.324968 -312.27141) (xy 203.324968 -311.86247)
			(xy 203.325409 -311.852307) (xy 203.333199 -311.833531) (xy 203.347581 -311.819166) (xy 203.366366 -311.811398)
			(xy 203.37653 -311.810908) (xy 204.77607 -311.810908) (xy 204.786222 -311.811457) (xy 204.804985 -311.819216)
			(xy 204.81935 -311.833565) (xy 204.827131 -311.852318) (xy 204.827632 -311.86247) (xy 204.827632 -312.27141)
			(xy 207.425036 -312.27141) (xy 207.425036 -311.86247) (xy 207.425509 -311.852311) (xy 207.433293 -311.833541)
			(xy 207.447665 -311.819177) (xy 207.466438 -311.811403) (xy 207.476598 -311.810908) (xy 208.876138 -311.810908)
			(xy 208.886295 -311.811402) (xy 208.905059 -311.819183) (xy 208.919422 -311.833548) (xy 208.9272 -311.852313)
			(xy 208.9277 -311.86247) (xy 208.9277 -312.27141) (xy 210.868768 -312.27141) (xy 210.868768 -311.86247)
			(xy 210.869209 -311.852307) (xy 210.876999 -311.833531) (xy 210.891381 -311.819166) (xy 210.910166 -311.811398)
			(xy 210.92033 -311.810908) (xy 212.31987 -311.810908) (xy 212.330022 -311.811457) (xy 212.348785 -311.819216)
			(xy 212.36315 -311.833565) (xy 212.370931 -311.852318) (xy 212.371432 -311.86247) (xy 212.371432 -312.27141)
			(xy 214.968836 -312.27141) (xy 214.968836 -311.86247) (xy 214.969309 -311.852311) (xy 214.977093 -311.833541)
			(xy 214.991465 -311.819177) (xy 215.010238 -311.811403) (xy 215.020398 -311.810908) (xy 216.419938 -311.810908)
			(xy 216.430095 -311.811402) (xy 216.448859 -311.819183) (xy 216.463222 -311.833548) (xy 216.471 -311.852313)
			(xy 216.4715 -311.86247) (xy 216.4715 -312.27141) (xy 255.329436 -312.27141) (xy 255.329436 -311.86247)
			(xy 255.329909 -311.852311) (xy 255.337693 -311.833541) (xy 255.352065 -311.819177) (xy 255.370838 -311.811403)
			(xy 255.380998 -311.810908) (xy 256.780538 -311.810908) (xy 256.790695 -311.811402) (xy 256.809459 -311.819183)
			(xy 256.823822 -311.833548) (xy 256.8316 -311.852313) (xy 256.8321 -311.86247) (xy 256.8321 -312.27141)
			(xy 259.429504 -312.27141) (xy 259.429504 -311.86247) (xy 259.430008 -311.852314) (xy 259.437786 -311.833551)
			(xy 259.452148 -311.819188) (xy 259.470911 -311.811409) (xy 259.481066 -311.810908) (xy 260.880606 -311.810908)
			(xy 260.89076 -311.811428) (xy 260.909524 -311.819199) (xy 260.923888 -311.833556) (xy 260.931667 -311.852316)
			(xy 260.932168 -311.86247) (xy 260.932168 -312.27141) (xy 262.873236 -312.27141) (xy 262.873236 -311.86247)
			(xy 262.873709 -311.852311) (xy 262.881493 -311.833541) (xy 262.895865 -311.819177) (xy 262.914638 -311.811403)
			(xy 262.924798 -311.810908) (xy 264.324338 -311.810908) (xy 264.334495 -311.811402) (xy 264.353259 -311.819183)
			(xy 264.367622 -311.833548) (xy 264.3754 -311.852313) (xy 264.3759 -311.86247) (xy 264.3759 -312.27141)
			(xy 266.973304 -312.27141) (xy 266.973304 -311.86247) (xy 266.973808 -311.852314) (xy 266.981586 -311.833551)
			(xy 266.995948 -311.819188) (xy 267.014711 -311.811409) (xy 267.024866 -311.810908) (xy 268.424406 -311.810908)
			(xy 268.43456 -311.811428) (xy 268.453324 -311.819199) (xy 268.467688 -311.833556) (xy 268.475467 -311.852316)
			(xy 268.475968 -311.86247) (xy 268.475968 -312.27141) (xy 270.417036 -312.27141) (xy 270.417036 -311.86247)
			(xy 270.417509 -311.852311) (xy 270.425293 -311.833541) (xy 270.439665 -311.819177) (xy 270.458438 -311.811403)
			(xy 270.468598 -311.810908) (xy 271.868138 -311.810908) (xy 271.878295 -311.811402) (xy 271.897059 -311.819183)
			(xy 271.911422 -311.833548) (xy 271.9192 -311.852313) (xy 271.9197 -311.86247) (xy 271.9197 -312.27141)
			(xy 274.517104 -312.27141) (xy 274.517104 -311.86247) (xy 274.517608 -311.852314) (xy 274.525386 -311.833551)
			(xy 274.539748 -311.819188) (xy 274.558511 -311.811409) (xy 274.568666 -311.810908) (xy 275.968206 -311.810908)
			(xy 275.97836 -311.811428) (xy 275.997124 -311.819199) (xy 276.011488 -311.833556) (xy 276.019267 -311.852316)
			(xy 276.019768 -311.86247) (xy 276.019768 -312.27141) (xy 277.960836 -312.27141) (xy 277.960836 -311.86247)
			(xy 277.961309 -311.852311) (xy 277.969093 -311.833541) (xy 277.983465 -311.819177) (xy 278.002238 -311.811403)
			(xy 278.012398 -311.810908) (xy 279.411938 -311.810908) (xy 279.422095 -311.811402) (xy 279.440859 -311.819183)
			(xy 279.455222 -311.833548) (xy 279.463 -311.852313) (xy 279.4635 -311.86247) (xy 279.4635 -312.27141)
			(xy 282.060904 -312.27141) (xy 282.060904 -311.86247) (xy 282.061408 -311.852314) (xy 282.069186 -311.833551)
			(xy 282.083548 -311.819188) (xy 282.102311 -311.811409) (xy 282.112466 -311.810908) (xy 283.512006 -311.810908)
			(xy 283.52216 -311.811428) (xy 283.540924 -311.819199) (xy 283.555288 -311.833556) (xy 283.563067 -311.852316)
			(xy 283.563568 -311.86247) (xy 283.563568 -312.27141) (xy 285.504636 -312.27141) (xy 285.504636 -311.86247)
			(xy 285.505109 -311.852311) (xy 285.512893 -311.833541) (xy 285.527265 -311.819177) (xy 285.546038 -311.811403)
			(xy 285.556198 -311.810908) (xy 286.955738 -311.810908) (xy 286.965895 -311.811402) (xy 286.984659 -311.819183)
			(xy 286.999022 -311.833548) (xy 287.0068 -311.852313) (xy 287.0073 -311.86247) (xy 287.0073 -312.27141)
			(xy 289.604704 -312.27141) (xy 289.604704 -311.86247) (xy 289.605208 -311.852314) (xy 289.612986 -311.833551)
			(xy 289.627348 -311.819188) (xy 289.646111 -311.811409) (xy 289.656266 -311.810908) (xy 291.055806 -311.810908)
			(xy 291.06596 -311.811428) (xy 291.084724 -311.819199) (xy 291.099088 -311.833556) (xy 291.106867 -311.852316)
			(xy 291.107368 -311.86247) (xy 291.107368 -312.27141) (xy 293.048436 -312.27141) (xy 293.048436 -311.86247)
			(xy 293.048909 -311.852311) (xy 293.056693 -311.833541) (xy 293.071065 -311.819177) (xy 293.089838 -311.811403)
			(xy 293.099998 -311.810908) (xy 294.499538 -311.810908) (xy 294.509695 -311.811402) (xy 294.528459 -311.819183)
			(xy 294.542822 -311.833548) (xy 294.5506 -311.852313) (xy 294.5511 -311.86247) (xy 294.5511 -312.27141)
			(xy 297.148504 -312.27141) (xy 297.148504 -311.86247) (xy 297.149008 -311.852314) (xy 297.156786 -311.833551)
			(xy 297.171148 -311.819188) (xy 297.189911 -311.811409) (xy 297.200066 -311.810908) (xy 298.599606 -311.810908)
			(xy 298.60976 -311.811428) (xy 298.628524 -311.819199) (xy 298.642888 -311.833556) (xy 298.650667 -311.852316)
			(xy 298.651168 -311.86247) (xy 298.651168 -312.27141) (xy 300.592236 -312.27141) (xy 300.592236 -311.86247)
			(xy 300.592709 -311.852311) (xy 300.600493 -311.833541) (xy 300.614865 -311.819177) (xy 300.633638 -311.811403)
			(xy 300.643798 -311.810908) (xy 302.043338 -311.810908) (xy 302.053495 -311.811402) (xy 302.072259 -311.819183)
			(xy 302.086622 -311.833548) (xy 302.0944 -311.852313) (xy 302.0949 -311.86247) (xy 302.0949 -312.27141)
			(xy 304.692304 -312.27141) (xy 304.692304 -311.86247) (xy 304.692808 -311.852314) (xy 304.700586 -311.833551)
			(xy 304.714948 -311.819188) (xy 304.733711 -311.811409) (xy 304.743866 -311.810908) (xy 306.143406 -311.810908)
			(xy 306.15356 -311.811428) (xy 306.172324 -311.819199) (xy 306.186688 -311.833556) (xy 306.194467 -311.852316)
			(xy 306.194968 -311.86247) (xy 306.194968 -312.27141) (xy 308.136036 -312.27141) (xy 308.136036 -311.86247)
			(xy 308.136509 -311.852311) (xy 308.144293 -311.833541) (xy 308.158665 -311.819177) (xy 308.177438 -311.811403)
			(xy 308.187598 -311.810908) (xy 309.587138 -311.810908) (xy 309.597295 -311.811402) (xy 309.616059 -311.819183)
			(xy 309.630422 -311.833548) (xy 309.6382 -311.852313) (xy 309.6387 -311.86247) (xy 309.6387 -312.27141)
			(xy 312.236104 -312.27141) (xy 312.236104 -311.86247) (xy 312.236608 -311.852314) (xy 312.244386 -311.833551)
			(xy 312.258748 -311.819188) (xy 312.277511 -311.811409) (xy 312.287666 -311.810908) (xy 313.687206 -311.810908)
			(xy 313.69736 -311.811428) (xy 313.716124 -311.819199) (xy 313.730488 -311.833556) (xy 313.738267 -311.852316)
			(xy 313.738768 -311.86247) (xy 313.738768 -312.27141) (xy 406.002236 -312.27141) (xy 406.002236 -311.86247)
			(xy 406.002709 -311.852311) (xy 406.010493 -311.833541) (xy 406.024865 -311.819177) (xy 406.043638 -311.811403)
			(xy 406.053798 -311.810908) (xy 407.453338 -311.810908) (xy 407.463495 -311.811402) (xy 407.482259 -311.819183)
			(xy 407.496622 -311.833548) (xy 407.5044 -311.852313) (xy 407.5049 -311.86247) (xy 407.5049 -312.27141)
			(xy 410.102304 -312.27141) (xy 410.102304 -311.86247) (xy 410.102808 -311.852314) (xy 410.110586 -311.833551)
			(xy 410.124948 -311.819188) (xy 410.143711 -311.811409) (xy 410.153866 -311.810908) (xy 411.553406 -311.810908)
			(xy 411.56356 -311.811428) (xy 411.582324 -311.819199) (xy 411.596688 -311.833556) (xy 411.604467 -311.852316)
			(xy 411.604968 -311.86247) (xy 411.604968 -312.27141) (xy 413.546036 -312.27141) (xy 413.546036 -311.86247)
			(xy 413.546509 -311.852311) (xy 413.554293 -311.833541) (xy 413.568665 -311.819177) (xy 413.587438 -311.811403)
			(xy 413.597598 -311.810908) (xy 414.997138 -311.810908) (xy 415.007295 -311.811402) (xy 415.026059 -311.819183)
			(xy 415.040422 -311.833548) (xy 415.0482 -311.852313) (xy 415.0487 -311.86247) (xy 415.0487 -312.27141)
			(xy 417.646104 -312.27141) (xy 417.646104 -311.86247) (xy 417.646608 -311.852314) (xy 417.654386 -311.833551)
			(xy 417.668748 -311.819188) (xy 417.687511 -311.811409) (xy 417.697666 -311.810908) (xy 419.097206 -311.810908)
			(xy 419.10736 -311.811428) (xy 419.126124 -311.819199) (xy 419.140488 -311.833556) (xy 419.148267 -311.852316)
			(xy 419.148768 -311.86247) (xy 419.148768 -312.27141) (xy 421.089836 -312.27141) (xy 421.089836 -311.86247)
			(xy 421.090309 -311.852311) (xy 421.098093 -311.833541) (xy 421.112465 -311.819177) (xy 421.131238 -311.811403)
			(xy 421.141398 -311.810908) (xy 422.540938 -311.810908) (xy 422.551095 -311.811402) (xy 422.569859 -311.819183)
			(xy 422.584222 -311.833548) (xy 422.592 -311.852313) (xy 422.5925 -311.86247) (xy 422.5925 -312.27141)
			(xy 425.189904 -312.27141) (xy 425.189904 -311.86247) (xy 425.190408 -311.852314) (xy 425.198186 -311.833551)
			(xy 425.212548 -311.819188) (xy 425.231311 -311.811409) (xy 425.241466 -311.810908) (xy 426.641006 -311.810908)
			(xy 426.65116 -311.811428) (xy 426.669924 -311.819199) (xy 426.684288 -311.833556) (xy 426.692067 -311.852316)
			(xy 426.692568 -311.86247) (xy 426.692568 -312.27141) (xy 428.633636 -312.27141) (xy 428.633636 -311.86247)
			(xy 428.634109 -311.852311) (xy 428.641893 -311.833541) (xy 428.656265 -311.819177) (xy 428.675038 -311.811403)
			(xy 428.685198 -311.810908) (xy 430.084738 -311.810908) (xy 430.094895 -311.811402) (xy 430.113659 -311.819183)
			(xy 430.128022 -311.833548) (xy 430.1358 -311.852313) (xy 430.1363 -311.86247) (xy 430.1363 -312.27141)
			(xy 432.733704 -312.27141) (xy 432.733704 -311.86247) (xy 432.734208 -311.852314) (xy 432.741986 -311.833551)
			(xy 432.756348 -311.819188) (xy 432.775111 -311.811409) (xy 432.785266 -311.810908) (xy 434.184806 -311.810908)
			(xy 434.19496 -311.811428) (xy 434.213724 -311.819199) (xy 434.228088 -311.833556) (xy 434.235867 -311.852316)
			(xy 434.236368 -311.86247) (xy 434.236368 -312.27141) (xy 436.177436 -312.27141) (xy 436.177436 -311.86247)
			(xy 436.177909 -311.852311) (xy 436.185693 -311.833541) (xy 436.200065 -311.819177) (xy 436.218838 -311.811403)
			(xy 436.228998 -311.810908) (xy 437.628538 -311.810908) (xy 437.638695 -311.811402) (xy 437.657459 -311.819183)
			(xy 437.671822 -311.833548) (xy 437.6796 -311.852313) (xy 437.6801 -311.86247) (xy 437.6801 -312.27141)
			(xy 440.277504 -312.27141) (xy 440.277504 -311.86247) (xy 440.278008 -311.852314) (xy 440.285786 -311.833551)
			(xy 440.300148 -311.819188) (xy 440.318911 -311.811409) (xy 440.329066 -311.810908) (xy 441.728606 -311.810908)
			(xy 441.73876 -311.811428) (xy 441.757524 -311.819199) (xy 441.771888 -311.833556) (xy 441.779667 -311.852316)
			(xy 441.780168 -311.86247) (xy 441.780168 -312.27141) (xy 443.721236 -312.27141) (xy 443.721236 -311.86247)
			(xy 443.721709 -311.852311) (xy 443.729493 -311.833541) (xy 443.743865 -311.819177) (xy 443.762638 -311.811403)
			(xy 443.772798 -311.810908) (xy 445.172338 -311.810908) (xy 445.182495 -311.811402) (xy 445.201259 -311.819183)
			(xy 445.215622 -311.833548) (xy 445.2234 -311.852313) (xy 445.2239 -311.86247) (xy 445.2239 -312.27141)
			(xy 447.821304 -312.27141) (xy 447.821304 -311.86247) (xy 447.821808 -311.852314) (xy 447.829586 -311.833551)
			(xy 447.843948 -311.819188) (xy 447.862711 -311.811409) (xy 447.872866 -311.810908) (xy 449.272406 -311.810908)
			(xy 449.28256 -311.811428) (xy 449.301324 -311.819199) (xy 449.315688 -311.833556) (xy 449.323467 -311.852316)
			(xy 449.323968 -311.86247) (xy 449.323968 -312.27141) (xy 451.265036 -312.27141) (xy 451.265036 -311.86247)
			(xy 451.265509 -311.852311) (xy 451.273293 -311.833541) (xy 451.287665 -311.819177) (xy 451.306438 -311.811403)
			(xy 451.316598 -311.810908) (xy 452.716138 -311.810908) (xy 452.726295 -311.811402) (xy 452.745059 -311.819183)
			(xy 452.759422 -311.833548) (xy 452.7672 -311.852313) (xy 452.7677 -311.86247) (xy 452.7677 -312.27141)
			(xy 455.365104 -312.27141) (xy 455.365104 -311.86247) (xy 455.365608 -311.852314) (xy 455.373386 -311.833551)
			(xy 455.387748 -311.819188) (xy 455.406511 -311.811409) (xy 455.416666 -311.810908) (xy 456.816206 -311.810908)
			(xy 456.82636 -311.811428) (xy 456.845124 -311.819199) (xy 456.859488 -311.833556) (xy 456.867267 -311.852316)
			(xy 456.867768 -311.86247) (xy 456.867768 -312.27141) (xy 458.808836 -312.27141) (xy 458.808836 -311.86247)
			(xy 458.809309 -311.852311) (xy 458.817093 -311.833541) (xy 458.831465 -311.819177) (xy 458.850238 -311.811403)
			(xy 458.860398 -311.810908) (xy 460.259938 -311.810908) (xy 460.270095 -311.811402) (xy 460.288859 -311.819183)
			(xy 460.303222 -311.833548) (xy 460.311 -311.852313) (xy 460.3115 -311.86247) (xy 460.3115 -312.27141)
			(xy 462.908904 -312.27141) (xy 462.908904 -311.86247) (xy 462.909408 -311.852314) (xy 462.917186 -311.833551)
			(xy 462.931548 -311.819188) (xy 462.950311 -311.811409) (xy 462.960466 -311.810908) (xy 464.360006 -311.810908)
			(xy 464.37016 -311.811428) (xy 464.388924 -311.819199) (xy 464.403288 -311.833556) (xy 464.411067 -311.852316)
			(xy 464.411568 -311.86247) (xy 464.411568 -312.27141) (xy 464.411075 -312.281568) (xy 464.403298 -312.300336)
			(xy 464.388932 -312.3147) (xy 464.370164 -312.322476) (xy 464.360006 -312.322972) (xy 462.960466 -312.322972)
			(xy 462.950307 -312.322495) (xy 462.931539 -312.314711) (xy 462.917176 -312.300341) (xy 462.909401 -312.281569)
			(xy 462.908904 -312.27141) (xy 460.3115 -312.27141) (xy 460.310976 -312.281564) (xy 460.303205 -312.300326)
			(xy 460.288849 -312.314689) (xy 460.270091 -312.32247) (xy 460.259938 -312.322972) (xy 458.860398 -312.322972)
			(xy 458.850241 -312.322468) (xy 458.831474 -312.314695) (xy 458.817109 -312.300333) (xy 458.809333 -312.281567)
			(xy 458.808836 -312.27141) (xy 456.867768 -312.27141) (xy 456.867275 -312.281568) (xy 456.859498 -312.300336)
			(xy 456.845132 -312.3147) (xy 456.826364 -312.322476) (xy 456.816206 -312.322972) (xy 455.416666 -312.322972)
			(xy 455.406507 -312.322495) (xy 455.387739 -312.314711) (xy 455.373376 -312.300341) (xy 455.365601 -312.281569)
			(xy 455.365104 -312.27141) (xy 452.7677 -312.27141) (xy 452.767176 -312.281564) (xy 452.759405 -312.300326)
			(xy 452.745049 -312.314689) (xy 452.726291 -312.32247) (xy 452.716138 -312.322972) (xy 451.316598 -312.322972)
			(xy 451.306441 -312.322468) (xy 451.287674 -312.314695) (xy 451.273309 -312.300333) (xy 451.265533 -312.281567)
			(xy 451.265036 -312.27141) (xy 449.323968 -312.27141) (xy 449.323475 -312.281568) (xy 449.315698 -312.300336)
			(xy 449.301332 -312.3147) (xy 449.282564 -312.322476) (xy 449.272406 -312.322972) (xy 447.872866 -312.322972)
			(xy 447.862707 -312.322495) (xy 447.843939 -312.314711) (xy 447.829576 -312.300341) (xy 447.821801 -312.281569)
			(xy 447.821304 -312.27141) (xy 445.2239 -312.27141) (xy 445.223376 -312.281564) (xy 445.215605 -312.300326)
			(xy 445.201249 -312.314689) (xy 445.182491 -312.32247) (xy 445.172338 -312.322972) (xy 443.772798 -312.322972)
			(xy 443.762641 -312.322468) (xy 443.743874 -312.314695) (xy 443.729509 -312.300333) (xy 443.721733 -312.281567)
			(xy 443.721236 -312.27141) (xy 441.780168 -312.27141) (xy 441.779675 -312.281568) (xy 441.771898 -312.300336)
			(xy 441.757532 -312.3147) (xy 441.738764 -312.322476) (xy 441.728606 -312.322972) (xy 440.329066 -312.322972)
			(xy 440.318907 -312.322495) (xy 440.300139 -312.314711) (xy 440.285776 -312.300341) (xy 440.278001 -312.281569)
			(xy 440.277504 -312.27141) (xy 437.6801 -312.27141) (xy 437.679576 -312.281564) (xy 437.671805 -312.300326)
			(xy 437.657449 -312.314689) (xy 437.638691 -312.32247) (xy 437.628538 -312.322972) (xy 436.228998 -312.322972)
			(xy 436.218841 -312.322468) (xy 436.200074 -312.314695) (xy 436.185709 -312.300333) (xy 436.177933 -312.281567)
			(xy 436.177436 -312.27141) (xy 434.236368 -312.27141) (xy 434.235875 -312.281568) (xy 434.228098 -312.300336)
			(xy 434.213732 -312.3147) (xy 434.194964 -312.322476) (xy 434.184806 -312.322972) (xy 432.785266 -312.322972)
			(xy 432.775107 -312.322495) (xy 432.756339 -312.314711) (xy 432.741976 -312.300341) (xy 432.734201 -312.281569)
			(xy 432.733704 -312.27141) (xy 430.1363 -312.27141) (xy 430.135776 -312.281564) (xy 430.128005 -312.300326)
			(xy 430.113649 -312.314689) (xy 430.094891 -312.32247) (xy 430.084738 -312.322972) (xy 428.685198 -312.322972)
			(xy 428.675041 -312.322468) (xy 428.656274 -312.314695) (xy 428.641909 -312.300333) (xy 428.634133 -312.281567)
			(xy 428.633636 -312.27141) (xy 426.692568 -312.27141) (xy 426.692075 -312.281568) (xy 426.684298 -312.300336)
			(xy 426.669932 -312.3147) (xy 426.651164 -312.322476) (xy 426.641006 -312.322972) (xy 425.241466 -312.322972)
			(xy 425.231307 -312.322495) (xy 425.212539 -312.314711) (xy 425.198176 -312.300341) (xy 425.190401 -312.281569)
			(xy 425.189904 -312.27141) (xy 422.5925 -312.27141) (xy 422.591976 -312.281564) (xy 422.584205 -312.300326)
			(xy 422.569849 -312.314689) (xy 422.551091 -312.32247) (xy 422.540938 -312.322972) (xy 421.141398 -312.322972)
			(xy 421.131241 -312.322468) (xy 421.112474 -312.314695) (xy 421.098109 -312.300333) (xy 421.090333 -312.281567)
			(xy 421.089836 -312.27141) (xy 419.148768 -312.27141) (xy 419.148275 -312.281568) (xy 419.140498 -312.300336)
			(xy 419.126132 -312.3147) (xy 419.107364 -312.322476) (xy 419.097206 -312.322972) (xy 417.697666 -312.322972)
			(xy 417.687507 -312.322495) (xy 417.668739 -312.314711) (xy 417.654376 -312.300341) (xy 417.646601 -312.281569)
			(xy 417.646104 -312.27141) (xy 415.0487 -312.27141) (xy 415.048176 -312.281564) (xy 415.040405 -312.300326)
			(xy 415.026049 -312.314689) (xy 415.007291 -312.32247) (xy 414.997138 -312.322972) (xy 413.597598 -312.322972)
			(xy 413.587441 -312.322468) (xy 413.568674 -312.314695) (xy 413.554309 -312.300333) (xy 413.546533 -312.281567)
			(xy 413.546036 -312.27141) (xy 411.604968 -312.27141) (xy 411.604475 -312.281568) (xy 411.596698 -312.300336)
			(xy 411.582332 -312.3147) (xy 411.563564 -312.322476) (xy 411.553406 -312.322972) (xy 410.153866 -312.322972)
			(xy 410.143707 -312.322495) (xy 410.124939 -312.314711) (xy 410.110576 -312.300341) (xy 410.102801 -312.281569)
			(xy 410.102304 -312.27141) (xy 407.5049 -312.27141) (xy 407.504376 -312.281564) (xy 407.496605 -312.300326)
			(xy 407.482249 -312.314689) (xy 407.463491 -312.32247) (xy 407.453338 -312.322972) (xy 406.053798 -312.322972)
			(xy 406.043641 -312.322468) (xy 406.024874 -312.314695) (xy 406.010509 -312.300333) (xy 406.002733 -312.281567)
			(xy 406.002236 -312.27141) (xy 313.738768 -312.27141) (xy 313.738275 -312.281568) (xy 313.730498 -312.300336)
			(xy 313.716132 -312.3147) (xy 313.697364 -312.322476) (xy 313.687206 -312.322972) (xy 312.287666 -312.322972)
			(xy 312.277507 -312.322495) (xy 312.258739 -312.314711) (xy 312.244376 -312.300341) (xy 312.236601 -312.281569)
			(xy 312.236104 -312.27141) (xy 309.6387 -312.27141) (xy 309.638176 -312.281564) (xy 309.630405 -312.300326)
			(xy 309.616049 -312.314689) (xy 309.597291 -312.32247) (xy 309.587138 -312.322972) (xy 308.187598 -312.322972)
			(xy 308.177441 -312.322468) (xy 308.158674 -312.314695) (xy 308.144309 -312.300333) (xy 308.136533 -312.281567)
			(xy 308.136036 -312.27141) (xy 306.194968 -312.27141) (xy 306.194475 -312.281568) (xy 306.186698 -312.300336)
			(xy 306.172332 -312.3147) (xy 306.153564 -312.322476) (xy 306.143406 -312.322972) (xy 304.743866 -312.322972)
			(xy 304.733707 -312.322495) (xy 304.714939 -312.314711) (xy 304.700576 -312.300341) (xy 304.692801 -312.281569)
			(xy 304.692304 -312.27141) (xy 302.0949 -312.27141) (xy 302.094376 -312.281564) (xy 302.086605 -312.300326)
			(xy 302.072249 -312.314689) (xy 302.053491 -312.32247) (xy 302.043338 -312.322972) (xy 300.643798 -312.322972)
			(xy 300.633641 -312.322468) (xy 300.614874 -312.314695) (xy 300.600509 -312.300333) (xy 300.592733 -312.281567)
			(xy 300.592236 -312.27141) (xy 298.651168 -312.27141) (xy 298.650675 -312.281568) (xy 298.642898 -312.300336)
			(xy 298.628532 -312.3147) (xy 298.609764 -312.322476) (xy 298.599606 -312.322972) (xy 297.200066 -312.322972)
			(xy 297.189907 -312.322495) (xy 297.171139 -312.314711) (xy 297.156776 -312.300341) (xy 297.149001 -312.281569)
			(xy 297.148504 -312.27141) (xy 294.5511 -312.27141) (xy 294.550576 -312.281564) (xy 294.542805 -312.300326)
			(xy 294.528449 -312.314689) (xy 294.509691 -312.32247) (xy 294.499538 -312.322972) (xy 293.099998 -312.322972)
			(xy 293.089841 -312.322468) (xy 293.071074 -312.314695) (xy 293.056709 -312.300333) (xy 293.048933 -312.281567)
			(xy 293.048436 -312.27141) (xy 291.107368 -312.27141) (xy 291.106875 -312.281568) (xy 291.099098 -312.300336)
			(xy 291.084732 -312.3147) (xy 291.065964 -312.322476) (xy 291.055806 -312.322972) (xy 289.656266 -312.322972)
			(xy 289.646107 -312.322495) (xy 289.627339 -312.314711) (xy 289.612976 -312.300341) (xy 289.605201 -312.281569)
			(xy 289.604704 -312.27141) (xy 287.0073 -312.27141) (xy 287.006776 -312.281564) (xy 286.999005 -312.300326)
			(xy 286.984649 -312.314689) (xy 286.965891 -312.32247) (xy 286.955738 -312.322972) (xy 285.556198 -312.322972)
			(xy 285.546041 -312.322468) (xy 285.527274 -312.314695) (xy 285.512909 -312.300333) (xy 285.505133 -312.281567)
			(xy 285.504636 -312.27141) (xy 283.563568 -312.27141) (xy 283.563075 -312.281568) (xy 283.555298 -312.300336)
			(xy 283.540932 -312.3147) (xy 283.522164 -312.322476) (xy 283.512006 -312.322972) (xy 282.112466 -312.322972)
			(xy 282.102307 -312.322495) (xy 282.083539 -312.314711) (xy 282.069176 -312.300341) (xy 282.061401 -312.281569)
			(xy 282.060904 -312.27141) (xy 279.4635 -312.27141) (xy 279.462976 -312.281564) (xy 279.455205 -312.300326)
			(xy 279.440849 -312.314689) (xy 279.422091 -312.32247) (xy 279.411938 -312.322972) (xy 278.012398 -312.322972)
			(xy 278.002241 -312.322468) (xy 277.983474 -312.314695) (xy 277.969109 -312.300333) (xy 277.961333 -312.281567)
			(xy 277.960836 -312.27141) (xy 276.019768 -312.27141) (xy 276.019275 -312.281568) (xy 276.011498 -312.300336)
			(xy 275.997132 -312.3147) (xy 275.978364 -312.322476) (xy 275.968206 -312.322972) (xy 274.568666 -312.322972)
			(xy 274.558507 -312.322495) (xy 274.539739 -312.314711) (xy 274.525376 -312.300341) (xy 274.517601 -312.281569)
			(xy 274.517104 -312.27141) (xy 271.9197 -312.27141) (xy 271.919176 -312.281564) (xy 271.911405 -312.300326)
			(xy 271.897049 -312.314689) (xy 271.878291 -312.32247) (xy 271.868138 -312.322972) (xy 270.468598 -312.322972)
			(xy 270.458441 -312.322468) (xy 270.439674 -312.314695) (xy 270.425309 -312.300333) (xy 270.417533 -312.281567)
			(xy 270.417036 -312.27141) (xy 268.475968 -312.27141) (xy 268.475475 -312.281568) (xy 268.467698 -312.300336)
			(xy 268.453332 -312.3147) (xy 268.434564 -312.322476) (xy 268.424406 -312.322972) (xy 267.024866 -312.322972)
			(xy 267.014707 -312.322495) (xy 266.995939 -312.314711) (xy 266.981576 -312.300341) (xy 266.973801 -312.281569)
			(xy 266.973304 -312.27141) (xy 264.3759 -312.27141) (xy 264.375376 -312.281564) (xy 264.367605 -312.300326)
			(xy 264.353249 -312.314689) (xy 264.334491 -312.32247) (xy 264.324338 -312.322972) (xy 262.924798 -312.322972)
			(xy 262.914641 -312.322468) (xy 262.895874 -312.314695) (xy 262.881509 -312.300333) (xy 262.873733 -312.281567)
			(xy 262.873236 -312.27141) (xy 260.932168 -312.27141) (xy 260.931675 -312.281568) (xy 260.923898 -312.300336)
			(xy 260.909532 -312.3147) (xy 260.890764 -312.322476) (xy 260.880606 -312.322972) (xy 259.481066 -312.322972)
			(xy 259.470907 -312.322495) (xy 259.452139 -312.314711) (xy 259.437776 -312.300341) (xy 259.430001 -312.281569)
			(xy 259.429504 -312.27141) (xy 256.8321 -312.27141) (xy 256.831576 -312.281564) (xy 256.823805 -312.300326)
			(xy 256.809449 -312.314689) (xy 256.790691 -312.32247) (xy 256.780538 -312.322972) (xy 255.380998 -312.322972)
			(xy 255.370841 -312.322468) (xy 255.352074 -312.314695) (xy 255.337709 -312.300333) (xy 255.329933 -312.281567)
			(xy 255.329436 -312.27141) (xy 216.4715 -312.27141) (xy 216.470976 -312.281564) (xy 216.463205 -312.300326)
			(xy 216.448849 -312.314689) (xy 216.430091 -312.32247) (xy 216.419938 -312.322972) (xy 215.020398 -312.322972)
			(xy 215.010241 -312.322468) (xy 214.991474 -312.314695) (xy 214.977109 -312.300333) (xy 214.969333 -312.281567)
			(xy 214.968836 -312.27141) (xy 212.371432 -312.27141) (xy 212.371044 -312.281586) (xy 212.36325 -312.300387)
			(xy 212.348853 -312.314772) (xy 212.330046 -312.322551) (xy 212.31987 -312.322972) (xy 210.92033 -312.322972)
			(xy 210.910162 -312.322512) (xy 210.89137 -312.314738) (xy 210.876984 -312.300364) (xy 210.869196 -312.281578)
			(xy 210.868768 -312.27141) (xy 208.9277 -312.27141) (xy 208.927176 -312.281564) (xy 208.919405 -312.300326)
			(xy 208.905049 -312.314689) (xy 208.886291 -312.32247) (xy 208.876138 -312.322972) (xy 207.476598 -312.322972)
			(xy 207.466441 -312.322468) (xy 207.447674 -312.314695) (xy 207.433309 -312.300333) (xy 207.425533 -312.281567)
			(xy 207.425036 -312.27141) (xy 204.827632 -312.27141) (xy 204.827244 -312.281586) (xy 204.81945 -312.300387)
			(xy 204.805053 -312.314772) (xy 204.786246 -312.322551) (xy 204.77607 -312.322972) (xy 203.37653 -312.322972)
			(xy 203.366362 -312.322512) (xy 203.34757 -312.314738) (xy 203.333184 -312.300364) (xy 203.325396 -312.281578)
			(xy 203.324968 -312.27141) (xy 201.3839 -312.27141) (xy 201.383376 -312.281564) (xy 201.375605 -312.300326)
			(xy 201.361249 -312.314689) (xy 201.342491 -312.32247) (xy 201.332338 -312.322972) (xy 199.932798 -312.322972)
			(xy 199.922641 -312.322468) (xy 199.903874 -312.314695) (xy 199.889509 -312.300333) (xy 199.881733 -312.281567)
			(xy 199.881236 -312.27141) (xy 197.283832 -312.27141) (xy 197.283444 -312.281586) (xy 197.27565 -312.300387)
			(xy 197.261253 -312.314772) (xy 197.242446 -312.322551) (xy 197.23227 -312.322972) (xy 195.83273 -312.322972)
			(xy 195.822562 -312.322512) (xy 195.80377 -312.314738) (xy 195.789384 -312.300364) (xy 195.781596 -312.281578)
			(xy 195.781168 -312.27141) (xy 193.8401 -312.27141) (xy 193.839576 -312.281564) (xy 193.831805 -312.300326)
			(xy 193.817449 -312.314689) (xy 193.798691 -312.32247) (xy 193.788538 -312.322972) (xy 192.388998 -312.322972)
			(xy 192.378841 -312.322468) (xy 192.360074 -312.314695) (xy 192.345709 -312.300333) (xy 192.337933 -312.281567)
			(xy 192.337436 -312.27141) (xy 189.740032 -312.27141) (xy 189.739644 -312.281586) (xy 189.73185 -312.300387)
			(xy 189.717453 -312.314772) (xy 189.698646 -312.322551) (xy 189.68847 -312.322972) (xy 188.28893 -312.322972)
			(xy 188.278762 -312.322512) (xy 188.25997 -312.314738) (xy 188.245584 -312.300364) (xy 188.237796 -312.281578)
			(xy 188.237368 -312.27141) (xy 186.2963 -312.27141) (xy 186.295776 -312.281564) (xy 186.288005 -312.300326)
			(xy 186.273649 -312.314689) (xy 186.254891 -312.32247) (xy 186.244738 -312.322972) (xy 184.845198 -312.322972)
			(xy 184.835041 -312.322468) (xy 184.816274 -312.314695) (xy 184.801909 -312.300333) (xy 184.794133 -312.281567)
			(xy 184.793636 -312.27141) (xy 182.196232 -312.27141) (xy 182.195844 -312.281586) (xy 182.18805 -312.300387)
			(xy 182.173653 -312.314772) (xy 182.154846 -312.322551) (xy 182.14467 -312.322972) (xy 180.74513 -312.322972)
			(xy 180.734962 -312.322512) (xy 180.71617 -312.314738) (xy 180.701784 -312.300364) (xy 180.693996 -312.281578)
			(xy 180.693568 -312.27141) (xy 178.7525 -312.27141) (xy 178.751976 -312.281564) (xy 178.744205 -312.300326)
			(xy 178.729849 -312.314689) (xy 178.711091 -312.32247) (xy 178.700938 -312.322972) (xy 177.301398 -312.322972)
			(xy 177.291241 -312.322468) (xy 177.272474 -312.314695) (xy 177.258109 -312.300333) (xy 177.250333 -312.281567)
			(xy 177.249836 -312.27141) (xy 174.652432 -312.27141) (xy 174.652044 -312.281586) (xy 174.64425 -312.300387)
			(xy 174.629853 -312.314772) (xy 174.611046 -312.322551) (xy 174.60087 -312.322972) (xy 173.20133 -312.322972)
			(xy 173.191162 -312.322512) (xy 173.17237 -312.314738) (xy 173.157984 -312.300364) (xy 173.150196 -312.281578)
			(xy 173.149768 -312.27141) (xy 171.2087 -312.27141) (xy 171.208176 -312.281564) (xy 171.200405 -312.300326)
			(xy 171.186049 -312.314689) (xy 171.167291 -312.32247) (xy 171.157138 -312.322972) (xy 169.757598 -312.322972)
			(xy 169.747441 -312.322468) (xy 169.728674 -312.314695) (xy 169.714309 -312.300333) (xy 169.706533 -312.281567)
			(xy 169.706036 -312.27141) (xy 167.108632 -312.27141) (xy 167.108244 -312.281586) (xy 167.10045 -312.300387)
			(xy 167.086053 -312.314772) (xy 167.067246 -312.322551) (xy 167.05707 -312.322972) (xy 165.65753 -312.322972)
			(xy 165.647362 -312.322512) (xy 165.62857 -312.314738) (xy 165.614184 -312.300364) (xy 165.606396 -312.281578)
			(xy 165.605968 -312.27141) (xy 163.6649 -312.27141) (xy 163.664376 -312.281564) (xy 163.656605 -312.300326)
			(xy 163.642249 -312.314689) (xy 163.623491 -312.32247) (xy 163.613338 -312.322972) (xy 162.213798 -312.322972)
			(xy 162.203641 -312.322468) (xy 162.184874 -312.314695) (xy 162.170509 -312.300333) (xy 162.162733 -312.281567)
			(xy 162.162236 -312.27141) (xy 159.564832 -312.27141) (xy 159.564444 -312.281586) (xy 159.55665 -312.300387)
			(xy 159.542253 -312.314772) (xy 159.523446 -312.322551) (xy 159.51327 -312.322972) (xy 158.11373 -312.322972)
			(xy 158.103562 -312.322512) (xy 158.08477 -312.314738) (xy 158.070384 -312.300364) (xy 158.062596 -312.281578)
			(xy 158.062168 -312.27141) (xy 65.7987 -312.27141) (xy 65.798176 -312.281564) (xy 65.790405 -312.300326)
			(xy 65.776049 -312.314689) (xy 65.757291 -312.32247) (xy 65.747138 -312.322972) (xy 64.347598 -312.322972)
			(xy 64.337441 -312.322468) (xy 64.318674 -312.314695) (xy 64.304309 -312.300333) (xy 64.296533 -312.281567)
			(xy 64.296036 -312.27141) (xy 61.698632 -312.27141) (xy 61.698244 -312.281586) (xy 61.69045 -312.300387)
			(xy 61.676053 -312.314772) (xy 61.657246 -312.322551) (xy 61.64707 -312.322972) (xy 60.24753 -312.322972)
			(xy 60.237362 -312.322512) (xy 60.21857 -312.314738) (xy 60.204184 -312.300364) (xy 60.196396 -312.281578)
			(xy 60.195968 -312.27141) (xy 58.2549 -312.27141) (xy 58.254376 -312.281564) (xy 58.246605 -312.300326)
			(xy 58.232249 -312.314689) (xy 58.213491 -312.32247) (xy 58.203338 -312.322972) (xy 56.803798 -312.322972)
			(xy 56.793641 -312.322468) (xy 56.774874 -312.314695) (xy 56.760509 -312.300333) (xy 56.752733 -312.281567)
			(xy 56.752236 -312.27141) (xy 54.154832 -312.27141) (xy 54.154444 -312.281586) (xy 54.14665 -312.300387)
			(xy 54.132253 -312.314772) (xy 54.113446 -312.322551) (xy 54.10327 -312.322972) (xy 52.70373 -312.322972)
			(xy 52.693562 -312.322512) (xy 52.67477 -312.314738) (xy 52.660384 -312.300364) (xy 52.652596 -312.281578)
			(xy 52.652168 -312.27141) (xy 50.7111 -312.27141) (xy 50.710576 -312.281564) (xy 50.702805 -312.300326)
			(xy 50.688449 -312.314689) (xy 50.669691 -312.32247) (xy 50.659538 -312.322972) (xy 49.259998 -312.322972)
			(xy 49.249841 -312.322468) (xy 49.231074 -312.314695) (xy 49.216709 -312.300333) (xy 49.208933 -312.281567)
			(xy 49.208436 -312.27141) (xy 46.611032 -312.27141) (xy 46.610644 -312.281586) (xy 46.60285 -312.300387)
			(xy 46.588453 -312.314772) (xy 46.569646 -312.322551) (xy 46.55947 -312.322972) (xy 45.15993 -312.322972)
			(xy 45.149762 -312.322512) (xy 45.13097 -312.314738) (xy 45.116584 -312.300364) (xy 45.108796 -312.281578)
			(xy 45.108368 -312.27141) (xy 43.1673 -312.27141) (xy 43.166776 -312.281564) (xy 43.159005 -312.300326)
			(xy 43.144649 -312.314689) (xy 43.125891 -312.32247) (xy 43.115738 -312.322972) (xy 41.716198 -312.322972)
			(xy 41.706041 -312.322468) (xy 41.687274 -312.314695) (xy 41.672909 -312.300333) (xy 41.665133 -312.281567)
			(xy 41.664636 -312.27141) (xy 39.067232 -312.27141) (xy 39.066844 -312.281586) (xy 39.05905 -312.300387)
			(xy 39.044653 -312.314772) (xy 39.025846 -312.322551) (xy 39.01567 -312.322972) (xy 37.61613 -312.322972)
			(xy 37.605962 -312.322512) (xy 37.58717 -312.314738) (xy 37.572784 -312.300364) (xy 37.564996 -312.281578)
			(xy 37.564568 -312.27141) (xy 35.6235 -312.27141) (xy 35.622976 -312.281564) (xy 35.615205 -312.300326)
			(xy 35.600849 -312.314689) (xy 35.582091 -312.32247) (xy 35.571938 -312.322972) (xy 34.172398 -312.322972)
			(xy 34.162241 -312.322468) (xy 34.143474 -312.314695) (xy 34.129109 -312.300333) (xy 34.121333 -312.281567)
			(xy 34.120836 -312.27141) (xy 31.523432 -312.27141) (xy 31.523044 -312.281586) (xy 31.51525 -312.300387)
			(xy 31.500853 -312.314772) (xy 31.482046 -312.322551) (xy 31.47187 -312.322972) (xy 30.07233 -312.322972)
			(xy 30.062162 -312.322512) (xy 30.04337 -312.314738) (xy 30.028984 -312.300364) (xy 30.021196 -312.281578)
			(xy 30.020768 -312.27141) (xy 28.0797 -312.27141) (xy 28.079176 -312.281564) (xy 28.071405 -312.300326)
			(xy 28.057049 -312.314689) (xy 28.038291 -312.32247) (xy 28.028138 -312.322972) (xy 26.628598 -312.322972)
			(xy 26.618441 -312.322468) (xy 26.599674 -312.314695) (xy 26.585309 -312.300333) (xy 26.577533 -312.281567)
			(xy 26.577036 -312.27141) (xy 23.979632 -312.27141) (xy 23.979244 -312.281586) (xy 23.97145 -312.300387)
			(xy 23.957053 -312.314772) (xy 23.938246 -312.322551) (xy 23.92807 -312.322972) (xy 22.52853 -312.322972)
			(xy 22.518362 -312.322512) (xy 22.49957 -312.314738) (xy 22.485184 -312.300364) (xy 22.477396 -312.281578)
			(xy 22.476968 -312.27141) (xy 20.5359 -312.27141) (xy 20.535376 -312.281564) (xy 20.527605 -312.300326)
			(xy 20.513249 -312.314689) (xy 20.494491 -312.32247) (xy 20.484338 -312.322972) (xy 19.084798 -312.322972)
			(xy 19.074641 -312.322468) (xy 19.055874 -312.314695) (xy 19.041509 -312.300333) (xy 19.033733 -312.281567)
			(xy 19.033236 -312.27141) (xy 16.435832 -312.27141) (xy 16.435444 -312.281586) (xy 16.42765 -312.300387)
			(xy 16.413253 -312.314772) (xy 16.394446 -312.322551) (xy 16.38427 -312.322972) (xy 14.98473 -312.322972)
			(xy 14.974562 -312.322512) (xy 14.95577 -312.314738) (xy 14.941384 -312.300364) (xy 14.933596 -312.281578)
			(xy 14.933168 -312.27141) (xy 12.9921 -312.27141) (xy 12.991576 -312.281564) (xy 12.983805 -312.300326)
			(xy 12.969449 -312.314689) (xy 12.950691 -312.32247) (xy 12.940538 -312.322972) (xy 11.540998 -312.322972)
			(xy 11.530841 -312.322468) (xy 11.512074 -312.314695) (xy 11.497709 -312.300333) (xy 11.489933 -312.281567)
			(xy 11.489436 -312.27141) (xy 8.892032 -312.27141) (xy 8.891644 -312.281586) (xy 8.88385 -312.300387)
			(xy 8.869453 -312.314772) (xy 8.850646 -312.322551) (xy 8.84047 -312.322972) (xy 7.44093 -312.322972)
			(xy 7.430762 -312.322512) (xy 7.41197 -312.314738) (xy 7.397584 -312.300364) (xy 7.389796 -312.281578)
			(xy 7.389368 -312.27141) (xy 2.509012 -312.27141) (xy 2.509012 -313.121294) (xy 7.389368 -313.121294)
			(xy 7.389368 -312.712354) (xy 7.389797 -312.70219) (xy 7.397592 -312.683414) (xy 7.411978 -312.669049)
			(xy 7.430765 -312.661282) (xy 7.44093 -312.660792) (xy 8.84047 -312.660792) (xy 8.85062 -312.661357)
			(xy 8.86938 -312.669113) (xy 8.883745 -312.683456) (xy 8.891528 -312.702205) (xy 8.892032 -312.712354)
			(xy 8.892032 -313.121294) (xy 14.933168 -313.121294) (xy 14.933168 -312.712354) (xy 14.933597 -312.70219)
			(xy 14.941392 -312.683414) (xy 14.955778 -312.669049) (xy 14.974565 -312.661282) (xy 14.98473 -312.660792)
			(xy 16.38427 -312.660792) (xy 16.39442 -312.661357) (xy 16.41318 -312.669113) (xy 16.427545 -312.683456)
			(xy 16.435328 -312.702205) (xy 16.435832 -312.712354) (xy 16.435832 -313.121294) (xy 22.476968 -313.121294)
			(xy 22.476968 -312.712354) (xy 22.477397 -312.70219) (xy 22.485192 -312.683414) (xy 22.499578 -312.669049)
			(xy 22.518365 -312.661282) (xy 22.52853 -312.660792) (xy 23.92807 -312.660792) (xy 23.93822 -312.661357)
			(xy 23.95698 -312.669113) (xy 23.971345 -312.683456) (xy 23.979128 -312.702205) (xy 23.979632 -312.712354)
			(xy 23.979632 -313.121294) (xy 30.020768 -313.121294) (xy 30.020768 -312.712354) (xy 30.021197 -312.70219)
			(xy 30.028992 -312.683414) (xy 30.043378 -312.669049) (xy 30.062165 -312.661282) (xy 30.07233 -312.660792)
			(xy 31.47187 -312.660792) (xy 31.48202 -312.661357) (xy 31.50078 -312.669113) (xy 31.515145 -312.683456)
			(xy 31.522928 -312.702205) (xy 31.523432 -312.712354) (xy 31.523432 -313.121294) (xy 37.564568 -313.121294)
			(xy 37.564568 -312.712354) (xy 37.564997 -312.70219) (xy 37.572792 -312.683414) (xy 37.587178 -312.669049)
			(xy 37.605965 -312.661282) (xy 37.61613 -312.660792) (xy 39.01567 -312.660792) (xy 39.02582 -312.661357)
			(xy 39.04458 -312.669113) (xy 39.058945 -312.683456) (xy 39.066728 -312.702205) (xy 39.067232 -312.712354)
			(xy 39.067232 -313.121294) (xy 45.108368 -313.121294) (xy 45.108368 -312.712354) (xy 45.108797 -312.70219)
			(xy 45.116592 -312.683414) (xy 45.130978 -312.669049) (xy 45.149765 -312.661282) (xy 45.15993 -312.660792)
			(xy 46.55947 -312.660792) (xy 46.56962 -312.661357) (xy 46.58838 -312.669113) (xy 46.602745 -312.683456)
			(xy 46.610528 -312.702205) (xy 46.611032 -312.712354) (xy 46.611032 -313.121294) (xy 52.652168 -313.121294)
			(xy 52.652168 -312.712354) (xy 52.652597 -312.70219) (xy 52.660392 -312.683414) (xy 52.674778 -312.669049)
			(xy 52.693565 -312.661282) (xy 52.70373 -312.660792) (xy 54.10327 -312.660792) (xy 54.11342 -312.661357)
			(xy 54.13218 -312.669113) (xy 54.146545 -312.683456) (xy 54.154328 -312.702205) (xy 54.154832 -312.712354)
			(xy 54.154832 -313.121294) (xy 60.195968 -313.121294) (xy 60.195968 -312.712354) (xy 60.196397 -312.70219)
			(xy 60.204192 -312.683414) (xy 60.218578 -312.669049) (xy 60.237365 -312.661282) (xy 60.24753 -312.660792)
			(xy 61.64707 -312.660792) (xy 61.65722 -312.661357) (xy 61.67598 -312.669113) (xy 61.690345 -312.683456)
			(xy 61.698128 -312.702205) (xy 61.698632 -312.712354) (xy 61.698632 -313.121294) (xy 158.062168 -313.121294)
			(xy 158.062168 -312.712354) (xy 158.062597 -312.70219) (xy 158.070392 -312.683414) (xy 158.084778 -312.669049)
			(xy 158.103565 -312.661282) (xy 158.11373 -312.660792) (xy 159.51327 -312.660792) (xy 159.52342 -312.661357)
			(xy 159.54218 -312.669113) (xy 159.556545 -312.683456) (xy 159.564328 -312.702205) (xy 159.564832 -312.712354)
			(xy 159.564832 -313.121294) (xy 165.605968 -313.121294) (xy 165.605968 -312.712354) (xy 165.606397 -312.70219)
			(xy 165.614192 -312.683414) (xy 165.628578 -312.669049) (xy 165.647365 -312.661282) (xy 165.65753 -312.660792)
			(xy 167.05707 -312.660792) (xy 167.06722 -312.661357) (xy 167.08598 -312.669113) (xy 167.100345 -312.683456)
			(xy 167.108128 -312.702205) (xy 167.108632 -312.712354) (xy 167.108632 -313.121294) (xy 173.149768 -313.121294)
			(xy 173.149768 -312.712354) (xy 173.150197 -312.70219) (xy 173.157992 -312.683414) (xy 173.172378 -312.669049)
			(xy 173.191165 -312.661282) (xy 173.20133 -312.660792) (xy 174.60087 -312.660792) (xy 174.61102 -312.661357)
			(xy 174.62978 -312.669113) (xy 174.644145 -312.683456) (xy 174.651928 -312.702205) (xy 174.652432 -312.712354)
			(xy 174.652432 -313.121294) (xy 180.693568 -313.121294) (xy 180.693568 -312.712354) (xy 180.693997 -312.70219)
			(xy 180.701792 -312.683414) (xy 180.716178 -312.669049) (xy 180.734965 -312.661282) (xy 180.74513 -312.660792)
			(xy 182.14467 -312.660792) (xy 182.15482 -312.661357) (xy 182.17358 -312.669113) (xy 182.187945 -312.683456)
			(xy 182.195728 -312.702205) (xy 182.196232 -312.712354) (xy 182.196232 -313.121294) (xy 188.237368 -313.121294)
			(xy 188.237368 -312.712354) (xy 188.237797 -312.70219) (xy 188.245592 -312.683414) (xy 188.259978 -312.669049)
			(xy 188.278765 -312.661282) (xy 188.28893 -312.660792) (xy 189.68847 -312.660792) (xy 189.69862 -312.661357)
			(xy 189.71738 -312.669113) (xy 189.731745 -312.683456) (xy 189.739528 -312.702205) (xy 189.740032 -312.712354)
			(xy 189.740032 -313.121294) (xy 195.781168 -313.121294) (xy 195.781168 -312.712354) (xy 195.781597 -312.70219)
			(xy 195.789392 -312.683414) (xy 195.803778 -312.669049) (xy 195.822565 -312.661282) (xy 195.83273 -312.660792)
			(xy 197.23227 -312.660792) (xy 197.24242 -312.661357) (xy 197.26118 -312.669113) (xy 197.275545 -312.683456)
			(xy 197.283328 -312.702205) (xy 197.283832 -312.712354) (xy 197.283832 -313.121294) (xy 203.324968 -313.121294)
			(xy 203.324968 -312.712354) (xy 203.325397 -312.70219) (xy 203.333192 -312.683414) (xy 203.347578 -312.669049)
			(xy 203.366365 -312.661282) (xy 203.37653 -312.660792) (xy 204.77607 -312.660792) (xy 204.78622 -312.661357)
			(xy 204.80498 -312.669113) (xy 204.819345 -312.683456) (xy 204.827128 -312.702205) (xy 204.827632 -312.712354)
			(xy 204.827632 -313.121294) (xy 210.868768 -313.121294) (xy 210.868768 -312.712354) (xy 210.869197 -312.70219)
			(xy 210.876992 -312.683414) (xy 210.891378 -312.669049) (xy 210.910165 -312.661282) (xy 210.92033 -312.660792)
			(xy 212.31987 -312.660792) (xy 212.33002 -312.661357) (xy 212.34878 -312.669113) (xy 212.363145 -312.683456)
			(xy 212.370928 -312.702205) (xy 212.371432 -312.712354) (xy 212.371432 -313.121294) (xy 255.329436 -313.121294)
			(xy 255.329436 -312.712354) (xy 255.329896 -312.702194) (xy 255.337685 -312.683424) (xy 255.352061 -312.66906)
			(xy 255.370837 -312.661287) (xy 255.380998 -312.660792) (xy 256.780538 -312.660792) (xy 256.790693 -312.661301)
			(xy 256.809454 -312.669079) (xy 256.823816 -312.68344) (xy 256.831597 -312.7022) (xy 256.8321 -312.712354)
			(xy 256.8321 -313.121294) (xy 262.873236 -313.121294) (xy 262.873236 -312.712354) (xy 262.873696 -312.702194)
			(xy 262.881485 -312.683424) (xy 262.895861 -312.66906) (xy 262.914637 -312.661287) (xy 262.924798 -312.660792)
			(xy 264.324338 -312.660792) (xy 264.334493 -312.661301) (xy 264.353254 -312.669079) (xy 264.367616 -312.68344)
			(xy 264.375397 -312.7022) (xy 264.3759 -312.712354) (xy 264.3759 -313.121294) (xy 270.417036 -313.121294)
			(xy 270.417036 -312.712354) (xy 270.417496 -312.702194) (xy 270.425285 -312.683424) (xy 270.439661 -312.66906)
			(xy 270.458437 -312.661287) (xy 270.468598 -312.660792) (xy 271.868138 -312.660792) (xy 271.878293 -312.661301)
			(xy 271.897054 -312.669079) (xy 271.911416 -312.68344) (xy 271.919197 -312.7022) (xy 271.9197 -312.712354)
			(xy 271.9197 -313.121294) (xy 277.960836 -313.121294) (xy 277.960836 -312.712354) (xy 277.961296 -312.702194)
			(xy 277.969085 -312.683424) (xy 277.983461 -312.66906) (xy 278.002237 -312.661287) (xy 278.012398 -312.660792)
			(xy 279.411938 -312.660792) (xy 279.422093 -312.661301) (xy 279.440854 -312.669079) (xy 279.455216 -312.68344)
			(xy 279.462997 -312.7022) (xy 279.4635 -312.712354) (xy 279.4635 -313.121294) (xy 285.504636 -313.121294)
			(xy 285.504636 -312.712354) (xy 285.505096 -312.702194) (xy 285.512885 -312.683424) (xy 285.527261 -312.66906)
			(xy 285.546037 -312.661287) (xy 285.556198 -312.660792) (xy 286.955738 -312.660792) (xy 286.965893 -312.661301)
			(xy 286.984654 -312.669079) (xy 286.999016 -312.68344) (xy 287.006797 -312.7022) (xy 287.0073 -312.712354)
			(xy 287.0073 -313.121294) (xy 293.048436 -313.121294) (xy 293.048436 -312.712354) (xy 293.048896 -312.702194)
			(xy 293.056685 -312.683424) (xy 293.071061 -312.66906) (xy 293.089837 -312.661287) (xy 293.099998 -312.660792)
			(xy 294.499538 -312.660792) (xy 294.509693 -312.661301) (xy 294.528454 -312.669079) (xy 294.542816 -312.68344)
			(xy 294.550597 -312.7022) (xy 294.5511 -312.712354) (xy 294.5511 -313.121294) (xy 300.592236 -313.121294)
			(xy 300.592236 -312.712354) (xy 300.592696 -312.702194) (xy 300.600485 -312.683424) (xy 300.614861 -312.66906)
			(xy 300.633637 -312.661287) (xy 300.643798 -312.660792) (xy 302.043338 -312.660792) (xy 302.053493 -312.661301)
			(xy 302.072254 -312.669079) (xy 302.086616 -312.68344) (xy 302.094397 -312.7022) (xy 302.0949 -312.712354)
			(xy 302.0949 -313.121294) (xy 308.136036 -313.121294) (xy 308.136036 -312.712354) (xy 308.136496 -312.702194)
			(xy 308.144285 -312.683424) (xy 308.158661 -312.66906) (xy 308.177437 -312.661287) (xy 308.187598 -312.660792)
			(xy 309.587138 -312.660792) (xy 309.597293 -312.661301) (xy 309.616054 -312.669079) (xy 309.630416 -312.68344)
			(xy 309.638197 -312.7022) (xy 309.6387 -312.712354) (xy 309.6387 -313.121294) (xy 406.002236 -313.121294)
			(xy 406.002236 -312.712354) (xy 406.002696 -312.702194) (xy 406.010485 -312.683424) (xy 406.024861 -312.66906)
			(xy 406.043637 -312.661287) (xy 406.053798 -312.660792) (xy 407.453338 -312.660792) (xy 407.463493 -312.661301)
			(xy 407.482254 -312.669079) (xy 407.496616 -312.68344) (xy 407.504397 -312.7022) (xy 407.5049 -312.712354)
			(xy 407.5049 -313.121294) (xy 413.546036 -313.121294) (xy 413.546036 -312.712354) (xy 413.546496 -312.702194)
			(xy 413.554285 -312.683424) (xy 413.568661 -312.66906) (xy 413.587437 -312.661287) (xy 413.597598 -312.660792)
			(xy 414.997138 -312.660792) (xy 415.007293 -312.661301) (xy 415.026054 -312.669079) (xy 415.040416 -312.68344)
			(xy 415.048197 -312.7022) (xy 415.0487 -312.712354) (xy 415.0487 -313.121294) (xy 421.089836 -313.121294)
			(xy 421.089836 -312.712354) (xy 421.090296 -312.702194) (xy 421.098085 -312.683424) (xy 421.112461 -312.66906)
			(xy 421.131237 -312.661287) (xy 421.141398 -312.660792) (xy 422.540938 -312.660792) (xy 422.551093 -312.661301)
			(xy 422.569854 -312.669079) (xy 422.584216 -312.68344) (xy 422.591997 -312.7022) (xy 422.5925 -312.712354)
			(xy 422.5925 -313.121294) (xy 428.633636 -313.121294) (xy 428.633636 -312.712354) (xy 428.634096 -312.702194)
			(xy 428.641885 -312.683424) (xy 428.656261 -312.66906) (xy 428.675037 -312.661287) (xy 428.685198 -312.660792)
			(xy 430.084738 -312.660792) (xy 430.094893 -312.661301) (xy 430.113654 -312.669079) (xy 430.128016 -312.68344)
			(xy 430.135797 -312.7022) (xy 430.1363 -312.712354) (xy 430.1363 -313.121294) (xy 436.177436 -313.121294)
			(xy 436.177436 -312.712354) (xy 436.177896 -312.702194) (xy 436.185685 -312.683424) (xy 436.200061 -312.66906)
			(xy 436.218837 -312.661287) (xy 436.228998 -312.660792) (xy 437.628538 -312.660792) (xy 437.638693 -312.661301)
			(xy 437.657454 -312.669079) (xy 437.671816 -312.68344) (xy 437.679597 -312.7022) (xy 437.6801 -312.712354)
			(xy 437.6801 -313.121294) (xy 443.721236 -313.121294) (xy 443.721236 -312.712354) (xy 443.721696 -312.702194)
			(xy 443.729485 -312.683424) (xy 443.743861 -312.66906) (xy 443.762637 -312.661287) (xy 443.772798 -312.660792)
			(xy 445.172338 -312.660792) (xy 445.182493 -312.661301) (xy 445.201254 -312.669079) (xy 445.215616 -312.68344)
			(xy 445.223397 -312.7022) (xy 445.2239 -312.712354) (xy 445.2239 -313.121294) (xy 451.265036 -313.121294)
			(xy 451.265036 -312.712354) (xy 451.265496 -312.702194) (xy 451.273285 -312.683424) (xy 451.287661 -312.66906)
			(xy 451.306437 -312.661287) (xy 451.316598 -312.660792) (xy 452.716138 -312.660792) (xy 452.726293 -312.661301)
			(xy 452.745054 -312.669079) (xy 452.759416 -312.68344) (xy 452.767197 -312.7022) (xy 452.7677 -312.712354)
			(xy 452.7677 -313.121294) (xy 458.808836 -313.121294) (xy 458.808836 -312.712354) (xy 458.809296 -312.702194)
			(xy 458.817085 -312.683424) (xy 458.831461 -312.66906) (xy 458.850237 -312.661287) (xy 458.860398 -312.660792)
			(xy 460.259938 -312.660792) (xy 460.270093 -312.661301) (xy 460.288854 -312.669079) (xy 460.303216 -312.68344)
			(xy 460.310997 -312.7022) (xy 460.3115 -312.712354) (xy 460.3115 -313.121294) (xy 460.310963 -313.131447)
			(xy 460.303197 -313.150208) (xy 460.288845 -313.164573) (xy 460.27009 -313.172354) (xy 460.259938 -313.172856)
			(xy 458.860398 -313.172856) (xy 458.850226 -313.172438) (xy 458.83143 -313.164651) (xy 458.817045 -313.150264)
			(xy 458.809261 -313.131467) (xy 458.808836 -313.121294) (xy 452.7677 -313.121294) (xy 452.767163 -313.131447)
			(xy 452.759397 -313.150208) (xy 452.745045 -313.164573) (xy 452.72629 -313.172354) (xy 452.716138 -313.172856)
			(xy 451.316598 -313.172856) (xy 451.306426 -313.172438) (xy 451.28763 -313.164651) (xy 451.273245 -313.150264)
			(xy 451.265461 -313.131467) (xy 451.265036 -313.121294) (xy 445.2239 -313.121294) (xy 445.223363 -313.131447)
			(xy 445.215597 -313.150208) (xy 445.201245 -313.164573) (xy 445.18249 -313.172354) (xy 445.172338 -313.172856)
			(xy 443.772798 -313.172856) (xy 443.762626 -313.172438) (xy 443.74383 -313.164651) (xy 443.729445 -313.150264)
			(xy 443.721661 -313.131467) (xy 443.721236 -313.121294) (xy 437.6801 -313.121294) (xy 437.679563 -313.131447)
			(xy 437.671797 -313.150208) (xy 437.657445 -313.164573) (xy 437.63869 -313.172354) (xy 437.628538 -313.172856)
			(xy 436.228998 -313.172856) (xy 436.218826 -313.172438) (xy 436.20003 -313.164651) (xy 436.185645 -313.150264)
			(xy 436.177861 -313.131467) (xy 436.177436 -313.121294) (xy 430.1363 -313.121294) (xy 430.135763 -313.131447)
			(xy 430.127997 -313.150208) (xy 430.113645 -313.164573) (xy 430.09489 -313.172354) (xy 430.084738 -313.172856)
			(xy 428.685198 -313.172856) (xy 428.675026 -313.172438) (xy 428.65623 -313.164651) (xy 428.641845 -313.150264)
			(xy 428.634061 -313.131467) (xy 428.633636 -313.121294) (xy 422.5925 -313.121294) (xy 422.591963 -313.131447)
			(xy 422.584197 -313.150208) (xy 422.569845 -313.164573) (xy 422.55109 -313.172354) (xy 422.540938 -313.172856)
			(xy 421.141398 -313.172856) (xy 421.131226 -313.172438) (xy 421.11243 -313.164651) (xy 421.098045 -313.150264)
			(xy 421.090261 -313.131467) (xy 421.089836 -313.121294) (xy 415.0487 -313.121294) (xy 415.048163 -313.131447)
			(xy 415.040397 -313.150208) (xy 415.026045 -313.164573) (xy 415.00729 -313.172354) (xy 414.997138 -313.172856)
			(xy 413.597598 -313.172856) (xy 413.587426 -313.172438) (xy 413.56863 -313.164651) (xy 413.554245 -313.150264)
			(xy 413.546461 -313.131467) (xy 413.546036 -313.121294) (xy 407.5049 -313.121294) (xy 407.504363 -313.131447)
			(xy 407.496597 -313.150208) (xy 407.482245 -313.164573) (xy 407.46349 -313.172354) (xy 407.453338 -313.172856)
			(xy 406.053798 -313.172856) (xy 406.043626 -313.172438) (xy 406.02483 -313.164651) (xy 406.010445 -313.150264)
			(xy 406.002661 -313.131467) (xy 406.002236 -313.121294) (xy 309.6387 -313.121294) (xy 309.638163 -313.131447)
			(xy 309.630397 -313.150208) (xy 309.616045 -313.164573) (xy 309.59729 -313.172354) (xy 309.587138 -313.172856)
			(xy 308.187598 -313.172856) (xy 308.177426 -313.172438) (xy 308.15863 -313.164651) (xy 308.144245 -313.150264)
			(xy 308.136461 -313.131467) (xy 308.136036 -313.121294) (xy 302.0949 -313.121294) (xy 302.094363 -313.131447)
			(xy 302.086597 -313.150208) (xy 302.072245 -313.164573) (xy 302.05349 -313.172354) (xy 302.043338 -313.172856)
			(xy 300.643798 -313.172856) (xy 300.633626 -313.172438) (xy 300.61483 -313.164651) (xy 300.600445 -313.150264)
			(xy 300.592661 -313.131467) (xy 300.592236 -313.121294) (xy 294.5511 -313.121294) (xy 294.550563 -313.131447)
			(xy 294.542797 -313.150208) (xy 294.528445 -313.164573) (xy 294.50969 -313.172354) (xy 294.499538 -313.172856)
			(xy 293.099998 -313.172856) (xy 293.089826 -313.172438) (xy 293.07103 -313.164651) (xy 293.056645 -313.150264)
			(xy 293.048861 -313.131467) (xy 293.048436 -313.121294) (xy 287.0073 -313.121294) (xy 287.006763 -313.131447)
			(xy 286.998997 -313.150208) (xy 286.984645 -313.164573) (xy 286.96589 -313.172354) (xy 286.955738 -313.172856)
			(xy 285.556198 -313.172856) (xy 285.546026 -313.172438) (xy 285.52723 -313.164651) (xy 285.512845 -313.150264)
			(xy 285.505061 -313.131467) (xy 285.504636 -313.121294) (xy 279.4635 -313.121294) (xy 279.462963 -313.131447)
			(xy 279.455197 -313.150208) (xy 279.440845 -313.164573) (xy 279.42209 -313.172354) (xy 279.411938 -313.172856)
			(xy 278.012398 -313.172856) (xy 278.002226 -313.172438) (xy 277.98343 -313.164651) (xy 277.969045 -313.150264)
			(xy 277.961261 -313.131467) (xy 277.960836 -313.121294) (xy 271.9197 -313.121294) (xy 271.919163 -313.131447)
			(xy 271.911397 -313.150208) (xy 271.897045 -313.164573) (xy 271.87829 -313.172354) (xy 271.868138 -313.172856)
			(xy 270.468598 -313.172856) (xy 270.458426 -313.172438) (xy 270.43963 -313.164651) (xy 270.425245 -313.150264)
			(xy 270.417461 -313.131467) (xy 270.417036 -313.121294) (xy 264.3759 -313.121294) (xy 264.375363 -313.131447)
			(xy 264.367597 -313.150208) (xy 264.353245 -313.164573) (xy 264.33449 -313.172354) (xy 264.324338 -313.172856)
			(xy 262.924798 -313.172856) (xy 262.914626 -313.172438) (xy 262.89583 -313.164651) (xy 262.881445 -313.150264)
			(xy 262.873661 -313.131467) (xy 262.873236 -313.121294) (xy 256.8321 -313.121294) (xy 256.831563 -313.131447)
			(xy 256.823797 -313.150208) (xy 256.809445 -313.164573) (xy 256.79069 -313.172354) (xy 256.780538 -313.172856)
			(xy 255.380998 -313.172856) (xy 255.370826 -313.172438) (xy 255.35203 -313.164651) (xy 255.337645 -313.150264)
			(xy 255.329861 -313.131467) (xy 255.329436 -313.121294) (xy 212.371432 -313.121294) (xy 212.371031 -313.131469)
			(xy 212.363242 -313.150269) (xy 212.348849 -313.164655) (xy 212.330045 -313.172435) (xy 212.31987 -313.172856)
			(xy 210.92033 -313.172856) (xy 210.91016 -313.172411) (xy 210.891364 -313.164635) (xy 210.876978 -313.150256)
			(xy 210.869193 -313.131464) (xy 210.868768 -313.121294) (xy 204.827632 -313.121294) (xy 204.827231 -313.131469)
			(xy 204.819442 -313.150269) (xy 204.805049 -313.164655) (xy 204.786245 -313.172435) (xy 204.77607 -313.172856)
			(xy 203.37653 -313.172856) (xy 203.36636 -313.172411) (xy 203.347564 -313.164635) (xy 203.333178 -313.150256)
			(xy 203.325393 -313.131464) (xy 203.324968 -313.121294) (xy 197.283832 -313.121294) (xy 197.283431 -313.131469)
			(xy 197.275642 -313.150269) (xy 197.261249 -313.164655) (xy 197.242445 -313.172435) (xy 197.23227 -313.172856)
			(xy 195.83273 -313.172856) (xy 195.82256 -313.172411) (xy 195.803764 -313.164635) (xy 195.789378 -313.150256)
			(xy 195.781593 -313.131464) (xy 195.781168 -313.121294) (xy 189.740032 -313.121294) (xy 189.739631 -313.131469)
			(xy 189.731842 -313.150269) (xy 189.717449 -313.164655) (xy 189.698645 -313.172435) (xy 189.68847 -313.172856)
			(xy 188.28893 -313.172856) (xy 188.27876 -313.172411) (xy 188.259964 -313.164635) (xy 188.245578 -313.150256)
			(xy 188.237793 -313.131464) (xy 188.237368 -313.121294) (xy 182.196232 -313.121294) (xy 182.195831 -313.131469)
			(xy 182.188042 -313.150269) (xy 182.173649 -313.164655) (xy 182.154845 -313.172435) (xy 182.14467 -313.172856)
			(xy 180.74513 -313.172856) (xy 180.73496 -313.172411) (xy 180.716164 -313.164635) (xy 180.701778 -313.150256)
			(xy 180.693993 -313.131464) (xy 180.693568 -313.121294) (xy 174.652432 -313.121294) (xy 174.652031 -313.131469)
			(xy 174.644242 -313.150269) (xy 174.629849 -313.164655) (xy 174.611045 -313.172435) (xy 174.60087 -313.172856)
			(xy 173.20133 -313.172856) (xy 173.19116 -313.172411) (xy 173.172364 -313.164635) (xy 173.157978 -313.150256)
			(xy 173.150193 -313.131464) (xy 173.149768 -313.121294) (xy 167.108632 -313.121294) (xy 167.108231 -313.131469)
			(xy 167.100442 -313.150269) (xy 167.086049 -313.164655) (xy 167.067245 -313.172435) (xy 167.05707 -313.172856)
			(xy 165.65753 -313.172856) (xy 165.64736 -313.172411) (xy 165.628564 -313.164635) (xy 165.614178 -313.150256)
			(xy 165.606393 -313.131464) (xy 165.605968 -313.121294) (xy 159.564832 -313.121294) (xy 159.564431 -313.131469)
			(xy 159.556642 -313.150269) (xy 159.542249 -313.164655) (xy 159.523445 -313.172435) (xy 159.51327 -313.172856)
			(xy 158.11373 -313.172856) (xy 158.10356 -313.172411) (xy 158.084764 -313.164635) (xy 158.070378 -313.150256)
			(xy 158.062593 -313.131464) (xy 158.062168 -313.121294) (xy 61.698632 -313.121294) (xy 61.698231 -313.131469)
			(xy 61.690442 -313.150269) (xy 61.676049 -313.164655) (xy 61.657245 -313.172435) (xy 61.64707 -313.172856)
			(xy 60.24753 -313.172856) (xy 60.23736 -313.172411) (xy 60.218564 -313.164635) (xy 60.204178 -313.150256)
			(xy 60.196393 -313.131464) (xy 60.195968 -313.121294) (xy 54.154832 -313.121294) (xy 54.154431 -313.131469)
			(xy 54.146642 -313.150269) (xy 54.132249 -313.164655) (xy 54.113445 -313.172435) (xy 54.10327 -313.172856)
			(xy 52.70373 -313.172856) (xy 52.69356 -313.172411) (xy 52.674764 -313.164635) (xy 52.660378 -313.150256)
			(xy 52.652593 -313.131464) (xy 52.652168 -313.121294) (xy 46.611032 -313.121294) (xy 46.610631 -313.131469)
			(xy 46.602842 -313.150269) (xy 46.588449 -313.164655) (xy 46.569645 -313.172435) (xy 46.55947 -313.172856)
			(xy 45.15993 -313.172856) (xy 45.14976 -313.172411) (xy 45.130964 -313.164635) (xy 45.116578 -313.150256)
			(xy 45.108793 -313.131464) (xy 45.108368 -313.121294) (xy 39.067232 -313.121294) (xy 39.066831 -313.131469)
			(xy 39.059042 -313.150269) (xy 39.044649 -313.164655) (xy 39.025845 -313.172435) (xy 39.01567 -313.172856)
			(xy 37.61613 -313.172856) (xy 37.60596 -313.172411) (xy 37.587164 -313.164635) (xy 37.572778 -313.150256)
			(xy 37.564993 -313.131464) (xy 37.564568 -313.121294) (xy 31.523432 -313.121294) (xy 31.523031 -313.131469)
			(xy 31.515242 -313.150269) (xy 31.500849 -313.164655) (xy 31.482045 -313.172435) (xy 31.47187 -313.172856)
			(xy 30.07233 -313.172856) (xy 30.06216 -313.172411) (xy 30.043364 -313.164635) (xy 30.028978 -313.150256)
			(xy 30.021193 -313.131464) (xy 30.020768 -313.121294) (xy 23.979632 -313.121294) (xy 23.979231 -313.131469)
			(xy 23.971442 -313.150269) (xy 23.957049 -313.164655) (xy 23.938245 -313.172435) (xy 23.92807 -313.172856)
			(xy 22.52853 -313.172856) (xy 22.51836 -313.172411) (xy 22.499564 -313.164635) (xy 22.485178 -313.150256)
			(xy 22.477393 -313.131464) (xy 22.476968 -313.121294) (xy 16.435832 -313.121294) (xy 16.435431 -313.131469)
			(xy 16.427642 -313.150269) (xy 16.413249 -313.164655) (xy 16.394445 -313.172435) (xy 16.38427 -313.172856)
			(xy 14.98473 -313.172856) (xy 14.97456 -313.172411) (xy 14.955764 -313.164635) (xy 14.941378 -313.150256)
			(xy 14.933593 -313.131464) (xy 14.933168 -313.121294) (xy 8.892032 -313.121294) (xy 8.891631 -313.131469)
			(xy 8.883842 -313.150269) (xy 8.869449 -313.164655) (xy 8.850645 -313.172435) (xy 8.84047 -313.172856)
			(xy 7.44093 -313.172856) (xy 7.43076 -313.172411) (xy 7.411964 -313.164635) (xy 7.397578 -313.150256)
			(xy 7.389793 -313.131464) (xy 7.389368 -313.121294) (xy 2.509012 -313.121294) (xy 2.509012 -313.971432)
			(xy 11.489436 -313.971432) (xy 11.489436 -313.562492) (xy 11.489816 -313.552333) (xy 11.497621 -313.533573)
			(xy 11.512031 -313.519249) (xy 11.530837 -313.511556) (xy 11.540998 -313.511184) (xy 12.940538 -313.511184)
			(xy 12.950673 -313.511597) (xy 12.969403 -313.519345) (xy 12.983759 -313.533654) (xy 12.99157 -313.552359)
			(xy 12.9921 -313.562492) (xy 12.9921 -313.971432) (xy 19.033236 -313.971432) (xy 19.033236 -313.562492)
			(xy 19.033616 -313.552333) (xy 19.041421 -313.533573) (xy 19.055831 -313.519249) (xy 19.074637 -313.511556)
			(xy 19.084798 -313.511184) (xy 20.484338 -313.511184) (xy 20.494473 -313.511597) (xy 20.513203 -313.519345)
			(xy 20.527559 -313.533654) (xy 20.53537 -313.552359) (xy 20.5359 -313.562492) (xy 20.5359 -313.971432)
			(xy 26.577036 -313.971432) (xy 26.577036 -313.562492) (xy 26.577416 -313.552333) (xy 26.585221 -313.533573)
			(xy 26.599631 -313.519249) (xy 26.618437 -313.511556) (xy 26.628598 -313.511184) (xy 28.028138 -313.511184)
			(xy 28.038273 -313.511597) (xy 28.057003 -313.519345) (xy 28.071359 -313.533654) (xy 28.07917 -313.552359)
			(xy 28.0797 -313.562492) (xy 28.0797 -313.971432) (xy 34.120836 -313.971432) (xy 34.120836 -313.562492)
			(xy 34.121216 -313.552333) (xy 34.129021 -313.533573) (xy 34.143431 -313.519249) (xy 34.162237 -313.511556)
			(xy 34.172398 -313.511184) (xy 35.571938 -313.511184) (xy 35.582073 -313.511597) (xy 35.600803 -313.519345)
			(xy 35.615159 -313.533654) (xy 35.62297 -313.552359) (xy 35.6235 -313.562492) (xy 35.6235 -313.971432)
			(xy 41.664636 -313.971432) (xy 41.664636 -313.562492) (xy 41.665016 -313.552333) (xy 41.672821 -313.533573)
			(xy 41.687231 -313.519249) (xy 41.706037 -313.511556) (xy 41.716198 -313.511184) (xy 43.115738 -313.511184)
			(xy 43.125873 -313.511597) (xy 43.144603 -313.519345) (xy 43.158959 -313.533654) (xy 43.16677 -313.552359)
			(xy 43.1673 -313.562492) (xy 43.1673 -313.971432) (xy 49.208436 -313.971432) (xy 49.208436 -313.562492)
			(xy 49.208816 -313.552333) (xy 49.216621 -313.533573) (xy 49.231031 -313.519249) (xy 49.249837 -313.511556)
			(xy 49.259998 -313.511184) (xy 50.659538 -313.511184) (xy 50.669673 -313.511597) (xy 50.688403 -313.519345)
			(xy 50.702759 -313.533654) (xy 50.71057 -313.552359) (xy 50.7111 -313.562492) (xy 50.7111 -313.971432)
			(xy 56.752236 -313.971432) (xy 56.752236 -313.562492) (xy 56.752616 -313.552333) (xy 56.760421 -313.533573)
			(xy 56.774831 -313.519249) (xy 56.793637 -313.511556) (xy 56.803798 -313.511184) (xy 58.203338 -313.511184)
			(xy 58.213473 -313.511597) (xy 58.232203 -313.519345) (xy 58.246559 -313.533654) (xy 58.25437 -313.552359)
			(xy 58.2549 -313.562492) (xy 58.2549 -313.971432) (xy 64.296036 -313.971432) (xy 64.296036 -313.562492)
			(xy 64.296416 -313.552333) (xy 64.304221 -313.533573) (xy 64.318631 -313.519249) (xy 64.337437 -313.511556)
			(xy 64.347598 -313.511184) (xy 65.747138 -313.511184) (xy 65.757273 -313.511597) (xy 65.776003 -313.519345)
			(xy 65.790359 -313.533654) (xy 65.79817 -313.552359) (xy 65.7987 -313.562492) (xy 65.7987 -313.971432)
			(xy 162.162236 -313.971432) (xy 162.162236 -313.562492) (xy 162.162616 -313.552333) (xy 162.170421 -313.533573)
			(xy 162.184831 -313.519249) (xy 162.203637 -313.511556) (xy 162.213798 -313.511184) (xy 163.613338 -313.511184)
			(xy 163.623473 -313.511597) (xy 163.642203 -313.519345) (xy 163.656559 -313.533654) (xy 163.66437 -313.552359)
			(xy 163.6649 -313.562492) (xy 163.6649 -313.971432) (xy 169.706036 -313.971432) (xy 169.706036 -313.562492)
			(xy 169.706416 -313.552333) (xy 169.714221 -313.533573) (xy 169.728631 -313.519249) (xy 169.747437 -313.511556)
			(xy 169.757598 -313.511184) (xy 171.157138 -313.511184) (xy 171.167273 -313.511597) (xy 171.186003 -313.519345)
			(xy 171.200359 -313.533654) (xy 171.20817 -313.552359) (xy 171.2087 -313.562492) (xy 171.2087 -313.971432)
			(xy 177.249836 -313.971432) (xy 177.249836 -313.562492) (xy 177.250216 -313.552333) (xy 177.258021 -313.533573)
			(xy 177.272431 -313.519249) (xy 177.291237 -313.511556) (xy 177.301398 -313.511184) (xy 178.700938 -313.511184)
			(xy 178.711073 -313.511597) (xy 178.729803 -313.519345) (xy 178.744159 -313.533654) (xy 178.75197 -313.552359)
			(xy 178.7525 -313.562492) (xy 178.7525 -313.971432) (xy 184.793636 -313.971432) (xy 184.793636 -313.562492)
			(xy 184.794016 -313.552333) (xy 184.801821 -313.533573) (xy 184.816231 -313.519249) (xy 184.835037 -313.511556)
			(xy 184.845198 -313.511184) (xy 186.244738 -313.511184) (xy 186.254873 -313.511597) (xy 186.273603 -313.519345)
			(xy 186.287959 -313.533654) (xy 186.29577 -313.552359) (xy 186.2963 -313.562492) (xy 186.2963 -313.971432)
			(xy 192.337436 -313.971432) (xy 192.337436 -313.562492) (xy 192.337816 -313.552333) (xy 192.345621 -313.533573)
			(xy 192.360031 -313.519249) (xy 192.378837 -313.511556) (xy 192.388998 -313.511184) (xy 193.788538 -313.511184)
			(xy 193.798673 -313.511597) (xy 193.817403 -313.519345) (xy 193.831759 -313.533654) (xy 193.83957 -313.552359)
			(xy 193.8401 -313.562492) (xy 193.8401 -313.971432) (xy 199.881236 -313.971432) (xy 199.881236 -313.562492)
			(xy 199.881616 -313.552333) (xy 199.889421 -313.533573) (xy 199.903831 -313.519249) (xy 199.922637 -313.511556)
			(xy 199.932798 -313.511184) (xy 201.332338 -313.511184) (xy 201.342473 -313.511597) (xy 201.361203 -313.519345)
			(xy 201.375559 -313.533654) (xy 201.38337 -313.552359) (xy 201.3839 -313.562492) (xy 201.3839 -313.971432)
			(xy 207.425036 -313.971432) (xy 207.425036 -313.562492) (xy 207.425416 -313.552333) (xy 207.433221 -313.533573)
			(xy 207.447631 -313.519249) (xy 207.466437 -313.511556) (xy 207.476598 -313.511184) (xy 208.876138 -313.511184)
			(xy 208.886273 -313.511597) (xy 208.905003 -313.519345) (xy 208.919359 -313.533654) (xy 208.92717 -313.552359)
			(xy 208.9277 -313.562492) (xy 208.9277 -313.971432) (xy 214.968836 -313.971432) (xy 214.968836 -313.562492)
			(xy 214.969216 -313.552333) (xy 214.977021 -313.533573) (xy 214.991431 -313.519249) (xy 215.010237 -313.511556)
			(xy 215.020398 -313.511184) (xy 216.419938 -313.511184) (xy 216.430073 -313.511597) (xy 216.448803 -313.519345)
			(xy 216.463159 -313.533654) (xy 216.47097 -313.552359) (xy 216.4715 -313.562492) (xy 216.4715 -313.971432)
			(xy 259.429504 -313.971432) (xy 259.429504 -313.562492) (xy 259.429915 -313.552337) (xy 259.437714 -313.533584)
			(xy 259.452114 -313.51926) (xy 259.470909 -313.511562) (xy 259.481066 -313.511184) (xy 260.880606 -313.511184)
			(xy 260.890738 -313.511623) (xy 260.909468 -313.519361) (xy 260.923826 -313.533662) (xy 260.931637 -313.552362)
			(xy 260.932168 -313.562492) (xy 260.932168 -313.971432) (xy 266.973304 -313.971432) (xy 266.973304 -313.562492)
			(xy 266.973715 -313.552337) (xy 266.981514 -313.533584) (xy 266.995914 -313.51926) (xy 267.014709 -313.511562)
			(xy 267.024866 -313.511184) (xy 268.424406 -313.511184) (xy 268.434538 -313.511623) (xy 268.453268 -313.519361)
			(xy 268.467626 -313.533662) (xy 268.475437 -313.552362) (xy 268.475968 -313.562492) (xy 268.475968 -313.971432)
			(xy 274.517104 -313.971432) (xy 274.517104 -313.562492) (xy 274.517515 -313.552337) (xy 274.525314 -313.533584)
			(xy 274.539714 -313.51926) (xy 274.558509 -313.511562) (xy 274.568666 -313.511184) (xy 275.968206 -313.511184)
			(xy 275.978338 -313.511623) (xy 275.997068 -313.519361) (xy 276.011426 -313.533662) (xy 276.019237 -313.552362)
			(xy 276.019768 -313.562492) (xy 276.019768 -313.971432) (xy 282.060904 -313.971432) (xy 282.060904 -313.562492)
			(xy 282.061315 -313.552337) (xy 282.069114 -313.533584) (xy 282.083514 -313.51926) (xy 282.102309 -313.511562)
			(xy 282.112466 -313.511184) (xy 283.512006 -313.511184) (xy 283.522138 -313.511623) (xy 283.540868 -313.519361)
			(xy 283.555226 -313.533662) (xy 283.563037 -313.552362) (xy 283.563568 -313.562492) (xy 283.563568 -313.971432)
			(xy 289.604704 -313.971432) (xy 289.604704 -313.562492) (xy 289.605115 -313.552337) (xy 289.612914 -313.533584)
			(xy 289.627314 -313.51926) (xy 289.646109 -313.511562) (xy 289.656266 -313.511184) (xy 291.055806 -313.511184)
			(xy 291.065938 -313.511623) (xy 291.084668 -313.519361) (xy 291.099026 -313.533662) (xy 291.106837 -313.552362)
			(xy 291.107368 -313.562492) (xy 291.107368 -313.971432) (xy 297.148504 -313.971432) (xy 297.148504 -313.562492)
			(xy 297.148915 -313.552337) (xy 297.156714 -313.533584) (xy 297.171114 -313.51926) (xy 297.189909 -313.511562)
			(xy 297.200066 -313.511184) (xy 298.599606 -313.511184) (xy 298.609738 -313.511623) (xy 298.628468 -313.519361)
			(xy 298.642826 -313.533662) (xy 298.650637 -313.552362) (xy 298.651168 -313.562492) (xy 298.651168 -313.971432)
			(xy 304.692304 -313.971432) (xy 304.692304 -313.562492) (xy 304.692715 -313.552337) (xy 304.700514 -313.533584)
			(xy 304.714914 -313.51926) (xy 304.733709 -313.511562) (xy 304.743866 -313.511184) (xy 306.143406 -313.511184)
			(xy 306.153538 -313.511623) (xy 306.172268 -313.519361) (xy 306.186626 -313.533662) (xy 306.194437 -313.552362)
			(xy 306.194968 -313.562492) (xy 306.194968 -313.971432) (xy 312.236104 -313.971432) (xy 312.236104 -313.562492)
			(xy 312.236515 -313.552337) (xy 312.244314 -313.533584) (xy 312.258714 -313.51926) (xy 312.277509 -313.511562)
			(xy 312.287666 -313.511184) (xy 313.687206 -313.511184) (xy 313.697338 -313.511623) (xy 313.716068 -313.519361)
			(xy 313.730426 -313.533662) (xy 313.738237 -313.552362) (xy 313.738768 -313.562492) (xy 313.738768 -313.971432)
			(xy 410.102304 -313.971432) (xy 410.102304 -313.562492) (xy 410.102715 -313.552337) (xy 410.110514 -313.533584)
			(xy 410.124914 -313.51926) (xy 410.143709 -313.511562) (xy 410.153866 -313.511184) (xy 411.553406 -313.511184)
			(xy 411.563538 -313.511623) (xy 411.582268 -313.519361) (xy 411.596626 -313.533662) (xy 411.604437 -313.552362)
			(xy 411.604968 -313.562492) (xy 411.604968 -313.971432) (xy 417.646104 -313.971432) (xy 417.646104 -313.562492)
			(xy 417.646515 -313.552337) (xy 417.654314 -313.533584) (xy 417.668714 -313.51926) (xy 417.687509 -313.511562)
			(xy 417.697666 -313.511184) (xy 419.097206 -313.511184) (xy 419.107338 -313.511623) (xy 419.126068 -313.519361)
			(xy 419.140426 -313.533662) (xy 419.148237 -313.552362) (xy 419.148768 -313.562492) (xy 419.148768 -313.971432)
			(xy 425.189904 -313.971432) (xy 425.189904 -313.562492) (xy 425.190315 -313.552337) (xy 425.198114 -313.533584)
			(xy 425.212514 -313.51926) (xy 425.231309 -313.511562) (xy 425.241466 -313.511184) (xy 426.641006 -313.511184)
			(xy 426.651138 -313.511623) (xy 426.669868 -313.519361) (xy 426.684226 -313.533662) (xy 426.692037 -313.552362)
			(xy 426.692568 -313.562492) (xy 426.692568 -313.971432) (xy 432.733704 -313.971432) (xy 432.733704 -313.562492)
			(xy 432.734115 -313.552337) (xy 432.741914 -313.533584) (xy 432.756314 -313.51926) (xy 432.775109 -313.511562)
			(xy 432.785266 -313.511184) (xy 434.184806 -313.511184) (xy 434.194938 -313.511623) (xy 434.213668 -313.519361)
			(xy 434.228026 -313.533662) (xy 434.235837 -313.552362) (xy 434.236368 -313.562492) (xy 434.236368 -313.971432)
			(xy 440.277504 -313.971432) (xy 440.277504 -313.562492) (xy 440.277915 -313.552337) (xy 440.285714 -313.533584)
			(xy 440.300114 -313.51926) (xy 440.318909 -313.511562) (xy 440.329066 -313.511184) (xy 441.728606 -313.511184)
			(xy 441.738738 -313.511623) (xy 441.757468 -313.519361) (xy 441.771826 -313.533662) (xy 441.779637 -313.552362)
			(xy 441.780168 -313.562492) (xy 441.780168 -313.971432) (xy 447.821304 -313.971432) (xy 447.821304 -313.562492)
			(xy 447.821715 -313.552337) (xy 447.829514 -313.533584) (xy 447.843914 -313.51926) (xy 447.862709 -313.511562)
			(xy 447.872866 -313.511184) (xy 449.272406 -313.511184) (xy 449.282538 -313.511623) (xy 449.301268 -313.519361)
			(xy 449.315626 -313.533662) (xy 449.323437 -313.552362) (xy 449.323968 -313.562492) (xy 449.323968 -313.971432)
			(xy 455.365104 -313.971432) (xy 455.365104 -313.562492) (xy 455.365515 -313.552337) (xy 455.373314 -313.533584)
			(xy 455.387714 -313.51926) (xy 455.406509 -313.511562) (xy 455.416666 -313.511184) (xy 456.816206 -313.511184)
			(xy 456.826338 -313.511623) (xy 456.845068 -313.519361) (xy 456.859426 -313.533662) (xy 456.867237 -313.552362)
			(xy 456.867768 -313.562492) (xy 456.867768 -313.971432) (xy 462.908904 -313.971432) (xy 462.908904 -313.562492)
			(xy 462.909315 -313.552337) (xy 462.917114 -313.533584) (xy 462.931514 -313.51926) (xy 462.950309 -313.511562)
			(xy 462.960466 -313.511184) (xy 464.360006 -313.511184) (xy 464.370138 -313.511623) (xy 464.388868 -313.519361)
			(xy 464.403226 -313.533662) (xy 464.411037 -313.552362) (xy 464.411568 -313.562492) (xy 464.411568 -313.971432)
			(xy 464.411204 -313.981592) (xy 464.403392 -314.000352) (xy 464.388977 -314.014675) (xy 464.370169 -314.022368)
			(xy 464.360006 -314.02274) (xy 462.960466 -314.02274) (xy 462.950335 -314.022301) (xy 462.931609 -314.014558)
			(xy 462.917253 -314.000257) (xy 462.909439 -313.981561) (xy 462.908904 -313.971432) (xy 456.867768 -313.971432)
			(xy 456.867404 -313.981592) (xy 456.859592 -314.000352) (xy 456.845177 -314.014675) (xy 456.826369 -314.022368)
			(xy 456.816206 -314.02274) (xy 455.416666 -314.02274) (xy 455.406535 -314.022301) (xy 455.387809 -314.014558)
			(xy 455.373453 -314.000257) (xy 455.365639 -313.981561) (xy 455.365104 -313.971432) (xy 449.323968 -313.971432)
			(xy 449.323604 -313.981592) (xy 449.315792 -314.000352) (xy 449.301377 -314.014675) (xy 449.282569 -314.022368)
			(xy 449.272406 -314.02274) (xy 447.872866 -314.02274) (xy 447.862735 -314.022301) (xy 447.844009 -314.014558)
			(xy 447.829653 -314.000257) (xy 447.821839 -313.981561) (xy 447.821304 -313.971432) (xy 441.780168 -313.971432)
			(xy 441.779804 -313.981592) (xy 441.771992 -314.000352) (xy 441.757577 -314.014675) (xy 441.738769 -314.022368)
			(xy 441.728606 -314.02274) (xy 440.329066 -314.02274) (xy 440.318935 -314.022301) (xy 440.300209 -314.014558)
			(xy 440.285853 -314.000257) (xy 440.278039 -313.981561) (xy 440.277504 -313.971432) (xy 434.236368 -313.971432)
			(xy 434.236004 -313.981592) (xy 434.228192 -314.000352) (xy 434.213777 -314.014675) (xy 434.194969 -314.022368)
			(xy 434.184806 -314.02274) (xy 432.785266 -314.02274) (xy 432.775135 -314.022301) (xy 432.756409 -314.014558)
			(xy 432.742053 -314.000257) (xy 432.734239 -313.981561) (xy 432.733704 -313.971432) (xy 426.692568 -313.971432)
			(xy 426.692204 -313.981592) (xy 426.684392 -314.000352) (xy 426.669977 -314.014675) (xy 426.651169 -314.022368)
			(xy 426.641006 -314.02274) (xy 425.241466 -314.02274) (xy 425.231335 -314.022301) (xy 425.212609 -314.014558)
			(xy 425.198253 -314.000257) (xy 425.190439 -313.981561) (xy 425.189904 -313.971432) (xy 419.148768 -313.971432)
			(xy 419.148404 -313.981592) (xy 419.140592 -314.000352) (xy 419.126177 -314.014675) (xy 419.107369 -314.022368)
			(xy 419.097206 -314.02274) (xy 417.697666 -314.02274) (xy 417.687535 -314.022301) (xy 417.668809 -314.014558)
			(xy 417.654453 -314.000257) (xy 417.646639 -313.981561) (xy 417.646104 -313.971432) (xy 411.604968 -313.971432)
			(xy 411.604604 -313.981592) (xy 411.596792 -314.000352) (xy 411.582377 -314.014675) (xy 411.563569 -314.022368)
			(xy 411.553406 -314.02274) (xy 410.153866 -314.02274) (xy 410.143735 -314.022301) (xy 410.125009 -314.014558)
			(xy 410.110653 -314.000257) (xy 410.102839 -313.981561) (xy 410.102304 -313.971432) (xy 313.738768 -313.971432)
			(xy 313.738404 -313.981592) (xy 313.730592 -314.000352) (xy 313.716177 -314.014675) (xy 313.697369 -314.022368)
			(xy 313.687206 -314.02274) (xy 312.287666 -314.02274) (xy 312.277535 -314.022301) (xy 312.258809 -314.014558)
			(xy 312.244453 -314.000257) (xy 312.236639 -313.981561) (xy 312.236104 -313.971432) (xy 306.194968 -313.971432)
			(xy 306.194604 -313.981592) (xy 306.186792 -314.000352) (xy 306.172377 -314.014675) (xy 306.153569 -314.022368)
			(xy 306.143406 -314.02274) (xy 304.743866 -314.02274) (xy 304.733735 -314.022301) (xy 304.715009 -314.014558)
			(xy 304.700653 -314.000257) (xy 304.692839 -313.981561) (xy 304.692304 -313.971432) (xy 298.651168 -313.971432)
			(xy 298.650804 -313.981592) (xy 298.642992 -314.000352) (xy 298.628577 -314.014675) (xy 298.609769 -314.022368)
			(xy 298.599606 -314.02274) (xy 297.200066 -314.02274) (xy 297.189935 -314.022301) (xy 297.171209 -314.014558)
			(xy 297.156853 -314.000257) (xy 297.149039 -313.981561) (xy 297.148504 -313.971432) (xy 291.107368 -313.971432)
			(xy 291.107004 -313.981592) (xy 291.099192 -314.000352) (xy 291.084777 -314.014675) (xy 291.065969 -314.022368)
			(xy 291.055806 -314.02274) (xy 289.656266 -314.02274) (xy 289.646135 -314.022301) (xy 289.627409 -314.014558)
			(xy 289.613053 -314.000257) (xy 289.605239 -313.981561) (xy 289.604704 -313.971432) (xy 283.563568 -313.971432)
			(xy 283.563204 -313.981592) (xy 283.555392 -314.000352) (xy 283.540977 -314.014675) (xy 283.522169 -314.022368)
			(xy 283.512006 -314.02274) (xy 282.112466 -314.02274) (xy 282.102335 -314.022301) (xy 282.083609 -314.014558)
			(xy 282.069253 -314.000257) (xy 282.061439 -313.981561) (xy 282.060904 -313.971432) (xy 276.019768 -313.971432)
			(xy 276.019404 -313.981592) (xy 276.011592 -314.000352) (xy 275.997177 -314.014675) (xy 275.978369 -314.022368)
			(xy 275.968206 -314.02274) (xy 274.568666 -314.02274) (xy 274.558535 -314.022301) (xy 274.539809 -314.014558)
			(xy 274.525453 -314.000257) (xy 274.517639 -313.981561) (xy 274.517104 -313.971432) (xy 268.475968 -313.971432)
			(xy 268.475604 -313.981592) (xy 268.467792 -314.000352) (xy 268.453377 -314.014675) (xy 268.434569 -314.022368)
			(xy 268.424406 -314.02274) (xy 267.024866 -314.02274) (xy 267.014735 -314.022301) (xy 266.996009 -314.014558)
			(xy 266.981653 -314.000257) (xy 266.973839 -313.981561) (xy 266.973304 -313.971432) (xy 260.932168 -313.971432)
			(xy 260.931804 -313.981592) (xy 260.923992 -314.000352) (xy 260.909577 -314.014675) (xy 260.890769 -314.022368)
			(xy 260.880606 -314.02274) (xy 259.481066 -314.02274) (xy 259.470935 -314.022301) (xy 259.452209 -314.014558)
			(xy 259.437853 -314.000257) (xy 259.430039 -313.981561) (xy 259.429504 -313.971432) (xy 216.4715 -313.971432)
			(xy 216.471105 -313.981588) (xy 216.463298 -314.000341) (xy 216.448894 -314.014664) (xy 216.430097 -314.022362)
			(xy 216.419938 -314.02274) (xy 215.020398 -314.02274) (xy 215.010269 -314.022274) (xy 214.991544 -314.014542)
			(xy 214.977187 -314.000249) (xy 214.969371 -313.981559) (xy 214.968836 -313.971432) (xy 208.9277 -313.971432)
			(xy 208.927305 -313.981588) (xy 208.919498 -314.000341) (xy 208.905094 -314.014664) (xy 208.886297 -314.022362)
			(xy 208.876138 -314.02274) (xy 207.476598 -314.02274) (xy 207.466469 -314.022274) (xy 207.447744 -314.014542)
			(xy 207.433387 -314.000249) (xy 207.425571 -313.981559) (xy 207.425036 -313.971432) (xy 201.3839 -313.971432)
			(xy 201.383505 -313.981588) (xy 201.375698 -314.000341) (xy 201.361294 -314.014664) (xy 201.342497 -314.022362)
			(xy 201.332338 -314.02274) (xy 199.932798 -314.02274) (xy 199.922669 -314.022274) (xy 199.903944 -314.014542)
			(xy 199.889587 -314.000249) (xy 199.881771 -313.981559) (xy 199.881236 -313.971432) (xy 193.8401 -313.971432)
			(xy 193.839705 -313.981588) (xy 193.831898 -314.000341) (xy 193.817494 -314.014664) (xy 193.798697 -314.022362)
			(xy 193.788538 -314.02274) (xy 192.388998 -314.02274) (xy 192.378869 -314.022274) (xy 192.360144 -314.014542)
			(xy 192.345787 -314.000249) (xy 192.337971 -313.981559) (xy 192.337436 -313.971432) (xy 186.2963 -313.971432)
			(xy 186.295905 -313.981588) (xy 186.288098 -314.000341) (xy 186.273694 -314.014664) (xy 186.254897 -314.022362)
			(xy 186.244738 -314.02274) (xy 184.845198 -314.02274) (xy 184.835069 -314.022274) (xy 184.816344 -314.014542)
			(xy 184.801987 -314.000249) (xy 184.794171 -313.981559) (xy 184.793636 -313.971432) (xy 178.7525 -313.971432)
			(xy 178.752105 -313.981588) (xy 178.744298 -314.000341) (xy 178.729894 -314.014664) (xy 178.711097 -314.022362)
			(xy 178.700938 -314.02274) (xy 177.301398 -314.02274) (xy 177.291269 -314.022274) (xy 177.272544 -314.014542)
			(xy 177.258187 -314.000249) (xy 177.250371 -313.981559) (xy 177.249836 -313.971432) (xy 171.2087 -313.971432)
			(xy 171.208305 -313.981588) (xy 171.200498 -314.000341) (xy 171.186094 -314.014664) (xy 171.167297 -314.022362)
			(xy 171.157138 -314.02274) (xy 169.757598 -314.02274) (xy 169.747469 -314.022274) (xy 169.728744 -314.014542)
			(xy 169.714387 -314.000249) (xy 169.706571 -313.981559) (xy 169.706036 -313.971432) (xy 163.6649 -313.971432)
			(xy 163.664505 -313.981588) (xy 163.656698 -314.000341) (xy 163.642294 -314.014664) (xy 163.623497 -314.022362)
			(xy 163.613338 -314.02274) (xy 162.213798 -314.02274) (xy 162.203669 -314.022274) (xy 162.184944 -314.014542)
			(xy 162.170587 -314.000249) (xy 162.162771 -313.981559) (xy 162.162236 -313.971432) (xy 65.7987 -313.971432)
			(xy 65.798305 -313.981588) (xy 65.790498 -314.000341) (xy 65.776094 -314.014664) (xy 65.757297 -314.022362)
			(xy 65.747138 -314.02274) (xy 64.347598 -314.02274) (xy 64.337469 -314.022274) (xy 64.318744 -314.014542)
			(xy 64.304387 -314.000249) (xy 64.296571 -313.981559) (xy 64.296036 -313.971432) (xy 58.2549 -313.971432)
			(xy 58.254505 -313.981588) (xy 58.246698 -314.000341) (xy 58.232294 -314.014664) (xy 58.213497 -314.022362)
			(xy 58.203338 -314.02274) (xy 56.803798 -314.02274) (xy 56.793669 -314.022274) (xy 56.774944 -314.014542)
			(xy 56.760587 -314.000249) (xy 56.752771 -313.981559) (xy 56.752236 -313.971432) (xy 50.7111 -313.971432)
			(xy 50.710705 -313.981588) (xy 50.702898 -314.000341) (xy 50.688494 -314.014664) (xy 50.669697 -314.022362)
			(xy 50.659538 -314.02274) (xy 49.259998 -314.02274) (xy 49.249869 -314.022274) (xy 49.231144 -314.014542)
			(xy 49.216787 -314.000249) (xy 49.208971 -313.981559) (xy 49.208436 -313.971432) (xy 43.1673 -313.971432)
			(xy 43.166905 -313.981588) (xy 43.159098 -314.000341) (xy 43.144694 -314.014664) (xy 43.125897 -314.022362)
			(xy 43.115738 -314.02274) (xy 41.716198 -314.02274) (xy 41.706069 -314.022274) (xy 41.687344 -314.014542)
			(xy 41.672987 -314.000249) (xy 41.665171 -313.981559) (xy 41.664636 -313.971432) (xy 35.6235 -313.971432)
			(xy 35.623105 -313.981588) (xy 35.615298 -314.000341) (xy 35.600894 -314.014664) (xy 35.582097 -314.022362)
			(xy 35.571938 -314.02274) (xy 34.172398 -314.02274) (xy 34.162269 -314.022274) (xy 34.143544 -314.014542)
			(xy 34.129187 -314.000249) (xy 34.121371 -313.981559) (xy 34.120836 -313.971432) (xy 28.0797 -313.971432)
			(xy 28.079305 -313.981588) (xy 28.071498 -314.000341) (xy 28.057094 -314.014664) (xy 28.038297 -314.022362)
			(xy 28.028138 -314.02274) (xy 26.628598 -314.02274) (xy 26.618469 -314.022274) (xy 26.599744 -314.014542)
			(xy 26.585387 -314.000249) (xy 26.577571 -313.981559) (xy 26.577036 -313.971432) (xy 20.5359 -313.971432)
			(xy 20.535505 -313.981588) (xy 20.527698 -314.000341) (xy 20.513294 -314.014664) (xy 20.494497 -314.022362)
			(xy 20.484338 -314.02274) (xy 19.084798 -314.02274) (xy 19.074669 -314.022274) (xy 19.055944 -314.014542)
			(xy 19.041587 -314.000249) (xy 19.033771 -313.981559) (xy 19.033236 -313.971432) (xy 12.9921 -313.971432)
			(xy 12.991705 -313.981588) (xy 12.983898 -314.000341) (xy 12.969494 -314.014664) (xy 12.950697 -314.022362)
			(xy 12.940538 -314.02274) (xy 11.540998 -314.02274) (xy 11.530869 -314.022274) (xy 11.512144 -314.014542)
			(xy 11.497787 -314.000249) (xy 11.489971 -313.981559) (xy 11.489436 -313.971432) (xy 2.509012 -313.971432)
			(xy 2.509012 -314.821316) (xy 7.389368 -314.821316) (xy 7.389368 -314.412376) (xy 7.389801 -314.402224)
			(xy 7.397599 -314.383477) (xy 7.411991 -314.369156) (xy 7.430776 -314.361451) (xy 7.44093 -314.361068)
			(xy 8.84047 -314.361068) (xy 8.850598 -314.361552) (xy 8.869324 -314.369275) (xy 8.883683 -314.383563)
			(xy 8.891498 -314.40225) (xy 8.892032 -314.412376) (xy 8.892032 -314.821316) (xy 14.933168 -314.821316)
			(xy 14.933168 -314.412376) (xy 14.933601 -314.402224) (xy 14.941399 -314.383477) (xy 14.955791 -314.369156)
			(xy 14.974576 -314.361451) (xy 14.98473 -314.361068) (xy 16.38427 -314.361068) (xy 16.394398 -314.361552)
			(xy 16.413124 -314.369275) (xy 16.427483 -314.383563) (xy 16.435298 -314.40225) (xy 16.435832 -314.412376)
			(xy 16.435832 -314.821316) (xy 22.476968 -314.821316) (xy 22.476968 -314.412376) (xy 22.477401 -314.402224)
			(xy 22.485199 -314.383477) (xy 22.499591 -314.369156) (xy 22.518376 -314.361451) (xy 22.52853 -314.361068)
			(xy 23.92807 -314.361068) (xy 23.938198 -314.361552) (xy 23.956924 -314.369275) (xy 23.971283 -314.383563)
			(xy 23.979098 -314.40225) (xy 23.979632 -314.412376) (xy 23.979632 -314.821316) (xy 30.020768 -314.821316)
			(xy 30.020768 -314.412376) (xy 30.021201 -314.402224) (xy 30.028999 -314.383477) (xy 30.043391 -314.369156)
			(xy 30.062176 -314.361451) (xy 30.07233 -314.361068) (xy 31.47187 -314.361068) (xy 31.481998 -314.361552)
			(xy 31.500724 -314.369275) (xy 31.515083 -314.383563) (xy 31.522898 -314.40225) (xy 31.523432 -314.412376)
			(xy 31.523432 -314.821316) (xy 37.564568 -314.821316) (xy 37.564568 -314.412376) (xy 37.565001 -314.402224)
			(xy 37.572799 -314.383477) (xy 37.587191 -314.369156) (xy 37.605976 -314.361451) (xy 37.61613 -314.361068)
			(xy 39.01567 -314.361068) (xy 39.025798 -314.361552) (xy 39.044524 -314.369275) (xy 39.058883 -314.383563)
			(xy 39.066698 -314.40225) (xy 39.067232 -314.412376) (xy 39.067232 -314.821316) (xy 45.108368 -314.821316)
			(xy 45.108368 -314.412376) (xy 45.108801 -314.402224) (xy 45.116599 -314.383477) (xy 45.130991 -314.369156)
			(xy 45.149776 -314.361451) (xy 45.15993 -314.361068) (xy 46.55947 -314.361068) (xy 46.569598 -314.361552)
			(xy 46.588324 -314.369275) (xy 46.602683 -314.383563) (xy 46.610498 -314.40225) (xy 46.611032 -314.412376)
			(xy 46.611032 -314.821316) (xy 52.652168 -314.821316) (xy 52.652168 -314.412376) (xy 52.652601 -314.402224)
			(xy 52.660399 -314.383477) (xy 52.674791 -314.369156) (xy 52.693576 -314.361451) (xy 52.70373 -314.361068)
			(xy 54.10327 -314.361068) (xy 54.113398 -314.361552) (xy 54.132124 -314.369275) (xy 54.146483 -314.383563)
			(xy 54.154298 -314.40225) (xy 54.154832 -314.412376) (xy 54.154832 -314.821316) (xy 60.195968 -314.821316)
			(xy 60.195968 -314.412376) (xy 60.196401 -314.402224) (xy 60.204199 -314.383477) (xy 60.218591 -314.369156)
			(xy 60.237376 -314.361451) (xy 60.24753 -314.361068) (xy 61.64707 -314.361068) (xy 61.657198 -314.361552)
			(xy 61.675924 -314.369275) (xy 61.690283 -314.383563) (xy 61.698098 -314.40225) (xy 61.698632 -314.412376)
			(xy 61.698632 -314.821316) (xy 158.062168 -314.821316) (xy 158.062168 -314.412376) (xy 158.062601 -314.402224)
			(xy 158.070399 -314.383477) (xy 158.084791 -314.369156) (xy 158.103576 -314.361451) (xy 158.11373 -314.361068)
			(xy 159.51327 -314.361068) (xy 159.523398 -314.361552) (xy 159.542124 -314.369275) (xy 159.556483 -314.383563)
			(xy 159.564298 -314.40225) (xy 159.564832 -314.412376) (xy 159.564832 -314.821316) (xy 165.605968 -314.821316)
			(xy 165.605968 -314.412376) (xy 165.606401 -314.402224) (xy 165.614199 -314.383477) (xy 165.628591 -314.369156)
			(xy 165.647376 -314.361451) (xy 165.65753 -314.361068) (xy 167.05707 -314.361068) (xy 167.067198 -314.361552)
			(xy 167.085924 -314.369275) (xy 167.100283 -314.383563) (xy 167.108098 -314.40225) (xy 167.108632 -314.412376)
			(xy 167.108632 -314.821316) (xy 173.149768 -314.821316) (xy 173.149768 -314.412376) (xy 173.150201 -314.402224)
			(xy 173.157999 -314.383477) (xy 173.172391 -314.369156) (xy 173.191176 -314.361451) (xy 173.20133 -314.361068)
			(xy 174.60087 -314.361068) (xy 174.610998 -314.361552) (xy 174.629724 -314.369275) (xy 174.644083 -314.383563)
			(xy 174.651898 -314.40225) (xy 174.652432 -314.412376) (xy 174.652432 -314.821316) (xy 180.693568 -314.821316)
			(xy 180.693568 -314.412376) (xy 180.694001 -314.402224) (xy 180.701799 -314.383477) (xy 180.716191 -314.369156)
			(xy 180.734976 -314.361451) (xy 180.74513 -314.361068) (xy 182.14467 -314.361068) (xy 182.154798 -314.361552)
			(xy 182.173524 -314.369275) (xy 182.187883 -314.383563) (xy 182.195698 -314.40225) (xy 182.196232 -314.412376)
			(xy 182.196232 -314.821316) (xy 188.237368 -314.821316) (xy 188.237368 -314.412376) (xy 188.237801 -314.402224)
			(xy 188.245599 -314.383477) (xy 188.259991 -314.369156) (xy 188.278776 -314.361451) (xy 188.28893 -314.361068)
			(xy 189.68847 -314.361068) (xy 189.698598 -314.361552) (xy 189.717324 -314.369275) (xy 189.731683 -314.383563)
			(xy 189.739498 -314.40225) (xy 189.740032 -314.412376) (xy 189.740032 -314.821316) (xy 195.781168 -314.821316)
			(xy 195.781168 -314.412376) (xy 195.781601 -314.402224) (xy 195.789399 -314.383477) (xy 195.803791 -314.369156)
			(xy 195.822576 -314.361451) (xy 195.83273 -314.361068) (xy 197.23227 -314.361068) (xy 197.242398 -314.361552)
			(xy 197.261124 -314.369275) (xy 197.275483 -314.383563) (xy 197.283298 -314.40225) (xy 197.283832 -314.412376)
			(xy 197.283832 -314.821316) (xy 203.324968 -314.821316) (xy 203.324968 -314.412376) (xy 203.325401 -314.402224)
			(xy 203.333199 -314.383477) (xy 203.347591 -314.369156) (xy 203.366376 -314.361451) (xy 203.37653 -314.361068)
			(xy 204.77607 -314.361068) (xy 204.786198 -314.361552) (xy 204.804924 -314.369275) (xy 204.819283 -314.383563)
			(xy 204.827098 -314.40225) (xy 204.827632 -314.412376) (xy 204.827632 -314.821316) (xy 210.868768 -314.821316)
			(xy 210.868768 -314.412376) (xy 210.869201 -314.402224) (xy 210.876999 -314.383477) (xy 210.891391 -314.369156)
			(xy 210.910176 -314.361451) (xy 210.92033 -314.361068) (xy 212.31987 -314.361068) (xy 212.329998 -314.361552)
			(xy 212.348724 -314.369275) (xy 212.363083 -314.383563) (xy 212.370898 -314.40225) (xy 212.371432 -314.412376)
			(xy 212.371432 -314.821316) (xy 255.329436 -314.821316) (xy 255.329436 -314.412376) (xy 255.329803 -314.402216)
			(xy 255.337613 -314.383456) (xy 255.352027 -314.369132) (xy 255.370835 -314.36144) (xy 255.380998 -314.361068)
			(xy 256.780538 -314.361068) (xy 256.790671 -314.361496) (xy 256.809398 -314.369242) (xy 256.823754 -314.383546)
			(xy 256.831567 -314.402245) (xy 256.8321 -314.412376) (xy 256.8321 -314.821316) (xy 262.873236 -314.821316)
			(xy 262.873236 -314.412376) (xy 262.873603 -314.402216) (xy 262.881413 -314.383456) (xy 262.895827 -314.369132)
			(xy 262.914635 -314.36144) (xy 262.924798 -314.361068) (xy 264.324338 -314.361068) (xy 264.334471 -314.361496)
			(xy 264.353198 -314.369242) (xy 264.367554 -314.383546) (xy 264.375367 -314.402245) (xy 264.3759 -314.412376)
			(xy 264.3759 -314.821316) (xy 270.417036 -314.821316) (xy 270.417036 -314.412376) (xy 270.417403 -314.402216)
			(xy 270.425213 -314.383456) (xy 270.439627 -314.369132) (xy 270.458435 -314.36144) (xy 270.468598 -314.361068)
			(xy 271.868138 -314.361068) (xy 271.878271 -314.361496) (xy 271.896998 -314.369242) (xy 271.911354 -314.383546)
			(xy 271.919167 -314.402245) (xy 271.9197 -314.412376) (xy 271.9197 -314.821316) (xy 277.960836 -314.821316)
			(xy 277.960836 -314.412376) (xy 277.961203 -314.402216) (xy 277.969013 -314.383456) (xy 277.983427 -314.369132)
			(xy 278.002235 -314.36144) (xy 278.012398 -314.361068) (xy 279.411938 -314.361068) (xy 279.422071 -314.361496)
			(xy 279.440798 -314.369242) (xy 279.455154 -314.383546) (xy 279.462967 -314.402245) (xy 279.4635 -314.412376)
			(xy 279.4635 -314.821316) (xy 285.504636 -314.821316) (xy 285.504636 -314.412376) (xy 285.505003 -314.402216)
			(xy 285.512813 -314.383456) (xy 285.527227 -314.369132) (xy 285.546035 -314.36144) (xy 285.556198 -314.361068)
			(xy 286.955738 -314.361068) (xy 286.965871 -314.361496) (xy 286.984598 -314.369242) (xy 286.998954 -314.383546)
			(xy 287.006767 -314.402245) (xy 287.0073 -314.412376) (xy 287.0073 -314.821316) (xy 293.048436 -314.821316)
			(xy 293.048436 -314.412376) (xy 293.048803 -314.402216) (xy 293.056613 -314.383456) (xy 293.071027 -314.369132)
			(xy 293.089835 -314.36144) (xy 293.099998 -314.361068) (xy 294.499538 -314.361068) (xy 294.509671 -314.361496)
			(xy 294.528398 -314.369242) (xy 294.542754 -314.383546) (xy 294.550567 -314.402245) (xy 294.5511 -314.412376)
			(xy 294.5511 -314.821316) (xy 300.592236 -314.821316) (xy 300.592236 -314.412376) (xy 300.592603 -314.402216)
			(xy 300.600413 -314.383456) (xy 300.614827 -314.369132) (xy 300.633635 -314.36144) (xy 300.643798 -314.361068)
			(xy 302.043338 -314.361068) (xy 302.053471 -314.361496) (xy 302.072198 -314.369242) (xy 302.086554 -314.383546)
			(xy 302.094367 -314.402245) (xy 302.0949 -314.412376) (xy 302.0949 -314.821316) (xy 308.136036 -314.821316)
			(xy 308.136036 -314.412376) (xy 308.136403 -314.402216) (xy 308.144213 -314.383456) (xy 308.158627 -314.369132)
			(xy 308.177435 -314.36144) (xy 308.187598 -314.361068) (xy 309.587138 -314.361068) (xy 309.597271 -314.361496)
			(xy 309.615998 -314.369242) (xy 309.630354 -314.383546) (xy 309.638167 -314.402245) (xy 309.6387 -314.412376)
			(xy 309.6387 -314.821316) (xy 406.002236 -314.821316) (xy 406.002236 -314.412376) (xy 406.002603 -314.402216)
			(xy 406.010413 -314.383456) (xy 406.024827 -314.369132) (xy 406.043635 -314.36144) (xy 406.053798 -314.361068)
			(xy 407.453338 -314.361068) (xy 407.463471 -314.361496) (xy 407.482198 -314.369242) (xy 407.496554 -314.383546)
			(xy 407.504367 -314.402245) (xy 407.5049 -314.412376) (xy 407.5049 -314.821316) (xy 413.546036 -314.821316)
			(xy 413.546036 -314.412376) (xy 413.546403 -314.402216) (xy 413.554213 -314.383456) (xy 413.568627 -314.369132)
			(xy 413.587435 -314.36144) (xy 413.597598 -314.361068) (xy 414.997138 -314.361068) (xy 415.007271 -314.361496)
			(xy 415.025998 -314.369242) (xy 415.040354 -314.383546) (xy 415.048167 -314.402245) (xy 415.0487 -314.412376)
			(xy 415.0487 -314.821316) (xy 421.089836 -314.821316) (xy 421.089836 -314.412376) (xy 421.090203 -314.402216)
			(xy 421.098013 -314.383456) (xy 421.112427 -314.369132) (xy 421.131235 -314.36144) (xy 421.141398 -314.361068)
			(xy 422.540938 -314.361068) (xy 422.551071 -314.361496) (xy 422.569798 -314.369242) (xy 422.584154 -314.383546)
			(xy 422.591967 -314.402245) (xy 422.5925 -314.412376) (xy 422.5925 -314.821316) (xy 428.633636 -314.821316)
			(xy 428.633636 -314.412376) (xy 428.634003 -314.402216) (xy 428.641813 -314.383456) (xy 428.656227 -314.369132)
			(xy 428.675035 -314.36144) (xy 428.685198 -314.361068) (xy 430.084738 -314.361068) (xy 430.094871 -314.361496)
			(xy 430.113598 -314.369242) (xy 430.127954 -314.383546) (xy 430.135767 -314.402245) (xy 430.1363 -314.412376)
			(xy 430.1363 -314.821316) (xy 436.177436 -314.821316) (xy 436.177436 -314.412376) (xy 436.177803 -314.402216)
			(xy 436.185613 -314.383456) (xy 436.200027 -314.369132) (xy 436.218835 -314.36144) (xy 436.228998 -314.361068)
			(xy 437.628538 -314.361068) (xy 437.638671 -314.361496) (xy 437.657398 -314.369242) (xy 437.671754 -314.383546)
			(xy 437.679567 -314.402245) (xy 437.6801 -314.412376) (xy 437.6801 -314.821316) (xy 443.721236 -314.821316)
			(xy 443.721236 -314.412376) (xy 443.721603 -314.402216) (xy 443.729413 -314.383456) (xy 443.743827 -314.369132)
			(xy 443.762635 -314.36144) (xy 443.772798 -314.361068) (xy 445.172338 -314.361068) (xy 445.182471 -314.361496)
			(xy 445.201198 -314.369242) (xy 445.215554 -314.383546) (xy 445.223367 -314.402245) (xy 445.2239 -314.412376)
			(xy 445.2239 -314.821316) (xy 451.265036 -314.821316) (xy 451.265036 -314.412376) (xy 451.265403 -314.402216)
			(xy 451.273213 -314.383456) (xy 451.287627 -314.369132) (xy 451.306435 -314.36144) (xy 451.316598 -314.361068)
			(xy 452.716138 -314.361068) (xy 452.726271 -314.361496) (xy 452.744998 -314.369242) (xy 452.759354 -314.383546)
			(xy 452.767167 -314.402245) (xy 452.7677 -314.412376) (xy 452.7677 -314.821316) (xy 458.808836 -314.821316)
			(xy 458.808836 -314.412376) (xy 458.809203 -314.402216) (xy 458.817013 -314.383456) (xy 458.831427 -314.369132)
			(xy 458.850235 -314.36144) (xy 458.860398 -314.361068) (xy 460.259938 -314.361068) (xy 460.270071 -314.361496)
			(xy 460.288798 -314.369242) (xy 460.303154 -314.383546) (xy 460.310967 -314.402245) (xy 460.3115 -314.412376)
			(xy 460.3115 -314.821316) (xy 460.311092 -314.831471) (xy 460.303291 -314.850224) (xy 460.28889 -314.864547)
			(xy 460.270095 -314.872246) (xy 460.259938 -314.872624) (xy 458.860398 -314.872624) (xy 458.850267 -314.872174)
			(xy 458.831539 -314.864439) (xy 458.817181 -314.850141) (xy 458.809369 -314.831445) (xy 458.808836 -314.821316)
			(xy 452.7677 -314.821316) (xy 452.767292 -314.831471) (xy 452.759491 -314.850224) (xy 452.74509 -314.864547)
			(xy 452.726295 -314.872246) (xy 452.716138 -314.872624) (xy 451.316598 -314.872624) (xy 451.306467 -314.872174)
			(xy 451.287739 -314.864439) (xy 451.273381 -314.850141) (xy 451.265569 -314.831445) (xy 451.265036 -314.821316)
			(xy 445.2239 -314.821316) (xy 445.223492 -314.831471) (xy 445.215691 -314.850224) (xy 445.20129 -314.864547)
			(xy 445.182495 -314.872246) (xy 445.172338 -314.872624) (xy 443.772798 -314.872624) (xy 443.762667 -314.872174)
			(xy 443.743939 -314.864439) (xy 443.729581 -314.850141) (xy 443.721769 -314.831445) (xy 443.721236 -314.821316)
			(xy 437.6801 -314.821316) (xy 437.679692 -314.831471) (xy 437.671891 -314.850224) (xy 437.65749 -314.864547)
			(xy 437.638695 -314.872246) (xy 437.628538 -314.872624) (xy 436.228998 -314.872624) (xy 436.218867 -314.872174)
			(xy 436.200139 -314.864439) (xy 436.185781 -314.850141) (xy 436.177969 -314.831445) (xy 436.177436 -314.821316)
			(xy 430.1363 -314.821316) (xy 430.135892 -314.831471) (xy 430.128091 -314.850224) (xy 430.11369 -314.864547)
			(xy 430.094895 -314.872246) (xy 430.084738 -314.872624) (xy 428.685198 -314.872624) (xy 428.675067 -314.872174)
			(xy 428.656339 -314.864439) (xy 428.641981 -314.850141) (xy 428.634169 -314.831445) (xy 428.633636 -314.821316)
			(xy 422.5925 -314.821316) (xy 422.592092 -314.831471) (xy 422.584291 -314.850224) (xy 422.56989 -314.864547)
			(xy 422.551095 -314.872246) (xy 422.540938 -314.872624) (xy 421.141398 -314.872624) (xy 421.131267 -314.872174)
			(xy 421.112539 -314.864439) (xy 421.098181 -314.850141) (xy 421.090369 -314.831445) (xy 421.089836 -314.821316)
			(xy 415.0487 -314.821316) (xy 415.048292 -314.831471) (xy 415.040491 -314.850224) (xy 415.02609 -314.864547)
			(xy 415.007295 -314.872246) (xy 414.997138 -314.872624) (xy 413.597598 -314.872624) (xy 413.587467 -314.872174)
			(xy 413.568739 -314.864439) (xy 413.554381 -314.850141) (xy 413.546569 -314.831445) (xy 413.546036 -314.821316)
			(xy 407.5049 -314.821316) (xy 407.504492 -314.831471) (xy 407.496691 -314.850224) (xy 407.48229 -314.864547)
			(xy 407.463495 -314.872246) (xy 407.453338 -314.872624) (xy 406.053798 -314.872624) (xy 406.043667 -314.872174)
			(xy 406.024939 -314.864439) (xy 406.010581 -314.850141) (xy 406.002769 -314.831445) (xy 406.002236 -314.821316)
			(xy 309.6387 -314.821316) (xy 309.638292 -314.831471) (xy 309.630491 -314.850224) (xy 309.61609 -314.864547)
			(xy 309.597295 -314.872246) (xy 309.587138 -314.872624) (xy 308.187598 -314.872624) (xy 308.177467 -314.872174)
			(xy 308.158739 -314.864439) (xy 308.144381 -314.850141) (xy 308.136569 -314.831445) (xy 308.136036 -314.821316)
			(xy 302.0949 -314.821316) (xy 302.094492 -314.831471) (xy 302.086691 -314.850224) (xy 302.07229 -314.864547)
			(xy 302.053495 -314.872246) (xy 302.043338 -314.872624) (xy 300.643798 -314.872624) (xy 300.633667 -314.872174)
			(xy 300.614939 -314.864439) (xy 300.600581 -314.850141) (xy 300.592769 -314.831445) (xy 300.592236 -314.821316)
			(xy 294.5511 -314.821316) (xy 294.550692 -314.831471) (xy 294.542891 -314.850224) (xy 294.52849 -314.864547)
			(xy 294.509695 -314.872246) (xy 294.499538 -314.872624) (xy 293.099998 -314.872624) (xy 293.089867 -314.872174)
			(xy 293.071139 -314.864439) (xy 293.056781 -314.850141) (xy 293.048969 -314.831445) (xy 293.048436 -314.821316)
			(xy 287.0073 -314.821316) (xy 287.006892 -314.831471) (xy 286.999091 -314.850224) (xy 286.98469 -314.864547)
			(xy 286.965895 -314.872246) (xy 286.955738 -314.872624) (xy 285.556198 -314.872624) (xy 285.546067 -314.872174)
			(xy 285.527339 -314.864439) (xy 285.512981 -314.850141) (xy 285.505169 -314.831445) (xy 285.504636 -314.821316)
			(xy 279.4635 -314.821316) (xy 279.463092 -314.831471) (xy 279.455291 -314.850224) (xy 279.44089 -314.864547)
			(xy 279.422095 -314.872246) (xy 279.411938 -314.872624) (xy 278.012398 -314.872624) (xy 278.002267 -314.872174)
			(xy 277.983539 -314.864439) (xy 277.969181 -314.850141) (xy 277.961369 -314.831445) (xy 277.960836 -314.821316)
			(xy 271.9197 -314.821316) (xy 271.919292 -314.831471) (xy 271.911491 -314.850224) (xy 271.89709 -314.864547)
			(xy 271.878295 -314.872246) (xy 271.868138 -314.872624) (xy 270.468598 -314.872624) (xy 270.458467 -314.872174)
			(xy 270.439739 -314.864439) (xy 270.425381 -314.850141) (xy 270.417569 -314.831445) (xy 270.417036 -314.821316)
			(xy 264.3759 -314.821316) (xy 264.375492 -314.831471) (xy 264.367691 -314.850224) (xy 264.35329 -314.864547)
			(xy 264.334495 -314.872246) (xy 264.324338 -314.872624) (xy 262.924798 -314.872624) (xy 262.914667 -314.872174)
			(xy 262.895939 -314.864439) (xy 262.881581 -314.850141) (xy 262.873769 -314.831445) (xy 262.873236 -314.821316)
			(xy 256.8321 -314.821316) (xy 256.831692 -314.831471) (xy 256.823891 -314.850224) (xy 256.80949 -314.864547)
			(xy 256.790695 -314.872246) (xy 256.780538 -314.872624) (xy 255.380998 -314.872624) (xy 255.370867 -314.872174)
			(xy 255.352139 -314.864439) (xy 255.337781 -314.850141) (xy 255.329969 -314.831445) (xy 255.329436 -314.821316)
			(xy 212.371432 -314.821316) (xy 212.370992 -314.831467) (xy 212.363197 -314.850214) (xy 212.348807 -314.864536)
			(xy 212.330023 -314.872241) (xy 212.31987 -314.872624) (xy 210.92033 -314.872624) (xy 210.910201 -314.872148)
			(xy 210.891473 -314.864423) (xy 210.877115 -314.850133) (xy 210.869301 -314.831443) (xy 210.868768 -314.821316)
			(xy 204.827632 -314.821316) (xy 204.827192 -314.831467) (xy 204.819397 -314.850214) (xy 204.805007 -314.864536)
			(xy 204.786223 -314.872241) (xy 204.77607 -314.872624) (xy 203.37653 -314.872624) (xy 203.366401 -314.872148)
			(xy 203.347673 -314.864423) (xy 203.333315 -314.850133) (xy 203.325501 -314.831443) (xy 203.324968 -314.821316)
			(xy 197.283832 -314.821316) (xy 197.283392 -314.831467) (xy 197.275597 -314.850214) (xy 197.261207 -314.864536)
			(xy 197.242423 -314.872241) (xy 197.23227 -314.872624) (xy 195.83273 -314.872624) (xy 195.822601 -314.872148)
			(xy 195.803873 -314.864423) (xy 195.789515 -314.850133) (xy 195.781701 -314.831443) (xy 195.781168 -314.821316)
			(xy 189.740032 -314.821316) (xy 189.739592 -314.831467) (xy 189.731797 -314.850214) (xy 189.717407 -314.864536)
			(xy 189.698623 -314.872241) (xy 189.68847 -314.872624) (xy 188.28893 -314.872624) (xy 188.278801 -314.872148)
			(xy 188.260073 -314.864423) (xy 188.245715 -314.850133) (xy 188.237901 -314.831443) (xy 188.237368 -314.821316)
			(xy 182.196232 -314.821316) (xy 182.195792 -314.831467) (xy 182.187997 -314.850214) (xy 182.173607 -314.864536)
			(xy 182.154823 -314.872241) (xy 182.14467 -314.872624) (xy 180.74513 -314.872624) (xy 180.735001 -314.872148)
			(xy 180.716273 -314.864423) (xy 180.701915 -314.850133) (xy 180.694101 -314.831443) (xy 180.693568 -314.821316)
			(xy 174.652432 -314.821316) (xy 174.651992 -314.831467) (xy 174.644197 -314.850214) (xy 174.629807 -314.864536)
			(xy 174.611023 -314.872241) (xy 174.60087 -314.872624) (xy 173.20133 -314.872624) (xy 173.191201 -314.872148)
			(xy 173.172473 -314.864423) (xy 173.158115 -314.850133) (xy 173.150301 -314.831443) (xy 173.149768 -314.821316)
			(xy 167.108632 -314.821316) (xy 167.108192 -314.831467) (xy 167.100397 -314.850214) (xy 167.086007 -314.864536)
			(xy 167.067223 -314.872241) (xy 167.05707 -314.872624) (xy 165.65753 -314.872624) (xy 165.647401 -314.872148)
			(xy 165.628673 -314.864423) (xy 165.614315 -314.850133) (xy 165.606501 -314.831443) (xy 165.605968 -314.821316)
			(xy 159.564832 -314.821316) (xy 159.564392 -314.831467) (xy 159.556597 -314.850214) (xy 159.542207 -314.864536)
			(xy 159.523423 -314.872241) (xy 159.51327 -314.872624) (xy 158.11373 -314.872624) (xy 158.103601 -314.872148)
			(xy 158.084873 -314.864423) (xy 158.070515 -314.850133) (xy 158.062701 -314.831443) (xy 158.062168 -314.821316)
			(xy 61.698632 -314.821316) (xy 61.698192 -314.831467) (xy 61.690397 -314.850214) (xy 61.676007 -314.864536)
			(xy 61.657223 -314.872241) (xy 61.64707 -314.872624) (xy 60.24753 -314.872624) (xy 60.237401 -314.872148)
			(xy 60.218673 -314.864423) (xy 60.204315 -314.850133) (xy 60.196501 -314.831443) (xy 60.195968 -314.821316)
			(xy 54.154832 -314.821316) (xy 54.154392 -314.831467) (xy 54.146597 -314.850214) (xy 54.132207 -314.864536)
			(xy 54.113423 -314.872241) (xy 54.10327 -314.872624) (xy 52.70373 -314.872624) (xy 52.693601 -314.872148)
			(xy 52.674873 -314.864423) (xy 52.660515 -314.850133) (xy 52.652701 -314.831443) (xy 52.652168 -314.821316)
			(xy 46.611032 -314.821316) (xy 46.610592 -314.831467) (xy 46.602797 -314.850214) (xy 46.588407 -314.864536)
			(xy 46.569623 -314.872241) (xy 46.55947 -314.872624) (xy 45.15993 -314.872624) (xy 45.149801 -314.872148)
			(xy 45.131073 -314.864423) (xy 45.116715 -314.850133) (xy 45.108901 -314.831443) (xy 45.108368 -314.821316)
			(xy 39.067232 -314.821316) (xy 39.066792 -314.831467) (xy 39.058997 -314.850214) (xy 39.044607 -314.864536)
			(xy 39.025823 -314.872241) (xy 39.01567 -314.872624) (xy 37.61613 -314.872624) (xy 37.606001 -314.872148)
			(xy 37.587273 -314.864423) (xy 37.572915 -314.850133) (xy 37.565101 -314.831443) (xy 37.564568 -314.821316)
			(xy 31.523432 -314.821316) (xy 31.522992 -314.831467) (xy 31.515197 -314.850214) (xy 31.500807 -314.864536)
			(xy 31.482023 -314.872241) (xy 31.47187 -314.872624) (xy 30.07233 -314.872624) (xy 30.062201 -314.872148)
			(xy 30.043473 -314.864423) (xy 30.029115 -314.850133) (xy 30.021301 -314.831443) (xy 30.020768 -314.821316)
			(xy 23.979632 -314.821316) (xy 23.979192 -314.831467) (xy 23.971397 -314.850214) (xy 23.957007 -314.864536)
			(xy 23.938223 -314.872241) (xy 23.92807 -314.872624) (xy 22.52853 -314.872624) (xy 22.518401 -314.872148)
			(xy 22.499673 -314.864423) (xy 22.485315 -314.850133) (xy 22.477501 -314.831443) (xy 22.476968 -314.821316)
			(xy 16.435832 -314.821316) (xy 16.435392 -314.831467) (xy 16.427597 -314.850214) (xy 16.413207 -314.864536)
			(xy 16.394423 -314.872241) (xy 16.38427 -314.872624) (xy 14.98473 -314.872624) (xy 14.974601 -314.872148)
			(xy 14.955873 -314.864423) (xy 14.941515 -314.850133) (xy 14.933701 -314.831443) (xy 14.933168 -314.821316)
			(xy 8.892032 -314.821316) (xy 8.891592 -314.831467) (xy 8.883797 -314.850214) (xy 8.869407 -314.864536)
			(xy 8.850623 -314.872241) (xy 8.84047 -314.872624) (xy 7.44093 -314.872624) (xy 7.430801 -314.872148)
			(xy 7.412073 -314.864423) (xy 7.397715 -314.850133) (xy 7.389901 -314.831443) (xy 7.389368 -314.821316)
			(xy 2.509012 -314.821316) (xy 2.509012 -315.671454) (xy 11.489436 -315.671454) (xy 11.489436 -315.262514)
			(xy 11.489875 -315.252344) (xy 11.497655 -315.233549) (xy 11.512036 -315.219164) (xy 11.530828 -315.211378)
			(xy 11.540998 -315.210952) (xy 12.940538 -315.210952) (xy 12.9507 -315.211403) (xy 12.969473 -315.219192)
			(xy 12.983837 -315.233571) (xy 12.991608 -315.252352) (xy 12.9921 -315.262514) (xy 12.9921 -315.671454)
			(xy 19.033236 -315.671454) (xy 19.033236 -315.262514) (xy 19.033675 -315.252344) (xy 19.041455 -315.233549)
			(xy 19.055836 -315.219164) (xy 19.074628 -315.211378) (xy 19.084798 -315.210952) (xy 20.484338 -315.210952)
			(xy 20.4945 -315.211403) (xy 20.513273 -315.219192) (xy 20.527637 -315.233571) (xy 20.535408 -315.252352)
			(xy 20.5359 -315.262514) (xy 20.5359 -315.671454) (xy 26.577036 -315.671454) (xy 26.577036 -315.262514)
			(xy 26.577475 -315.252344) (xy 26.585255 -315.233549) (xy 26.599636 -315.219164) (xy 26.618428 -315.211378)
			(xy 26.628598 -315.210952) (xy 28.028138 -315.210952) (xy 28.0383 -315.211403) (xy 28.057073 -315.219192)
			(xy 28.071437 -315.233571) (xy 28.079208 -315.252352) (xy 28.0797 -315.262514) (xy 28.0797 -315.671454)
			(xy 34.120836 -315.671454) (xy 34.120836 -315.262514) (xy 34.121275 -315.252344) (xy 34.129055 -315.233549)
			(xy 34.143436 -315.219164) (xy 34.162228 -315.211378) (xy 34.172398 -315.210952) (xy 35.571938 -315.210952)
			(xy 35.5821 -315.211403) (xy 35.600873 -315.219192) (xy 35.615237 -315.233571) (xy 35.623008 -315.252352)
			(xy 35.6235 -315.262514) (xy 35.6235 -315.671454) (xy 41.664636 -315.671454) (xy 41.664636 -315.262514)
			(xy 41.665075 -315.252344) (xy 41.672855 -315.233549) (xy 41.687236 -315.219164) (xy 41.706028 -315.211378)
			(xy 41.716198 -315.210952) (xy 43.115738 -315.210952) (xy 43.1259 -315.211403) (xy 43.144673 -315.219192)
			(xy 43.159037 -315.233571) (xy 43.166808 -315.252352) (xy 43.1673 -315.262514) (xy 43.1673 -315.671454)
			(xy 49.208436 -315.671454) (xy 49.208436 -315.262514) (xy 49.208875 -315.252344) (xy 49.216655 -315.233549)
			(xy 49.231036 -315.219164) (xy 49.249828 -315.211378) (xy 49.259998 -315.210952) (xy 50.659538 -315.210952)
			(xy 50.6697 -315.211403) (xy 50.688473 -315.219192) (xy 50.702837 -315.233571) (xy 50.710608 -315.252352)
			(xy 50.7111 -315.262514) (xy 50.7111 -315.671454) (xy 56.752236 -315.671454) (xy 56.752236 -315.262514)
			(xy 56.752675 -315.252344) (xy 56.760455 -315.233549) (xy 56.774836 -315.219164) (xy 56.793628 -315.211378)
			(xy 56.803798 -315.210952) (xy 58.203338 -315.210952) (xy 58.2135 -315.211403) (xy 58.232273 -315.219192)
			(xy 58.246637 -315.233571) (xy 58.254408 -315.252352) (xy 58.2549 -315.262514) (xy 58.2549 -315.671454)
			(xy 64.296036 -315.671454) (xy 64.296036 -315.262514) (xy 64.296475 -315.252344) (xy 64.304255 -315.233549)
			(xy 64.318636 -315.219164) (xy 64.337428 -315.211378) (xy 64.347598 -315.210952) (xy 65.747138 -315.210952)
			(xy 65.7573 -315.211403) (xy 65.776073 -315.219192) (xy 65.790437 -315.233571) (xy 65.798208 -315.252352)
			(xy 65.7987 -315.262514) (xy 65.7987 -315.671454) (xy 162.162236 -315.671454) (xy 162.162236 -315.262514)
			(xy 162.162675 -315.252344) (xy 162.170455 -315.233549) (xy 162.184836 -315.219164) (xy 162.203628 -315.211378)
			(xy 162.213798 -315.210952) (xy 163.613338 -315.210952) (xy 163.6235 -315.211403) (xy 163.642273 -315.219192)
			(xy 163.656637 -315.233571) (xy 163.664408 -315.252352) (xy 163.6649 -315.262514) (xy 163.6649 -315.671454)
			(xy 169.706036 -315.671454) (xy 169.706036 -315.262514) (xy 169.706475 -315.252344) (xy 169.714255 -315.233549)
			(xy 169.728636 -315.219164) (xy 169.747428 -315.211378) (xy 169.757598 -315.210952) (xy 171.157138 -315.210952)
			(xy 171.1673 -315.211403) (xy 171.186073 -315.219192) (xy 171.200437 -315.233571) (xy 171.208208 -315.252352)
			(xy 171.2087 -315.262514) (xy 171.2087 -315.671454) (xy 177.249836 -315.671454) (xy 177.249836 -315.262514)
			(xy 177.250275 -315.252344) (xy 177.258055 -315.233549) (xy 177.272436 -315.219164) (xy 177.291228 -315.211378)
			(xy 177.301398 -315.210952) (xy 178.700938 -315.210952) (xy 178.7111 -315.211403) (xy 178.729873 -315.219192)
			(xy 178.744237 -315.233571) (xy 178.752008 -315.252352) (xy 178.7525 -315.262514) (xy 178.7525 -315.671454)
			(xy 184.793636 -315.671454) (xy 184.793636 -315.262514) (xy 184.794075 -315.252344) (xy 184.801855 -315.233549)
			(xy 184.816236 -315.219164) (xy 184.835028 -315.211378) (xy 184.845198 -315.210952) (xy 186.244738 -315.210952)
			(xy 186.2549 -315.211403) (xy 186.273673 -315.219192) (xy 186.288037 -315.233571) (xy 186.295808 -315.252352)
			(xy 186.2963 -315.262514) (xy 186.2963 -315.671454) (xy 192.337436 -315.671454) (xy 192.337436 -315.262514)
			(xy 192.337875 -315.252344) (xy 192.345655 -315.233549) (xy 192.360036 -315.219164) (xy 192.378828 -315.211378)
			(xy 192.388998 -315.210952) (xy 193.788538 -315.210952) (xy 193.7987 -315.211403) (xy 193.817473 -315.219192)
			(xy 193.831837 -315.233571) (xy 193.839608 -315.252352) (xy 193.8401 -315.262514) (xy 193.8401 -315.671454)
			(xy 199.881236 -315.671454) (xy 199.881236 -315.262514) (xy 199.881675 -315.252344) (xy 199.889455 -315.233549)
			(xy 199.903836 -315.219164) (xy 199.922628 -315.211378) (xy 199.932798 -315.210952) (xy 201.332338 -315.210952)
			(xy 201.3425 -315.211403) (xy 201.361273 -315.219192) (xy 201.375637 -315.233571) (xy 201.383408 -315.252352)
			(xy 201.3839 -315.262514) (xy 201.3839 -315.671454) (xy 207.425036 -315.671454) (xy 207.425036 -315.262514)
			(xy 207.425475 -315.252344) (xy 207.433255 -315.233549) (xy 207.447636 -315.219164) (xy 207.466428 -315.211378)
			(xy 207.476598 -315.210952) (xy 208.876138 -315.210952) (xy 208.8863 -315.211403) (xy 208.905073 -315.219192)
			(xy 208.919437 -315.233571) (xy 208.927208 -315.252352) (xy 208.9277 -315.262514) (xy 208.9277 -315.671454)
			(xy 214.968836 -315.671454) (xy 214.968836 -315.262514) (xy 214.969275 -315.252344) (xy 214.977055 -315.233549)
			(xy 214.991436 -315.219164) (xy 215.010228 -315.211378) (xy 215.020398 -315.210952) (xy 216.419938 -315.210952)
			(xy 216.4301 -315.211403) (xy 216.448873 -315.219192) (xy 216.463237 -315.233571) (xy 216.471008 -315.252352)
			(xy 216.4715 -315.262514) (xy 216.4715 -315.671454) (xy 259.429504 -315.671454) (xy 259.429504 -315.262514)
			(xy 259.430044 -315.252361) (xy 259.437807 -315.233599) (xy 259.452159 -315.219234) (xy 259.470914 -315.211453)
			(xy 259.481066 -315.210952) (xy 260.880606 -315.210952) (xy 260.89078 -315.211359) (xy 260.909577 -315.219149)
			(xy 260.923962 -315.23354) (xy 260.931745 -315.25234) (xy 260.932168 -315.262514) (xy 260.932168 -315.671454)
			(xy 266.973304 -315.671454) (xy 266.973304 -315.262514) (xy 266.973844 -315.252361) (xy 266.981607 -315.233599)
			(xy 266.995959 -315.219234) (xy 267.014714 -315.211453) (xy 267.024866 -315.210952) (xy 268.424406 -315.210952)
			(xy 268.43458 -315.211359) (xy 268.453377 -315.219149) (xy 268.467762 -315.23354) (xy 268.475545 -315.25234)
			(xy 268.475968 -315.262514) (xy 268.475968 -315.671454) (xy 274.517104 -315.671454) (xy 274.517104 -315.262514)
			(xy 274.517644 -315.252361) (xy 274.525407 -315.233599) (xy 274.539759 -315.219234) (xy 274.558514 -315.211453)
			(xy 274.568666 -315.210952) (xy 275.968206 -315.210952) (xy 275.97838 -315.211359) (xy 275.997177 -315.219149)
			(xy 276.011562 -315.23354) (xy 276.019345 -315.25234) (xy 276.019768 -315.262514) (xy 276.019768 -315.671454)
			(xy 282.060904 -315.671454) (xy 282.060904 -315.262514) (xy 282.061444 -315.252361) (xy 282.069207 -315.233599)
			(xy 282.083559 -315.219234) (xy 282.102314 -315.211453) (xy 282.112466 -315.210952) (xy 283.512006 -315.210952)
			(xy 283.52218 -315.211359) (xy 283.540977 -315.219149) (xy 283.555362 -315.23354) (xy 283.563145 -315.25234)
			(xy 283.563568 -315.262514) (xy 283.563568 -315.671454) (xy 289.604704 -315.671454) (xy 289.604704 -315.262514)
			(xy 289.605244 -315.252361) (xy 289.613007 -315.233599) (xy 289.627359 -315.219234) (xy 289.646114 -315.211453)
			(xy 289.656266 -315.210952) (xy 291.055806 -315.210952) (xy 291.06598 -315.211359) (xy 291.084777 -315.219149)
			(xy 291.099162 -315.23354) (xy 291.106945 -315.25234) (xy 291.107368 -315.262514) (xy 291.107368 -315.671454)
			(xy 297.148504 -315.671454) (xy 297.148504 -315.262514) (xy 297.149044 -315.252361) (xy 297.156807 -315.233599)
			(xy 297.171159 -315.219234) (xy 297.189914 -315.211453) (xy 297.200066 -315.210952) (xy 298.599606 -315.210952)
			(xy 298.60978 -315.211359) (xy 298.628577 -315.219149) (xy 298.642962 -315.23354) (xy 298.650745 -315.25234)
			(xy 298.651168 -315.262514) (xy 298.651168 -315.671454) (xy 304.692304 -315.671454) (xy 304.692304 -315.262514)
			(xy 304.692844 -315.252361) (xy 304.700607 -315.233599) (xy 304.714959 -315.219234) (xy 304.733714 -315.211453)
			(xy 304.743866 -315.210952) (xy 306.143406 -315.210952) (xy 306.15358 -315.211359) (xy 306.172377 -315.219149)
			(xy 306.186762 -315.23354) (xy 306.194545 -315.25234) (xy 306.194968 -315.262514) (xy 306.194968 -315.671454)
			(xy 312.236104 -315.671454) (xy 312.236104 -315.262514) (xy 312.236644 -315.252361) (xy 312.244407 -315.233599)
			(xy 312.258759 -315.219234) (xy 312.277514 -315.211453) (xy 312.287666 -315.210952) (xy 313.687206 -315.210952)
			(xy 313.69738 -315.211359) (xy 313.716177 -315.219149) (xy 313.730562 -315.23354) (xy 313.738345 -315.25234)
			(xy 313.738768 -315.262514) (xy 313.738768 -315.671454) (xy 410.102304 -315.671454) (xy 410.102304 -315.262514)
			(xy 410.102844 -315.252361) (xy 410.110607 -315.233599) (xy 410.124959 -315.219234) (xy 410.143714 -315.211453)
			(xy 410.153866 -315.210952) (xy 411.553406 -315.210952) (xy 411.56358 -315.211359) (xy 411.582377 -315.219149)
			(xy 411.596762 -315.23354) (xy 411.604545 -315.25234) (xy 411.604968 -315.262514) (xy 411.604968 -315.671454)
			(xy 417.646104 -315.671454) (xy 417.646104 -315.262514) (xy 417.646644 -315.252361) (xy 417.654407 -315.233599)
			(xy 417.668759 -315.219234) (xy 417.687514 -315.211453) (xy 417.697666 -315.210952) (xy 419.097206 -315.210952)
			(xy 419.10738 -315.211359) (xy 419.126177 -315.219149) (xy 419.140562 -315.23354) (xy 419.148345 -315.25234)
			(xy 419.148768 -315.262514) (xy 419.148768 -315.671454) (xy 425.189904 -315.671454) (xy 425.189904 -315.262514)
			(xy 425.190444 -315.252361) (xy 425.198207 -315.233599) (xy 425.212559 -315.219234) (xy 425.231314 -315.211453)
			(xy 425.241466 -315.210952) (xy 426.641006 -315.210952) (xy 426.65118 -315.211359) (xy 426.669977 -315.219149)
			(xy 426.684362 -315.23354) (xy 426.692145 -315.25234) (xy 426.692568 -315.262514) (xy 426.692568 -315.671454)
			(xy 432.733704 -315.671454) (xy 432.733704 -315.262514) (xy 432.734244 -315.252361) (xy 432.742007 -315.233599)
			(xy 432.756359 -315.219234) (xy 432.775114 -315.211453) (xy 432.785266 -315.210952) (xy 434.184806 -315.210952)
			(xy 434.19498 -315.211359) (xy 434.213777 -315.219149) (xy 434.228162 -315.23354) (xy 434.235945 -315.25234)
			(xy 434.236368 -315.262514) (xy 434.236368 -315.671454) (xy 440.277504 -315.671454) (xy 440.277504 -315.262514)
			(xy 440.278044 -315.252361) (xy 440.285807 -315.233599) (xy 440.300159 -315.219234) (xy 440.318914 -315.211453)
			(xy 440.329066 -315.210952) (xy 441.728606 -315.210952) (xy 441.73878 -315.211359) (xy 441.757577 -315.219149)
			(xy 441.771962 -315.23354) (xy 441.779745 -315.25234) (xy 441.780168 -315.262514) (xy 441.780168 -315.671454)
			(xy 447.821304 -315.671454) (xy 447.821304 -315.262514) (xy 447.821844 -315.252361) (xy 447.829607 -315.233599)
			(xy 447.843959 -315.219234) (xy 447.862714 -315.211453) (xy 447.872866 -315.210952) (xy 449.272406 -315.210952)
			(xy 449.28258 -315.211359) (xy 449.301377 -315.219149) (xy 449.315762 -315.23354) (xy 449.323545 -315.25234)
			(xy 449.323968 -315.262514) (xy 449.323968 -315.671454) (xy 455.365104 -315.671454) (xy 455.365104 -315.262514)
			(xy 455.365644 -315.252361) (xy 455.373407 -315.233599) (xy 455.387759 -315.219234) (xy 455.406514 -315.211453)
			(xy 455.416666 -315.210952) (xy 456.816206 -315.210952) (xy 456.82638 -315.211359) (xy 456.845177 -315.219149)
			(xy 456.859562 -315.23354) (xy 456.867345 -315.25234) (xy 456.867768 -315.262514) (xy 456.867768 -315.671454)
			(xy 462.908904 -315.671454) (xy 462.908904 -315.262514) (xy 462.909444 -315.252361) (xy 462.917207 -315.233599)
			(xy 462.931559 -315.219234) (xy 462.950314 -315.211453) (xy 462.960466 -315.210952) (xy 464.360006 -315.210952)
			(xy 464.37018 -315.211359) (xy 464.388977 -315.219149) (xy 464.403362 -315.23354) (xy 464.411145 -315.25234)
			(xy 464.411568 -315.262514) (xy 464.411568 -315.671454) (xy 464.411099 -315.681622) (xy 464.40333 -315.700414)
			(xy 464.388958 -315.714801) (xy 464.370173 -315.722588) (xy 464.360006 -315.723016) (xy 462.960466 -315.723016)
			(xy 462.950286 -315.722663) (xy 462.931482 -315.714858) (xy 462.917097 -315.700451) (xy 462.909321 -315.681634)
			(xy 462.908904 -315.671454) (xy 456.867768 -315.671454) (xy 456.867299 -315.681622) (xy 456.85953 -315.700414)
			(xy 456.845158 -315.714801) (xy 456.826373 -315.722588) (xy 456.816206 -315.723016) (xy 455.416666 -315.723016)
			(xy 455.406486 -315.722663) (xy 455.387682 -315.714858) (xy 455.373297 -315.700451) (xy 455.365521 -315.681634)
			(xy 455.365104 -315.671454) (xy 449.323968 -315.671454) (xy 449.323499 -315.681622) (xy 449.31573 -315.700414)
			(xy 449.301358 -315.714801) (xy 449.282573 -315.722588) (xy 449.272406 -315.723016) (xy 447.872866 -315.723016)
			(xy 447.862686 -315.722663) (xy 447.843882 -315.714858) (xy 447.829497 -315.700451) (xy 447.821721 -315.681634)
			(xy 447.821304 -315.671454) (xy 441.780168 -315.671454) (xy 441.779699 -315.681622) (xy 441.77193 -315.700414)
			(xy 441.757558 -315.714801) (xy 441.738773 -315.722588) (xy 441.728606 -315.723016) (xy 440.329066 -315.723016)
			(xy 440.318886 -315.722663) (xy 440.300082 -315.714858) (xy 440.285697 -315.700451) (xy 440.277921 -315.681634)
			(xy 440.277504 -315.671454) (xy 434.236368 -315.671454) (xy 434.235899 -315.681622) (xy 434.22813 -315.700414)
			(xy 434.213758 -315.714801) (xy 434.194973 -315.722588) (xy 434.184806 -315.723016) (xy 432.785266 -315.723016)
			(xy 432.775086 -315.722663) (xy 432.756282 -315.714858) (xy 432.741897 -315.700451) (xy 432.734121 -315.681634)
			(xy 432.733704 -315.671454) (xy 426.692568 -315.671454) (xy 426.692099 -315.681622) (xy 426.68433 -315.700414)
			(xy 426.669958 -315.714801) (xy 426.651173 -315.722588) (xy 426.641006 -315.723016) (xy 425.241466 -315.723016)
			(xy 425.231286 -315.722663) (xy 425.212482 -315.714858) (xy 425.198097 -315.700451) (xy 425.190321 -315.681634)
			(xy 425.189904 -315.671454) (xy 419.148768 -315.671454) (xy 419.148299 -315.681622) (xy 419.14053 -315.700414)
			(xy 419.126158 -315.714801) (xy 419.107373 -315.722588) (xy 419.097206 -315.723016) (xy 417.697666 -315.723016)
			(xy 417.687486 -315.722663) (xy 417.668682 -315.714858) (xy 417.654297 -315.700451) (xy 417.646521 -315.681634)
			(xy 417.646104 -315.671454) (xy 411.604968 -315.671454) (xy 411.604499 -315.681622) (xy 411.59673 -315.700414)
			(xy 411.582358 -315.714801) (xy 411.563573 -315.722588) (xy 411.553406 -315.723016) (xy 410.153866 -315.723016)
			(xy 410.143686 -315.722663) (xy 410.124882 -315.714858) (xy 410.110497 -315.700451) (xy 410.102721 -315.681634)
			(xy 410.102304 -315.671454) (xy 313.738768 -315.671454) (xy 313.738299 -315.681622) (xy 313.73053 -315.700414)
			(xy 313.716158 -315.714801) (xy 313.697373 -315.722588) (xy 313.687206 -315.723016) (xy 312.287666 -315.723016)
			(xy 312.277486 -315.722663) (xy 312.258682 -315.714858) (xy 312.244297 -315.700451) (xy 312.236521 -315.681634)
			(xy 312.236104 -315.671454) (xy 306.194968 -315.671454) (xy 306.194499 -315.681622) (xy 306.18673 -315.700414)
			(xy 306.172358 -315.714801) (xy 306.153573 -315.722588) (xy 306.143406 -315.723016) (xy 304.743866 -315.723016)
			(xy 304.733686 -315.722663) (xy 304.714882 -315.714858) (xy 304.700497 -315.700451) (xy 304.692721 -315.681634)
			(xy 304.692304 -315.671454) (xy 298.651168 -315.671454) (xy 298.650699 -315.681622) (xy 298.64293 -315.700414)
			(xy 298.628558 -315.714801) (xy 298.609773 -315.722588) (xy 298.599606 -315.723016) (xy 297.200066 -315.723016)
			(xy 297.189886 -315.722663) (xy 297.171082 -315.714858) (xy 297.156697 -315.700451) (xy 297.148921 -315.681634)
			(xy 297.148504 -315.671454) (xy 291.107368 -315.671454) (xy 291.106899 -315.681622) (xy 291.09913 -315.700414)
			(xy 291.084758 -315.714801) (xy 291.065973 -315.722588) (xy 291.055806 -315.723016) (xy 289.656266 -315.723016)
			(xy 289.646086 -315.722663) (xy 289.627282 -315.714858) (xy 289.612897 -315.700451) (xy 289.605121 -315.681634)
			(xy 289.604704 -315.671454) (xy 283.563568 -315.671454) (xy 283.563099 -315.681622) (xy 283.55533 -315.700414)
			(xy 283.540958 -315.714801) (xy 283.522173 -315.722588) (xy 283.512006 -315.723016) (xy 282.112466 -315.723016)
			(xy 282.102286 -315.722663) (xy 282.083482 -315.714858) (xy 282.069097 -315.700451) (xy 282.061321 -315.681634)
			(xy 282.060904 -315.671454) (xy 276.019768 -315.671454) (xy 276.019299 -315.681622) (xy 276.01153 -315.700414)
			(xy 275.997158 -315.714801) (xy 275.978373 -315.722588) (xy 275.968206 -315.723016) (xy 274.568666 -315.723016)
			(xy 274.558486 -315.722663) (xy 274.539682 -315.714858) (xy 274.525297 -315.700451) (xy 274.517521 -315.681634)
			(xy 274.517104 -315.671454) (xy 268.475968 -315.671454) (xy 268.475499 -315.681622) (xy 268.46773 -315.700414)
			(xy 268.453358 -315.714801) (xy 268.434573 -315.722588) (xy 268.424406 -315.723016) (xy 267.024866 -315.723016)
			(xy 267.014686 -315.722663) (xy 266.995882 -315.714858) (xy 266.981497 -315.700451) (xy 266.973721 -315.681634)
			(xy 266.973304 -315.671454) (xy 260.932168 -315.671454) (xy 260.931699 -315.681622) (xy 260.92393 -315.700414)
			(xy 260.909558 -315.714801) (xy 260.890773 -315.722588) (xy 260.880606 -315.723016) (xy 259.481066 -315.723016)
			(xy 259.470886 -315.722663) (xy 259.452082 -315.714858) (xy 259.437697 -315.700451) (xy 259.429921 -315.681634)
			(xy 259.429504 -315.671454) (xy 216.4715 -315.671454) (xy 216.470999 -315.681618) (xy 216.463237 -315.700404)
			(xy 216.448875 -315.714789) (xy 216.430101 -315.722583) (xy 216.419938 -315.723016) (xy 215.020398 -315.723016)
			(xy 215.010221 -315.722637) (xy 214.991417 -315.714842) (xy 214.977031 -315.700443) (xy 214.969254 -315.681632)
			(xy 214.968836 -315.671454) (xy 208.9277 -315.671454) (xy 208.927199 -315.681618) (xy 208.919437 -315.700404)
			(xy 208.905075 -315.714789) (xy 208.886301 -315.722583) (xy 208.876138 -315.723016) (xy 207.476598 -315.723016)
			(xy 207.466421 -315.722637) (xy 207.447617 -315.714842) (xy 207.433231 -315.700443) (xy 207.425454 -315.681632)
			(xy 207.425036 -315.671454) (xy 201.3839 -315.671454) (xy 201.383399 -315.681618) (xy 201.375637 -315.700404)
			(xy 201.361275 -315.714789) (xy 201.342501 -315.722583) (xy 201.332338 -315.723016) (xy 199.932798 -315.723016)
			(xy 199.922621 -315.722637) (xy 199.903817 -315.714842) (xy 199.889431 -315.700443) (xy 199.881654 -315.681632)
			(xy 199.881236 -315.671454) (xy 193.8401 -315.671454) (xy 193.839599 -315.681618) (xy 193.831837 -315.700404)
			(xy 193.817475 -315.714789) (xy 193.798701 -315.722583) (xy 193.788538 -315.723016) (xy 192.388998 -315.723016)
			(xy 192.378821 -315.722637) (xy 192.360017 -315.714842) (xy 192.345631 -315.700443) (xy 192.337854 -315.681632)
			(xy 192.337436 -315.671454) (xy 186.2963 -315.671454) (xy 186.295799 -315.681618) (xy 186.288037 -315.700404)
			(xy 186.273675 -315.714789) (xy 186.254901 -315.722583) (xy 186.244738 -315.723016) (xy 184.845198 -315.723016)
			(xy 184.835021 -315.722637) (xy 184.816217 -315.714842) (xy 184.801831 -315.700443) (xy 184.794054 -315.681632)
			(xy 184.793636 -315.671454) (xy 178.7525 -315.671454) (xy 178.751999 -315.681618) (xy 178.744237 -315.700404)
			(xy 178.729875 -315.714789) (xy 178.711101 -315.722583) (xy 178.700938 -315.723016) (xy 177.301398 -315.723016)
			(xy 177.291221 -315.722637) (xy 177.272417 -315.714842) (xy 177.258031 -315.700443) (xy 177.250254 -315.681632)
			(xy 177.249836 -315.671454) (xy 171.2087 -315.671454) (xy 171.208199 -315.681618) (xy 171.200437 -315.700404)
			(xy 171.186075 -315.714789) (xy 171.167301 -315.722583) (xy 171.157138 -315.723016) (xy 169.757598 -315.723016)
			(xy 169.747421 -315.722637) (xy 169.728617 -315.714842) (xy 169.714231 -315.700443) (xy 169.706454 -315.681632)
			(xy 169.706036 -315.671454) (xy 163.6649 -315.671454) (xy 163.664399 -315.681618) (xy 163.656637 -315.700404)
			(xy 163.642275 -315.714789) (xy 163.623501 -315.722583) (xy 163.613338 -315.723016) (xy 162.213798 -315.723016)
			(xy 162.203621 -315.722637) (xy 162.184817 -315.714842) (xy 162.170431 -315.700443) (xy 162.162654 -315.681632)
			(xy 162.162236 -315.671454) (xy 65.7987 -315.671454) (xy 65.798199 -315.681618) (xy 65.790437 -315.700404)
			(xy 65.776075 -315.714789) (xy 65.757301 -315.722583) (xy 65.747138 -315.723016) (xy 64.347598 -315.723016)
			(xy 64.337421 -315.722637) (xy 64.318617 -315.714842) (xy 64.304231 -315.700443) (xy 64.296454 -315.681632)
			(xy 64.296036 -315.671454) (xy 58.2549 -315.671454) (xy 58.254399 -315.681618) (xy 58.246637 -315.700404)
			(xy 58.232275 -315.714789) (xy 58.213501 -315.722583) (xy 58.203338 -315.723016) (xy 56.803798 -315.723016)
			(xy 56.793621 -315.722637) (xy 56.774817 -315.714842) (xy 56.760431 -315.700443) (xy 56.752654 -315.681632)
			(xy 56.752236 -315.671454) (xy 50.7111 -315.671454) (xy 50.710599 -315.681618) (xy 50.702837 -315.700404)
			(xy 50.688475 -315.714789) (xy 50.669701 -315.722583) (xy 50.659538 -315.723016) (xy 49.259998 -315.723016)
			(xy 49.249821 -315.722637) (xy 49.231017 -315.714842) (xy 49.216631 -315.700443) (xy 49.208854 -315.681632)
			(xy 49.208436 -315.671454) (xy 43.1673 -315.671454) (xy 43.166799 -315.681618) (xy 43.159037 -315.700404)
			(xy 43.144675 -315.714789) (xy 43.125901 -315.722583) (xy 43.115738 -315.723016) (xy 41.716198 -315.723016)
			(xy 41.706021 -315.722637) (xy 41.687217 -315.714842) (xy 41.672831 -315.700443) (xy 41.665054 -315.681632)
			(xy 41.664636 -315.671454) (xy 35.6235 -315.671454) (xy 35.622999 -315.681618) (xy 35.615237 -315.700404)
			(xy 35.600875 -315.714789) (xy 35.582101 -315.722583) (xy 35.571938 -315.723016) (xy 34.172398 -315.723016)
			(xy 34.162221 -315.722637) (xy 34.143417 -315.714842) (xy 34.129031 -315.700443) (xy 34.121254 -315.681632)
			(xy 34.120836 -315.671454) (xy 28.0797 -315.671454) (xy 28.079199 -315.681618) (xy 28.071437 -315.700404)
			(xy 28.057075 -315.714789) (xy 28.038301 -315.722583) (xy 28.028138 -315.723016) (xy 26.628598 -315.723016)
			(xy 26.618421 -315.722637) (xy 26.599617 -315.714842) (xy 26.585231 -315.700443) (xy 26.577454 -315.681632)
			(xy 26.577036 -315.671454) (xy 20.5359 -315.671454) (xy 20.535399 -315.681618) (xy 20.527637 -315.700404)
			(xy 20.513275 -315.714789) (xy 20.494501 -315.722583) (xy 20.484338 -315.723016) (xy 19.084798 -315.723016)
			(xy 19.074621 -315.722637) (xy 19.055817 -315.714842) (xy 19.041431 -315.700443) (xy 19.033654 -315.681632)
			(xy 19.033236 -315.671454) (xy 12.9921 -315.671454) (xy 12.991599 -315.681618) (xy 12.983837 -315.700404)
			(xy 12.969475 -315.714789) (xy 12.950701 -315.722583) (xy 12.940538 -315.723016) (xy 11.540998 -315.723016)
			(xy 11.530821 -315.722637) (xy 11.512017 -315.714842) (xy 11.497631 -315.700443) (xy 11.489854 -315.681632)
			(xy 11.489436 -315.671454) (xy 2.509012 -315.671454) (xy 2.509012 -316.521338) (xy 7.389368 -316.521338)
			(xy 7.389368 -316.112398) (xy 7.389763 -316.102223) (xy 7.397554 -316.083422) (xy 7.411949 -316.069036)
			(xy 7.430754 -316.061257) (xy 7.44093 -316.060836) (xy 8.84047 -316.060836) (xy 8.850639 -316.061289)
			(xy 8.869433 -316.069063) (xy 8.883819 -316.08344) (xy 8.891605 -316.102229) (xy 8.892032 -316.112398)
			(xy 8.892032 -316.521338) (xy 14.933168 -316.521338) (xy 14.933168 -316.112398) (xy 14.933563 -316.102223)
			(xy 14.941354 -316.083422) (xy 14.955749 -316.069036) (xy 14.974554 -316.061257) (xy 14.98473 -316.060836)
			(xy 16.38427 -316.060836) (xy 16.394439 -316.061289) (xy 16.413233 -316.069063) (xy 16.427619 -316.08344)
			(xy 16.435405 -316.102229) (xy 16.435832 -316.112398) (xy 16.435832 -316.521338) (xy 22.476968 -316.521338)
			(xy 22.476968 -316.112398) (xy 22.477363 -316.102223) (xy 22.485154 -316.083422) (xy 22.499549 -316.069036)
			(xy 22.518354 -316.061257) (xy 22.52853 -316.060836) (xy 23.92807 -316.060836) (xy 23.938239 -316.061289)
			(xy 23.957033 -316.069063) (xy 23.971419 -316.08344) (xy 23.979205 -316.102229) (xy 23.979632 -316.112398)
			(xy 23.979632 -316.521338) (xy 30.020768 -316.521338) (xy 30.020768 -316.112398) (xy 30.021163 -316.102223)
			(xy 30.028954 -316.083422) (xy 30.043349 -316.069036) (xy 30.062154 -316.061257) (xy 30.07233 -316.060836)
			(xy 31.47187 -316.060836) (xy 31.482039 -316.061289) (xy 31.500833 -316.069063) (xy 31.515219 -316.08344)
			(xy 31.523005 -316.102229) (xy 31.523432 -316.112398) (xy 31.523432 -316.521338) (xy 37.564568 -316.521338)
			(xy 37.564568 -316.112398) (xy 37.564963 -316.102223) (xy 37.572754 -316.083422) (xy 37.587149 -316.069036)
			(xy 37.605954 -316.061257) (xy 37.61613 -316.060836) (xy 39.01567 -316.060836) (xy 39.025839 -316.061289)
			(xy 39.044633 -316.069063) (xy 39.059019 -316.08344) (xy 39.066805 -316.102229) (xy 39.067232 -316.112398)
			(xy 39.067232 -316.521338) (xy 45.108368 -316.521338) (xy 45.108368 -316.112398) (xy 45.108763 -316.102223)
			(xy 45.116554 -316.083422) (xy 45.130949 -316.069036) (xy 45.149754 -316.061257) (xy 45.15993 -316.060836)
			(xy 46.55947 -316.060836) (xy 46.569639 -316.061289) (xy 46.588433 -316.069063) (xy 46.602819 -316.08344)
			(xy 46.610605 -316.102229) (xy 46.611032 -316.112398) (xy 46.611032 -316.521338) (xy 52.652168 -316.521338)
			(xy 52.652168 -316.112398) (xy 52.652563 -316.102223) (xy 52.660354 -316.083422) (xy 52.674749 -316.069036)
			(xy 52.693554 -316.061257) (xy 52.70373 -316.060836) (xy 54.10327 -316.060836) (xy 54.113439 -316.061289)
			(xy 54.132233 -316.069063) (xy 54.146619 -316.08344) (xy 54.154405 -316.102229) (xy 54.154832 -316.112398)
			(xy 54.154832 -316.521338) (xy 60.195968 -316.521338) (xy 60.195968 -316.112398) (xy 60.196363 -316.102223)
			(xy 60.204154 -316.083422) (xy 60.218549 -316.069036) (xy 60.237354 -316.061257) (xy 60.24753 -316.060836)
			(xy 61.64707 -316.060836) (xy 61.657239 -316.061289) (xy 61.676033 -316.069063) (xy 61.690419 -316.08344)
			(xy 61.698205 -316.102229) (xy 61.698632 -316.112398) (xy 61.698632 -316.521338) (xy 158.062168 -316.521338)
			(xy 158.062168 -316.112398) (xy 158.062563 -316.102223) (xy 158.070354 -316.083422) (xy 158.084749 -316.069036)
			(xy 158.103554 -316.061257) (xy 158.11373 -316.060836) (xy 159.51327 -316.060836) (xy 159.523439 -316.061289)
			(xy 159.542233 -316.069063) (xy 159.556619 -316.08344) (xy 159.564405 -316.102229) (xy 159.564832 -316.112398)
			(xy 159.564832 -316.521338) (xy 165.605968 -316.521338) (xy 165.605968 -316.112398) (xy 165.606363 -316.102223)
			(xy 165.614154 -316.083422) (xy 165.628549 -316.069036) (xy 165.647354 -316.061257) (xy 165.65753 -316.060836)
			(xy 167.05707 -316.060836) (xy 167.067239 -316.061289) (xy 167.086033 -316.069063) (xy 167.100419 -316.08344)
			(xy 167.108205 -316.102229) (xy 167.108632 -316.112398) (xy 167.108632 -316.521338) (xy 173.149768 -316.521338)
			(xy 173.149768 -316.112398) (xy 173.150163 -316.102223) (xy 173.157954 -316.083422) (xy 173.172349 -316.069036)
			(xy 173.191154 -316.061257) (xy 173.20133 -316.060836) (xy 174.60087 -316.060836) (xy 174.611039 -316.061289)
			(xy 174.629833 -316.069063) (xy 174.644219 -316.08344) (xy 174.652005 -316.102229) (xy 174.652432 -316.112398)
			(xy 174.652432 -316.521338) (xy 180.693568 -316.521338) (xy 180.693568 -316.112398) (xy 180.693963 -316.102223)
			(xy 180.701754 -316.083422) (xy 180.716149 -316.069036) (xy 180.734954 -316.061257) (xy 180.74513 -316.060836)
			(xy 182.14467 -316.060836) (xy 182.154839 -316.061289) (xy 182.173633 -316.069063) (xy 182.188019 -316.08344)
			(xy 182.195805 -316.102229) (xy 182.196232 -316.112398) (xy 182.196232 -316.521338) (xy 188.237368 -316.521338)
			(xy 188.237368 -316.112398) (xy 188.237763 -316.102223) (xy 188.245554 -316.083422) (xy 188.259949 -316.069036)
			(xy 188.278754 -316.061257) (xy 188.28893 -316.060836) (xy 189.68847 -316.060836) (xy 189.698639 -316.061289)
			(xy 189.717433 -316.069063) (xy 189.731819 -316.08344) (xy 189.739605 -316.102229) (xy 189.740032 -316.112398)
			(xy 189.740032 -316.521338) (xy 195.781168 -316.521338) (xy 195.781168 -316.112398) (xy 195.781563 -316.102223)
			(xy 195.789354 -316.083422) (xy 195.803749 -316.069036) (xy 195.822554 -316.061257) (xy 195.83273 -316.060836)
			(xy 197.23227 -316.060836) (xy 197.242439 -316.061289) (xy 197.261233 -316.069063) (xy 197.275619 -316.08344)
			(xy 197.283405 -316.102229) (xy 197.283832 -316.112398) (xy 197.283832 -316.521338) (xy 203.324968 -316.521338)
			(xy 203.324968 -316.112398) (xy 203.325363 -316.102223) (xy 203.333154 -316.083422) (xy 203.347549 -316.069036)
			(xy 203.366354 -316.061257) (xy 203.37653 -316.060836) (xy 204.77607 -316.060836) (xy 204.786239 -316.061289)
			(xy 204.805033 -316.069063) (xy 204.819419 -316.08344) (xy 204.827205 -316.102229) (xy 204.827632 -316.112398)
			(xy 204.827632 -316.521338) (xy 210.868768 -316.521338) (xy 210.868768 -316.112398) (xy 210.869163 -316.102223)
			(xy 210.876954 -316.083422) (xy 210.891349 -316.069036) (xy 210.910154 -316.061257) (xy 210.92033 -316.060836)
			(xy 212.31987 -316.060836) (xy 212.330039 -316.061289) (xy 212.348833 -316.069063) (xy 212.363219 -316.08344)
			(xy 212.371005 -316.102229) (xy 212.371432 -316.112398) (xy 212.371432 -316.521338) (xy 255.329436 -316.521338)
			(xy 255.329436 -316.112398) (xy 255.329932 -316.10224) (xy 255.337706 -316.083472) (xy 255.352072 -316.069106)
			(xy 255.37084 -316.061332) (xy 255.380998 -316.060836) (xy 256.780538 -316.060836) (xy 256.790698 -316.061302)
			(xy 256.809468 -316.069089) (xy 256.823831 -316.083463) (xy 256.831605 -316.102238) (xy 256.8321 -316.112398)
			(xy 256.8321 -316.521338) (xy 262.873236 -316.521338) (xy 262.873236 -316.112398) (xy 262.873732 -316.10224)
			(xy 262.881506 -316.083472) (xy 262.895872 -316.069106) (xy 262.91464 -316.061332) (xy 262.924798 -316.060836)
			(xy 264.324338 -316.060836) (xy 264.334498 -316.061302) (xy 264.353268 -316.069089) (xy 264.367631 -316.083463)
			(xy 264.375405 -316.102238) (xy 264.3759 -316.112398) (xy 264.3759 -316.521338) (xy 270.417036 -316.521338)
			(xy 270.417036 -316.112398) (xy 270.417532 -316.10224) (xy 270.425306 -316.083472) (xy 270.439672 -316.069106)
			(xy 270.45844 -316.061332) (xy 270.468598 -316.060836) (xy 271.868138 -316.060836) (xy 271.878298 -316.061302)
			(xy 271.897068 -316.069089) (xy 271.911431 -316.083463) (xy 271.919205 -316.102238) (xy 271.9197 -316.112398)
			(xy 271.9197 -316.521338) (xy 277.960836 -316.521338) (xy 277.960836 -316.112398) (xy 277.961332 -316.10224)
			(xy 277.969106 -316.083472) (xy 277.983472 -316.069106) (xy 278.00224 -316.061332) (xy 278.012398 -316.060836)
			(xy 279.411938 -316.060836) (xy 279.422098 -316.061302) (xy 279.440868 -316.069089) (xy 279.455231 -316.083463)
			(xy 279.463005 -316.102238) (xy 279.4635 -316.112398) (xy 279.4635 -316.521338) (xy 285.504636 -316.521338)
			(xy 285.504636 -316.112398) (xy 285.505132 -316.10224) (xy 285.512906 -316.083472) (xy 285.527272 -316.069106)
			(xy 285.54604 -316.061332) (xy 285.556198 -316.060836) (xy 286.955738 -316.060836) (xy 286.965898 -316.061302)
			(xy 286.984668 -316.069089) (xy 286.999031 -316.083463) (xy 287.006805 -316.102238) (xy 287.0073 -316.112398)
			(xy 287.0073 -316.521338) (xy 293.048436 -316.521338) (xy 293.048436 -316.112398) (xy 293.048932 -316.10224)
			(xy 293.056706 -316.083472) (xy 293.071072 -316.069106) (xy 293.08984 -316.061332) (xy 293.099998 -316.060836)
			(xy 294.499538 -316.060836) (xy 294.509698 -316.061302) (xy 294.528468 -316.069089) (xy 294.542831 -316.083463)
			(xy 294.550605 -316.102238) (xy 294.5511 -316.112398) (xy 294.5511 -316.521338) (xy 300.592236 -316.521338)
			(xy 300.592236 -316.112398) (xy 300.592732 -316.10224) (xy 300.600506 -316.083472) (xy 300.614872 -316.069106)
			(xy 300.63364 -316.061332) (xy 300.643798 -316.060836) (xy 302.043338 -316.060836) (xy 302.053498 -316.061302)
			(xy 302.072268 -316.069089) (xy 302.086631 -316.083463) (xy 302.094405 -316.102238) (xy 302.0949 -316.112398)
			(xy 302.0949 -316.521338) (xy 308.136036 -316.521338) (xy 308.136036 -316.112398) (xy 308.136532 -316.10224)
			(xy 308.144306 -316.083472) (xy 308.158672 -316.069106) (xy 308.17744 -316.061332) (xy 308.187598 -316.060836)
			(xy 309.587138 -316.060836) (xy 309.597298 -316.061302) (xy 309.616068 -316.069089) (xy 309.630431 -316.083463)
			(xy 309.638205 -316.102238) (xy 309.6387 -316.112398) (xy 309.6387 -316.521338) (xy 406.002236 -316.521338)
			(xy 406.002236 -316.112398) (xy 406.002732 -316.10224) (xy 406.010506 -316.083472) (xy 406.024872 -316.069106)
			(xy 406.04364 -316.061332) (xy 406.053798 -316.060836) (xy 407.453338 -316.060836) (xy 407.463498 -316.061302)
			(xy 407.482268 -316.069089) (xy 407.496631 -316.083463) (xy 407.504405 -316.102238) (xy 407.5049 -316.112398)
			(xy 407.5049 -316.521338) (xy 413.546036 -316.521338) (xy 413.546036 -316.112398) (xy 413.546532 -316.10224)
			(xy 413.554306 -316.083472) (xy 413.568672 -316.069106) (xy 413.58744 -316.061332) (xy 413.597598 -316.060836)
			(xy 414.997138 -316.060836) (xy 415.007298 -316.061302) (xy 415.026068 -316.069089) (xy 415.040431 -316.083463)
			(xy 415.048205 -316.102238) (xy 415.0487 -316.112398) (xy 415.0487 -316.521338) (xy 421.089836 -316.521338)
			(xy 421.089836 -316.112398) (xy 421.090332 -316.10224) (xy 421.098106 -316.083472) (xy 421.112472 -316.069106)
			(xy 421.13124 -316.061332) (xy 421.141398 -316.060836) (xy 422.540938 -316.060836) (xy 422.551098 -316.061302)
			(xy 422.569868 -316.069089) (xy 422.584231 -316.083463) (xy 422.592005 -316.102238) (xy 422.5925 -316.112398)
			(xy 422.5925 -316.521338) (xy 428.633636 -316.521338) (xy 428.633636 -316.112398) (xy 428.634132 -316.10224)
			(xy 428.641906 -316.083472) (xy 428.656272 -316.069106) (xy 428.67504 -316.061332) (xy 428.685198 -316.060836)
			(xy 430.084738 -316.060836) (xy 430.094898 -316.061302) (xy 430.113668 -316.069089) (xy 430.128031 -316.083463)
			(xy 430.135805 -316.102238) (xy 430.1363 -316.112398) (xy 430.1363 -316.521338) (xy 436.177436 -316.521338)
			(xy 436.177436 -316.112398) (xy 436.177932 -316.10224) (xy 436.185706 -316.083472) (xy 436.200072 -316.069106)
			(xy 436.21884 -316.061332) (xy 436.228998 -316.060836) (xy 437.628538 -316.060836) (xy 437.638698 -316.061302)
			(xy 437.657468 -316.069089) (xy 437.671831 -316.083463) (xy 437.679605 -316.102238) (xy 437.6801 -316.112398)
			(xy 437.6801 -316.521338) (xy 443.721236 -316.521338) (xy 443.721236 -316.112398) (xy 443.721732 -316.10224)
			(xy 443.729506 -316.083472) (xy 443.743872 -316.069106) (xy 443.76264 -316.061332) (xy 443.772798 -316.060836)
			(xy 445.172338 -316.060836) (xy 445.182498 -316.061302) (xy 445.201268 -316.069089) (xy 445.215631 -316.083463)
			(xy 445.223405 -316.102238) (xy 445.2239 -316.112398) (xy 445.2239 -316.521338) (xy 451.265036 -316.521338)
			(xy 451.265036 -316.112398) (xy 451.265532 -316.10224) (xy 451.273306 -316.083472) (xy 451.287672 -316.069106)
			(xy 451.30644 -316.061332) (xy 451.316598 -316.060836) (xy 452.716138 -316.060836) (xy 452.726298 -316.061302)
			(xy 452.745068 -316.069089) (xy 452.759431 -316.083463) (xy 452.767205 -316.102238) (xy 452.7677 -316.112398)
			(xy 452.7677 -316.521338) (xy 458.808836 -316.521338) (xy 458.808836 -316.112398) (xy 458.809332 -316.10224)
			(xy 458.817106 -316.083472) (xy 458.831472 -316.069106) (xy 458.85024 -316.061332) (xy 458.860398 -316.060836)
			(xy 460.259938 -316.060836) (xy 460.270098 -316.061302) (xy 460.288868 -316.069089) (xy 460.303231 -316.083463)
			(xy 460.311005 -316.102238) (xy 460.3115 -316.112398) (xy 460.3115 -316.521338) (xy 460.310999 -316.531494)
			(xy 460.303219 -316.550256) (xy 460.288856 -316.564619) (xy 460.270094 -316.572399) (xy 460.259938 -316.5729)
			(xy 458.860398 -316.5729) (xy 458.850245 -316.572369) (xy 458.831483 -316.564601) (xy 458.817119 -316.550247)
			(xy 458.809338 -316.531491) (xy 458.808836 -316.521338) (xy 452.7677 -316.521338) (xy 452.767199 -316.531494)
			(xy 452.759419 -316.550256) (xy 452.745056 -316.564619) (xy 452.726294 -316.572399) (xy 452.716138 -316.5729)
			(xy 451.316598 -316.5729) (xy 451.306445 -316.572369) (xy 451.287683 -316.564601) (xy 451.273319 -316.550247)
			(xy 451.265538 -316.531491) (xy 451.265036 -316.521338) (xy 445.2239 -316.521338) (xy 445.223399 -316.531494)
			(xy 445.215619 -316.550256) (xy 445.201256 -316.564619) (xy 445.182494 -316.572399) (xy 445.172338 -316.5729)
			(xy 443.772798 -316.5729) (xy 443.762645 -316.572369) (xy 443.743883 -316.564601) (xy 443.729519 -316.550247)
			(xy 443.721738 -316.531491) (xy 443.721236 -316.521338) (xy 437.6801 -316.521338) (xy 437.679599 -316.531494)
			(xy 437.671819 -316.550256) (xy 437.657456 -316.564619) (xy 437.638694 -316.572399) (xy 437.628538 -316.5729)
			(xy 436.228998 -316.5729) (xy 436.218845 -316.572369) (xy 436.200083 -316.564601) (xy 436.185719 -316.550247)
			(xy 436.177938 -316.531491) (xy 436.177436 -316.521338) (xy 430.1363 -316.521338) (xy 430.135799 -316.531494)
			(xy 430.128019 -316.550256) (xy 430.113656 -316.564619) (xy 430.094894 -316.572399) (xy 430.084738 -316.5729)
			(xy 428.685198 -316.5729) (xy 428.675045 -316.572369) (xy 428.656283 -316.564601) (xy 428.641919 -316.550247)
			(xy 428.634138 -316.531491) (xy 428.633636 -316.521338) (xy 422.5925 -316.521338) (xy 422.591999 -316.531494)
			(xy 422.584219 -316.550256) (xy 422.569856 -316.564619) (xy 422.551094 -316.572399) (xy 422.540938 -316.5729)
			(xy 421.141398 -316.5729) (xy 421.131245 -316.572369) (xy 421.112483 -316.564601) (xy 421.098119 -316.550247)
			(xy 421.090338 -316.531491) (xy 421.089836 -316.521338) (xy 415.0487 -316.521338) (xy 415.048199 -316.531494)
			(xy 415.040419 -316.550256) (xy 415.026056 -316.564619) (xy 415.007294 -316.572399) (xy 414.997138 -316.5729)
			(xy 413.597598 -316.5729) (xy 413.587445 -316.572369) (xy 413.568683 -316.564601) (xy 413.554319 -316.550247)
			(xy 413.546538 -316.531491) (xy 413.546036 -316.521338) (xy 407.5049 -316.521338) (xy 407.504399 -316.531494)
			(xy 407.496619 -316.550256) (xy 407.482256 -316.564619) (xy 407.463494 -316.572399) (xy 407.453338 -316.5729)
			(xy 406.053798 -316.5729) (xy 406.043645 -316.572369) (xy 406.024883 -316.564601) (xy 406.010519 -316.550247)
			(xy 406.002738 -316.531491) (xy 406.002236 -316.521338) (xy 309.6387 -316.521338) (xy 309.638199 -316.531494)
			(xy 309.630419 -316.550256) (xy 309.616056 -316.564619) (xy 309.597294 -316.572399) (xy 309.587138 -316.5729)
			(xy 308.187598 -316.5729) (xy 308.177445 -316.572369) (xy 308.158683 -316.564601) (xy 308.144319 -316.550247)
			(xy 308.136538 -316.531491) (xy 308.136036 -316.521338) (xy 302.0949 -316.521338) (xy 302.094399 -316.531494)
			(xy 302.086619 -316.550256) (xy 302.072256 -316.564619) (xy 302.053494 -316.572399) (xy 302.043338 -316.5729)
			(xy 300.643798 -316.5729) (xy 300.633645 -316.572369) (xy 300.614883 -316.564601) (xy 300.600519 -316.550247)
			(xy 300.592738 -316.531491) (xy 300.592236 -316.521338) (xy 294.5511 -316.521338) (xy 294.550599 -316.531494)
			(xy 294.542819 -316.550256) (xy 294.528456 -316.564619) (xy 294.509694 -316.572399) (xy 294.499538 -316.5729)
			(xy 293.099998 -316.5729) (xy 293.089845 -316.572369) (xy 293.071083 -316.564601) (xy 293.056719 -316.550247)
			(xy 293.048938 -316.531491) (xy 293.048436 -316.521338) (xy 287.0073 -316.521338) (xy 287.006799 -316.531494)
			(xy 286.999019 -316.550256) (xy 286.984656 -316.564619) (xy 286.965894 -316.572399) (xy 286.955738 -316.5729)
			(xy 285.556198 -316.5729) (xy 285.546045 -316.572369) (xy 285.527283 -316.564601) (xy 285.512919 -316.550247)
			(xy 285.505138 -316.531491) (xy 285.504636 -316.521338) (xy 279.4635 -316.521338) (xy 279.462999 -316.531494)
			(xy 279.455219 -316.550256) (xy 279.440856 -316.564619) (xy 279.422094 -316.572399) (xy 279.411938 -316.5729)
			(xy 278.012398 -316.5729) (xy 278.002245 -316.572369) (xy 277.983483 -316.564601) (xy 277.969119 -316.550247)
			(xy 277.961338 -316.531491) (xy 277.960836 -316.521338) (xy 271.9197 -316.521338) (xy 271.919199 -316.531494)
			(xy 271.911419 -316.550256) (xy 271.897056 -316.564619) (xy 271.878294 -316.572399) (xy 271.868138 -316.5729)
			(xy 270.468598 -316.5729) (xy 270.458445 -316.572369) (xy 270.439683 -316.564601) (xy 270.425319 -316.550247)
			(xy 270.417538 -316.531491) (xy 270.417036 -316.521338) (xy 264.3759 -316.521338) (xy 264.375399 -316.531494)
			(xy 264.367619 -316.550256) (xy 264.353256 -316.564619) (xy 264.334494 -316.572399) (xy 264.324338 -316.5729)
			(xy 262.924798 -316.5729) (xy 262.914645 -316.572369) (xy 262.895883 -316.564601) (xy 262.881519 -316.550247)
			(xy 262.873738 -316.531491) (xy 262.873236 -316.521338) (xy 256.8321 -316.521338) (xy 256.831599 -316.531494)
			(xy 256.823819 -316.550256) (xy 256.809456 -316.564619) (xy 256.790694 -316.572399) (xy 256.780538 -316.5729)
			(xy 255.380998 -316.5729) (xy 255.370845 -316.572369) (xy 255.352083 -316.564601) (xy 255.337719 -316.550247)
			(xy 255.329938 -316.531491) (xy 255.329436 -316.521338) (xy 212.371432 -316.521338) (xy 212.370997 -316.531502)
			(xy 212.363204 -316.550278) (xy 212.348821 -316.564643) (xy 212.330035 -316.57241) (xy 212.31987 -316.5729)
			(xy 210.92033 -316.5729) (xy 210.910179 -316.572343) (xy 210.891417 -316.564586) (xy 210.877052 -316.55024)
			(xy 210.86927 -316.531489) (xy 210.868768 -316.521338) (xy 204.827632 -316.521338) (xy 204.827197 -316.531502)
			(xy 204.819404 -316.550278) (xy 204.805021 -316.564643) (xy 204.786235 -316.57241) (xy 204.77607 -316.5729)
			(xy 203.37653 -316.5729) (xy 203.366379 -316.572343) (xy 203.347617 -316.564586) (xy 203.333252 -316.55024)
			(xy 203.32547 -316.531489) (xy 203.324968 -316.521338) (xy 197.283832 -316.521338) (xy 197.283397 -316.531502)
			(xy 197.275604 -316.550278) (xy 197.261221 -316.564643) (xy 197.242435 -316.57241) (xy 197.23227 -316.5729)
			(xy 195.83273 -316.5729) (xy 195.822579 -316.572343) (xy 195.803817 -316.564586) (xy 195.789452 -316.55024)
			(xy 195.78167 -316.531489) (xy 195.781168 -316.521338) (xy 189.740032 -316.521338) (xy 189.739597 -316.531502)
			(xy 189.731804 -316.550278) (xy 189.717421 -316.564643) (xy 189.698635 -316.57241) (xy 189.68847 -316.5729)
			(xy 188.28893 -316.5729) (xy 188.278779 -316.572343) (xy 188.260017 -316.564586) (xy 188.245652 -316.55024)
			(xy 188.23787 -316.531489) (xy 188.237368 -316.521338) (xy 182.196232 -316.521338) (xy 182.195797 -316.531502)
			(xy 182.188004 -316.550278) (xy 182.173621 -316.564643) (xy 182.154835 -316.57241) (xy 182.14467 -316.5729)
			(xy 180.74513 -316.5729) (xy 180.734979 -316.572343) (xy 180.716217 -316.564586) (xy 180.701852 -316.55024)
			(xy 180.69407 -316.531489) (xy 180.693568 -316.521338) (xy 174.652432 -316.521338) (xy 174.651997 -316.531502)
			(xy 174.644204 -316.550278) (xy 174.629821 -316.564643) (xy 174.611035 -316.57241) (xy 174.60087 -316.5729)
			(xy 173.20133 -316.5729) (xy 173.191179 -316.572343) (xy 173.172417 -316.564586) (xy 173.158052 -316.55024)
			(xy 173.15027 -316.531489) (xy 173.149768 -316.521338) (xy 167.108632 -316.521338) (xy 167.108197 -316.531502)
			(xy 167.100404 -316.550278) (xy 167.086021 -316.564643) (xy 167.067235 -316.57241) (xy 167.05707 -316.5729)
			(xy 165.65753 -316.5729) (xy 165.647379 -316.572343) (xy 165.628617 -316.564586) (xy 165.614252 -316.55024)
			(xy 165.60647 -316.531489) (xy 165.605968 -316.521338) (xy 159.564832 -316.521338) (xy 159.564397 -316.531502)
			(xy 159.556604 -316.550278) (xy 159.542221 -316.564643) (xy 159.523435 -316.57241) (xy 159.51327 -316.5729)
			(xy 158.11373 -316.5729) (xy 158.103579 -316.572343) (xy 158.084817 -316.564586) (xy 158.070452 -316.55024)
			(xy 158.06267 -316.531489) (xy 158.062168 -316.521338) (xy 61.698632 -316.521338) (xy 61.698197 -316.531502)
			(xy 61.690404 -316.550278) (xy 61.676021 -316.564643) (xy 61.657235 -316.57241) (xy 61.64707 -316.5729)
			(xy 60.24753 -316.5729) (xy 60.237379 -316.572343) (xy 60.218617 -316.564586) (xy 60.204252 -316.55024)
			(xy 60.19647 -316.531489) (xy 60.195968 -316.521338) (xy 54.154832 -316.521338) (xy 54.154397 -316.531502)
			(xy 54.146604 -316.550278) (xy 54.132221 -316.564643) (xy 54.113435 -316.57241) (xy 54.10327 -316.5729)
			(xy 52.70373 -316.5729) (xy 52.693579 -316.572343) (xy 52.674817 -316.564586) (xy 52.660452 -316.55024)
			(xy 52.65267 -316.531489) (xy 52.652168 -316.521338) (xy 46.611032 -316.521338) (xy 46.610597 -316.531502)
			(xy 46.602804 -316.550278) (xy 46.588421 -316.564643) (xy 46.569635 -316.57241) (xy 46.55947 -316.5729)
			(xy 45.15993 -316.5729) (xy 45.149779 -316.572343) (xy 45.131017 -316.564586) (xy 45.116652 -316.55024)
			(xy 45.10887 -316.531489) (xy 45.108368 -316.521338) (xy 39.067232 -316.521338) (xy 39.066797 -316.531502)
			(xy 39.059004 -316.550278) (xy 39.044621 -316.564643) (xy 39.025835 -316.57241) (xy 39.01567 -316.5729)
			(xy 37.61613 -316.5729) (xy 37.605979 -316.572343) (xy 37.587217 -316.564586) (xy 37.572852 -316.55024)
			(xy 37.56507 -316.531489) (xy 37.564568 -316.521338) (xy 31.523432 -316.521338) (xy 31.522997 -316.531502)
			(xy 31.515204 -316.550278) (xy 31.500821 -316.564643) (xy 31.482035 -316.57241) (xy 31.47187 -316.5729)
			(xy 30.07233 -316.5729) (xy 30.062179 -316.572343) (xy 30.043417 -316.564586) (xy 30.029052 -316.55024)
			(xy 30.02127 -316.531489) (xy 30.020768 -316.521338) (xy 23.979632 -316.521338) (xy 23.979197 -316.531502)
			(xy 23.971404 -316.550278) (xy 23.957021 -316.564643) (xy 23.938235 -316.57241) (xy 23.92807 -316.5729)
			(xy 22.52853 -316.5729) (xy 22.518379 -316.572343) (xy 22.499617 -316.564586) (xy 22.485252 -316.55024)
			(xy 22.47747 -316.531489) (xy 22.476968 -316.521338) (xy 16.435832 -316.521338) (xy 16.435397 -316.531502)
			(xy 16.427604 -316.550278) (xy 16.413221 -316.564643) (xy 16.394435 -316.57241) (xy 16.38427 -316.5729)
			(xy 14.98473 -316.5729) (xy 14.974579 -316.572343) (xy 14.955817 -316.564586) (xy 14.941452 -316.55024)
			(xy 14.93367 -316.531489) (xy 14.933168 -316.521338) (xy 8.892032 -316.521338) (xy 8.891597 -316.531502)
			(xy 8.883804 -316.550278) (xy 8.869421 -316.564643) (xy 8.850635 -316.57241) (xy 8.84047 -316.5729)
			(xy 7.44093 -316.5729) (xy 7.430779 -316.572343) (xy 7.412017 -316.564586) (xy 7.397652 -316.55024)
			(xy 7.38987 -316.531489) (xy 7.389368 -316.521338) (xy 2.509012 -316.521338) (xy 2.509012 -360.76382)
			(xy 4.226823 -360.76382) (xy 4.230819 -360.553934) (xy 4.242804 -360.344352) (xy 4.262758 -360.135378)
			(xy 4.290654 -359.927316) (xy 4.326451 -359.720466) (xy 4.370096 -359.515129) (xy 4.421528 -359.311603)
			(xy 4.48067 -359.110182) (xy 4.547438 -358.911159) (xy 4.621734 -358.714822) (xy 4.703452 -358.521456)
			(xy 4.792471 -358.331341) (xy 4.888664 -358.144753) (xy 4.991891 -357.961962) (xy 5.102002 -357.783234)
			(xy 5.218837 -357.608827) (xy 5.342227 -357.438995) (xy 5.471994 -357.273983) (xy 5.607948 -357.114032)
			(xy 5.749894 -356.959372) (xy 5.897624 -356.810228) (xy 6.050926 -356.666817) (xy 6.209576 -356.529346)
			(xy 6.373345 -356.398014) (xy 6.541995 -356.273013) (xy 6.715281 -356.154522) (xy 6.892953 -356.042715)
			(xy 7.074753 -355.937753) (xy 7.260417 -355.839788) (xy 7.449675 -355.748963) (xy 7.642255 -355.665409)
			(xy 7.837876 -355.589246) (xy 8.036254 -355.520587) (xy 8.237103 -355.45953) (xy 8.44013 -355.406163)
			(xy 8.645043 -355.360565) (xy 8.851542 -355.3228) (xy 9.059329 -355.292925) (xy 9.268104 -355.270982)
			(xy 9.477562 -355.257003) (xy 9.687401 -355.251008) (xy 9.897315 -355.253007) (xy 10.107002 -355.262995)
			(xy 10.316156 -355.28096) (xy 10.524474 -355.306874) (xy 10.731655 -355.340699) (xy 10.937399 -355.382388)
			(xy 11.141405 -355.43188) (xy 11.34338 -355.489102) (xy 11.54303 -355.553972) (xy 11.740065 -355.626396)
			(xy 11.934201 -355.706269) (xy 12.125154 -355.793475) (xy 12.31265 -355.887887) (xy 12.496415 -355.989369)
			(xy 12.676183 -356.097773) (xy 12.851694 -356.212943) (xy 13.022693 -356.334711) (xy 13.188933 -356.4629)
			(xy 13.350172 -356.597326) (xy 13.506176 -356.737793) (xy 13.656719 -356.884097) (xy 13.801583 -357.036026)
			(xy 13.940558 -357.19336) (xy 14.073443 -357.355871) (xy 14.200044 -357.523324) (xy 14.320179 -357.695474)
			(xy 14.433673 -357.872074) (xy 14.540361 -358.052866) (xy 14.640088 -358.237589) (xy 14.732711 -358.425975)
			(xy 14.818095 -358.61775) (xy 14.896116 -358.812637) (xy 14.966661 -359.010353) (xy 15.029628 -359.210611)
			(xy 15.084925 -359.413121) (xy 15.132472 -359.61759) (xy 15.1722 -359.823721) (xy 15.204052 -360.031214)
			(xy 15.227982 -360.23977) (xy 15.243954 -360.449086) (xy 15.251946 -360.658858) (xy 15.252446 -360.76382)
			(xy 15.251946 -360.868782) (xy 15.243954 -361.078554) (xy 15.239789 -361.133136) (xy 121.446286 -361.133136)
			(xy 121.450375 -361.077254) (xy 121.462558 -361.022564) (xy 121.482574 -360.97023) (xy 121.509997 -360.921368)
			(xy 121.544242 -360.87702) (xy 121.584578 -360.83813) (xy 121.630148 -360.805528) (xy 121.679979 -360.779909)
			(xy 121.733009 -360.761817) (xy 121.788107 -360.75164) (xy 121.844101 -360.749594) (xy 121.899796 -360.755722)
			(xy 121.930771 -360.76382) (xy 211.161635 -360.76382) (xy 211.16566 -360.621628) (xy 211.177723 -360.479892)
			(xy 211.197786 -360.339066) (xy 211.225784 -360.1996) (xy 211.261628 -360.061941) (xy 211.305202 -359.926531)
			(xy 211.356367 -359.793803) (xy 211.41496 -359.664182) (xy 211.480791 -359.538084) (xy 211.553652 -359.415912)
			(xy 211.633307 -359.298058) (xy 211.719503 -359.184899) (xy 211.811962 -359.076797) (xy 211.91039 -358.9741)
			(xy 212.014469 -358.877136) (xy 212.123868 -358.786216) (xy 212.238236 -358.70163) (xy 212.357205 -358.62365)
			(xy 212.480396 -358.552526) (xy 212.607413 -358.488485) (xy 212.73785 -358.431733) (xy 212.871289 -358.382451)
			(xy 213.007302 -358.340797) (xy 213.145454 -358.306905) (xy 213.285303 -358.280884) (xy 213.426399 -358.262816)
			(xy 213.568291 -358.252759) (xy 213.710526 -358.250746) (xy 213.852646 -358.256783) (xy 213.994197 -358.270851)
			(xy 214.134726 -358.292905) (xy 214.273781 -358.322874) (xy 214.410919 -358.360662) (xy 214.545699 -358.406148)
			(xy 214.67769 -358.459186) (xy 214.806469 -358.519607) (xy 214.931623 -358.587216) (xy 215.052751 -358.661798)
			(xy 215.169467 -358.743114) (xy 215.281395 -358.830902) (xy 215.388177 -358.924882) (xy 215.489471 -359.024752)
			(xy 215.584952 -359.130194) (xy 215.674316 -359.240868) (xy 215.757274 -359.356421) (xy 215.833563 -359.476482)
			(xy 215.902937 -359.600667) (xy 215.965174 -359.728578) (xy 216.020075 -359.859805) (xy 216.067463 -359.993928)
			(xy 216.107188 -360.130517) (xy 216.139121 -360.269135) (xy 216.163162 -360.409337) (xy 216.179231 -360.550675)
			(xy 216.187279 -360.692696) (xy 216.187782 -360.76382) (xy 255.611635 -360.76382) (xy 255.61566 -360.621628)
			(xy 255.627723 -360.479892) (xy 255.647786 -360.339066) (xy 255.675784 -360.1996) (xy 255.711628 -360.061941)
			(xy 255.755202 -359.926531) (xy 255.806367 -359.793803) (xy 255.86496 -359.664182) (xy 255.930791 -359.538084)
			(xy 256.003652 -359.415912) (xy 256.083307 -359.298058) (xy 256.169503 -359.184899) (xy 256.261962 -359.076797)
			(xy 256.36039 -358.9741) (xy 256.464469 -358.877136) (xy 256.573868 -358.786216) (xy 256.688236 -358.70163)
			(xy 256.807205 -358.62365) (xy 256.930396 -358.552526) (xy 257.057413 -358.488485) (xy 257.18785 -358.431733)
			(xy 257.321289 -358.382451) (xy 257.457302 -358.340797) (xy 257.595454 -358.306905) (xy 257.735303 -358.280884)
			(xy 257.876399 -358.262816) (xy 258.018291 -358.252759) (xy 258.160526 -358.250746) (xy 258.302646 -358.256783)
			(xy 258.444197 -358.270851) (xy 258.584726 -358.292905) (xy 258.723781 -358.322874) (xy 258.860919 -358.360662)
			(xy 258.995699 -358.406148) (xy 259.12769 -358.459186) (xy 259.256469 -358.519607) (xy 259.381623 -358.587216)
			(xy 259.502751 -358.661798) (xy 259.619467 -358.743114) (xy 259.731395 -358.830902) (xy 259.838177 -358.924882)
			(xy 259.939471 -359.024752) (xy 260.034952 -359.130194) (xy 260.124316 -359.240868) (xy 260.207274 -359.356421)
			(xy 260.283563 -359.476482) (xy 260.352937 -359.600667) (xy 260.415174 -359.728578) (xy 260.470075 -359.859805)
			(xy 260.517463 -359.993928) (xy 260.557188 -360.130517) (xy 260.589121 -360.269135) (xy 260.613162 -360.409337)
			(xy 260.629231 -360.550675) (xy 260.637279 -360.692696) (xy 260.637782 -360.76382) (xy 260.637279 -360.834944)
			(xy 260.629231 -360.976965) (xy 260.613162 -361.118303) (xy 260.610619 -361.133136) (xy 369.3861 -361.133136)
			(xy 369.390189 -361.077254) (xy 369.402372 -361.022564) (xy 369.422388 -360.97023) (xy 369.449811 -360.921368)
			(xy 369.484056 -360.87702) (xy 369.524392 -360.83813) (xy 369.569962 -360.805528) (xy 369.619793 -360.779909)
			(xy 369.672823 -360.761817) (xy 369.727921 -360.75164) (xy 369.783915 -360.749594) (xy 369.83961 -360.755722)
			(xy 369.870585 -360.76382) (xy 456.565771 -360.76382) (xy 456.569767 -360.553934) (xy 456.581752 -360.344352)
			(xy 456.601706 -360.135378) (xy 456.629602 -359.927316) (xy 456.665399 -359.720466) (xy 456.709044 -359.515129)
			(xy 456.760476 -359.311603) (xy 456.819618 -359.110182) (xy 456.886386 -358.911159) (xy 456.960682 -358.714822)
			(xy 457.0424 -358.521456) (xy 457.131419 -358.331341) (xy 457.227612 -358.144753) (xy 457.330839 -357.961962)
			(xy 457.44095 -357.783234) (xy 457.557785 -357.608827) (xy 457.681175 -357.438995) (xy 457.810942 -357.273983)
			(xy 457.946896 -357.114032) (xy 458.088842 -356.959372) (xy 458.236572 -356.810228) (xy 458.389874 -356.666817)
			(xy 458.548524 -356.529346) (xy 458.712293 -356.398014) (xy 458.880943 -356.273013) (xy 459.054229 -356.154522)
			(xy 459.231901 -356.042715) (xy 459.413701 -355.937753) (xy 459.599365 -355.839788) (xy 459.788623 -355.748963)
			(xy 459.981203 -355.665409) (xy 460.176824 -355.589246) (xy 460.375202 -355.520587) (xy 460.576051 -355.45953)
			(xy 460.779078 -355.406163) (xy 460.983991 -355.360565) (xy 461.19049 -355.3228) (xy 461.398277 -355.292925)
			(xy 461.607052 -355.270982) (xy 461.81651 -355.257003) (xy 462.026349 -355.251008) (xy 462.236263 -355.253007)
			(xy 462.44595 -355.262995) (xy 462.655104 -355.28096) (xy 462.863422 -355.306874) (xy 463.070603 -355.340699)
			(xy 463.276347 -355.382388) (xy 463.480353 -355.43188) (xy 463.682328 -355.489102) (xy 463.881978 -355.553972)
			(xy 464.079013 -355.626396) (xy 464.273149 -355.706269) (xy 464.464102 -355.793475) (xy 464.651598 -355.887887)
			(xy 464.835363 -355.989369) (xy 465.015131 -356.097773) (xy 465.190642 -356.212943) (xy 465.361641 -356.334711)
			(xy 465.527881 -356.4629) (xy 465.68912 -356.597326) (xy 465.845124 -356.737793) (xy 465.995667 -356.884097)
			(xy 466.140531 -357.036026) (xy 466.279506 -357.19336) (xy 466.412391 -357.355871) (xy 466.538992 -357.523324)
			(xy 466.659127 -357.695474) (xy 466.772621 -357.872074) (xy 466.879309 -358.052866) (xy 466.979036 -358.237589)
			(xy 467.071659 -358.425975) (xy 467.157043 -358.61775) (xy 467.235064 -358.812637) (xy 467.305609 -359.010353)
			(xy 467.368576 -359.210611) (xy 467.423873 -359.413121) (xy 467.47142 -359.61759) (xy 467.511148 -359.823721)
			(xy 467.543 -360.031214) (xy 467.56693 -360.23977) (xy 467.582902 -360.449086) (xy 467.590894 -360.658858)
			(xy 467.591394 -360.76382) (xy 467.590894 -360.868782) (xy 467.582902 -361.078554) (xy 467.56693 -361.28787)
			(xy 467.543 -361.496426) (xy 467.511148 -361.703919) (xy 467.47142 -361.91005) (xy 467.423873 -362.114519)
			(xy 467.368576 -362.317029) (xy 467.305609 -362.517287) (xy 467.235064 -362.715003) (xy 467.157043 -362.90989)
			(xy 467.071659 -363.101665) (xy 466.979036 -363.290051) (xy 466.879309 -363.474774) (xy 466.772621 -363.655566)
			(xy 466.659127 -363.832166) (xy 466.538992 -364.004316) (xy 466.412391 -364.171769) (xy 466.279506 -364.33428)
			(xy 466.140531 -364.491614) (xy 465.995667 -364.643543) (xy 465.845124 -364.789847) (xy 465.68912 -364.930314)
			(xy 465.527881 -365.06474) (xy 465.361641 -365.192929) (xy 465.190642 -365.314697) (xy 465.015131 -365.429867)
			(xy 464.835363 -365.538271) (xy 464.651598 -365.639753) (xy 464.464102 -365.734165) (xy 464.273149 -365.821371)
			(xy 464.079013 -365.901244) (xy 463.881978 -365.973668) (xy 463.682328 -366.038538) (xy 463.480353 -366.09576)
			(xy 463.276347 -366.145252) (xy 463.070603 -366.186941) (xy 462.863422 -366.220766) (xy 462.655104 -366.24668)
			(xy 462.44595 -366.264645) (xy 462.236263 -366.274633) (xy 462.026349 -366.276632) (xy 461.81651 -366.270637)
			(xy 461.607052 -366.256658) (xy 461.398277 -366.234715) (xy 461.19049 -366.20484) (xy 460.983991 -366.167075)
			(xy 460.779078 -366.121477) (xy 460.576051 -366.06811) (xy 460.375202 -366.007053) (xy 460.176824 -365.938394)
			(xy 459.981203 -365.862231) (xy 459.788623 -365.778677) (xy 459.599365 -365.687852) (xy 459.413701 -365.589887)
			(xy 459.231901 -365.484925) (xy 459.054229 -365.373118) (xy 458.880943 -365.254627) (xy 458.712293 -365.129626)
			(xy 458.548524 -364.998294) (xy 458.389874 -364.860823) (xy 458.236572 -364.717412) (xy 458.088842 -364.568268)
			(xy 457.946896 -364.413608) (xy 457.810942 -364.253657) (xy 457.681175 -364.088645) (xy 457.557785 -363.918813)
			(xy 457.44095 -363.744406) (xy 457.330839 -363.565678) (xy 457.227612 -363.382887) (xy 457.131419 -363.196299)
			(xy 457.0424 -363.006184) (xy 456.960682 -362.812818) (xy 456.886386 -362.616481) (xy 456.819618 -362.417458)
			(xy 456.760476 -362.216037) (xy 456.709044 -362.012511) (xy 456.665399 -361.807174) (xy 456.629602 -361.600324)
			(xy 456.601706 -361.392262) (xy 456.581752 -361.183288) (xy 456.569767 -360.973706) (xy 456.565771 -360.76382)
			(xy 369.870585 -360.76382) (xy 369.893819 -360.769894) (xy 369.945387 -360.791808) (xy 369.993215 -360.820997)
			(xy 370.036283 -360.856838) (xy 370.073673 -360.898568) (xy 370.104589 -360.945298) (xy 370.128372 -360.996031)
			(xy 370.144514 -361.049687) (xy 370.152673 -361.105121) (xy 370.153184 -361.133136) (xy 370.152673 -361.161151)
			(xy 370.144514 -361.216585) (xy 370.128372 -361.270241) (xy 370.104589 -361.320974) (xy 370.073673 -361.367704)
			(xy 370.036283 -361.409434) (xy 369.993215 -361.445275) (xy 369.945387 -361.474464) (xy 369.893819 -361.496378)
			(xy 369.83961 -361.51055) (xy 369.783915 -361.516678) (xy 369.727921 -361.514632) (xy 369.672823 -361.504455)
			(xy 369.619793 -361.486363) (xy 369.569962 -361.460744) (xy 369.524392 -361.428142) (xy 369.484056 -361.389252)
			(xy 369.449811 -361.344904) (xy 369.422388 -361.296042) (xy 369.402372 -361.243708) (xy 369.390189 -361.189018)
			(xy 369.3861 -361.133136) (xy 260.610619 -361.133136) (xy 260.589121 -361.258505) (xy 260.557188 -361.397123)
			(xy 260.517463 -361.533712) (xy 260.470075 -361.667835) (xy 260.415174 -361.799062) (xy 260.352937 -361.926973)
			(xy 260.283563 -362.051158) (xy 260.207274 -362.171219) (xy 260.124316 -362.286772) (xy 260.034952 -362.397446)
			(xy 259.939471 -362.502888) (xy 259.838177 -362.602758) (xy 259.731395 -362.696738) (xy 259.619467 -362.784526)
			(xy 259.502751 -362.865842) (xy 259.381623 -362.940424) (xy 259.256469 -363.008033) (xy 259.12769 -363.068454)
			(xy 258.995699 -363.121492) (xy 258.860919 -363.166978) (xy 258.723781 -363.204766) (xy 258.584726 -363.234735)
			(xy 258.444197 -363.256789) (xy 258.302646 -363.270857) (xy 258.160526 -363.276894) (xy 258.018291 -363.274881)
			(xy 257.876399 -363.264824) (xy 257.735303 -363.246756) (xy 257.595454 -363.220735) (xy 257.457302 -363.186843)
			(xy 257.321289 -363.145189) (xy 257.18785 -363.095907) (xy 257.057413 -363.039155) (xy 256.930396 -362.975114)
			(xy 256.807205 -362.90399) (xy 256.688236 -362.82601) (xy 256.573868 -362.741424) (xy 256.464469 -362.650504)
			(xy 256.36039 -362.55354) (xy 256.261962 -362.450843) (xy 256.169503 -362.342741) (xy 256.083307 -362.229582)
			(xy 256.003652 -362.111728) (xy 255.930791 -361.989556) (xy 255.86496 -361.863458) (xy 255.806367 -361.733837)
			(xy 255.755202 -361.601109) (xy 255.711628 -361.465699) (xy 255.675784 -361.32804) (xy 255.647786 -361.188574)
			(xy 255.627723 -361.047748) (xy 255.61566 -360.906012) (xy 255.611635 -360.76382) (xy 216.187782 -360.76382)
			(xy 216.187279 -360.834944) (xy 216.179231 -360.976965) (xy 216.163162 -361.118303) (xy 216.139121 -361.258505)
			(xy 216.107188 -361.397123) (xy 216.067463 -361.533712) (xy 216.020075 -361.667835) (xy 215.965174 -361.799062)
			(xy 215.902937 -361.926973) (xy 215.833563 -362.051158) (xy 215.757274 -362.171219) (xy 215.674316 -362.286772)
			(xy 215.584952 -362.397446) (xy 215.489471 -362.502888) (xy 215.388177 -362.602758) (xy 215.281395 -362.696738)
			(xy 215.169467 -362.784526) (xy 215.052751 -362.865842) (xy 214.931623 -362.940424) (xy 214.806469 -363.008033)
			(xy 214.67769 -363.068454) (xy 214.545699 -363.121492) (xy 214.410919 -363.166978) (xy 214.273781 -363.204766)
			(xy 214.134726 -363.234735) (xy 213.994197 -363.256789) (xy 213.852646 -363.270857) (xy 213.710526 -363.276894)
			(xy 213.568291 -363.274881) (xy 213.426399 -363.264824) (xy 213.285303 -363.246756) (xy 213.145454 -363.220735)
			(xy 213.007302 -363.186843) (xy 212.871289 -363.145189) (xy 212.73785 -363.095907) (xy 212.607413 -363.039155)
			(xy 212.480396 -362.975114) (xy 212.357205 -362.90399) (xy 212.238236 -362.82601) (xy 212.123868 -362.741424)
			(xy 212.014469 -362.650504) (xy 211.91039 -362.55354) (xy 211.811962 -362.450843) (xy 211.719503 -362.342741)
			(xy 211.633307 -362.229582) (xy 211.553652 -362.111728) (xy 211.480791 -361.989556) (xy 211.41496 -361.863458)
			(xy 211.356367 -361.733837) (xy 211.305202 -361.601109) (xy 211.261628 -361.465699) (xy 211.225784 -361.32804)
			(xy 211.197786 -361.188574) (xy 211.177723 -361.047748) (xy 211.16566 -360.906012) (xy 211.161635 -360.76382)
			(xy 121.930771 -360.76382) (xy 121.954005 -360.769894) (xy 122.005573 -360.791808) (xy 122.053401 -360.820997)
			(xy 122.096469 -360.856838) (xy 122.133859 -360.898568) (xy 122.164775 -360.945298) (xy 122.188558 -360.996031)
			(xy 122.2047 -361.049687) (xy 122.212859 -361.105121) (xy 122.21337 -361.133136) (xy 122.212859 -361.161151)
			(xy 122.2047 -361.216585) (xy 122.188558 -361.270241) (xy 122.164775 -361.320974) (xy 122.133859 -361.367704)
			(xy 122.096469 -361.409434) (xy 122.053401 -361.445275) (xy 122.005573 -361.474464) (xy 121.954005 -361.496378)
			(xy 121.899796 -361.51055) (xy 121.844101 -361.516678) (xy 121.788107 -361.514632) (xy 121.733009 -361.504455)
			(xy 121.679979 -361.486363) (xy 121.630148 -361.460744) (xy 121.584578 -361.428142) (xy 121.544242 -361.389252)
			(xy 121.509997 -361.344904) (xy 121.482574 -361.296042) (xy 121.462558 -361.243708) (xy 121.450375 -361.189018)
			(xy 121.446286 -361.133136) (xy 15.239789 -361.133136) (xy 15.227982 -361.28787) (xy 15.204052 -361.496426)
			(xy 15.1722 -361.703919) (xy 15.132472 -361.91005) (xy 15.084925 -362.114519) (xy 15.029628 -362.317029)
			(xy 14.966661 -362.517287) (xy 14.896116 -362.715003) (xy 14.818095 -362.90989) (xy 14.732711 -363.101665)
			(xy 14.640088 -363.290051) (xy 14.540361 -363.474774) (xy 14.433673 -363.655566) (xy 14.320179 -363.832166)
			(xy 14.200044 -364.004316) (xy 14.073443 -364.171769) (xy 13.940558 -364.33428) (xy 13.801583 -364.491614)
			(xy 13.656719 -364.643543) (xy 13.506176 -364.789847) (xy 13.350172 -364.930314) (xy 13.188933 -365.06474)
			(xy 13.022693 -365.192929) (xy 12.851694 -365.314697) (xy 12.676183 -365.429867) (xy 12.496415 -365.538271)
			(xy 12.31265 -365.639753) (xy 12.125154 -365.734165) (xy 11.934201 -365.821371) (xy 11.740065 -365.901244)
			(xy 11.54303 -365.973668) (xy 11.34338 -366.038538) (xy 11.141405 -366.09576) (xy 10.937399 -366.145252)
			(xy 10.731655 -366.186941) (xy 10.524474 -366.220766) (xy 10.316156 -366.24668) (xy 10.107002 -366.264645)
			(xy 9.897315 -366.274633) (xy 9.687401 -366.276632) (xy 9.477562 -366.270637) (xy 9.268104 -366.256658)
			(xy 9.059329 -366.234715) (xy 8.851542 -366.20484) (xy 8.645043 -366.167075) (xy 8.44013 -366.121477)
			(xy 8.237103 -366.06811) (xy 8.036254 -366.007053) (xy 7.837876 -365.938394) (xy 7.642255 -365.862231)
			(xy 7.449675 -365.778677) (xy 7.260417 -365.687852) (xy 7.074753 -365.589887) (xy 6.892953 -365.484925)
			(xy 6.715281 -365.373118) (xy 6.541995 -365.254627) (xy 6.373345 -365.129626) (xy 6.209576 -364.998294)
			(xy 6.050926 -364.860823) (xy 5.897624 -364.717412) (xy 5.749894 -364.568268) (xy 5.607948 -364.413608)
			(xy 5.471994 -364.253657) (xy 5.342227 -364.088645) (xy 5.218837 -363.918813) (xy 5.102002 -363.744406)
			(xy 4.991891 -363.565678) (xy 4.888664 -363.382887) (xy 4.792471 -363.196299) (xy 4.703452 -363.006184)
			(xy 4.621734 -362.812818) (xy 4.547438 -362.616481) (xy 4.48067 -362.417458) (xy 4.421528 -362.216037)
			(xy 4.370096 -362.012511) (xy 4.326451 -361.807174) (xy 4.290654 -361.600324) (xy 4.262758 -361.392262)
			(xy 4.242804 -361.183288) (xy 4.230819 -360.973706) (xy 4.226823 -360.76382) (xy 2.509012 -360.76382)
			(xy 2.509012 -383.932484) (xy 8.539215 -383.932484) (xy 8.539215 -383.803344) (xy 8.547165 -383.674449)
			(xy 8.563035 -383.546289) (xy 8.586764 -383.419348) (xy 8.618263 -383.294109) (xy 8.657412 -383.171046)
			(xy 8.704063 -383.050627) (xy 8.758038 -382.933308) (xy 8.819133 -382.819534) (xy 8.887116 -382.709737)
			(xy 8.96173 -382.604334) (xy 9.042691 -382.503724) (xy 9.129691 -382.408289) (xy 9.222402 -382.31839)
			(xy 9.320472 -382.234369) (xy 9.423527 -382.156545) (xy 9.531178 -382.085213) (xy 9.643017 -382.020643)
			(xy 9.758618 -381.963081) (xy 9.877543 -381.912744) (xy 9.999342 -381.869824) (xy 10.123552 -381.834483)
			(xy 10.249701 -381.806856) (xy 10.377313 -381.787047) (xy 10.505902 -381.775131) (xy 10.63498 -381.771155)
			(xy 10.764058 -381.775131) (xy 10.892647 -381.787047) (xy 11.020259 -381.806856) (xy 11.146408 -381.834483)
			(xy 11.270618 -381.869824) (xy 11.392417 -381.912744) (xy 11.511342 -381.963081) (xy 11.626943 -382.020643)
			(xy 11.738782 -382.085213) (xy 11.846433 -382.156545) (xy 11.949488 -382.234369) (xy 12.047558 -382.31839)
			(xy 12.140269 -382.408289) (xy 12.227269 -382.503724) (xy 12.30823 -382.604334) (xy 12.382844 -382.709737)
			(xy 12.450827 -382.819534) (xy 12.505341 -382.921052) (xy 19.016679 -382.921052) (xy 19.016679 -382.866548)
			(xy 19.024437 -382.812598) (xy 19.039793 -382.760301) (xy 19.062436 -382.710722) (xy 19.091904 -382.664871)
			(xy 19.127599 -382.62368) (xy 19.168792 -382.587989) (xy 19.214645 -382.558523) (xy 19.264226 -382.535884)
			(xy 19.316523 -382.520531) (xy 19.370474 -382.512778) (xy 19.397726 -382.512316) (xy 20.261326 -382.512316)
			(xy 20.288578 -382.512756) (xy 20.342526 -382.520516) (xy 20.394821 -382.535874) (xy 20.444398 -382.558518)
			(xy 20.490248 -382.587987) (xy 20.531438 -382.623681) (xy 20.567129 -382.664873) (xy 20.596594 -382.710725)
			(xy 20.619235 -382.760303) (xy 20.63459 -382.812599) (xy 20.642346 -382.866548) (xy 20.642346 -382.921052)
			(xy 20.636681 -382.960459) (xy 22.291788 -382.960459) (xy 22.291788 -382.905921) (xy 22.29955 -382.851938)
			(xy 22.314915 -382.79961) (xy 22.337571 -382.75) (xy 22.367056 -382.70412) (xy 22.40277 -382.662903)
			(xy 22.443987 -382.627188) (xy 22.489867 -382.597702) (xy 22.539476 -382.575046) (xy 22.591804 -382.559681)
			(xy 22.645787 -382.551919) (xy 22.673056 -382.551432) (xy 23.536656 -382.551432) (xy 23.563927 -382.551887)
			(xy 23.617915 -382.559649) (xy 23.670249 -382.575015) (xy 23.719863 -382.597673) (xy 23.765748 -382.62716)
			(xy 23.806969 -382.662878) (xy 23.842687 -382.704099) (xy 23.872175 -382.749983) (xy 23.894834 -382.799597)
			(xy 23.9102 -382.851931) (xy 23.917962 -382.905919) (xy 23.917962 -382.960461) (xy 23.9102 -383.014449)
			(xy 23.894834 -383.066783) (xy 23.872175 -383.116397) (xy 23.842687 -383.162281) (xy 23.806969 -383.203502)
			(xy 23.765748 -383.23922) (xy 23.719863 -383.268707) (xy 23.670249 -383.291365) (xy 23.617915 -383.306731)
			(xy 23.563927 -383.314493) (xy 23.536656 -383.314956) (xy 22.673056 -383.314956) (xy 22.645787 -383.314461)
			(xy 22.591804 -383.306699) (xy 22.539476 -383.291334) (xy 22.489867 -383.268678) (xy 22.443987 -383.239192)
			(xy 22.40277 -383.203477) (xy 22.367056 -383.16226) (xy 22.337571 -383.11638) (xy 22.314915 -383.06677)
			(xy 22.29955 -383.014442) (xy 22.291788 -382.960459) (xy 20.636681 -382.960459) (xy 20.63459 -382.975001)
			(xy 20.619235 -383.027297) (xy 20.596594 -383.076875) (xy 20.567129 -383.122727) (xy 20.531438 -383.163919)
			(xy 20.490248 -383.199613) (xy 20.444398 -383.229082) (xy 20.394821 -383.251726) (xy 20.342526 -383.267084)
			(xy 20.288578 -383.274844) (xy 20.261326 -383.275332) (xy 19.397726 -383.275332) (xy 19.370474 -383.274822)
			(xy 19.316523 -383.267069) (xy 19.264226 -383.251716) (xy 19.214645 -383.229077) (xy 19.168792 -383.199611)
			(xy 19.127599 -383.16392) (xy 19.091904 -383.122729) (xy 19.062436 -383.076878) (xy 19.039793 -383.027299)
			(xy 19.024437 -382.975002) (xy 19.016679 -382.921052) (xy 12.505341 -382.921052) (xy 12.511922 -382.933308)
			(xy 12.565897 -383.050627) (xy 12.612548 -383.171046) (xy 12.651697 -383.294109) (xy 12.683196 -383.419348)
			(xy 12.706925 -383.546289) (xy 12.722795 -383.674449) (xy 12.730745 -383.803344) (xy 12.731242 -383.867914)
			(xy 12.730745 -383.932484) (xy 12.722795 -384.061379) (xy 12.706925 -384.189539) (xy 12.683196 -384.31648)
			(xy 12.651697 -384.441719) (xy 12.612548 -384.564782) (xy 12.565897 -384.685201) (xy 12.511922 -384.80252)
			(xy 12.450827 -384.916294) (xy 12.382844 -385.026091) (xy 12.30823 -385.131494) (xy 12.227269 -385.232104)
			(xy 12.140269 -385.327539) (xy 12.047558 -385.417438) (xy 11.949488 -385.501459) (xy 11.846433 -385.579283)
			(xy 11.738782 -385.650615) (xy 11.626943 -385.715185) (xy 11.511342 -385.772747) (xy 11.392417 -385.823084)
			(xy 11.270618 -385.866004) (xy 11.146408 -385.901345) (xy 11.020259 -385.928972) (xy 10.892647 -385.948781)
			(xy 10.764058 -385.960697) (xy 10.63498 -385.964674) (xy 10.505902 -385.960697) (xy 10.377313 -385.948781)
			(xy 10.249701 -385.928972) (xy 10.123552 -385.901345) (xy 9.999342 -385.866004) (xy 9.877543 -385.823084)
			(xy 9.758618 -385.772747) (xy 9.643017 -385.715185) (xy 9.531178 -385.650615) (xy 9.423527 -385.579283)
			(xy 9.320472 -385.501459) (xy 9.222402 -385.417438) (xy 9.129691 -385.327539) (xy 9.042691 -385.232104)
			(xy 8.96173 -385.131494) (xy 8.887116 -385.026091) (xy 8.819133 -384.916294) (xy 8.758038 -384.80252)
			(xy 8.704063 -384.685201) (xy 8.657412 -384.564782) (xy 8.618263 -384.441719) (xy 8.586764 -384.31648)
			(xy 8.563035 -384.189539) (xy 8.547165 -384.061379) (xy 8.539215 -383.932484) (xy 2.509012 -383.932484)
			(xy 2.509012 -386.402834) (xy 18.947892 -386.402834) (xy 18.947892 -385.333494) (xy 18.948146 -385.329684)
			(xy 18.9484 -385.32816) (xy 18.9484 -384.676396) (xy 18.947892 -384.676396) (xy 18.947892 -384.533394)
			(xy 18.94853 -384.520997) (xy 18.955194 -384.497091) (xy 18.967498 -384.475539) (xy 18.975832 -384.466338)
			(xy 18.985506 -384.456943) (xy 19.008717 -384.443238) (xy 19.034742 -384.436215) (xy 19.048222 -384.435858)
			(xy 19.048222 -384.436112) (xy 19.355054 -384.436112) (xy 19.368779 -384.437187) (xy 19.394846 -384.446019)
			(xy 19.417495 -384.461657) (xy 19.434991 -384.482903) (xy 19.445994 -384.508131) (xy 19.448272 -384.52171)
			(xy 19.449288 -384.528314) (xy 19.449288 -384.535426) (xy 19.449797 -384.549528) (xy 19.457521 -384.576653)
			(xy 19.472373 -384.60063) (xy 19.493218 -384.619627) (xy 19.518467 -384.632196) (xy 19.54619 -384.637377)
			(xy 19.574274 -384.634773) (xy 19.600573 -384.624585) (xy 19.612102 -384.616452) (xy 19.637121 -384.598258)
			(xy 19.691838 -384.5694) (xy 19.750493 -384.549747) (xy 19.81155 -384.539813) (xy 19.84248 -384.539236)
			(xy 19.873319 -384.539844) (xy 19.934199 -384.549733) (xy 19.992705 -384.569259) (xy 20.047321 -384.597917)
			(xy 20.07235 -384.615944) (xy 20.083892 -384.624066) (xy 20.110193 -384.634266) (xy 20.138282 -384.636879)
			(xy 20.166014 -384.631703) (xy 20.19127 -384.619136) (xy 20.212123 -384.600136) (xy 20.226979 -384.576155)
			(xy 20.234704 -384.549023) (xy 20.235164 -384.534918) (xy 20.235164 -384.534664) (xy 20.235799 -384.522286)
			(xy 20.242363 -384.498392) (xy 20.254565 -384.476827) (xy 20.26285 -384.467608) (xy 20.272527 -384.458216)
			(xy 20.295735 -384.444507) (xy 20.32176 -384.437484) (xy 20.33524 -384.437128) (xy 20.642072 -384.437128)
			(xy 20.655808 -384.438297) (xy 20.681899 -384.447151) (xy 20.70456 -384.462824) (xy 20.722052 -384.484112)
			(xy 20.733031 -384.509383) (xy 20.73529 -384.52298) (xy 20.736052 -384.529584) (xy 20.736052 -386.315458)
			(xy 22.20976 -386.315458) (xy 22.20976 -384.446018) (xy 22.210371 -384.433637) (xy 22.216945 -384.409744)
			(xy 22.229157 -384.388179) (xy 22.237446 -384.378962) (xy 22.247117 -384.369564) (xy 22.270329 -384.355859)
			(xy 22.296355 -384.348838) (xy 22.309836 -384.348482) (xy 22.309836 -384.348736) (xy 22.616668 -384.348736)
			(xy 22.630389 -384.34986) (xy 22.656456 -384.358674) (xy 22.679108 -384.374298) (xy 22.696606 -384.395536)
			(xy 22.707609 -384.420758) (xy 22.709886 -384.434334) (xy 22.710648 -384.440938) (xy 22.710648 -384.5687)
			(xy 22.711199 -384.582977) (xy 22.719132 -384.610407) (xy 22.734349 -384.634569) (xy 22.755662 -384.653572)
			(xy 22.781403 -384.665932) (xy 22.809559 -384.670682) (xy 22.83793 -384.66745) (xy 22.864297 -384.656489)
			(xy 22.875748 -384.647948) (xy 22.896085 -384.632255) (xy 22.940171 -384.60589) (xy 22.987397 -384.58568)
			(xy 23.036908 -384.571991) (xy 23.087808 -384.565069) (xy 23.113492 -384.564636) (xy 23.139482 -384.565093)
			(xy 23.190983 -384.572133) (xy 23.241052 -384.586099) (xy 23.288762 -384.606731) (xy 23.333231 -384.633648)
			(xy 23.373634 -384.666351) (xy 23.409225 -384.704236) (xy 23.424642 -384.725164) (xy 23.439628 -384.7465)
			(xy 23.516844 -384.7465) (xy 23.516844 -384.58902) (xy 23.516336 -384.58902) (xy 23.516336 -384.446018)
			(xy 23.517002 -384.433624) (xy 23.523656 -384.40972) (xy 23.535948 -384.388166) (xy 23.544276 -384.378962)
			(xy 23.553935 -384.36955) (xy 23.577153 -384.355849) (xy 23.603184 -384.348834) (xy 23.616666 -384.348482)
			(xy 23.616666 -384.348736) (xy 23.923498 -384.348736) (xy 23.937221 -384.349836) (xy 23.96329 -384.358657)
			(xy 23.985941 -384.374288) (xy 24.003438 -384.39553) (xy 24.01444 -384.420756) (xy 24.016716 -384.434334)
			(xy 24.017732 -384.440938) (xy 24.017732 -385.440249) (xy 36.585674 -385.440249) (xy 36.585674 -385.385751)
			(xy 36.593429 -385.331807) (xy 36.608782 -385.279515) (xy 36.63142 -385.229941) (xy 36.660882 -385.184092)
			(xy 36.696569 -385.142903) (xy 36.737753 -385.107211) (xy 36.783598 -385.077743) (xy 36.83317 -385.055099)
			(xy 36.88546 -385.039739) (xy 36.939403 -385.031977) (xy 36.966652 -385.031488) (xy 37.830252 -385.031488)
			(xy 37.857507 -385.031956) (xy 37.911462 -385.039707) (xy 37.963765 -385.055059) (xy 38.013351 -385.077699)
			(xy 38.05921 -385.107165) (xy 38.100408 -385.142858) (xy 38.136106 -385.184052) (xy 38.165578 -385.229907)
			(xy 38.188224 -385.27949) (xy 38.203582 -385.331791) (xy 38.211341 -385.385745) (xy 38.211341 -385.440255)
			(xy 38.203582 -385.494209) (xy 38.188224 -385.54651) (xy 38.165578 -385.596093) (xy 38.16123 -385.602858)
			(xy 41.455211 -385.602858) (xy 41.455211 -385.548342) (xy 41.46297 -385.494381) (xy 41.47833 -385.442074)
			(xy 41.500978 -385.392486) (xy 41.530453 -385.346625) (xy 41.566155 -385.305427) (xy 41.607357 -385.269729)
			(xy 41.653221 -385.240259) (xy 41.702812 -385.217616) (xy 41.755121 -385.202261) (xy 41.809082 -385.194508)
			(xy 41.83634 -385.194048) (xy 42.69994 -385.194048) (xy 42.727186 -385.194625) (xy 42.781123 -385.202385)
			(xy 42.833407 -385.217742) (xy 42.882974 -385.240383) (xy 42.928814 -385.269847) (xy 42.969994 -385.305534)
			(xy 43.005677 -385.346718) (xy 43.035136 -385.392562) (xy 43.057772 -385.44213) (xy 43.073123 -385.494416)
			(xy 43.080878 -385.548354) (xy 43.080878 -385.602846) (xy 43.073123 -385.656784) (xy 43.057772 -385.70907)
			(xy 43.035136 -385.758638) (xy 43.005677 -385.804482) (xy 42.969994 -385.845666) (xy 42.928814 -385.881353)
			(xy 42.882974 -385.910817) (xy 42.833407 -385.933458) (xy 42.781123 -385.948815) (xy 42.727186 -385.956575)
			(xy 42.69994 -385.957064) (xy 41.83634 -385.957064) (xy 41.809082 -385.956692) (xy 41.755121 -385.948939)
			(xy 41.702812 -385.933584) (xy 41.653221 -385.910941) (xy 41.607357 -385.881471) (xy 41.566155 -385.845773)
			(xy 41.530453 -385.804575) (xy 41.500978 -385.758714) (xy 41.47833 -385.709126) (xy 41.46297 -385.656819)
			(xy 41.455211 -385.602858) (xy 38.16123 -385.602858) (xy 38.136106 -385.641948) (xy 38.100408 -385.683142)
			(xy 38.05921 -385.718835) (xy 38.013351 -385.748301) (xy 37.963765 -385.770941) (xy 37.911462 -385.786293)
			(xy 37.857507 -385.794044) (xy 37.830252 -385.794504) (xy 36.966652 -385.794504) (xy 36.939403 -385.794023)
			(xy 36.88546 -385.786261) (xy 36.83317 -385.770901) (xy 36.783598 -385.748257) (xy 36.737753 -385.718789)
			(xy 36.696569 -385.683097) (xy 36.660882 -385.641908) (xy 36.63142 -385.596059) (xy 36.608782 -385.546485)
			(xy 36.593429 -385.494193) (xy 36.585674 -385.440249) (xy 24.017732 -385.440249) (xy 24.017732 -385.510278)
			(xy 24.017478 -385.514088) (xy 24.017224 -385.515612) (xy 24.017224 -386.167376) (xy 24.017732 -386.167376)
			(xy 24.017732 -386.310378) (xy 24.017073 -386.322773) (xy 24.010417 -386.346677) (xy 23.998122 -386.368231)
			(xy 23.989792 -386.377434) (xy 23.980104 -386.386813) (xy 23.9569 -386.400524) (xy 23.93088 -386.407553)
			(xy 23.917402 -386.407914) (xy 23.917402 -386.40766) (xy 23.61057 -386.40766) (xy 23.596844 -386.406589)
			(xy 23.570774 -386.39776) (xy 23.548123 -386.382121) (xy 23.530628 -386.360873) (xy 23.519628 -386.335642)
			(xy 23.517352 -386.322062) (xy 23.516336 -386.315458) (xy 23.516336 -386.187696) (xy 23.515792 -386.173434)
			(xy 23.507899 -386.146024) (xy 23.492732 -386.121867) (xy 23.471473 -386.102848) (xy 23.445783 -386.090454)
			(xy 23.417667 -386.08565) (xy 23.389319 -386.088812) (xy 23.362952 -386.099693) (xy 23.35149 -386.108194)
			(xy 23.331159 -386.123953) (xy 23.287037 -386.1504) (xy 23.239759 -386.170671) (xy 23.190184 -386.184398)
			(xy 23.139212 -386.191331) (xy 23.113492 -386.19176) (xy 23.08753 -386.191325) (xy 23.036085 -386.184274)
			(xy 22.986071 -386.170318) (xy 22.938409 -386.149713) (xy 22.893979 -386.12284) (xy 22.8536 -386.090194)
			(xy 22.818017 -386.052377) (xy 22.802596 -386.031486) (xy 22.78761 -386.01015) (xy 22.710648 -386.01015)
			(xy 22.710648 -386.310378) (xy 22.710033 -386.322758) (xy 22.70346 -386.346652) (xy 22.69125 -386.368216)
			(xy 22.682962 -386.377434) (xy 22.673287 -386.386827) (xy 22.650077 -386.400534) (xy 22.624052 -386.407557)
			(xy 22.610572 -386.407914) (xy 22.610572 -386.40766) (xy 22.30374 -386.40766) (xy 22.290011 -386.406614)
			(xy 22.26394 -386.397777) (xy 22.24129 -386.382132) (xy 22.223796 -386.360879) (xy 22.212797 -386.335644)
			(xy 22.210522 -386.322062) (xy 22.20976 -386.315458) (xy 20.736052 -386.315458) (xy 20.736052 -386.399024)
			(xy 20.735407 -386.411401) (xy 20.728847 -386.435294) (xy 20.716649 -386.45686) (xy 20.708366 -386.46608)
			(xy 20.698681 -386.475463) (xy 20.675477 -386.489175) (xy 20.649455 -386.496202) (xy 20.635976 -386.49656)
			(xy 20.329144 -386.49656) (xy 20.315409 -386.495388) (xy 20.289316 -386.486537) (xy 20.266654 -386.470865)
			(xy 20.249163 -386.449577) (xy 20.238184 -386.424306) (xy 20.235926 -386.410708) (xy 20.235164 -386.404104)
			(xy 20.235164 -386.17017) (xy 20.234735 -386.156062) (xy 20.227005 -386.128925) (xy 20.212143 -386.104939)
			(xy 20.191285 -386.085936) (xy 20.166023 -386.073366) (xy 20.138285 -386.06819) (xy 20.11019 -386.070802)
			(xy 20.083881 -386.081003) (xy 20.07235 -386.089144) (xy 20.047342 -386.10721) (xy 19.992741 -386.135924)
			(xy 19.934225 -386.155459) (xy 19.873326 -386.165305) (xy 19.84248 -386.165852) (xy 19.81151 -386.165246)
			(xy 19.75038 -386.155262) (xy 19.691663 -386.135541) (xy 19.636899 -386.106602) (xy 19.611848 -386.088382)
			(xy 19.600316 -386.080214) (xy 19.573983 -386.06999) (xy 19.545857 -386.067362) (xy 19.518085 -386.072531)
			(xy 19.492788 -386.085102) (xy 19.471896 -386.104116) (xy 19.457005 -386.128121) (xy 19.44925 -386.155284)
			(xy 19.44878 -386.169408) (xy 19.44878 -386.254752) (xy 19.449288 -386.254752) (xy 19.449288 -386.397754)
			(xy 19.448601 -386.410146) (xy 19.441955 -386.434049) (xy 19.429671 -386.455605) (xy 19.421348 -386.46481)
			(xy 19.411675 -386.474206) (xy 19.388464 -386.487913) (xy 19.362439 -386.494934) (xy 19.348958 -386.49529)
			(xy 19.348958 -386.495036) (xy 19.042126 -386.495036) (xy 19.028413 -386.493856) (xy 19.002354 -386.485049)
			(xy 18.979707 -386.469436) (xy 18.962206 -386.448214) (xy 18.951193 -386.423008) (xy 18.948908 -386.409438)
			(xy 18.947892 -386.402834) (xy 2.509012 -386.402834) (xy 2.509012 -389.402275) (xy 286.566098 -389.402275)
			(xy 286.566098 -389.317529) (xy 286.574154 -389.233168) (xy 286.590192 -389.149954) (xy 286.614067 -389.068641)
			(xy 286.645564 -388.989966) (xy 286.684397 -388.914642) (xy 286.730213 -388.843349) (xy 286.7826 -388.776735)
			(xy 286.84108 -388.715402) (xy 286.905127 -388.659906) (xy 286.974158 -388.610748) (xy 287.04755 -388.568376)
			(xy 287.124637 -388.533171) (xy 287.204721 -388.505454) (xy 287.287078 -388.485474) (xy 287.370961 -388.473414)
			(xy 287.45561 -388.469382) (xy 287.540259 -388.473414) (xy 287.624142 -388.485474) (xy 287.706499 -388.505454)
			(xy 287.786583 -388.533171) (xy 287.86367 -388.568376) (xy 287.937062 -388.610748) (xy 288.006093 -388.659906)
			(xy 288.07014 -388.715402) (xy 288.12862 -388.776735) (xy 288.181007 -388.843349) (xy 288.226823 -388.914642)
			(xy 288.265656 -388.989966) (xy 288.297153 -389.068641) (xy 288.321028 -389.149954) (xy 288.337066 -389.233168)
			(xy 288.345122 -389.317529) (xy 288.345626 -389.359902) (xy 288.345122 -389.402275) (xy 297.615098 -389.402275)
			(xy 297.615098 -389.317529) (xy 297.623154 -389.233168) (xy 297.639192 -389.149954) (xy 297.663067 -389.068641)
			(xy 297.694564 -388.989966) (xy 297.733397 -388.914642) (xy 297.779213 -388.843349) (xy 297.8316 -388.776735)
			(xy 297.89008 -388.715402) (xy 297.954127 -388.659906) (xy 298.023158 -388.610748) (xy 298.09655 -388.568376)
			(xy 298.173637 -388.533171) (xy 298.253721 -388.505454) (xy 298.336078 -388.485474) (xy 298.419961 -388.473414)
			(xy 298.50461 -388.469382) (xy 298.589259 -388.473414) (xy 298.673142 -388.485474) (xy 298.755499 -388.505454)
			(xy 298.835583 -388.533171) (xy 298.91267 -388.568376) (xy 298.986062 -388.610748) (xy 299.055093 -388.659906)
			(xy 299.11914 -388.715402) (xy 299.17762 -388.776735) (xy 299.230007 -388.843349) (xy 299.275823 -388.914642)
			(xy 299.314656 -388.989966) (xy 299.346153 -389.068641) (xy 299.370028 -389.149954) (xy 299.386066 -389.233168)
			(xy 299.394122 -389.317529) (xy 299.394626 -389.359902) (xy 299.394122 -389.402275) (xy 299.386066 -389.486636)
			(xy 299.370028 -389.56985) (xy 299.346153 -389.651163) (xy 299.314656 -389.729838) (xy 299.275823 -389.805162)
			(xy 299.230007 -389.876455) (xy 299.17762 -389.943069) (xy 299.11914 -390.004402) (xy 299.055093 -390.059898)
			(xy 298.986062 -390.109056) (xy 298.91267 -390.151428) (xy 298.835583 -390.186633) (xy 298.755499 -390.21435)
			(xy 298.673142 -390.23433) (xy 298.589259 -390.24639) (xy 298.50461 -390.250423) (xy 298.419961 -390.24639)
			(xy 298.336078 -390.23433) (xy 298.253721 -390.21435) (xy 298.173637 -390.186633) (xy 298.09655 -390.151428)
			(xy 298.023158 -390.109056) (xy 297.954127 -390.059898) (xy 297.89008 -390.004402) (xy 297.8316 -389.943069)
			(xy 297.779213 -389.876455) (xy 297.733397 -389.805162) (xy 297.694564 -389.729838) (xy 297.663067 -389.651163)
			(xy 297.639192 -389.56985) (xy 297.623154 -389.486636) (xy 297.615098 -389.402275) (xy 288.345122 -389.402275)
			(xy 288.337066 -389.486636) (xy 288.321028 -389.56985) (xy 288.297153 -389.651163) (xy 288.265656 -389.729838)
			(xy 288.226823 -389.805162) (xy 288.181007 -389.876455) (xy 288.12862 -389.943069) (xy 288.07014 -390.004402)
			(xy 288.006093 -390.059898) (xy 287.937062 -390.109056) (xy 287.86367 -390.151428) (xy 287.786583 -390.186633)
			(xy 287.706499 -390.21435) (xy 287.624142 -390.23433) (xy 287.540259 -390.24639) (xy 287.45561 -390.250423)
			(xy 287.370961 -390.24639) (xy 287.287078 -390.23433) (xy 287.204721 -390.21435) (xy 287.124637 -390.186633)
			(xy 287.04755 -390.151428) (xy 286.974158 -390.109056) (xy 286.905127 -390.059898) (xy 286.84108 -390.004402)
			(xy 286.7826 -389.943069) (xy 286.730213 -389.876455) (xy 286.684397 -389.805162) (xy 286.645564 -389.729838)
			(xy 286.614067 -389.651163) (xy 286.590192 -389.56985) (xy 286.574154 -389.486636) (xy 286.566098 -389.402275)
			(xy 2.509012 -389.402275) (xy 2.509012 -390.74852) (xy 289.828732 -390.74852) (xy 289.829157 -390.717787)
			(xy 289.836564 -390.656768) (xy 289.851272 -390.597088) (xy 289.873068 -390.539615) (xy 289.901633 -390.485189)
			(xy 289.93655 -390.434604) (xy 289.97731 -390.388596) (xy 290.023319 -390.347837) (xy 290.073907 -390.312922)
			(xy 290.128334 -390.28436) (xy 290.185807 -390.262566) (xy 290.245488 -390.24786) (xy 290.306507 -390.240455)
			(xy 290.33724 -390.240012) (xy 290.369283 -390.240508) (xy 290.432859 -390.248584) (xy 290.494917 -390.264579)
			(xy 290.554476 -390.288239) (xy 290.610594 -390.31919) (xy 290.662381 -390.356941) (xy 290.709019 -390.400896)
			(xy 290.749768 -390.450359) (xy 290.783985 -390.504546) (xy 290.811128 -390.562601) (xy 290.830767 -390.623604)
			(xy 290.842591 -390.686591) (xy 290.844986 -390.718548) (xy 290.846452 -390.733661) (xy 290.857061 -390.762093)
			(xy 290.875562 -390.786147) (xy 290.900318 -390.803698) (xy 290.929141 -390.813192) (xy 290.9443 -390.814052)
			(xy 290.977155 -390.815239) (xy 291.042167 -390.825028) (xy 291.105376 -390.843112) (xy 291.165728 -390.86919)
			(xy 291.222216 -390.902827) (xy 291.2739 -390.943462) (xy 291.319917 -390.990417) (xy 291.359501 -391.04291)
			(xy 291.391992 -391.100065) (xy 291.416847 -391.160931) (xy 291.433653 -391.224491) (xy 291.442129 -391.289688)
			(xy 291.442648 -391.32256) (xy 291.442106 -391.353289) (xy 291.434703 -391.414298) (xy 291.42 -391.473971)
			(xy 291.398212 -391.531436) (xy 291.369656 -391.585856) (xy 291.334748 -391.636437) (xy 291.293998 -391.682441)
			(xy 291.248 -391.723199) (xy 291.197424 -391.758114) (xy 291.143009 -391.786679) (xy 291.085547 -391.808477)
			(xy 291.025877 -391.823189) (xy 290.964869 -391.830602) (xy 290.93414 -391.831068) (xy 290.902098 -391.830516)
			(xy 290.838523 -391.822449) (xy 290.776465 -391.806463) (xy 290.716905 -391.78281) (xy 290.660787 -391.751866)
			(xy 290.608999 -391.71412) (xy 290.56236 -391.670169) (xy 290.521609 -391.620711) (xy 290.487392 -391.566526)
			(xy 290.460249 -391.508474) (xy 290.440611 -391.447473) (xy 290.428788 -391.384488) (xy 290.426394 -391.352532)
			(xy 290.424962 -391.337414) (xy 290.414346 -391.308979) (xy 290.395837 -391.284924) (xy 290.371072 -391.267376)
			(xy 290.342242 -391.257886) (xy 290.32708 -391.257028) (xy 290.294229 -391.25578) (xy 290.229223 -391.24599)
			(xy 290.166019 -391.227907) (xy 290.105673 -391.201832) (xy 290.049188 -391.1682) (xy 289.997507 -391.127571)
			(xy 289.95149 -391.080623) (xy 289.911906 -391.028137) (xy 289.879413 -390.97099) (xy 289.854553 -390.910132)
			(xy 289.837741 -390.846579) (xy 289.829256 -390.78139) (xy 289.828732 -390.74852) (xy 2.509012 -390.74852)
			(xy 2.509012 -394.8085) (xy 243.179528 -394.8085) (xy 243.183558 -394.723892) (xy 243.195613 -394.640051)
			(xy 243.215583 -394.557735) (xy 243.243287 -394.47769) (xy 243.278475 -394.400641) (xy 243.320827 -394.327286)
			(xy 243.36996 -394.258289) (xy 243.42543 -394.194274) (xy 243.486733 -394.135823) (xy 243.553315 -394.083463)
			(xy 243.624573 -394.03767) (xy 243.699861 -393.998857) (xy 243.778498 -393.967377) (xy 243.859771 -393.943515)
			(xy 243.942944 -393.927486) (xy 244.027264 -393.919435) (xy 244.069616 -393.918948) (xy 244.11084 -393.919417)
			(xy 244.192933 -393.927053) (xy 244.273968 -393.94225) (xy 244.35325 -393.964876) (xy 244.430099 -393.994739)
			(xy 244.503857 -394.031582) (xy 244.573891 -394.075088) (xy 244.639601 -394.124886) (xy 244.670326 -394.152374)
			(xy 244.677558 -394.158461) (xy 244.695171 -394.165287) (xy 244.714061 -394.165287) (xy 244.731674 -394.158461)
			(xy 244.738906 -394.152374) (xy 244.769639 -394.124894) (xy 244.835341 -394.075085) (xy 244.905371 -394.03157)
			(xy 244.979128 -393.994723) (xy 245.055977 -393.964858) (xy 245.13526 -393.942233) (xy 245.216297 -393.927041)
			(xy 245.298392 -393.919413) (xy 245.339616 -393.918948) (xy 245.380184 -393.919416) (xy 245.460981 -393.926807)
			(xy 245.54077 -393.941524) (xy 245.618888 -393.963447) (xy 245.694684 -393.992392) (xy 245.767529 -394.02812)
			(xy 245.836818 -394.070333) (xy 245.901975 -394.118681) (xy 245.962458 -394.172761) (xy 246.017765 -394.232125)
			(xy 246.067436 -394.296278) (xy 246.111059 -394.364689) (xy 246.130064 -394.400532) (xy 246.157157 -394.401367)
			(xy 246.21073 -394.409598) (xy 246.262601 -394.42532) (xy 246.31173 -394.448214) (xy 246.357129 -394.477824)
			(xy 246.397887 -394.513553) (xy 246.433186 -394.554684) (xy 246.462317 -394.600391) (xy 246.484695 -394.649758)
			(xy 246.499871 -394.701791) (xy 246.507539 -394.755447) (xy 246.508016 -394.782548) (xy 246.507582 -394.8085)
			(xy 249.114543 -394.8085) (xy 249.118574 -394.723896) (xy 249.130628 -394.640058) (xy 249.150596 -394.557746)
			(xy 249.178298 -394.477704) (xy 249.213483 -394.400658) (xy 249.255833 -394.327305) (xy 249.304963 -394.25831)
			(xy 249.360429 -394.194298) (xy 249.421729 -394.135847) (xy 249.488307 -394.083488) (xy 249.55956 -394.037695)
			(xy 249.634844 -393.998882) (xy 249.713476 -393.967401) (xy 249.794745 -393.943537) (xy 249.877914 -393.927506)
			(xy 249.96223 -393.919453) (xy 250.00458 -393.918948) (xy 250.045803 -393.919439) (xy 250.127896 -393.927072)
			(xy 250.20893 -393.942266) (xy 250.288212 -393.964889) (xy 250.365061 -393.994749) (xy 250.438819 -394.031588)
			(xy 250.508854 -394.075092) (xy 250.574564 -394.124887) (xy 250.60529 -394.152374) (xy 250.612522 -394.158461)
			(xy 250.630135 -394.165287) (xy 250.649025 -394.165287) (xy 250.666638 -394.158461) (xy 250.67387 -394.152374)
			(xy 250.704576 -394.124863) (xy 250.770283 -394.075057) (xy 250.840317 -394.031545) (xy 250.914078 -393.994701)
			(xy 250.990931 -393.96484) (xy 251.070218 -393.942219) (xy 251.151257 -393.927032) (xy 251.233355 -393.91941)
			(xy 251.27458 -393.918948) (xy 251.315219 -393.919386) (xy 251.396157 -393.926808) (xy 251.47608 -393.941582)
			(xy 251.554323 -393.963585) (xy 251.630232 -393.992634) (xy 251.703174 -394.028487) (xy 251.772542 -394.070844)
			(xy 251.837756 -394.119353) (xy 251.898274 -394.173608) (xy 251.95359 -394.233158) (xy 252.003243 -394.297505)
			(xy 252.046819 -394.366114) (xy 252.06579 -394.402056) (xy 252.086364 -394.401548) (xy 252.113582 -394.401996)
			(xy 252.167464 -394.409739) (xy 252.219695 -394.425073) (xy 252.269213 -394.447684) (xy 252.315007 -394.477114)
			(xy 252.356147 -394.512762) (xy 252.391793 -394.553902) (xy 252.421221 -394.599698) (xy 252.443832 -394.649216)
			(xy 252.459163 -394.701448) (xy 252.466905 -394.75533) (xy 252.467364 -394.782548) (xy 252.466916 -394.8085)
			(xy 255.049428 -394.8085) (xy 255.053459 -394.723891) (xy 255.065514 -394.640048) (xy 255.085484 -394.55773)
			(xy 255.11319 -394.477684) (xy 255.148379 -394.400634) (xy 255.190732 -394.327277) (xy 255.239868 -394.258279)
			(xy 255.295339 -394.194265) (xy 255.356645 -394.135813) (xy 255.423229 -394.083453) (xy 255.494489 -394.03766)
			(xy 255.56978 -393.998849) (xy 255.648419 -393.96737) (xy 255.729694 -393.943509) (xy 255.812869 -393.927482)
			(xy 255.897191 -393.919434) (xy 255.939544 -393.918948) (xy 255.980768 -393.919399) (xy 256.062862 -393.927038)
			(xy 256.143897 -393.942237) (xy 256.223179 -393.964866) (xy 256.300029 -393.994731) (xy 256.373786 -394.031576)
			(xy 256.44382 -394.075085) (xy 256.509529 -394.124885) (xy 256.540254 -394.152374) (xy 256.547486 -394.158461)
			(xy 256.565099 -394.165287) (xy 256.583989 -394.165287) (xy 256.601602 -394.158461) (xy 256.608834 -394.152374)
			(xy 256.639555 -394.12488) (xy 256.70526 -394.075073) (xy 256.775292 -394.031559) (xy 256.849049 -393.994713)
			(xy 256.925901 -393.96485) (xy 257.005185 -393.942227) (xy 257.086223 -393.927037) (xy 257.168319 -393.919412)
			(xy 257.209544 -393.918948) (xy 257.250365 -393.919407) (xy 257.331665 -393.926876) (xy 257.411938 -393.941765)
			(xy 257.490509 -393.963948) (xy 257.566715 -393.993239) (xy 257.639917 -394.029392) (xy 257.709496 -394.072102)
			(xy 257.774868 -394.121009) (xy 257.835483 -394.175702) (xy 257.890829 -394.235721) (xy 257.940442 -394.300559)
			(xy 257.983902 -394.369672) (xy 258.002786 -394.405866) (xy 258.01873 -394.403337) (xy 258.050905 -394.400664)
			(xy 258.067048 -394.400532) (xy 258.094337 -394.400926) (xy 258.148358 -394.408699) (xy 258.200723 -394.424081)
			(xy 258.250366 -394.446758) (xy 258.296278 -394.476268) (xy 258.337522 -394.512012) (xy 258.37326 -394.553261)
			(xy 258.402765 -394.599176) (xy 258.425436 -394.648822) (xy 258.440811 -394.701189) (xy 258.448577 -394.755211)
			(xy 258.448577 -394.8085) (xy 260.984428 -394.8085) (xy 260.988458 -394.723893) (xy 261.000513 -394.640052)
			(xy 261.020483 -394.557736) (xy 261.048186 -394.477692) (xy 261.083374 -394.400643) (xy 261.125725 -394.327288)
			(xy 261.174858 -394.258291) (xy 261.230327 -394.194277) (xy 261.29163 -394.135826) (xy 261.358212 -394.083466)
			(xy 261.429469 -394.037672) (xy 261.504756 -393.99886) (xy 261.583392 -393.967379) (xy 261.664664 -393.943516)
			(xy 261.747837 -393.927487) (xy 261.832156 -393.919436) (xy 261.874508 -393.918948) (xy 261.915732 -393.919422)
			(xy 261.997825 -393.927057) (xy 262.078859 -393.942253) (xy 262.158141 -393.964879) (xy 262.234991 -393.994741)
			(xy 262.308749 -394.031583) (xy 262.378783 -394.075089) (xy 262.444493 -394.124886) (xy 262.475218 -394.152374)
			(xy 262.48245 -394.158461) (xy 262.500063 -394.165287) (xy 262.518953 -394.165287) (xy 262.536566 -394.158461)
			(xy 262.543798 -394.152374) (xy 262.574534 -394.124897) (xy 262.640236 -394.075089) (xy 262.710266 -394.031574)
			(xy 262.784021 -393.994725) (xy 262.86087 -393.96486) (xy 262.940153 -393.942234) (xy 263.021189 -393.927042)
			(xy 263.103284 -393.919413) (xy 263.144508 -393.918948) (xy 263.185239 -393.919443) (xy 263.26636 -393.9269)
			(xy 263.346458 -393.941743) (xy 263.424865 -393.963847) (xy 263.500922 -393.993026) (xy 263.573993 -394.029037)
			(xy 263.643465 -394.071577) (xy 263.708758 -394.120291) (xy 263.769323 -394.174771) (xy 263.824654 -394.234559)
			(xy 263.874287 -394.299155) (xy 263.917806 -394.368019) (xy 263.936734 -394.404088) (xy 263.947933 -394.402872)
			(xy 263.970427 -394.401601) (xy 263.981692 -394.401548) (xy 264.008912 -394.401914) (xy 264.062799 -394.409661)
			(xy 264.115035 -394.424998) (xy 264.164556 -394.447612) (xy 264.210355 -394.477045) (xy 264.251499 -394.512695)
			(xy 264.287151 -394.553838) (xy 264.316584 -394.599637) (xy 264.3392 -394.649158) (xy 264.354537 -394.701393)
			(xy 264.362285 -394.75528) (xy 264.362285 -394.8085) (xy 266.919443 -394.8085) (xy 266.923474 -394.723896)
			(xy 266.935527 -394.640059) (xy 266.955496 -394.557747) (xy 266.983198 -394.477706) (xy 267.018382 -394.40066)
			(xy 267.060731 -394.327308) (xy 267.109861 -394.258313) (xy 267.165326 -394.194301) (xy 267.226625 -394.13585)
			(xy 267.293203 -394.083491) (xy 267.364456 -394.037698) (xy 267.439739 -393.998885) (xy 267.51837 -393.967403)
			(xy 267.599638 -393.943538) (xy 267.682807 -393.927507) (xy 267.767122 -393.919453) (xy 267.809472 -393.918948)
			(xy 267.850695 -393.919444) (xy 267.932787 -393.927077) (xy 268.013822 -393.942269) (xy 268.093103 -393.964892)
			(xy 268.169953 -393.994751) (xy 268.243711 -394.03159) (xy 268.313746 -394.075093) (xy 268.379456 -394.124888)
			(xy 268.410182 -394.152374) (xy 268.417414 -394.158461) (xy 268.435027 -394.165287) (xy 268.453917 -394.165287)
			(xy 268.47153 -394.158461) (xy 268.478762 -394.152374) (xy 268.509471 -394.124866) (xy 268.575178 -394.07506)
			(xy 268.645212 -394.031548) (xy 268.718971 -393.994703) (xy 268.795824 -393.964842) (xy 268.87511 -393.942221)
			(xy 268.95615 -393.927033) (xy 269.038247 -393.91941) (xy 269.079472 -393.918948) (xy 269.120039 -393.919454)
			(xy 269.200835 -393.92684) (xy 269.280624 -393.941554) (xy 269.35874 -393.963472) (xy 269.434536 -393.992414)
			(xy 269.507381 -394.028138) (xy 269.576671 -394.070348) (xy 269.641828 -394.118693) (xy 269.702312 -394.17277)
			(xy 269.757619 -394.232131) (xy 269.807291 -394.296282) (xy 269.850914 -394.36469) (xy 269.86992 -394.400532)
			(xy 269.897015 -394.401316) (xy 269.95059 -394.409555) (xy 270.002462 -394.425283) (xy 270.051591 -394.448184)
			(xy 270.096989 -394.477799) (xy 270.137747 -394.513533) (xy 270.173045 -394.554669) (xy 270.202175 -394.60038)
			(xy 270.224552 -394.64975) (xy 270.239727 -394.701787) (xy 270.247395 -394.755446) (xy 270.247872 -394.782548)
			(xy 270.24739 -394.8085) (xy 272.854328 -394.8085) (xy 272.858359 -394.723891) (xy 272.870414 -394.640048)
			(xy 272.890384 -394.557731) (xy 272.918089 -394.477686) (xy 272.953277 -394.400636) (xy 272.995631 -394.32728)
			(xy 273.044766 -394.258282) (xy 273.100237 -394.194267) (xy 273.161542 -394.135816) (xy 273.228125 -394.083456)
			(xy 273.299385 -394.037663) (xy 273.374675 -393.998851) (xy 273.453313 -393.967372) (xy 273.534587 -393.943511)
			(xy 273.617762 -393.927483) (xy 273.702084 -393.919434) (xy 273.744436 -393.918948) (xy 273.78566 -393.919404)
			(xy 273.867754 -393.927042) (xy 273.948789 -393.942241) (xy 274.028071 -393.964869) (xy 274.10492 -393.994734)
			(xy 274.178678 -394.031578) (xy 274.248712 -394.075086) (xy 274.314421 -394.124886) (xy 274.345146 -394.152374)
			(xy 274.352378 -394.158461) (xy 274.369991 -394.165287) (xy 274.388881 -394.165287) (xy 274.406494 -394.158461)
			(xy 274.413726 -394.152374) (xy 274.44445 -394.124884) (xy 274.510154 -394.075076) (xy 274.580186 -394.031562)
			(xy 274.653943 -393.994716) (xy 274.730794 -393.964852) (xy 274.810078 -393.942228) (xy 274.891116 -393.927038)
			(xy 274.973211 -393.919412) (xy 275.014436 -393.918948) (xy 275.055004 -393.9194) (xy 275.135802 -393.926792)
			(xy 275.215592 -393.941511) (xy 275.293709 -393.963435) (xy 275.369506 -393.992382) (xy 275.442351 -394.028112)
			(xy 275.51164 -394.070326) (xy 275.576797 -394.118675) (xy 275.63728 -394.172757) (xy 275.692586 -394.232122)
			(xy 275.742257 -394.296277) (xy 275.785879 -394.364688) (xy 275.804884 -394.400532) (xy 275.831978 -394.401349)
			(xy 275.885551 -394.409583) (xy 275.937423 -394.425306) (xy 275.986552 -394.448204) (xy 276.031951 -394.477815)
			(xy 276.072709 -394.513546) (xy 276.108007 -394.554678) (xy 276.137138 -394.600387) (xy 276.159515 -394.649755)
			(xy 276.174691 -394.70179) (xy 276.182359 -394.755447) (xy 276.182836 -394.782548) (xy 276.182385 -394.808456)
			(xy 278.916892 -394.808456) (xy 278.917356 -394.766262) (xy 278.925335 -394.682252) (xy 278.941234 -394.599376)
			(xy 278.964912 -394.518378) (xy 278.996156 -394.439987) (xy 279.034684 -394.364908) (xy 279.08015 -394.293815)
			(xy 279.132146 -394.227349) (xy 279.190203 -394.166106) (xy 279.2538 -394.110638) (xy 279.322365 -394.061443)
			(xy 279.395282 -394.018964) (xy 279.471894 -393.983582) (xy 279.551513 -393.955615) (xy 279.633423 -393.935316)
			(xy 279.675082 -393.9286) (xy 279.689459 -393.925944) (xy 279.715949 -393.913606) (xy 279.737852 -393.894262)
			(xy 279.753368 -393.869499) (xy 279.761223 -393.841352) (xy 279.760772 -393.812133) (xy 279.75687 -393.798044)
			(xy 279.744165 -393.755179) (xy 279.726399 -393.667554) (xy 279.717507 -393.578589) (xy 279.716992 -393.533884)
			(xy 279.717496 -393.491536) (xy 279.725547 -393.407222) (xy 279.741576 -393.324056) (xy 279.765437 -393.242789)
			(xy 279.796916 -393.164159) (xy 279.835727 -393.088878) (xy 279.881517 -393.017626) (xy 279.933873 -392.95105)
			(xy 279.992321 -392.889752) (xy 280.056331 -392.834287) (xy 280.125323 -392.785158) (xy 280.198673 -392.742809)
			(xy 280.275716 -392.707625) (xy 280.355755 -392.679923) (xy 280.438064 -392.659955) (xy 280.521899 -392.647902)
			(xy 280.6065 -392.643872) (xy 280.691101 -392.647902) (xy 280.774936 -392.659955) (xy 280.857245 -392.679923)
			(xy 280.937284 -392.707625) (xy 281.014327 -392.742809) (xy 281.087677 -392.785158) (xy 281.156669 -392.834287)
			(xy 281.220679 -392.889752) (xy 281.279127 -392.95105) (xy 281.331483 -393.017626) (xy 281.377273 -393.088878)
			(xy 281.416084 -393.164159) (xy 281.447563 -393.242789) (xy 281.471424 -393.324056) (xy 281.487453 -393.407222)
			(xy 281.495504 -393.491536) (xy 281.496008 -393.533884) (xy 281.495487 -393.576077) (xy 281.487514 -393.660085)
			(xy 281.47162 -393.74296) (xy 281.461756 -393.776708) (xy 289.471608 -393.776708) (xy 289.471608 -393.776454)
			(xy 289.47211 -393.744493) (xy 289.480121 -393.681075) (xy 289.496018 -393.619161) (xy 289.51955 -393.559728)
			(xy 289.550344 -393.503713) (xy 289.587917 -393.451998) (xy 289.631674 -393.405401) (xy 289.680927 -393.364656)
			(xy 289.734898 -393.330405) (xy 289.792737 -393.303188) (xy 289.85353 -393.283435) (xy 289.91632 -393.271457)
			(xy 289.980116 -393.267444) (xy 290.043912 -393.271457) (xy 290.106702 -393.283435) (xy 290.167495 -393.303188)
			(xy 290.225334 -393.330405) (xy 290.279305 -393.364656) (xy 290.328558 -393.405401) (xy 290.372315 -393.451998)
			(xy 290.409888 -393.503713) (xy 290.440682 -393.559728) (xy 290.464214 -393.619161) (xy 290.480111 -393.681075)
			(xy 290.488122 -393.744493) (xy 290.488624 -393.776454) (xy 290.488624 -393.7765) (xy 291.470768 -393.7765)
			(xy 291.474784 -393.712663) (xy 291.48677 -393.649832) (xy 291.506536 -393.589) (xy 291.533771 -393.531124)
			(xy 291.568045 -393.477118) (xy 291.608817 -393.427834) (xy 291.655445 -393.384049) (xy 291.707193 -393.346453)
			(xy 291.763245 -393.315639) (xy 291.822717 -393.292094) (xy 291.884671 -393.276188) (xy 291.94813 -393.268172)
			(xy 291.980112 -393.267692) (xy 292.010658 -393.268138) (xy 292.071311 -393.275449) (xy 292.13065 -393.289975)
			(xy 292.187822 -393.311508) (xy 292.242001 -393.339737) (xy 292.292406 -393.374254) (xy 292.338312 -393.414564)
			(xy 292.379057 -393.460084) (xy 292.396926 -393.484862) (xy 292.405296 -393.496027) (xy 292.426903 -393.51367)
			(xy 292.452477 -393.52481) (xy 292.480111 -393.528618) (xy 292.507745 -393.52481) (xy 292.533319 -393.51367)
			(xy 292.554926 -393.496027) (xy 292.563296 -393.484862) (xy 292.582389 -393.458454) (xy 292.626241 -393.410247)
			(xy 292.675892 -393.368039) (xy 292.730528 -393.332518) (xy 292.789254 -393.304269) (xy 292.851108 -393.283754)
			(xy 292.915076 -393.271309) (xy 292.98011 -393.267138) (xy 293.045144 -393.271309) (xy 293.109112 -393.283754)
			(xy 293.170966 -393.304269) (xy 293.229692 -393.332518) (xy 293.284328 -393.368039) (xy 293.333979 -393.410247)
			(xy 293.377831 -393.458454) (xy 293.396924 -393.484862) (xy 293.405294 -393.496027) (xy 293.426901 -393.51367)
			(xy 293.452475 -393.52481) (xy 293.480109 -393.528618) (xy 293.507743 -393.52481) (xy 293.533317 -393.51367)
			(xy 293.554924 -393.496027) (xy 293.563294 -393.484862) (xy 293.582387 -393.458454) (xy 293.626239 -393.410247)
			(xy 293.67589 -393.368039) (xy 293.730526 -393.332518) (xy 293.789252 -393.304269) (xy 293.851106 -393.283754)
			(xy 293.915074 -393.271309) (xy 293.980108 -393.267138) (xy 294.045142 -393.271309) (xy 294.10911 -393.283754)
			(xy 294.170964 -393.304269) (xy 294.22969 -393.332518) (xy 294.284326 -393.368039) (xy 294.333977 -393.410247)
			(xy 294.377829 -393.458454) (xy 294.396922 -393.484862) (xy 294.405292 -393.496027) (xy 294.426899 -393.51367)
			(xy 294.452473 -393.52481) (xy 294.480107 -393.528618) (xy 294.507741 -393.52481) (xy 294.533315 -393.51367)
			(xy 294.554922 -393.496027) (xy 294.563292 -393.484862) (xy 294.582385 -393.458454) (xy 294.626237 -393.410247)
			(xy 294.675888 -393.368039) (xy 294.730524 -393.332518) (xy 294.78925 -393.304269) (xy 294.851104 -393.283754)
			(xy 294.915072 -393.271309) (xy 294.980106 -393.267138) (xy 295.04514 -393.271309) (xy 295.109108 -393.283754)
			(xy 295.170962 -393.304269) (xy 295.229688 -393.332518) (xy 295.284324 -393.368039) (xy 295.333975 -393.410247)
			(xy 295.377827 -393.458454) (xy 295.39692 -393.484862) (xy 295.40529 -393.496027) (xy 295.426897 -393.51367)
			(xy 295.452471 -393.52481) (xy 295.480105 -393.528618) (xy 295.507739 -393.52481) (xy 295.533313 -393.51367)
			(xy 295.55492 -393.496027) (xy 295.56329 -393.484862) (xy 295.582383 -393.458454) (xy 295.626235 -393.410247)
			(xy 295.675886 -393.368039) (xy 295.730522 -393.332518) (xy 295.789248 -393.304269) (xy 295.851102 -393.283754)
			(xy 295.91507 -393.271309) (xy 295.980104 -393.267138) (xy 296.045138 -393.271309) (xy 296.109106 -393.283754)
			(xy 296.17096 -393.304269) (xy 296.229686 -393.332518) (xy 296.284322 -393.368039) (xy 296.333973 -393.410247)
			(xy 296.377825 -393.458454) (xy 296.396918 -393.484862) (xy 296.405288 -393.496027) (xy 296.426895 -393.51367)
			(xy 296.452469 -393.52481) (xy 296.480103 -393.528618) (xy 296.507737 -393.52481) (xy 296.533311 -393.51367)
			(xy 296.554918 -393.496027) (xy 296.563288 -393.484862) (xy 296.581151 -393.46008) (xy 296.621903 -393.414568)
			(xy 296.667813 -393.374265) (xy 296.71822 -393.339752) (xy 296.772399 -393.311525) (xy 296.829568 -393.289992)
			(xy 296.888906 -393.275462) (xy 296.949557 -393.268144) (xy 296.980102 -393.267692) (xy 297.012076 -393.268286)
			(xy 297.07552 -393.276301) (xy 297.137459 -393.292204) (xy 297.196916 -393.315745) (xy 297.252954 -393.346553)
			(xy 297.304689 -393.384141) (xy 297.351305 -393.427916) (xy 297.392067 -393.477189) (xy 297.426332 -393.531182)
			(xy 297.45356 -393.589044) (xy 297.473321 -393.649863) (xy 297.485304 -393.712678) (xy 297.489319 -393.7765)
			(xy 297.485304 -393.840322) (xy 297.473321 -393.903137) (xy 297.45356 -393.963956) (xy 297.426332 -394.021818)
			(xy 297.392067 -394.075811) (xy 297.351305 -394.125084) (xy 297.304689 -394.168859) (xy 297.252954 -394.206447)
			(xy 297.196916 -394.237255) (xy 297.137459 -394.260796) (xy 297.07552 -394.276699) (xy 297.012076 -394.284714)
			(xy 296.980102 -394.285216) (xy 296.949556 -394.284756) (xy 296.888904 -394.277447) (xy 296.829565 -394.262922)
			(xy 296.772394 -394.241392) (xy 296.718215 -394.213165) (xy 296.667809 -394.178649) (xy 296.621903 -394.138341)
			(xy 296.581158 -394.092823) (xy 296.563288 -394.068046) (xy 296.554946 -394.056837) (xy 296.53336 -394.03911)
			(xy 296.507771 -394.027912) (xy 296.480103 -394.024083) (xy 296.452435 -394.027912) (xy 296.426846 -394.03911)
			(xy 296.40526 -394.056837) (xy 296.396918 -394.068046) (xy 296.377825 -394.094454) (xy 296.333973 -394.142661)
			(xy 296.284322 -394.184869) (xy 296.229686 -394.22039) (xy 296.17096 -394.248639) (xy 296.109106 -394.269154)
			(xy 296.045138 -394.281599) (xy 295.980104 -394.28577) (xy 295.91507 -394.281599) (xy 295.851102 -394.269154)
			(xy 295.789248 -394.248639) (xy 295.730522 -394.22039) (xy 295.675886 -394.184869) (xy 295.626235 -394.142661)
			(xy 295.582383 -394.094454) (xy 295.56329 -394.068046) (xy 295.554948 -394.056837) (xy 295.533362 -394.03911)
			(xy 295.507773 -394.027912) (xy 295.480105 -394.024083) (xy 295.452437 -394.027912) (xy 295.426848 -394.03911)
			(xy 295.405262 -394.056837) (xy 295.39692 -394.068046) (xy 295.377827 -394.094454) (xy 295.333975 -394.142661)
			(xy 295.284324 -394.184869) (xy 295.229688 -394.22039) (xy 295.170962 -394.248639) (xy 295.109108 -394.269154)
			(xy 295.04514 -394.281599) (xy 294.980106 -394.28577) (xy 294.915072 -394.281599) (xy 294.851104 -394.269154)
			(xy 294.78925 -394.248639) (xy 294.730524 -394.22039) (xy 294.675888 -394.184869) (xy 294.626237 -394.142661)
			(xy 294.582385 -394.094454) (xy 294.563292 -394.068046) (xy 294.55495 -394.056837) (xy 294.533364 -394.03911)
			(xy 294.507775 -394.027912) (xy 294.480107 -394.024083) (xy 294.452439 -394.027912) (xy 294.42685 -394.03911)
			(xy 294.405264 -394.056837) (xy 294.396922 -394.068046) (xy 294.377829 -394.094454) (xy 294.333977 -394.142661)
			(xy 294.284326 -394.184869) (xy 294.22969 -394.22039) (xy 294.170964 -394.248639) (xy 294.10911 -394.269154)
			(xy 294.045142 -394.281599) (xy 293.980108 -394.28577) (xy 293.915074 -394.281599) (xy 293.851106 -394.269154)
			(xy 293.789252 -394.248639) (xy 293.730526 -394.22039) (xy 293.67589 -394.184869) (xy 293.626239 -394.142661)
			(xy 293.582387 -394.094454) (xy 293.563294 -394.068046) (xy 293.554952 -394.056837) (xy 293.533366 -394.03911)
			(xy 293.507777 -394.027912) (xy 293.480109 -394.024083) (xy 293.452441 -394.027912) (xy 293.426852 -394.03911)
			(xy 293.405266 -394.056837) (xy 293.396924 -394.068046) (xy 293.377831 -394.094454) (xy 293.333979 -394.142661)
			(xy 293.284328 -394.184869) (xy 293.229692 -394.22039) (xy 293.170966 -394.248639) (xy 293.109112 -394.269154)
			(xy 293.045144 -394.281599) (xy 292.98011 -394.28577) (xy 292.915076 -394.281599) (xy 292.851108 -394.269154)
			(xy 292.789254 -394.248639) (xy 292.730528 -394.22039) (xy 292.675892 -394.184869) (xy 292.626241 -394.142661)
			(xy 292.582389 -394.094454) (xy 292.563296 -394.068046) (xy 292.554954 -394.056837) (xy 292.533368 -394.03911)
			(xy 292.507779 -394.027912) (xy 292.480111 -394.024083) (xy 292.452443 -394.027912) (xy 292.426854 -394.03911)
			(xy 292.405268 -394.056837) (xy 292.396926 -394.068046) (xy 292.379057 -394.092823) (xy 292.338306 -394.138335)
			(xy 292.292396 -394.178638) (xy 292.24199 -394.213151) (xy 292.187812 -394.241378) (xy 292.130644 -394.262913)
			(xy 292.071307 -394.277444) (xy 292.010657 -394.284763) (xy 291.980112 -394.285216) (xy 291.94813 -394.284828)
			(xy 291.884671 -394.276812) (xy 291.822717 -394.260906) (xy 291.763245 -394.237361) (xy 291.707193 -394.206547)
			(xy 291.655445 -394.168951) (xy 291.608817 -394.125166) (xy 291.568045 -394.075882) (xy 291.533771 -394.021876)
			(xy 291.506536 -393.964) (xy 291.48677 -393.903168) (xy 291.474784 -393.840337) (xy 291.470768 -393.7765)
			(xy 290.488624 -393.7765) (xy 290.488624 -393.776962) (xy 290.488202 -393.806564) (xy 290.481324 -393.865367)
			(xy 290.467658 -393.922971) (xy 290.447389 -393.978597) (xy 290.420792 -394.03149) (xy 290.388226 -394.080932)
			(xy 290.369498 -394.10386) (xy 290.389588 -394.127178) (xy 290.424612 -394.17779) (xy 290.453267 -394.232263)
			(xy 290.475133 -394.289797) (xy 290.48989 -394.349552) (xy 290.497321 -394.410651) (xy 290.497768 -394.441426)
			(xy 290.497768 -394.44168) (xy 290.497266 -394.473641) (xy 290.489255 -394.537059) (xy 290.473358 -394.598973)
			(xy 290.449826 -394.658406) (xy 290.419032 -394.714421) (xy 290.381459 -394.766136) (xy 290.337702 -394.812733)
			(xy 290.288449 -394.853478) (xy 290.234478 -394.887729) (xy 290.176639 -394.914946) (xy 290.115846 -394.934699)
			(xy 290.053056 -394.946677) (xy 289.98926 -394.950691) (xy 289.925464 -394.946677) (xy 289.862674 -394.934699)
			(xy 289.801881 -394.914946) (xy 289.744042 -394.887729) (xy 289.690071 -394.853478) (xy 289.640818 -394.812733)
			(xy 289.597061 -394.766136) (xy 289.559488 -394.714421) (xy 289.528694 -394.658406) (xy 289.505162 -394.598973)
			(xy 289.489265 -394.537059) (xy 289.481254 -394.473641) (xy 289.480752 -394.44168) (xy 289.480752 -394.441172)
			(xy 289.481141 -394.411569) (xy 289.488026 -394.352765) (xy 289.501699 -394.29516) (xy 289.521974 -394.239535)
			(xy 289.548577 -394.186643) (xy 289.581148 -394.137202) (xy 289.599878 -394.114274) (xy 289.579769 -394.090972)
			(xy 289.544745 -394.040357) (xy 289.516091 -393.985882) (xy 289.494228 -393.928344) (xy 289.479476 -393.868586)
			(xy 289.472051 -393.807484) (xy 289.471608 -393.776708) (xy 281.461756 -393.776708) (xy 281.447947 -393.823957)
			(xy 281.416708 -393.902348) (xy 281.378185 -393.977427) (xy 281.332723 -394.04852) (xy 281.280732 -394.114986)
			(xy 281.222678 -394.176229) (xy 281.159084 -394.231698) (xy 281.090523 -394.280894) (xy 281.017609 -394.323374)
			(xy 280.941 -394.358757) (xy 280.861383 -394.386724) (xy 280.779476 -394.407024) (xy 280.737818 -394.41374)
			(xy 280.72343 -394.416347) (xy 280.696933 -394.428691) (xy 280.675026 -394.448046) (xy 280.659511 -394.472819)
			(xy 280.651661 -394.500977) (xy 280.652122 -394.530204) (xy 280.65603 -394.544296) (xy 280.668744 -394.587158)
			(xy 280.686507 -394.674785) (xy 280.695395 -394.763751) (xy 280.695908 -394.808456) (xy 280.695404 -394.850804)
			(xy 280.687353 -394.935118) (xy 280.671324 -395.018284) (xy 280.647463 -395.099551) (xy 280.615984 -395.178181)
			(xy 280.577173 -395.253462) (xy 280.531383 -395.324714) (xy 280.479027 -395.39129) (xy 280.420579 -395.452588)
			(xy 280.356569 -395.508053) (xy 280.287577 -395.557182) (xy 280.214227 -395.599531) (xy 280.137184 -395.634715)
			(xy 280.057145 -395.662417) (xy 279.974836 -395.682385) (xy 279.891001 -395.694438) (xy 279.8064 -395.698469)
			(xy 279.721799 -395.694438) (xy 279.637964 -395.682385) (xy 279.555655 -395.662417) (xy 279.475616 -395.634715)
			(xy 279.398573 -395.599531) (xy 279.325223 -395.557182) (xy 279.256231 -395.508053) (xy 279.192221 -395.452588)
			(xy 279.133773 -395.39129) (xy 279.081417 -395.324714) (xy 279.035627 -395.253462) (xy 278.996816 -395.178181)
			(xy 278.965337 -395.099551) (xy 278.941476 -395.018284) (xy 278.925447 -394.935118) (xy 278.917396 -394.850804)
			(xy 278.916892 -394.808456) (xy 276.182385 -394.808456) (xy 276.182339 -394.81111) (xy 276.173854 -394.867601)
			(xy 276.157051 -394.922198) (xy 276.132304 -394.973684) (xy 276.100165 -395.02091) (xy 276.061351 -395.062822)
			(xy 276.016728 -395.098487) (xy 275.967291 -395.127109) (xy 275.914142 -395.148048) (xy 275.858468 -395.160839)
			(xy 275.83003 -395.163548) (xy 275.812369 -395.202766) (xy 275.770577 -395.277947) (xy 275.721724 -395.348744)
			(xy 275.666266 -395.414494) (xy 275.60472 -395.474584) (xy 275.537661 -395.528453) (xy 275.465716 -395.575598)
			(xy 275.389556 -395.615578) (xy 275.309893 -395.648021) (xy 275.22747 -395.672622) (xy 275.143058 -395.689153)
			(xy 275.057444 -395.697459) (xy 275.014436 -395.697964) (xy 274.973213 -395.69746) (xy 274.891121 -395.689828)
			(xy 274.810087 -395.674636) (xy 274.730806 -395.652015) (xy 274.653956 -395.622157) (xy 274.580198 -395.585319)
			(xy 274.510163 -395.541817) (xy 274.444452 -395.492024) (xy 274.413726 -395.464538) (xy 274.406494 -395.458451)
			(xy 274.388881 -395.451625) (xy 274.369991 -395.451625) (xy 274.352378 -395.458451) (xy 274.345146 -395.464538)
			(xy 274.314435 -395.492044) (xy 274.248729 -395.54185) (xy 274.178695 -395.585362) (xy 274.104936 -395.622207)
			(xy 274.028083 -395.652068) (xy 273.948797 -395.67469) (xy 273.867758 -395.689878) (xy 273.785661 -395.697501)
			(xy 273.744436 -395.697964) (xy 273.702084 -395.697566) (xy 273.617762 -395.689517) (xy 273.534587 -395.673489)
			(xy 273.453313 -395.649628) (xy 273.374675 -395.618149) (xy 273.299385 -395.579337) (xy 273.228125 -395.533544)
			(xy 273.161542 -395.481184) (xy 273.100237 -395.422733) (xy 273.044766 -395.358718) (xy 272.995631 -395.28972)
			(xy 272.953277 -395.216364) (xy 272.918089 -395.139314) (xy 272.890384 -395.059269) (xy 272.870414 -394.976952)
			(xy 272.858359 -394.893109) (xy 272.854328 -394.8085) (xy 270.24739 -394.8085) (xy 270.247342 -394.811109)
			(xy 270.238858 -394.867596) (xy 270.222057 -394.922191) (xy 270.197312 -394.973674) (xy 270.165177 -395.020899)
			(xy 270.126367 -395.062811) (xy 270.081748 -395.098476) (xy 270.032316 -395.127099) (xy 269.979172 -395.148042)
			(xy 269.923503 -395.160836) (xy 269.895066 -395.163548) (xy 269.877376 -395.202752) (xy 269.835586 -395.277933)
			(xy 269.786736 -395.348729) (xy 269.73128 -395.414479) (xy 269.669737 -395.474569) (xy 269.602681 -395.528439)
			(xy 269.530739 -395.575585) (xy 269.454582 -395.615566) (xy 269.374921 -395.648011) (xy 269.292501 -395.672615)
			(xy 269.208091 -395.689148) (xy 269.122479 -395.697457) (xy 269.079472 -395.697964) (xy 269.038248 -395.6975)
			(xy 268.956155 -395.689862) (xy 268.87512 -395.674665) (xy 268.795838 -395.652037) (xy 268.718989 -395.622174)
			(xy 268.645231 -395.585331) (xy 268.575197 -395.541824) (xy 268.509487 -395.492026) (xy 268.478762 -395.464538)
			(xy 268.47153 -395.458451) (xy 268.453917 -395.451625) (xy 268.435027 -395.451625) (xy 268.417414 -395.458451)
			(xy 268.410182 -395.464538) (xy 268.379456 -395.492026) (xy 268.313752 -395.541834) (xy 268.243721 -395.585348)
			(xy 268.169964 -395.622194) (xy 268.093113 -395.652058) (xy 268.013829 -395.674682) (xy 267.932792 -395.689873)
			(xy 267.850696 -395.6975) (xy 267.809472 -395.697964) (xy 267.767122 -395.697547) (xy 267.682807 -395.689493)
			(xy 267.599638 -395.673462) (xy 267.51837 -395.649597) (xy 267.439739 -395.618115) (xy 267.364456 -395.579302)
			(xy 267.293203 -395.533509) (xy 267.226625 -395.48115) (xy 267.165326 -395.422699) (xy 267.109861 -395.358687)
			(xy 267.060731 -395.289692) (xy 267.018382 -395.21634) (xy 266.983198 -395.139294) (xy 266.955496 -395.059253)
			(xy 266.935527 -394.976941) (xy 266.923474 -394.893104) (xy 266.919443 -394.8085) (xy 264.362285 -394.8085)
			(xy 264.362285 -394.80972) (xy 264.354537 -394.863607) (xy 264.3392 -394.915842) (xy 264.316584 -394.965363)
			(xy 264.287151 -395.011162) (xy 264.251499 -395.052305) (xy 264.210355 -395.087955) (xy 264.164556 -395.117388)
			(xy 264.115035 -395.140002) (xy 264.062799 -395.155339) (xy 264.008912 -395.163086) (xy 263.981692 -395.163548)
			(xy 263.960356 -395.16304) (xy 263.942674 -395.202274) (xy 263.9009 -395.277517) (xy 263.852055 -395.348375)
			(xy 263.796597 -395.414185) (xy 263.735042 -395.474332) (xy 263.667968 -395.528254) (xy 263.596 -395.575447)
			(xy 263.519811 -395.61547) (xy 263.440113 -395.647949) (xy 263.357652 -395.67258) (xy 263.273197 -395.689134)
			(xy 263.187539 -395.697455) (xy 263.144508 -395.697964) (xy 263.103285 -395.697477) (xy 263.021192 -395.689843)
			(xy 262.940158 -395.674649) (xy 262.860876 -395.652025) (xy 262.784027 -395.622164) (xy 262.710269 -395.585324)
			(xy 262.640234 -395.54182) (xy 262.574524 -395.492025) (xy 262.543798 -395.464538) (xy 262.536566 -395.458451)
			(xy 262.518953 -395.451625) (xy 262.500063 -395.451625) (xy 262.48245 -395.458451) (xy 262.475218 -395.464538)
			(xy 262.444477 -395.492009) (xy 262.378775 -395.541818) (xy 262.308747 -395.585333) (xy 262.234992 -395.622182)
			(xy 262.158144 -395.652048) (xy 262.078861 -395.674675) (xy 261.997826 -395.689868) (xy 261.915732 -395.697498)
			(xy 261.874508 -395.697964) (xy 261.832156 -395.697564) (xy 261.747837 -395.689513) (xy 261.664664 -395.673484)
			(xy 261.583392 -395.649621) (xy 261.504756 -395.61814) (xy 261.429469 -395.579328) (xy 261.358212 -395.533534)
			(xy 261.29163 -395.481174) (xy 261.230327 -395.422723) (xy 261.174858 -395.358709) (xy 261.125725 -395.289712)
			(xy 261.083374 -395.216357) (xy 261.048186 -395.139308) (xy 261.020483 -395.059264) (xy 261.000513 -394.976948)
			(xy 260.988458 -394.893107) (xy 260.984428 -394.8085) (xy 258.448577 -394.8085) (xy 258.448577 -394.809789)
			(xy 258.440811 -394.863811) (xy 258.425436 -394.916178) (xy 258.402765 -394.965824) (xy 258.37326 -395.011739)
			(xy 258.337522 -395.052988) (xy 258.296278 -395.088732) (xy 258.250366 -395.118242) (xy 258.200723 -395.140919)
			(xy 258.148358 -395.156301) (xy 258.094337 -395.164074) (xy 258.067048 -395.164564) (xy 258.056676 -395.164479)
			(xy 258.035964 -395.163337) (xy 258.025646 -395.162278) (xy 258.008 -395.201564) (xy 257.966267 -395.276906)
			(xy 257.917448 -395.347861) (xy 257.861999 -395.413765) (xy 257.80044 -395.474001) (xy 257.733346 -395.528004)
			(xy 257.661347 -395.575269) (xy 257.585116 -395.615354) (xy 257.505368 -395.647883) (xy 257.422848 -395.672551)
			(xy 257.338331 -395.689127) (xy 257.252608 -395.697456) (xy 257.209544 -395.697964) (xy 257.168321 -395.697455)
			(xy 257.08623 -395.689824) (xy 257.005196 -395.674633) (xy 256.925914 -395.652012) (xy 256.849065 -395.622155)
			(xy 256.775306 -395.585317) (xy 256.705271 -395.541816) (xy 256.63956 -395.492023) (xy 256.608834 -395.464538)
			(xy 256.601602 -395.458451) (xy 256.583989 -395.451625) (xy 256.565099 -395.451625) (xy 256.547486 -395.458451)
			(xy 256.540254 -395.464538) (xy 256.50954 -395.49204) (xy 256.443834 -395.541846) (xy 256.373801 -395.585359)
			(xy 256.300042 -395.622204) (xy 256.22319 -395.652066) (xy 256.143904 -395.674688) (xy 256.062865 -395.689877)
			(xy 255.980769 -395.697501) (xy 255.939544 -395.697964) (xy 255.897191 -395.697566) (xy 255.812869 -395.689518)
			(xy 255.729694 -395.673491) (xy 255.648419 -395.64963) (xy 255.56978 -395.618151) (xy 255.494489 -395.57934)
			(xy 255.423229 -395.533547) (xy 255.356645 -395.481187) (xy 255.295339 -395.422735) (xy 255.239868 -395.358721)
			(xy 255.190732 -395.289723) (xy 255.148379 -395.216366) (xy 255.11319 -395.139316) (xy 255.085484 -395.05927)
			(xy 255.065514 -394.976952) (xy 255.053459 -394.893109) (xy 255.049428 -394.8085) (xy 252.466916 -394.8085)
			(xy 252.466897 -394.809592) (xy 252.459254 -394.863136) (xy 252.444116 -394.915061) (xy 252.421785 -394.964324)
			(xy 252.392711 -395.009932) (xy 252.357479 -395.05097) (xy 252.316797 -395.086613) (xy 252.271483 -395.116143)
			(xy 252.222447 -395.138967) (xy 252.170677 -395.154627) (xy 252.117212 -395.162807) (xy 252.090174 -395.163548)
			(xy 252.072477 -395.202749) (xy 252.030688 -395.27793) (xy 251.981838 -395.348725) (xy 251.926383 -395.414475)
			(xy 251.864841 -395.474566) (xy 251.797785 -395.528436) (xy 251.725844 -395.575582) (xy 251.649687 -395.615564)
			(xy 251.570027 -395.648009) (xy 251.487608 -395.672613) (xy 251.403198 -395.689147) (xy 251.317587 -395.697457)
			(xy 251.27458 -395.697964) (xy 251.233356 -395.697495) (xy 251.151263 -395.689858) (xy 251.070228 -395.674661)
			(xy 250.990947 -395.652035) (xy 250.914097 -395.622172) (xy 250.840339 -395.58533) (xy 250.770305 -395.541823)
			(xy 250.704595 -395.492026) (xy 250.67387 -395.464538) (xy 250.666638 -395.458451) (xy 250.649025 -395.451625)
			(xy 250.630135 -395.451625) (xy 250.612522 -395.458451) (xy 250.60529 -395.464538) (xy 250.574561 -395.492023)
			(xy 250.508857 -395.54183) (xy 250.438827 -395.585344) (xy 250.36507 -395.622192) (xy 250.28822 -395.652056)
			(xy 250.208936 -395.67468) (xy 250.127899 -395.689872) (xy 250.045804 -395.697499) (xy 250.00458 -395.697964)
			(xy 249.96223 -395.697547) (xy 249.877914 -395.689494) (xy 249.794745 -395.673463) (xy 249.713476 -395.649599)
			(xy 249.634844 -395.618118) (xy 249.55956 -395.579305) (xy 249.488307 -395.533512) (xy 249.421729 -395.481153)
			(xy 249.360429 -395.422702) (xy 249.304963 -395.35869) (xy 249.255833 -395.289695) (xy 249.213483 -395.216342)
			(xy 249.178298 -395.139296) (xy 249.150596 -395.059254) (xy 249.130628 -394.976942) (xy 249.118574 -394.893104)
			(xy 249.114543 -394.8085) (xy 246.507582 -394.8085) (xy 246.507538 -394.811111) (xy 246.499052 -394.867604)
			(xy 246.482248 -394.922202) (xy 246.457499 -394.973689) (xy 246.425358 -395.020916) (xy 246.386542 -395.062829)
			(xy 246.341916 -395.098493) (xy 246.292476 -395.127114) (xy 246.239326 -395.148052) (xy 246.183649 -395.16084)
			(xy 246.15521 -395.163548) (xy 246.137565 -395.202774) (xy 246.095772 -395.277955) (xy 246.046918 -395.348752)
			(xy 245.991458 -395.414502) (xy 245.929911 -395.474592) (xy 245.86285 -395.528461) (xy 245.790904 -395.575605)
			(xy 245.714742 -395.615585) (xy 245.635078 -395.648026) (xy 245.552653 -395.672626) (xy 245.46824 -395.689156)
			(xy 245.382624 -395.69746) (xy 245.339616 -395.697964) (xy 245.298393 -395.697472) (xy 245.216301 -395.689839)
			(xy 245.135266 -395.674645) (xy 245.055985 -395.652022) (xy 244.979135 -395.622162) (xy 244.905377 -395.585323)
			(xy 244.835342 -395.541819) (xy 244.769632 -395.492024) (xy 244.738906 -395.464538) (xy 244.731674 -395.458451)
			(xy 244.714061 -395.451625) (xy 244.695171 -395.451625) (xy 244.677558 -395.458451) (xy 244.670326 -395.464538)
			(xy 244.639624 -395.492053) (xy 244.573916 -395.541859) (xy 244.503881 -395.58537) (xy 244.43012 -395.622214)
			(xy 244.353266 -395.652074) (xy 244.273979 -395.674694) (xy 244.192939 -395.68988) (xy 244.110841 -395.697502)
			(xy 244.069616 -395.697964) (xy 244.027264 -395.697565) (xy 243.942944 -395.689514) (xy 243.859771 -395.673485)
			(xy 243.778498 -395.649623) (xy 243.699861 -395.618143) (xy 243.624573 -395.57933) (xy 243.553315 -395.533537)
			(xy 243.486733 -395.481177) (xy 243.42543 -395.422726) (xy 243.36996 -395.358711) (xy 243.320827 -395.289714)
			(xy 243.278475 -395.216359) (xy 243.243287 -395.13931) (xy 243.215583 -395.059265) (xy 243.195613 -394.976949)
			(xy 243.183558 -394.893108) (xy 243.179528 -394.8085) (xy 2.509012 -394.8085) (xy 2.509012 -397.347948)
			(xy 18.390108 -397.347948) (xy 18.390108 -396.278608) (xy 18.390362 -396.274798) (xy 18.390616 -396.273274)
			(xy 18.390616 -395.621256) (xy 18.390108 -395.621256) (xy 18.390108 -395.478508) (xy 18.390749 -395.466112)
			(xy 18.397411 -395.442205) (xy 18.409714 -395.420653) (xy 18.418048 -395.411452) (xy 18.427717 -395.402052)
			(xy 18.45093 -395.388347) (xy 18.476957 -395.381327) (xy 18.490438 -395.380972) (xy 18.79727 -395.380972)
			(xy 18.81101 -395.382106) (xy 18.837107 -395.390964) (xy 18.85977 -395.406644) (xy 18.877261 -395.427942)
			(xy 18.888234 -395.453223) (xy 18.890488 -395.466824) (xy 18.891504 -395.473428) (xy 18.891504 -395.593824)
			(xy 18.891989 -395.607928) (xy 18.899714 -395.635057) (xy 18.914569 -395.659037) (xy 18.935418 -395.678037)
			(xy 18.960671 -395.690606) (xy 18.988399 -395.695785) (xy 19.016486 -395.693179) (xy 19.042788 -395.682986)
			(xy 19.054318 -395.67485) (xy 19.079309 -395.656745) (xy 19.133913 -395.627998) (xy 19.192429 -395.608407)
			(xy 19.253334 -395.598481) (xy 19.284188 -395.597888) (xy 19.313272 -395.598406) (xy 19.370764 -395.607241)
			(xy 19.426251 -395.624694) (xy 19.478449 -395.65036) (xy 19.526151 -395.683647) (xy 19.568252 -395.723783)
			(xy 19.586448 -395.746478) (xy 19.601688 -395.76629) (xy 19.67738 -395.76629) (xy 19.67738 -395.479778)
			(xy 19.678018 -395.4674) (xy 19.68458 -395.443506) (xy 19.696781 -395.421941) (xy 19.705066 -395.412722)
			(xy 19.714738 -395.403325) (xy 19.737949 -395.389616) (xy 19.763975 -395.382596) (xy 19.777456 -395.382242)
			(xy 19.777456 -395.382496) (xy 20.084288 -395.382496) (xy 20.098006 -395.383638) (xy 20.124069 -395.392452)
			(xy 20.146718 -395.408073) (xy 20.164217 -395.429305) (xy 20.175225 -395.45452) (xy 20.177506 -395.468094)
			(xy 20.178268 -395.474698) (xy 20.178268 -395.769057) (xy 288.471858 -395.769057) (xy 288.471858 -395.705103)
			(xy 288.479873 -395.641653) (xy 288.495778 -395.579708) (xy 288.519321 -395.520246) (xy 288.550131 -395.464202)
			(xy 288.587723 -395.412462) (xy 288.631502 -395.365842) (xy 288.68078 -395.325076) (xy 288.734778 -395.290808)
			(xy 288.792645 -395.263577) (xy 288.853469 -395.243814) (xy 288.91629 -395.231831) (xy 288.980118 -395.227815)
			(xy 289.043946 -395.231831) (xy 289.106767 -395.243814) (xy 289.167591 -395.263577) (xy 289.225458 -395.290808)
			(xy 289.279456 -395.325076) (xy 289.328734 -395.365842) (xy 289.372513 -395.412462) (xy 289.410105 -395.464202)
			(xy 289.440915 -395.520246) (xy 289.464458 -395.579708) (xy 289.480363 -395.641653) (xy 289.488378 -395.705103)
			(xy 289.48888 -395.73708) (xy 289.488378 -395.769057) (xy 289.480363 -395.832507) (xy 289.464458 -395.894452)
			(xy 289.440915 -395.953914) (xy 289.410105 -396.009958) (xy 289.372513 -396.061698) (xy 289.328734 -396.108318)
			(xy 289.279456 -396.149084) (xy 289.225458 -396.183352) (xy 289.167591 -396.210583) (xy 289.106767 -396.230346)
			(xy 289.043946 -396.242329) (xy 288.980118 -396.246345) (xy 288.91629 -396.242329) (xy 288.853469 -396.230346)
			(xy 288.792645 -396.210583) (xy 288.734778 -396.183352) (xy 288.68078 -396.149084) (xy 288.631502 -396.108318)
			(xy 288.587723 -396.061698) (xy 288.550131 -396.009958) (xy 288.519321 -395.953914) (xy 288.495778 -395.894452)
			(xy 288.479873 -395.832507) (xy 288.471858 -395.769057) (xy 20.178268 -395.769057) (xy 20.178268 -397.344138)
			(xy 20.177626 -397.356516) (xy 20.171064 -397.380408) (xy 20.158865 -397.401974) (xy 20.150582 -397.411194)
			(xy 20.140892 -397.420571) (xy 20.11769 -397.434285) (xy 20.09167 -397.441314) (xy 20.078192 -397.441674)
			(xy 20.078192 -397.44142) (xy 19.77136 -397.44142) (xy 19.75764 -397.440307) (xy 19.731577 -397.431481)
			(xy 19.70893 -397.415852) (xy 19.691433 -397.394615) (xy 19.680424 -397.369397) (xy 19.678142 -397.355822)
			(xy 19.67738 -397.349218) (xy 19.67738 -397.228314) (xy 19.67698 -397.214175) (xy 19.669258 -397.186973)
			(xy 19.654374 -397.16293) (xy 19.633468 -397.143889) (xy 19.608144 -397.131309) (xy 19.580341 -397.126154)
			(xy 19.552189 -397.128819) (xy 19.525848 -397.1391) (xy 19.514312 -397.147288) (xy 19.489309 -397.165451)
			(xy 19.434658 -397.194293) (xy 19.376073 -397.21395) (xy 19.315086 -397.223907) (xy 19.284188 -397.224504)
			(xy 19.255134 -397.223973) (xy 19.197698 -397.215173) (xy 19.142261 -397.197762) (xy 19.090106 -397.172144)
			(xy 19.042441 -397.138911) (xy 19.000367 -397.098833) (xy 18.982182 -397.076168) (xy 18.966942 -397.05661)
			(xy 18.890996 -397.05661) (xy 18.890996 -397.20012) (xy 18.891504 -397.20012) (xy 18.891504 -397.342868)
			(xy 18.890847 -397.355263) (xy 18.884191 -397.379168) (xy 18.871895 -397.400722) (xy 18.863564 -397.409924)
			(xy 18.853886 -397.419314) (xy 18.830677 -397.433023) (xy 18.804654 -397.440046) (xy 18.791174 -397.440404)
			(xy 18.484342 -397.440404) (xy 18.4706 -397.439281) (xy 18.444501 -397.430423) (xy 18.421835 -397.414741)
			(xy 18.404346 -397.393439) (xy 18.393375 -397.368155) (xy 18.391124 -397.354552) (xy 18.390108 -397.347948)
			(xy 2.509012 -397.347948) (xy 2.509012 -398.224502) (xy 24.433784 -398.224502) (xy 24.433784 -397.155162)
			(xy 24.434038 -397.151352) (xy 24.434292 -397.149828) (xy 24.434292 -396.498064) (xy 24.433784 -396.498064)
			(xy 24.433784 -396.355062) (xy 24.434461 -396.342669) (xy 24.441109 -396.318764) (xy 24.453397 -396.29721)
			(xy 24.461724 -396.288006) (xy 24.471411 -396.278626) (xy 24.494615 -396.264913) (xy 24.520635 -396.257885)
			(xy 24.534114 -396.257526) (xy 24.534114 -396.25778) (xy 24.840946 -396.25778) (xy 24.854667 -396.258888)
			(xy 24.88073 -396.267715) (xy 24.903377 -396.283346) (xy 24.920874 -396.304583) (xy 24.931882 -396.329803)
			(xy 24.934164 -396.343378) (xy 24.93518 -396.349982) (xy 24.93518 -396.363698) (xy 24.935727 -396.377928)
			(xy 24.943637 -396.40527) (xy 24.958789 -396.429365) (xy 24.980003 -396.448341) (xy 25.005631 -396.460724)
			(xy 25.033682 -396.46555) (xy 25.061975 -396.462445) (xy 25.088311 -396.451651) (xy 25.099772 -396.4432)
			(xy 25.120056 -396.427664) (xy 25.164006 -396.401604) (xy 25.211039 -396.38164) (xy 25.260315 -396.368129)
			(xy 25.310953 -396.361313) (xy 25.3365 -396.360904) (xy 25.36453 -396.361364) (xy 25.419987 -396.369563)
			(xy 25.473649 -396.385785) (xy 25.524361 -396.409681) (xy 25.571033 -396.440738) (xy 25.612661 -396.478286)
			(xy 25.630886 -396.499588) (xy 25.721056 -396.46733) (xy 25.721056 -396.356332) (xy 25.721675 -396.343952)
			(xy 25.728246 -396.320059) (xy 25.740455 -396.298494) (xy 25.748742 -396.289276) (xy 25.758417 -396.279883)
			(xy 25.781627 -396.266175) (xy 25.807652 -396.259153) (xy 25.821132 -396.258796) (xy 26.127964 -396.258796)
			(xy 26.141707 -396.259914) (xy 26.167806 -396.268774) (xy 26.190471 -396.284457) (xy 26.20796 -396.30576)
			(xy 26.218931 -396.331045) (xy 26.221182 -396.344648) (xy 26.221944 -396.351252) (xy 26.221944 -398.220692)
			(xy 26.221338 -398.233073) (xy 26.214761 -398.256967) (xy 26.202548 -398.278531) (xy 26.194258 -398.287748)
			(xy 26.184587 -398.297145) (xy 26.161374 -398.310851) (xy 26.135349 -398.317872) (xy 26.121868 -398.318228)
			(xy 25.815036 -398.318228) (xy 25.801296 -398.317089) (xy 25.7752 -398.308232) (xy 25.752536 -398.292553)
			(xy 25.735046 -398.271256) (xy 25.724072 -398.245977) (xy 25.721818 -398.232376) (xy 25.721056 -398.225772)
			(xy 25.721056 -397.997426) (xy 25.720661 -397.983442) (xy 25.713029 -397.956534) (xy 25.698385 -397.932705)
			(xy 25.677826 -397.913742) (xy 25.652894 -397.901065) (xy 25.625459 -397.895627) (xy 25.597576 -397.897833)
			(xy 25.571338 -397.907519) (xy 25.559766 -397.915384) (xy 25.535244 -397.932374) (xy 25.482022 -397.959323)
			(xy 25.425256 -397.977662) (xy 25.366328 -397.986944) (xy 25.3365 -397.98752) (xy 25.335992 -397.98752)
			(xy 25.310471 -397.98708) (xy 25.259886 -397.980256) (xy 25.210663 -397.966744) (xy 25.163683 -397.946786)
			(xy 25.119786 -397.920739) (xy 25.099518 -397.905224) (xy 25.088096 -397.896655) (xy 25.06171 -397.88576)
			(xy 25.033339 -397.882592) (xy 25.0052 -397.887399) (xy 24.97949 -397.899804) (xy 24.958216 -397.91884)
			(xy 24.94304 -397.943018) (xy 24.935148 -397.970452) (xy 24.934672 -397.984726) (xy 24.934672 -398.07642)
			(xy 24.93518 -398.07642) (xy 24.93518 -398.219422) (xy 24.934477 -398.231812) (xy 24.927838 -398.255715)
			(xy 24.915561 -398.277272) (xy 24.90724 -398.286478) (xy 24.897565 -398.295872) (xy 24.874356 -398.309582)
			(xy 24.848331 -398.316603) (xy 24.83485 -398.316958) (xy 24.83485 -398.316704) (xy 24.528018 -398.316704)
			(xy 24.514301 -398.315558) (xy 24.488238 -398.306745) (xy 24.465589 -398.291125) (xy 24.44809 -398.269894)
			(xy 24.437081 -398.244679) (xy 24.4348 -398.231106) (xy 24.433784 -398.224502) (xy 2.509012 -398.224502)
			(xy 2.509012 -398.68657) (xy 36.781952 -398.68657) (xy 36.781952 -398.63203) (xy 36.789714 -398.578046)
			(xy 36.805081 -398.525717) (xy 36.827739 -398.476107) (xy 36.857227 -398.430227) (xy 36.892945 -398.389011)
			(xy 36.934165 -398.353298) (xy 36.980049 -398.323816) (xy 37.029662 -398.301164) (xy 37.081993 -398.285804)
			(xy 37.135978 -398.278048) (xy 37.163248 -398.277588) (xy 38.026848 -398.277588) (xy 38.054119 -398.277978)
			(xy 38.108104 -398.285746) (xy 38.160435 -398.301118) (xy 38.210045 -398.323779) (xy 38.255926 -398.353271)
			(xy 38.297144 -398.38899) (xy 38.332858 -398.430212) (xy 38.362344 -398.476097) (xy 38.384999 -398.52571)
			(xy 38.400364 -398.578043) (xy 38.408126 -398.632029) (xy 38.408126 -398.686571) (xy 38.400364 -398.740557)
			(xy 38.384999 -398.79289) (xy 38.38214 -398.799152) (xy 42.10455 -398.799152) (xy 42.10455 -398.744648)
			(xy 42.112306 -398.6907) (xy 42.12766 -398.638404) (xy 42.150301 -398.588826) (xy 42.179766 -398.542974)
			(xy 42.215456 -398.501781) (xy 42.256645 -398.466087) (xy 42.302494 -398.436618) (xy 42.35207 -398.413973)
			(xy 42.404365 -398.398614) (xy 42.458312 -398.390852) (xy 42.485564 -398.390364) (xy 43.349164 -398.390364)
			(xy 43.376417 -398.390881) (xy 43.430367 -398.398633) (xy 43.482666 -398.413985) (xy 43.532247 -398.436624)
			(xy 43.578101 -398.466088) (xy 43.619295 -398.50178) (xy 43.65499 -398.54297) (xy 43.684459 -398.588822)
			(xy 43.707103 -398.638401) (xy 43.722459 -398.690697) (xy 43.730217 -398.744648) (xy 43.730217 -398.799152)
			(xy 43.722459 -398.853103) (xy 43.707103 -398.9054) (xy 43.684459 -398.954978) (xy 43.65499 -399.00083)
			(xy 43.619295 -399.04202) (xy 43.578101 -399.077712) (xy 43.532247 -399.107176) (xy 43.482666 -399.129815)
			(xy 43.430367 -399.145167) (xy 43.376417 -399.152919) (xy 43.349164 -399.15338) (xy 42.485564 -399.15338)
			(xy 42.458312 -399.152948) (xy 42.404365 -399.145186) (xy 42.35207 -399.129827) (xy 42.302494 -399.107182)
			(xy 42.256645 -399.077713) (xy 42.215456 -399.042019) (xy 42.179766 -399.000826) (xy 42.150301 -398.954974)
			(xy 42.12766 -398.905396) (xy 42.112306 -398.8531) (xy 42.10455 -398.799152) (xy 38.38214 -398.799152)
			(xy 38.362344 -398.842503) (xy 38.332858 -398.888388) (xy 38.297144 -398.92961) (xy 38.255926 -398.965329)
			(xy 38.210045 -398.994821) (xy 38.160435 -399.017482) (xy 38.108104 -399.032854) (xy 38.054119 -399.040622)
			(xy 38.026848 -399.041112) (xy 37.163248 -399.041112) (xy 37.135978 -399.040552) (xy 37.081993 -399.032796)
			(xy 37.029662 -399.017436) (xy 36.980049 -398.994784) (xy 36.934165 -398.965302) (xy 36.892945 -398.929589)
			(xy 36.857227 -398.888373) (xy 36.827739 -398.842493) (xy 36.805081 -398.792883) (xy 36.789714 -398.740554)
			(xy 36.781952 -398.68657) (xy 2.509012 -398.68657) (xy 2.509012 -399.443249) (xy 18.470394 -399.443249)
			(xy 18.470394 -399.388751) (xy 18.47815 -399.334808) (xy 18.493503 -399.282518) (xy 18.516141 -399.232945)
			(xy 18.545603 -399.187098) (xy 18.58129 -399.14591) (xy 18.622475 -399.11022) (xy 18.66832 -399.080754)
			(xy 18.717892 -399.058112) (xy 18.770181 -399.042756) (xy 18.824123 -399.034996) (xy 18.851372 -399.034508)
			(xy 19.714972 -399.034508) (xy 19.742227 -399.034937) (xy 19.796184 -399.042691) (xy 19.848487 -399.058045)
			(xy 19.898073 -399.080687) (xy 19.943931 -399.110156) (xy 19.985129 -399.145851) (xy 20.020827 -399.187046)
			(xy 20.050299 -399.232903) (xy 20.072945 -399.282487) (xy 20.088303 -399.334789) (xy 20.096061 -399.388745)
			(xy 20.096061 -399.443255) (xy 20.088303 -399.497211) (xy 20.072945 -399.549513) (xy 20.050299 -399.599097)
			(xy 20.020828 -399.644954) (xy 19.985129 -399.686149) (xy 19.943931 -399.721844) (xy 19.898073 -399.751313)
			(xy 19.848487 -399.773955) (xy 19.796184 -399.789309) (xy 19.742227 -399.797063) (xy 19.714972 -399.797524)
			(xy 18.851372 -399.797524) (xy 18.824123 -399.797004) (xy 18.770181 -399.789244) (xy 18.717892 -399.773888)
			(xy 18.66832 -399.751246) (xy 18.622475 -399.72178) (xy 18.58129 -399.68609) (xy 18.545603 -399.644902)
			(xy 18.516141 -399.599055) (xy 18.493503 -399.549482) (xy 18.47815 -399.497192) (xy 18.470394 -399.443249)
			(xy 2.509012 -399.443249) (xy 2.509012 -400.459248) (xy 25.590794 -400.459248) (xy 25.590794 -400.404752)
			(xy 25.598549 -400.350811) (xy 25.613901 -400.298522) (xy 25.636538 -400.24895) (xy 25.665999 -400.203104)
			(xy 25.701684 -400.161916) (xy 25.742867 -400.126226) (xy 25.788709 -400.09676) (xy 25.838279 -400.074117)
			(xy 25.890566 -400.058759) (xy 25.944506 -400.050997) (xy 25.971754 -400.050508) (xy 26.835354 -400.050508)
			(xy 26.86261 -400.050936) (xy 26.916568 -400.058688) (xy 26.968874 -400.07404) (xy 27.018462 -400.096681)
			(xy 27.064323 -400.126149) (xy 27.105523 -400.161845) (xy 27.141223 -400.20304) (xy 27.170697 -400.248897)
			(xy 27.193343 -400.298483) (xy 27.208702 -400.350787) (xy 27.216461 -400.404744) (xy 27.216461 -400.459256)
			(xy 27.208702 -400.513213) (xy 27.193343 -400.565517) (xy 27.170697 -400.615103) (xy 27.141223 -400.66096)
			(xy 27.105523 -400.702155) (xy 27.064323 -400.737851) (xy 27.018462 -400.767319) (xy 26.968874 -400.78996)
			(xy 26.916568 -400.805312) (xy 26.86261 -400.813064) (xy 26.835354 -400.813524) (xy 25.971754 -400.813524)
			(xy 25.944506 -400.813003) (xy 25.890566 -400.805241) (xy 25.838279 -400.789883) (xy 25.788709 -400.76724)
			(xy 25.742867 -400.737774) (xy 25.701684 -400.702084) (xy 25.665999 -400.660896) (xy 25.636538 -400.61505)
			(xy 25.613901 -400.565478) (xy 25.598549 -400.513189) (xy 25.590794 -400.459248) (xy 2.509012 -400.459248)
			(xy 2.509012 -400.885453) (xy 47.598783 -400.885453) (xy 47.598783 -400.830947) (xy 47.606541 -400.776997)
			(xy 47.621898 -400.7247) (xy 47.644541 -400.675121) (xy 47.674011 -400.629269) (xy 47.709706 -400.588079)
			(xy 47.7509 -400.552388) (xy 47.796754 -400.522923) (xy 47.846336 -400.500284) (xy 47.898634 -400.484933)
			(xy 47.952585 -400.477181) (xy 47.979838 -400.47672) (xy 48.843438 -400.47672) (xy 48.870689 -400.477152)
			(xy 48.924637 -400.484914) (xy 48.976931 -400.500273) (xy 49.026507 -400.522918) (xy 49.072356 -400.552388)
			(xy 49.113545 -400.588082) (xy 49.149235 -400.629274) (xy 49.1787 -400.675126) (xy 49.20134 -400.724705)
			(xy 49.216694 -400.777) (xy 49.22445 -400.830948) (xy 49.22445 -400.885448) (xy 50.662106 -400.885448)
			(xy 50.662106 -400.830952) (xy 50.669862 -400.77701) (xy 50.685214 -400.724721) (xy 50.707852 -400.675149)
			(xy 50.737314 -400.629303) (xy 50.773001 -400.588116) (xy 50.814185 -400.552427) (xy 50.86003 -400.522963)
			(xy 50.9096 -400.500322) (xy 50.961888 -400.484966) (xy 51.01583 -400.477208) (xy 51.043078 -400.47672)
			(xy 51.906678 -400.47672) (xy 51.933934 -400.477125) (xy 51.987891 -400.48488) (xy 52.040196 -400.500236)
			(xy 52.089782 -400.522879) (xy 52.135642 -400.552348) (xy 52.17684 -400.588045) (xy 52.212539 -400.629241)
			(xy 52.242011 -400.675098) (xy 52.264657 -400.724684) (xy 52.280015 -400.776987) (xy 52.287773 -400.830944)
			(xy 52.287773 -400.885452) (xy 53.725283 -400.885452) (xy 53.725283 -400.830948) (xy 53.73304 -400.777)
			(xy 53.748396 -400.724704) (xy 53.771038 -400.675127) (xy 53.800506 -400.629276) (xy 53.836199 -400.588086)
			(xy 53.87739 -400.552395) (xy 53.923242 -400.52293) (xy 53.972821 -400.50029) (xy 54.025117 -400.484936)
			(xy 54.079066 -400.477182) (xy 54.106318 -400.47672) (xy 54.969918 -400.47672) (xy 54.99717 -400.477151)
			(xy 55.05112 -400.48491) (xy 55.103417 -400.500268) (xy 55.152995 -400.522912) (xy 55.198847 -400.552381)
			(xy 55.240038 -400.588075) (xy 55.27573 -400.629268) (xy 55.305197 -400.675121) (xy 55.327838 -400.7247)
			(xy 55.343194 -400.776997) (xy 55.35095 -400.830948) (xy 55.35095 -400.885447) (xy 56.788606 -400.885447)
			(xy 56.788606 -400.830953) (xy 56.796361 -400.777013) (xy 56.811713 -400.724725) (xy 56.834349 -400.675154)
			(xy 56.863809 -400.629309) (xy 56.899494 -400.588123) (xy 56.940676 -400.552435) (xy 56.986518 -400.522969)
			(xy 57.036086 -400.500327) (xy 57.088372 -400.48497) (xy 57.142311 -400.477209) (xy 57.169558 -400.47672)
			(xy 58.033158 -400.47672) (xy 58.060415 -400.477124) (xy 58.114374 -400.484877) (xy 58.166681 -400.50023)
			(xy 58.21627 -400.522872) (xy 58.262132 -400.552341) (xy 58.303333 -400.588037) (xy 58.339034 -400.629234)
			(xy 58.368508 -400.675093) (xy 58.391155 -400.724679) (xy 58.406514 -400.776985) (xy 58.414273 -400.830943)
			(xy 58.414273 -400.885449) (xy 59.851806 -400.885449) (xy 59.851806 -400.830951) (xy 59.859562 -400.777007)
			(xy 59.874916 -400.724717) (xy 59.897555 -400.675143) (xy 59.927019 -400.629296) (xy 59.962708 -400.588109)
			(xy 60.003895 -400.55242) (xy 60.049742 -400.522956) (xy 60.099315 -400.500317) (xy 60.151605 -400.484963)
			(xy 60.205549 -400.477206) (xy 60.232798 -400.47672) (xy 61.096398 -400.47672) (xy 61.123653 -400.477127)
			(xy 61.177608 -400.484884) (xy 61.22991 -400.500241) (xy 61.279494 -400.522885) (xy 61.325351 -400.552355)
			(xy 61.366547 -400.588052) (xy 61.402243 -400.629247) (xy 61.431714 -400.675104) (xy 61.454358 -400.724688)
			(xy 61.469715 -400.77699) (xy 61.477473 -400.830945) (xy 61.477473 -400.885453) (xy 62.914983 -400.885453)
			(xy 62.914983 -400.830947) (xy 62.922741 -400.776997) (xy 62.938098 -400.7247) (xy 62.960741 -400.675121)
			(xy 62.990211 -400.629269) (xy 63.025906 -400.588079) (xy 63.0671 -400.552388) (xy 63.112954 -400.522923)
			(xy 63.162536 -400.500284) (xy 63.214834 -400.484933) (xy 63.268785 -400.477181) (xy 63.296038 -400.47672)
			(xy 64.159638 -400.47672) (xy 64.186889 -400.477152) (xy 64.240837 -400.484914) (xy 64.293131 -400.500273)
			(xy 64.342707 -400.522918) (xy 64.388556 -400.552388) (xy 64.429745 -400.588082) (xy 64.465435 -400.629274)
			(xy 64.4949 -400.675126) (xy 64.51754 -400.724705) (xy 64.532894 -400.777) (xy 64.54065 -400.830948)
			(xy 64.54065 -400.885448) (xy 65.978306 -400.885448) (xy 65.978306 -400.830952) (xy 65.986062 -400.77701)
			(xy 66.001414 -400.724721) (xy 66.024052 -400.675149) (xy 66.053514 -400.629303) (xy 66.089201 -400.588116)
			(xy 66.130385 -400.552427) (xy 66.17623 -400.522963) (xy 66.2258 -400.500322) (xy 66.278088 -400.484966)
			(xy 66.33203 -400.477208) (xy 66.359278 -400.47672) (xy 67.222878 -400.47672) (xy 67.250134 -400.477125)
			(xy 67.304091 -400.48488) (xy 67.356396 -400.500236) (xy 67.405982 -400.522879) (xy 67.451842 -400.552348)
			(xy 67.49304 -400.588045) (xy 67.528739 -400.629241) (xy 67.558211 -400.675098) (xy 67.580857 -400.724684)
			(xy 67.596215 -400.776987) (xy 67.603973 -400.830944) (xy 67.603973 -400.885452) (xy 69.041483 -400.885452)
			(xy 69.041483 -400.830948) (xy 69.04924 -400.777) (xy 69.064596 -400.724704) (xy 69.087238 -400.675127)
			(xy 69.116706 -400.629276) (xy 69.152399 -400.588086) (xy 69.19359 -400.552395) (xy 69.239442 -400.52293)
			(xy 69.289021 -400.50029) (xy 69.341317 -400.484936) (xy 69.395266 -400.477182) (xy 69.422518 -400.47672)
			(xy 70.286118 -400.47672) (xy 70.31337 -400.477151) (xy 70.36732 -400.48491) (xy 70.419617 -400.500268)
			(xy 70.469195 -400.522912) (xy 70.515047 -400.552381) (xy 70.556238 -400.588075) (xy 70.59193 -400.629268)
			(xy 70.621397 -400.675121) (xy 70.644038 -400.7247) (xy 70.659394 -400.776997) (xy 70.66715 -400.830948)
			(xy 70.66715 -400.885447) (xy 72.104806 -400.885447) (xy 72.104806 -400.830953) (xy 72.112561 -400.777013)
			(xy 72.127913 -400.724725) (xy 72.150549 -400.675154) (xy 72.180009 -400.629309) (xy 72.215694 -400.588123)
			(xy 72.256876 -400.552435) (xy 72.302718 -400.522969) (xy 72.352286 -400.500327) (xy 72.404572 -400.48497)
			(xy 72.458511 -400.477209) (xy 72.485758 -400.47672) (xy 73.349358 -400.47672) (xy 73.376615 -400.477124)
			(xy 73.430574 -400.484877) (xy 73.482881 -400.50023) (xy 73.53247 -400.522872) (xy 73.578332 -400.552341)
			(xy 73.619533 -400.588037) (xy 73.655234 -400.629234) (xy 73.684708 -400.675093) (xy 73.707355 -400.724679)
			(xy 73.722714 -400.776985) (xy 73.730473 -400.830943) (xy 73.730473 -400.885449) (xy 75.168006 -400.885449)
			(xy 75.168006 -400.830951) (xy 75.175762 -400.777007) (xy 75.191116 -400.724717) (xy 75.213755 -400.675143)
			(xy 75.243219 -400.629296) (xy 75.278908 -400.588109) (xy 75.320095 -400.55242) (xy 75.365942 -400.522956)
			(xy 75.415515 -400.500317) (xy 75.467805 -400.484963) (xy 75.521749 -400.477206) (xy 75.548998 -400.47672)
			(xy 76.412598 -400.47672) (xy 76.439853 -400.477127) (xy 76.493808 -400.484884) (xy 76.54611 -400.500241)
			(xy 76.595694 -400.522885) (xy 76.641551 -400.552355) (xy 76.682747 -400.588052) (xy 76.718443 -400.629247)
			(xy 76.747914 -400.675104) (xy 76.770558 -400.724688) (xy 76.785915 -400.77699) (xy 76.793673 -400.830945)
			(xy 76.793673 -400.885453) (xy 78.231183 -400.885453) (xy 78.231183 -400.830947) (xy 78.238941 -400.776997)
			(xy 78.254298 -400.7247) (xy 78.276941 -400.675121) (xy 78.306411 -400.629269) (xy 78.342106 -400.588079)
			(xy 78.3833 -400.552388) (xy 78.429154 -400.522923) (xy 78.478736 -400.500284) (xy 78.531034 -400.484933)
			(xy 78.584985 -400.477181) (xy 78.612238 -400.47672) (xy 79.475838 -400.47672) (xy 79.503089 -400.477152)
			(xy 79.557037 -400.484914) (xy 79.609331 -400.500273) (xy 79.658907 -400.522918) (xy 79.704756 -400.552388)
			(xy 79.745945 -400.588082) (xy 79.781635 -400.629274) (xy 79.8111 -400.675126) (xy 79.83374 -400.724705)
			(xy 79.849094 -400.777) (xy 79.85685 -400.830948) (xy 79.85685 -400.885448) (xy 81.294506 -400.885448)
			(xy 81.294506 -400.830952) (xy 81.302262 -400.77701) (xy 81.317614 -400.724721) (xy 81.340252 -400.675149)
			(xy 81.369714 -400.629303) (xy 81.405401 -400.588116) (xy 81.446585 -400.552427) (xy 81.49243 -400.522963)
			(xy 81.542 -400.500322) (xy 81.594288 -400.484966) (xy 81.64823 -400.477208) (xy 81.675478 -400.47672)
			(xy 82.539078 -400.47672) (xy 82.566334 -400.477125) (xy 82.620291 -400.48488) (xy 82.672596 -400.500236)
			(xy 82.722182 -400.522879) (xy 82.768042 -400.552348) (xy 82.80924 -400.588045) (xy 82.844939 -400.629241)
			(xy 82.874411 -400.675098) (xy 82.897057 -400.724684) (xy 82.912415 -400.776987) (xy 82.920173 -400.830944)
			(xy 82.920173 -400.885452) (xy 84.357683 -400.885452) (xy 84.357683 -400.830948) (xy 84.36544 -400.777)
			(xy 84.380796 -400.724704) (xy 84.403438 -400.675127) (xy 84.432906 -400.629276) (xy 84.468599 -400.588086)
			(xy 84.50979 -400.552395) (xy 84.555642 -400.52293) (xy 84.605221 -400.50029) (xy 84.657517 -400.484936)
			(xy 84.711466 -400.477182) (xy 84.738718 -400.47672) (xy 85.602318 -400.47672) (xy 85.62957 -400.477151)
			(xy 85.68352 -400.48491) (xy 85.735817 -400.500268) (xy 85.785395 -400.522912) (xy 85.831247 -400.552381)
			(xy 85.872438 -400.588075) (xy 85.90813 -400.629268) (xy 85.937597 -400.675121) (xy 85.960238 -400.7247)
			(xy 85.975594 -400.776997) (xy 85.98335 -400.830948) (xy 85.98335 -400.885447) (xy 87.421006 -400.885447)
			(xy 87.421006 -400.830953) (xy 87.428761 -400.777013) (xy 87.444113 -400.724725) (xy 87.466749 -400.675154)
			(xy 87.496209 -400.629309) (xy 87.531894 -400.588123) (xy 87.573076 -400.552435) (xy 87.618918 -400.522969)
			(xy 87.668486 -400.500327) (xy 87.720772 -400.48497) (xy 87.774711 -400.477209) (xy 87.801958 -400.47672)
			(xy 88.665558 -400.47672) (xy 88.692815 -400.477124) (xy 88.746774 -400.484877) (xy 88.799081 -400.50023)
			(xy 88.84867 -400.522872) (xy 88.894532 -400.552341) (xy 88.935733 -400.588037) (xy 88.971434 -400.629234)
			(xy 89.000908 -400.675093) (xy 89.023555 -400.724679) (xy 89.038914 -400.776985) (xy 89.046673 -400.830943)
			(xy 89.046673 -400.885449) (xy 90.484206 -400.885449) (xy 90.484206 -400.830951) (xy 90.491962 -400.777007)
			(xy 90.507316 -400.724717) (xy 90.529955 -400.675143) (xy 90.559419 -400.629296) (xy 90.595108 -400.588109)
			(xy 90.636295 -400.55242) (xy 90.682142 -400.522956) (xy 90.731715 -400.500317) (xy 90.784005 -400.484963)
			(xy 90.837949 -400.477206) (xy 90.865198 -400.47672) (xy 91.728798 -400.47672) (xy 91.756053 -400.477127)
			(xy 91.810008 -400.484884) (xy 91.86231 -400.500241) (xy 91.911894 -400.522885) (xy 91.957751 -400.552355)
			(xy 91.998947 -400.588052) (xy 92.034643 -400.629247) (xy 92.064114 -400.675104) (xy 92.086758 -400.724688)
			(xy 92.102115 -400.77699) (xy 92.109873 -400.830945) (xy 92.109873 -400.885453) (xy 93.547383 -400.885453)
			(xy 93.547383 -400.830947) (xy 93.555141 -400.776997) (xy 93.570498 -400.7247) (xy 93.593141 -400.675121)
			(xy 93.622611 -400.629269) (xy 93.658306 -400.588079) (xy 93.6995 -400.552388) (xy 93.745354 -400.522923)
			(xy 93.794936 -400.500284) (xy 93.847234 -400.484933) (xy 93.901185 -400.477181) (xy 93.928438 -400.47672)
			(xy 94.792038 -400.47672) (xy 94.819289 -400.477152) (xy 94.873237 -400.484914) (xy 94.925531 -400.500273)
			(xy 94.975107 -400.522918) (xy 95.020956 -400.552388) (xy 95.062145 -400.588082) (xy 95.097835 -400.629274)
			(xy 95.1273 -400.675126) (xy 95.14994 -400.724705) (xy 95.165294 -400.777) (xy 95.17305 -400.830948)
			(xy 95.17305 -400.885447) (xy 119.774006 -400.885447) (xy 119.774006 -400.830953) (xy 119.781761 -400.777013)
			(xy 119.797112 -400.724726) (xy 119.819749 -400.675156) (xy 119.849208 -400.629311) (xy 119.884892 -400.588125)
			(xy 119.926074 -400.552436) (xy 119.971915 -400.522971) (xy 120.021483 -400.500329) (xy 120.073768 -400.484971)
			(xy 120.127707 -400.477209) (xy 120.154954 -400.47672) (xy 121.018554 -400.47672) (xy 121.045811 -400.477124)
			(xy 121.099771 -400.484876) (xy 121.152078 -400.500229) (xy 121.201668 -400.522871) (xy 121.24753 -400.55234)
			(xy 121.288731 -400.588036) (xy 121.324433 -400.629233) (xy 121.353907 -400.675092) (xy 121.376555 -400.724679)
			(xy 121.391914 -400.776984) (xy 121.399673 -400.830943) (xy 121.399673 -400.885449) (xy 122.837206 -400.885449)
			(xy 122.837206 -400.830951) (xy 122.844962 -400.777008) (xy 122.860316 -400.724717) (xy 122.882955 -400.675144)
			(xy 122.912418 -400.629298) (xy 122.948106 -400.588111) (xy 122.989293 -400.552422) (xy 123.035139 -400.522958)
			(xy 123.084712 -400.500318) (xy 123.137002 -400.484963) (xy 123.190945 -400.477207) (xy 123.218194 -400.47672)
			(xy 124.081794 -400.47672) (xy 124.109049 -400.477127) (xy 124.163005 -400.484883) (xy 124.215307 -400.50024)
			(xy 124.264892 -400.522884) (xy 124.310749 -400.552354) (xy 124.351946 -400.58805) (xy 124.387643 -400.629246)
			(xy 124.417113 -400.675103) (xy 124.439758 -400.724687) (xy 124.455115 -400.776989) (xy 124.462873 -400.830945)
			(xy 124.462873 -400.885452) (xy 125.900383 -400.885452) (xy 125.900383 -400.830948) (xy 125.908141 -400.776998)
			(xy 125.923497 -400.724701) (xy 125.946141 -400.675122) (xy 125.97561 -400.629271) (xy 126.011304 -400.58808)
			(xy 126.052498 -400.552389) (xy 126.098352 -400.522924) (xy 126.147933 -400.500285) (xy 126.200231 -400.484933)
			(xy 126.254182 -400.477181) (xy 126.281434 -400.47672) (xy 127.145034 -400.47672) (xy 127.172286 -400.477152)
			(xy 127.226234 -400.484913) (xy 127.278528 -400.500272) (xy 127.328105 -400.522917) (xy 127.373954 -400.552386)
			(xy 127.415143 -400.588081) (xy 127.450834 -400.629273) (xy 127.480299 -400.675125) (xy 127.50294 -400.724704)
			(xy 127.518294 -400.777) (xy 127.52605 -400.830948) (xy 127.52605 -400.885448) (xy 128.963706 -400.885448)
			(xy 128.963706 -400.830952) (xy 128.971461 -400.777011) (xy 128.986814 -400.724722) (xy 129.009452 -400.67515)
			(xy 129.038913 -400.629304) (xy 129.074599 -400.588118) (xy 129.115783 -400.552429) (xy 129.161627 -400.522964)
			(xy 129.211197 -400.500323) (xy 129.263485 -400.484967) (xy 129.317426 -400.477208) (xy 129.344674 -400.47672)
			(xy 130.208274 -400.47672) (xy 130.23553 -400.477125) (xy 130.289488 -400.48488) (xy 130.341793 -400.500235)
			(xy 130.39138 -400.522877) (xy 130.43724 -400.552347) (xy 130.478438 -400.588043) (xy 130.514138 -400.62924)
			(xy 130.54361 -400.675097) (xy 130.566256 -400.724683) (xy 130.581615 -400.776987) (xy 130.589373 -400.830944)
			(xy 130.589373 -400.885451) (xy 132.026883 -400.885451) (xy 132.026883 -400.830949) (xy 132.03464 -400.777)
			(xy 132.049996 -400.724705) (xy 132.072638 -400.675128) (xy 132.102105 -400.629277) (xy 132.137797 -400.588087)
			(xy 132.178989 -400.552396) (xy 132.22484 -400.522931) (xy 132.274418 -400.500291) (xy 132.326714 -400.484937)
			(xy 132.380662 -400.477182) (xy 132.407914 -400.47672) (xy 133.271514 -400.47672) (xy 133.298767 -400.477151)
			(xy 133.352717 -400.48491) (xy 133.405014 -400.500267) (xy 133.454593 -400.522911) (xy 133.500445 -400.552379)
			(xy 133.541636 -400.588074) (xy 133.577329 -400.629266) (xy 133.606796 -400.67512) (xy 133.629438 -400.724699)
			(xy 133.644793 -400.776997) (xy 133.65255 -400.830947) (xy 133.65255 -400.885447) (xy 135.090206 -400.885447)
			(xy 135.090206 -400.830953) (xy 135.097961 -400.777013) (xy 135.113312 -400.724726) (xy 135.135949 -400.675156)
			(xy 135.165408 -400.629311) (xy 135.201092 -400.588125) (xy 135.242274 -400.552436) (xy 135.288115 -400.522971)
			(xy 135.337683 -400.500329) (xy 135.389968 -400.484971) (xy 135.443907 -400.477209) (xy 135.471154 -400.47672)
			(xy 136.334754 -400.47672) (xy 136.362011 -400.477124) (xy 136.415971 -400.484876) (xy 136.468278 -400.500229)
			(xy 136.517868 -400.522871) (xy 136.56373 -400.55234) (xy 136.604931 -400.588036) (xy 136.640633 -400.629233)
			(xy 136.670107 -400.675092) (xy 136.692755 -400.724679) (xy 136.708114 -400.776984) (xy 136.715873 -400.830943)
			(xy 136.715873 -400.885449) (xy 138.153406 -400.885449) (xy 138.153406 -400.830951) (xy 138.161162 -400.777008)
			(xy 138.176516 -400.724717) (xy 138.199155 -400.675144) (xy 138.228618 -400.629298) (xy 138.264306 -400.588111)
			(xy 138.305493 -400.552422) (xy 138.351339 -400.522958) (xy 138.400912 -400.500318) (xy 138.453202 -400.484963)
			(xy 138.507145 -400.477207) (xy 138.534394 -400.47672) (xy 139.397994 -400.47672) (xy 139.425249 -400.477127)
			(xy 139.479205 -400.484883) (xy 139.531507 -400.50024) (xy 139.581092 -400.522884) (xy 139.626949 -400.552354)
			(xy 139.668146 -400.58805) (xy 139.703843 -400.629246) (xy 139.733313 -400.675103) (xy 139.755958 -400.724687)
			(xy 139.771315 -400.776989) (xy 139.779073 -400.830945) (xy 139.779073 -400.885452) (xy 141.216583 -400.885452)
			(xy 141.216583 -400.830948) (xy 141.224341 -400.776998) (xy 141.239697 -400.724701) (xy 141.262341 -400.675122)
			(xy 141.29181 -400.629271) (xy 141.327504 -400.58808) (xy 141.368698 -400.552389) (xy 141.414552 -400.522924)
			(xy 141.464133 -400.500285) (xy 141.516431 -400.484933) (xy 141.570382 -400.477181) (xy 141.597634 -400.47672)
			(xy 142.461234 -400.47672) (xy 142.488486 -400.477152) (xy 142.542434 -400.484913) (xy 142.594728 -400.500272)
			(xy 142.644305 -400.522917) (xy 142.690154 -400.552386) (xy 142.731343 -400.588081) (xy 142.767034 -400.629273)
			(xy 142.796499 -400.675125) (xy 142.81914 -400.724704) (xy 142.834494 -400.777) (xy 142.84225 -400.830948)
			(xy 142.84225 -400.885448) (xy 144.279906 -400.885448) (xy 144.279906 -400.830952) (xy 144.287661 -400.777011)
			(xy 144.303014 -400.724722) (xy 144.325652 -400.67515) (xy 144.355113 -400.629304) (xy 144.390799 -400.588118)
			(xy 144.431983 -400.552429) (xy 144.477827 -400.522964) (xy 144.527397 -400.500323) (xy 144.579685 -400.484967)
			(xy 144.633626 -400.477208) (xy 144.660874 -400.47672) (xy 145.524474 -400.47672) (xy 145.55173 -400.477125)
			(xy 145.605688 -400.48488) (xy 145.657993 -400.500235) (xy 145.70758 -400.522877) (xy 145.75344 -400.552347)
			(xy 145.794638 -400.588043) (xy 145.830338 -400.62924) (xy 145.85981 -400.675097) (xy 145.882456 -400.724683)
			(xy 145.897815 -400.776987) (xy 145.905573 -400.830944) (xy 145.905573 -400.885451) (xy 147.343083 -400.885451)
			(xy 147.343083 -400.830949) (xy 147.35084 -400.777) (xy 147.366196 -400.724705) (xy 147.388838 -400.675128)
			(xy 147.418305 -400.629277) (xy 147.453997 -400.588087) (xy 147.495189 -400.552396) (xy 147.54104 -400.522931)
			(xy 147.590618 -400.500291) (xy 147.642914 -400.484937) (xy 147.696862 -400.477182) (xy 147.724114 -400.47672)
			(xy 148.587714 -400.47672) (xy 148.614967 -400.477151) (xy 148.668917 -400.48491) (xy 148.721214 -400.500267)
			(xy 148.770793 -400.522911) (xy 148.816645 -400.552379) (xy 148.857836 -400.588074) (xy 148.893529 -400.629266)
			(xy 148.922996 -400.67512) (xy 148.945638 -400.724699) (xy 148.960993 -400.776997) (xy 148.96875 -400.830947)
			(xy 148.96875 -400.885447) (xy 150.406406 -400.885447) (xy 150.406406 -400.830953) (xy 150.414161 -400.777013)
			(xy 150.429512 -400.724726) (xy 150.452149 -400.675156) (xy 150.481608 -400.629311) (xy 150.517292 -400.588125)
			(xy 150.558474 -400.552436) (xy 150.604315 -400.522971) (xy 150.653883 -400.500329) (xy 150.706168 -400.484971)
			(xy 150.760107 -400.477209) (xy 150.787354 -400.47672) (xy 151.650954 -400.47672) (xy 151.678211 -400.477124)
			(xy 151.732171 -400.484876) (xy 151.784478 -400.500229) (xy 151.834068 -400.522871) (xy 151.87993 -400.55234)
			(xy 151.921131 -400.588036) (xy 151.956833 -400.629233) (xy 151.986307 -400.675092) (xy 152.008955 -400.724679)
			(xy 152.024314 -400.776984) (xy 152.032073 -400.830943) (xy 152.032073 -400.885449) (xy 153.469606 -400.885449)
			(xy 153.469606 -400.830951) (xy 153.477362 -400.777008) (xy 153.492716 -400.724717) (xy 153.515355 -400.675144)
			(xy 153.544818 -400.629298) (xy 153.580506 -400.588111) (xy 153.621693 -400.552422) (xy 153.667539 -400.522958)
			(xy 153.717112 -400.500318) (xy 153.769402 -400.484963) (xy 153.823345 -400.477207) (xy 153.850594 -400.47672)
			(xy 154.714194 -400.47672) (xy 154.741449 -400.477127) (xy 154.795405 -400.484883) (xy 154.847707 -400.50024)
			(xy 154.897292 -400.522884) (xy 154.943149 -400.552354) (xy 154.984346 -400.58805) (xy 155.020043 -400.629246)
			(xy 155.049513 -400.675103) (xy 155.072158 -400.724687) (xy 155.087515 -400.776989) (xy 155.095273 -400.830945)
			(xy 155.095273 -400.885452) (xy 156.532783 -400.885452) (xy 156.532783 -400.830948) (xy 156.540541 -400.776998)
			(xy 156.555897 -400.724701) (xy 156.578541 -400.675122) (xy 156.60801 -400.629271) (xy 156.643704 -400.58808)
			(xy 156.684898 -400.552389) (xy 156.730752 -400.522924) (xy 156.780333 -400.500285) (xy 156.832631 -400.484933)
			(xy 156.886582 -400.477181) (xy 156.913834 -400.47672) (xy 157.777434 -400.47672) (xy 157.804686 -400.477152)
			(xy 157.858634 -400.484913) (xy 157.910928 -400.500272) (xy 157.960505 -400.522917) (xy 158.006354 -400.552386)
			(xy 158.047543 -400.588081) (xy 158.083234 -400.629273) (xy 158.112699 -400.675125) (xy 158.13534 -400.724704)
			(xy 158.150694 -400.777) (xy 158.15845 -400.830948) (xy 158.15845 -400.885448) (xy 159.596106 -400.885448)
			(xy 159.596106 -400.830952) (xy 159.603861 -400.777011) (xy 159.619214 -400.724722) (xy 159.641852 -400.67515)
			(xy 159.671313 -400.629304) (xy 159.706999 -400.588118) (xy 159.748183 -400.552429) (xy 159.794027 -400.522964)
			(xy 159.843597 -400.500323) (xy 159.895885 -400.484967) (xy 159.949826 -400.477208) (xy 159.977074 -400.47672)
			(xy 160.840674 -400.47672) (xy 160.86793 -400.477125) (xy 160.921888 -400.48488) (xy 160.974193 -400.500235)
			(xy 161.02378 -400.522877) (xy 161.06964 -400.552347) (xy 161.110838 -400.588043) (xy 161.146538 -400.62924)
			(xy 161.17601 -400.675097) (xy 161.198656 -400.724683) (xy 161.214015 -400.776987) (xy 161.221773 -400.830944)
			(xy 161.221773 -400.885451) (xy 162.659283 -400.885451) (xy 162.659283 -400.830949) (xy 162.66704 -400.777)
			(xy 162.682396 -400.724705) (xy 162.705038 -400.675128) (xy 162.734505 -400.629277) (xy 162.770197 -400.588087)
			(xy 162.811389 -400.552396) (xy 162.85724 -400.522931) (xy 162.906818 -400.500291) (xy 162.959114 -400.484937)
			(xy 163.013062 -400.477182) (xy 163.040314 -400.47672) (xy 163.903914 -400.47672) (xy 163.931167 -400.477151)
			(xy 163.985117 -400.48491) (xy 164.037414 -400.500267) (xy 164.086993 -400.522911) (xy 164.132845 -400.552379)
			(xy 164.174036 -400.588074) (xy 164.209729 -400.629266) (xy 164.239196 -400.67512) (xy 164.261838 -400.724699)
			(xy 164.277193 -400.776997) (xy 164.28495 -400.830947) (xy 164.28495 -400.885447) (xy 165.722606 -400.885447)
			(xy 165.722606 -400.830953) (xy 165.730361 -400.777013) (xy 165.745712 -400.724726) (xy 165.768349 -400.675156)
			(xy 165.797808 -400.629311) (xy 165.833492 -400.588125) (xy 165.874674 -400.552436) (xy 165.920515 -400.522971)
			(xy 165.970083 -400.500329) (xy 166.022368 -400.484971) (xy 166.076307 -400.477209) (xy 166.103554 -400.47672)
			(xy 166.967154 -400.47672) (xy 166.994411 -400.477124) (xy 167.048371 -400.484876) (xy 167.100678 -400.500229)
			(xy 167.150268 -400.522871) (xy 167.19613 -400.55234) (xy 167.237331 -400.588036) (xy 167.273033 -400.629233)
			(xy 167.302507 -400.675092) (xy 167.325155 -400.724679) (xy 167.340514 -400.776984) (xy 167.348273 -400.830943)
			(xy 167.348273 -400.885457) (xy 167.340514 -400.939416) (xy 167.325155 -400.991721) (xy 167.302507 -401.041308)
			(xy 167.273033 -401.087167) (xy 167.237331 -401.128364) (xy 167.19613 -401.16406) (xy 167.150268 -401.193529)
			(xy 167.100678 -401.216171) (xy 167.048371 -401.231524) (xy 166.994411 -401.239276) (xy 166.967154 -401.239736)
			(xy 166.103554 -401.239736) (xy 166.076307 -401.239191) (xy 166.022368 -401.231429) (xy 165.970083 -401.216071)
			(xy 165.920515 -401.193429) (xy 165.874674 -401.163964) (xy 165.833492 -401.128275) (xy 165.797808 -401.087089)
			(xy 165.768349 -401.041244) (xy 165.745712 -400.991674) (xy 165.730361 -400.939387) (xy 165.722606 -400.885447)
			(xy 164.28495 -400.885447) (xy 164.28495 -400.885453) (xy 164.277193 -400.939403) (xy 164.261838 -400.991701)
			(xy 164.239196 -401.04128) (xy 164.209729 -401.087134) (xy 164.174036 -401.128326) (xy 164.132845 -401.164021)
			(xy 164.086993 -401.193489) (xy 164.037414 -401.216133) (xy 163.985117 -401.23149) (xy 163.931167 -401.239249)
			(xy 163.903914 -401.239736) (xy 163.040314 -401.239736) (xy 163.013062 -401.239218) (xy 162.959114 -401.231463)
			(xy 162.906818 -401.216109) (xy 162.85724 -401.193469) (xy 162.811389 -401.164004) (xy 162.770197 -401.128313)
			(xy 162.734505 -401.087123) (xy 162.705038 -401.041272) (xy 162.682396 -400.991695) (xy 162.66704 -400.9394)
			(xy 162.659283 -400.885451) (xy 161.221773 -400.885451) (xy 161.221773 -400.885456) (xy 161.214015 -400.939413)
			(xy 161.198656 -400.991717) (xy 161.17601 -401.041303) (xy 161.146538 -401.08716) (xy 161.110838 -401.128357)
			(xy 161.06964 -401.164053) (xy 161.02378 -401.193523) (xy 160.974193 -401.216165) (xy 160.921888 -401.23152)
			(xy 160.86793 -401.239275) (xy 160.840674 -401.239736) (xy 159.977074 -401.239736) (xy 159.949826 -401.239192)
			(xy 159.895885 -401.231433) (xy 159.843597 -401.216077) (xy 159.794027 -401.193436) (xy 159.748183 -401.163971)
			(xy 159.706999 -401.128282) (xy 159.671313 -401.087096) (xy 159.641852 -401.04125) (xy 159.619214 -400.991678)
			(xy 159.603861 -400.939389) (xy 159.596106 -400.885448) (xy 158.15845 -400.885448) (xy 158.15845 -400.885452)
			(xy 158.150694 -400.9394) (xy 158.13534 -400.991696) (xy 158.112699 -401.041275) (xy 158.083234 -401.087127)
			(xy 158.047543 -401.128319) (xy 158.006354 -401.164014) (xy 157.960505 -401.193483) (xy 157.910928 -401.216128)
			(xy 157.858634 -401.231487) (xy 157.804686 -401.239248) (xy 157.777434 -401.239736) (xy 156.913834 -401.239736)
			(xy 156.886582 -401.239219) (xy 156.832631 -401.231467) (xy 156.780333 -401.216115) (xy 156.730752 -401.193476)
			(xy 156.684898 -401.164011) (xy 156.643704 -401.12832) (xy 156.60801 -401.087129) (xy 156.578541 -401.041278)
			(xy 156.555897 -400.991699) (xy 156.540541 -400.939402) (xy 156.532783 -400.885452) (xy 155.095273 -400.885452)
			(xy 155.095273 -400.885455) (xy 155.087515 -400.939411) (xy 155.072158 -400.991713) (xy 155.049513 -401.041297)
			(xy 155.020043 -401.087154) (xy 154.984346 -401.12835) (xy 154.943149 -401.164046) (xy 154.897292 -401.193516)
			(xy 154.847707 -401.21616) (xy 154.795405 -401.231517) (xy 154.741449 -401.239273) (xy 154.714194 -401.239736)
			(xy 153.850594 -401.239736) (xy 153.823345 -401.239193) (xy 153.769402 -401.231437) (xy 153.717112 -401.216082)
			(xy 153.667539 -401.193442) (xy 153.621693 -401.163978) (xy 153.580506 -401.128289) (xy 153.544818 -401.087102)
			(xy 153.515355 -401.041256) (xy 153.492716 -400.991683) (xy 153.477362 -400.939392) (xy 153.469606 -400.885449)
			(xy 152.032073 -400.885449) (xy 152.032073 -400.885457) (xy 152.024314 -400.939416) (xy 152.008955 -400.991721)
			(xy 151.986307 -401.041308) (xy 151.956833 -401.087167) (xy 151.921131 -401.128364) (xy 151.87993 -401.16406)
			(xy 151.834068 -401.193529) (xy 151.784478 -401.216171) (xy 151.732171 -401.231524) (xy 151.678211 -401.239276)
			(xy 151.650954 -401.239736) (xy 150.787354 -401.239736) (xy 150.760107 -401.239191) (xy 150.706168 -401.231429)
			(xy 150.653883 -401.216071) (xy 150.604315 -401.193429) (xy 150.558474 -401.163964) (xy 150.517292 -401.128275)
			(xy 150.481608 -401.087089) (xy 150.452149 -401.041244) (xy 150.429512 -400.991674) (xy 150.414161 -400.939387)
			(xy 150.406406 -400.885447) (xy 148.96875 -400.885447) (xy 148.96875 -400.885453) (xy 148.960993 -400.939403)
			(xy 148.945638 -400.991701) (xy 148.922996 -401.04128) (xy 148.893529 -401.087134) (xy 148.857836 -401.128326)
			(xy 148.816645 -401.164021) (xy 148.770793 -401.193489) (xy 148.721214 -401.216133) (xy 148.668917 -401.23149)
			(xy 148.614967 -401.239249) (xy 148.587714 -401.239736) (xy 147.724114 -401.239736) (xy 147.696862 -401.239218)
			(xy 147.642914 -401.231463) (xy 147.590618 -401.216109) (xy 147.54104 -401.193469) (xy 147.495189 -401.164004)
			(xy 147.453997 -401.128313) (xy 147.418305 -401.087123) (xy 147.388838 -401.041272) (xy 147.366196 -400.991695)
			(xy 147.35084 -400.9394) (xy 147.343083 -400.885451) (xy 145.905573 -400.885451) (xy 145.905573 -400.885456)
			(xy 145.897815 -400.939413) (xy 145.882456 -400.991717) (xy 145.85981 -401.041303) (xy 145.830338 -401.08716)
			(xy 145.794638 -401.128357) (xy 145.75344 -401.164053) (xy 145.70758 -401.193523) (xy 145.657993 -401.216165)
			(xy 145.605688 -401.23152) (xy 145.55173 -401.239275) (xy 145.524474 -401.239736) (xy 144.660874 -401.239736)
			(xy 144.633626 -401.239192) (xy 144.579685 -401.231433) (xy 144.527397 -401.216077) (xy 144.477827 -401.193436)
			(xy 144.431983 -401.163971) (xy 144.390799 -401.128282) (xy 144.355113 -401.087096) (xy 144.325652 -401.04125)
			(xy 144.303014 -400.991678) (xy 144.287661 -400.939389) (xy 144.279906 -400.885448) (xy 142.84225 -400.885448)
			(xy 142.84225 -400.885452) (xy 142.834494 -400.9394) (xy 142.81914 -400.991696) (xy 142.796499 -401.041275)
			(xy 142.767034 -401.087127) (xy 142.731343 -401.128319) (xy 142.690154 -401.164014) (xy 142.644305 -401.193483)
			(xy 142.594728 -401.216128) (xy 142.542434 -401.231487) (xy 142.488486 -401.239248) (xy 142.461234 -401.239736)
			(xy 141.597634 -401.239736) (xy 141.570382 -401.239219) (xy 141.516431 -401.231467) (xy 141.464133 -401.216115)
			(xy 141.414552 -401.193476) (xy 141.368698 -401.164011) (xy 141.327504 -401.12832) (xy 141.29181 -401.087129)
			(xy 141.262341 -401.041278) (xy 141.239697 -400.991699) (xy 141.224341 -400.939402) (xy 141.216583 -400.885452)
			(xy 139.779073 -400.885452) (xy 139.779073 -400.885455) (xy 139.771315 -400.939411) (xy 139.755958 -400.991713)
			(xy 139.733313 -401.041297) (xy 139.703843 -401.087154) (xy 139.668146 -401.12835) (xy 139.626949 -401.164046)
			(xy 139.581092 -401.193516) (xy 139.531507 -401.21616) (xy 139.479205 -401.231517) (xy 139.425249 -401.239273)
			(xy 139.397994 -401.239736) (xy 138.534394 -401.239736) (xy 138.507145 -401.239193) (xy 138.453202 -401.231437)
			(xy 138.400912 -401.216082) (xy 138.351339 -401.193442) (xy 138.305493 -401.163978) (xy 138.264306 -401.128289)
			(xy 138.228618 -401.087102) (xy 138.199155 -401.041256) (xy 138.176516 -400.991683) (xy 138.161162 -400.939392)
			(xy 138.153406 -400.885449) (xy 136.715873 -400.885449) (xy 136.715873 -400.885457) (xy 136.708114 -400.939416)
			(xy 136.692755 -400.991721) (xy 136.670107 -401.041308) (xy 136.640633 -401.087167) (xy 136.604931 -401.128364)
			(xy 136.56373 -401.16406) (xy 136.517868 -401.193529) (xy 136.468278 -401.216171) (xy 136.415971 -401.231524)
			(xy 136.362011 -401.239276) (xy 136.334754 -401.239736) (xy 135.471154 -401.239736) (xy 135.443907 -401.239191)
			(xy 135.389968 -401.231429) (xy 135.337683 -401.216071) (xy 135.288115 -401.193429) (xy 135.242274 -401.163964)
			(xy 135.201092 -401.128275) (xy 135.165408 -401.087089) (xy 135.135949 -401.041244) (xy 135.113312 -400.991674)
			(xy 135.097961 -400.939387) (xy 135.090206 -400.885447) (xy 133.65255 -400.885447) (xy 133.65255 -400.885453)
			(xy 133.644793 -400.939403) (xy 133.629438 -400.991701) (xy 133.606796 -401.04128) (xy 133.577329 -401.087134)
			(xy 133.541636 -401.128326) (xy 133.500445 -401.164021) (xy 133.454593 -401.193489) (xy 133.405014 -401.216133)
			(xy 133.352717 -401.23149) (xy 133.298767 -401.239249) (xy 133.271514 -401.239736) (xy 132.407914 -401.239736)
			(xy 132.380662 -401.239218) (xy 132.326714 -401.231463) (xy 132.274418 -401.216109) (xy 132.22484 -401.193469)
			(xy 132.178989 -401.164004) (xy 132.137797 -401.128313) (xy 132.102105 -401.087123) (xy 132.072638 -401.041272)
			(xy 132.049996 -400.991695) (xy 132.03464 -400.9394) (xy 132.026883 -400.885451) (xy 130.589373 -400.885451)
			(xy 130.589373 -400.885456) (xy 130.581615 -400.939413) (xy 130.566256 -400.991717) (xy 130.54361 -401.041303)
			(xy 130.514138 -401.08716) (xy 130.478438 -401.128357) (xy 130.43724 -401.164053) (xy 130.39138 -401.193523)
			(xy 130.341793 -401.216165) (xy 130.289488 -401.23152) (xy 130.23553 -401.239275) (xy 130.208274 -401.239736)
			(xy 129.344674 -401.239736) (xy 129.317426 -401.239192) (xy 129.263485 -401.231433) (xy 129.211197 -401.216077)
			(xy 129.161627 -401.193436) (xy 129.115783 -401.163971) (xy 129.074599 -401.128282) (xy 129.038913 -401.087096)
			(xy 129.009452 -401.04125) (xy 128.986814 -400.991678) (xy 128.971461 -400.939389) (xy 128.963706 -400.885448)
			(xy 127.52605 -400.885448) (xy 127.52605 -400.885452) (xy 127.518294 -400.9394) (xy 127.50294 -400.991696)
			(xy 127.480299 -401.041275) (xy 127.450834 -401.087127) (xy 127.415143 -401.128319) (xy 127.373954 -401.164014)
			(xy 127.328105 -401.193483) (xy 127.278528 -401.216128) (xy 127.226234 -401.231487) (xy 127.172286 -401.239248)
			(xy 127.145034 -401.239736) (xy 126.281434 -401.239736) (xy 126.254182 -401.239219) (xy 126.200231 -401.231467)
			(xy 126.147933 -401.216115) (xy 126.098352 -401.193476) (xy 126.052498 -401.164011) (xy 126.011304 -401.12832)
			(xy 125.97561 -401.087129) (xy 125.946141 -401.041278) (xy 125.923497 -400.991699) (xy 125.908141 -400.939402)
			(xy 125.900383 -400.885452) (xy 124.462873 -400.885452) (xy 124.462873 -400.885455) (xy 124.455115 -400.939411)
			(xy 124.439758 -400.991713) (xy 124.417113 -401.041297) (xy 124.387643 -401.087154) (xy 124.351946 -401.12835)
			(xy 124.310749 -401.164046) (xy 124.264892 -401.193516) (xy 124.215307 -401.21616) (xy 124.163005 -401.231517)
			(xy 124.109049 -401.239273) (xy 124.081794 -401.239736) (xy 123.218194 -401.239736) (xy 123.190945 -401.239193)
			(xy 123.137002 -401.231437) (xy 123.084712 -401.216082) (xy 123.035139 -401.193442) (xy 122.989293 -401.163978)
			(xy 122.948106 -401.128289) (xy 122.912418 -401.087102) (xy 122.882955 -401.041256) (xy 122.860316 -400.991683)
			(xy 122.844962 -400.939392) (xy 122.837206 -400.885449) (xy 121.399673 -400.885449) (xy 121.399673 -400.885457)
			(xy 121.391914 -400.939416) (xy 121.376555 -400.991721) (xy 121.353907 -401.041308) (xy 121.324433 -401.087167)
			(xy 121.288731 -401.128364) (xy 121.24753 -401.16406) (xy 121.201668 -401.193529) (xy 121.152078 -401.216171)
			(xy 121.099771 -401.231524) (xy 121.045811 -401.239276) (xy 121.018554 -401.239736) (xy 120.154954 -401.239736)
			(xy 120.127707 -401.239191) (xy 120.073768 -401.231429) (xy 120.021483 -401.216071) (xy 119.971915 -401.193429)
			(xy 119.926074 -401.163964) (xy 119.884892 -401.128275) (xy 119.849208 -401.087089) (xy 119.819749 -401.041244)
			(xy 119.797112 -400.991674) (xy 119.781761 -400.939387) (xy 119.774006 -400.885447) (xy 95.17305 -400.885447)
			(xy 95.17305 -400.885452) (xy 95.165294 -400.9394) (xy 95.14994 -400.991695) (xy 95.1273 -401.041274)
			(xy 95.097835 -401.087126) (xy 95.062145 -401.128318) (xy 95.020956 -401.164012) (xy 94.975107 -401.193482)
			(xy 94.925531 -401.216127) (xy 94.873237 -401.231486) (xy 94.819289 -401.239248) (xy 94.792038 -401.239736)
			(xy 93.928438 -401.239736) (xy 93.901185 -401.239219) (xy 93.847234 -401.231467) (xy 93.794936 -401.216116)
			(xy 93.745354 -401.193477) (xy 93.6995 -401.164012) (xy 93.658306 -401.128321) (xy 93.622611 -401.087131)
			(xy 93.593141 -401.041279) (xy 93.570498 -400.9917) (xy 93.555141 -400.939403) (xy 93.547383 -400.885453)
			(xy 92.109873 -400.885453) (xy 92.109873 -400.885455) (xy 92.102115 -400.93941) (xy 92.086758 -400.991712)
			(xy 92.064114 -401.041296) (xy 92.034643 -401.087153) (xy 91.998947 -401.128348) (xy 91.957751 -401.164045)
			(xy 91.911894 -401.193515) (xy 91.86231 -401.216159) (xy 91.810008 -401.231516) (xy 91.756053 -401.239273)
			(xy 91.728798 -401.239736) (xy 90.865198 -401.239736) (xy 90.837949 -401.239194) (xy 90.784005 -401.231437)
			(xy 90.731715 -401.216083) (xy 90.682142 -401.193444) (xy 90.636295 -401.16398) (xy 90.595108 -401.128291)
			(xy 90.559419 -401.087104) (xy 90.529955 -401.041257) (xy 90.507316 -400.991683) (xy 90.491962 -400.939393)
			(xy 90.484206 -400.885449) (xy 89.046673 -400.885449) (xy 89.046673 -400.885457) (xy 89.038914 -400.939415)
			(xy 89.023555 -400.991721) (xy 89.000908 -401.041307) (xy 88.971434 -401.087166) (xy 88.935733 -401.128363)
			(xy 88.894532 -401.164059) (xy 88.84867 -401.193528) (xy 88.799081 -401.21617) (xy 88.746774 -401.231523)
			(xy 88.692815 -401.239276) (xy 88.665558 -401.239736) (xy 87.801958 -401.239736) (xy 87.774711 -401.239191)
			(xy 87.720772 -401.23143) (xy 87.668486 -401.216073) (xy 87.618918 -401.193431) (xy 87.573076 -401.163965)
			(xy 87.531894 -401.128277) (xy 87.496209 -401.087091) (xy 87.466749 -401.041246) (xy 87.444113 -400.991675)
			(xy 87.428761 -400.939387) (xy 87.421006 -400.885447) (xy 85.98335 -400.885447) (xy 85.98335 -400.885452)
			(xy 85.975594 -400.939403) (xy 85.960238 -400.9917) (xy 85.937597 -401.041279) (xy 85.90813 -401.087132)
			(xy 85.872438 -401.128325) (xy 85.831247 -401.164019) (xy 85.785395 -401.193488) (xy 85.735817 -401.216132)
			(xy 85.68352 -401.23149) (xy 85.62957 -401.239249) (xy 85.602318 -401.239736) (xy 84.738718 -401.239736)
			(xy 84.711466 -401.239218) (xy 84.657517 -401.231464) (xy 84.605221 -401.21611) (xy 84.555642 -401.19347)
			(xy 84.50979 -401.164005) (xy 84.468599 -401.128314) (xy 84.432906 -401.087124) (xy 84.403438 -401.041273)
			(xy 84.380796 -400.991696) (xy 84.36544 -400.9394) (xy 84.357683 -400.885452) (xy 82.920173 -400.885452)
			(xy 82.920173 -400.885456) (xy 82.912415 -400.939413) (xy 82.897057 -400.991716) (xy 82.874411 -401.041302)
			(xy 82.844939 -401.087159) (xy 82.80924 -401.128355) (xy 82.768042 -401.164052) (xy 82.722182 -401.193521)
			(xy 82.672596 -401.216164) (xy 82.620291 -401.23152) (xy 82.566334 -401.239275) (xy 82.539078 -401.239736)
			(xy 81.675478 -401.239736) (xy 81.64823 -401.239192) (xy 81.594288 -401.231434) (xy 81.542 -401.216078)
			(xy 81.49243 -401.193437) (xy 81.446585 -401.163973) (xy 81.405401 -401.128284) (xy 81.369714 -401.087097)
			(xy 81.340252 -401.041251) (xy 81.317614 -400.991679) (xy 81.302262 -400.93939) (xy 81.294506 -400.885448)
			(xy 79.85685 -400.885448) (xy 79.85685 -400.885452) (xy 79.849094 -400.9394) (xy 79.83374 -400.991695)
			(xy 79.8111 -401.041274) (xy 79.781635 -401.087126) (xy 79.745945 -401.128318) (xy 79.704756 -401.164012)
			(xy 79.658907 -401.193482) (xy 79.609331 -401.216127) (xy 79.557037 -401.231486) (xy 79.503089 -401.239248)
			(xy 79.475838 -401.239736) (xy 78.612238 -401.239736) (xy 78.584985 -401.239219) (xy 78.531034 -401.231467)
			(xy 78.478736 -401.216116) (xy 78.429154 -401.193477) (xy 78.3833 -401.164012) (xy 78.342106 -401.128321)
			(xy 78.306411 -401.087131) (xy 78.276941 -401.041279) (xy 78.254298 -400.9917) (xy 78.238941 -400.939403)
			(xy 78.231183 -400.885453) (xy 76.793673 -400.885453) (xy 76.793673 -400.885455) (xy 76.785915 -400.93941)
			(xy 76.770558 -400.991712) (xy 76.747914 -401.041296) (xy 76.718443 -401.087153) (xy 76.682747 -401.128348)
			(xy 76.641551 -401.164045) (xy 76.595694 -401.193515) (xy 76.54611 -401.216159) (xy 76.493808 -401.231516)
			(xy 76.439853 -401.239273) (xy 76.412598 -401.239736) (xy 75.548998 -401.239736) (xy 75.521749 -401.239194)
			(xy 75.467805 -401.231437) (xy 75.415515 -401.216083) (xy 75.365942 -401.193444) (xy 75.320095 -401.16398)
			(xy 75.278908 -401.128291) (xy 75.243219 -401.087104) (xy 75.213755 -401.041257) (xy 75.191116 -400.991683)
			(xy 75.175762 -400.939393) (xy 75.168006 -400.885449) (xy 73.730473 -400.885449) (xy 73.730473 -400.885457)
			(xy 73.722714 -400.939415) (xy 73.707355 -400.991721) (xy 73.684708 -401.041307) (xy 73.655234 -401.087166)
			(xy 73.619533 -401.128363) (xy 73.578332 -401.164059) (xy 73.53247 -401.193528) (xy 73.482881 -401.21617)
			(xy 73.430574 -401.231523) (xy 73.376615 -401.239276) (xy 73.349358 -401.239736) (xy 72.485758 -401.239736)
			(xy 72.458511 -401.239191) (xy 72.404572 -401.23143) (xy 72.352286 -401.216073) (xy 72.302718 -401.193431)
			(xy 72.256876 -401.163965) (xy 72.215694 -401.128277) (xy 72.180009 -401.087091) (xy 72.150549 -401.041246)
			(xy 72.127913 -400.991675) (xy 72.112561 -400.939387) (xy 72.104806 -400.885447) (xy 70.66715 -400.885447)
			(xy 70.66715 -400.885452) (xy 70.659394 -400.939403) (xy 70.644038 -400.9917) (xy 70.621397 -401.041279)
			(xy 70.59193 -401.087132) (xy 70.556238 -401.128325) (xy 70.515047 -401.164019) (xy 70.469195 -401.193488)
			(xy 70.419617 -401.216132) (xy 70.36732 -401.23149) (xy 70.31337 -401.239249) (xy 70.286118 -401.239736)
			(xy 69.422518 -401.239736) (xy 69.395266 -401.239218) (xy 69.341317 -401.231464) (xy 69.289021 -401.21611)
			(xy 69.239442 -401.19347) (xy 69.19359 -401.164005) (xy 69.152399 -401.128314) (xy 69.116706 -401.087124)
			(xy 69.087238 -401.041273) (xy 69.064596 -400.991696) (xy 69.04924 -400.9394) (xy 69.041483 -400.885452)
			(xy 67.603973 -400.885452) (xy 67.603973 -400.885456) (xy 67.596215 -400.939413) (xy 67.580857 -400.991716)
			(xy 67.558211 -401.041302) (xy 67.528739 -401.087159) (xy 67.49304 -401.128355) (xy 67.451842 -401.164052)
			(xy 67.405982 -401.193521) (xy 67.356396 -401.216164) (xy 67.304091 -401.23152) (xy 67.250134 -401.239275)
			(xy 67.222878 -401.239736) (xy 66.359278 -401.239736) (xy 66.33203 -401.239192) (xy 66.278088 -401.231434)
			(xy 66.2258 -401.216078) (xy 66.17623 -401.193437) (xy 66.130385 -401.163973) (xy 66.089201 -401.128284)
			(xy 66.053514 -401.087097) (xy 66.024052 -401.041251) (xy 66.001414 -400.991679) (xy 65.986062 -400.93939)
			(xy 65.978306 -400.885448) (xy 64.54065 -400.885448) (xy 64.54065 -400.885452) (xy 64.532894 -400.9394)
			(xy 64.51754 -400.991695) (xy 64.4949 -401.041274) (xy 64.465435 -401.087126) (xy 64.429745 -401.128318)
			(xy 64.388556 -401.164012) (xy 64.342707 -401.193482) (xy 64.293131 -401.216127) (xy 64.240837 -401.231486)
			(xy 64.186889 -401.239248) (xy 64.159638 -401.239736) (xy 63.296038 -401.239736) (xy 63.268785 -401.239219)
			(xy 63.214834 -401.231467) (xy 63.162536 -401.216116) (xy 63.112954 -401.193477) (xy 63.0671 -401.164012)
			(xy 63.025906 -401.128321) (xy 62.990211 -401.087131) (xy 62.960741 -401.041279) (xy 62.938098 -400.9917)
			(xy 62.922741 -400.939403) (xy 62.914983 -400.885453) (xy 61.477473 -400.885453) (xy 61.477473 -400.885455)
			(xy 61.469715 -400.93941) (xy 61.454358 -400.991712) (xy 61.431714 -401.041296) (xy 61.402243 -401.087153)
			(xy 61.366547 -401.128348) (xy 61.325351 -401.164045) (xy 61.279494 -401.193515) (xy 61.22991 -401.216159)
			(xy 61.177608 -401.231516) (xy 61.123653 -401.239273) (xy 61.096398 -401.239736) (xy 60.232798 -401.239736)
			(xy 60.205549 -401.239194) (xy 60.151605 -401.231437) (xy 60.099315 -401.216083) (xy 60.049742 -401.193444)
			(xy 60.003895 -401.16398) (xy 59.962708 -401.128291) (xy 59.927019 -401.087104) (xy 59.897555 -401.041257)
			(xy 59.874916 -400.991683) (xy 59.859562 -400.939393) (xy 59.851806 -400.885449) (xy 58.414273 -400.885449)
			(xy 58.414273 -400.885457) (xy 58.406514 -400.939415) (xy 58.391155 -400.991721) (xy 58.368508 -401.041307)
			(xy 58.339034 -401.087166) (xy 58.303333 -401.128363) (xy 58.262132 -401.164059) (xy 58.21627 -401.193528)
			(xy 58.166681 -401.21617) (xy 58.114374 -401.231523) (xy 58.060415 -401.239276) (xy 58.033158 -401.239736)
			(xy 57.169558 -401.239736) (xy 57.142311 -401.239191) (xy 57.088372 -401.23143) (xy 57.036086 -401.216073)
			(xy 56.986518 -401.193431) (xy 56.940676 -401.163965) (xy 56.899494 -401.128277) (xy 56.863809 -401.087091)
			(xy 56.834349 -401.041246) (xy 56.811713 -400.991675) (xy 56.796361 -400.939387) (xy 56.788606 -400.885447)
			(xy 55.35095 -400.885447) (xy 55.35095 -400.885452) (xy 55.343194 -400.939403) (xy 55.327838 -400.9917)
			(xy 55.305197 -401.041279) (xy 55.27573 -401.087132) (xy 55.240038 -401.128325) (xy 55.198847 -401.164019)
			(xy 55.152995 -401.193488) (xy 55.103417 -401.216132) (xy 55.05112 -401.23149) (xy 54.99717 -401.239249)
			(xy 54.969918 -401.239736) (xy 54.106318 -401.239736) (xy 54.079066 -401.239218) (xy 54.025117 -401.231464)
			(xy 53.972821 -401.21611) (xy 53.923242 -401.19347) (xy 53.87739 -401.164005) (xy 53.836199 -401.128314)
			(xy 53.800506 -401.087124) (xy 53.771038 -401.041273) (xy 53.748396 -400.991696) (xy 53.73304 -400.9394)
			(xy 53.725283 -400.885452) (xy 52.287773 -400.885452) (xy 52.287773 -400.885456) (xy 52.280015 -400.939413)
			(xy 52.264657 -400.991716) (xy 52.242011 -401.041302) (xy 52.212539 -401.087159) (xy 52.17684 -401.128355)
			(xy 52.135642 -401.164052) (xy 52.089782 -401.193521) (xy 52.040196 -401.216164) (xy 51.987891 -401.23152)
			(xy 51.933934 -401.239275) (xy 51.906678 -401.239736) (xy 51.043078 -401.239736) (xy 51.01583 -401.239192)
			(xy 50.961888 -401.231434) (xy 50.9096 -401.216078) (xy 50.86003 -401.193437) (xy 50.814185 -401.163973)
			(xy 50.773001 -401.128284) (xy 50.737314 -401.087097) (xy 50.707852 -401.041251) (xy 50.685214 -400.991679)
			(xy 50.669862 -400.93939) (xy 50.662106 -400.885448) (xy 49.22445 -400.885448) (xy 49.22445 -400.885452)
			(xy 49.216694 -400.9394) (xy 49.20134 -400.991695) (xy 49.1787 -401.041274) (xy 49.149235 -401.087126)
			(xy 49.113545 -401.128318) (xy 49.072356 -401.164012) (xy 49.026507 -401.193482) (xy 48.976931 -401.216127)
			(xy 48.924637 -401.231486) (xy 48.870689 -401.239248) (xy 48.843438 -401.239736) (xy 47.979838 -401.239736)
			(xy 47.952585 -401.239219) (xy 47.898634 -401.231467) (xy 47.846336 -401.216116) (xy 47.796754 -401.193477)
			(xy 47.7509 -401.164012) (xy 47.709706 -401.128321) (xy 47.674011 -401.087131) (xy 47.644541 -401.041279)
			(xy 47.621898 -400.9917) (xy 47.606541 -400.939403) (xy 47.598783 -400.885453) (xy 2.509012 -400.885453)
			(xy 2.509012 -402.713952) (xy 47.76216 -402.713952) (xy 47.76216 -402.028152) (xy 47.762623 -402.016078)
			(xy 47.770095 -401.993115) (xy 47.784293 -401.973581) (xy 47.803829 -401.959387) (xy 47.826794 -401.95192)
			(xy 47.838868 -401.951444) (xy 48.033432 -401.951444) (xy 48.044537 -401.951828) (xy 48.065829 -401.958149)
			(xy 48.075342 -401.96389) (xy 48.368966 -402.156422) (xy 48.378355 -402.162115) (xy 48.399365 -402.168452)
			(xy 48.42131 -402.168528) (xy 48.442364 -402.162338) (xy 48.45177 -402.156676) (xy 48.747934 -401.96389)
			(xy 48.75745 -401.958152) (xy 48.778739 -401.95182) (xy 48.789844 -401.951444) (xy 48.984408 -401.951444)
			(xy 48.996478 -401.951957) (xy 49.019437 -401.959416) (xy 49.03897 -401.973601) (xy 49.053166 -401.993127)
			(xy 49.060637 -402.016082) (xy 49.061116 -402.028152) (xy 49.061116 -402.713952) (xy 50.8254 -402.713952)
			(xy 50.8254 -402.028152) (xy 50.825823 -402.016074) (xy 50.8333 -401.993104) (xy 50.847507 -401.973567)
			(xy 50.867054 -401.959374) (xy 50.89003 -401.951914) (xy 50.902108 -401.951444) (xy 51.096672 -401.951444)
			(xy 51.107778 -401.951812) (xy 51.12907 -401.958144) (xy 51.138582 -401.96389) (xy 51.432206 -402.156422)
			(xy 51.441576 -402.162149) (xy 51.462595 -402.168478) (xy 51.484547 -402.168545) (xy 51.505604 -402.162344)
			(xy 51.51501 -402.156676) (xy 51.811174 -401.96389) (xy 51.820682 -401.958137) (xy 51.841977 -401.951815)
			(xy 51.853084 -401.951444) (xy 52.047648 -401.951444) (xy 52.05972 -401.951922) (xy 52.082681 -401.959392)
			(xy 52.102213 -401.973587) (xy 52.116408 -401.993119) (xy 52.123878 -402.01608) (xy 52.124356 -402.028152)
			(xy 52.124356 -402.713952) (xy 53.88864 -402.713952) (xy 53.88864 -402.028152) (xy 53.889024 -402.01607)
			(xy 53.896506 -401.993093) (xy 53.910721 -401.973553) (xy 53.930279 -401.959362) (xy 53.953266 -401.951909)
			(xy 53.965348 -401.951444) (xy 54.159912 -401.951444) (xy 54.171016 -401.951837) (xy 54.192308 -401.958152)
			(xy 54.201822 -401.96389) (xy 54.495446 -402.156422) (xy 54.504797 -402.162183) (xy 54.525825 -402.168505)
			(xy 54.547783 -402.168562) (xy 54.568844 -402.16235) (xy 54.57825 -402.156676) (xy 54.874414 -401.96389)
			(xy 54.883914 -401.958122) (xy 54.905215 -401.951809) (xy 54.916324 -401.951444) (xy 55.110888 -401.951444)
			(xy 55.122957 -401.951974) (xy 55.145916 -401.959427) (xy 55.165449 -401.973608) (xy 55.179646 -401.99313)
			(xy 55.187117 -402.016083) (xy 55.187596 -402.028152) (xy 55.187596 -402.713952) (xy 56.95188 -402.713952)
			(xy 56.95188 -402.028152) (xy 56.952323 -402.016076) (xy 56.959797 -401.993109) (xy 56.974 -401.973574)
			(xy 56.993542 -401.959381) (xy 57.016512 -401.951917) (xy 57.028588 -401.951444) (xy 57.223152 -401.951444)
			(xy 57.234257 -401.95182) (xy 57.255549 -401.958147) (xy 57.265062 -401.96389) (xy 57.558686 -402.156422)
			(xy 57.568066 -402.162132) (xy 57.58908 -402.168465) (xy 57.611028 -402.168537) (xy 57.632084 -402.162341)
			(xy 57.64149 -402.156676) (xy 57.937654 -401.96389) (xy 57.947166 -401.958145) (xy 57.968458 -401.951817)
			(xy 57.979564 -401.951444) (xy 58.174128 -401.951444) (xy 58.186199 -401.951939) (xy 58.209159 -401.959404)
			(xy 58.228692 -401.973594) (xy 58.242887 -401.993123) (xy 58.250358 -402.016081) (xy 58.250836 -402.028152)
			(xy 58.250836 -402.713952) (xy 60.01512 -402.713952) (xy 60.01512 -402.028152) (xy 60.015524 -402.016072)
			(xy 60.023003 -401.993099) (xy 60.037214 -401.97356) (xy 60.056767 -401.959368) (xy 60.079748 -401.951912)
			(xy 60.091828 -401.951444) (xy 60.286392 -401.951444) (xy 60.297499 -401.951805) (xy 60.318791 -401.958142)
			(xy 60.328302 -401.96389) (xy 60.621926 -402.156422) (xy 60.631287 -402.162166) (xy 60.65231 -402.168491)
			(xy 60.674265 -402.168553) (xy 60.695324 -402.162347) (xy 60.70473 -402.156676) (xy 61.000894 -401.96389)
			(xy 61.010398 -401.95813) (xy 61.031696 -401.951812) (xy 61.042804 -401.951444) (xy 61.237368 -401.951444)
			(xy 61.249436 -401.951991) (xy 61.272394 -401.959438) (xy 61.291928 -401.973615) (xy 61.306125 -401.993134)
			(xy 61.313597 -402.016084) (xy 61.314076 -402.028152) (xy 61.314076 -402.713952) (xy 63.07836 -402.713952)
			(xy 63.07836 -402.028152) (xy 63.078823 -402.016078) (xy 63.086295 -401.993115) (xy 63.100493 -401.973581)
			(xy 63.120029 -401.959387) (xy 63.142994 -401.95192) (xy 63.155068 -401.951444) (xy 63.349632 -401.951444)
			(xy 63.360737 -401.951828) (xy 63.382029 -401.958149) (xy 63.391542 -401.96389) (xy 63.685166 -402.156422)
			(xy 63.694555 -402.162115) (xy 63.715565 -402.168452) (xy 63.73751 -402.168528) (xy 63.758564 -402.162338)
			(xy 63.76797 -402.156676) (xy 64.064134 -401.96389) (xy 64.07365 -401.958152) (xy 64.094939 -401.95182)
			(xy 64.106044 -401.951444) (xy 64.300608 -401.951444) (xy 64.312678 -401.951957) (xy 64.335637 -401.959416)
			(xy 64.35517 -401.973601) (xy 64.369366 -401.993127) (xy 64.376837 -402.016082) (xy 64.377316 -402.028152)
			(xy 64.377316 -402.713952) (xy 66.1416 -402.713952) (xy 66.1416 -402.028152) (xy 66.142023 -402.016074)
			(xy 66.1495 -401.993104) (xy 66.163707 -401.973567) (xy 66.183254 -401.959374) (xy 66.20623 -401.951914)
			(xy 66.218308 -401.951444) (xy 66.412872 -401.951444) (xy 66.423978 -401.951812) (xy 66.44527 -401.958144)
			(xy 66.454782 -401.96389) (xy 66.748406 -402.156422) (xy 66.757776 -402.162149) (xy 66.778795 -402.168478)
			(xy 66.800747 -402.168545) (xy 66.821804 -402.162344) (xy 66.83121 -402.156676) (xy 67.127374 -401.96389)
			(xy 67.136882 -401.958137) (xy 67.158177 -401.951815) (xy 67.169284 -401.951444) (xy 67.363848 -401.951444)
			(xy 67.37592 -401.951922) (xy 67.398881 -401.959392) (xy 67.418413 -401.973587) (xy 67.432608 -401.993119)
			(xy 67.440078 -402.01608) (xy 67.440556 -402.028152) (xy 67.440556 -402.713952) (xy 69.20484 -402.713952)
			(xy 69.20484 -402.028152) (xy 69.205224 -402.01607) (xy 69.212706 -401.993093) (xy 69.226921 -401.973553)
			(xy 69.246479 -401.959362) (xy 69.269466 -401.951909) (xy 69.281548 -401.951444) (xy 69.476112 -401.951444)
			(xy 69.487216 -401.951837) (xy 69.508508 -401.958152) (xy 69.518022 -401.96389) (xy 69.811646 -402.156422)
			(xy 69.820997 -402.162183) (xy 69.842025 -402.168505) (xy 69.863983 -402.168562) (xy 69.885044 -402.16235)
			(xy 69.89445 -402.156676) (xy 70.190614 -401.96389) (xy 70.200114 -401.958122) (xy 70.221415 -401.951809)
			(xy 70.232524 -401.951444) (xy 70.427088 -401.951444) (xy 70.439157 -401.951974) (xy 70.462116 -401.959427)
			(xy 70.481649 -401.973608) (xy 70.495846 -401.99313) (xy 70.503317 -402.016083) (xy 70.503796 -402.028152)
			(xy 70.503796 -402.713952) (xy 72.26808 -402.713952) (xy 72.26808 -402.028152) (xy 72.268523 -402.016076)
			(xy 72.275997 -401.993109) (xy 72.2902 -401.973574) (xy 72.309742 -401.959381) (xy 72.332712 -401.951917)
			(xy 72.344788 -401.951444) (xy 72.539352 -401.951444) (xy 72.550457 -401.95182) (xy 72.571749 -401.958147)
			(xy 72.581262 -401.96389) (xy 72.874886 -402.156422) (xy 72.884266 -402.162132) (xy 72.90528 -402.168465)
			(xy 72.927228 -402.168537) (xy 72.948284 -402.162341) (xy 72.95769 -402.156676) (xy 73.253854 -401.96389)
			(xy 73.263366 -401.958145) (xy 73.284658 -401.951817) (xy 73.295764 -401.951444) (xy 73.490328 -401.951444)
			(xy 73.502399 -401.951939) (xy 73.525359 -401.959404) (xy 73.544892 -401.973594) (xy 73.559087 -401.993123)
			(xy 73.566558 -402.016081) (xy 73.567036 -402.028152) (xy 73.567036 -402.713952) (xy 75.33132 -402.713952)
			(xy 75.33132 -402.028152) (xy 75.331724 -402.016072) (xy 75.339203 -401.993099) (xy 75.353414 -401.97356)
			(xy 75.372967 -401.959368) (xy 75.395948 -401.951912) (xy 75.408028 -401.951444) (xy 75.602592 -401.951444)
			(xy 75.613699 -401.951805) (xy 75.634991 -401.958142) (xy 75.644502 -401.96389) (xy 75.938126 -402.156422)
			(xy 75.947487 -402.162166) (xy 75.96851 -402.168491) (xy 75.990465 -402.168553) (xy 76.011524 -402.162347)
			(xy 76.02093 -402.156676) (xy 76.317094 -401.96389) (xy 76.326598 -401.95813) (xy 76.347896 -401.951812)
			(xy 76.359004 -401.951444) (xy 76.553568 -401.951444) (xy 76.565636 -401.951991) (xy 76.588594 -401.959438)
			(xy 76.608128 -401.973615) (xy 76.622325 -401.993134) (xy 76.629797 -402.016084) (xy 76.630276 -402.028152)
			(xy 76.630276 -402.713952) (xy 78.39456 -402.713952) (xy 78.39456 -402.028152) (xy 78.395023 -402.016078)
			(xy 78.402495 -401.993115) (xy 78.416693 -401.973581) (xy 78.436229 -401.959387) (xy 78.459194 -401.95192)
			(xy 78.471268 -401.951444) (xy 78.665832 -401.951444) (xy 78.676937 -401.951828) (xy 78.698229 -401.958149)
			(xy 78.707742 -401.96389) (xy 79.001366 -402.156422) (xy 79.010755 -402.162115) (xy 79.031765 -402.168452)
			(xy 79.05371 -402.168528) (xy 79.074764 -402.162338) (xy 79.08417 -402.156676) (xy 79.380334 -401.96389)
			(xy 79.38985 -401.958152) (xy 79.411139 -401.95182) (xy 79.422244 -401.951444) (xy 79.616808 -401.951444)
			(xy 79.628878 -401.951957) (xy 79.651837 -401.959416) (xy 79.67137 -401.973601) (xy 79.685566 -401.993127)
			(xy 79.693037 -402.016082) (xy 79.693516 -402.028152) (xy 79.693516 -402.713952) (xy 81.4578 -402.713952)
			(xy 81.4578 -402.028152) (xy 81.458223 -402.016074) (xy 81.4657 -401.993104) (xy 81.479907 -401.973567)
			(xy 81.499454 -401.959374) (xy 81.52243 -401.951914) (xy 81.534508 -401.951444) (xy 81.729072 -401.951444)
			(xy 81.740178 -401.951812) (xy 81.76147 -401.958144) (xy 81.770982 -401.96389) (xy 82.064606 -402.156422)
			(xy 82.073976 -402.162149) (xy 82.094995 -402.168478) (xy 82.116947 -402.168545) (xy 82.138004 -402.162344)
			(xy 82.14741 -402.156676) (xy 82.443574 -401.96389) (xy 82.453082 -401.958137) (xy 82.474377 -401.951815)
			(xy 82.485484 -401.951444) (xy 82.680048 -401.951444) (xy 82.69212 -401.951922) (xy 82.715081 -401.959392)
			(xy 82.734613 -401.973587) (xy 82.748808 -401.993119) (xy 82.756278 -402.01608) (xy 82.756756 -402.028152)
			(xy 82.756756 -402.713952) (xy 84.52104 -402.713952) (xy 84.52104 -402.028152) (xy 84.521424 -402.01607)
			(xy 84.528906 -401.993093) (xy 84.543121 -401.973553) (xy 84.562679 -401.959362) (xy 84.585666 -401.951909)
			(xy 84.597748 -401.951444) (xy 84.792312 -401.951444) (xy 84.803416 -401.951837) (xy 84.824708 -401.958152)
			(xy 84.834222 -401.96389) (xy 85.127846 -402.156422) (xy 85.137197 -402.162183) (xy 85.158225 -402.168505)
			(xy 85.180183 -402.168562) (xy 85.201244 -402.16235) (xy 85.21065 -402.156676) (xy 85.506814 -401.96389)
			(xy 85.516314 -401.958122) (xy 85.537615 -401.951809) (xy 85.548724 -401.951444) (xy 85.743288 -401.951444)
			(xy 85.755357 -401.951974) (xy 85.778316 -401.959427) (xy 85.797849 -401.973608) (xy 85.812046 -401.99313)
			(xy 85.819517 -402.016083) (xy 85.819996 -402.028152) (xy 85.819996 -402.713952) (xy 87.58428 -402.713952)
			(xy 87.58428 -402.028152) (xy 87.584723 -402.016076) (xy 87.592197 -401.993109) (xy 87.6064 -401.973574)
			(xy 87.625942 -401.959381) (xy 87.648912 -401.951917) (xy 87.660988 -401.951444) (xy 87.855552 -401.951444)
			(xy 87.866657 -401.95182) (xy 87.887949 -401.958147) (xy 87.897462 -401.96389) (xy 88.191086 -402.156422)
			(xy 88.200466 -402.162132) (xy 88.22148 -402.168465) (xy 88.243428 -402.168537) (xy 88.264484 -402.162341)
			(xy 88.27389 -402.156676) (xy 88.570054 -401.96389) (xy 88.579566 -401.958145) (xy 88.600858 -401.951817)
			(xy 88.611964 -401.951444) (xy 88.806528 -401.951444) (xy 88.818599 -401.951939) (xy 88.841559 -401.959404)
			(xy 88.861092 -401.973594) (xy 88.875287 -401.993123) (xy 88.882758 -402.016081) (xy 88.883236 -402.028152)
			(xy 88.883236 -402.713952) (xy 90.64752 -402.713952) (xy 90.64752 -402.028152) (xy 90.647924 -402.016072)
			(xy 90.655403 -401.993099) (xy 90.669614 -401.97356) (xy 90.689167 -401.959368) (xy 90.712148 -401.951912)
			(xy 90.724228 -401.951444) (xy 90.918792 -401.951444) (xy 90.929899 -401.951805) (xy 90.951191 -401.958142)
			(xy 90.960702 -401.96389) (xy 91.254326 -402.156422) (xy 91.263687 -402.162166) (xy 91.28471 -402.168491)
			(xy 91.306665 -402.168553) (xy 91.327724 -402.162347) (xy 91.33713 -402.156676) (xy 91.633294 -401.96389)
			(xy 91.642798 -401.95813) (xy 91.664096 -401.951812) (xy 91.675204 -401.951444) (xy 91.869768 -401.951444)
			(xy 91.881836 -401.951991) (xy 91.904794 -401.959438) (xy 91.924328 -401.973615) (xy 91.938525 -401.993134)
			(xy 91.945997 -402.016084) (xy 91.946476 -402.028152) (xy 91.946476 -402.713952) (xy 93.71076 -402.713952)
			(xy 93.71076 -402.028152) (xy 93.711223 -402.016078) (xy 93.718695 -401.993115) (xy 93.732893 -401.973581)
			(xy 93.752429 -401.959387) (xy 93.775394 -401.95192) (xy 93.787468 -401.951444) (xy 93.982032 -401.951444)
			(xy 93.993137 -401.951828) (xy 94.014429 -401.958149) (xy 94.023942 -401.96389) (xy 94.317566 -402.156422)
			(xy 94.326955 -402.162115) (xy 94.347965 -402.168452) (xy 94.36991 -402.168528) (xy 94.390964 -402.162338)
			(xy 94.40037 -402.156676) (xy 94.696534 -401.96389) (xy 94.70605 -401.958152) (xy 94.727339 -401.95182)
			(xy 94.738444 -401.951444) (xy 94.933008 -401.951444) (xy 94.945078 -401.951957) (xy 94.968037 -401.959416)
			(xy 94.98757 -401.973601) (xy 95.001766 -401.993127) (xy 95.009237 -402.016082) (xy 95.009716 -402.028152)
			(xy 95.009716 -402.656674) (xy 98.152872 -402.656674) (xy 98.152872 -402.602126) (xy 98.160635 -402.548133)
			(xy 98.176003 -402.495795) (xy 98.198664 -402.446176) (xy 98.228156 -402.400288) (xy 98.263878 -402.359064)
			(xy 98.305104 -402.323344) (xy 98.350994 -402.293855) (xy 98.400613 -402.271196) (xy 98.452953 -402.255831)
			(xy 98.506946 -402.24807) (xy 98.53422 -402.247608) (xy 99.39782 -402.247608) (xy 99.425086 -402.248156)
			(xy 99.479063 -402.255919) (xy 99.531387 -402.271285) (xy 99.58099 -402.293941) (xy 99.626865 -402.323425)
			(xy 99.668077 -402.359137) (xy 99.703787 -402.400351) (xy 99.733269 -402.446227) (xy 99.755922 -402.495832)
			(xy 99.771285 -402.548156) (xy 99.779046 -402.602134) (xy 99.779046 -402.656666) (xy 99.771285 -402.710644)
			(xy 99.770314 -402.713952) (xy 119.937276 -402.713952) (xy 119.937276 -402.028152) (xy 119.937723 -402.016077)
			(xy 119.945197 -401.99311) (xy 119.959398 -401.973576) (xy 119.978939 -401.959382) (xy 120.001908 -401.951918)
			(xy 120.013984 -401.951444) (xy 120.208548 -401.951444) (xy 120.219653 -401.951822) (xy 120.240945 -401.958147)
			(xy 120.250458 -401.96389) (xy 120.544082 -402.156422) (xy 120.553463 -402.162129) (xy 120.574477 -402.168462)
			(xy 120.596425 -402.168535) (xy 120.61748 -402.16234) (xy 120.626886 -402.156676) (xy 120.92305 -401.96389)
			(xy 120.932563 -401.958146) (xy 120.953854 -401.951818) (xy 120.96496 -401.951444) (xy 121.159524 -401.951444)
			(xy 121.171595 -401.951943) (xy 121.194555 -401.959406) (xy 121.214087 -401.973596) (xy 121.228283 -401.993124)
			(xy 121.235753 -402.016081) (xy 121.236232 -402.028152) (xy 121.236232 -402.713952) (xy 123.000516 -402.713952)
			(xy 123.000516 -402.028152) (xy 123.000924 -402.016073) (xy 123.008402 -401.9931) (xy 123.022613 -401.973561)
			(xy 123.042164 -401.959369) (xy 123.065144 -401.951912) (xy 123.077224 -401.951444) (xy 123.271788 -401.951444)
			(xy 123.282895 -401.951806) (xy 123.304186 -401.958142) (xy 123.313698 -401.96389) (xy 123.607322 -402.156422)
			(xy 123.616685 -402.162163) (xy 123.637707 -402.168489) (xy 123.659661 -402.168552) (xy 123.68072 -402.162346)
			(xy 123.690126 -402.156676) (xy 123.98629 -401.96389) (xy 123.995795 -401.958131) (xy 124.017092 -401.951812)
			(xy 124.0282 -401.951444) (xy 124.222764 -401.951444) (xy 124.234832 -401.951994) (xy 124.25779 -401.959441)
			(xy 124.277323 -401.973617) (xy 124.291521 -401.993135) (xy 124.298993 -402.016085) (xy 124.299472 -402.028152)
			(xy 124.299472 -402.713952) (xy 126.063756 -402.713952) (xy 126.063756 -402.028152) (xy 126.064223 -402.016078)
			(xy 126.071694 -401.993116) (xy 126.085891 -401.973583) (xy 126.105427 -401.959388) (xy 126.12839 -401.951921)
			(xy 126.140464 -401.951444) (xy 126.335028 -401.951444) (xy 126.346132 -401.95183) (xy 126.367425 -401.95815)
			(xy 126.376938 -401.96389) (xy 126.670562 -402.156422) (xy 126.679953 -402.162112) (xy 126.700962 -402.168449)
			(xy 126.722906 -402.168527) (xy 126.74396 -402.162338) (xy 126.753366 -402.156676) (xy 127.04953 -401.96389)
			(xy 127.059047 -401.958153) (xy 127.080335 -401.951821) (xy 127.09144 -401.951444) (xy 127.286004 -401.951444)
			(xy 127.298074 -401.95196) (xy 127.321033 -401.959418) (xy 127.340566 -401.973603) (xy 127.354762 -401.993127)
			(xy 127.362233 -402.016082) (xy 127.362712 -402.028152) (xy 127.362712 -402.713952) (xy 129.126996 -402.713952)
			(xy 129.126996 -402.028152) (xy 129.127423 -402.016075) (xy 129.134899 -401.993105) (xy 129.149105 -401.973568)
			(xy 129.168652 -401.959376) (xy 129.191626 -401.951915) (xy 129.203704 -401.951444) (xy 129.398268 -401.951444)
			(xy 129.409374 -401.951814) (xy 129.430666 -401.958145) (xy 129.440178 -401.96389) (xy 129.733802 -402.156422)
			(xy 129.743174 -402.162146) (xy 129.764192 -402.168476) (xy 129.786143 -402.168543) (xy 129.8072 -402.162343)
			(xy 129.816606 -402.156676) (xy 130.11277 -401.96389) (xy 130.122279 -401.958139) (xy 130.143573 -401.951815)
			(xy 130.15468 -401.951444) (xy 130.349244 -401.951444) (xy 130.361316 -401.951926) (xy 130.384277 -401.959395)
			(xy 130.403809 -401.973588) (xy 130.418004 -401.99312) (xy 130.425474 -402.01608) (xy 130.425952 -402.028152)
			(xy 130.425952 -402.713952) (xy 132.190236 -402.713952) (xy 132.190236 -402.028152) (xy 132.190624 -402.016071)
			(xy 132.198105 -401.993094) (xy 132.21232 -401.973554) (xy 132.231877 -401.959363) (xy 132.254862 -401.951909)
			(xy 132.266944 -401.951444) (xy 132.461508 -401.951444) (xy 132.472612 -401.951839) (xy 132.493904 -401.958153)
			(xy 132.503418 -401.96389) (xy 132.797042 -402.156422) (xy 132.806395 -402.16218) (xy 132.827422 -402.168502)
			(xy 132.849379 -402.16856) (xy 132.87044 -402.162349) (xy 132.879846 -402.156676) (xy 133.17601 -401.96389)
			(xy 133.185511 -401.958124) (xy 133.206812 -401.95181) (xy 133.21792 -401.951444) (xy 133.412484 -401.951444)
			(xy 133.424553 -401.951977) (xy 133.447512 -401.959429) (xy 133.467045 -401.97361) (xy 133.481241 -401.993131)
			(xy 133.488713 -402.016083) (xy 133.489192 -402.028152) (xy 133.489192 -402.713952) (xy 135.253476 -402.713952)
			(xy 135.253476 -402.028152) (xy 135.253923 -402.016077) (xy 135.261397 -401.99311) (xy 135.275598 -401.973576)
			(xy 135.295139 -401.959382) (xy 135.318108 -401.951918) (xy 135.330184 -401.951444) (xy 135.524748 -401.951444)
			(xy 135.535853 -401.951822) (xy 135.557145 -401.958147) (xy 135.566658 -401.96389) (xy 135.860282 -402.156422)
			(xy 135.869663 -402.162129) (xy 135.890677 -402.168462) (xy 135.912625 -402.168535) (xy 135.93368 -402.16234)
			(xy 135.943086 -402.156676) (xy 136.23925 -401.96389) (xy 136.248763 -401.958146) (xy 136.270054 -401.951818)
			(xy 136.28116 -401.951444) (xy 136.475724 -401.951444) (xy 136.487795 -401.951943) (xy 136.510755 -401.959406)
			(xy 136.530287 -401.973596) (xy 136.544483 -401.993124) (xy 136.551953 -402.016081) (xy 136.552432 -402.028152)
			(xy 136.552432 -402.713952) (xy 138.316716 -402.713952) (xy 138.316716 -402.028152) (xy 138.317124 -402.016073)
			(xy 138.324602 -401.9931) (xy 138.338813 -401.973561) (xy 138.358364 -401.959369) (xy 138.381344 -401.951912)
			(xy 138.393424 -401.951444) (xy 138.587988 -401.951444) (xy 138.599095 -401.951806) (xy 138.620386 -401.958142)
			(xy 138.629898 -401.96389) (xy 138.923522 -402.156422) (xy 138.932885 -402.162163) (xy 138.953907 -402.168489)
			(xy 138.975861 -402.168552) (xy 138.99692 -402.162346) (xy 139.006326 -402.156676) (xy 139.30249 -401.96389)
			(xy 139.311995 -401.958131) (xy 139.333292 -401.951812) (xy 139.3444 -401.951444) (xy 139.538964 -401.951444)
			(xy 139.551032 -401.951994) (xy 139.57399 -401.959441) (xy 139.593523 -401.973617) (xy 139.607721 -401.993135)
			(xy 139.615193 -402.016085) (xy 139.615672 -402.028152) (xy 139.615672 -402.713952) (xy 141.379956 -402.713952)
			(xy 141.379956 -402.028152) (xy 141.380423 -402.016078) (xy 141.387894 -401.993116) (xy 141.402091 -401.973583)
			(xy 141.421627 -401.959388) (xy 141.44459 -401.951921) (xy 141.456664 -401.951444) (xy 141.651228 -401.951444)
			(xy 141.662332 -401.95183) (xy 141.683625 -401.95815) (xy 141.693138 -401.96389) (xy 141.986762 -402.156422)
			(xy 141.996153 -402.162112) (xy 142.017162 -402.168449) (xy 142.039106 -402.168527) (xy 142.06016 -402.162338)
			(xy 142.069566 -402.156676) (xy 142.36573 -401.96389) (xy 142.375247 -401.958153) (xy 142.396535 -401.951821)
			(xy 142.40764 -401.951444) (xy 142.602204 -401.951444) (xy 142.614274 -401.95196) (xy 142.637233 -401.959418)
			(xy 142.656766 -401.973603) (xy 142.670962 -401.993127) (xy 142.678433 -402.016082) (xy 142.678912 -402.028152)
			(xy 142.678912 -402.713952) (xy 144.443196 -402.713952) (xy 144.443196 -402.028152) (xy 144.443623 -402.016075)
			(xy 144.451099 -401.993105) (xy 144.465305 -401.973568) (xy 144.484852 -401.959376) (xy 144.507826 -401.951915)
			(xy 144.519904 -401.951444) (xy 144.714468 -401.951444) (xy 144.725574 -401.951814) (xy 144.746866 -401.958145)
			(xy 144.756378 -401.96389) (xy 145.050002 -402.156422) (xy 145.059374 -402.162146) (xy 145.080392 -402.168476)
			(xy 145.102343 -402.168543) (xy 145.1234 -402.162343) (xy 145.132806 -402.156676) (xy 145.42897 -401.96389)
			(xy 145.438479 -401.958139) (xy 145.459773 -401.951815) (xy 145.47088 -401.951444) (xy 145.665444 -401.951444)
			(xy 145.677516 -401.951926) (xy 145.700477 -401.959395) (xy 145.720009 -401.973588) (xy 145.734204 -401.99312)
			(xy 145.741674 -402.01608) (xy 145.742152 -402.028152) (xy 145.742152 -402.713952) (xy 147.506436 -402.713952)
			(xy 147.506436 -402.028152) (xy 147.506824 -402.016071) (xy 147.514305 -401.993094) (xy 147.52852 -401.973554)
			(xy 147.548077 -401.959363) (xy 147.571062 -401.951909) (xy 147.583144 -401.951444) (xy 147.777708 -401.951444)
			(xy 147.788812 -401.951839) (xy 147.810104 -401.958153) (xy 147.819618 -401.96389) (xy 148.113242 -402.156422)
			(xy 148.122595 -402.16218) (xy 148.143622 -402.168502) (xy 148.165579 -402.16856) (xy 148.18664 -402.162349)
			(xy 148.196046 -402.156676) (xy 148.49221 -401.96389) (xy 148.501711 -401.958124) (xy 148.523012 -401.95181)
			(xy 148.53412 -401.951444) (xy 148.728684 -401.951444) (xy 148.740753 -401.951977) (xy 148.763712 -401.959429)
			(xy 148.783245 -401.97361) (xy 148.797441 -401.993131) (xy 148.804913 -402.016083) (xy 148.805392 -402.028152)
			(xy 148.805392 -402.713952) (xy 150.569676 -402.713952) (xy 150.569676 -402.028152) (xy 150.570123 -402.016077)
			(xy 150.577597 -401.99311) (xy 150.591798 -401.973576) (xy 150.611339 -401.959382) (xy 150.634308 -401.951918)
			(xy 150.646384 -401.951444) (xy 150.840948 -401.951444) (xy 150.852053 -401.951822) (xy 150.873345 -401.958147)
			(xy 150.882858 -401.96389) (xy 151.176482 -402.156422) (xy 151.185863 -402.162129) (xy 151.206877 -402.168462)
			(xy 151.228825 -402.168535) (xy 151.24988 -402.16234) (xy 151.259286 -402.156676) (xy 151.55545 -401.96389)
			(xy 151.564963 -401.958146) (xy 151.586254 -401.951818) (xy 151.59736 -401.951444) (xy 151.791924 -401.951444)
			(xy 151.803995 -401.951943) (xy 151.826955 -401.959406) (xy 151.846487 -401.973596) (xy 151.860683 -401.993124)
			(xy 151.868153 -402.016081) (xy 151.868632 -402.028152) (xy 151.868632 -402.713952) (xy 153.632916 -402.713952)
			(xy 153.632916 -402.028152) (xy 153.633324 -402.016073) (xy 153.640802 -401.9931) (xy 153.655013 -401.973561)
			(xy 153.674564 -401.959369) (xy 153.697544 -401.951912) (xy 153.709624 -401.951444) (xy 153.904188 -401.951444)
			(xy 153.915295 -401.951806) (xy 153.936586 -401.958142) (xy 153.946098 -401.96389) (xy 154.239722 -402.156422)
			(xy 154.249085 -402.162163) (xy 154.270107 -402.168489) (xy 154.292061 -402.168552) (xy 154.31312 -402.162346)
			(xy 154.322526 -402.156676) (xy 154.61869 -401.96389) (xy 154.628195 -401.958131) (xy 154.649492 -401.951812)
			(xy 154.6606 -401.951444) (xy 154.855164 -401.951444) (xy 154.867232 -401.951994) (xy 154.89019 -401.959441)
			(xy 154.909723 -401.973617) (xy 154.923921 -401.993135) (xy 154.931393 -402.016085) (xy 154.931872 -402.028152)
			(xy 154.931872 -402.713952) (xy 156.696156 -402.713952) (xy 156.696156 -402.028152) (xy 156.696623 -402.016078)
			(xy 156.704094 -401.993116) (xy 156.718291 -401.973583) (xy 156.737827 -401.959388) (xy 156.76079 -401.951921)
			(xy 156.772864 -401.951444) (xy 156.967428 -401.951444) (xy 156.978532 -401.95183) (xy 156.999825 -401.95815)
			(xy 157.009338 -401.96389) (xy 157.302962 -402.156422) (xy 157.312353 -402.162112) (xy 157.333362 -402.168449)
			(xy 157.355306 -402.168527) (xy 157.37636 -402.162338) (xy 157.385766 -402.156676) (xy 157.68193 -401.96389)
			(xy 157.691447 -401.958153) (xy 157.712735 -401.951821) (xy 157.72384 -401.951444) (xy 157.918404 -401.951444)
			(xy 157.930474 -401.95196) (xy 157.953433 -401.959418) (xy 157.972966 -401.973603) (xy 157.987162 -401.993127)
			(xy 157.994633 -402.016082) (xy 157.995112 -402.028152) (xy 157.995112 -402.713952) (xy 159.759396 -402.713952)
			(xy 159.759396 -402.028152) (xy 159.759823 -402.016075) (xy 159.767299 -401.993105) (xy 159.781505 -401.973568)
			(xy 159.801052 -401.959376) (xy 159.824026 -401.951915) (xy 159.836104 -401.951444) (xy 160.030668 -401.951444)
			(xy 160.041774 -401.951814) (xy 160.063066 -401.958145) (xy 160.072578 -401.96389) (xy 160.366202 -402.156422)
			(xy 160.375574 -402.162146) (xy 160.396592 -402.168476) (xy 160.418543 -402.168543) (xy 160.4396 -402.162343)
			(xy 160.449006 -402.156676) (xy 160.74517 -401.96389) (xy 160.754679 -401.958139) (xy 160.775973 -401.951815)
			(xy 160.78708 -401.951444) (xy 160.981644 -401.951444) (xy 160.993716 -401.951926) (xy 161.016677 -401.959395)
			(xy 161.036209 -401.973588) (xy 161.050404 -401.99312) (xy 161.057874 -402.01608) (xy 161.058352 -402.028152)
			(xy 161.058352 -402.713952) (xy 162.822636 -402.713952) (xy 162.822636 -402.028152) (xy 162.823024 -402.016071)
			(xy 162.830505 -401.993094) (xy 162.84472 -401.973554) (xy 162.864277 -401.959363) (xy 162.887262 -401.951909)
			(xy 162.899344 -401.951444) (xy 163.093908 -401.951444) (xy 163.105012 -401.951839) (xy 163.126304 -401.958153)
			(xy 163.135818 -401.96389) (xy 163.429442 -402.156422) (xy 163.438795 -402.16218) (xy 163.459822 -402.168502)
			(xy 163.481779 -402.16856) (xy 163.50284 -402.162349) (xy 163.512246 -402.156676) (xy 163.80841 -401.96389)
			(xy 163.817911 -401.958124) (xy 163.839212 -401.95181) (xy 163.85032 -401.951444) (xy 164.044884 -401.951444)
			(xy 164.056953 -401.951977) (xy 164.079912 -401.959429) (xy 164.099445 -401.97361) (xy 164.113641 -401.993131)
			(xy 164.121113 -402.016083) (xy 164.121592 -402.028152) (xy 164.121592 -402.713952) (xy 165.885876 -402.713952)
			(xy 165.885876 -402.028152) (xy 165.886323 -402.016077) (xy 165.893797 -401.99311) (xy 165.907998 -401.973576)
			(xy 165.927539 -401.959382) (xy 165.950508 -401.951918) (xy 165.962584 -401.951444) (xy 166.157148 -401.951444)
			(xy 166.168253 -401.951822) (xy 166.189545 -401.958147) (xy 166.199058 -401.96389) (xy 166.492682 -402.156422)
			(xy 166.502063 -402.162129) (xy 166.523077 -402.168462) (xy 166.545025 -402.168535) (xy 166.56608 -402.16234)
			(xy 166.575486 -402.156676) (xy 166.87165 -401.96389) (xy 166.881163 -401.958146) (xy 166.902454 -401.951818)
			(xy 166.91356 -401.951444) (xy 167.108124 -401.951444) (xy 167.120195 -401.951943) (xy 167.143155 -401.959406)
			(xy 167.162687 -401.973596) (xy 167.176883 -401.993124) (xy 167.184353 -402.016081) (xy 167.184832 -402.028152)
			(xy 167.184832 -402.713952) (xy 167.184347 -402.72603) (xy 167.176895 -402.749007) (xy 167.162707 -402.768556)
			(xy 167.143172 -402.782763) (xy 167.120201 -402.790236) (xy 167.108124 -402.79066) (xy 166.91356 -402.79066)
			(xy 166.902452 -402.7903) (xy 166.881156 -402.783973) (xy 166.87165 -402.778214) (xy 166.576756 -402.585682)
			(xy 166.567369 -402.579979) (xy 166.546331 -402.573706) (xy 166.524377 -402.573706) (xy 166.503339 -402.579979)
			(xy 166.493952 -402.585682) (xy 166.200328 -402.778214) (xy 166.19082 -402.783966) (xy 166.169525 -402.790289)
			(xy 166.158418 -402.79066) (xy 165.962584 -402.79066) (xy 165.950496 -402.7903) (xy 165.927504 -402.782823)
			(xy 165.90795 -402.768604) (xy 165.893748 -402.749038) (xy 165.88629 -402.726041) (xy 165.885876 -402.713952)
			(xy 164.121592 -402.713952) (xy 164.121146 -402.726034) (xy 164.11369 -402.749018) (xy 164.099493 -402.76857)
			(xy 164.079946 -402.782775) (xy 164.056966 -402.790241) (xy 164.044884 -402.79066) (xy 163.85032 -402.79066)
			(xy 163.83921 -402.790316) (xy 163.817914 -402.783978) (xy 163.80841 -402.778214) (xy 163.513516 -402.585682)
			(xy 163.504129 -402.579979) (xy 163.483091 -402.573706) (xy 163.461137 -402.573706) (xy 163.440099 -402.579979)
			(xy 163.430712 -402.585682) (xy 163.137088 -402.778214) (xy 163.127588 -402.783981) (xy 163.106287 -402.790295)
			(xy 163.095178 -402.79066) (xy 162.899344 -402.79066) (xy 162.887259 -402.790249) (xy 162.864269 -402.782788)
			(xy 162.844714 -402.768583) (xy 162.83051 -402.749027) (xy 162.82305 -402.726037) (xy 162.822636 -402.713952)
			(xy 161.058352 -402.713952) (xy 161.057847 -402.726028) (xy 161.050398 -402.749002) (xy 161.036214 -402.768549)
			(xy 161.016684 -402.782756) (xy 160.993719 -402.790233) (xy 160.981644 -402.79066) (xy 160.78708 -402.79066)
			(xy 160.775972 -402.790292) (xy 160.754676 -402.783971) (xy 160.74517 -402.778214) (xy 160.450276 -402.585682)
			(xy 160.440889 -402.579979) (xy 160.419851 -402.573706) (xy 160.397897 -402.573706) (xy 160.376859 -402.579979)
			(xy 160.367472 -402.585682) (xy 160.073848 -402.778214) (xy 160.064336 -402.783959) (xy 160.043044 -402.790286)
			(xy 160.031938 -402.79066) (xy 159.836104 -402.79066) (xy 159.824017 -402.790283) (xy 159.801026 -402.782811)
			(xy 159.781471 -402.768597) (xy 159.767269 -402.749035) (xy 159.75981 -402.72604) (xy 159.759396 -402.713952)
			(xy 157.995112 -402.713952) (xy 157.994647 -402.726032) (xy 157.987193 -402.749012) (xy 157.973 -402.768563)
			(xy 157.953459 -402.782769) (xy 157.930484 -402.790238) (xy 157.918404 -402.79066) (xy 157.72384 -402.79066)
			(xy 157.712731 -402.790308) (xy 157.691435 -402.783976) (xy 157.68193 -402.778214) (xy 157.387036 -402.585682)
			(xy 157.377649 -402.579979) (xy 157.356611 -402.573706) (xy 157.334657 -402.573706) (xy 157.313619 -402.579979)
			(xy 157.304232 -402.585682) (xy 157.010608 -402.778214) (xy 157.001104 -402.783974) (xy 156.979806 -402.790292)
			(xy 156.968698 -402.79066) (xy 156.772864 -402.79066) (xy 156.760775 -402.790317) (xy 156.737783 -402.782834)
			(xy 156.718229 -402.768611) (xy 156.704028 -402.749042) (xy 156.69657 -402.726042) (xy 156.696156 -402.713952)
			(xy 154.931872 -402.713952) (xy 154.931446 -402.726036) (xy 154.923987 -402.749023) (xy 154.909786 -402.768577)
			(xy 154.890234 -402.782782) (xy 154.867248 -402.790244) (xy 154.855164 -402.79066) (xy 154.6606 -402.79066)
			(xy 154.649493 -402.790283) (xy 154.628197 -402.783968) (xy 154.61869 -402.778214) (xy 154.323796 -402.585682)
			(xy 154.314409 -402.579979) (xy 154.293371 -402.573706) (xy 154.271417 -402.573706) (xy 154.250379 -402.579979)
			(xy 154.240992 -402.585682) (xy 153.947368 -402.778214) (xy 153.937852 -402.783952) (xy 153.916563 -402.790284)
			(xy 153.905458 -402.79066) (xy 153.709624 -402.79066) (xy 153.697538 -402.790266) (xy 153.674548 -402.782799)
			(xy 153.654993 -402.76859) (xy 153.64079 -402.749031) (xy 153.63333 -402.726038) (xy 153.632916 -402.713952)
			(xy 151.868632 -402.713952) (xy 151.868147 -402.72603) (xy 151.860695 -402.749007) (xy 151.846507 -402.768556)
			(xy 151.826972 -402.782763) (xy 151.804001 -402.790236) (xy 151.791924 -402.79066) (xy 151.59736 -402.79066)
			(xy 151.586252 -402.7903) (xy 151.564956 -402.783973) (xy 151.55545 -402.778214) (xy 151.260556 -402.585682)
			(xy 151.251169 -402.579979) (xy 151.230131 -402.573706) (xy 151.208177 -402.573706) (xy 151.187139 -402.579979)
			(xy 151.177752 -402.585682) (xy 150.884128 -402.778214) (xy 150.87462 -402.783966) (xy 150.853325 -402.790289)
			(xy 150.842218 -402.79066) (xy 150.646384 -402.79066) (xy 150.634296 -402.7903) (xy 150.611304 -402.782823)
			(xy 150.59175 -402.768604) (xy 150.577548 -402.749038) (xy 150.57009 -402.726041) (xy 150.569676 -402.713952)
			(xy 148.805392 -402.713952) (xy 148.804946 -402.726034) (xy 148.79749 -402.749018) (xy 148.783293 -402.76857)
			(xy 148.763746 -402.782775) (xy 148.740766 -402.790241) (xy 148.728684 -402.79066) (xy 148.53412 -402.79066)
			(xy 148.52301 -402.790316) (xy 148.501714 -402.783978) (xy 148.49221 -402.778214) (xy 148.197316 -402.585682)
			(xy 148.187929 -402.579979) (xy 148.166891 -402.573706) (xy 148.144937 -402.573706) (xy 148.123899 -402.579979)
			(xy 148.114512 -402.585682) (xy 147.820888 -402.778214) (xy 147.811388 -402.783981) (xy 147.790087 -402.790295)
			(xy 147.778978 -402.79066) (xy 147.583144 -402.79066) (xy 147.571059 -402.790249) (xy 147.548069 -402.782788)
			(xy 147.528514 -402.768583) (xy 147.51431 -402.749027) (xy 147.50685 -402.726037) (xy 147.506436 -402.713952)
			(xy 145.742152 -402.713952) (xy 145.741647 -402.726028) (xy 145.734198 -402.749002) (xy 145.720014 -402.768549)
			(xy 145.700484 -402.782756) (xy 145.677519 -402.790233) (xy 145.665444 -402.79066) (xy 145.47088 -402.79066)
			(xy 145.459772 -402.790292) (xy 145.438476 -402.783971) (xy 145.42897 -402.778214) (xy 145.134076 -402.585682)
			(xy 145.124689 -402.579979) (xy 145.103651 -402.573706) (xy 145.081697 -402.573706) (xy 145.060659 -402.579979)
			(xy 145.051272 -402.585682) (xy 144.757648 -402.778214) (xy 144.748136 -402.783959) (xy 144.726844 -402.790286)
			(xy 144.715738 -402.79066) (xy 144.519904 -402.79066) (xy 144.507817 -402.790283) (xy 144.484826 -402.782811)
			(xy 144.465271 -402.768597) (xy 144.451069 -402.749035) (xy 144.44361 -402.72604) (xy 144.443196 -402.713952)
			(xy 142.678912 -402.713952) (xy 142.678447 -402.726032) (xy 142.670993 -402.749012) (xy 142.6568 -402.768563)
			(xy 142.637259 -402.782769) (xy 142.614284 -402.790238) (xy 142.602204 -402.79066) (xy 142.40764 -402.79066)
			(xy 142.396531 -402.790308) (xy 142.375235 -402.783976) (xy 142.36573 -402.778214) (xy 142.070836 -402.585682)
			(xy 142.061449 -402.579979) (xy 142.040411 -402.573706) (xy 142.018457 -402.573706) (xy 141.997419 -402.579979)
			(xy 141.988032 -402.585682) (xy 141.694408 -402.778214) (xy 141.684904 -402.783974) (xy 141.663606 -402.790292)
			(xy 141.652498 -402.79066) (xy 141.456664 -402.79066) (xy 141.444575 -402.790317) (xy 141.421583 -402.782834)
			(xy 141.402029 -402.768611) (xy 141.387828 -402.749042) (xy 141.38037 -402.726042) (xy 141.379956 -402.713952)
			(xy 139.615672 -402.713952) (xy 139.615246 -402.726036) (xy 139.607787 -402.749023) (xy 139.593586 -402.768577)
			(xy 139.574034 -402.782782) (xy 139.551048 -402.790244) (xy 139.538964 -402.79066) (xy 139.3444 -402.79066)
			(xy 139.333293 -402.790283) (xy 139.311997 -402.783968) (xy 139.30249 -402.778214) (xy 139.007596 -402.585682)
			(xy 138.998209 -402.579979) (xy 138.977171 -402.573706) (xy 138.955217 -402.573706) (xy 138.934179 -402.579979)
			(xy 138.924792 -402.585682) (xy 138.631168 -402.778214) (xy 138.621652 -402.783952) (xy 138.600363 -402.790284)
			(xy 138.589258 -402.79066) (xy 138.393424 -402.79066) (xy 138.381338 -402.790266) (xy 138.358348 -402.782799)
			(xy 138.338793 -402.76859) (xy 138.32459 -402.749031) (xy 138.31713 -402.726038) (xy 138.316716 -402.713952)
			(xy 136.552432 -402.713952) (xy 136.551947 -402.72603) (xy 136.544495 -402.749007) (xy 136.530307 -402.768556)
			(xy 136.510772 -402.782763) (xy 136.487801 -402.790236) (xy 136.475724 -402.79066) (xy 136.28116 -402.79066)
			(xy 136.270052 -402.7903) (xy 136.248756 -402.783973) (xy 136.23925 -402.778214) (xy 135.944356 -402.585682)
			(xy 135.934969 -402.579979) (xy 135.913931 -402.573706) (xy 135.891977 -402.573706) (xy 135.870939 -402.579979)
			(xy 135.861552 -402.585682) (xy 135.567928 -402.778214) (xy 135.55842 -402.783966) (xy 135.537125 -402.790289)
			(xy 135.526018 -402.79066) (xy 135.330184 -402.79066) (xy 135.318096 -402.7903) (xy 135.295104 -402.782823)
			(xy 135.27555 -402.768604) (xy 135.261348 -402.749038) (xy 135.25389 -402.726041) (xy 135.253476 -402.713952)
			(xy 133.489192 -402.713952) (xy 133.488746 -402.726034) (xy 133.48129 -402.749018) (xy 133.467093 -402.76857)
			(xy 133.447546 -402.782775) (xy 133.424566 -402.790241) (xy 133.412484 -402.79066) (xy 133.21792 -402.79066)
			(xy 133.20681 -402.790316) (xy 133.185514 -402.783978) (xy 133.17601 -402.778214) (xy 132.881116 -402.585682)
			(xy 132.871729 -402.579979) (xy 132.850691 -402.573706) (xy 132.828737 -402.573706) (xy 132.807699 -402.579979)
			(xy 132.798312 -402.585682) (xy 132.504688 -402.778214) (xy 132.495188 -402.783981) (xy 132.473887 -402.790295)
			(xy 132.462778 -402.79066) (xy 132.266944 -402.79066) (xy 132.254859 -402.790249) (xy 132.231869 -402.782788)
			(xy 132.212314 -402.768583) (xy 132.19811 -402.749027) (xy 132.19065 -402.726037) (xy 132.190236 -402.713952)
			(xy 130.425952 -402.713952) (xy 130.425447 -402.726028) (xy 130.417998 -402.749002) (xy 130.403814 -402.768549)
			(xy 130.384284 -402.782756) (xy 130.361319 -402.790233) (xy 130.349244 -402.79066) (xy 130.15468 -402.79066)
			(xy 130.143572 -402.790292) (xy 130.122276 -402.783971) (xy 130.11277 -402.778214) (xy 129.817876 -402.585682)
			(xy 129.808489 -402.579979) (xy 129.787451 -402.573706) (xy 129.765497 -402.573706) (xy 129.744459 -402.579979)
			(xy 129.735072 -402.585682) (xy 129.441448 -402.778214) (xy 129.431936 -402.783959) (xy 129.410644 -402.790286)
			(xy 129.399538 -402.79066) (xy 129.203704 -402.79066) (xy 129.191617 -402.790283) (xy 129.168626 -402.782811)
			(xy 129.149071 -402.768597) (xy 129.134869 -402.749035) (xy 129.12741 -402.72604) (xy 129.126996 -402.713952)
			(xy 127.362712 -402.713952) (xy 127.362247 -402.726032) (xy 127.354793 -402.749012) (xy 127.3406 -402.768563)
			(xy 127.321059 -402.782769) (xy 127.298084 -402.790238) (xy 127.286004 -402.79066) (xy 127.09144 -402.79066)
			(xy 127.080331 -402.790308) (xy 127.059035 -402.783976) (xy 127.04953 -402.778214) (xy 126.754636 -402.585682)
			(xy 126.745249 -402.579979) (xy 126.724211 -402.573706) (xy 126.702257 -402.573706) (xy 126.681219 -402.579979)
			(xy 126.671832 -402.585682) (xy 126.378208 -402.778214) (xy 126.368704 -402.783974) (xy 126.347406 -402.790292)
			(xy 126.336298 -402.79066) (xy 126.140464 -402.79066) (xy 126.128375 -402.790317) (xy 126.105383 -402.782834)
			(xy 126.085829 -402.768611) (xy 126.071628 -402.749042) (xy 126.06417 -402.726042) (xy 126.063756 -402.713952)
			(xy 124.299472 -402.713952) (xy 124.299046 -402.726036) (xy 124.291587 -402.749023) (xy 124.277386 -402.768577)
			(xy 124.257834 -402.782782) (xy 124.234848 -402.790244) (xy 124.222764 -402.79066) (xy 124.0282 -402.79066)
			(xy 124.017093 -402.790283) (xy 123.995797 -402.783968) (xy 123.98629 -402.778214) (xy 123.691396 -402.585682)
			(xy 123.682009 -402.579979) (xy 123.660971 -402.573706) (xy 123.639017 -402.573706) (xy 123.617979 -402.579979)
			(xy 123.608592 -402.585682) (xy 123.314968 -402.778214) (xy 123.305452 -402.783952) (xy 123.284163 -402.790284)
			(xy 123.273058 -402.79066) (xy 123.077224 -402.79066) (xy 123.065138 -402.790266) (xy 123.042148 -402.782799)
			(xy 123.022593 -402.76859) (xy 123.00839 -402.749031) (xy 123.00093 -402.726038) (xy 123.000516 -402.713952)
			(xy 121.236232 -402.713952) (xy 121.235747 -402.72603) (xy 121.228295 -402.749007) (xy 121.214107 -402.768556)
			(xy 121.194572 -402.782763) (xy 121.171601 -402.790236) (xy 121.159524 -402.79066) (xy 120.96496 -402.79066)
			(xy 120.953852 -402.7903) (xy 120.932556 -402.783973) (xy 120.92305 -402.778214) (xy 120.628156 -402.585682)
			(xy 120.618769 -402.579979) (xy 120.597731 -402.573706) (xy 120.575777 -402.573706) (xy 120.554739 -402.579979)
			(xy 120.545352 -402.585682) (xy 120.251728 -402.778214) (xy 120.24222 -402.783966) (xy 120.220925 -402.790289)
			(xy 120.209818 -402.79066) (xy 120.013984 -402.79066) (xy 120.001896 -402.7903) (xy 119.978904 -402.782823)
			(xy 119.95935 -402.768604) (xy 119.945148 -402.749038) (xy 119.93769 -402.726041) (xy 119.937276 -402.713952)
			(xy 99.770314 -402.713952) (xy 99.755922 -402.762968) (xy 99.733269 -402.812573) (xy 99.703787 -402.858449)
			(xy 99.668077 -402.899663) (xy 99.626865 -402.935375) (xy 99.58099 -402.964859) (xy 99.531387 -402.987515)
			(xy 99.479063 -403.002881) (xy 99.425086 -403.010644) (xy 99.39782 -403.011132) (xy 98.53422 -403.011132)
			(xy 98.506946 -403.01073) (xy 98.452953 -403.002969) (xy 98.400613 -402.987604) (xy 98.350994 -402.964945)
			(xy 98.305104 -402.935456) (xy 98.263878 -402.899736) (xy 98.228156 -402.858512) (xy 98.198664 -402.812624)
			(xy 98.176003 -402.763005) (xy 98.160635 -402.710667) (xy 98.152872 -402.656674) (xy 95.009716 -402.656674)
			(xy 95.009716 -402.713952) (xy 95.009247 -402.726031) (xy 95.001793 -402.749011) (xy 94.987601 -402.768562)
			(xy 94.968061 -402.782768) (xy 94.945087 -402.790238) (xy 94.933008 -402.79066) (xy 94.738444 -402.79066)
			(xy 94.727335 -402.790306) (xy 94.706039 -402.783975) (xy 94.696534 -402.778214) (xy 94.40164 -402.585682)
			(xy 94.392253 -402.579979) (xy 94.371215 -402.573706) (xy 94.349261 -402.573706) (xy 94.328223 -402.579979)
			(xy 94.318836 -402.585682) (xy 94.025212 -402.778214) (xy 94.015707 -402.783972) (xy 93.99441 -402.790291)
			(xy 93.983302 -402.79066) (xy 93.787468 -402.79066) (xy 93.775379 -402.790314) (xy 93.752387 -402.782832)
			(xy 93.732833 -402.76861) (xy 93.718632 -402.749041) (xy 93.711174 -402.726042) (xy 93.71076 -402.713952)
			(xy 91.946476 -402.713952) (xy 91.946046 -402.726035) (xy 91.938588 -402.749022) (xy 91.924387 -402.768576)
			(xy 91.904836 -402.78278) (xy 91.881851 -402.790243) (xy 91.869768 -402.79066) (xy 91.675204 -402.79066)
			(xy 91.664097 -402.790282) (xy 91.642801 -402.783968) (xy 91.633294 -402.778214) (xy 91.3384 -402.585682)
			(xy 91.329013 -402.579979) (xy 91.307975 -402.573706) (xy 91.286021 -402.573706) (xy 91.264983 -402.579979)
			(xy 91.255596 -402.585682) (xy 90.961972 -402.778214) (xy 90.952455 -402.78395) (xy 90.931167 -402.790283)
			(xy 90.920062 -402.79066) (xy 90.724228 -402.79066) (xy 90.712142 -402.790263) (xy 90.689152 -402.782797)
			(xy 90.669597 -402.768589) (xy 90.655394 -402.74903) (xy 90.647934 -402.726038) (xy 90.64752 -402.713952)
			(xy 88.883236 -402.713952) (xy 88.882747 -402.726029) (xy 88.875296 -402.749006) (xy 88.861109 -402.768555)
			(xy 88.841574 -402.782761) (xy 88.818605 -402.790235) (xy 88.806528 -402.79066) (xy 88.611964 -402.79066)
			(xy 88.600856 -402.790298) (xy 88.57956 -402.783973) (xy 88.570054 -402.778214) (xy 88.27516 -402.585682)
			(xy 88.265773 -402.579979) (xy 88.244735 -402.573706) (xy 88.222781 -402.573706) (xy 88.201743 -402.579979)
			(xy 88.192356 -402.585682) (xy 87.898732 -402.778214) (xy 87.889223 -402.783965) (xy 87.867929 -402.790289)
			(xy 87.856822 -402.79066) (xy 87.660988 -402.79066) (xy 87.6489 -402.790297) (xy 87.625909 -402.78282)
			(xy 87.606354 -402.768603) (xy 87.592152 -402.749038) (xy 87.584694 -402.72604) (xy 87.58428 -402.713952)
			(xy 85.819996 -402.713952) (xy 85.819546 -402.726033) (xy 85.81209 -402.749017) (xy 85.797894 -402.768569)
			(xy 85.778349 -402.782774) (xy 85.755369 -402.790241) (xy 85.743288 -402.79066) (xy 85.548724 -402.79066)
			(xy 85.537615 -402.790314) (xy 85.516318 -402.783978) (xy 85.506814 -402.778214) (xy 85.21192 -402.585682)
			(xy 85.202533 -402.579979) (xy 85.181495 -402.573706) (xy 85.159541 -402.573706) (xy 85.138503 -402.579979)
			(xy 85.129116 -402.585682) (xy 84.835492 -402.778214) (xy 84.825991 -402.78398) (xy 84.80469 -402.790294)
			(xy 84.793582 -402.79066) (xy 84.597748 -402.79066) (xy 84.585663 -402.790246) (xy 84.562674 -402.782786)
			(xy 84.543118 -402.768582) (xy 84.528914 -402.749026) (xy 84.521454 -402.726037) (xy 84.52104 -402.713952)
			(xy 82.756756 -402.713952) (xy 82.756196 -402.726019) (xy 82.748752 -402.748977) (xy 82.734579 -402.768511)
			(xy 82.715063 -402.782709) (xy 82.692115 -402.790181) (xy 82.680048 -402.79066) (xy 82.485484 -402.79066)
			(xy 82.474377 -402.79029) (xy 82.45308 -402.78397) (xy 82.443574 -402.778214) (xy 82.14868 -402.585682)
			(xy 82.139293 -402.579979) (xy 82.118255 -402.573706) (xy 82.096301 -402.573706) (xy 82.075263 -402.579979)
			(xy 82.065876 -402.585682) (xy 81.772252 -402.778214) (xy 81.762739 -402.783958) (xy 81.741448 -402.790286)
			(xy 81.730342 -402.79066) (xy 81.534508 -402.79066) (xy 81.522421 -402.79028) (xy 81.49943 -402.782809)
			(xy 81.479876 -402.768596) (xy 81.465673 -402.749034) (xy 81.458214 -402.726039) (xy 81.4578 -402.713952)
			(xy 79.693516 -402.713952) (xy 79.693047 -402.726031) (xy 79.685593 -402.749011) (xy 79.671401 -402.768562)
			(xy 79.651861 -402.782768) (xy 79.628887 -402.790238) (xy 79.616808 -402.79066) (xy 79.422244 -402.79066)
			(xy 79.411135 -402.790306) (xy 79.389839 -402.783975) (xy 79.380334 -402.778214) (xy 79.08544 -402.585682)
			(xy 79.076053 -402.579979) (xy 79.055015 -402.573706) (xy 79.033061 -402.573706) (xy 79.012023 -402.579979)
			(xy 79.002636 -402.585682) (xy 78.709012 -402.778214) (xy 78.699507 -402.783972) (xy 78.67821 -402.790291)
			(xy 78.667102 -402.79066) (xy 78.471268 -402.79066) (xy 78.459179 -402.790314) (xy 78.436187 -402.782832)
			(xy 78.416633 -402.76861) (xy 78.402432 -402.749041) (xy 78.394974 -402.726042) (xy 78.39456 -402.713952)
			(xy 76.630276 -402.713952) (xy 76.629846 -402.726035) (xy 76.622388 -402.749022) (xy 76.608187 -402.768576)
			(xy 76.588636 -402.78278) (xy 76.565651 -402.790243) (xy 76.553568 -402.79066) (xy 76.359004 -402.79066)
			(xy 76.347897 -402.790282) (xy 76.326601 -402.783968) (xy 76.317094 -402.778214) (xy 76.0222 -402.585682)
			(xy 76.012813 -402.579979) (xy 75.991775 -402.573706) (xy 75.969821 -402.573706) (xy 75.948783 -402.579979)
			(xy 75.939396 -402.585682) (xy 75.645772 -402.778214) (xy 75.636255 -402.78395) (xy 75.614967 -402.790283)
			(xy 75.603862 -402.79066) (xy 75.408028 -402.79066) (xy 75.395942 -402.790263) (xy 75.372952 -402.782797)
			(xy 75.353397 -402.768589) (xy 75.339194 -402.74903) (xy 75.331734 -402.726038) (xy 75.33132 -402.713952)
			(xy 73.567036 -402.713952) (xy 73.566547 -402.726029) (xy 73.559096 -402.749006) (xy 73.544909 -402.768555)
			(xy 73.525374 -402.782761) (xy 73.502405 -402.790235) (xy 73.490328 -402.79066) (xy 73.295764 -402.79066)
			(xy 73.284656 -402.790298) (xy 73.26336 -402.783973) (xy 73.253854 -402.778214) (xy 72.95896 -402.585682)
			(xy 72.949573 -402.579979) (xy 72.928535 -402.573706) (xy 72.906581 -402.573706) (xy 72.885543 -402.579979)
			(xy 72.876156 -402.585682) (xy 72.582532 -402.778214) (xy 72.573023 -402.783965) (xy 72.551729 -402.790289)
			(xy 72.540622 -402.79066) (xy 72.344788 -402.79066) (xy 72.3327 -402.790297) (xy 72.309709 -402.78282)
			(xy 72.290154 -402.768603) (xy 72.275952 -402.749038) (xy 72.268494 -402.72604) (xy 72.26808 -402.713952)
			(xy 70.503796 -402.713952) (xy 70.503346 -402.726033) (xy 70.49589 -402.749017) (xy 70.481694 -402.768569)
			(xy 70.462149 -402.782774) (xy 70.439169 -402.790241) (xy 70.427088 -402.79066) (xy 70.232524 -402.79066)
			(xy 70.221415 -402.790314) (xy 70.200118 -402.783978) (xy 70.190614 -402.778214) (xy 69.89572 -402.585682)
			(xy 69.886333 -402.579979) (xy 69.865295 -402.573706) (xy 69.843341 -402.573706) (xy 69.822303 -402.579979)
			(xy 69.812916 -402.585682) (xy 69.519292 -402.778214) (xy 69.509791 -402.78398) (xy 69.48849 -402.790294)
			(xy 69.477382 -402.79066) (xy 69.281548 -402.79066) (xy 69.269463 -402.790246) (xy 69.246474 -402.782786)
			(xy 69.226918 -402.768582) (xy 69.212714 -402.749026) (xy 69.205254 -402.726037) (xy 69.20484 -402.713952)
			(xy 67.440556 -402.713952) (xy 67.439996 -402.726019) (xy 67.432552 -402.748977) (xy 67.418379 -402.768511)
			(xy 67.398863 -402.782709) (xy 67.375915 -402.790181) (xy 67.363848 -402.79066) (xy 67.169284 -402.79066)
			(xy 67.158177 -402.79029) (xy 67.13688 -402.78397) (xy 67.127374 -402.778214) (xy 66.83248 -402.585682)
			(xy 66.823093 -402.579979) (xy 66.802055 -402.573706) (xy 66.780101 -402.573706) (xy 66.759063 -402.579979)
			(xy 66.749676 -402.585682) (xy 66.456052 -402.778214) (xy 66.446539 -402.783958) (xy 66.425248 -402.790286)
			(xy 66.414142 -402.79066) (xy 66.218308 -402.79066) (xy 66.206221 -402.79028) (xy 66.18323 -402.782809)
			(xy 66.163676 -402.768596) (xy 66.149473 -402.749034) (xy 66.142014 -402.726039) (xy 66.1416 -402.713952)
			(xy 64.377316 -402.713952) (xy 64.376847 -402.726031) (xy 64.369393 -402.749011) (xy 64.355201 -402.768562)
			(xy 64.335661 -402.782768) (xy 64.312687 -402.790238) (xy 64.300608 -402.79066) (xy 64.106044 -402.79066)
			(xy 64.094935 -402.790306) (xy 64.073639 -402.783975) (xy 64.064134 -402.778214) (xy 63.76924 -402.585682)
			(xy 63.759853 -402.579979) (xy 63.738815 -402.573706) (xy 63.716861 -402.573706) (xy 63.695823 -402.579979)
			(xy 63.686436 -402.585682) (xy 63.392812 -402.778214) (xy 63.383307 -402.783972) (xy 63.36201 -402.790291)
			(xy 63.350902 -402.79066) (xy 63.155068 -402.79066) (xy 63.142979 -402.790314) (xy 63.119987 -402.782832)
			(xy 63.100433 -402.76861) (xy 63.086232 -402.749041) (xy 63.078774 -402.726042) (xy 63.07836 -402.713952)
			(xy 61.314076 -402.713952) (xy 61.313646 -402.726035) (xy 61.306188 -402.749022) (xy 61.291987 -402.768576)
			(xy 61.272436 -402.78278) (xy 61.249451 -402.790243) (xy 61.237368 -402.79066) (xy 61.042804 -402.79066)
			(xy 61.031697 -402.790282) (xy 61.010401 -402.783968) (xy 61.000894 -402.778214) (xy 60.706 -402.585682)
			(xy 60.696613 -402.579979) (xy 60.675575 -402.573706) (xy 60.653621 -402.573706) (xy 60.632583 -402.579979)
			(xy 60.623196 -402.585682) (xy 60.329572 -402.778214) (xy 60.320055 -402.78395) (xy 60.298767 -402.790283)
			(xy 60.287662 -402.79066) (xy 60.091828 -402.79066) (xy 60.079742 -402.790263) (xy 60.056752 -402.782797)
			(xy 60.037197 -402.768589) (xy 60.022994 -402.74903) (xy 60.015534 -402.726038) (xy 60.01512 -402.713952)
			(xy 58.250836 -402.713952) (xy 58.250347 -402.726029) (xy 58.242896 -402.749006) (xy 58.228709 -402.768555)
			(xy 58.209174 -402.782761) (xy 58.186205 -402.790235) (xy 58.174128 -402.79066) (xy 57.979564 -402.79066)
			(xy 57.968456 -402.790298) (xy 57.94716 -402.783973) (xy 57.937654 -402.778214) (xy 57.64276 -402.585682)
			(xy 57.633373 -402.579979) (xy 57.612335 -402.573706) (xy 57.590381 -402.573706) (xy 57.569343 -402.579979)
			(xy 57.559956 -402.585682) (xy 57.266332 -402.778214) (xy 57.256823 -402.783965) (xy 57.235529 -402.790289)
			(xy 57.224422 -402.79066) (xy 57.028588 -402.79066) (xy 57.0165 -402.790297) (xy 56.993509 -402.78282)
			(xy 56.973954 -402.768603) (xy 56.959752 -402.749038) (xy 56.952294 -402.72604) (xy 56.95188 -402.713952)
			(xy 55.187596 -402.713952) (xy 55.187146 -402.726033) (xy 55.17969 -402.749017) (xy 55.165494 -402.768569)
			(xy 55.145949 -402.782774) (xy 55.122969 -402.790241) (xy 55.110888 -402.79066) (xy 54.916324 -402.79066)
			(xy 54.905215 -402.790314) (xy 54.883918 -402.783978) (xy 54.874414 -402.778214) (xy 54.57952 -402.585682)
			(xy 54.570133 -402.579979) (xy 54.549095 -402.573706) (xy 54.527141 -402.573706) (xy 54.506103 -402.579979)
			(xy 54.496716 -402.585682) (xy 54.203092 -402.778214) (xy 54.193591 -402.78398) (xy 54.17229 -402.790294)
			(xy 54.161182 -402.79066) (xy 53.965348 -402.79066) (xy 53.953263 -402.790246) (xy 53.930274 -402.782786)
			(xy 53.910718 -402.768582) (xy 53.896514 -402.749026) (xy 53.889054 -402.726037) (xy 53.88864 -402.713952)
			(xy 52.124356 -402.713952) (xy 52.123796 -402.726019) (xy 52.116352 -402.748977) (xy 52.102179 -402.768511)
			(xy 52.082663 -402.782709) (xy 52.059715 -402.790181) (xy 52.047648 -402.79066) (xy 51.853084 -402.79066)
			(xy 51.841977 -402.79029) (xy 51.82068 -402.78397) (xy 51.811174 -402.778214) (xy 51.51628 -402.585682)
			(xy 51.506893 -402.579979) (xy 51.485855 -402.573706) (xy 51.463901 -402.573706) (xy 51.442863 -402.579979)
			(xy 51.433476 -402.585682) (xy 51.139852 -402.778214) (xy 51.130339 -402.783958) (xy 51.109048 -402.790286)
			(xy 51.097942 -402.79066) (xy 50.902108 -402.79066) (xy 50.890021 -402.79028) (xy 50.86703 -402.782809)
			(xy 50.847476 -402.768596) (xy 50.833273 -402.749034) (xy 50.825814 -402.726039) (xy 50.8254 -402.713952)
			(xy 49.061116 -402.713952) (xy 49.060647 -402.726031) (xy 49.053193 -402.749011) (xy 49.039001 -402.768562)
			(xy 49.019461 -402.782768) (xy 48.996487 -402.790238) (xy 48.984408 -402.79066) (xy 48.789844 -402.79066)
			(xy 48.778735 -402.790306) (xy 48.757439 -402.783975) (xy 48.747934 -402.778214) (xy 48.45304 -402.585682)
			(xy 48.443653 -402.579979) (xy 48.422615 -402.573706) (xy 48.400661 -402.573706) (xy 48.379623 -402.579979)
			(xy 48.370236 -402.585682) (xy 48.076612 -402.778214) (xy 48.067107 -402.783972) (xy 48.04581 -402.790291)
			(xy 48.034702 -402.79066) (xy 47.838868 -402.79066) (xy 47.826779 -402.790314) (xy 47.803787 -402.782832)
			(xy 47.784233 -402.76861) (xy 47.770032 -402.749041) (xy 47.762574 -402.726042) (xy 47.76216 -402.713952)
			(xy 2.509012 -402.713952) (xy 2.509012 -403.371812) (xy 2.5095 -403.425034) (xy 2.517117 -403.531207)
			(xy 2.532283 -403.636566) (xy 2.554922 -403.740575) (xy 2.584919 -403.842706) (xy 2.610452 -403.911156)
			(xy 47.598731 -403.911156) (xy 47.598731 -403.856644) (xy 47.606489 -403.802686) (xy 47.621848 -403.750382)
			(xy 47.644495 -403.700796) (xy 47.673969 -403.654938) (xy 47.709669 -403.613742) (xy 47.750868 -403.578046)
			(xy 47.796729 -403.548577) (xy 47.846317 -403.525935) (xy 47.898623 -403.510581) (xy 47.952582 -403.502828)
			(xy 47.979838 -403.502368) (xy 48.843438 -403.502368) (xy 48.870686 -403.502905) (xy 48.924626 -403.510665)
			(xy 48.976913 -403.526023) (xy 49.026482 -403.548665) (xy 49.072325 -403.57813) (xy 49.113508 -403.613819)
			(xy 49.149193 -403.655006) (xy 49.178654 -403.700851) (xy 49.201291 -403.750423) (xy 49.216643 -403.802711)
			(xy 49.224398 -403.856652) (xy 49.224398 -403.911148) (xy 49.224397 -403.911152) (xy 50.662054 -403.911152)
			(xy 50.662054 -403.856648) (xy 50.66981 -403.802699) (xy 50.685165 -403.750403) (xy 50.707806 -403.700824)
			(xy 50.737272 -403.654971) (xy 50.772964 -403.613779) (xy 50.814154 -403.578085) (xy 50.860004 -403.548617)
			(xy 50.909582 -403.525973) (xy 50.961877 -403.510615) (xy 51.015826 -403.502855) (xy 51.043078 -403.502368)
			(xy 51.906678 -403.502368) (xy 51.93393 -403.502878) (xy 51.98788 -403.510632) (xy 52.040177 -403.525985)
			(xy 52.089757 -403.548625) (xy 52.13561 -403.57809) (xy 52.176803 -403.613782) (xy 52.212497 -403.654972)
			(xy 52.241965 -403.700824) (xy 52.264607 -403.750402) (xy 52.279964 -403.802698) (xy 52.287721 -403.856648)
			(xy 52.287721 -403.911152) (xy 52.287721 -403.911155) (xy 53.725231 -403.911155) (xy 53.725231 -403.856645)
			(xy 53.732989 -403.802689) (xy 53.748347 -403.750386) (xy 53.770992 -403.700801) (xy 53.800464 -403.654945)
			(xy 53.836162 -403.613749) (xy 53.877359 -403.578053) (xy 53.923217 -403.548583) (xy 53.972803 -403.525941)
			(xy 54.025106 -403.510585) (xy 54.079063 -403.50283) (xy 54.106318 -403.502368) (xy 54.969918 -403.502368)
			(xy 54.997167 -403.502903) (xy 55.051109 -403.510662) (xy 55.103398 -403.526017) (xy 55.15297 -403.548658)
			(xy 55.198815 -403.578123) (xy 55.240001 -403.613812) (xy 55.275688 -403.654999) (xy 55.305151 -403.700846)
			(xy 55.327789 -403.750419) (xy 55.343142 -403.802709) (xy 55.350898 -403.856651) (xy 55.350898 -403.911149)
			(xy 55.350898 -403.911151) (xy 56.788554 -403.911151) (xy 56.788554 -403.856649) (xy 56.79631 -403.802702)
			(xy 56.811664 -403.750407) (xy 56.834303 -403.700829) (xy 56.863767 -403.654978) (xy 56.899457 -403.613786)
			(xy 56.940644 -403.578093) (xy 56.986492 -403.548623) (xy 57.036067 -403.525978) (xy 57.08836 -403.510619)
			(xy 57.142307 -403.502857) (xy 57.169558 -403.502368) (xy 58.033158 -403.502368) (xy 58.060411 -403.502876)
			(xy 58.114363 -403.510628) (xy 58.166663 -403.525979) (xy 58.216245 -403.548618) (xy 58.262101 -403.578083)
			(xy 58.303296 -403.613775) (xy 58.338992 -403.654966) (xy 58.368462 -403.700818) (xy 58.391106 -403.750398)
			(xy 58.406463 -403.802696) (xy 58.414221 -403.856647) (xy 58.414221 -403.911153) (xy 59.851754 -403.911153)
			(xy 59.851754 -403.856647) (xy 59.859511 -403.802696) (xy 59.874867 -403.750398) (xy 59.897509 -403.700818)
			(xy 59.926977 -403.654965) (xy 59.962671 -403.613772) (xy 60.003863 -403.578078) (xy 60.049716 -403.54861)
			(xy 60.099296 -403.525967) (xy 60.151594 -403.510611) (xy 60.205545 -403.502854) (xy 60.232798 -403.502368)
			(xy 61.096398 -403.502368) (xy 61.123649 -403.502879) (xy 61.177597 -403.510635) (xy 61.229892 -403.52599)
			(xy 61.279469 -403.548631) (xy 61.32532 -403.578097) (xy 61.36651 -403.613789) (xy 61.402201 -403.654979)
			(xy 61.431668 -403.700829) (xy 61.454309 -403.750406) (xy 61.469664 -403.802701) (xy 61.477421 -403.856649)
			(xy 61.477421 -403.911151) (xy 61.47742 -403.911156) (xy 62.914931 -403.911156) (xy 62.914931 -403.856644)
			(xy 62.922689 -403.802686) (xy 62.938048 -403.750382) (xy 62.960695 -403.700796) (xy 62.990169 -403.654938)
			(xy 63.025869 -403.613742) (xy 63.067068 -403.578046) (xy 63.112929 -403.548577) (xy 63.162517 -403.525935)
			(xy 63.214823 -403.510581) (xy 63.268782 -403.502828) (xy 63.296038 -403.502368) (xy 64.159638 -403.502368)
			(xy 64.186886 -403.502905) (xy 64.240826 -403.510665) (xy 64.293113 -403.526023) (xy 64.342682 -403.548665)
			(xy 64.388525 -403.57813) (xy 64.429708 -403.613819) (xy 64.465393 -403.655006) (xy 64.494854 -403.700851)
			(xy 64.517491 -403.750423) (xy 64.532843 -403.802711) (xy 64.540598 -403.856652) (xy 64.540598 -403.911148)
			(xy 64.540597 -403.911152) (xy 65.978254 -403.911152) (xy 65.978254 -403.856648) (xy 65.98601 -403.802699)
			(xy 66.001365 -403.750403) (xy 66.024006 -403.700824) (xy 66.053472 -403.654971) (xy 66.089164 -403.613779)
			(xy 66.130354 -403.578085) (xy 66.176204 -403.548617) (xy 66.225782 -403.525973) (xy 66.278077 -403.510615)
			(xy 66.332026 -403.502855) (xy 66.359278 -403.502368) (xy 67.222878 -403.502368) (xy 67.25013 -403.502878)
			(xy 67.30408 -403.510632) (xy 67.356377 -403.525985) (xy 67.405957 -403.548625) (xy 67.45181 -403.57809)
			(xy 67.493003 -403.613782) (xy 67.528697 -403.654972) (xy 67.558165 -403.700824) (xy 67.580807 -403.750402)
			(xy 67.596164 -403.802698) (xy 67.603921 -403.856648) (xy 67.603921 -403.911152) (xy 67.603921 -403.911155)
			(xy 69.041431 -403.911155) (xy 69.041431 -403.856645) (xy 69.049189 -403.802689) (xy 69.064547 -403.750386)
			(xy 69.087192 -403.700801) (xy 69.116664 -403.654945) (xy 69.152362 -403.613749) (xy 69.193559 -403.578053)
			(xy 69.239417 -403.548583) (xy 69.289003 -403.525941) (xy 69.341306 -403.510585) (xy 69.395263 -403.50283)
			(xy 69.422518 -403.502368) (xy 70.286118 -403.502368) (xy 70.313367 -403.502903) (xy 70.367309 -403.510662)
			(xy 70.419598 -403.526017) (xy 70.46917 -403.548658) (xy 70.515015 -403.578123) (xy 70.556201 -403.613812)
			(xy 70.591888 -403.654999) (xy 70.621351 -403.700846) (xy 70.643989 -403.750419) (xy 70.659342 -403.802709)
			(xy 70.667098 -403.856651) (xy 70.667098 -403.911149) (xy 70.667098 -403.911151) (xy 72.104754 -403.911151)
			(xy 72.104754 -403.856649) (xy 72.11251 -403.802702) (xy 72.127864 -403.750407) (xy 72.150503 -403.700829)
			(xy 72.179967 -403.654978) (xy 72.215657 -403.613786) (xy 72.256844 -403.578093) (xy 72.302692 -403.548623)
			(xy 72.352267 -403.525978) (xy 72.40456 -403.510619) (xy 72.458507 -403.502857) (xy 72.485758 -403.502368)
			(xy 73.349358 -403.502368) (xy 73.376611 -403.502876) (xy 73.430563 -403.510628) (xy 73.482863 -403.525979)
			(xy 73.532445 -403.548618) (xy 73.578301 -403.578083) (xy 73.619496 -403.613775) (xy 73.655192 -403.654966)
			(xy 73.684662 -403.700818) (xy 73.707306 -403.750398) (xy 73.722663 -403.802696) (xy 73.730421 -403.856647)
			(xy 73.730421 -403.911153) (xy 75.167954 -403.911153) (xy 75.167954 -403.856647) (xy 75.175711 -403.802696)
			(xy 75.191067 -403.750398) (xy 75.213709 -403.700818) (xy 75.243177 -403.654965) (xy 75.278871 -403.613772)
			(xy 75.320063 -403.578078) (xy 75.365916 -403.54861) (xy 75.415496 -403.525967) (xy 75.467794 -403.510611)
			(xy 75.521745 -403.502854) (xy 75.548998 -403.502368) (xy 76.412598 -403.502368) (xy 76.439849 -403.502879)
			(xy 76.493797 -403.510635) (xy 76.546092 -403.52599) (xy 76.595669 -403.548631) (xy 76.64152 -403.578097)
			(xy 76.68271 -403.613789) (xy 76.718401 -403.654979) (xy 76.747868 -403.700829) (xy 76.770509 -403.750406)
			(xy 76.785864 -403.802701) (xy 76.793621 -403.856649) (xy 76.793621 -403.911151) (xy 76.79362 -403.911156)
			(xy 78.231131 -403.911156) (xy 78.231131 -403.856644) (xy 78.238889 -403.802686) (xy 78.254248 -403.750382)
			(xy 78.276895 -403.700796) (xy 78.306369 -403.654938) (xy 78.342069 -403.613742) (xy 78.383268 -403.578046)
			(xy 78.429129 -403.548577) (xy 78.478717 -403.525935) (xy 78.531023 -403.510581) (xy 78.584982 -403.502828)
			(xy 78.612238 -403.502368) (xy 79.475838 -403.502368) (xy 79.503086 -403.502905) (xy 79.557026 -403.510665)
			(xy 79.609313 -403.526023) (xy 79.658882 -403.548665) (xy 79.704725 -403.57813) (xy 79.745908 -403.613819)
			(xy 79.781593 -403.655006) (xy 79.811054 -403.700851) (xy 79.833691 -403.750423) (xy 79.849043 -403.802711)
			(xy 79.856798 -403.856652) (xy 79.856798 -403.911148) (xy 79.856797 -403.911152) (xy 81.294454 -403.911152)
			(xy 81.294454 -403.856648) (xy 81.30221 -403.802699) (xy 81.317565 -403.750403) (xy 81.340206 -403.700824)
			(xy 81.369672 -403.654971) (xy 81.405364 -403.613779) (xy 81.446554 -403.578085) (xy 81.492404 -403.548617)
			(xy 81.541982 -403.525973) (xy 81.594277 -403.510615) (xy 81.648226 -403.502855) (xy 81.675478 -403.502368)
			(xy 82.539078 -403.502368) (xy 82.56633 -403.502878) (xy 82.62028 -403.510632) (xy 82.672577 -403.525985)
			(xy 82.722157 -403.548625) (xy 82.76801 -403.57809) (xy 82.809203 -403.613782) (xy 82.844897 -403.654972)
			(xy 82.874365 -403.700824) (xy 82.897007 -403.750402) (xy 82.912364 -403.802698) (xy 82.920121 -403.856648)
			(xy 82.920121 -403.911152) (xy 82.920121 -403.911155) (xy 84.357631 -403.911155) (xy 84.357631 -403.856645)
			(xy 84.365389 -403.802689) (xy 84.380747 -403.750386) (xy 84.403392 -403.700801) (xy 84.432864 -403.654945)
			(xy 84.468562 -403.613749) (xy 84.509759 -403.578053) (xy 84.555617 -403.548583) (xy 84.605203 -403.525941)
			(xy 84.657506 -403.510585) (xy 84.711463 -403.50283) (xy 84.738718 -403.502368) (xy 85.602318 -403.502368)
			(xy 85.629567 -403.502903) (xy 85.683509 -403.510662) (xy 85.735798 -403.526017) (xy 85.78537 -403.548658)
			(xy 85.831215 -403.578123) (xy 85.872401 -403.613812) (xy 85.908088 -403.654999) (xy 85.937551 -403.700846)
			(xy 85.960189 -403.750419) (xy 85.975542 -403.802709) (xy 85.983298 -403.856651) (xy 85.983298 -403.911149)
			(xy 85.983298 -403.911151) (xy 87.420954 -403.911151) (xy 87.420954 -403.856649) (xy 87.42871 -403.802702)
			(xy 87.444064 -403.750407) (xy 87.466703 -403.700829) (xy 87.496167 -403.654978) (xy 87.531857 -403.613786)
			(xy 87.573044 -403.578093) (xy 87.618892 -403.548623) (xy 87.668467 -403.525978) (xy 87.72076 -403.510619)
			(xy 87.774707 -403.502857) (xy 87.801958 -403.502368) (xy 88.665558 -403.502368) (xy 88.692811 -403.502876)
			(xy 88.746763 -403.510628) (xy 88.799063 -403.525979) (xy 88.848645 -403.548618) (xy 88.894501 -403.578083)
			(xy 88.935696 -403.613775) (xy 88.971392 -403.654966) (xy 89.000862 -403.700818) (xy 89.023506 -403.750398)
			(xy 89.038863 -403.802696) (xy 89.046621 -403.856647) (xy 89.046621 -403.911153) (xy 90.484154 -403.911153)
			(xy 90.484154 -403.856647) (xy 90.491911 -403.802696) (xy 90.507267 -403.750398) (xy 90.529909 -403.700818)
			(xy 90.559377 -403.654965) (xy 90.595071 -403.613772) (xy 90.636263 -403.578078) (xy 90.682116 -403.54861)
			(xy 90.731696 -403.525967) (xy 90.783994 -403.510611) (xy 90.837945 -403.502854) (xy 90.865198 -403.502368)
			(xy 91.728798 -403.502368) (xy 91.756049 -403.502879) (xy 91.809997 -403.510635) (xy 91.862292 -403.52599)
			(xy 91.911869 -403.548631) (xy 91.95772 -403.578097) (xy 91.99891 -403.613789) (xy 92.034601 -403.654979)
			(xy 92.064068 -403.700829) (xy 92.086709 -403.750406) (xy 92.102064 -403.802701) (xy 92.109821 -403.856649)
			(xy 92.109821 -403.911151) (xy 92.10982 -403.911156) (xy 93.547331 -403.911156) (xy 93.547331 -403.856644)
			(xy 93.555089 -403.802686) (xy 93.570448 -403.750382) (xy 93.593095 -403.700796) (xy 93.622569 -403.654938)
			(xy 93.658269 -403.613742) (xy 93.699468 -403.578046) (xy 93.745329 -403.548577) (xy 93.794917 -403.525935)
			(xy 93.847223 -403.510581) (xy 93.901182 -403.502828) (xy 93.928438 -403.502368) (xy 94.792038 -403.502368)
			(xy 94.819286 -403.502905) (xy 94.873226 -403.510665) (xy 94.925513 -403.526023) (xy 94.975082 -403.548665)
			(xy 95.020925 -403.57813) (xy 95.062108 -403.613819) (xy 95.097793 -403.655006) (xy 95.127254 -403.700851)
			(xy 95.149891 -403.750423) (xy 95.165243 -403.802711) (xy 95.172998 -403.856652) (xy 95.172998 -403.911148)
			(xy 95.172998 -403.911151) (xy 119.773954 -403.911151) (xy 119.773954 -403.856649) (xy 119.78171 -403.802702)
			(xy 119.797063 -403.750408) (xy 119.819702 -403.70083) (xy 119.849166 -403.654979) (xy 119.884855 -403.613788)
			(xy 119.926042 -403.578094) (xy 119.97189 -403.548625) (xy 120.021465 -403.525979) (xy 120.073757 -403.510619)
			(xy 120.127703 -403.502857) (xy 120.154954 -403.502368) (xy 121.018554 -403.502368) (xy 121.045807 -403.502876)
			(xy 121.09976 -403.510627) (xy 121.15206 -403.525978) (xy 121.201643 -403.548617) (xy 121.247499 -403.578082)
			(xy 121.288694 -403.613773) (xy 121.324391 -403.654964) (xy 121.353861 -403.700817) (xy 121.376506 -403.750397)
			(xy 121.391863 -403.802695) (xy 121.399621 -403.856647) (xy 121.399621 -403.911153) (xy 122.837154 -403.911153)
			(xy 122.837154 -403.856647) (xy 122.844911 -403.802697) (xy 122.860266 -403.750399) (xy 122.882909 -403.700819)
			(xy 122.912376 -403.654966) (xy 122.948069 -403.613774) (xy 122.989261 -403.57808) (xy 123.035114 -403.548611)
			(xy 123.084694 -403.525969) (xy 123.136991 -403.510612) (xy 123.190941 -403.502854) (xy 123.218194 -403.502368)
			(xy 124.081794 -403.502368) (xy 124.109045 -403.502879) (xy 124.162994 -403.510635) (xy 124.215289 -403.525989)
			(xy 124.264867 -403.54863) (xy 124.310718 -403.578096) (xy 124.351908 -403.613787) (xy 124.3876 -403.654978)
			(xy 124.417067 -403.700828) (xy 124.439709 -403.750406) (xy 124.455064 -403.802701) (xy 124.462821 -403.856649)
			(xy 124.462821 -403.911151) (xy 124.46282 -403.911156) (xy 125.900331 -403.911156) (xy 125.900331 -403.856644)
			(xy 125.908089 -403.802686) (xy 125.923448 -403.750383) (xy 125.946095 -403.700797) (xy 125.975568 -403.654939)
			(xy 126.011267 -403.613743) (xy 126.052467 -403.578047) (xy 126.098327 -403.548578) (xy 126.147914 -403.525936)
			(xy 126.20022 -403.510582) (xy 126.254178 -403.502829) (xy 126.281434 -403.502368) (xy 127.145034 -403.502368)
			(xy 127.172282 -403.502905) (xy 127.226223 -403.510664) (xy 127.27851 -403.526022) (xy 127.32808 -403.548663)
			(xy 127.373923 -403.578129) (xy 127.415106 -403.613818) (xy 127.450792 -403.655004) (xy 127.480253 -403.70085)
			(xy 127.50289 -403.750422) (xy 127.518243 -403.802711) (xy 127.525998 -403.856652) (xy 127.525998 -403.911148)
			(xy 127.525997 -403.911152) (xy 128.963654 -403.911152) (xy 128.963654 -403.856648) (xy 128.97141 -403.802699)
			(xy 128.986765 -403.750403) (xy 129.009406 -403.700825) (xy 129.038871 -403.654973) (xy 129.074562 -403.613781)
			(xy 129.115752 -403.578087) (xy 129.161602 -403.548618) (xy 129.211179 -403.525974) (xy 129.263474 -403.510616)
			(xy 129.317422 -403.502856) (xy 129.344674 -403.502368) (xy 130.208274 -403.502368) (xy 130.235526 -403.502878)
			(xy 130.289477 -403.510631) (xy 130.341774 -403.525984) (xy 130.391355 -403.548623) (xy 130.437208 -403.578089)
			(xy 130.478401 -403.61378) (xy 130.514096 -403.654971) (xy 130.543564 -403.700822) (xy 130.566207 -403.750401)
			(xy 130.581563 -403.802698) (xy 130.589321 -403.856648) (xy 130.589321 -403.911152) (xy 130.589321 -403.911155)
			(xy 132.026831 -403.911155) (xy 132.026831 -403.856645) (xy 132.034589 -403.802689) (xy 132.049946 -403.750387)
			(xy 132.072591 -403.700803) (xy 132.102063 -403.654946) (xy 132.13776 -403.61375) (xy 132.178957 -403.578054)
			(xy 132.224815 -403.548585) (xy 132.2744 -403.525942) (xy 132.326703 -403.510586) (xy 132.380659 -403.50283)
			(xy 132.407914 -403.502368) (xy 133.271514 -403.502368) (xy 133.298763 -403.502903) (xy 133.352706 -403.510661)
			(xy 133.404995 -403.526016) (xy 133.454568 -403.548657) (xy 133.500413 -403.578121) (xy 133.541599 -403.613811)
			(xy 133.577287 -403.654998) (xy 133.60675 -403.700845) (xy 133.629389 -403.750418) (xy 133.644742 -403.802708)
			(xy 133.652498 -403.856651) (xy 133.652498 -403.911149) (xy 133.652498 -403.911151) (xy 135.090154 -403.911151)
			(xy 135.090154 -403.856649) (xy 135.09791 -403.802702) (xy 135.113263 -403.750408) (xy 135.135902 -403.70083)
			(xy 135.165366 -403.654979) (xy 135.201055 -403.613788) (xy 135.242242 -403.578094) (xy 135.28809 -403.548625)
			(xy 135.337665 -403.525979) (xy 135.389957 -403.510619) (xy 135.443903 -403.502857) (xy 135.471154 -403.502368)
			(xy 136.334754 -403.502368) (xy 136.362007 -403.502876) (xy 136.41596 -403.510627) (xy 136.46826 -403.525978)
			(xy 136.517843 -403.548617) (xy 136.563699 -403.578082) (xy 136.604894 -403.613773) (xy 136.640591 -403.654964)
			(xy 136.670061 -403.700817) (xy 136.692706 -403.750397) (xy 136.708063 -403.802695) (xy 136.715821 -403.856647)
			(xy 136.715821 -403.911153) (xy 138.153354 -403.911153) (xy 138.153354 -403.856647) (xy 138.161111 -403.802697)
			(xy 138.176466 -403.750399) (xy 138.199109 -403.700819) (xy 138.228576 -403.654966) (xy 138.264269 -403.613774)
			(xy 138.305461 -403.57808) (xy 138.351314 -403.548611) (xy 138.400894 -403.525969) (xy 138.453191 -403.510612)
			(xy 138.507141 -403.502854) (xy 138.534394 -403.502368) (xy 139.397994 -403.502368) (xy 139.425245 -403.502879)
			(xy 139.479194 -403.510635) (xy 139.531489 -403.525989) (xy 139.581067 -403.54863) (xy 139.626918 -403.578096)
			(xy 139.668108 -403.613787) (xy 139.7038 -403.654978) (xy 139.733267 -403.700828) (xy 139.755909 -403.750406)
			(xy 139.771264 -403.802701) (xy 139.779021 -403.856649) (xy 139.779021 -403.911151) (xy 139.77902 -403.911156)
			(xy 141.216531 -403.911156) (xy 141.216531 -403.856644) (xy 141.224289 -403.802686) (xy 141.239648 -403.750383)
			(xy 141.262295 -403.700797) (xy 141.291768 -403.654939) (xy 141.327467 -403.613743) (xy 141.368667 -403.578047)
			(xy 141.414527 -403.548578) (xy 141.464114 -403.525936) (xy 141.51642 -403.510582) (xy 141.570378 -403.502829)
			(xy 141.597634 -403.502368) (xy 142.461234 -403.502368) (xy 142.488482 -403.502905) (xy 142.542423 -403.510664)
			(xy 142.59471 -403.526022) (xy 142.64428 -403.548663) (xy 142.690123 -403.578129) (xy 142.731306 -403.613818)
			(xy 142.766992 -403.655004) (xy 142.796453 -403.70085) (xy 142.81909 -403.750422) (xy 142.834443 -403.802711)
			(xy 142.842198 -403.856652) (xy 142.842198 -403.911148) (xy 142.842197 -403.911152) (xy 144.279854 -403.911152)
			(xy 144.279854 -403.856648) (xy 144.28761 -403.802699) (xy 144.302965 -403.750403) (xy 144.325606 -403.700825)
			(xy 144.355071 -403.654973) (xy 144.390762 -403.613781) (xy 144.431952 -403.578087) (xy 144.477802 -403.548618)
			(xy 144.527379 -403.525974) (xy 144.579674 -403.510616) (xy 144.633622 -403.502856) (xy 144.660874 -403.502368)
			(xy 145.524474 -403.502368) (xy 145.551726 -403.502878) (xy 145.605677 -403.510631) (xy 145.657974 -403.525984)
			(xy 145.707555 -403.548623) (xy 145.753408 -403.578089) (xy 145.794601 -403.61378) (xy 145.830296 -403.654971)
			(xy 145.859764 -403.700822) (xy 145.882407 -403.750401) (xy 145.897763 -403.802698) (xy 145.905521 -403.856648)
			(xy 145.905521 -403.911152) (xy 145.905521 -403.911155) (xy 147.343031 -403.911155) (xy 147.343031 -403.856645)
			(xy 147.350789 -403.802689) (xy 147.366146 -403.750387) (xy 147.388791 -403.700803) (xy 147.418263 -403.654946)
			(xy 147.45396 -403.61375) (xy 147.495157 -403.578054) (xy 147.541015 -403.548585) (xy 147.5906 -403.525942)
			(xy 147.642903 -403.510586) (xy 147.696859 -403.50283) (xy 147.724114 -403.502368) (xy 148.587714 -403.502368)
			(xy 148.614963 -403.502903) (xy 148.668906 -403.510661) (xy 148.721195 -403.526016) (xy 148.770768 -403.548657)
			(xy 148.816613 -403.578121) (xy 148.857799 -403.613811) (xy 148.893487 -403.654998) (xy 148.92295 -403.700845)
			(xy 148.945589 -403.750418) (xy 148.960942 -403.802708) (xy 148.968698 -403.856651) (xy 148.968698 -403.911149)
			(xy 148.968698 -403.911151) (xy 150.406354 -403.911151) (xy 150.406354 -403.856649) (xy 150.41411 -403.802702)
			(xy 150.429463 -403.750408) (xy 150.452102 -403.70083) (xy 150.481566 -403.654979) (xy 150.517255 -403.613788)
			(xy 150.558442 -403.578094) (xy 150.60429 -403.548625) (xy 150.653865 -403.525979) (xy 150.706157 -403.510619)
			(xy 150.760103 -403.502857) (xy 150.787354 -403.502368) (xy 151.650954 -403.502368) (xy 151.678207 -403.502876)
			(xy 151.73216 -403.510627) (xy 151.78446 -403.525978) (xy 151.834043 -403.548617) (xy 151.879899 -403.578082)
			(xy 151.921094 -403.613773) (xy 151.956791 -403.654964) (xy 151.986261 -403.700817) (xy 152.008906 -403.750397)
			(xy 152.024263 -403.802695) (xy 152.032021 -403.856647) (xy 152.032021 -403.911153) (xy 153.469554 -403.911153)
			(xy 153.469554 -403.856647) (xy 153.477311 -403.802697) (xy 153.492666 -403.750399) (xy 153.515309 -403.700819)
			(xy 153.544776 -403.654966) (xy 153.580469 -403.613774) (xy 153.621661 -403.57808) (xy 153.667514 -403.548611)
			(xy 153.717094 -403.525969) (xy 153.769391 -403.510612) (xy 153.823341 -403.502854) (xy 153.850594 -403.502368)
			(xy 154.714194 -403.502368) (xy 154.741445 -403.502879) (xy 154.795394 -403.510635) (xy 154.847689 -403.525989)
			(xy 154.897267 -403.54863) (xy 154.943118 -403.578096) (xy 154.984308 -403.613787) (xy 155.02 -403.654978)
			(xy 155.049467 -403.700828) (xy 155.072109 -403.750406) (xy 155.087464 -403.802701) (xy 155.095221 -403.856649)
			(xy 155.095221 -403.911151) (xy 155.09522 -403.911156) (xy 156.532731 -403.911156) (xy 156.532731 -403.856644)
			(xy 156.540489 -403.802686) (xy 156.555848 -403.750383) (xy 156.578495 -403.700797) (xy 156.607968 -403.654939)
			(xy 156.643667 -403.613743) (xy 156.684867 -403.578047) (xy 156.730727 -403.548578) (xy 156.780314 -403.525936)
			(xy 156.83262 -403.510582) (xy 156.886578 -403.502829) (xy 156.913834 -403.502368) (xy 157.777434 -403.502368)
			(xy 157.804682 -403.502905) (xy 157.858623 -403.510664) (xy 157.91091 -403.526022) (xy 157.96048 -403.548663)
			(xy 158.006323 -403.578129) (xy 158.047506 -403.613818) (xy 158.083192 -403.655004) (xy 158.112653 -403.70085)
			(xy 158.13529 -403.750422) (xy 158.150643 -403.802711) (xy 158.158398 -403.856652) (xy 158.158398 -403.911148)
			(xy 158.158397 -403.911152) (xy 159.596054 -403.911152) (xy 159.596054 -403.856648) (xy 159.60381 -403.802699)
			(xy 159.619165 -403.750403) (xy 159.641806 -403.700825) (xy 159.671271 -403.654973) (xy 159.706962 -403.613781)
			(xy 159.748152 -403.578087) (xy 159.794002 -403.548618) (xy 159.843579 -403.525974) (xy 159.895874 -403.510616)
			(xy 159.949822 -403.502856) (xy 159.977074 -403.502368) (xy 160.840674 -403.502368) (xy 160.867926 -403.502878)
			(xy 160.921877 -403.510631) (xy 160.974174 -403.525984) (xy 161.023755 -403.548623) (xy 161.069608 -403.578089)
			(xy 161.110801 -403.61378) (xy 161.146496 -403.654971) (xy 161.175964 -403.700822) (xy 161.198607 -403.750401)
			(xy 161.213963 -403.802698) (xy 161.221721 -403.856648) (xy 161.221721 -403.911152) (xy 161.221721 -403.911155)
			(xy 162.659231 -403.911155) (xy 162.659231 -403.856645) (xy 162.666989 -403.802689) (xy 162.682346 -403.750387)
			(xy 162.704991 -403.700803) (xy 162.734463 -403.654946) (xy 162.77016 -403.61375) (xy 162.811357 -403.578054)
			(xy 162.857215 -403.548585) (xy 162.9068 -403.525942) (xy 162.959103 -403.510586) (xy 163.013059 -403.50283)
			(xy 163.040314 -403.502368) (xy 163.903914 -403.502368) (xy 163.931163 -403.502903) (xy 163.985106 -403.510661)
			(xy 164.037395 -403.526016) (xy 164.086968 -403.548657) (xy 164.132813 -403.578121) (xy 164.173999 -403.613811)
			(xy 164.209687 -403.654998) (xy 164.23915 -403.700845) (xy 164.261789 -403.750418) (xy 164.277142 -403.802708)
			(xy 164.284898 -403.856651) (xy 164.284898 -403.911149) (xy 164.284898 -403.911151) (xy 165.722554 -403.911151)
			(xy 165.722554 -403.856649) (xy 165.73031 -403.802702) (xy 165.745663 -403.750408) (xy 165.768302 -403.70083)
			(xy 165.797766 -403.654979) (xy 165.833455 -403.613788) (xy 165.874642 -403.578094) (xy 165.92049 -403.548625)
			(xy 165.970065 -403.525979) (xy 166.022357 -403.510619) (xy 166.076303 -403.502857) (xy 166.103554 -403.502368)
			(xy 166.967154 -403.502368) (xy 166.994407 -403.502876) (xy 167.04836 -403.510627) (xy 167.10066 -403.525978)
			(xy 167.150243 -403.548617) (xy 167.196099 -403.578082) (xy 167.237294 -403.613773) (xy 167.272991 -403.654964)
			(xy 167.302461 -403.700817) (xy 167.325106 -403.750397) (xy 167.340463 -403.802695) (xy 167.348221 -403.856647)
			(xy 167.348221 -403.911153) (xy 167.340463 -403.965105) (xy 167.325106 -404.017403) (xy 167.302461 -404.066983)
			(xy 167.272991 -404.112836) (xy 167.237294 -404.154027) (xy 167.196099 -404.189718) (xy 167.150243 -404.219183)
			(xy 167.10066 -404.241822) (xy 167.04836 -404.257173) (xy 166.994407 -404.264924) (xy 166.967154 -404.265384)
			(xy 166.103554 -404.265384) (xy 166.076303 -404.264943) (xy 166.022357 -404.257181) (xy 165.970065 -404.241821)
			(xy 165.92049 -404.219175) (xy 165.874642 -404.189706) (xy 165.833455 -404.154012) (xy 165.797766 -404.112821)
			(xy 165.768302 -404.06697) (xy 165.745663 -404.017392) (xy 165.73031 -403.965098) (xy 165.722554 -403.911151)
			(xy 164.284898 -403.911151) (xy 164.277142 -403.965092) (xy 164.261789 -404.017382) (xy 164.23915 -404.066955)
			(xy 164.209687 -404.112802) (xy 164.173999 -404.153989) (xy 164.132813 -404.189679) (xy 164.086968 -404.219143)
			(xy 164.037395 -404.241784) (xy 163.985106 -404.257139) (xy 163.931163 -404.264897) (xy 163.903914 -404.265384)
			(xy 163.040314 -404.265384) (xy 163.013059 -404.26497) (xy 162.959103 -404.257214) (xy 162.9068 -404.241858)
			(xy 162.857215 -404.219215) (xy 162.811357 -404.189746) (xy 162.77016 -404.15405) (xy 162.734463 -404.112854)
			(xy 162.704991 -404.066997) (xy 162.682346 -404.017413) (xy 162.666989 -403.965111) (xy 162.659231 -403.911155)
			(xy 161.221721 -403.911155) (xy 161.213963 -403.965102) (xy 161.198607 -404.017399) (xy 161.175964 -404.066978)
			(xy 161.146496 -404.112829) (xy 161.110801 -404.15402) (xy 161.069608 -404.189711) (xy 161.023755 -404.219177)
			(xy 160.974174 -404.241816) (xy 160.921877 -404.257169) (xy 160.867926 -404.264922) (xy 160.840674 -404.265384)
			(xy 159.977074 -404.265384) (xy 159.949822 -404.264944) (xy 159.895874 -404.257184) (xy 159.843579 -404.241826)
			(xy 159.794002 -404.219182) (xy 159.748152 -404.189713) (xy 159.706962 -404.154019) (xy 159.671271 -404.112827)
			(xy 159.641806 -404.066975) (xy 159.619165 -404.017397) (xy 159.60381 -403.965101) (xy 159.596054 -403.911152)
			(xy 158.158397 -403.911152) (xy 158.150643 -403.965089) (xy 158.13529 -404.017378) (xy 158.112653 -404.06695)
			(xy 158.083192 -404.112796) (xy 158.047506 -404.153982) (xy 158.006323 -404.189671) (xy 157.96048 -404.219137)
			(xy 157.91091 -404.241778) (xy 157.858623 -404.257136) (xy 157.804682 -404.264895) (xy 157.777434 -404.265384)
			(xy 156.913834 -404.265384) (xy 156.886578 -404.264971) (xy 156.83262 -404.257218) (xy 156.780314 -404.241864)
			(xy 156.730727 -404.219222) (xy 156.684867 -404.189753) (xy 156.643667 -404.154057) (xy 156.607968 -404.112861)
			(xy 156.578495 -404.067003) (xy 156.555848 -404.017417) (xy 156.540489 -403.965114) (xy 156.532731 -403.911156)
			(xy 155.09522 -403.911156) (xy 155.087464 -403.965099) (xy 155.072109 -404.017394) (xy 155.049467 -404.066972)
			(xy 155.02 -404.112822) (xy 154.984308 -404.154013) (xy 154.943118 -404.189704) (xy 154.897267 -404.21917)
			(xy 154.847689 -404.241811) (xy 154.795394 -404.257165) (xy 154.741445 -404.264921) (xy 154.714194 -404.265384)
			(xy 153.850594 -404.265384) (xy 153.823341 -404.264946) (xy 153.769391 -404.257188) (xy 153.717094 -404.241831)
			(xy 153.667514 -404.219189) (xy 153.621661 -404.18972) (xy 153.580469 -404.154026) (xy 153.544776 -404.112834)
			(xy 153.515309 -404.066981) (xy 153.492666 -404.017401) (xy 153.477311 -403.965103) (xy 153.469554 -403.911153)
			(xy 152.032021 -403.911153) (xy 152.024263 -403.965105) (xy 152.008906 -404.017403) (xy 151.986261 -404.066983)
			(xy 151.956791 -404.112836) (xy 151.921094 -404.154027) (xy 151.879899 -404.189718) (xy 151.834043 -404.219183)
			(xy 151.78446 -404.241822) (xy 151.73216 -404.257173) (xy 151.678207 -404.264924) (xy 151.650954 -404.265384)
			(xy 150.787354 -404.265384) (xy 150.760103 -404.264943) (xy 150.706157 -404.257181) (xy 150.653865 -404.241821)
			(xy 150.60429 -404.219175) (xy 150.558442 -404.189706) (xy 150.517255 -404.154012) (xy 150.481566 -404.112821)
			(xy 150.452102 -404.06697) (xy 150.429463 -404.017392) (xy 150.41411 -403.965098) (xy 150.406354 -403.911151)
			(xy 148.968698 -403.911151) (xy 148.960942 -403.965092) (xy 148.945589 -404.017382) (xy 148.92295 -404.066955)
			(xy 148.893487 -404.112802) (xy 148.857799 -404.153989) (xy 148.816613 -404.189679) (xy 148.770768 -404.219143)
			(xy 148.721195 -404.241784) (xy 148.668906 -404.257139) (xy 148.614963 -404.264897) (xy 148.587714 -404.265384)
			(xy 147.724114 -404.265384) (xy 147.696859 -404.26497) (xy 147.642903 -404.257214) (xy 147.5906 -404.241858)
			(xy 147.541015 -404.219215) (xy 147.495157 -404.189746) (xy 147.45396 -404.15405) (xy 147.418263 -404.112854)
			(xy 147.388791 -404.066997) (xy 147.366146 -404.017413) (xy 147.350789 -403.965111) (xy 147.343031 -403.911155)
			(xy 145.905521 -403.911155) (xy 145.897763 -403.965102) (xy 145.882407 -404.017399) (xy 145.859764 -404.066978)
			(xy 145.830296 -404.112829) (xy 145.794601 -404.15402) (xy 145.753408 -404.189711) (xy 145.707555 -404.219177)
			(xy 145.657974 -404.241816) (xy 145.605677 -404.257169) (xy 145.551726 -404.264922) (xy 145.524474 -404.265384)
			(xy 144.660874 -404.265384) (xy 144.633622 -404.264944) (xy 144.579674 -404.257184) (xy 144.527379 -404.241826)
			(xy 144.477802 -404.219182) (xy 144.431952 -404.189713) (xy 144.390762 -404.154019) (xy 144.355071 -404.112827)
			(xy 144.325606 -404.066975) (xy 144.302965 -404.017397) (xy 144.28761 -403.965101) (xy 144.279854 -403.911152)
			(xy 142.842197 -403.911152) (xy 142.834443 -403.965089) (xy 142.81909 -404.017378) (xy 142.796453 -404.06695)
			(xy 142.766992 -404.112796) (xy 142.731306 -404.153982) (xy 142.690123 -404.189671) (xy 142.64428 -404.219137)
			(xy 142.59471 -404.241778) (xy 142.542423 -404.257136) (xy 142.488482 -404.264895) (xy 142.461234 -404.265384)
			(xy 141.597634 -404.265384) (xy 141.570378 -404.264971) (xy 141.51642 -404.257218) (xy 141.464114 -404.241864)
			(xy 141.414527 -404.219222) (xy 141.368667 -404.189753) (xy 141.327467 -404.154057) (xy 141.291768 -404.112861)
			(xy 141.262295 -404.067003) (xy 141.239648 -404.017417) (xy 141.224289 -403.965114) (xy 141.216531 -403.911156)
			(xy 139.77902 -403.911156) (xy 139.771264 -403.965099) (xy 139.755909 -404.017394) (xy 139.733267 -404.066972)
			(xy 139.7038 -404.112822) (xy 139.668108 -404.154013) (xy 139.626918 -404.189704) (xy 139.581067 -404.21917)
			(xy 139.531489 -404.241811) (xy 139.479194 -404.257165) (xy 139.425245 -404.264921) (xy 139.397994 -404.265384)
			(xy 138.534394 -404.265384) (xy 138.507141 -404.264946) (xy 138.453191 -404.257188) (xy 138.400894 -404.241831)
			(xy 138.351314 -404.219189) (xy 138.305461 -404.18972) (xy 138.264269 -404.154026) (xy 138.228576 -404.112834)
			(xy 138.199109 -404.066981) (xy 138.176466 -404.017401) (xy 138.161111 -403.965103) (xy 138.153354 -403.911153)
			(xy 136.715821 -403.911153) (xy 136.708063 -403.965105) (xy 136.692706 -404.017403) (xy 136.670061 -404.066983)
			(xy 136.640591 -404.112836) (xy 136.604894 -404.154027) (xy 136.563699 -404.189718) (xy 136.517843 -404.219183)
			(xy 136.46826 -404.241822) (xy 136.41596 -404.257173) (xy 136.362007 -404.264924) (xy 136.334754 -404.265384)
			(xy 135.471154 -404.265384) (xy 135.443903 -404.264943) (xy 135.389957 -404.257181) (xy 135.337665 -404.241821)
			(xy 135.28809 -404.219175) (xy 135.242242 -404.189706) (xy 135.201055 -404.154012) (xy 135.165366 -404.112821)
			(xy 135.135902 -404.06697) (xy 135.113263 -404.017392) (xy 135.09791 -403.965098) (xy 135.090154 -403.911151)
			(xy 133.652498 -403.911151) (xy 133.644742 -403.965092) (xy 133.629389 -404.017382) (xy 133.60675 -404.066955)
			(xy 133.577287 -404.112802) (xy 133.541599 -404.153989) (xy 133.500413 -404.189679) (xy 133.454568 -404.219143)
			(xy 133.404995 -404.241784) (xy 133.352706 -404.257139) (xy 133.298763 -404.264897) (xy 133.271514 -404.265384)
			(xy 132.407914 -404.265384) (xy 132.380659 -404.26497) (xy 132.326703 -404.257214) (xy 132.2744 -404.241858)
			(xy 132.224815 -404.219215) (xy 132.178957 -404.189746) (xy 132.13776 -404.15405) (xy 132.102063 -404.112854)
			(xy 132.072591 -404.066997) (xy 132.049946 -404.017413) (xy 132.034589 -403.965111) (xy 132.026831 -403.911155)
			(xy 130.589321 -403.911155) (xy 130.581563 -403.965102) (xy 130.566207 -404.017399) (xy 130.543564 -404.066978)
			(xy 130.514096 -404.112829) (xy 130.478401 -404.15402) (xy 130.437208 -404.189711) (xy 130.391355 -404.219177)
			(xy 130.341774 -404.241816) (xy 130.289477 -404.257169) (xy 130.235526 -404.264922) (xy 130.208274 -404.265384)
			(xy 129.344674 -404.265384) (xy 129.317422 -404.264944) (xy 129.263474 -404.257184) (xy 129.211179 -404.241826)
			(xy 129.161602 -404.219182) (xy 129.115752 -404.189713) (xy 129.074562 -404.154019) (xy 129.038871 -404.112827)
			(xy 129.009406 -404.066975) (xy 128.986765 -404.017397) (xy 128.97141 -403.965101) (xy 128.963654 -403.911152)
			(xy 127.525997 -403.911152) (xy 127.518243 -403.965089) (xy 127.50289 -404.017378) (xy 127.480253 -404.06695)
			(xy 127.450792 -404.112796) (xy 127.415106 -404.153982) (xy 127.373923 -404.189671) (xy 127.32808 -404.219137)
			(xy 127.27851 -404.241778) (xy 127.226223 -404.257136) (xy 127.172282 -404.264895) (xy 127.145034 -404.265384)
			(xy 126.281434 -404.265384) (xy 126.254178 -404.264971) (xy 126.20022 -404.257218) (xy 126.147914 -404.241864)
			(xy 126.098327 -404.219222) (xy 126.052467 -404.189753) (xy 126.011267 -404.154057) (xy 125.975568 -404.112861)
			(xy 125.946095 -404.067003) (xy 125.923448 -404.017417) (xy 125.908089 -403.965114) (xy 125.900331 -403.911156)
			(xy 124.46282 -403.911156) (xy 124.455064 -403.965099) (xy 124.439709 -404.017394) (xy 124.417067 -404.066972)
			(xy 124.3876 -404.112822) (xy 124.351908 -404.154013) (xy 124.310718 -404.189704) (xy 124.264867 -404.21917)
			(xy 124.215289 -404.241811) (xy 124.162994 -404.257165) (xy 124.109045 -404.264921) (xy 124.081794 -404.265384)
			(xy 123.218194 -404.265384) (xy 123.190941 -404.264946) (xy 123.136991 -404.257188) (xy 123.084694 -404.241831)
			(xy 123.035114 -404.219189) (xy 122.989261 -404.18972) (xy 122.948069 -404.154026) (xy 122.912376 -404.112834)
			(xy 122.882909 -404.066981) (xy 122.860266 -404.017401) (xy 122.844911 -403.965103) (xy 122.837154 -403.911153)
			(xy 121.399621 -403.911153) (xy 121.391863 -403.965105) (xy 121.376506 -404.017403) (xy 121.353861 -404.066983)
			(xy 121.324391 -404.112836) (xy 121.288694 -404.154027) (xy 121.247499 -404.189718) (xy 121.201643 -404.219183)
			(xy 121.15206 -404.241822) (xy 121.09976 -404.257173) (xy 121.045807 -404.264924) (xy 121.018554 -404.265384)
			(xy 120.154954 -404.265384) (xy 120.127703 -404.264943) (xy 120.073757 -404.257181) (xy 120.021465 -404.241821)
			(xy 119.97189 -404.219175) (xy 119.926042 -404.189706) (xy 119.884855 -404.154012) (xy 119.849166 -404.112821)
			(xy 119.819702 -404.06697) (xy 119.797063 -404.017392) (xy 119.78171 -403.965098) (xy 119.773954 -403.911151)
			(xy 95.172998 -403.911151) (xy 95.165243 -403.965089) (xy 95.149891 -404.017377) (xy 95.127254 -404.066949)
			(xy 95.097793 -404.112794) (xy 95.062108 -404.153981) (xy 95.020925 -404.18967) (xy 94.975082 -404.219135)
			(xy 94.925513 -404.241777) (xy 94.873226 -404.257135) (xy 94.819286 -404.264895) (xy 94.792038 -404.265384)
			(xy 93.928438 -404.265384) (xy 93.901182 -404.264972) (xy 93.847223 -404.257219) (xy 93.794917 -404.241865)
			(xy 93.745329 -404.219223) (xy 93.699468 -404.189754) (xy 93.658269 -404.154058) (xy 93.622569 -404.112862)
			(xy 93.593095 -404.067004) (xy 93.570448 -404.017418) (xy 93.555089 -403.965114) (xy 93.547331 -403.911156)
			(xy 92.10982 -403.911156) (xy 92.102064 -403.965099) (xy 92.086709 -404.017394) (xy 92.064068 -404.066971)
			(xy 92.034601 -404.112821) (xy 91.99891 -404.154011) (xy 91.95772 -404.189703) (xy 91.911869 -404.219169)
			(xy 91.862292 -404.24181) (xy 91.809997 -404.257165) (xy 91.756049 -404.264921) (xy 91.728798 -404.265384)
			(xy 90.865198 -404.265384) (xy 90.837945 -404.264946) (xy 90.783994 -404.257189) (xy 90.731696 -404.241833)
			(xy 90.682116 -404.21919) (xy 90.636263 -404.189722) (xy 90.595071 -404.154028) (xy 90.559377 -404.112835)
			(xy 90.529909 -404.066982) (xy 90.507267 -404.017402) (xy 90.491911 -403.965104) (xy 90.484154 -403.911153)
			(xy 89.046621 -403.911153) (xy 89.038863 -403.965104) (xy 89.023506 -404.017402) (xy 89.000862 -404.066982)
			(xy 88.971392 -404.112834) (xy 88.935696 -404.154025) (xy 88.894501 -404.189717) (xy 88.848645 -404.219182)
			(xy 88.799063 -404.241821) (xy 88.746763 -404.257172) (xy 88.692811 -404.264924) (xy 88.665558 -404.265384)
			(xy 87.801958 -404.265384) (xy 87.774707 -404.264943) (xy 87.72076 -404.257181) (xy 87.668467 -404.241822)
			(xy 87.618892 -404.219177) (xy 87.573044 -404.189707) (xy 87.531857 -404.154014) (xy 87.496167 -404.112822)
			(xy 87.466703 -404.066971) (xy 87.444064 -404.017393) (xy 87.42871 -403.965098) (xy 87.420954 -403.911151)
			(xy 85.983298 -403.911151) (xy 85.975542 -403.965091) (xy 85.960189 -404.017381) (xy 85.937551 -404.066954)
			(xy 85.908088 -404.112801) (xy 85.872401 -404.153988) (xy 85.831215 -404.189677) (xy 85.78537 -404.219142)
			(xy 85.735798 -404.241783) (xy 85.683509 -404.257138) (xy 85.629567 -404.264897) (xy 85.602318 -404.265384)
			(xy 84.738718 -404.265384) (xy 84.711463 -404.26497) (xy 84.657506 -404.257215) (xy 84.605203 -404.241859)
			(xy 84.555617 -404.219217) (xy 84.509759 -404.189747) (xy 84.468562 -404.154051) (xy 84.432864 -404.112855)
			(xy 84.403392 -404.066999) (xy 84.380747 -404.017414) (xy 84.365389 -403.965111) (xy 84.357631 -403.911155)
			(xy 82.920121 -403.911155) (xy 82.912364 -403.965102) (xy 82.897007 -404.017398) (xy 82.874365 -404.066976)
			(xy 82.844897 -404.112828) (xy 82.809203 -404.154018) (xy 82.76801 -404.18971) (xy 82.722157 -404.219175)
			(xy 82.672577 -404.241815) (xy 82.62028 -404.257168) (xy 82.56633 -404.264922) (xy 82.539078 -404.265384)
			(xy 81.675478 -404.265384) (xy 81.648226 -404.264945) (xy 81.594277 -404.257185) (xy 81.541982 -404.241827)
			(xy 81.492404 -404.219183) (xy 81.446554 -404.189715) (xy 81.405364 -404.154021) (xy 81.369672 -404.112829)
			(xy 81.340206 -404.066976) (xy 81.317565 -404.017397) (xy 81.30221 -403.965101) (xy 81.294454 -403.911152)
			(xy 79.856797 -403.911152) (xy 79.849043 -403.965089) (xy 79.833691 -404.017377) (xy 79.811054 -404.066949)
			(xy 79.781593 -404.112794) (xy 79.745908 -404.153981) (xy 79.704725 -404.18967) (xy 79.658882 -404.219135)
			(xy 79.609313 -404.241777) (xy 79.557026 -404.257135) (xy 79.503086 -404.264895) (xy 79.475838 -404.265384)
			(xy 78.612238 -404.265384) (xy 78.584982 -404.264972) (xy 78.531023 -404.257219) (xy 78.478717 -404.241865)
			(xy 78.429129 -404.219223) (xy 78.383268 -404.189754) (xy 78.342069 -404.154058) (xy 78.306369 -404.112862)
			(xy 78.276895 -404.067004) (xy 78.254248 -404.017418) (xy 78.238889 -403.965114) (xy 78.231131 -403.911156)
			(xy 76.79362 -403.911156) (xy 76.785864 -403.965099) (xy 76.770509 -404.017394) (xy 76.747868 -404.066971)
			(xy 76.718401 -404.112821) (xy 76.68271 -404.154011) (xy 76.64152 -404.189703) (xy 76.595669 -404.219169)
			(xy 76.546092 -404.24181) (xy 76.493797 -404.257165) (xy 76.439849 -404.264921) (xy 76.412598 -404.265384)
			(xy 75.548998 -404.265384) (xy 75.521745 -404.264946) (xy 75.467794 -404.257189) (xy 75.415496 -404.241833)
			(xy 75.365916 -404.21919) (xy 75.320063 -404.189722) (xy 75.278871 -404.154028) (xy 75.243177 -404.112835)
			(xy 75.213709 -404.066982) (xy 75.191067 -404.017402) (xy 75.175711 -403.965104) (xy 75.167954 -403.911153)
			(xy 73.730421 -403.911153) (xy 73.722663 -403.965104) (xy 73.707306 -404.017402) (xy 73.684662 -404.066982)
			(xy 73.655192 -404.112834) (xy 73.619496 -404.154025) (xy 73.578301 -404.189717) (xy 73.532445 -404.219182)
			(xy 73.482863 -404.241821) (xy 73.430563 -404.257172) (xy 73.376611 -404.264924) (xy 73.349358 -404.265384)
			(xy 72.485758 -404.265384) (xy 72.458507 -404.264943) (xy 72.40456 -404.257181) (xy 72.352267 -404.241822)
			(xy 72.302692 -404.219177) (xy 72.256844 -404.189707) (xy 72.215657 -404.154014) (xy 72.179967 -404.112822)
			(xy 72.150503 -404.066971) (xy 72.127864 -404.017393) (xy 72.11251 -403.965098) (xy 72.104754 -403.911151)
			(xy 70.667098 -403.911151) (xy 70.659342 -403.965091) (xy 70.643989 -404.017381) (xy 70.621351 -404.066954)
			(xy 70.591888 -404.112801) (xy 70.556201 -404.153988) (xy 70.515015 -404.189677) (xy 70.46917 -404.219142)
			(xy 70.419598 -404.241783) (xy 70.367309 -404.257138) (xy 70.313367 -404.264897) (xy 70.286118 -404.265384)
			(xy 69.422518 -404.265384) (xy 69.395263 -404.26497) (xy 69.341306 -404.257215) (xy 69.289003 -404.241859)
			(xy 69.239417 -404.219217) (xy 69.193559 -404.189747) (xy 69.152362 -404.154051) (xy 69.116664 -404.112855)
			(xy 69.087192 -404.066999) (xy 69.064547 -404.017414) (xy 69.049189 -403.965111) (xy 69.041431 -403.911155)
			(xy 67.603921 -403.911155) (xy 67.596164 -403.965102) (xy 67.580807 -404.017398) (xy 67.558165 -404.066976)
			(xy 67.528697 -404.112828) (xy 67.493003 -404.154018) (xy 67.45181 -404.18971) (xy 67.405957 -404.219175)
			(xy 67.356377 -404.241815) (xy 67.30408 -404.257168) (xy 67.25013 -404.264922) (xy 67.222878 -404.265384)
			(xy 66.359278 -404.265384) (xy 66.332026 -404.264945) (xy 66.278077 -404.257185) (xy 66.225782 -404.241827)
			(xy 66.176204 -404.219183) (xy 66.130354 -404.189715) (xy 66.089164 -404.154021) (xy 66.053472 -404.112829)
			(xy 66.024006 -404.066976) (xy 66.001365 -404.017397) (xy 65.98601 -403.965101) (xy 65.978254 -403.911152)
			(xy 64.540597 -403.911152) (xy 64.532843 -403.965089) (xy 64.517491 -404.017377) (xy 64.494854 -404.066949)
			(xy 64.465393 -404.112794) (xy 64.429708 -404.153981) (xy 64.388525 -404.18967) (xy 64.342682 -404.219135)
			(xy 64.293113 -404.241777) (xy 64.240826 -404.257135) (xy 64.186886 -404.264895) (xy 64.159638 -404.265384)
			(xy 63.296038 -404.265384) (xy 63.268782 -404.264972) (xy 63.214823 -404.257219) (xy 63.162517 -404.241865)
			(xy 63.112929 -404.219223) (xy 63.067068 -404.189754) (xy 63.025869 -404.154058) (xy 62.990169 -404.112862)
			(xy 62.960695 -404.067004) (xy 62.938048 -404.017418) (xy 62.922689 -403.965114) (xy 62.914931 -403.911156)
			(xy 61.47742 -403.911156) (xy 61.469664 -403.965099) (xy 61.454309 -404.017394) (xy 61.431668 -404.066971)
			(xy 61.402201 -404.112821) (xy 61.36651 -404.154011) (xy 61.32532 -404.189703) (xy 61.279469 -404.219169)
			(xy 61.229892 -404.24181) (xy 61.177597 -404.257165) (xy 61.123649 -404.264921) (xy 61.096398 -404.265384)
			(xy 60.232798 -404.265384) (xy 60.205545 -404.264946) (xy 60.151594 -404.257189) (xy 60.099296 -404.241833)
			(xy 60.049716 -404.21919) (xy 60.003863 -404.189722) (xy 59.962671 -404.154028) (xy 59.926977 -404.112835)
			(xy 59.897509 -404.066982) (xy 59.874867 -404.017402) (xy 59.859511 -403.965104) (xy 59.851754 -403.911153)
			(xy 58.414221 -403.911153) (xy 58.406463 -403.965104) (xy 58.391106 -404.017402) (xy 58.368462 -404.066982)
			(xy 58.338992 -404.112834) (xy 58.303296 -404.154025) (xy 58.262101 -404.189717) (xy 58.216245 -404.219182)
			(xy 58.166663 -404.241821) (xy 58.114363 -404.257172) (xy 58.060411 -404.264924) (xy 58.033158 -404.265384)
			(xy 57.169558 -404.265384) (xy 57.142307 -404.264943) (xy 57.08836 -404.257181) (xy 57.036067 -404.241822)
			(xy 56.986492 -404.219177) (xy 56.940644 -404.189707) (xy 56.899457 -404.154014) (xy 56.863767 -404.112822)
			(xy 56.834303 -404.066971) (xy 56.811664 -404.017393) (xy 56.79631 -403.965098) (xy 56.788554 -403.911151)
			(xy 55.350898 -403.911151) (xy 55.343142 -403.965091) (xy 55.327789 -404.017381) (xy 55.305151 -404.066954)
			(xy 55.275688 -404.112801) (xy 55.240001 -404.153988) (xy 55.198815 -404.189677) (xy 55.15297 -404.219142)
			(xy 55.103398 -404.241783) (xy 55.051109 -404.257138) (xy 54.997167 -404.264897) (xy 54.969918 -404.265384)
			(xy 54.106318 -404.265384) (xy 54.079063 -404.26497) (xy 54.025106 -404.257215) (xy 53.972803 -404.241859)
			(xy 53.923217 -404.219217) (xy 53.877359 -404.189747) (xy 53.836162 -404.154051) (xy 53.800464 -404.112855)
			(xy 53.770992 -404.066999) (xy 53.748347 -404.017414) (xy 53.732989 -403.965111) (xy 53.725231 -403.911155)
			(xy 52.287721 -403.911155) (xy 52.279964 -403.965102) (xy 52.264607 -404.017398) (xy 52.241965 -404.066976)
			(xy 52.212497 -404.112828) (xy 52.176803 -404.154018) (xy 52.13561 -404.18971) (xy 52.089757 -404.219175)
			(xy 52.040177 -404.241815) (xy 51.98788 -404.257168) (xy 51.93393 -404.264922) (xy 51.906678 -404.265384)
			(xy 51.043078 -404.265384) (xy 51.015826 -404.264945) (xy 50.961877 -404.257185) (xy 50.909582 -404.241827)
			(xy 50.860004 -404.219183) (xy 50.814154 -404.189715) (xy 50.772964 -404.154021) (xy 50.737272 -404.112829)
			(xy 50.707806 -404.066976) (xy 50.685165 -404.017397) (xy 50.66981 -403.965101) (xy 50.662054 -403.911152)
			(xy 49.224397 -403.911152) (xy 49.216643 -403.965089) (xy 49.201291 -404.017377) (xy 49.178654 -404.066949)
			(xy 49.149193 -404.112794) (xy 49.113508 -404.153981) (xy 49.072325 -404.18967) (xy 49.026482 -404.219135)
			(xy 48.976913 -404.241777) (xy 48.924626 -404.257135) (xy 48.870686 -404.264895) (xy 48.843438 -404.265384)
			(xy 47.979838 -404.265384) (xy 47.952582 -404.264972) (xy 47.898623 -404.257219) (xy 47.846317 -404.241865)
			(xy 47.796729 -404.219223) (xy 47.750868 -404.189754) (xy 47.709669 -404.154058) (xy 47.673969 -404.112862)
			(xy 47.644495 -404.067004) (xy 47.621848 -404.017418) (xy 47.606489 -403.965114) (xy 47.598731 -403.911156)
			(xy 2.610452 -403.911156) (xy 2.622121 -403.942439) (xy 2.666338 -404.039266) (xy 2.717346 -404.132693)
			(xy 2.774884 -404.222247) (xy 2.838661 -404.307471) (xy 2.908351 -404.387931) (xy 2.945638 -404.425912)
			(xy 3.748786 -405.22906) (xy 102.242112 -405.22906) (xy 102.242112 -404.36546) (xy 102.242598 -404.338209)
			(xy 102.250354 -404.284261) (xy 102.265709 -404.231966) (xy 102.288351 -404.182389) (xy 102.317817 -404.136539)
			(xy 102.353508 -404.095348) (xy 102.394699 -404.059657) (xy 102.440549 -404.030191) (xy 102.490126 -404.007549)
			(xy 102.542421 -403.992194) (xy 102.596369 -403.984438) (xy 102.650871 -403.984438) (xy 102.704819 -403.992194)
			(xy 102.757114 -404.007549) (xy 102.806691 -404.030191) (xy 102.852541 -404.059657) (xy 102.893732 -404.095348)
			(xy 102.929423 -404.136539) (xy 102.958889 -404.182389) (xy 102.981531 -404.231966) (xy 102.996886 -404.284261)
			(xy 103.004642 -404.338209) (xy 103.005128 -404.36546) (xy 103.005128 -405.22906) (xy 103.004642 -405.256311)
			(xy 102.996886 -405.310259) (xy 102.981531 -405.362554) (xy 102.958889 -405.412131) (xy 102.929423 -405.457981)
			(xy 102.893732 -405.499172) (xy 102.852541 -405.534863) (xy 102.806691 -405.564329) (xy 102.757114 -405.586971)
			(xy 102.704819 -405.602326) (xy 102.650871 -405.610082) (xy 102.596369 -405.610082) (xy 102.542421 -405.602326)
			(xy 102.490126 -405.586971) (xy 102.440549 -405.564329) (xy 102.394699 -405.534863) (xy 102.353508 -405.499172)
			(xy 102.317817 -405.457981) (xy 102.288351 -405.412131) (xy 102.265709 -405.362554) (xy 102.250354 -405.310259)
			(xy 102.242598 -405.256311) (xy 102.242112 -405.22906) (xy 3.748786 -405.22906) (xy 5.555234 -407.035508)
			(xy 15.978632 -407.035508) (xy 15.978632 -406.171908) (xy 15.979118 -406.144657) (xy 15.986874 -406.090709)
			(xy 16.002229 -406.038414) (xy 16.024871 -405.988837) (xy 16.054337 -405.942987) (xy 16.090028 -405.901796)
			(xy 16.131219 -405.866105) (xy 16.177069 -405.836639) (xy 16.226646 -405.813997) (xy 16.278941 -405.798642)
			(xy 16.332889 -405.790886) (xy 16.387391 -405.790886) (xy 16.441339 -405.798642) (xy 16.493634 -405.813997)
			(xy 16.543211 -405.836639) (xy 16.589061 -405.866105) (xy 16.630252 -405.901796) (xy 16.665943 -405.942987)
			(xy 16.695409 -405.988837) (xy 16.718051 -406.038414) (xy 16.733406 -406.090709) (xy 16.741162 -406.144657)
			(xy 16.741648 -406.171908) (xy 16.741648 -406.620726) (xy 184.561988 -406.620726) (xy 184.561988 -400.685254)
			(xy 184.562447 -400.660304) (xy 184.570259 -400.611019) (xy 184.585684 -400.563563) (xy 184.608342 -400.519104)
			(xy 184.637676 -400.478736) (xy 184.672962 -400.443454) (xy 184.713333 -400.414125) (xy 184.757795 -400.391471)
			(xy 184.805253 -400.376051) (xy 184.854538 -400.368244) (xy 184.879488 -400.367754) (xy 188.73343 -400.367754)
			(xy 188.758609 -400.368272) (xy 188.808334 -400.376233) (xy 188.856176 -400.39195) (xy 188.900934 -400.415029)
			(xy 188.941484 -400.444889) (xy 188.95949 -400.462496) (xy 189.16142 -400.667474) (xy 189.178411 -400.68542)
			(xy 189.207232 -400.725562) (xy 189.229493 -400.76968) (xy 189.244658 -400.816712) (xy 189.252363 -400.865524)
			(xy 189.25286 -400.890232) (xy 189.25286 -403.517354) (xy 189.46876 -403.517354) (xy 189.49371 -403.51783)
			(xy 189.542993 -403.525649) (xy 189.590451 -403.541071) (xy 189.634916 -403.563718) (xy 189.675298 -403.593032)
			(xy 189.693296 -403.610318) (xy 189.904624 -403.821646) (xy 189.921945 -403.839613) (xy 189.951264 -403.879997)
			(xy 189.973905 -403.92447) (xy 189.989312 -403.971937) (xy 189.997105 -404.021229) (xy 189.997588 -404.046182)
			(xy 189.997588 -404.34641) (xy 190.325756 -404.674832) (xy 190.350648 -404.671276) (xy 190.363288 -404.669701)
			(xy 190.38871 -404.668051) (xy 190.401448 -404.667974) (xy 190.4287 -404.668433) (xy 190.482647 -404.676196)
			(xy 190.534941 -404.691556) (xy 190.584518 -404.714201) (xy 190.630367 -404.743671) (xy 190.671556 -404.779365)
			(xy 190.707247 -404.820557) (xy 190.736713 -404.866409) (xy 190.759355 -404.915987) (xy 190.774711 -404.968282)
			(xy 190.782469 -405.02223) (xy 190.782956 -405.049482) (xy 190.782871 -405.06222) (xy 190.781219 -405.087641)
			(xy 190.779654 -405.100282) (xy 190.776098 -405.125174) (xy 191.001904 -405.35098) (xy 196.838316 -405.35098)
			(xy 197.83298 -404.356316) (xy 197.83298 -400.893788) (xy 197.833478 -400.868839) (xy 197.841291 -400.819556)
			(xy 197.856708 -400.772099) (xy 197.879349 -400.727633) (xy 197.908659 -400.68725) (xy 197.925944 -400.669252)
			(xy 198.116952 -400.478244) (xy 198.134911 -400.460913) (xy 198.175295 -400.431588) (xy 198.219769 -400.408941)
			(xy 198.267238 -400.393531) (xy 198.316534 -400.385737) (xy 198.341488 -400.38528) (xy 201.995532 -400.38528)
			(xy 202.020482 -400.385766) (xy 202.069765 -400.393582) (xy 202.117222 -400.409001) (xy 202.161688 -400.431645)
			(xy 202.20207 -400.460958) (xy 202.220068 -400.478244) (xy 202.418696 -400.676872) (xy 202.435977 -400.694876)
			(xy 202.465302 -400.73525) (xy 202.487952 -400.779713) (xy 202.503368 -400.827172) (xy 202.511171 -400.876458)
			(xy 202.51166 -400.901408) (xy 202.51166 -404.330916) (xy 202.604624 -404.42388) (xy 202.621913 -404.441876)
			(xy 202.651236 -404.482252) (xy 202.673884 -404.526718) (xy 202.689298 -404.574178) (xy 202.6971 -404.623466)
			(xy 202.697588 -404.648416) (xy 202.697588 -407.475436) (xy 204.291692 -409.06954) (xy 206.414116 -409.06954)
			(xy 208.310988 -407.172668) (xy 208.310988 -404.642828) (xy 208.311509 -404.61788) (xy 208.319316 -404.568598)
			(xy 208.334727 -404.521141) (xy 208.357363 -404.476674) (xy 208.386669 -404.436291) (xy 208.403952 -404.418292)
			(xy 208.50098 -404.321264) (xy 208.50098 -400.893788) (xy 208.501478 -400.868839) (xy 208.509291 -400.819556)
			(xy 208.524708 -400.772099) (xy 208.547349 -400.727633) (xy 208.576659 -400.68725) (xy 208.593944 -400.669252)
			(xy 208.784952 -400.478244) (xy 208.802911 -400.460913) (xy 208.843295 -400.431588) (xy 208.887769 -400.408941)
			(xy 208.935238 -400.393531) (xy 208.984534 -400.385737) (xy 209.009488 -400.38528) (xy 212.668612 -400.38528)
			(xy 212.693561 -400.385778) (xy 212.742844 -400.393591) (xy 212.790301 -400.409008) (xy 212.834767 -400.431649)
			(xy 212.87515 -400.460959) (xy 212.893148 -400.478244) (xy 213.084156 -400.669252) (xy 213.101487 -400.687211)
			(xy 213.130812 -400.727595) (xy 213.153459 -400.772069) (xy 213.168869 -400.819538) (xy 213.176663 -400.868834)
			(xy 213.17712 -400.893788) (xy 213.17712 -404.353776) (xy 213.261956 -404.438612) (xy 213.279249 -404.456605)
			(xy 213.308574 -404.496981) (xy 213.331222 -404.541447) (xy 213.346636 -404.588909) (xy 213.354434 -404.638197)
			(xy 213.35492 -404.663148) (xy 213.35492 -407.394156) (xy 214.926164 -408.9654) (xy 217.141044 -408.9654)
			(xy 218.978988 -407.127456) (xy 218.978988 -404.673308) (xy 218.979496 -404.648359) (xy 218.987307 -404.599077)
			(xy 219.00272 -404.55162) (xy 219.02536 -404.507153) (xy 219.054668 -404.46677) (xy 219.071952 -404.448772)
			(xy 219.16136 -404.359364) (xy 219.16136 -400.906488) (xy 219.161864 -400.881539) (xy 219.169676 -400.832257)
			(xy 219.185092 -400.7848) (xy 219.207732 -400.740334) (xy 219.23704 -400.699951) (xy 219.254324 -400.681952)
			(xy 219.458032 -400.478244) (xy 219.476 -400.460922) (xy 219.516381 -400.431596) (xy 219.560853 -400.408948)
			(xy 219.60832 -400.393535) (xy 219.657614 -400.385739) (xy 219.682568 -400.38528) (xy 223.323912 -400.38528)
			(xy 223.348861 -400.385778) (xy 223.398144 -400.393591) (xy 223.445601 -400.409008) (xy 223.490067 -400.431649)
			(xy 223.53045 -400.460959) (xy 223.548448 -400.478244) (xy 223.759776 -400.689572) (xy 223.777053 -400.707579)
			(xy 223.80638 -400.747952) (xy 223.82903 -400.792414) (xy 223.844447 -400.839873) (xy 223.852251 -400.889158)
			(xy 223.85274 -400.914108) (xy 223.85274 -404.348188) (xy 223.940624 -404.436072) (xy 223.957909 -404.454071)
			(xy 223.987233 -404.494447) (xy 224.009881 -404.538912) (xy 224.025297 -404.586371) (xy 224.0331 -404.635658)
			(xy 224.033588 -404.660608) (xy 224.033588 -407.272236) (xy 225.838512 -409.07716) (xy 227.803456 -409.07716)
			(xy 229.621588 -407.259028) (xy 229.621588 -404.678388) (xy 229.622084 -404.653439) (xy 229.629897 -404.604156)
			(xy 229.645314 -404.556698) (xy 229.667956 -404.512233) (xy 229.697267 -404.47185) (xy 229.714552 -404.453852)
			(xy 229.82682 -404.341584) (xy 229.82682 -400.901408) (xy 229.827348 -400.87646) (xy 229.835156 -400.82718)
			(xy 229.850567 -400.779723) (xy 229.873201 -400.735257) (xy 229.902503 -400.694872) (xy 229.919784 -400.676872)
			(xy 230.120952 -400.475704) (xy 230.138921 -400.458385) (xy 230.179304 -400.429065) (xy 230.223776 -400.406422)
			(xy 230.271243 -400.391015) (xy 230.320536 -400.383222) (xy 230.345488 -400.38274) (xy 233.996992 -400.38274)
			(xy 234.02194 -400.383262) (xy 234.071221 -400.391071) (xy 234.118678 -400.406483) (xy 234.163144 -400.429118)
			(xy 234.203528 -400.458422) (xy 234.221528 -400.475704) (xy 234.422696 -400.676872) (xy 234.439977 -400.694876)
			(xy 234.469302 -400.73525) (xy 234.491952 -400.779713) (xy 234.507368 -400.827172) (xy 234.515171 -400.876458)
			(xy 234.51566 -400.901408) (xy 234.51566 -404.346156) (xy 235.652564 -405.48306) (xy 237.746032 -405.48306)
			(xy 237.770981 -405.483551) (xy 237.820264 -405.491367) (xy 237.867721 -405.506785) (xy 237.912187 -405.529428)
			(xy 237.95257 -405.558739) (xy 237.970568 -405.576024) (xy 238.814356 -406.419812) (xy 238.968788 -406.419812)
			(xy 239.014 -406.3746) (xy 239.014 -397.839946) (xy 239.014705 -397.809318) (xy 239.02648 -397.749203)
			(xy 239.037368 -397.720566) (xy 239.093502 -397.582136) (xy 239.102124 -397.561821) (xy 239.124183 -397.523596)
			(xy 239.151323 -397.488796) (xy 239.166908 -397.47317) (xy 239.218978 -397.423132) (xy 239.692688 -396.949422)
			(xy 239.720237 -396.922524) (xy 239.780375 -396.87444) (xy 239.845524 -396.833399) (xy 239.914862 -396.799918)
			(xy 239.987515 -396.774419) (xy 240.062568 -396.757222) (xy 240.139075 -396.748545) (xy 240.177574 -396.748)
			(xy 274.117054 -396.748) (xy 274.147682 -396.748705) (xy 274.207797 -396.76048) (xy 274.236434 -396.771368)
			(xy 274.374864 -396.827502) (xy 274.395179 -396.836124) (xy 274.433404 -396.858183) (xy 274.468204 -396.885323)
			(xy 274.48383 -396.900908) (xy 274.533868 -396.952978) (xy 274.753578 -397.172688) (xy 274.777454 -397.19758)
			(xy 274.787032 -397.207432) (xy 274.810234 -397.222125) (xy 274.836515 -397.230094) (xy 274.86397 -397.230762)
			(xy 274.890608 -397.22408) (xy 274.914497 -397.210532) (xy 274.92452 -397.201136) (xy 275.284692 -396.840964)
			(xy 275.302681 -396.823665) (xy 275.343056 -396.794335) (xy 275.387522 -396.771682) (xy 275.434985 -396.756264)
			(xy 275.484276 -396.748462) (xy 275.509228 -396.748) (xy 280.83764 -396.748) (xy 280.86259 -396.748475)
			(xy 280.911874 -396.756293) (xy 280.959332 -396.771714) (xy 281.003797 -396.794361) (xy 281.044179 -396.823677)
			(xy 281.062176 -396.840964) (xy 281.593544 -397.372332) (xy 281.610864 -397.390302) (xy 281.640191 -397.430682)
			(xy 281.66284 -397.475154) (xy 281.678252 -397.522621) (xy 281.686049 -397.571915) (xy 281.686508 -397.596868)
			(xy 281.686508 -398.65534) (xy 457.185003 -398.65534) (xy 457.185003 -398.5262) (xy 457.192953 -398.397305)
			(xy 457.208823 -398.269145) (xy 457.232552 -398.142204) (xy 457.264051 -398.016965) (xy 457.3032 -397.893902)
			(xy 457.349851 -397.773483) (xy 457.403826 -397.656164) (xy 457.464921 -397.54239) (xy 457.532904 -397.432593)
			(xy 457.607518 -397.32719) (xy 457.688479 -397.22658) (xy 457.775479 -397.131145) (xy 457.86819 -397.041246)
			(xy 457.96626 -396.957225) (xy 458.069315 -396.879401) (xy 458.176966 -396.808069) (xy 458.288805 -396.743499)
			(xy 458.404406 -396.685937) (xy 458.523331 -396.6356) (xy 458.64513 -396.59268) (xy 458.76934 -396.557339)
			(xy 458.895489 -396.529712) (xy 459.023101 -396.509903) (xy 459.15169 -396.497987) (xy 459.280768 -396.494011)
			(xy 459.409846 -396.497987) (xy 459.538435 -396.509903) (xy 459.666047 -396.529712) (xy 459.792196 -396.557339)
			(xy 459.916406 -396.59268) (xy 460.038205 -396.6356) (xy 460.15713 -396.685937) (xy 460.272731 -396.743499)
			(xy 460.38457 -396.808069) (xy 460.492221 -396.879401) (xy 460.595276 -396.957225) (xy 460.693346 -397.041246)
			(xy 460.786057 -397.131145) (xy 460.873057 -397.22658) (xy 460.954018 -397.32719) (xy 461.028632 -397.432593)
			(xy 461.096615 -397.54239) (xy 461.15771 -397.656164) (xy 461.211685 -397.773483) (xy 461.258336 -397.893902)
			(xy 461.297485 -398.016965) (xy 461.328984 -398.142204) (xy 461.352713 -398.269145) (xy 461.368583 -398.397305)
			(xy 461.376533 -398.5262) (xy 461.37703 -398.59077) (xy 461.376533 -398.65534) (xy 461.368583 -398.784235)
			(xy 461.352713 -398.912395) (xy 461.328984 -399.039336) (xy 461.297485 -399.164575) (xy 461.258336 -399.287638)
			(xy 461.211685 -399.408057) (xy 461.15771 -399.525376) (xy 461.096615 -399.63915) (xy 461.028632 -399.748947)
			(xy 460.954018 -399.85435) (xy 460.873057 -399.95496) (xy 460.786057 -400.050395) (xy 460.693346 -400.140294)
			(xy 460.595276 -400.224315) (xy 460.492221 -400.302139) (xy 460.38457 -400.373471) (xy 460.272731 -400.438041)
			(xy 460.15713 -400.495603) (xy 460.038205 -400.54594) (xy 459.916406 -400.58886) (xy 459.792196 -400.624201)
			(xy 459.666047 -400.651828) (xy 459.538435 -400.671637) (xy 459.409846 -400.683553) (xy 459.280768 -400.68753)
			(xy 459.15169 -400.683553) (xy 459.023101 -400.671637) (xy 458.895489 -400.651828) (xy 458.76934 -400.624201)
			(xy 458.64513 -400.58886) (xy 458.523331 -400.54594) (xy 458.404406 -400.495603) (xy 458.288805 -400.438041)
			(xy 458.176966 -400.373471) (xy 458.069315 -400.302139) (xy 457.96626 -400.224315) (xy 457.86819 -400.140294)
			(xy 457.775479 -400.050395) (xy 457.688479 -399.95496) (xy 457.607518 -399.85435) (xy 457.532904 -399.748947)
			(xy 457.464921 -399.63915) (xy 457.403826 -399.525376) (xy 457.349851 -399.408057) (xy 457.3032 -399.287638)
			(xy 457.264051 -399.164575) (xy 457.232552 -399.039336) (xy 457.208823 -398.912395) (xy 457.192953 -398.784235)
			(xy 457.185003 -398.65534) (xy 281.686508 -398.65534) (xy 281.686508 -399.9835) (xy 289.606441 -399.9835)
			(xy 289.610455 -399.919698) (xy 289.622434 -399.856902) (xy 289.642189 -399.796103) (xy 289.669408 -399.73826)
			(xy 289.703662 -399.684283) (xy 289.744411 -399.635026) (xy 289.791013 -399.591264) (xy 289.842731 -399.553688)
			(xy 289.898752 -399.52289) (xy 289.958191 -399.499357) (xy 290.02011 -399.483458) (xy 290.083534 -399.475446)
			(xy 290.115498 -399.474944) (xy 290.115752 -399.474944) (xy 290.147498 -399.475464) (xy 290.210494 -399.483393)
			(xy 290.272014 -399.499096) (xy 290.331102 -399.52233) (xy 290.386842 -399.552733) (xy 290.438367 -399.589834)
			(xy 290.461954 -399.611088) (xy 290.469217 -399.617272) (xy 290.486967 -399.624223) (xy 290.506029 -399.624223)
			(xy 290.523779 -399.617272) (xy 290.531042 -399.611088) (xy 290.554631 -399.589832) (xy 290.60614 -399.5527)
			(xy 290.661874 -399.522276) (xy 290.720965 -399.499035) (xy 290.782492 -399.483338) (xy 290.845495 -399.475431)
			(xy 290.877244 -399.474944) (xy 290.877498 -399.474944) (xy 290.909457 -399.475521) (xy 290.972872 -399.483532)
			(xy 291.034783 -399.499427) (xy 291.094213 -399.522957) (xy 291.150226 -399.55375) (xy 291.201937 -399.591321)
			(xy 291.248532 -399.635076) (xy 291.289276 -399.684326) (xy 291.323525 -399.738295) (xy 291.350741 -399.79613)
			(xy 291.370493 -399.856921) (xy 291.38247 -399.919707) (xy 291.386484 -399.9835) (xy 292.146441 -399.9835)
			(xy 292.150455 -399.919698) (xy 292.162434 -399.856902) (xy 292.182189 -399.796103) (xy 292.209408 -399.73826)
			(xy 292.243662 -399.684283) (xy 292.284411 -399.635026) (xy 292.331013 -399.591264) (xy 292.382731 -399.553688)
			(xy 292.438752 -399.52289) (xy 292.498191 -399.499357) (xy 292.56011 -399.483458) (xy 292.623534 -399.475446)
			(xy 292.655498 -399.474944) (xy 292.655752 -399.474944) (xy 292.687498 -399.475464) (xy 292.750494 -399.483393)
			(xy 292.812014 -399.499096) (xy 292.871102 -399.52233) (xy 292.926842 -399.552733) (xy 292.978367 -399.589834)
			(xy 293.001954 -399.611088) (xy 293.009217 -399.617272) (xy 293.026967 -399.624223) (xy 293.046029 -399.624223)
			(xy 293.063779 -399.617272) (xy 293.071042 -399.611088) (xy 293.094631 -399.589832) (xy 293.14614 -399.5527)
			(xy 293.201874 -399.522276) (xy 293.260965 -399.499035) (xy 293.322492 -399.483338) (xy 293.385495 -399.475431)
			(xy 293.417244 -399.474944) (xy 293.417498 -399.474944) (xy 293.449457 -399.475521) (xy 293.512872 -399.483532)
			(xy 293.574783 -399.499427) (xy 293.634213 -399.522957) (xy 293.690226 -399.55375) (xy 293.741937 -399.591321)
			(xy 293.788532 -399.635076) (xy 293.829276 -399.684326) (xy 293.863525 -399.738295) (xy 293.890741 -399.79613)
			(xy 293.910493 -399.856921) (xy 293.92247 -399.919707) (xy 293.926484 -399.9835) (xy 294.53602 -399.9835)
			(xy 294.540035 -399.919693) (xy 294.552015 -399.856892) (xy 294.571773 -399.796089) (xy 294.598995 -399.738241)
			(xy 294.633253 -399.684261) (xy 294.674007 -399.635001) (xy 294.720613 -399.591237) (xy 294.772338 -399.55366)
			(xy 294.828364 -399.522862) (xy 294.887809 -399.499329) (xy 294.949734 -399.483433) (xy 295.013163 -399.475423)
			(xy 295.04513 -399.474944) (xy 295.045384 -399.474944) (xy 295.077131 -399.475444) (xy 295.140127 -399.483377)
			(xy 295.201647 -399.499084) (xy 295.260736 -399.522322) (xy 295.316476 -399.552728) (xy 295.368 -399.589832)
			(xy 295.391586 -399.611088) (xy 295.398849 -399.617272) (xy 295.416599 -399.624223) (xy 295.435661 -399.624223)
			(xy 295.453411 -399.617272) (xy 295.460674 -399.611088) (xy 295.48425 -399.589817) (xy 295.535761 -399.552686)
			(xy 295.591498 -399.522265) (xy 295.650592 -399.499026) (xy 295.712121 -399.483332) (xy 295.775126 -399.475429)
			(xy 295.806876 -399.474944) (xy 295.80713 -399.474944) (xy 295.839087 -399.475544) (xy 295.902496 -399.483558)
			(xy 295.964401 -399.499455) (xy 296.023825 -399.522986) (xy 296.079832 -399.553779) (xy 296.131538 -399.591348)
			(xy 296.178128 -399.635102) (xy 296.218866 -399.684349) (xy 296.253112 -399.738314) (xy 296.280324 -399.796145)
			(xy 296.300074 -399.856931) (xy 296.312049 -399.919712) (xy 296.316063 -399.9835) (xy 297.07602 -399.9835)
			(xy 297.080035 -399.919693) (xy 297.092015 -399.856892) (xy 297.111773 -399.796089) (xy 297.138995 -399.738241)
			(xy 297.173253 -399.684261) (xy 297.214007 -399.635001) (xy 297.260613 -399.591237) (xy 297.312338 -399.55366)
			(xy 297.368364 -399.522862) (xy 297.427809 -399.499329) (xy 297.489734 -399.483433) (xy 297.553163 -399.475423)
			(xy 297.58513 -399.474944) (xy 297.585384 -399.474944) (xy 297.617131 -399.475444) (xy 297.680127 -399.483377)
			(xy 297.741647 -399.499084) (xy 297.800736 -399.522322) (xy 297.856476 -399.552728) (xy 297.908 -399.589832)
			(xy 297.931586 -399.611088) (xy 297.938849 -399.617272) (xy 297.956599 -399.624223) (xy 297.975661 -399.624223)
			(xy 297.993411 -399.617272) (xy 298.000674 -399.611088) (xy 298.02425 -399.589817) (xy 298.075761 -399.552686)
			(xy 298.131498 -399.522265) (xy 298.190592 -399.499026) (xy 298.252121 -399.483332) (xy 298.315126 -399.475429)
			(xy 298.346876 -399.474944) (xy 298.34713 -399.474944) (xy 298.379087 -399.475544) (xy 298.442496 -399.483558)
			(xy 298.504401 -399.499455) (xy 298.563825 -399.522986) (xy 298.619832 -399.553779) (xy 298.671538 -399.591348)
			(xy 298.718128 -399.635102) (xy 298.758866 -399.684349) (xy 298.793112 -399.738314) (xy 298.820324 -399.796145)
			(xy 298.840074 -399.856931) (xy 298.852049 -399.919712) (xy 298.856063 -399.9835) (xy 298.852049 -400.047288)
			(xy 298.840074 -400.110069) (xy 298.820324 -400.170855) (xy 298.793112 -400.228686) (xy 298.758866 -400.282651)
			(xy 298.718128 -400.331898) (xy 298.671538 -400.375652) (xy 298.619832 -400.413221) (xy 298.563825 -400.444014)
			(xy 298.504401 -400.467545) (xy 298.442496 -400.483442) (xy 298.379087 -400.491456) (xy 298.34713 -400.49196)
			(xy 298.346876 -400.49196) (xy 298.315131 -400.491422) (xy 298.252136 -400.483497) (xy 298.190616 -400.467797)
			(xy 298.131527 -400.444566) (xy 298.075787 -400.414166) (xy 298.024261 -400.377069) (xy 298.000674 -400.355816)
			(xy 297.993411 -400.349632) (xy 297.975661 -400.342681) (xy 297.956599 -400.342681) (xy 297.938849 -400.349632)
			(xy 297.931586 -400.355816) (xy 297.908028 -400.377107) (xy 297.856512 -400.414235) (xy 297.800771 -400.444654)
			(xy 297.741674 -400.467889) (xy 297.680142 -400.483579) (xy 297.617135 -400.491478) (xy 297.585384 -400.49196)
			(xy 297.58513 -400.49196) (xy 297.553163 -400.491577) (xy 297.489734 -400.483567) (xy 297.427809 -400.467671)
			(xy 297.368364 -400.444138) (xy 297.312338 -400.41334) (xy 297.260613 -400.375763) (xy 297.214007 -400.331999)
			(xy 297.173253 -400.282739) (xy 297.138995 -400.228759) (xy 297.111773 -400.170911) (xy 297.092015 -400.110108)
			(xy 297.080035 -400.047307) (xy 297.07602 -399.9835) (xy 296.316063 -399.9835) (xy 296.312049 -400.047288)
			(xy 296.300074 -400.110069) (xy 296.280324 -400.170855) (xy 296.253112 -400.228686) (xy 296.218866 -400.282651)
			(xy 296.178128 -400.331898) (xy 296.131538 -400.375652) (xy 296.079832 -400.413221) (xy 296.023825 -400.444014)
			(xy 295.964401 -400.467545) (xy 295.902496 -400.483442) (xy 295.839087 -400.491456) (xy 295.80713 -400.49196)
			(xy 295.806876 -400.49196) (xy 295.775131 -400.491422) (xy 295.712136 -400.483497) (xy 295.650616 -400.467797)
			(xy 295.591527 -400.444566) (xy 295.535787 -400.414166) (xy 295.484261 -400.377069) (xy 295.460674 -400.355816)
			(xy 295.453411 -400.349632) (xy 295.435661 -400.342681) (xy 295.416599 -400.342681) (xy 295.398849 -400.349632)
			(xy 295.391586 -400.355816) (xy 295.368028 -400.377107) (xy 295.316512 -400.414235) (xy 295.260771 -400.444654)
			(xy 295.201674 -400.467889) (xy 295.140142 -400.483579) (xy 295.077135 -400.491478) (xy 295.045384 -400.49196)
			(xy 295.04513 -400.49196) (xy 295.013163 -400.491577) (xy 294.949734 -400.483567) (xy 294.887809 -400.467671)
			(xy 294.828364 -400.444138) (xy 294.772338 -400.41334) (xy 294.720613 -400.375763) (xy 294.674007 -400.331999)
			(xy 294.633253 -400.282739) (xy 294.598995 -400.228759) (xy 294.571773 -400.170911) (xy 294.552015 -400.110108)
			(xy 294.540035 -400.047307) (xy 294.53602 -399.9835) (xy 293.926484 -399.9835) (xy 293.92247 -400.047293)
			(xy 293.910493 -400.110079) (xy 293.890741 -400.17087) (xy 293.863525 -400.228705) (xy 293.829276 -400.282674)
			(xy 293.788532 -400.331924) (xy 293.741937 -400.375679) (xy 293.690226 -400.41325) (xy 293.634213 -400.444043)
			(xy 293.574783 -400.467573) (xy 293.512872 -400.483468) (xy 293.449457 -400.491479) (xy 293.417498 -400.49196)
			(xy 293.417244 -400.49196) (xy 293.385498 -400.491442) (xy 293.322502 -400.483512) (xy 293.260982 -400.467809)
			(xy 293.201894 -400.444575) (xy 293.146154 -400.414171) (xy 293.094629 -400.37707) (xy 293.071042 -400.355816)
			(xy 293.063779 -400.349632) (xy 293.046029 -400.342681) (xy 293.026967 -400.342681) (xy 293.009217 -400.349632)
			(xy 293.001954 -400.355816) (xy 292.978367 -400.377074) (xy 292.926858 -400.414206) (xy 292.871123 -400.44463)
			(xy 292.812032 -400.467871) (xy 292.750504 -400.483567) (xy 292.687501 -400.491474) (xy 292.655752 -400.49196)
			(xy 292.655498 -400.49196) (xy 292.623534 -400.491554) (xy 292.56011 -400.483542) (xy 292.498191 -400.467643)
			(xy 292.438752 -400.44411) (xy 292.382731 -400.413312) (xy 292.331013 -400.375736) (xy 292.284411 -400.331974)
			(xy 292.243662 -400.282717) (xy 292.209408 -400.22874) (xy 292.182189 -400.170897) (xy 292.162434 -400.110098)
			(xy 292.150455 -400.047302) (xy 292.146441 -399.9835) (xy 291.386484 -399.9835) (xy 291.38247 -400.047293)
			(xy 291.370493 -400.110079) (xy 291.350741 -400.17087) (xy 291.323525 -400.228705) (xy 291.289276 -400.282674)
			(xy 291.248532 -400.331924) (xy 291.201937 -400.375679) (xy 291.150226 -400.41325) (xy 291.094213 -400.444043)
			(xy 291.034783 -400.467573) (xy 290.972872 -400.483468) (xy 290.909457 -400.491479) (xy 290.877498 -400.49196)
			(xy 290.877244 -400.49196) (xy 290.845498 -400.491442) (xy 290.782502 -400.483512) (xy 290.720982 -400.467809)
			(xy 290.661894 -400.444575) (xy 290.606154 -400.414171) (xy 290.554629 -400.37707) (xy 290.531042 -400.355816)
			(xy 290.523779 -400.349632) (xy 290.506029 -400.342681) (xy 290.486967 -400.342681) (xy 290.469217 -400.349632)
			(xy 290.461954 -400.355816) (xy 290.438367 -400.377074) (xy 290.386858 -400.414206) (xy 290.331123 -400.44463)
			(xy 290.272032 -400.467871) (xy 290.210504 -400.483567) (xy 290.147501 -400.491474) (xy 290.115752 -400.49196)
			(xy 290.115498 -400.49196) (xy 290.083534 -400.491554) (xy 290.02011 -400.483542) (xy 289.958191 -400.467643)
			(xy 289.898752 -400.44411) (xy 289.842731 -400.413312) (xy 289.791013 -400.375736) (xy 289.744411 -400.331974)
			(xy 289.703662 -400.282717) (xy 289.669408 -400.22874) (xy 289.642189 -400.170897) (xy 289.622434 -400.110098)
			(xy 289.610455 -400.047302) (xy 289.606441 -399.9835) (xy 281.686508 -399.9835) (xy 281.686508 -400.885449)
			(xy 303.599106 -400.885449) (xy 303.599106 -400.830951) (xy 303.606862 -400.777009) (xy 303.622215 -400.724719)
			(xy 303.644854 -400.675146) (xy 303.674317 -400.6293) (xy 303.710004 -400.588113) (xy 303.75119 -400.552424)
			(xy 303.797036 -400.52296) (xy 303.846608 -400.500319) (xy 303.898897 -400.484964) (xy 303.952839 -400.477207)
			(xy 303.980088 -400.47672) (xy 304.843688 -400.47672) (xy 304.870943 -400.477126) (xy 304.9249 -400.484882)
			(xy 304.977203 -400.500238) (xy 305.026788 -400.522882) (xy 305.072646 -400.552352) (xy 305.113843 -400.588048)
			(xy 305.149541 -400.629244) (xy 305.179012 -400.675101) (xy 305.201657 -400.724686) (xy 305.217015 -400.776989)
			(xy 305.224773 -400.830945) (xy 305.224773 -400.885452) (xy 306.662283 -400.885452) (xy 306.662283 -400.830948)
			(xy 306.67004 -400.776998) (xy 306.685397 -400.724702) (xy 306.70804 -400.675124) (xy 306.737508 -400.629273)
			(xy 306.773202 -400.588082) (xy 306.814395 -400.552391) (xy 306.860248 -400.522926) (xy 306.909828 -400.500287)
			(xy 306.962126 -400.484935) (xy 307.016076 -400.477181) (xy 307.043328 -400.47672) (xy 307.906928 -400.47672)
			(xy 307.93418 -400.477152) (xy 307.988129 -400.484912) (xy 308.040424 -400.500271) (xy 308.090001 -400.522915)
			(xy 308.135851 -400.552384) (xy 308.177041 -400.588079) (xy 308.212732 -400.629271) (xy 308.242198 -400.675123)
			(xy 308.264839 -400.724702) (xy 308.280194 -400.776999) (xy 308.28795 -400.830948) (xy 308.28795 -400.885448)
			(xy 309.725606 -400.885448) (xy 309.725606 -400.830952) (xy 309.733361 -400.777011) (xy 309.748714 -400.724723)
			(xy 309.771351 -400.675152) (xy 309.800812 -400.629306) (xy 309.836497 -400.58812) (xy 309.877681 -400.552431)
			(xy 309.923524 -400.522966) (xy 309.973093 -400.500325) (xy 310.02538 -400.484968) (xy 310.07932 -400.477208)
			(xy 310.106568 -400.47672) (xy 310.970168 -400.47672) (xy 310.997424 -400.477125) (xy 311.051383 -400.484879)
			(xy 311.103688 -400.500233) (xy 311.153276 -400.522875) (xy 311.199137 -400.552345) (xy 311.240336 -400.588041)
			(xy 311.276036 -400.629238) (xy 311.305509 -400.675096) (xy 311.328156 -400.724682) (xy 311.343515 -400.776986)
			(xy 311.351273 -400.830944) (xy 311.351273 -400.885451) (xy 312.788783 -400.885451) (xy 312.788783 -400.830949)
			(xy 312.79654 -400.777001) (xy 312.811895 -400.724706) (xy 312.834537 -400.675129) (xy 312.864003 -400.629279)
			(xy 312.899695 -400.588089) (xy 312.940886 -400.552398) (xy 312.986736 -400.522933) (xy 313.036314 -400.500292)
			(xy 313.088609 -400.484938) (xy 313.142557 -400.477183) (xy 313.169808 -400.47672) (xy 314.033408 -400.47672)
			(xy 314.060661 -400.47715) (xy 314.114612 -400.484908) (xy 314.166909 -400.500265) (xy 314.216489 -400.522909)
			(xy 314.262342 -400.552377) (xy 314.303534 -400.588071) (xy 314.339228 -400.629264) (xy 314.368695 -400.675118)
			(xy 314.391337 -400.724698) (xy 314.406693 -400.776996) (xy 314.41445 -400.830947) (xy 314.41445 -400.885453)
			(xy 315.851983 -400.885453) (xy 315.851983 -400.830947) (xy 315.859741 -400.776996) (xy 315.875098 -400.724698)
			(xy 315.897743 -400.675118) (xy 315.927213 -400.629266) (xy 315.962909 -400.588075) (xy 316.004105 -400.552384)
			(xy 316.04996 -400.52292) (xy 316.099543 -400.500282) (xy 316.151843 -400.484931) (xy 316.205795 -400.47718)
			(xy 316.233048 -400.47672) (xy 317.096648 -400.47672) (xy 317.123899 -400.477153) (xy 317.177846 -400.484916)
			(xy 317.230138 -400.500276) (xy 317.279713 -400.522922) (xy 317.325561 -400.552391) (xy 317.366748 -400.588086)
			(xy 317.402437 -400.629278) (xy 317.431901 -400.675129) (xy 317.454541 -400.724707) (xy 317.469894 -400.777001)
			(xy 317.47765 -400.830949) (xy 317.47765 -400.885449) (xy 318.915306 -400.885449) (xy 318.915306 -400.830951)
			(xy 318.923062 -400.777009) (xy 318.938415 -400.724719) (xy 318.961054 -400.675146) (xy 318.990517 -400.6293)
			(xy 319.026204 -400.588113) (xy 319.06739 -400.552424) (xy 319.113236 -400.52296) (xy 319.162808 -400.500319)
			(xy 319.215097 -400.484964) (xy 319.269039 -400.477207) (xy 319.296288 -400.47672) (xy 320.159888 -400.47672)
			(xy 320.187143 -400.477126) (xy 320.2411 -400.484882) (xy 320.293403 -400.500238) (xy 320.342988 -400.522882)
			(xy 320.388846 -400.552352) (xy 320.430043 -400.588048) (xy 320.465741 -400.629244) (xy 320.495212 -400.675101)
			(xy 320.517857 -400.724686) (xy 320.533215 -400.776989) (xy 320.540973 -400.830945) (xy 320.540973 -400.885452)
			(xy 321.978483 -400.885452) (xy 321.978483 -400.830948) (xy 321.98624 -400.776998) (xy 322.001597 -400.724702)
			(xy 322.02424 -400.675124) (xy 322.053708 -400.629273) (xy 322.089402 -400.588082) (xy 322.130595 -400.552391)
			(xy 322.176448 -400.522926) (xy 322.226028 -400.500287) (xy 322.278326 -400.484935) (xy 322.332276 -400.477181)
			(xy 322.359528 -400.47672) (xy 323.223128 -400.47672) (xy 323.25038 -400.477152) (xy 323.304329 -400.484912)
			(xy 323.356624 -400.500271) (xy 323.406201 -400.522915) (xy 323.452051 -400.552384) (xy 323.493241 -400.588079)
			(xy 323.528932 -400.629271) (xy 323.558398 -400.675123) (xy 323.581039 -400.724702) (xy 323.596394 -400.776999)
			(xy 323.60415 -400.830948) (xy 323.60415 -400.885448) (xy 325.041806 -400.885448) (xy 325.041806 -400.830952)
			(xy 325.049561 -400.777011) (xy 325.064914 -400.724723) (xy 325.087551 -400.675152) (xy 325.117012 -400.629306)
			(xy 325.152697 -400.58812) (xy 325.193881 -400.552431) (xy 325.239724 -400.522966) (xy 325.289293 -400.500325)
			(xy 325.34158 -400.484968) (xy 325.39552 -400.477208) (xy 325.422768 -400.47672) (xy 326.286368 -400.47672)
			(xy 326.313624 -400.477125) (xy 326.367583 -400.484879) (xy 326.419888 -400.500233) (xy 326.469476 -400.522875)
			(xy 326.515337 -400.552345) (xy 326.556536 -400.588041) (xy 326.592236 -400.629238) (xy 326.621709 -400.675096)
			(xy 326.644356 -400.724682) (xy 326.659715 -400.776986) (xy 326.667473 -400.830944) (xy 326.667473 -400.885451)
			(xy 328.104983 -400.885451) (xy 328.104983 -400.830949) (xy 328.11274 -400.777001) (xy 328.128095 -400.724706)
			(xy 328.150737 -400.675129) (xy 328.180203 -400.629279) (xy 328.215895 -400.588089) (xy 328.257086 -400.552398)
			(xy 328.302936 -400.522933) (xy 328.352514 -400.500292) (xy 328.404809 -400.484938) (xy 328.458757 -400.477183)
			(xy 328.486008 -400.47672) (xy 329.349608 -400.47672) (xy 329.376861 -400.47715) (xy 329.430812 -400.484908)
			(xy 329.483109 -400.500265) (xy 329.532689 -400.522909) (xy 329.578542 -400.552377) (xy 329.619734 -400.588071)
			(xy 329.655428 -400.629264) (xy 329.684895 -400.675118) (xy 329.707537 -400.724698) (xy 329.722893 -400.776996)
			(xy 329.73065 -400.830947) (xy 329.73065 -400.885453) (xy 331.168183 -400.885453) (xy 331.168183 -400.830947)
			(xy 331.175941 -400.776996) (xy 331.191298 -400.724698) (xy 331.213943 -400.675118) (xy 331.243413 -400.629266)
			(xy 331.279109 -400.588075) (xy 331.320305 -400.552384) (xy 331.36616 -400.52292) (xy 331.415743 -400.500282)
			(xy 331.468043 -400.484931) (xy 331.521995 -400.47718) (xy 331.549248 -400.47672) (xy 332.412848 -400.47672)
			(xy 332.440099 -400.477153) (xy 332.494046 -400.484916) (xy 332.546338 -400.500276) (xy 332.595913 -400.522922)
			(xy 332.641761 -400.552391) (xy 332.682948 -400.588086) (xy 332.718637 -400.629278) (xy 332.748101 -400.675129)
			(xy 332.770741 -400.724707) (xy 332.786094 -400.777001) (xy 332.79385 -400.830949) (xy 332.79385 -400.885449)
			(xy 334.231506 -400.885449) (xy 334.231506 -400.830951) (xy 334.239262 -400.777009) (xy 334.254615 -400.724719)
			(xy 334.277254 -400.675146) (xy 334.306717 -400.6293) (xy 334.342404 -400.588113) (xy 334.38359 -400.552424)
			(xy 334.429436 -400.52296) (xy 334.479008 -400.500319) (xy 334.531297 -400.484964) (xy 334.585239 -400.477207)
			(xy 334.612488 -400.47672) (xy 335.476088 -400.47672) (xy 335.503343 -400.477126) (xy 335.5573 -400.484882)
			(xy 335.609603 -400.500238) (xy 335.659188 -400.522882) (xy 335.705046 -400.552352) (xy 335.746243 -400.588048)
			(xy 335.781941 -400.629244) (xy 335.811412 -400.675101) (xy 335.834057 -400.724686) (xy 335.849415 -400.776989)
			(xy 335.857173 -400.830945) (xy 335.857173 -400.885452) (xy 337.294683 -400.885452) (xy 337.294683 -400.830948)
			(xy 337.30244 -400.776998) (xy 337.317797 -400.724702) (xy 337.34044 -400.675124) (xy 337.369908 -400.629273)
			(xy 337.405602 -400.588082) (xy 337.446795 -400.552391) (xy 337.492648 -400.522926) (xy 337.542228 -400.500287)
			(xy 337.594526 -400.484935) (xy 337.648476 -400.477181) (xy 337.675728 -400.47672) (xy 338.539328 -400.47672)
			(xy 338.56658 -400.477152) (xy 338.620529 -400.484912) (xy 338.672824 -400.500271) (xy 338.722401 -400.522915)
			(xy 338.768251 -400.552384) (xy 338.809441 -400.588079) (xy 338.845132 -400.629271) (xy 338.874598 -400.675123)
			(xy 338.897239 -400.724702) (xy 338.912594 -400.776999) (xy 338.92035 -400.830948) (xy 338.92035 -400.885448)
			(xy 340.358006 -400.885448) (xy 340.358006 -400.830952) (xy 340.365761 -400.777011) (xy 340.381114 -400.724723)
			(xy 340.403751 -400.675152) (xy 340.433212 -400.629306) (xy 340.468897 -400.58812) (xy 340.510081 -400.552431)
			(xy 340.555924 -400.522966) (xy 340.605493 -400.500325) (xy 340.65778 -400.484968) (xy 340.71172 -400.477208)
			(xy 340.738968 -400.47672) (xy 341.602568 -400.47672) (xy 341.629824 -400.477125) (xy 341.683783 -400.484879)
			(xy 341.736088 -400.500233) (xy 341.785676 -400.522875) (xy 341.831537 -400.552345) (xy 341.872736 -400.588041)
			(xy 341.908436 -400.629238) (xy 341.937909 -400.675096) (xy 341.960556 -400.724682) (xy 341.975915 -400.776986)
			(xy 341.983673 -400.830944) (xy 341.983673 -400.885451) (xy 343.421183 -400.885451) (xy 343.421183 -400.830949)
			(xy 343.42894 -400.777001) (xy 343.444295 -400.724706) (xy 343.466937 -400.675129) (xy 343.496403 -400.629279)
			(xy 343.532095 -400.588089) (xy 343.573286 -400.552398) (xy 343.619136 -400.522933) (xy 343.668714 -400.500292)
			(xy 343.721009 -400.484938) (xy 343.774957 -400.477183) (xy 343.802208 -400.47672) (xy 344.665808 -400.47672)
			(xy 344.693061 -400.47715) (xy 344.747012 -400.484908) (xy 344.799309 -400.500265) (xy 344.848889 -400.522909)
			(xy 344.894742 -400.552377) (xy 344.935934 -400.588071) (xy 344.971628 -400.629264) (xy 345.001095 -400.675118)
			(xy 345.023737 -400.724698) (xy 345.039093 -400.776996) (xy 345.04685 -400.830947) (xy 345.04685 -400.885453)
			(xy 346.484383 -400.885453) (xy 346.484383 -400.830947) (xy 346.492141 -400.776996) (xy 346.507498 -400.724698)
			(xy 346.530143 -400.675118) (xy 346.559613 -400.629266) (xy 346.595309 -400.588075) (xy 346.636505 -400.552384)
			(xy 346.68236 -400.52292) (xy 346.731943 -400.500282) (xy 346.784243 -400.484931) (xy 346.838195 -400.47718)
			(xy 346.865448 -400.47672) (xy 347.729048 -400.47672) (xy 347.756299 -400.477153) (xy 347.810246 -400.484916)
			(xy 347.862538 -400.500276) (xy 347.912113 -400.522922) (xy 347.957961 -400.552391) (xy 347.999148 -400.588086)
			(xy 348.034837 -400.629278) (xy 348.064301 -400.675129) (xy 348.086941 -400.724707) (xy 348.102294 -400.777001)
			(xy 348.11005 -400.830949) (xy 348.11005 -400.885449) (xy 349.547706 -400.885449) (xy 349.547706 -400.830951)
			(xy 349.555462 -400.777009) (xy 349.570815 -400.724719) (xy 349.593454 -400.675146) (xy 349.622917 -400.6293)
			(xy 349.658604 -400.588113) (xy 349.69979 -400.552424) (xy 349.745636 -400.52296) (xy 349.795208 -400.500319)
			(xy 349.847497 -400.484964) (xy 349.901439 -400.477207) (xy 349.928688 -400.47672) (xy 350.792288 -400.47672)
			(xy 350.819543 -400.477126) (xy 350.8735 -400.484882) (xy 350.925803 -400.500238) (xy 350.975388 -400.522882)
			(xy 351.021246 -400.552352) (xy 351.062443 -400.588048) (xy 351.098141 -400.629244) (xy 351.127612 -400.675101)
			(xy 351.150257 -400.724686) (xy 351.165615 -400.776989) (xy 351.173373 -400.830945) (xy 351.173373 -400.885452)
			(xy 371.041883 -400.885452) (xy 371.041883 -400.830948) (xy 371.049641 -400.776998) (xy 371.064997 -400.724702)
			(xy 371.08764 -400.675123) (xy 371.117109 -400.629272) (xy 371.152803 -400.588082) (xy 371.193996 -400.552391)
			(xy 371.23985 -400.522926) (xy 371.28943 -400.500286) (xy 371.341728 -400.484934) (xy 371.395678 -400.477181)
			(xy 371.42293 -400.47672) (xy 372.28653 -400.47672) (xy 372.313782 -400.477152) (xy 372.36773 -400.484912)
			(xy 372.420025 -400.500271) (xy 372.469602 -400.522916) (xy 372.515452 -400.552385) (xy 372.556642 -400.588079)
			(xy 372.592333 -400.629272) (xy 372.621799 -400.675124) (xy 372.644439 -400.724703) (xy 372.659794 -400.776999)
			(xy 372.66755 -400.830948) (xy 372.66755 -400.885448) (xy 374.105206 -400.885448) (xy 374.105206 -400.830952)
			(xy 374.112961 -400.777011) (xy 374.128314 -400.724723) (xy 374.150951 -400.675151) (xy 374.180412 -400.629306)
			(xy 374.216098 -400.588119) (xy 374.257281 -400.55243) (xy 374.303125 -400.522965) (xy 374.352694 -400.500324)
			(xy 374.404982 -400.484968) (xy 374.458922 -400.477208) (xy 374.48617 -400.47672) (xy 375.34977 -400.47672)
			(xy 375.377026 -400.477125) (xy 375.430984 -400.484879) (xy 375.48329 -400.500234) (xy 375.532877 -400.522876)
			(xy 375.578738 -400.552345) (xy 375.619937 -400.588042) (xy 375.655637 -400.629238) (xy 375.68511 -400.675096)
			(xy 375.707756 -400.724682) (xy 375.723115 -400.776986) (xy 375.730873 -400.830944) (xy 375.730873 -400.885451)
			(xy 377.168383 -400.885451) (xy 377.168383 -400.830949) (xy 377.17614 -400.777001) (xy 377.191495 -400.724706)
			(xy 377.214137 -400.675129) (xy 377.243604 -400.629279) (xy 377.279296 -400.588089) (xy 377.320487 -400.552398)
			(xy 377.366338 -400.522932) (xy 377.415915 -400.500292) (xy 377.468211 -400.484938) (xy 377.522159 -400.477183)
			(xy 377.54941 -400.47672) (xy 378.41301 -400.47672) (xy 378.440263 -400.477151) (xy 378.494213 -400.484909)
			(xy 378.546511 -400.500266) (xy 378.59609 -400.522909) (xy 378.641943 -400.552378) (xy 378.683135 -400.588072)
			(xy 378.718828 -400.629265) (xy 378.748296 -400.675118) (xy 378.770938 -400.724699) (xy 378.786293 -400.776996)
			(xy 378.79405 -400.830947) (xy 378.79405 -400.885447) (xy 380.231706 -400.885447) (xy 380.231706 -400.830953)
			(xy 380.239461 -400.777014) (xy 380.254812 -400.724727) (xy 380.277448 -400.675157) (xy 380.306907 -400.629312)
			(xy 380.342591 -400.588126) (xy 380.383772 -400.552437) (xy 380.429613 -400.522972) (xy 380.47918 -400.50033)
			(xy 380.531465 -400.484971) (xy 380.585403 -400.47721) (xy 380.61265 -400.47672) (xy 381.47625 -400.47672)
			(xy 381.503507 -400.477124) (xy 381.557468 -400.484875) (xy 381.609775 -400.500228) (xy 381.659365 -400.522869)
			(xy 381.705228 -400.552338) (xy 381.74643 -400.588035) (xy 381.782132 -400.629232) (xy 381.811607 -400.675091)
			(xy 381.834254 -400.724678) (xy 381.849614 -400.776983) (xy 381.857373 -400.830943) (xy 381.857373 -400.885449)
			(xy 383.294906 -400.885449) (xy 383.294906 -400.830951) (xy 383.302662 -400.777008) (xy 383.318015 -400.724718)
			(xy 383.340654 -400.675145) (xy 383.370117 -400.629299) (xy 383.405805 -400.588112) (xy 383.446991 -400.552423)
			(xy 383.492837 -400.522959) (xy 383.542409 -400.500319) (xy 383.594699 -400.484964) (xy 383.648641 -400.477207)
			(xy 383.67589 -400.47672) (xy 384.53949 -400.47672) (xy 384.566745 -400.477126) (xy 384.620701 -400.484883)
			(xy 384.673004 -400.500239) (xy 384.722589 -400.522883) (xy 384.768447 -400.552352) (xy 384.809644 -400.588049)
			(xy 384.845342 -400.629245) (xy 384.874813 -400.675102) (xy 384.897458 -400.724686) (xy 384.912815 -400.776989)
			(xy 384.920573 -400.830945) (xy 384.920573 -400.885452) (xy 386.358083 -400.885452) (xy 386.358083 -400.830948)
			(xy 386.365841 -400.776998) (xy 386.381197 -400.724702) (xy 386.40384 -400.675123) (xy 386.433309 -400.629272)
			(xy 386.469003 -400.588082) (xy 386.510196 -400.552391) (xy 386.55605 -400.522926) (xy 386.60563 -400.500286)
			(xy 386.657928 -400.484934) (xy 386.711878 -400.477181) (xy 386.73913 -400.47672) (xy 387.60273 -400.47672)
			(xy 387.629982 -400.477152) (xy 387.68393 -400.484912) (xy 387.736225 -400.500271) (xy 387.785802 -400.522916)
			(xy 387.831652 -400.552385) (xy 387.872842 -400.588079) (xy 387.908533 -400.629272) (xy 387.937999 -400.675124)
			(xy 387.960639 -400.724703) (xy 387.975994 -400.776999) (xy 387.98375 -400.830948) (xy 387.98375 -400.885448)
			(xy 389.421406 -400.885448) (xy 389.421406 -400.830952) (xy 389.429161 -400.777011) (xy 389.444514 -400.724723)
			(xy 389.467151 -400.675151) (xy 389.496612 -400.629306) (xy 389.532298 -400.588119) (xy 389.573481 -400.55243)
			(xy 389.619325 -400.522965) (xy 389.668894 -400.500324) (xy 389.721182 -400.484968) (xy 389.775122 -400.477208)
			(xy 389.80237 -400.47672) (xy 390.66597 -400.47672) (xy 390.693226 -400.477125) (xy 390.747184 -400.484879)
			(xy 390.79949 -400.500234) (xy 390.849077 -400.522876) (xy 390.894938 -400.552345) (xy 390.936137 -400.588042)
			(xy 390.971837 -400.629238) (xy 391.00131 -400.675096) (xy 391.023956 -400.724682) (xy 391.039315 -400.776986)
			(xy 391.047073 -400.830944) (xy 391.047073 -400.885451) (xy 392.484583 -400.885451) (xy 392.484583 -400.830949)
			(xy 392.49234 -400.777001) (xy 392.507695 -400.724706) (xy 392.530337 -400.675129) (xy 392.559804 -400.629279)
			(xy 392.595496 -400.588089) (xy 392.636687 -400.552398) (xy 392.682538 -400.522932) (xy 392.732115 -400.500292)
			(xy 392.784411 -400.484938) (xy 392.838359 -400.477183) (xy 392.86561 -400.47672) (xy 393.72921 -400.47672)
			(xy 393.756463 -400.477151) (xy 393.810413 -400.484909) (xy 393.862711 -400.500266) (xy 393.91229 -400.522909)
			(xy 393.958143 -400.552378) (xy 393.999335 -400.588072) (xy 394.035028 -400.629265) (xy 394.064496 -400.675118)
			(xy 394.087138 -400.724699) (xy 394.102493 -400.776996) (xy 394.11025 -400.830947) (xy 394.11025 -400.885447)
			(xy 395.547906 -400.885447) (xy 395.547906 -400.830953) (xy 395.555661 -400.777014) (xy 395.571012 -400.724727)
			(xy 395.593648 -400.675157) (xy 395.623107 -400.629312) (xy 395.658791 -400.588126) (xy 395.699972 -400.552437)
			(xy 395.745813 -400.522972) (xy 395.79538 -400.50033) (xy 395.847665 -400.484971) (xy 395.901603 -400.47721)
			(xy 395.92885 -400.47672) (xy 396.79245 -400.47672) (xy 396.819707 -400.477124) (xy 396.873668 -400.484875)
			(xy 396.925975 -400.500228) (xy 396.975565 -400.522869) (xy 397.021428 -400.552338) (xy 397.06263 -400.588035)
			(xy 397.098332 -400.629232) (xy 397.127807 -400.675091) (xy 397.150454 -400.724678) (xy 397.165814 -400.776983)
			(xy 397.173573 -400.830943) (xy 397.173573 -400.885449) (xy 398.611106 -400.885449) (xy 398.611106 -400.830951)
			(xy 398.618862 -400.777008) (xy 398.634215 -400.724718) (xy 398.656854 -400.675145) (xy 398.686317 -400.629299)
			(xy 398.722005 -400.588112) (xy 398.763191 -400.552423) (xy 398.809037 -400.522959) (xy 398.858609 -400.500319)
			(xy 398.910899 -400.484964) (xy 398.964841 -400.477207) (xy 398.99209 -400.47672) (xy 399.85569 -400.47672)
			(xy 399.882945 -400.477126) (xy 399.936901 -400.484883) (xy 399.989204 -400.500239) (xy 400.038789 -400.522883)
			(xy 400.084647 -400.552352) (xy 400.125844 -400.588049) (xy 400.161542 -400.629245) (xy 400.191013 -400.675102)
			(xy 400.213658 -400.724686) (xy 400.229015 -400.776989) (xy 400.236773 -400.830945) (xy 400.236773 -400.885452)
			(xy 401.674283 -400.885452) (xy 401.674283 -400.830948) (xy 401.682041 -400.776998) (xy 401.697397 -400.724702)
			(xy 401.72004 -400.675123) (xy 401.749509 -400.629272) (xy 401.785203 -400.588082) (xy 401.826396 -400.552391)
			(xy 401.87225 -400.522926) (xy 401.92183 -400.500286) (xy 401.974128 -400.484934) (xy 402.028078 -400.477181)
			(xy 402.05533 -400.47672) (xy 402.91893 -400.47672) (xy 402.946182 -400.477152) (xy 403.00013 -400.484912)
			(xy 403.052425 -400.500271) (xy 403.102002 -400.522916) (xy 403.147852 -400.552385) (xy 403.189042 -400.588079)
			(xy 403.224733 -400.629272) (xy 403.254199 -400.675124) (xy 403.276839 -400.724703) (xy 403.292194 -400.776999)
			(xy 403.29995 -400.830948) (xy 403.29995 -400.885448) (xy 404.737606 -400.885448) (xy 404.737606 -400.830952)
			(xy 404.745361 -400.777011) (xy 404.760714 -400.724723) (xy 404.783351 -400.675151) (xy 404.812812 -400.629306)
			(xy 404.848498 -400.588119) (xy 404.889681 -400.55243) (xy 404.935525 -400.522965) (xy 404.985094 -400.500324)
			(xy 405.037382 -400.484968) (xy 405.091322 -400.477208) (xy 405.11857 -400.47672) (xy 405.98217 -400.47672)
			(xy 406.009426 -400.477125) (xy 406.063384 -400.484879) (xy 406.11569 -400.500234) (xy 406.165277 -400.522876)
			(xy 406.211138 -400.552345) (xy 406.252337 -400.588042) (xy 406.288037 -400.629238) (xy 406.31751 -400.675096)
			(xy 406.340156 -400.724682) (xy 406.355515 -400.776986) (xy 406.363273 -400.830944) (xy 406.363273 -400.885451)
			(xy 407.800783 -400.885451) (xy 407.800783 -400.830949) (xy 407.80854 -400.777001) (xy 407.823895 -400.724706)
			(xy 407.846537 -400.675129) (xy 407.876004 -400.629279) (xy 407.911696 -400.588089) (xy 407.952887 -400.552398)
			(xy 407.998738 -400.522932) (xy 408.048315 -400.500292) (xy 408.100611 -400.484938) (xy 408.154559 -400.477183)
			(xy 408.18181 -400.47672) (xy 409.04541 -400.47672) (xy 409.072663 -400.477151) (xy 409.126613 -400.484909)
			(xy 409.178911 -400.500266) (xy 409.22849 -400.522909) (xy 409.274343 -400.552378) (xy 409.315535 -400.588072)
			(xy 409.351228 -400.629265) (xy 409.380696 -400.675118) (xy 409.403338 -400.724699) (xy 409.418693 -400.776996)
			(xy 409.42645 -400.830947) (xy 409.42645 -400.885447) (xy 410.864106 -400.885447) (xy 410.864106 -400.830953)
			(xy 410.871861 -400.777014) (xy 410.887212 -400.724727) (xy 410.909848 -400.675157) (xy 410.939307 -400.629312)
			(xy 410.974991 -400.588126) (xy 411.016172 -400.552437) (xy 411.062013 -400.522972) (xy 411.11158 -400.50033)
			(xy 411.163865 -400.484971) (xy 411.217803 -400.47721) (xy 411.24505 -400.47672) (xy 412.10865 -400.47672)
			(xy 412.135907 -400.477124) (xy 412.189868 -400.484875) (xy 412.242175 -400.500228) (xy 412.291765 -400.522869)
			(xy 412.337628 -400.552338) (xy 412.37883 -400.588035) (xy 412.414532 -400.629232) (xy 412.444007 -400.675091)
			(xy 412.466654 -400.724678) (xy 412.482014 -400.776983) (xy 412.489773 -400.830943) (xy 412.489773 -400.885449)
			(xy 413.927306 -400.885449) (xy 413.927306 -400.830951) (xy 413.935062 -400.777008) (xy 413.950415 -400.724718)
			(xy 413.973054 -400.675145) (xy 414.002517 -400.629299) (xy 414.038205 -400.588112) (xy 414.079391 -400.552423)
			(xy 414.125237 -400.522959) (xy 414.174809 -400.500319) (xy 414.227099 -400.484964) (xy 414.281041 -400.477207)
			(xy 414.30829 -400.47672) (xy 415.17189 -400.47672) (xy 415.199145 -400.477126) (xy 415.253101 -400.484883)
			(xy 415.305404 -400.500239) (xy 415.354989 -400.522883) (xy 415.400847 -400.552352) (xy 415.442044 -400.588049)
			(xy 415.477742 -400.629245) (xy 415.507213 -400.675102) (xy 415.529858 -400.724686) (xy 415.545215 -400.776989)
			(xy 415.552973 -400.830945) (xy 415.552973 -400.885452) (xy 416.990483 -400.885452) (xy 416.990483 -400.830948)
			(xy 416.998241 -400.776998) (xy 417.013597 -400.724702) (xy 417.03624 -400.675123) (xy 417.065709 -400.629272)
			(xy 417.101403 -400.588082) (xy 417.142596 -400.552391) (xy 417.18845 -400.522926) (xy 417.23803 -400.500286)
			(xy 417.290328 -400.484934) (xy 417.344278 -400.477181) (xy 417.37153 -400.47672) (xy 418.23513 -400.47672)
			(xy 418.262382 -400.477152) (xy 418.31633 -400.484912) (xy 418.368625 -400.500271) (xy 418.418202 -400.522916)
			(xy 418.464052 -400.552385) (xy 418.505242 -400.588079) (xy 418.540933 -400.629272) (xy 418.570399 -400.675124)
			(xy 418.593039 -400.724703) (xy 418.608394 -400.776999) (xy 418.61615 -400.830948) (xy 418.61615 -400.885452)
			(xy 418.608394 -400.939401) (xy 418.593039 -400.991697) (xy 418.570399 -401.041276) (xy 418.540933 -401.087128)
			(xy 418.505242 -401.128321) (xy 418.464052 -401.164015) (xy 418.418202 -401.193484) (xy 418.368625 -401.216129)
			(xy 418.31633 -401.231488) (xy 418.262382 -401.239248) (xy 418.23513 -401.239736) (xy 417.37153 -401.239736)
			(xy 417.344278 -401.239219) (xy 417.290328 -401.231466) (xy 417.23803 -401.216114) (xy 417.18845 -401.193474)
			(xy 417.142596 -401.164009) (xy 417.101403 -401.128318) (xy 417.065709 -401.087128) (xy 417.03624 -401.041277)
			(xy 417.013597 -400.991698) (xy 416.998241 -400.939402) (xy 416.990483 -400.885452) (xy 415.552973 -400.885452)
			(xy 415.552973 -400.885455) (xy 415.545215 -400.939411) (xy 415.529858 -400.991714) (xy 415.507213 -401.041298)
			(xy 415.477742 -401.087155) (xy 415.442044 -401.128351) (xy 415.400847 -401.164048) (xy 415.354989 -401.193517)
			(xy 415.305404 -401.216161) (xy 415.253101 -401.231517) (xy 415.199145 -401.239274) (xy 415.17189 -401.239736)
			(xy 414.30829 -401.239736) (xy 414.281041 -401.239193) (xy 414.227099 -401.231436) (xy 414.174809 -401.216081)
			(xy 414.125237 -401.193441) (xy 414.079391 -401.163977) (xy 414.038205 -401.128288) (xy 414.002517 -401.087101)
			(xy 413.973054 -401.041255) (xy 413.950415 -400.991682) (xy 413.935062 -400.939392) (xy 413.927306 -400.885449)
			(xy 412.489773 -400.885449) (xy 412.489773 -400.885457) (xy 412.482014 -400.939416) (xy 412.466654 -400.991722)
			(xy 412.444007 -401.041309) (xy 412.414532 -401.087168) (xy 412.37883 -401.128365) (xy 412.337628 -401.164062)
			(xy 412.291765 -401.193531) (xy 412.242175 -401.216172) (xy 412.189868 -401.231525) (xy 412.135907 -401.239276)
			(xy 412.10865 -401.239736) (xy 411.24505 -401.239736) (xy 411.217803 -401.23919) (xy 411.163865 -401.231429)
			(xy 411.11158 -401.21607) (xy 411.062013 -401.193428) (xy 411.016172 -401.163963) (xy 410.974991 -401.128274)
			(xy 410.939307 -401.087088) (xy 410.909848 -401.041243) (xy 410.887212 -400.991673) (xy 410.871861 -400.939386)
			(xy 410.864106 -400.885447) (xy 409.42645 -400.885447) (xy 409.42645 -400.885453) (xy 409.418693 -400.939404)
			(xy 409.403338 -400.991701) (xy 409.380696 -401.041282) (xy 409.351228 -401.087135) (xy 409.315535 -401.128328)
			(xy 409.274343 -401.164022) (xy 409.22849 -401.193491) (xy 409.178911 -401.216134) (xy 409.126613 -401.231491)
			(xy 409.072663 -401.239249) (xy 409.04541 -401.239736) (xy 408.18181 -401.239736) (xy 408.154559 -401.239217)
			(xy 408.100611 -401.231462) (xy 408.048315 -401.216108) (xy 407.998738 -401.193468) (xy 407.952887 -401.164002)
			(xy 407.911696 -401.128311) (xy 407.876004 -401.087121) (xy 407.846537 -401.041271) (xy 407.823895 -400.991694)
			(xy 407.80854 -400.939399) (xy 407.800783 -400.885451) (xy 406.363273 -400.885451) (xy 406.363273 -400.885456)
			(xy 406.355515 -400.939414) (xy 406.340156 -400.991718) (xy 406.31751 -401.041304) (xy 406.288037 -401.087162)
			(xy 406.252337 -401.128358) (xy 406.211138 -401.164055) (xy 406.165277 -401.193524) (xy 406.11569 -401.216166)
			(xy 406.063384 -401.231521) (xy 406.009426 -401.239275) (xy 405.98217 -401.239736) (xy 405.11857 -401.239736)
			(xy 405.091322 -401.239192) (xy 405.037382 -401.231432) (xy 404.985094 -401.216076) (xy 404.935525 -401.193435)
			(xy 404.889682 -401.16397) (xy 404.848498 -401.128281) (xy 404.812812 -401.087094) (xy 404.783351 -401.041249)
			(xy 404.760714 -400.991677) (xy 404.745361 -400.939389) (xy 404.737606 -400.885448) (xy 403.29995 -400.885448)
			(xy 403.29995 -400.885452) (xy 403.292194 -400.939401) (xy 403.276839 -400.991697) (xy 403.254199 -401.041276)
			(xy 403.224733 -401.087128) (xy 403.189042 -401.128321) (xy 403.147852 -401.164015) (xy 403.102002 -401.193484)
			(xy 403.052425 -401.216129) (xy 403.00013 -401.231488) (xy 402.946182 -401.239248) (xy 402.91893 -401.239736)
			(xy 402.05533 -401.239736) (xy 402.028078 -401.239219) (xy 401.974128 -401.231466) (xy 401.92183 -401.216114)
			(xy 401.87225 -401.193474) (xy 401.826396 -401.164009) (xy 401.785203 -401.128318) (xy 401.749509 -401.087128)
			(xy 401.72004 -401.041277) (xy 401.697397 -400.991698) (xy 401.682041 -400.939402) (xy 401.674283 -400.885452)
			(xy 400.236773 -400.885452) (xy 400.236773 -400.885455) (xy 400.229015 -400.939411) (xy 400.213658 -400.991714)
			(xy 400.191013 -401.041298) (xy 400.161542 -401.087155) (xy 400.125844 -401.128351) (xy 400.084647 -401.164048)
			(xy 400.038789 -401.193517) (xy 399.989204 -401.216161) (xy 399.936901 -401.231517) (xy 399.882945 -401.239274)
			(xy 399.85569 -401.239736) (xy 398.99209 -401.239736) (xy 398.964841 -401.239193) (xy 398.910899 -401.231436)
			(xy 398.858609 -401.216081) (xy 398.809037 -401.193441) (xy 398.763191 -401.163977) (xy 398.722005 -401.128288)
			(xy 398.686317 -401.087101) (xy 398.656854 -401.041255) (xy 398.634215 -400.991682) (xy 398.618862 -400.939392)
			(xy 398.611106 -400.885449) (xy 397.173573 -400.885449) (xy 397.173573 -400.885457) (xy 397.165814 -400.939416)
			(xy 397.150454 -400.991722) (xy 397.127807 -401.041309) (xy 397.098332 -401.087168) (xy 397.06263 -401.128365)
			(xy 397.021428 -401.164062) (xy 396.975565 -401.193531) (xy 396.925975 -401.216172) (xy 396.873668 -401.231525)
			(xy 396.819707 -401.239276) (xy 396.79245 -401.239736) (xy 395.92885 -401.239736) (xy 395.901603 -401.23919)
			(xy 395.847665 -401.231429) (xy 395.79538 -401.21607) (xy 395.745813 -401.193428) (xy 395.699972 -401.163963)
			(xy 395.658791 -401.128274) (xy 395.623107 -401.087088) (xy 395.593648 -401.041243) (xy 395.571012 -400.991673)
			(xy 395.555661 -400.939386) (xy 395.547906 -400.885447) (xy 394.11025 -400.885447) (xy 394.11025 -400.885453)
			(xy 394.102493 -400.939404) (xy 394.087138 -400.991701) (xy 394.064496 -401.041282) (xy 394.035028 -401.087135)
			(xy 393.999335 -401.128328) (xy 393.958143 -401.164022) (xy 393.91229 -401.193491) (xy 393.862711 -401.216134)
			(xy 393.810413 -401.231491) (xy 393.756463 -401.239249) (xy 393.72921 -401.239736) (xy 392.86561 -401.239736)
			(xy 392.838359 -401.239217) (xy 392.784411 -401.231462) (xy 392.732115 -401.216108) (xy 392.682538 -401.193468)
			(xy 392.636687 -401.164002) (xy 392.595496 -401.128311) (xy 392.559804 -401.087121) (xy 392.530337 -401.041271)
			(xy 392.507695 -400.991694) (xy 392.49234 -400.939399) (xy 392.484583 -400.885451) (xy 391.047073 -400.885451)
			(xy 391.047073 -400.885456) (xy 391.039315 -400.939414) (xy 391.023956 -400.991718) (xy 391.00131 -401.041304)
			(xy 390.971837 -401.087162) (xy 390.936137 -401.128358) (xy 390.894938 -401.164055) (xy 390.849077 -401.193524)
			(xy 390.79949 -401.216166) (xy 390.747184 -401.231521) (xy 390.693226 -401.239275) (xy 390.66597 -401.239736)
			(xy 389.80237 -401.239736) (xy 389.775122 -401.239192) (xy 389.721182 -401.231432) (xy 389.668894 -401.216076)
			(xy 389.619325 -401.193435) (xy 389.573482 -401.16397) (xy 389.532298 -401.128281) (xy 389.496612 -401.087094)
			(xy 389.467151 -401.041249) (xy 389.444514 -400.991677) (xy 389.429161 -400.939389) (xy 389.421406 -400.885448)
			(xy 387.98375 -400.885448) (xy 387.98375 -400.885452) (xy 387.975994 -400.939401) (xy 387.960639 -400.991697)
			(xy 387.937999 -401.041276) (xy 387.908533 -401.087128) (xy 387.872842 -401.128321) (xy 387.831652 -401.164015)
			(xy 387.785802 -401.193484) (xy 387.736225 -401.216129) (xy 387.68393 -401.231488) (xy 387.629982 -401.239248)
			(xy 387.60273 -401.239736) (xy 386.73913 -401.239736) (xy 386.711878 -401.239219) (xy 386.657928 -401.231466)
			(xy 386.60563 -401.216114) (xy 386.55605 -401.193474) (xy 386.510196 -401.164009) (xy 386.469003 -401.128318)
			(xy 386.433309 -401.087128) (xy 386.40384 -401.041277) (xy 386.381197 -400.991698) (xy 386.365841 -400.939402)
			(xy 386.358083 -400.885452) (xy 384.920573 -400.885452) (xy 384.920573 -400.885455) (xy 384.912815 -400.939411)
			(xy 384.897458 -400.991714) (xy 384.874813 -401.041298) (xy 384.845342 -401.087155) (xy 384.809644 -401.128351)
			(xy 384.768447 -401.164048) (xy 384.722589 -401.193517) (xy 384.673004 -401.216161) (xy 384.620701 -401.231517)
			(xy 384.566745 -401.239274) (xy 384.53949 -401.239736) (xy 383.67589 -401.239736) (xy 383.648641 -401.239193)
			(xy 383.594699 -401.231436) (xy 383.542409 -401.216081) (xy 383.492837 -401.193441) (xy 383.446991 -401.163977)
			(xy 383.405805 -401.128288) (xy 383.370117 -401.087101) (xy 383.340654 -401.041255) (xy 383.318015 -400.991682)
			(xy 383.302662 -400.939392) (xy 383.294906 -400.885449) (xy 381.857373 -400.885449) (xy 381.857373 -400.885457)
			(xy 381.849614 -400.939416) (xy 381.834254 -400.991722) (xy 381.811607 -401.041309) (xy 381.782132 -401.087168)
			(xy 381.74643 -401.128365) (xy 381.705228 -401.164062) (xy 381.659365 -401.193531) (xy 381.609775 -401.216172)
			(xy 381.557468 -401.231525) (xy 381.503507 -401.239276) (xy 381.47625 -401.239736) (xy 380.61265 -401.239736)
			(xy 380.585403 -401.23919) (xy 380.531465 -401.231429) (xy 380.47918 -401.21607) (xy 380.429613 -401.193428)
			(xy 380.383772 -401.163963) (xy 380.342591 -401.128274) (xy 380.306907 -401.087088) (xy 380.277448 -401.041243)
			(xy 380.254812 -400.991673) (xy 380.239461 -400.939386) (xy 380.231706 -400.885447) (xy 378.79405 -400.885447)
			(xy 378.79405 -400.885453) (xy 378.786293 -400.939404) (xy 378.770938 -400.991701) (xy 378.748296 -401.041282)
			(xy 378.718828 -401.087135) (xy 378.683135 -401.128328) (xy 378.641943 -401.164022) (xy 378.59609 -401.193491)
			(xy 378.546511 -401.216134) (xy 378.494213 -401.231491) (xy 378.440263 -401.239249) (xy 378.41301 -401.239736)
			(xy 377.54941 -401.239736) (xy 377.522159 -401.239217) (xy 377.468211 -401.231462) (xy 377.415915 -401.216108)
			(xy 377.366338 -401.193468) (xy 377.320487 -401.164002) (xy 377.279296 -401.128311) (xy 377.243604 -401.087121)
			(xy 377.214137 -401.041271) (xy 377.191495 -400.991694) (xy 377.17614 -400.939399) (xy 377.168383 -400.885451)
			(xy 375.730873 -400.885451) (xy 375.730873 -400.885456) (xy 375.723115 -400.939414) (xy 375.707756 -400.991718)
			(xy 375.68511 -401.041304) (xy 375.655637 -401.087162) (xy 375.619937 -401.128358) (xy 375.578738 -401.164055)
			(xy 375.532877 -401.193524) (xy 375.48329 -401.216166) (xy 375.430984 -401.231521) (xy 375.377026 -401.239275)
			(xy 375.34977 -401.239736) (xy 374.48617 -401.239736) (xy 374.458922 -401.239192) (xy 374.404982 -401.231432)
			(xy 374.352694 -401.216076) (xy 374.303125 -401.193435) (xy 374.257282 -401.16397) (xy 374.216098 -401.128281)
			(xy 374.180412 -401.087094) (xy 374.150951 -401.041249) (xy 374.128314 -400.991677) (xy 374.112961 -400.939389)
			(xy 374.105206 -400.885448) (xy 372.66755 -400.885448) (xy 372.66755 -400.885452) (xy 372.659794 -400.939401)
			(xy 372.644439 -400.991697) (xy 372.621799 -401.041276) (xy 372.592333 -401.087128) (xy 372.556642 -401.128321)
			(xy 372.515452 -401.164015) (xy 372.469602 -401.193484) (xy 372.420025 -401.216129) (xy 372.36773 -401.231488)
			(xy 372.313782 -401.239248) (xy 372.28653 -401.239736) (xy 371.42293 -401.239736) (xy 371.395678 -401.239219)
			(xy 371.341728 -401.231466) (xy 371.28943 -401.216114) (xy 371.23985 -401.193474) (xy 371.193996 -401.164009)
			(xy 371.152803 -401.128318) (xy 371.117109 -401.087128) (xy 371.08764 -401.041277) (xy 371.064997 -400.991698)
			(xy 371.049641 -400.939402) (xy 371.041883 -400.885452) (xy 351.173373 -400.885452) (xy 351.173373 -400.885455)
			(xy 351.165615 -400.939411) (xy 351.150257 -400.991714) (xy 351.127612 -401.041299) (xy 351.098141 -401.087156)
			(xy 351.062443 -401.128352) (xy 351.021246 -401.164048) (xy 350.975388 -401.193518) (xy 350.925803 -401.216162)
			(xy 350.8735 -401.231518) (xy 350.819543 -401.239274) (xy 350.792288 -401.239736) (xy 349.928688 -401.239736)
			(xy 349.901439 -401.239193) (xy 349.847497 -401.231436) (xy 349.795208 -401.216081) (xy 349.745636 -401.19344)
			(xy 349.69979 -401.163976) (xy 349.658604 -401.128287) (xy 349.622917 -401.0871) (xy 349.593454 -401.041254)
			(xy 349.570815 -400.991681) (xy 349.555462 -400.939391) (xy 349.547706 -400.885449) (xy 348.11005 -400.885449)
			(xy 348.11005 -400.885451) (xy 348.102294 -400.939399) (xy 348.086941 -400.991693) (xy 348.064301 -401.041271)
			(xy 348.034837 -401.087122) (xy 347.999148 -401.128314) (xy 347.957961 -401.164009) (xy 347.912113 -401.193478)
			(xy 347.862538 -401.216124) (xy 347.810245 -401.231484) (xy 347.756299 -401.239247) (xy 347.729048 -401.239736)
			(xy 346.865448 -401.239736) (xy 346.838195 -401.23922) (xy 346.784243 -401.231469) (xy 346.731943 -401.216118)
			(xy 346.68236 -401.19348) (xy 346.636505 -401.164016) (xy 346.595309 -401.128325) (xy 346.559613 -401.087134)
			(xy 346.530143 -401.041282) (xy 346.507498 -400.991702) (xy 346.492141 -400.939404) (xy 346.484383 -400.885453)
			(xy 345.04685 -400.885453) (xy 345.039093 -400.939404) (xy 345.023737 -400.991702) (xy 345.001095 -401.041282)
			(xy 344.971628 -401.087136) (xy 344.935934 -401.128329) (xy 344.894742 -401.164023) (xy 344.848889 -401.193491)
			(xy 344.799309 -401.216135) (xy 344.747012 -401.231492) (xy 344.693061 -401.23925) (xy 344.665808 -401.239736)
			(xy 343.802208 -401.239736) (xy 343.774957 -401.239217) (xy 343.721009 -401.231462) (xy 343.668714 -401.216108)
			(xy 343.619136 -401.193467) (xy 343.573286 -401.164002) (xy 343.532095 -401.128311) (xy 343.496403 -401.087121)
			(xy 343.466937 -401.041271) (xy 343.444295 -400.991694) (xy 343.42894 -400.939399) (xy 343.421183 -400.885451)
			(xy 341.983673 -400.885451) (xy 341.983673 -400.885456) (xy 341.975915 -400.939414) (xy 341.960556 -400.991718)
			(xy 341.937909 -401.041304) (xy 341.908436 -401.087162) (xy 341.872736 -401.128359) (xy 341.831537 -401.164055)
			(xy 341.785676 -401.193525) (xy 341.736088 -401.216167) (xy 341.683783 -401.231521) (xy 341.629824 -401.239275)
			(xy 341.602568 -401.239736) (xy 340.738968 -401.239736) (xy 340.71172 -401.239192) (xy 340.65778 -401.231432)
			(xy 340.605493 -401.216075) (xy 340.555924 -401.193434) (xy 340.510081 -401.163969) (xy 340.468897 -401.12828)
			(xy 340.433212 -401.087094) (xy 340.403751 -401.041248) (xy 340.381114 -400.991677) (xy 340.365761 -400.939389)
			(xy 340.358006 -400.885448) (xy 338.92035 -400.885448) (xy 338.92035 -400.885452) (xy 338.912594 -400.939401)
			(xy 338.897239 -400.991698) (xy 338.874598 -401.041277) (xy 338.845132 -401.087129) (xy 338.809441 -401.128321)
			(xy 338.768251 -401.164016) (xy 338.722401 -401.193485) (xy 338.672824 -401.216129) (xy 338.620529 -401.231488)
			(xy 338.56658 -401.239248) (xy 338.539328 -401.239736) (xy 337.675728 -401.239736) (xy 337.648476 -401.239219)
			(xy 337.594526 -401.231465) (xy 337.542228 -401.216113) (xy 337.492648 -401.193474) (xy 337.446795 -401.164009)
			(xy 337.405602 -401.128318) (xy 337.369908 -401.087127) (xy 337.34044 -401.041276) (xy 337.317797 -400.991698)
			(xy 337.30244 -400.939402) (xy 337.294683 -400.885452) (xy 335.857173 -400.885452) (xy 335.857173 -400.885455)
			(xy 335.849415 -400.939411) (xy 335.834057 -400.991714) (xy 335.811412 -401.041299) (xy 335.781941 -401.087156)
			(xy 335.746243 -401.128352) (xy 335.705046 -401.164048) (xy 335.659188 -401.193518) (xy 335.609603 -401.216162)
			(xy 335.5573 -401.231518) (xy 335.503343 -401.239274) (xy 335.476088 -401.239736) (xy 334.612488 -401.239736)
			(xy 334.585239 -401.239193) (xy 334.531297 -401.231436) (xy 334.479008 -401.216081) (xy 334.429436 -401.19344)
			(xy 334.38359 -401.163976) (xy 334.342404 -401.128287) (xy 334.306717 -401.0871) (xy 334.277254 -401.041254)
			(xy 334.254615 -400.991681) (xy 334.239262 -400.939391) (xy 334.231506 -400.885449) (xy 332.79385 -400.885449)
			(xy 332.79385 -400.885451) (xy 332.786094 -400.939399) (xy 332.770741 -400.991693) (xy 332.748101 -401.041271)
			(xy 332.718637 -401.087122) (xy 332.682948 -401.128314) (xy 332.641761 -401.164009) (xy 332.595913 -401.193478)
			(xy 332.546338 -401.216124) (xy 332.494045 -401.231484) (xy 332.440099 -401.239247) (xy 332.412848 -401.239736)
			(xy 331.549248 -401.239736) (xy 331.521995 -401.23922) (xy 331.468043 -401.231469) (xy 331.415743 -401.216118)
			(xy 331.36616 -401.19348) (xy 331.320305 -401.164016) (xy 331.279109 -401.128325) (xy 331.243413 -401.087134)
			(xy 331.213943 -401.041282) (xy 331.191298 -400.991702) (xy 331.175941 -400.939404) (xy 331.168183 -400.885453)
			(xy 329.73065 -400.885453) (xy 329.722893 -400.939404) (xy 329.707537 -400.991702) (xy 329.684895 -401.041282)
			(xy 329.655428 -401.087136) (xy 329.619734 -401.128329) (xy 329.578542 -401.164023) (xy 329.532689 -401.193491)
			(xy 329.483109 -401.216135) (xy 329.430812 -401.231492) (xy 329.376861 -401.23925) (xy 329.349608 -401.239736)
			(xy 328.486008 -401.239736) (xy 328.458757 -401.239217) (xy 328.404809 -401.231462) (xy 328.352514 -401.216108)
			(xy 328.302936 -401.193467) (xy 328.257086 -401.164002) (xy 328.215895 -401.128311) (xy 328.180203 -401.087121)
			(xy 328.150737 -401.041271) (xy 328.128095 -400.991694) (xy 328.11274 -400.939399) (xy 328.104983 -400.885451)
			(xy 326.667473 -400.885451) (xy 326.667473 -400.885456) (xy 326.659715 -400.939414) (xy 326.644356 -400.991718)
			(xy 326.621709 -401.041304) (xy 326.592236 -401.087162) (xy 326.556536 -401.128359) (xy 326.515337 -401.164055)
			(xy 326.469476 -401.193525) (xy 326.419888 -401.216167) (xy 326.367583 -401.231521) (xy 326.313624 -401.239275)
			(xy 326.286368 -401.239736) (xy 325.422768 -401.239736) (xy 325.39552 -401.239192) (xy 325.34158 -401.231432)
			(xy 325.289293 -401.216075) (xy 325.239724 -401.193434) (xy 325.193881 -401.163969) (xy 325.152697 -401.12828)
			(xy 325.117012 -401.087094) (xy 325.087551 -401.041248) (xy 325.064914 -400.991677) (xy 325.049561 -400.939389)
			(xy 325.041806 -400.885448) (xy 323.60415 -400.885448) (xy 323.60415 -400.885452) (xy 323.596394 -400.939401)
			(xy 323.581039 -400.991698) (xy 323.558398 -401.041277) (xy 323.528932 -401.087129) (xy 323.493241 -401.128321)
			(xy 323.452051 -401.164016) (xy 323.406201 -401.193485) (xy 323.356624 -401.216129) (xy 323.304329 -401.231488)
			(xy 323.25038 -401.239248) (xy 323.223128 -401.239736) (xy 322.359528 -401.239736) (xy 322.332276 -401.239219)
			(xy 322.278326 -401.231465) (xy 322.226028 -401.216113) (xy 322.176448 -401.193474) (xy 322.130595 -401.164009)
			(xy 322.089402 -401.128318) (xy 322.053708 -401.087127) (xy 322.02424 -401.041276) (xy 322.001597 -400.991698)
			(xy 321.98624 -400.939402) (xy 321.978483 -400.885452) (xy 320.540973 -400.885452) (xy 320.540973 -400.885455)
			(xy 320.533215 -400.939411) (xy 320.517857 -400.991714) (xy 320.495212 -401.041299) (xy 320.465741 -401.087156)
			(xy 320.430043 -401.128352) (xy 320.388846 -401.164048) (xy 320.342988 -401.193518) (xy 320.293403 -401.216162)
			(xy 320.2411 -401.231518) (xy 320.187143 -401.239274) (xy 320.159888 -401.239736) (xy 319.296288 -401.239736)
			(xy 319.269039 -401.239193) (xy 319.215097 -401.231436) (xy 319.162808 -401.216081) (xy 319.113236 -401.19344)
			(xy 319.06739 -401.163976) (xy 319.026204 -401.128287) (xy 318.990517 -401.0871) (xy 318.961054 -401.041254)
			(xy 318.938415 -400.991681) (xy 318.923062 -400.939391) (xy 318.915306 -400.885449) (xy 317.47765 -400.885449)
			(xy 317.47765 -400.885451) (xy 317.469894 -400.939399) (xy 317.454541 -400.991693) (xy 317.431901 -401.041271)
			(xy 317.402437 -401.087122) (xy 317.366748 -401.128314) (xy 317.325561 -401.164009) (xy 317.279713 -401.193478)
			(xy 317.230138 -401.216124) (xy 317.177845 -401.231484) (xy 317.123899 -401.239247) (xy 317.096648 -401.239736)
			(xy 316.233048 -401.239736) (xy 316.205795 -401.23922) (xy 316.151843 -401.231469) (xy 316.099543 -401.216118)
			(xy 316.04996 -401.19348) (xy 316.004105 -401.164016) (xy 315.962909 -401.128325) (xy 315.927213 -401.087134)
			(xy 315.897743 -401.041282) (xy 315.875098 -400.991702) (xy 315.859741 -400.939404) (xy 315.851983 -400.885453)
			(xy 314.41445 -400.885453) (xy 314.406693 -400.939404) (xy 314.391337 -400.991702) (xy 314.368695 -401.041282)
			(xy 314.339228 -401.087136) (xy 314.303534 -401.128329) (xy 314.262342 -401.164023) (xy 314.216489 -401.193491)
			(xy 314.166909 -401.216135) (xy 314.114612 -401.231492) (xy 314.060661 -401.23925) (xy 314.033408 -401.239736)
			(xy 313.169808 -401.239736) (xy 313.142557 -401.239217) (xy 313.088609 -401.231462) (xy 313.036314 -401.216108)
			(xy 312.986736 -401.193467) (xy 312.940886 -401.164002) (xy 312.899695 -401.128311) (xy 312.864003 -401.087121)
			(xy 312.834537 -401.041271) (xy 312.811895 -400.991694) (xy 312.79654 -400.939399) (xy 312.788783 -400.885451)
			(xy 311.351273 -400.885451) (xy 311.351273 -400.885456) (xy 311.343515 -400.939414) (xy 311.328156 -400.991718)
			(xy 311.305509 -401.041304) (xy 311.276036 -401.087162) (xy 311.240336 -401.128359) (xy 311.199137 -401.164055)
			(xy 311.153276 -401.193525) (xy 311.103688 -401.216167) (xy 311.051383 -401.231521) (xy 310.997424 -401.239275)
			(xy 310.970168 -401.239736) (xy 310.106568 -401.239736) (xy 310.07932 -401.239192) (xy 310.02538 -401.231432)
			(xy 309.973093 -401.216075) (xy 309.923524 -401.193434) (xy 309.877681 -401.163969) (xy 309.836497 -401.12828)
			(xy 309.800812 -401.087094) (xy 309.771351 -401.041248) (xy 309.748714 -400.991677) (xy 309.733361 -400.939389)
			(xy 309.725606 -400.885448) (xy 308.28795 -400.885448) (xy 308.28795 -400.885452) (xy 308.280194 -400.939401)
			(xy 308.264839 -400.991698) (xy 308.242198 -401.041277) (xy 308.212732 -401.087129) (xy 308.177041 -401.128321)
			(xy 308.135851 -401.164016) (xy 308.090001 -401.193485) (xy 308.040424 -401.216129) (xy 307.988129 -401.231488)
			(xy 307.93418 -401.239248) (xy 307.906928 -401.239736) (xy 307.043328 -401.239736) (xy 307.016076 -401.239219)
			(xy 306.962126 -401.231465) (xy 306.909828 -401.216113) (xy 306.860248 -401.193474) (xy 306.814395 -401.164009)
			(xy 306.773202 -401.128318) (xy 306.737508 -401.087127) (xy 306.70804 -401.041276) (xy 306.685397 -400.991698)
			(xy 306.67004 -400.939402) (xy 306.662283 -400.885452) (xy 305.224773 -400.885452) (xy 305.224773 -400.885455)
			(xy 305.217015 -400.939411) (xy 305.201657 -400.991714) (xy 305.179012 -401.041299) (xy 305.149541 -401.087156)
			(xy 305.113843 -401.128352) (xy 305.072646 -401.164048) (xy 305.026788 -401.193518) (xy 304.977203 -401.216162)
			(xy 304.9249 -401.231518) (xy 304.870943 -401.239274) (xy 304.843688 -401.239736) (xy 303.980088 -401.239736)
			(xy 303.952839 -401.239193) (xy 303.898897 -401.231436) (xy 303.846608 -401.216081) (xy 303.797036 -401.19344)
			(xy 303.75119 -401.163976) (xy 303.710004 -401.128287) (xy 303.674317 -401.0871) (xy 303.644854 -401.041254)
			(xy 303.622215 -400.991681) (xy 303.606862 -400.939391) (xy 303.599106 -400.885449) (xy 281.686508 -400.885449)
			(xy 281.686508 -402.0155) (xy 287.066441 -402.0155) (xy 287.070455 -401.951698) (xy 287.082434 -401.888902)
			(xy 287.102189 -401.828103) (xy 287.129408 -401.77026) (xy 287.163662 -401.716283) (xy 287.204411 -401.667026)
			(xy 287.251013 -401.623264) (xy 287.302731 -401.585688) (xy 287.358752 -401.55489) (xy 287.418191 -401.531357)
			(xy 287.48011 -401.515458) (xy 287.543534 -401.507446) (xy 287.575498 -401.506944) (xy 287.575752 -401.506944)
			(xy 287.607498 -401.507464) (xy 287.670494 -401.515393) (xy 287.732014 -401.531096) (xy 287.791102 -401.55433)
			(xy 287.846842 -401.584733) (xy 287.898367 -401.621834) (xy 287.921954 -401.643088) (xy 287.929217 -401.649272)
			(xy 287.946967 -401.656223) (xy 287.966029 -401.656223) (xy 287.983779 -401.649272) (xy 287.991042 -401.643088)
			(xy 288.014631 -401.621832) (xy 288.06614 -401.5847) (xy 288.121874 -401.554276) (xy 288.180965 -401.531035)
			(xy 288.242492 -401.515338) (xy 288.305495 -401.507431) (xy 288.337244 -401.506944) (xy 288.337498 -401.506944)
			(xy 288.369457 -401.507521) (xy 288.432872 -401.515532) (xy 288.494783 -401.531427) (xy 288.554213 -401.554957)
			(xy 288.610226 -401.58575) (xy 288.661937 -401.623321) (xy 288.708532 -401.667076) (xy 288.749276 -401.716326)
			(xy 288.783525 -401.770295) (xy 288.810741 -401.82813) (xy 288.830493 -401.888921) (xy 288.84247 -401.951707)
			(xy 288.846484 -402.0155) (xy 289.606441 -402.0155) (xy 289.610455 -401.951698) (xy 289.622434 -401.888902)
			(xy 289.642189 -401.828103) (xy 289.669408 -401.77026) (xy 289.703662 -401.716283) (xy 289.744411 -401.667026)
			(xy 289.791013 -401.623264) (xy 289.842731 -401.585688) (xy 289.898752 -401.55489) (xy 289.958191 -401.531357)
			(xy 290.02011 -401.515458) (xy 290.083534 -401.507446) (xy 290.115498 -401.506944) (xy 290.115752 -401.506944)
			(xy 290.147498 -401.507464) (xy 290.210494 -401.515393) (xy 290.272014 -401.531096) (xy 290.331102 -401.55433)
			(xy 290.386842 -401.584733) (xy 290.438367 -401.621834) (xy 290.461954 -401.643088) (xy 290.469217 -401.649272)
			(xy 290.486967 -401.656223) (xy 290.506029 -401.656223) (xy 290.523779 -401.649272) (xy 290.531042 -401.643088)
			(xy 290.554631 -401.621832) (xy 290.60614 -401.5847) (xy 290.661874 -401.554276) (xy 290.720965 -401.531035)
			(xy 290.782492 -401.515338) (xy 290.845495 -401.507431) (xy 290.877244 -401.506944) (xy 290.877498 -401.506944)
			(xy 290.909457 -401.507521) (xy 290.972872 -401.515532) (xy 291.034783 -401.531427) (xy 291.094213 -401.554957)
			(xy 291.150226 -401.58575) (xy 291.201937 -401.623321) (xy 291.248532 -401.667076) (xy 291.289276 -401.716326)
			(xy 291.323525 -401.770295) (xy 291.350741 -401.82813) (xy 291.370493 -401.888921) (xy 291.38247 -401.951707)
			(xy 291.386484 -402.0155) (xy 292.146441 -402.0155) (xy 292.150455 -401.951698) (xy 292.162434 -401.888902)
			(xy 292.182189 -401.828103) (xy 292.209408 -401.77026) (xy 292.243662 -401.716283) (xy 292.284411 -401.667026)
			(xy 292.331013 -401.623264) (xy 292.382731 -401.585688) (xy 292.438752 -401.55489) (xy 292.498191 -401.531357)
			(xy 292.56011 -401.515458) (xy 292.623534 -401.507446) (xy 292.655498 -401.506944) (xy 292.655752 -401.506944)
			(xy 292.687498 -401.507464) (xy 292.750494 -401.515393) (xy 292.812014 -401.531096) (xy 292.871102 -401.55433)
			(xy 292.926842 -401.584733) (xy 292.978367 -401.621834) (xy 293.001954 -401.643088) (xy 293.009217 -401.649272)
			(xy 293.026967 -401.656223) (xy 293.046029 -401.656223) (xy 293.063779 -401.649272) (xy 293.071042 -401.643088)
			(xy 293.094631 -401.621832) (xy 293.14614 -401.5847) (xy 293.201874 -401.554276) (xy 293.260965 -401.531035)
			(xy 293.322492 -401.515338) (xy 293.385495 -401.507431) (xy 293.417244 -401.506944) (xy 293.417498 -401.506944)
			(xy 293.449457 -401.507521) (xy 293.512872 -401.515532) (xy 293.574783 -401.531427) (xy 293.634213 -401.554957)
			(xy 293.690226 -401.58575) (xy 293.741937 -401.623321) (xy 293.788532 -401.667076) (xy 293.829276 -401.716326)
			(xy 293.863525 -401.770295) (xy 293.890741 -401.82813) (xy 293.910493 -401.888921) (xy 293.92247 -401.951707)
			(xy 293.926484 -402.0155) (xy 294.53602 -402.0155) (xy 294.540035 -401.951693) (xy 294.552015 -401.888892)
			(xy 294.571773 -401.828089) (xy 294.598995 -401.770241) (xy 294.633253 -401.716261) (xy 294.674007 -401.667001)
			(xy 294.720613 -401.623237) (xy 294.772338 -401.58566) (xy 294.828364 -401.554862) (xy 294.887809 -401.531329)
			(xy 294.949734 -401.515433) (xy 295.013163 -401.507423) (xy 295.04513 -401.506944) (xy 295.045384 -401.506944)
			(xy 295.077131 -401.507444) (xy 295.140127 -401.515377) (xy 295.201647 -401.531084) (xy 295.260736 -401.554322)
			(xy 295.316476 -401.584728) (xy 295.368 -401.621832) (xy 295.391586 -401.643088) (xy 295.398849 -401.649272)
			(xy 295.416599 -401.656223) (xy 295.435661 -401.656223) (xy 295.453411 -401.649272) (xy 295.460674 -401.643088)
			(xy 295.48425 -401.621817) (xy 295.535761 -401.584686) (xy 295.591498 -401.554265) (xy 295.650592 -401.531026)
			(xy 295.712121 -401.515332) (xy 295.775126 -401.507429) (xy 295.806876 -401.506944) (xy 295.80713 -401.506944)
			(xy 295.839087 -401.507544) (xy 295.902496 -401.515558) (xy 295.964401 -401.531455) (xy 296.023825 -401.554986)
			(xy 296.079832 -401.585779) (xy 296.131538 -401.623348) (xy 296.178128 -401.667102) (xy 296.218866 -401.716349)
			(xy 296.253112 -401.770314) (xy 296.280324 -401.828145) (xy 296.300074 -401.888931) (xy 296.312049 -401.951712)
			(xy 296.316063 -402.0155) (xy 297.07602 -402.0155) (xy 297.080035 -401.951693) (xy 297.092015 -401.888892)
			(xy 297.111773 -401.828089) (xy 297.138995 -401.770241) (xy 297.173253 -401.716261) (xy 297.214007 -401.667001)
			(xy 297.260613 -401.623237) (xy 297.312338 -401.58566) (xy 297.368364 -401.554862) (xy 297.427809 -401.531329)
			(xy 297.489734 -401.515433) (xy 297.553163 -401.507423) (xy 297.58513 -401.506944) (xy 297.585384 -401.506944)
			(xy 297.617131 -401.507444) (xy 297.680127 -401.515377) (xy 297.741647 -401.531084) (xy 297.800736 -401.554322)
			(xy 297.856476 -401.584728) (xy 297.908 -401.621832) (xy 297.931586 -401.643088) (xy 297.938849 -401.649272)
			(xy 297.956599 -401.656223) (xy 297.975661 -401.656223) (xy 297.993411 -401.649272) (xy 298.000674 -401.643088)
			(xy 298.02425 -401.621817) (xy 298.075761 -401.584686) (xy 298.131498 -401.554265) (xy 298.190592 -401.531026)
			(xy 298.252121 -401.515332) (xy 298.315126 -401.507429) (xy 298.346876 -401.506944) (xy 298.34713 -401.506944)
			(xy 298.379087 -401.507544) (xy 298.442496 -401.515558) (xy 298.504401 -401.531455) (xy 298.563825 -401.554986)
			(xy 298.619832 -401.585779) (xy 298.671538 -401.623348) (xy 298.718128 -401.667102) (xy 298.758866 -401.716349)
			(xy 298.793112 -401.770314) (xy 298.820324 -401.828145) (xy 298.840074 -401.888931) (xy 298.852049 -401.951712)
			(xy 298.856063 -402.0155) (xy 298.852049 -402.079288) (xy 298.840074 -402.142069) (xy 298.820324 -402.202855)
			(xy 298.793112 -402.260686) (xy 298.758866 -402.314651) (xy 298.718128 -402.363898) (xy 298.671538 -402.407652)
			(xy 298.619832 -402.445221) (xy 298.563825 -402.476014) (xy 298.504401 -402.499545) (xy 298.442496 -402.515442)
			(xy 298.379087 -402.523456) (xy 298.34713 -402.52396) (xy 298.346876 -402.52396) (xy 298.315131 -402.523422)
			(xy 298.252136 -402.515497) (xy 298.190616 -402.499797) (xy 298.131527 -402.476566) (xy 298.075787 -402.446166)
			(xy 298.024261 -402.409069) (xy 298.000674 -402.387816) (xy 297.993411 -402.381632) (xy 297.975661 -402.374681)
			(xy 297.956599 -402.374681) (xy 297.938849 -402.381632) (xy 297.931586 -402.387816) (xy 297.908028 -402.409107)
			(xy 297.856512 -402.446235) (xy 297.800771 -402.476654) (xy 297.741674 -402.499889) (xy 297.680142 -402.515579)
			(xy 297.617135 -402.523478) (xy 297.585384 -402.52396) (xy 297.58513 -402.52396) (xy 297.553163 -402.523577)
			(xy 297.489734 -402.515567) (xy 297.427809 -402.499671) (xy 297.368364 -402.476138) (xy 297.312338 -402.44534)
			(xy 297.260613 -402.407763) (xy 297.214007 -402.363999) (xy 297.173253 -402.314739) (xy 297.138995 -402.260759)
			(xy 297.111773 -402.202911) (xy 297.092015 -402.142108) (xy 297.080035 -402.079307) (xy 297.07602 -402.0155)
			(xy 296.316063 -402.0155) (xy 296.312049 -402.079288) (xy 296.300074 -402.142069) (xy 296.280324 -402.202855)
			(xy 296.253112 -402.260686) (xy 296.218866 -402.314651) (xy 296.178128 -402.363898) (xy 296.131538 -402.407652)
			(xy 296.079832 -402.445221) (xy 296.023825 -402.476014) (xy 295.964401 -402.499545) (xy 295.902496 -402.515442)
			(xy 295.839087 -402.523456) (xy 295.80713 -402.52396) (xy 295.806876 -402.52396) (xy 295.775131 -402.523422)
			(xy 295.712136 -402.515497) (xy 295.650616 -402.499797) (xy 295.591527 -402.476566) (xy 295.535787 -402.446166)
			(xy 295.484261 -402.409069) (xy 295.460674 -402.387816) (xy 295.453411 -402.381632) (xy 295.435661 -402.374681)
			(xy 295.416599 -402.374681) (xy 295.398849 -402.381632) (xy 295.391586 -402.387816) (xy 295.368028 -402.409107)
			(xy 295.316512 -402.446235) (xy 295.260771 -402.476654) (xy 295.201674 -402.499889) (xy 295.140142 -402.515579)
			(xy 295.077135 -402.523478) (xy 295.045384 -402.52396) (xy 295.04513 -402.52396) (xy 295.013163 -402.523577)
			(xy 294.949734 -402.515567) (xy 294.887809 -402.499671) (xy 294.828364 -402.476138) (xy 294.772338 -402.44534)
			(xy 294.720613 -402.407763) (xy 294.674007 -402.363999) (xy 294.633253 -402.314739) (xy 294.598995 -402.260759)
			(xy 294.571773 -402.202911) (xy 294.552015 -402.142108) (xy 294.540035 -402.079307) (xy 294.53602 -402.0155)
			(xy 293.926484 -402.0155) (xy 293.92247 -402.079293) (xy 293.910493 -402.142079) (xy 293.890741 -402.20287)
			(xy 293.863525 -402.260705) (xy 293.829276 -402.314674) (xy 293.788532 -402.363924) (xy 293.741937 -402.407679)
			(xy 293.690226 -402.44525) (xy 293.634213 -402.476043) (xy 293.574783 -402.499573) (xy 293.512872 -402.515468)
			(xy 293.449457 -402.523479) (xy 293.417498 -402.52396) (xy 293.417244 -402.52396) (xy 293.385498 -402.523442)
			(xy 293.322502 -402.515512) (xy 293.260982 -402.499809) (xy 293.201894 -402.476575) (xy 293.146154 -402.446171)
			(xy 293.094629 -402.40907) (xy 293.071042 -402.387816) (xy 293.063779 -402.381632) (xy 293.046029 -402.374681)
			(xy 293.026967 -402.374681) (xy 293.009217 -402.381632) (xy 293.001954 -402.387816) (xy 292.978367 -402.409074)
			(xy 292.926858 -402.446206) (xy 292.871123 -402.47663) (xy 292.812032 -402.499871) (xy 292.750504 -402.515567)
			(xy 292.687501 -402.523474) (xy 292.655752 -402.52396) (xy 292.655498 -402.52396) (xy 292.623534 -402.523554)
			(xy 292.56011 -402.515542) (xy 292.498191 -402.499643) (xy 292.438752 -402.47611) (xy 292.382731 -402.445312)
			(xy 292.331013 -402.407736) (xy 292.284411 -402.363974) (xy 292.243662 -402.314717) (xy 292.209408 -402.26074)
			(xy 292.182189 -402.202897) (xy 292.162434 -402.142098) (xy 292.150455 -402.079302) (xy 292.146441 -402.0155)
			(xy 291.386484 -402.0155) (xy 291.38247 -402.079293) (xy 291.370493 -402.142079) (xy 291.350741 -402.20287)
			(xy 291.323525 -402.260705) (xy 291.289276 -402.314674) (xy 291.248532 -402.363924) (xy 291.201937 -402.407679)
			(xy 291.150226 -402.44525) (xy 291.094213 -402.476043) (xy 291.034783 -402.499573) (xy 290.972872 -402.515468)
			(xy 290.909457 -402.523479) (xy 290.877498 -402.52396) (xy 290.877244 -402.52396) (xy 290.845498 -402.523442)
			(xy 290.782502 -402.515512) (xy 290.720982 -402.499809) (xy 290.661894 -402.476575) (xy 290.606154 -402.446171)
			(xy 290.554629 -402.40907) (xy 290.531042 -402.387816) (xy 290.523779 -402.381632) (xy 290.506029 -402.374681)
			(xy 290.486967 -402.374681) (xy 290.469217 -402.381632) (xy 290.461954 -402.387816) (xy 290.438367 -402.409074)
			(xy 290.386858 -402.446206) (xy 290.331123 -402.47663) (xy 290.272032 -402.499871) (xy 290.210504 -402.515567)
			(xy 290.147501 -402.523474) (xy 290.115752 -402.52396) (xy 290.115498 -402.52396) (xy 290.083534 -402.523554)
			(xy 290.02011 -402.515542) (xy 289.958191 -402.499643) (xy 289.898752 -402.47611) (xy 289.842731 -402.445312)
			(xy 289.791013 -402.407736) (xy 289.744411 -402.363974) (xy 289.703662 -402.314717) (xy 289.669408 -402.26074)
			(xy 289.642189 -402.202897) (xy 289.622434 -402.142098) (xy 289.610455 -402.079302) (xy 289.606441 -402.0155)
			(xy 288.846484 -402.0155) (xy 288.84247 -402.079293) (xy 288.830493 -402.142079) (xy 288.810741 -402.20287)
			(xy 288.783525 -402.260705) (xy 288.749276 -402.314674) (xy 288.708532 -402.363924) (xy 288.661937 -402.407679)
			(xy 288.610226 -402.44525) (xy 288.554213 -402.476043) (xy 288.494783 -402.499573) (xy 288.432872 -402.515468)
			(xy 288.369457 -402.523479) (xy 288.337498 -402.52396) (xy 288.337244 -402.52396) (xy 288.305498 -402.523442)
			(xy 288.242502 -402.515512) (xy 288.180982 -402.499809) (xy 288.121894 -402.476575) (xy 288.066154 -402.446171)
			(xy 288.014629 -402.40907) (xy 287.991042 -402.387816) (xy 287.983779 -402.381632) (xy 287.966029 -402.374681)
			(xy 287.946967 -402.374681) (xy 287.929217 -402.381632) (xy 287.921954 -402.387816) (xy 287.898367 -402.409074)
			(xy 287.846858 -402.446206) (xy 287.791123 -402.47663) (xy 287.732032 -402.499871) (xy 287.670504 -402.515567)
			(xy 287.607501 -402.523474) (xy 287.575752 -402.52396) (xy 287.575498 -402.52396) (xy 287.543534 -402.523554)
			(xy 287.48011 -402.515542) (xy 287.418191 -402.499643) (xy 287.358752 -402.47611) (xy 287.302731 -402.445312)
			(xy 287.251013 -402.407736) (xy 287.204411 -402.363974) (xy 287.163662 -402.314717) (xy 287.129408 -402.26074)
			(xy 287.102189 -402.202897) (xy 287.082434 -402.142098) (xy 287.070455 -402.079302) (xy 287.066441 -402.0155)
			(xy 281.686508 -402.0155) (xy 281.686508 -402.713952) (xy 303.762156 -402.713952) (xy 303.762156 -402.028152)
			(xy 303.762575 -402.016045) (xy 303.770082 -401.993024) (xy 303.784345 -401.973455) (xy 303.803962 -401.959261)
			(xy 303.82701 -401.951833) (xy 303.839118 -401.951444) (xy 304.033682 -401.951444) (xy 304.044788 -401.951809)
			(xy 304.06608 -401.958143) (xy 304.075592 -401.96389) (xy 304.369216 -402.156422) (xy 304.378581 -402.162158)
			(xy 304.399603 -402.168485) (xy 304.421556 -402.168549) (xy 304.442614 -402.162345) (xy 304.45202 -402.156676)
			(xy 304.748184 -401.96389) (xy 304.75769 -401.958133) (xy 304.778987 -401.951813) (xy 304.790094 -401.951444)
			(xy 304.984658 -401.951444) (xy 304.996746 -401.951943) (xy 305.019746 -401.959389) (xy 305.039327 -401.973567)
			(xy 305.053579 -401.993094) (xy 305.061111 -402.016066) (xy 305.06162 -402.028152) (xy 305.06162 -402.713952)
			(xy 306.825396 -402.713952) (xy 306.825396 -402.028152) (xy 306.825776 -402.016041) (xy 306.833288 -401.993013)
			(xy 306.847559 -401.973441) (xy 306.867188 -401.959248) (xy 306.890245 -401.951828) (xy 306.902358 -401.951444)
			(xy 307.096922 -401.951444) (xy 307.108026 -401.951832) (xy 307.129318 -401.958151) (xy 307.138832 -401.96389)
			(xy 307.432456 -402.156422) (xy 307.44185 -402.162107) (xy 307.462858 -402.168445) (xy 307.484801 -402.168524)
			(xy 307.505854 -402.162337) (xy 307.51526 -402.156676) (xy 307.811424 -401.96389) (xy 307.820942 -401.958156)
			(xy 307.842229 -401.951821) (xy 307.853334 -401.951444) (xy 308.047898 -401.951444) (xy 308.059988 -401.951909)
			(xy 308.082989 -401.959366) (xy 308.102569 -401.973553) (xy 308.11682 -401.993087) (xy 308.124351 -402.016064)
			(xy 308.12486 -402.028152) (xy 308.12486 -402.713952) (xy 309.888636 -402.713952) (xy 309.888636 -402.028152)
			(xy 309.888976 -402.016037) (xy 309.896493 -401.993002) (xy 309.910773 -401.973427) (xy 309.930413 -401.959235)
			(xy 309.953481 -401.951822) (xy 309.965598 -401.951444) (xy 310.160162 -401.951444) (xy 310.171268 -401.951816)
			(xy 310.19256 -401.958146) (xy 310.202072 -401.96389) (xy 310.495696 -402.156422) (xy 310.505071 -402.162141)
			(xy 310.526088 -402.168472) (xy 310.548037 -402.168541) (xy 310.569094 -402.162342) (xy 310.5785 -402.156676)
			(xy 310.874664 -401.96389) (xy 310.884174 -401.958141) (xy 310.905468 -401.951816) (xy 310.916574 -401.951444)
			(xy 311.111138 -401.951444) (xy 311.12323 -401.951875) (xy 311.146233 -401.959343) (xy 311.165812 -401.973538)
			(xy 311.180061 -401.993079) (xy 311.187592 -402.016061) (xy 311.1881 -402.028152) (xy 311.1881 -402.713952)
			(xy 312.951876 -402.713952) (xy 312.951876 -402.028152) (xy 312.952275 -402.016043) (xy 312.959785 -401.993018)
			(xy 312.974052 -401.973448) (xy 312.993675 -401.959254) (xy 313.016728 -401.95183) (xy 313.028838 -401.951444)
			(xy 313.223402 -401.951444) (xy 313.234506 -401.951841) (xy 313.255798 -401.958154) (xy 313.265312 -401.96389)
			(xy 313.558936 -402.156422) (xy 313.568292 -402.162175) (xy 313.589318 -402.168498) (xy 313.611274 -402.168558)
			(xy 313.632334 -402.162348) (xy 313.64174 -402.156676) (xy 313.937904 -401.96389) (xy 313.947406 -401.958126)
			(xy 313.968706 -401.95181) (xy 313.979814 -401.951444) (xy 314.174378 -401.951444) (xy 314.186467 -401.951926)
			(xy 314.209467 -401.959377) (xy 314.229048 -401.97356) (xy 314.243299 -401.993091) (xy 314.250831 -402.016065)
			(xy 314.25134 -402.028152) (xy 314.25134 -402.713952) (xy 316.015116 -402.713952) (xy 316.015116 -402.028152)
			(xy 316.015476 -402.016039) (xy 316.02299 -401.993007) (xy 316.037266 -401.973434) (xy 316.0569 -401.959241)
			(xy 316.079963 -401.951825) (xy 316.092078 -401.951444) (xy 316.286642 -401.951444) (xy 316.297747 -401.951824)
			(xy 316.319039 -401.958148) (xy 316.328552 -401.96389) (xy 316.622176 -402.156422) (xy 316.63156 -402.162124)
			(xy 316.652573 -402.168458) (xy 316.674519 -402.168532) (xy 316.695574 -402.16234) (xy 316.70498 -402.156676)
			(xy 317.001144 -401.96389) (xy 317.010658 -401.958148) (xy 317.031948 -401.951819) (xy 317.043054 -401.951444)
			(xy 317.237618 -401.951444) (xy 317.249709 -401.951892) (xy 317.272711 -401.959354) (xy 317.292291 -401.973545)
			(xy 317.306541 -401.993083) (xy 317.314072 -402.016063) (xy 317.31458 -402.028152) (xy 317.31458 -402.713952)
			(xy 319.078356 -402.713952) (xy 319.078356 -402.028152) (xy 319.078775 -402.016045) (xy 319.086282 -401.993024)
			(xy 319.100545 -401.973455) (xy 319.120162 -401.959261) (xy 319.14321 -401.951833) (xy 319.155318 -401.951444)
			(xy 319.349882 -401.951444) (xy 319.360988 -401.951809) (xy 319.38228 -401.958143) (xy 319.391792 -401.96389)
			(xy 319.685416 -402.156422) (xy 319.694781 -402.162158) (xy 319.715803 -402.168485) (xy 319.737756 -402.168549)
			(xy 319.758814 -402.162345) (xy 319.76822 -402.156676) (xy 320.064384 -401.96389) (xy 320.07389 -401.958133)
			(xy 320.095187 -401.951813) (xy 320.106294 -401.951444) (xy 320.300858 -401.951444) (xy 320.312946 -401.951943)
			(xy 320.335946 -401.959389) (xy 320.355527 -401.973567) (xy 320.369779 -401.993094) (xy 320.377311 -402.016066)
			(xy 320.37782 -402.028152) (xy 320.37782 -402.713952) (xy 322.141596 -402.713952) (xy 322.141596 -402.028152)
			(xy 322.141976 -402.016041) (xy 322.149488 -401.993013) (xy 322.163759 -401.973441) (xy 322.183388 -401.959248)
			(xy 322.206445 -401.951828) (xy 322.218558 -401.951444) (xy 322.413122 -401.951444) (xy 322.424226 -401.951832)
			(xy 322.445518 -401.958151) (xy 322.455032 -401.96389) (xy 322.748656 -402.156422) (xy 322.75805 -402.162107)
			(xy 322.779058 -402.168445) (xy 322.801001 -402.168524) (xy 322.822054 -402.162337) (xy 322.83146 -402.156676)
			(xy 323.127624 -401.96389) (xy 323.137142 -401.958156) (xy 323.158429 -401.951821) (xy 323.169534 -401.951444)
			(xy 323.364098 -401.951444) (xy 323.376188 -401.951909) (xy 323.399189 -401.959366) (xy 323.418769 -401.973553)
			(xy 323.43302 -401.993087) (xy 323.440551 -402.016064) (xy 323.44106 -402.028152) (xy 323.44106 -402.713952)
			(xy 325.204836 -402.713952) (xy 325.204836 -402.028152) (xy 325.205176 -402.016037) (xy 325.212693 -401.993002)
			(xy 325.226973 -401.973427) (xy 325.246613 -401.959235) (xy 325.269681 -401.951822) (xy 325.281798 -401.951444)
			(xy 325.476362 -401.951444) (xy 325.487468 -401.951816) (xy 325.50876 -401.958146) (xy 325.518272 -401.96389)
			(xy 325.811896 -402.156422) (xy 325.821271 -402.162141) (xy 325.842288 -402.168472) (xy 325.864237 -402.168541)
			(xy 325.885294 -402.162342) (xy 325.8947 -402.156676) (xy 326.190864 -401.96389) (xy 326.200374 -401.958141)
			(xy 326.221668 -401.951816) (xy 326.232774 -401.951444) (xy 326.427338 -401.951444) (xy 326.43943 -401.951875)
			(xy 326.462433 -401.959343) (xy 326.482012 -401.973538) (xy 326.496261 -401.993079) (xy 326.503792 -402.016061)
			(xy 326.5043 -402.028152) (xy 326.5043 -402.713952) (xy 328.268076 -402.713952) (xy 328.268076 -402.028152)
			(xy 328.268475 -402.016043) (xy 328.275985 -401.993018) (xy 328.290252 -401.973448) (xy 328.309875 -401.959254)
			(xy 328.332928 -401.95183) (xy 328.345038 -401.951444) (xy 328.539602 -401.951444) (xy 328.550706 -401.951841)
			(xy 328.571998 -401.958154) (xy 328.581512 -401.96389) (xy 328.875136 -402.156422) (xy 328.884492 -402.162175)
			(xy 328.905518 -402.168498) (xy 328.927474 -402.168558) (xy 328.948534 -402.162348) (xy 328.95794 -402.156676)
			(xy 329.254104 -401.96389) (xy 329.263606 -401.958126) (xy 329.284906 -401.95181) (xy 329.296014 -401.951444)
			(xy 329.490578 -401.951444) (xy 329.502667 -401.951926) (xy 329.525667 -401.959377) (xy 329.545248 -401.97356)
			(xy 329.559499 -401.993091) (xy 329.567031 -402.016065) (xy 329.56754 -402.028152) (xy 329.56754 -402.713952)
			(xy 331.331316 -402.713952) (xy 331.331316 -402.028152) (xy 331.331676 -402.016039) (xy 331.33919 -401.993007)
			(xy 331.353466 -401.973434) (xy 331.3731 -401.959241) (xy 331.396163 -401.951825) (xy 331.408278 -401.951444)
			(xy 331.602842 -401.951444) (xy 331.613947 -401.951824) (xy 331.635239 -401.958148) (xy 331.644752 -401.96389)
			(xy 331.938376 -402.156422) (xy 331.94776 -402.162124) (xy 331.968773 -402.168458) (xy 331.990719 -402.168532)
			(xy 332.011774 -402.16234) (xy 332.02118 -402.156676) (xy 332.317344 -401.96389) (xy 332.326858 -401.958148)
			(xy 332.348148 -401.951819) (xy 332.359254 -401.951444) (xy 332.553818 -401.951444) (xy 332.565909 -401.951892)
			(xy 332.588911 -401.959354) (xy 332.608491 -401.973545) (xy 332.622741 -401.993083) (xy 332.630272 -402.016063)
			(xy 332.63078 -402.028152) (xy 332.63078 -402.713952) (xy 334.394556 -402.713952) (xy 334.394556 -402.028152)
			(xy 334.394975 -402.016045) (xy 334.402482 -401.993024) (xy 334.416745 -401.973455) (xy 334.436362 -401.959261)
			(xy 334.45941 -401.951833) (xy 334.471518 -401.951444) (xy 334.666082 -401.951444) (xy 334.677188 -401.951809)
			(xy 334.69848 -401.958143) (xy 334.707992 -401.96389) (xy 335.001616 -402.156422) (xy 335.010981 -402.162158)
			(xy 335.032003 -402.168485) (xy 335.053956 -402.168549) (xy 335.075014 -402.162345) (xy 335.08442 -402.156676)
			(xy 335.380584 -401.96389) (xy 335.39009 -401.958133) (xy 335.411387 -401.951813) (xy 335.422494 -401.951444)
			(xy 335.617058 -401.951444) (xy 335.629146 -401.951943) (xy 335.652146 -401.959389) (xy 335.671727 -401.973567)
			(xy 335.685979 -401.993094) (xy 335.693511 -402.016066) (xy 335.69402 -402.028152) (xy 335.69402 -402.713952)
			(xy 337.457796 -402.713952) (xy 337.457796 -402.028152) (xy 337.458176 -402.016041) (xy 337.465688 -401.993013)
			(xy 337.479959 -401.973441) (xy 337.499588 -401.959248) (xy 337.522645 -401.951828) (xy 337.534758 -401.951444)
			(xy 337.729322 -401.951444) (xy 337.740426 -401.951832) (xy 337.761718 -401.958151) (xy 337.771232 -401.96389)
			(xy 338.064856 -402.156422) (xy 338.07425 -402.162107) (xy 338.095258 -402.168445) (xy 338.117201 -402.168524)
			(xy 338.138254 -402.162337) (xy 338.14766 -402.156676) (xy 338.443824 -401.96389) (xy 338.453342 -401.958156)
			(xy 338.474629 -401.951821) (xy 338.485734 -401.951444) (xy 338.680298 -401.951444) (xy 338.692388 -401.951909)
			(xy 338.715389 -401.959366) (xy 338.734969 -401.973553) (xy 338.74922 -401.993087) (xy 338.756751 -402.016064)
			(xy 338.75726 -402.028152) (xy 338.75726 -402.713952) (xy 340.521036 -402.713952) (xy 340.521036 -402.028152)
			(xy 340.521376 -402.016037) (xy 340.528893 -401.993002) (xy 340.543173 -401.973427) (xy 340.562813 -401.959235)
			(xy 340.585881 -401.951822) (xy 340.597998 -401.951444) (xy 340.792562 -401.951444) (xy 340.803668 -401.951816)
			(xy 340.82496 -401.958146) (xy 340.834472 -401.96389) (xy 341.128096 -402.156422) (xy 341.137471 -402.162141)
			(xy 341.158488 -402.168472) (xy 341.180437 -402.168541) (xy 341.201494 -402.162342) (xy 341.2109 -402.156676)
			(xy 341.507064 -401.96389) (xy 341.516574 -401.958141) (xy 341.537868 -401.951816) (xy 341.548974 -401.951444)
			(xy 341.743538 -401.951444) (xy 341.75563 -401.951875) (xy 341.778633 -401.959343) (xy 341.798212 -401.973538)
			(xy 341.812461 -401.993079) (xy 341.819992 -402.016061) (xy 341.8205 -402.028152) (xy 341.8205 -402.713952)
			(xy 343.584276 -402.713952) (xy 343.584276 -402.028152) (xy 343.584675 -402.016043) (xy 343.592185 -401.993018)
			(xy 343.606452 -401.973448) (xy 343.626075 -401.959254) (xy 343.649128 -401.95183) (xy 343.661238 -401.951444)
			(xy 343.855802 -401.951444) (xy 343.866906 -401.951841) (xy 343.888198 -401.958154) (xy 343.897712 -401.96389)
			(xy 344.191336 -402.156422) (xy 344.200692 -402.162175) (xy 344.221718 -402.168498) (xy 344.243674 -402.168558)
			(xy 344.264734 -402.162348) (xy 344.27414 -402.156676) (xy 344.570304 -401.96389) (xy 344.579806 -401.958126)
			(xy 344.601106 -401.95181) (xy 344.612214 -401.951444) (xy 344.806778 -401.951444) (xy 344.818867 -401.951926)
			(xy 344.841867 -401.959377) (xy 344.861448 -401.97356) (xy 344.875699 -401.993091) (xy 344.883231 -402.016065)
			(xy 344.88374 -402.028152) (xy 344.88374 -402.713952) (xy 346.647516 -402.713952) (xy 346.647516 -402.028152)
			(xy 346.647876 -402.016039) (xy 346.65539 -401.993007) (xy 346.669666 -401.973434) (xy 346.6893 -401.959241)
			(xy 346.712363 -401.951825) (xy 346.724478 -401.951444) (xy 346.919042 -401.951444) (xy 346.930147 -401.951824)
			(xy 346.951439 -401.958148) (xy 346.960952 -401.96389) (xy 347.254576 -402.156422) (xy 347.26396 -402.162124)
			(xy 347.284973 -402.168458) (xy 347.306919 -402.168532) (xy 347.327974 -402.16234) (xy 347.33738 -402.156676)
			(xy 347.633544 -401.96389) (xy 347.643058 -401.958148) (xy 347.664348 -401.951819) (xy 347.675454 -401.951444)
			(xy 347.870018 -401.951444) (xy 347.882109 -401.951892) (xy 347.905111 -401.959354) (xy 347.924691 -401.973545)
			(xy 347.938941 -401.993083) (xy 347.946472 -402.016063) (xy 347.94698 -402.028152) (xy 347.94698 -402.713952)
			(xy 349.710756 -402.713952) (xy 349.710756 -402.028152) (xy 349.711175 -402.016045) (xy 349.718682 -401.993024)
			(xy 349.732945 -401.973455) (xy 349.752562 -401.959261) (xy 349.77561 -401.951833) (xy 349.787718 -401.951444)
			(xy 349.982282 -401.951444) (xy 349.993388 -401.951809) (xy 350.01468 -401.958143) (xy 350.024192 -401.96389)
			(xy 350.317816 -402.156422) (xy 350.327181 -402.162158) (xy 350.348203 -402.168485) (xy 350.370156 -402.168549)
			(xy 350.391214 -402.162345) (xy 350.40062 -402.156676) (xy 350.696784 -401.96389) (xy 350.70629 -401.958133)
			(xy 350.727587 -401.951813) (xy 350.738694 -401.951444) (xy 350.933258 -401.951444) (xy 350.945346 -401.951943)
			(xy 350.968346 -401.959389) (xy 350.987927 -401.973567) (xy 351.002179 -401.993094) (xy 351.009711 -402.016066)
			(xy 351.01022 -402.028152) (xy 351.01022 -402.713952) (xy 371.205252 -402.713952) (xy 371.205252 -402.028152)
			(xy 371.205723 -402.016079) (xy 371.213193 -401.993117) (xy 371.22739 -401.973584) (xy 371.246924 -401.95939)
			(xy 371.269887 -401.951921) (xy 371.28196 -401.951444) (xy 371.476524 -401.951444) (xy 371.487628 -401.951832)
			(xy 371.50892 -401.95815) (xy 371.518434 -401.96389) (xy 371.812058 -402.156422) (xy 371.821451 -402.162108)
			(xy 371.842459 -402.168446) (xy 371.864403 -402.168525) (xy 371.885456 -402.162337) (xy 371.894862 -402.156676)
			(xy 372.191026 -401.96389) (xy 372.200544 -401.958155) (xy 372.221831 -401.951821) (xy 372.232936 -401.951444)
			(xy 372.4275 -401.951444) (xy 372.43957 -401.951964) (xy 372.462529 -401.95942) (xy 372.482062 -401.973604)
			(xy 372.496258 -401.993128) (xy 372.503729 -402.016083) (xy 372.504208 -402.028152) (xy 372.504208 -402.713952)
			(xy 374.268492 -402.713952) (xy 374.268492 -402.028152) (xy 374.268923 -402.016075) (xy 374.276399 -401.993106)
			(xy 374.290604 -401.97357) (xy 374.310149 -401.959377) (xy 374.333123 -401.951916) (xy 374.3452 -401.951444)
			(xy 374.539764 -401.951444) (xy 374.55087 -401.951816) (xy 374.572162 -401.958145) (xy 374.581674 -401.96389)
			(xy 374.875298 -402.156422) (xy 374.884672 -402.162142) (xy 374.905689 -402.168473) (xy 374.927639 -402.168542)
			(xy 374.948696 -402.162343) (xy 374.958102 -402.156676) (xy 375.254266 -401.96389) (xy 375.263776 -401.95814)
			(xy 375.285069 -401.951816) (xy 375.296176 -401.951444) (xy 375.49074 -401.951444) (xy 375.502812 -401.951929)
			(xy 375.525772 -401.959397) (xy 375.545305 -401.97359) (xy 375.559499 -401.993121) (xy 375.56697 -402.01608)
			(xy 375.567448 -402.028152) (xy 375.567448 -402.713952) (xy 377.331732 -402.713952) (xy 377.331732 -402.028152)
			(xy 377.332124 -402.016071) (xy 377.339604 -401.993095) (xy 377.353818 -401.973556) (xy 377.373374 -401.959364)
			(xy 377.396358 -401.95191) (xy 377.40844 -401.951444) (xy 377.603004 -401.951444) (xy 377.614108 -401.95184)
			(xy 377.6354 -401.958153) (xy 377.644914 -401.96389) (xy 377.938538 -402.156422) (xy 377.947893 -402.162176)
			(xy 377.968919 -402.168499) (xy 377.990876 -402.168558) (xy 378.011936 -402.162348) (xy 378.021342 -402.156676)
			(xy 378.317506 -401.96389) (xy 378.327008 -401.958125) (xy 378.348308 -401.95181) (xy 378.359416 -401.951444)
			(xy 378.55398 -401.951444) (xy 378.566049 -401.95198) (xy 378.589007 -401.959432) (xy 378.60854 -401.973611)
			(xy 378.622737 -401.993132) (xy 378.630209 -402.016084) (xy 378.630688 -402.028152) (xy 378.630688 -402.713952)
			(xy 380.394972 -402.713952) (xy 380.394972 -402.028152) (xy 380.395423 -402.016077) (xy 380.402896 -401.993112)
			(xy 380.417097 -401.973577) (xy 380.436637 -401.959383) (xy 380.459605 -401.951918) (xy 380.47168 -401.951444)
			(xy 380.666244 -401.951444) (xy 380.677349 -401.951824) (xy 380.698641 -401.958148) (xy 380.708154 -401.96389)
			(xy 381.001778 -402.156422) (xy 381.011161 -402.162125) (xy 381.032174 -402.16846) (xy 381.054121 -402.168533)
			(xy 381.075176 -402.16234) (xy 381.084582 -402.156676) (xy 381.380746 -401.96389) (xy 381.39026 -401.958148)
			(xy 381.41155 -401.951818) (xy 381.422656 -401.951444) (xy 381.61722 -401.951444) (xy 381.629291 -401.951947)
			(xy 381.65225 -401.959409) (xy 381.671783 -401.973597) (xy 381.685978 -401.993124) (xy 381.693449 -402.016081)
			(xy 381.693928 -402.028152) (xy 381.693928 -402.713952) (xy 383.458212 -402.713952) (xy 383.458212 -402.028152)
			(xy 383.458624 -402.016073) (xy 383.466102 -401.993101) (xy 383.480311 -401.973563) (xy 383.499862 -401.959371)
			(xy 383.522841 -401.951913) (xy 383.53492 -401.951444) (xy 383.729484 -401.951444) (xy 383.74059 -401.951808)
			(xy 383.761882 -401.958143) (xy 383.771394 -401.96389) (xy 384.065018 -402.156422) (xy 384.074383 -402.162159)
			(xy 384.095404 -402.168486) (xy 384.117357 -402.16855) (xy 384.138416 -402.162346) (xy 384.147822 -402.156676)
			(xy 384.443986 -401.96389) (xy 384.453492 -401.958133) (xy 384.474789 -401.951813) (xy 384.485896 -401.951444)
			(xy 384.68046 -401.951444) (xy 384.692528 -401.951997) (xy 384.715486 -401.959443) (xy 384.735019 -401.973618)
			(xy 384.749217 -401.993136) (xy 384.756689 -402.016085) (xy 384.757168 -402.028152) (xy 384.757168 -402.713952)
			(xy 386.521452 -402.713952) (xy 386.521452 -402.028152) (xy 386.521923 -402.016079) (xy 386.529393 -401.993117)
			(xy 386.54359 -401.973584) (xy 386.563124 -401.95939) (xy 386.586087 -401.951921) (xy 386.59816 -401.951444)
			(xy 386.792724 -401.951444) (xy 386.803828 -401.951832) (xy 386.82512 -401.95815) (xy 386.834634 -401.96389)
			(xy 387.128258 -402.156422) (xy 387.137651 -402.162108) (xy 387.158659 -402.168446) (xy 387.180603 -402.168525)
			(xy 387.201656 -402.162337) (xy 387.211062 -402.156676) (xy 387.507226 -401.96389) (xy 387.516744 -401.958155)
			(xy 387.538031 -401.951821) (xy 387.549136 -401.951444) (xy 387.7437 -401.951444) (xy 387.75577 -401.951964)
			(xy 387.778729 -401.95942) (xy 387.798262 -401.973604) (xy 387.812458 -401.993128) (xy 387.819929 -402.016083)
			(xy 387.820408 -402.028152) (xy 387.820408 -402.713952) (xy 389.584692 -402.713952) (xy 389.584692 -402.028152)
			(xy 389.585123 -402.016075) (xy 389.592599 -401.993106) (xy 389.606804 -401.97357) (xy 389.626349 -401.959377)
			(xy 389.649323 -401.951916) (xy 389.6614 -401.951444) (xy 389.855964 -401.951444) (xy 389.86707 -401.951816)
			(xy 389.888362 -401.958145) (xy 389.897874 -401.96389) (xy 390.191498 -402.156422) (xy 390.200872 -402.162142)
			(xy 390.221889 -402.168473) (xy 390.243839 -402.168542) (xy 390.264896 -402.162343) (xy 390.274302 -402.156676)
			(xy 390.570466 -401.96389) (xy 390.579976 -401.95814) (xy 390.601269 -401.951816) (xy 390.612376 -401.951444)
			(xy 390.80694 -401.951444) (xy 390.819012 -401.951929) (xy 390.841972 -401.959397) (xy 390.861505 -401.97359)
			(xy 390.875699 -401.993121) (xy 390.88317 -402.01608) (xy 390.883648 -402.028152) (xy 390.883648 -402.713952)
			(xy 392.647932 -402.713952) (xy 392.647932 -402.028152) (xy 392.648324 -402.016071) (xy 392.655804 -401.993095)
			(xy 392.670018 -401.973556) (xy 392.689574 -401.959364) (xy 392.712558 -401.95191) (xy 392.72464 -401.951444)
			(xy 392.919204 -401.951444) (xy 392.930308 -401.95184) (xy 392.9516 -401.958153) (xy 392.961114 -401.96389)
			(xy 393.254738 -402.156422) (xy 393.264093 -402.162176) (xy 393.285119 -402.168499) (xy 393.307076 -402.168558)
			(xy 393.328136 -402.162348) (xy 393.337542 -402.156676) (xy 393.633706 -401.96389) (xy 393.643208 -401.958125)
			(xy 393.664508 -401.95181) (xy 393.675616 -401.951444) (xy 393.87018 -401.951444) (xy 393.882249 -401.95198)
			(xy 393.905207 -401.959432) (xy 393.92474 -401.973611) (xy 393.938937 -401.993132) (xy 393.946409 -402.016084)
			(xy 393.946888 -402.028152) (xy 393.946888 -402.713952) (xy 395.711172 -402.713952) (xy 395.711172 -402.028152)
			(xy 395.711623 -402.016077) (xy 395.719096 -401.993112) (xy 395.733297 -401.973577) (xy 395.752837 -401.959383)
			(xy 395.775805 -401.951918) (xy 395.78788 -401.951444) (xy 395.982444 -401.951444) (xy 395.993549 -401.951824)
			(xy 396.014841 -401.958148) (xy 396.024354 -401.96389) (xy 396.317978 -402.156422) (xy 396.327361 -402.162125)
			(xy 396.348374 -402.16846) (xy 396.370321 -402.168533) (xy 396.391376 -402.16234) (xy 396.400782 -402.156676)
			(xy 396.696946 -401.96389) (xy 396.70646 -401.958148) (xy 396.72775 -401.951818) (xy 396.738856 -401.951444)
			(xy 396.93342 -401.951444) (xy 396.945491 -401.951947) (xy 396.96845 -401.959409) (xy 396.987983 -401.973597)
			(xy 397.002178 -401.993124) (xy 397.009649 -402.016081) (xy 397.010128 -402.028152) (xy 397.010128 -402.713952)
			(xy 398.774412 -402.713952) (xy 398.774412 -402.028152) (xy 398.774824 -402.016073) (xy 398.782302 -401.993101)
			(xy 398.796511 -401.973563) (xy 398.816062 -401.959371) (xy 398.839041 -401.951913) (xy 398.85112 -401.951444)
			(xy 399.045684 -401.951444) (xy 399.05679 -401.951808) (xy 399.078082 -401.958143) (xy 399.087594 -401.96389)
			(xy 399.381218 -402.156422) (xy 399.390583 -402.162159) (xy 399.411604 -402.168486) (xy 399.433557 -402.16855)
			(xy 399.454616 -402.162346) (xy 399.464022 -402.156676) (xy 399.760186 -401.96389) (xy 399.769692 -401.958133)
			(xy 399.790989 -401.951813) (xy 399.802096 -401.951444) (xy 399.99666 -401.951444) (xy 400.008728 -401.951997)
			(xy 400.031686 -401.959443) (xy 400.051219 -401.973618) (xy 400.065417 -401.993136) (xy 400.072889 -402.016085)
			(xy 400.073368 -402.028152) (xy 400.073368 -402.713952) (xy 401.837652 -402.713952) (xy 401.837652 -402.028152)
			(xy 401.838123 -402.016079) (xy 401.845593 -401.993117) (xy 401.85979 -401.973584) (xy 401.879324 -401.95939)
			(xy 401.902287 -401.951921) (xy 401.91436 -401.951444) (xy 402.108924 -401.951444) (xy 402.120028 -401.951832)
			(xy 402.14132 -401.95815) (xy 402.150834 -401.96389) (xy 402.444458 -402.156422) (xy 402.453851 -402.162108)
			(xy 402.474859 -402.168446) (xy 402.496803 -402.168525) (xy 402.517856 -402.162337) (xy 402.527262 -402.156676)
			(xy 402.823426 -401.96389) (xy 402.832944 -401.958155) (xy 402.854231 -401.951821) (xy 402.865336 -401.951444)
			(xy 403.0599 -401.951444) (xy 403.07197 -401.951964) (xy 403.094929 -401.95942) (xy 403.114462 -401.973604)
			(xy 403.128658 -401.993128) (xy 403.136129 -402.016083) (xy 403.136608 -402.028152) (xy 403.136608 -402.713952)
			(xy 404.900892 -402.713952) (xy 404.900892 -402.028152) (xy 404.901323 -402.016075) (xy 404.908799 -401.993106)
			(xy 404.923004 -401.97357) (xy 404.942549 -401.959377) (xy 404.965523 -401.951916) (xy 404.9776 -401.951444)
			(xy 405.172164 -401.951444) (xy 405.18327 -401.951816) (xy 405.204562 -401.958145) (xy 405.214074 -401.96389)
			(xy 405.507698 -402.156422) (xy 405.517072 -402.162142) (xy 405.538089 -402.168473) (xy 405.560039 -402.168542)
			(xy 405.581096 -402.162343) (xy 405.590502 -402.156676) (xy 405.886666 -401.96389) (xy 405.896176 -401.95814)
			(xy 405.917469 -401.951816) (xy 405.928576 -401.951444) (xy 406.12314 -401.951444) (xy 406.135212 -401.951929)
			(xy 406.158172 -401.959397) (xy 406.177705 -401.97359) (xy 406.191899 -401.993121) (xy 406.19937 -402.01608)
			(xy 406.199848 -402.028152) (xy 406.199848 -402.713952) (xy 407.964132 -402.713952) (xy 407.964132 -402.028152)
			(xy 407.964524 -402.016071) (xy 407.972004 -401.993095) (xy 407.986218 -401.973556) (xy 408.005774 -401.959364)
			(xy 408.028758 -401.95191) (xy 408.04084 -401.951444) (xy 408.235404 -401.951444) (xy 408.246508 -401.95184)
			(xy 408.2678 -401.958153) (xy 408.277314 -401.96389) (xy 408.570938 -402.156422) (xy 408.580293 -402.162176)
			(xy 408.601319 -402.168499) (xy 408.623276 -402.168558) (xy 408.644336 -402.162348) (xy 408.653742 -402.156676)
			(xy 408.949906 -401.96389) (xy 408.959408 -401.958125) (xy 408.980708 -401.95181) (xy 408.991816 -401.951444)
			(xy 409.18638 -401.951444) (xy 409.198449 -401.95198) (xy 409.221407 -401.959432) (xy 409.24094 -401.973611)
			(xy 409.255137 -401.993132) (xy 409.262609 -402.016084) (xy 409.263088 -402.028152) (xy 409.263088 -402.713952)
			(xy 411.027372 -402.713952) (xy 411.027372 -402.028152) (xy 411.027823 -402.016077) (xy 411.035296 -401.993112)
			(xy 411.049497 -401.973577) (xy 411.069037 -401.959383) (xy 411.092005 -401.951918) (xy 411.10408 -401.951444)
			(xy 411.298644 -401.951444) (xy 411.309749 -401.951824) (xy 411.331041 -401.958148) (xy 411.340554 -401.96389)
			(xy 411.634178 -402.156422) (xy 411.643561 -402.162125) (xy 411.664574 -402.16846) (xy 411.686521 -402.168533)
			(xy 411.707576 -402.16234) (xy 411.716982 -402.156676) (xy 412.013146 -401.96389) (xy 412.02266 -401.958148)
			(xy 412.04395 -401.951818) (xy 412.055056 -401.951444) (xy 412.24962 -401.951444) (xy 412.261691 -401.951947)
			(xy 412.28465 -401.959409) (xy 412.304183 -401.973597) (xy 412.318378 -401.993124) (xy 412.325849 -402.016081)
			(xy 412.326328 -402.028152) (xy 412.326328 -402.713952) (xy 414.090612 -402.713952) (xy 414.090612 -402.028152)
			(xy 414.091024 -402.016073) (xy 414.098502 -401.993101) (xy 414.112711 -401.973563) (xy 414.132262 -401.959371)
			(xy 414.155241 -401.951913) (xy 414.16732 -401.951444) (xy 414.361884 -401.951444) (xy 414.37299 -401.951808)
			(xy 414.394282 -401.958143) (xy 414.403794 -401.96389) (xy 414.697418 -402.156422) (xy 414.706783 -402.162159)
			(xy 414.727804 -402.168486) (xy 414.749757 -402.16855) (xy 414.770816 -402.162346) (xy 414.780222 -402.156676)
			(xy 415.076386 -401.96389) (xy 415.085892 -401.958133) (xy 415.107189 -401.951813) (xy 415.118296 -401.951444)
			(xy 415.31286 -401.951444) (xy 415.324928 -401.951997) (xy 415.347886 -401.959443) (xy 415.367419 -401.973618)
			(xy 415.381617 -401.993136) (xy 415.389089 -402.016085) (xy 415.389568 -402.028152) (xy 415.389568 -402.713952)
			(xy 417.153852 -402.713952) (xy 417.153852 -402.028152) (xy 417.154323 -402.016079) (xy 417.161793 -401.993117)
			(xy 417.17599 -401.973584) (xy 417.195524 -401.95939) (xy 417.218487 -401.951921) (xy 417.23056 -401.951444)
			(xy 417.425124 -401.951444) (xy 417.436228 -401.951832) (xy 417.45752 -401.95815) (xy 417.467034 -401.96389)
			(xy 417.760658 -402.156422) (xy 417.770051 -402.162108) (xy 417.791059 -402.168446) (xy 417.813003 -402.168525)
			(xy 417.834056 -402.162337) (xy 417.843462 -402.156676) (xy 418.139626 -401.96389) (xy 418.149144 -401.958155)
			(xy 418.170431 -401.951821) (xy 418.181536 -401.951444) (xy 418.3761 -401.951444) (xy 418.38817 -401.951964)
			(xy 418.411129 -401.95942) (xy 418.430662 -401.973604) (xy 418.444858 -401.993128) (xy 418.452329 -402.016083)
			(xy 418.452808 -402.028152) (xy 418.452808 -402.713952) (xy 418.452346 -402.726032) (xy 418.444892 -402.749013)
			(xy 418.430699 -402.768564) (xy 418.411156 -402.78277) (xy 418.38818 -402.790239) (xy 418.3761 -402.79066)
			(xy 418.181536 -402.79066) (xy 418.170427 -402.790309) (xy 418.149131 -402.783976) (xy 418.139626 -402.778214)
			(xy 417.844732 -402.585682) (xy 417.835345 -402.579979) (xy 417.814307 -402.573706) (xy 417.792353 -402.573706)
			(xy 417.771315 -402.579979) (xy 417.761928 -402.585682) (xy 417.468304 -402.778214) (xy 417.4588 -402.783975)
			(xy 417.437502 -402.790293) (xy 417.426394 -402.79066) (xy 417.23056 -402.79066) (xy 417.21847 -402.790321)
			(xy 417.195478 -402.782836) (xy 417.175925 -402.768613) (xy 417.161723 -402.749043) (xy 417.154265 -402.726042)
			(xy 417.153852 -402.713952) (xy 415.389568 -402.713952) (xy 415.389146 -402.726036) (xy 415.381687 -402.749024)
			(xy 415.367484 -402.768579) (xy 415.347931 -402.782783) (xy 415.324944 -402.790245) (xy 415.31286 -402.79066)
			(xy 415.118296 -402.79066) (xy 415.107189 -402.790285) (xy 415.085893 -402.783969) (xy 415.076386 -402.778214)
			(xy 414.781492 -402.585682) (xy 414.772105 -402.579979) (xy 414.751067 -402.573706) (xy 414.729113 -402.573706)
			(xy 414.708075 -402.579979) (xy 414.698688 -402.585682) (xy 414.405064 -402.778214) (xy 414.395549 -402.783953)
			(xy 414.374259 -402.790284) (xy 414.363154 -402.79066) (xy 414.16732 -402.79066) (xy 414.155234 -402.790269)
			(xy 414.132243 -402.782802) (xy 414.112689 -402.768591) (xy 414.098486 -402.749031) (xy 414.091026 -402.726039)
			(xy 414.090612 -402.713952) (xy 412.326328 -402.713952) (xy 412.325847 -402.72603) (xy 412.318395 -402.749008)
			(xy 412.304206 -402.768557) (xy 412.284669 -402.782764) (xy 412.261698 -402.790236) (xy 412.24962 -402.79066)
			(xy 412.055056 -402.79066) (xy 412.043948 -402.790301) (xy 412.022651 -402.783974) (xy 412.013146 -402.778214)
			(xy 411.718252 -402.585682) (xy 411.708865 -402.579979) (xy 411.687827 -402.573706) (xy 411.665873 -402.573706)
			(xy 411.644835 -402.579979) (xy 411.635448 -402.585682) (xy 411.341824 -402.778214) (xy 411.332317 -402.783968)
			(xy 411.311021 -402.79029) (xy 411.299914 -402.79066) (xy 411.10408 -402.79066) (xy 411.091991 -402.790304)
			(xy 411.069 -402.782825) (xy 411.049446 -402.768606) (xy 411.035244 -402.749039) (xy 411.027786 -402.726041)
			(xy 411.027372 -402.713952) (xy 409.263088 -402.713952) (xy 409.262646 -402.726034) (xy 409.255189 -402.749019)
			(xy 409.240992 -402.768572) (xy 409.221444 -402.782777) (xy 409.198462 -402.790242) (xy 409.18638 -402.79066)
			(xy 408.991816 -402.79066) (xy 408.980706 -402.790317) (xy 408.95941 -402.783979) (xy 408.949906 -402.778214)
			(xy 408.655012 -402.585682) (xy 408.645625 -402.579979) (xy 408.624587 -402.573706) (xy 408.602633 -402.573706)
			(xy 408.581595 -402.579979) (xy 408.572208 -402.585682) (xy 408.278584 -402.778214) (xy 408.269084 -402.783983)
			(xy 408.247783 -402.790295) (xy 408.236674 -402.79066) (xy 408.04084 -402.79066) (xy 408.028755 -402.790252)
			(xy 408.005765 -402.78279) (xy 407.98621 -402.768584) (xy 407.972006 -402.749028) (xy 407.964546 -402.726037)
			(xy 407.964132 -402.713952) (xy 406.199848 -402.713952) (xy 406.199347 -402.726028) (xy 406.191898 -402.749003)
			(xy 406.177713 -402.76855) (xy 406.158182 -402.782757) (xy 406.135216 -402.790233) (xy 406.12314 -402.79066)
			(xy 405.928576 -402.79066) (xy 405.917468 -402.790293) (xy 405.896172 -402.783971) (xy 405.886666 -402.778214)
			(xy 405.591772 -402.585682) (xy 405.582385 -402.579979) (xy 405.561347 -402.573706) (xy 405.539393 -402.573706)
			(xy 405.518355 -402.579979) (xy 405.508968 -402.585682) (xy 405.215344 -402.778214) (xy 405.205833 -402.78396)
			(xy 405.18454 -402.790287) (xy 405.173434 -402.79066) (xy 404.9776 -402.79066) (xy 404.965512 -402.790287)
			(xy 404.942522 -402.782813) (xy 404.922967 -402.768599) (xy 404.908765 -402.749035) (xy 404.901306 -402.72604)
			(xy 404.900892 -402.713952) (xy 403.136608 -402.713952) (xy 403.136146 -402.726032) (xy 403.128692 -402.749013)
			(xy 403.114499 -402.768564) (xy 403.094956 -402.78277) (xy 403.07198 -402.790239) (xy 403.0599 -402.79066)
			(xy 402.865336 -402.79066) (xy 402.854227 -402.790309) (xy 402.832931 -402.783976) (xy 402.823426 -402.778214)
			(xy 402.528532 -402.585682) (xy 402.519145 -402.579979) (xy 402.498107 -402.573706) (xy 402.476153 -402.573706)
			(xy 402.455115 -402.579979) (xy 402.445728 -402.585682) (xy 402.152104 -402.778214) (xy 402.1426 -402.783975)
			(xy 402.121302 -402.790293) (xy 402.110194 -402.79066) (xy 401.91436 -402.79066) (xy 401.90227 -402.790321)
			(xy 401.879278 -402.782836) (xy 401.859725 -402.768613) (xy 401.845523 -402.749043) (xy 401.838065 -402.726042)
			(xy 401.837652 -402.713952) (xy 400.073368 -402.713952) (xy 400.072946 -402.726036) (xy 400.065487 -402.749024)
			(xy 400.051284 -402.768579) (xy 400.031731 -402.782783) (xy 400.008744 -402.790245) (xy 399.99666 -402.79066)
			(xy 399.802096 -402.79066) (xy 399.790989 -402.790285) (xy 399.769693 -402.783969) (xy 399.760186 -402.778214)
			(xy 399.465292 -402.585682) (xy 399.455905 -402.579979) (xy 399.434867 -402.573706) (xy 399.412913 -402.573706)
			(xy 399.391875 -402.579979) (xy 399.382488 -402.585682) (xy 399.088864 -402.778214) (xy 399.079349 -402.783953)
			(xy 399.058059 -402.790284) (xy 399.046954 -402.79066) (xy 398.85112 -402.79066) (xy 398.839034 -402.790269)
			(xy 398.816043 -402.782802) (xy 398.796489 -402.768591) (xy 398.782286 -402.749031) (xy 398.774826 -402.726039)
			(xy 398.774412 -402.713952) (xy 397.010128 -402.713952) (xy 397.009647 -402.72603) (xy 397.002195 -402.749008)
			(xy 396.988006 -402.768557) (xy 396.968469 -402.782764) (xy 396.945498 -402.790236) (xy 396.93342 -402.79066)
			(xy 396.738856 -402.79066) (xy 396.727748 -402.790301) (xy 396.706451 -402.783974) (xy 396.696946 -402.778214)
			(xy 396.402052 -402.585682) (xy 396.392665 -402.579979) (xy 396.371627 -402.573706) (xy 396.349673 -402.573706)
			(xy 396.328635 -402.579979) (xy 396.319248 -402.585682) (xy 396.025624 -402.778214) (xy 396.016117 -402.783968)
			(xy 395.994821 -402.79029) (xy 395.983714 -402.79066) (xy 395.78788 -402.79066) (xy 395.775791 -402.790304)
			(xy 395.7528 -402.782825) (xy 395.733246 -402.768606) (xy 395.719044 -402.749039) (xy 395.711586 -402.726041)
			(xy 395.711172 -402.713952) (xy 393.946888 -402.713952) (xy 393.946446 -402.726034) (xy 393.938989 -402.749019)
			(xy 393.924792 -402.768572) (xy 393.905244 -402.782777) (xy 393.882262 -402.790242) (xy 393.87018 -402.79066)
			(xy 393.675616 -402.79066) (xy 393.664506 -402.790317) (xy 393.64321 -402.783979) (xy 393.633706 -402.778214)
			(xy 393.338812 -402.585682) (xy 393.329425 -402.579979) (xy 393.308387 -402.573706) (xy 393.286433 -402.573706)
			(xy 393.265395 -402.579979) (xy 393.256008 -402.585682) (xy 392.962384 -402.778214) (xy 392.952884 -402.783983)
			(xy 392.931583 -402.790295) (xy 392.920474 -402.79066) (xy 392.72464 -402.79066) (xy 392.712555 -402.790252)
			(xy 392.689565 -402.78279) (xy 392.67001 -402.768584) (xy 392.655806 -402.749028) (xy 392.648346 -402.726037)
			(xy 392.647932 -402.713952) (xy 390.883648 -402.713952) (xy 390.883147 -402.726028) (xy 390.875698 -402.749003)
			(xy 390.861513 -402.76855) (xy 390.841982 -402.782757) (xy 390.819016 -402.790233) (xy 390.80694 -402.79066)
			(xy 390.612376 -402.79066) (xy 390.601268 -402.790293) (xy 390.579972 -402.783971) (xy 390.570466 -402.778214)
			(xy 390.275572 -402.585682) (xy 390.266185 -402.579979) (xy 390.245147 -402.573706) (xy 390.223193 -402.573706)
			(xy 390.202155 -402.579979) (xy 390.192768 -402.585682) (xy 389.899144 -402.778214) (xy 389.889633 -402.78396)
			(xy 389.86834 -402.790287) (xy 389.857234 -402.79066) (xy 389.6614 -402.79066) (xy 389.649312 -402.790287)
			(xy 389.626322 -402.782813) (xy 389.606767 -402.768599) (xy 389.592565 -402.749035) (xy 389.585106 -402.72604)
			(xy 389.584692 -402.713952) (xy 387.820408 -402.713952) (xy 387.819946 -402.726032) (xy 387.812492 -402.749013)
			(xy 387.798299 -402.768564) (xy 387.778756 -402.78277) (xy 387.75578 -402.790239) (xy 387.7437 -402.79066)
			(xy 387.549136 -402.79066) (xy 387.538027 -402.790309) (xy 387.516731 -402.783976) (xy 387.507226 -402.778214)
			(xy 387.212332 -402.585682) (xy 387.202945 -402.579979) (xy 387.181907 -402.573706) (xy 387.159953 -402.573706)
			(xy 387.138915 -402.579979) (xy 387.129528 -402.585682) (xy 386.835904 -402.778214) (xy 386.8264 -402.783975)
			(xy 386.805102 -402.790293) (xy 386.793994 -402.79066) (xy 386.59816 -402.79066) (xy 386.58607 -402.790321)
			(xy 386.563078 -402.782836) (xy 386.543525 -402.768613) (xy 386.529323 -402.749043) (xy 386.521865 -402.726042)
			(xy 386.521452 -402.713952) (xy 384.757168 -402.713952) (xy 384.756746 -402.726036) (xy 384.749287 -402.749024)
			(xy 384.735084 -402.768579) (xy 384.715531 -402.782783) (xy 384.692544 -402.790245) (xy 384.68046 -402.79066)
			(xy 384.485896 -402.79066) (xy 384.474789 -402.790285) (xy 384.453493 -402.783969) (xy 384.443986 -402.778214)
			(xy 384.149092 -402.585682) (xy 384.139705 -402.579979) (xy 384.118667 -402.573706) (xy 384.096713 -402.573706)
			(xy 384.075675 -402.579979) (xy 384.066288 -402.585682) (xy 383.772664 -402.778214) (xy 383.763149 -402.783953)
			(xy 383.741859 -402.790284) (xy 383.730754 -402.79066) (xy 383.53492 -402.79066) (xy 383.522834 -402.790269)
			(xy 383.499843 -402.782802) (xy 383.480289 -402.768591) (xy 383.466086 -402.749031) (xy 383.458626 -402.726039)
			(xy 383.458212 -402.713952) (xy 381.693928 -402.713952) (xy 381.693447 -402.72603) (xy 381.685995 -402.749008)
			(xy 381.671806 -402.768557) (xy 381.652269 -402.782764) (xy 381.629298 -402.790236) (xy 381.61722 -402.79066)
			(xy 381.422656 -402.79066) (xy 381.411548 -402.790301) (xy 381.390251 -402.783974) (xy 381.380746 -402.778214)
			(xy 381.085852 -402.585682) (xy 381.076465 -402.579979) (xy 381.055427 -402.573706) (xy 381.033473 -402.573706)
			(xy 381.012435 -402.579979) (xy 381.003048 -402.585682) (xy 380.709424 -402.778214) (xy 380.699917 -402.783968)
			(xy 380.678621 -402.79029) (xy 380.667514 -402.79066) (xy 380.47168 -402.79066) (xy 380.459591 -402.790304)
			(xy 380.4366 -402.782825) (xy 380.417046 -402.768606) (xy 380.402844 -402.749039) (xy 380.395386 -402.726041)
			(xy 380.394972 -402.713952) (xy 378.630688 -402.713952) (xy 378.630246 -402.726034) (xy 378.622789 -402.749019)
			(xy 378.608592 -402.768572) (xy 378.589044 -402.782777) (xy 378.566062 -402.790242) (xy 378.55398 -402.79066)
			(xy 378.359416 -402.79066) (xy 378.348306 -402.790317) (xy 378.32701 -402.783979) (xy 378.317506 -402.778214)
			(xy 378.022612 -402.585682) (xy 378.013225 -402.579979) (xy 377.992187 -402.573706) (xy 377.970233 -402.573706)
			(xy 377.949195 -402.579979) (xy 377.939808 -402.585682) (xy 377.646184 -402.778214) (xy 377.636684 -402.783983)
			(xy 377.615383 -402.790295) (xy 377.604274 -402.79066) (xy 377.40844 -402.79066) (xy 377.396355 -402.790252)
			(xy 377.373365 -402.78279) (xy 377.35381 -402.768584) (xy 377.339606 -402.749028) (xy 377.332146 -402.726037)
			(xy 377.331732 -402.713952) (xy 375.567448 -402.713952) (xy 375.566947 -402.726028) (xy 375.559498 -402.749003)
			(xy 375.545313 -402.76855) (xy 375.525782 -402.782757) (xy 375.502816 -402.790233) (xy 375.49074 -402.79066)
			(xy 375.296176 -402.79066) (xy 375.285068 -402.790293) (xy 375.263772 -402.783971) (xy 375.254266 -402.778214)
			(xy 374.959372 -402.585682) (xy 374.949985 -402.579979) (xy 374.928947 -402.573706) (xy 374.906993 -402.573706)
			(xy 374.885955 -402.579979) (xy 374.876568 -402.585682) (xy 374.582944 -402.778214) (xy 374.573433 -402.78396)
			(xy 374.55214 -402.790287) (xy 374.541034 -402.79066) (xy 374.3452 -402.79066) (xy 374.333112 -402.790287)
			(xy 374.310122 -402.782813) (xy 374.290567 -402.768599) (xy 374.276365 -402.749035) (xy 374.268906 -402.72604)
			(xy 374.268492 -402.713952) (xy 372.504208 -402.713952) (xy 372.503746 -402.726032) (xy 372.496292 -402.749013)
			(xy 372.482099 -402.768564) (xy 372.462556 -402.78277) (xy 372.43958 -402.790239) (xy 372.4275 -402.79066)
			(xy 372.232936 -402.79066) (xy 372.221827 -402.790309) (xy 372.200531 -402.783976) (xy 372.191026 -402.778214)
			(xy 371.896132 -402.585682) (xy 371.886745 -402.579979) (xy 371.865707 -402.573706) (xy 371.843753 -402.573706)
			(xy 371.822715 -402.579979) (xy 371.813328 -402.585682) (xy 371.519704 -402.778214) (xy 371.5102 -402.783975)
			(xy 371.488902 -402.790293) (xy 371.477794 -402.79066) (xy 371.28196 -402.79066) (xy 371.26987 -402.790321)
			(xy 371.246878 -402.782836) (xy 371.227325 -402.768613) (xy 371.213123 -402.749043) (xy 371.205665 -402.726042)
			(xy 371.205252 -402.713952) (xy 351.01022 -402.713952) (xy 351.009743 -402.726056) (xy 351.002259 -402.749079)
			(xy 350.988013 -402.768651) (xy 350.968405 -402.782848) (xy 350.945363 -402.790273) (xy 350.933258 -402.79066)
			(xy 350.738694 -402.79066) (xy 350.727587 -402.790286) (xy 350.706291 -402.783969) (xy 350.696784 -402.778214)
			(xy 350.40189 -402.585682) (xy 350.392503 -402.579979) (xy 350.371465 -402.573706) (xy 350.349511 -402.573706)
			(xy 350.328473 -402.579979) (xy 350.319086 -402.585682) (xy 350.025462 -402.778214) (xy 350.015947 -402.783954)
			(xy 349.994657 -402.790285) (xy 349.983552 -402.79066) (xy 349.787718 -402.79066) (xy 349.775629 -402.790177)
			(xy 349.752629 -402.782725) (xy 349.733049 -402.768543) (xy 349.718798 -402.749013) (xy 349.711266 -402.726039)
			(xy 349.710756 -402.713952) (xy 347.94698 -402.713952) (xy 347.946543 -402.72606) (xy 347.939054 -402.74909)
			(xy 347.924799 -402.768665) (xy 347.905179 -402.782861) (xy 347.882128 -402.790279) (xy 347.870018 -402.79066)
			(xy 347.675454 -402.79066) (xy 347.664346 -402.790302) (xy 347.643049 -402.783974) (xy 347.633544 -402.778214)
			(xy 347.33865 -402.585682) (xy 347.329263 -402.579979) (xy 347.308225 -402.573706) (xy 347.286271 -402.573706)
			(xy 347.265233 -402.579979) (xy 347.255846 -402.585682) (xy 346.962222 -402.778214) (xy 346.952715 -402.783969)
			(xy 346.931419 -402.79029) (xy 346.920312 -402.79066) (xy 346.724478 -402.79066) (xy 346.712387 -402.790212)
			(xy 346.689386 -402.782749) (xy 346.669806 -402.768557) (xy 346.655556 -402.74902) (xy 346.648025 -402.726041)
			(xy 346.647516 -402.713952) (xy 344.88374 -402.713952) (xy 344.883243 -402.726054) (xy 344.875762 -402.749073)
			(xy 344.86152 -402.768644) (xy 344.841917 -402.782841) (xy 344.818881 -402.79027) (xy 344.806778 -402.79066)
			(xy 344.612214 -402.79066) (xy 344.601104 -402.790318) (xy 344.579808 -402.783979) (xy 344.570304 -402.778214)
			(xy 344.27541 -402.585682) (xy 344.266023 -402.579979) (xy 344.244985 -402.573706) (xy 344.223031 -402.573706)
			(xy 344.201993 -402.579979) (xy 344.192606 -402.585682) (xy 343.898982 -402.778214) (xy 343.889483 -402.783983)
			(xy 343.868181 -402.790296) (xy 343.857072 -402.79066) (xy 343.661238 -402.79066) (xy 343.64915 -402.79016)
			(xy 343.626151 -402.782714) (xy 343.60657 -402.768536) (xy 343.592319 -402.749009) (xy 343.584786 -402.726038)
			(xy 343.584276 -402.713952) (xy 341.8205 -402.713952) (xy 341.820043 -402.726058) (xy 341.812557 -402.749084)
			(xy 341.798306 -402.768658) (xy 341.778692 -402.782854) (xy 341.755645 -402.790276) (xy 341.743538 -402.79066)
			(xy 341.548974 -402.79066) (xy 341.537866 -402.790294) (xy 341.51657 -402.783972) (xy 341.507064 -402.778214)
			(xy 341.21217 -402.585682) (xy 341.202783 -402.579979) (xy 341.181745 -402.573706) (xy 341.159791 -402.573706)
			(xy 341.138753 -402.579979) (xy 341.129366 -402.585682) (xy 340.835742 -402.778214) (xy 340.826231 -402.783961)
			(xy 340.804938 -402.790287) (xy 340.793832 -402.79066) (xy 340.597998 -402.79066) (xy 340.585908 -402.790194)
			(xy 340.562908 -402.782737) (xy 340.543328 -402.76855) (xy 340.529077 -402.749016) (xy 340.521546 -402.72604)
			(xy 340.521036 -402.713952) (xy 338.75726 -402.713952) (xy 338.756842 -402.726062) (xy 338.749351 -402.749095)
			(xy 338.735091 -402.768672) (xy 338.715467 -402.782867) (xy 338.69241 -402.790282) (xy 338.680298 -402.79066)
			(xy 338.485734 -402.79066) (xy 338.474625 -402.79031) (xy 338.453329 -402.783977) (xy 338.443824 -402.778214)
			(xy 338.14893 -402.585682) (xy 338.139543 -402.579979) (xy 338.118505 -402.573706) (xy 338.096551 -402.573706)
			(xy 338.075513 -402.579979) (xy 338.066126 -402.585682) (xy 337.772502 -402.778214) (xy 337.762999 -402.783976)
			(xy 337.7417 -402.790293) (xy 337.730592 -402.79066) (xy 337.534758 -402.79066) (xy 337.522666 -402.790228)
			(xy 337.499664 -402.78276) (xy 337.480085 -402.768564) (xy 337.465836 -402.749024) (xy 337.458305 -402.726042)
			(xy 337.457796 -402.713952) (xy 335.69402 -402.713952) (xy 335.693543 -402.726056) (xy 335.686059 -402.749079)
			(xy 335.671813 -402.768651) (xy 335.652205 -402.782848) (xy 335.629163 -402.790273) (xy 335.617058 -402.79066)
			(xy 335.422494 -402.79066) (xy 335.411387 -402.790286) (xy 335.390091 -402.783969) (xy 335.380584 -402.778214)
			(xy 335.08569 -402.585682) (xy 335.076303 -402.579979) (xy 335.055265 -402.573706) (xy 335.033311 -402.573706)
			(xy 335.012273 -402.579979) (xy 335.002886 -402.585682) (xy 334.709262 -402.778214) (xy 334.699747 -402.783954)
			(xy 334.678457 -402.790285) (xy 334.667352 -402.79066) (xy 334.471518 -402.79066) (xy 334.459429 -402.790177)
			(xy 334.436429 -402.782725) (xy 334.416849 -402.768543) (xy 334.402598 -402.749013) (xy 334.395066 -402.726039)
			(xy 334.394556 -402.713952) (xy 332.63078 -402.713952) (xy 332.630343 -402.72606) (xy 332.622854 -402.74909)
			(xy 332.608599 -402.768665) (xy 332.588979 -402.782861) (xy 332.565928 -402.790279) (xy 332.553818 -402.79066)
			(xy 332.359254 -402.79066) (xy 332.348146 -402.790302) (xy 332.326849 -402.783974) (xy 332.317344 -402.778214)
			(xy 332.02245 -402.585682) (xy 332.013063 -402.579979) (xy 331.992025 -402.573706) (xy 331.970071 -402.573706)
			(xy 331.949033 -402.579979) (xy 331.939646 -402.585682) (xy 331.646022 -402.778214) (xy 331.636515 -402.783969)
			(xy 331.615219 -402.79029) (xy 331.604112 -402.79066) (xy 331.408278 -402.79066) (xy 331.396187 -402.790212)
			(xy 331.373186 -402.782749) (xy 331.353606 -402.768557) (xy 331.339356 -402.74902) (xy 331.331825 -402.726041)
			(xy 331.331316 -402.713952) (xy 329.56754 -402.713952) (xy 329.567043 -402.726054) (xy 329.559562 -402.749073)
			(xy 329.54532 -402.768644) (xy 329.525717 -402.782841) (xy 329.502681 -402.79027) (xy 329.490578 -402.79066)
			(xy 329.296014 -402.79066) (xy 329.284904 -402.790318) (xy 329.263608 -402.783979) (xy 329.254104 -402.778214)
			(xy 328.95921 -402.585682) (xy 328.949823 -402.579979) (xy 328.928785 -402.573706) (xy 328.906831 -402.573706)
			(xy 328.885793 -402.579979) (xy 328.876406 -402.585682) (xy 328.582782 -402.778214) (xy 328.573283 -402.783983)
			(xy 328.551981 -402.790296) (xy 328.540872 -402.79066) (xy 328.345038 -402.79066) (xy 328.33295 -402.79016)
			(xy 328.309951 -402.782714) (xy 328.29037 -402.768536) (xy 328.276119 -402.749009) (xy 328.268586 -402.726038)
			(xy 328.268076 -402.713952) (xy 326.5043 -402.713952) (xy 326.503843 -402.726058) (xy 326.496357 -402.749084)
			(xy 326.482106 -402.768658) (xy 326.462492 -402.782854) (xy 326.439445 -402.790276) (xy 326.427338 -402.79066)
			(xy 326.232774 -402.79066) (xy 326.221666 -402.790294) (xy 326.20037 -402.783972) (xy 326.190864 -402.778214)
			(xy 325.89597 -402.585682) (xy 325.886583 -402.579979) (xy 325.865545 -402.573706) (xy 325.843591 -402.573706)
			(xy 325.822553 -402.579979) (xy 325.813166 -402.585682) (xy 325.519542 -402.778214) (xy 325.510031 -402.783961)
			(xy 325.488738 -402.790287) (xy 325.477632 -402.79066) (xy 325.281798 -402.79066) (xy 325.269708 -402.790194)
			(xy 325.246708 -402.782737) (xy 325.227128 -402.76855) (xy 325.212877 -402.749016) (xy 325.205346 -402.72604)
			(xy 325.204836 -402.713952) (xy 323.44106 -402.713952) (xy 323.440642 -402.726062) (xy 323.433151 -402.749095)
			(xy 323.418891 -402.768672) (xy 323.399267 -402.782867) (xy 323.37621 -402.790282) (xy 323.364098 -402.79066)
			(xy 323.169534 -402.79066) (xy 323.158425 -402.79031) (xy 323.137129 -402.783977) (xy 323.127624 -402.778214)
			(xy 322.83273 -402.585682) (xy 322.823343 -402.579979) (xy 322.802305 -402.573706) (xy 322.780351 -402.573706)
			(xy 322.759313 -402.579979) (xy 322.749926 -402.585682) (xy 322.456302 -402.778214) (xy 322.446799 -402.783976)
			(xy 322.4255 -402.790293) (xy 322.414392 -402.79066) (xy 322.218558 -402.79066) (xy 322.206466 -402.790228)
			(xy 322.183464 -402.78276) (xy 322.163885 -402.768564) (xy 322.149636 -402.749024) (xy 322.142105 -402.726042)
			(xy 322.141596 -402.713952) (xy 320.37782 -402.713952) (xy 320.377343 -402.726056) (xy 320.369859 -402.749079)
			(xy 320.355613 -402.768651) (xy 320.336005 -402.782848) (xy 320.312963 -402.790273) (xy 320.300858 -402.79066)
			(xy 320.106294 -402.79066) (xy 320.095187 -402.790286) (xy 320.073891 -402.783969) (xy 320.064384 -402.778214)
			(xy 319.76949 -402.585682) (xy 319.760103 -402.579979) (xy 319.739065 -402.573706) (xy 319.717111 -402.573706)
			(xy 319.696073 -402.579979) (xy 319.686686 -402.585682) (xy 319.393062 -402.778214) (xy 319.383547 -402.783954)
			(xy 319.362257 -402.790285) (xy 319.351152 -402.79066) (xy 319.155318 -402.79066) (xy 319.143229 -402.790177)
			(xy 319.120229 -402.782725) (xy 319.100649 -402.768543) (xy 319.086398 -402.749013) (xy 319.078866 -402.726039)
			(xy 319.078356 -402.713952) (xy 317.31458 -402.713952) (xy 317.314143 -402.72606) (xy 317.306654 -402.74909)
			(xy 317.292399 -402.768665) (xy 317.272779 -402.782861) (xy 317.249728 -402.790279) (xy 317.237618 -402.79066)
			(xy 317.043054 -402.79066) (xy 317.031946 -402.790302) (xy 317.010649 -402.783974) (xy 317.001144 -402.778214)
			(xy 316.70625 -402.585682) (xy 316.696863 -402.579979) (xy 316.675825 -402.573706) (xy 316.653871 -402.573706)
			(xy 316.632833 -402.579979) (xy 316.623446 -402.585682) (xy 316.329822 -402.778214) (xy 316.320315 -402.783969)
			(xy 316.299019 -402.79029) (xy 316.287912 -402.79066) (xy 316.092078 -402.79066) (xy 316.079987 -402.790212)
			(xy 316.056986 -402.782749) (xy 316.037406 -402.768557) (xy 316.023156 -402.74902) (xy 316.015625 -402.726041)
			(xy 316.015116 -402.713952) (xy 314.25134 -402.713952) (xy 314.250843 -402.726054) (xy 314.243362 -402.749073)
			(xy 314.22912 -402.768644) (xy 314.209517 -402.782841) (xy 314.186481 -402.79027) (xy 314.174378 -402.79066)
			(xy 313.979814 -402.79066) (xy 313.968704 -402.790318) (xy 313.947408 -402.783979) (xy 313.937904 -402.778214)
			(xy 313.64301 -402.585682) (xy 313.633623 -402.579979) (xy 313.612585 -402.573706) (xy 313.590631 -402.573706)
			(xy 313.569593 -402.579979) (xy 313.560206 -402.585682) (xy 313.266582 -402.778214) (xy 313.257083 -402.783983)
			(xy 313.235781 -402.790296) (xy 313.224672 -402.79066) (xy 313.028838 -402.79066) (xy 313.01675 -402.79016)
			(xy 312.993751 -402.782714) (xy 312.97417 -402.768536) (xy 312.959919 -402.749009) (xy 312.952386 -402.726038)
			(xy 312.951876 -402.713952) (xy 311.1881 -402.713952) (xy 311.187643 -402.726058) (xy 311.180157 -402.749084)
			(xy 311.165906 -402.768658) (xy 311.146292 -402.782854) (xy 311.123245 -402.790276) (xy 311.111138 -402.79066)
			(xy 310.916574 -402.79066) (xy 310.905466 -402.790294) (xy 310.88417 -402.783972) (xy 310.874664 -402.778214)
			(xy 310.57977 -402.585682) (xy 310.570383 -402.579979) (xy 310.549345 -402.573706) (xy 310.527391 -402.573706)
			(xy 310.506353 -402.579979) (xy 310.496966 -402.585682) (xy 310.203342 -402.778214) (xy 310.193831 -402.783961)
			(xy 310.172538 -402.790287) (xy 310.161432 -402.79066) (xy 309.965598 -402.79066) (xy 309.953508 -402.790194)
			(xy 309.930508 -402.782737) (xy 309.910928 -402.76855) (xy 309.896677 -402.749016) (xy 309.889146 -402.72604)
			(xy 309.888636 -402.713952) (xy 308.12486 -402.713952) (xy 308.124442 -402.726062) (xy 308.116951 -402.749095)
			(xy 308.102691 -402.768672) (xy 308.083067 -402.782867) (xy 308.06001 -402.790282) (xy 308.047898 -402.79066)
			(xy 307.853334 -402.79066) (xy 307.842225 -402.79031) (xy 307.820929 -402.783977) (xy 307.811424 -402.778214)
			(xy 307.51653 -402.585682) (xy 307.507143 -402.579979) (xy 307.486105 -402.573706) (xy 307.464151 -402.573706)
			(xy 307.443113 -402.579979) (xy 307.433726 -402.585682) (xy 307.140102 -402.778214) (xy 307.130599 -402.783976)
			(xy 307.1093 -402.790293) (xy 307.098192 -402.79066) (xy 306.902358 -402.79066) (xy 306.890266 -402.790228)
			(xy 306.867264 -402.78276) (xy 306.847685 -402.768564) (xy 306.833436 -402.749024) (xy 306.825905 -402.726042)
			(xy 306.825396 -402.713952) (xy 305.06162 -402.713952) (xy 305.061143 -402.726056) (xy 305.053659 -402.749079)
			(xy 305.039413 -402.768651) (xy 305.019805 -402.782848) (xy 304.996763 -402.790273) (xy 304.984658 -402.79066)
			(xy 304.790094 -402.79066) (xy 304.778987 -402.790286) (xy 304.757691 -402.783969) (xy 304.748184 -402.778214)
			(xy 304.45329 -402.585682) (xy 304.443903 -402.579979) (xy 304.422865 -402.573706) (xy 304.400911 -402.573706)
			(xy 304.379873 -402.579979) (xy 304.370486 -402.585682) (xy 304.076862 -402.778214) (xy 304.067347 -402.783954)
			(xy 304.046057 -402.790285) (xy 304.034952 -402.79066) (xy 303.839118 -402.79066) (xy 303.827029 -402.790177)
			(xy 303.804029 -402.782725) (xy 303.784449 -402.768543) (xy 303.770198 -402.749013) (xy 303.762666 -402.726039)
			(xy 303.762156 -402.713952) (xy 281.686508 -402.713952) (xy 281.686508 -404.0475) (xy 287.066441 -404.0475)
			(xy 287.070455 -403.983698) (xy 287.082434 -403.920902) (xy 287.102189 -403.860103) (xy 287.129408 -403.80226)
			(xy 287.163662 -403.748283) (xy 287.204411 -403.699026) (xy 287.251013 -403.655264) (xy 287.302731 -403.617688)
			(xy 287.358752 -403.58689) (xy 287.418191 -403.563357) (xy 287.48011 -403.547458) (xy 287.543534 -403.539446)
			(xy 287.575498 -403.538944) (xy 287.575752 -403.538944) (xy 287.607498 -403.539464) (xy 287.670494 -403.547393)
			(xy 287.732014 -403.563096) (xy 287.791102 -403.58633) (xy 287.846842 -403.616733) (xy 287.898367 -403.653834)
			(xy 287.921954 -403.675088) (xy 287.929217 -403.681272) (xy 287.946967 -403.688223) (xy 287.966029 -403.688223)
			(xy 287.983779 -403.681272) (xy 287.991042 -403.675088) (xy 288.014631 -403.653832) (xy 288.06614 -403.6167)
			(xy 288.121874 -403.586276) (xy 288.180965 -403.563035) (xy 288.242492 -403.547338) (xy 288.305495 -403.539431)
			(xy 288.337244 -403.538944) (xy 288.337498 -403.538944) (xy 288.369457 -403.539521) (xy 288.432872 -403.547532)
			(xy 288.494783 -403.563427) (xy 288.554213 -403.586957) (xy 288.610226 -403.61775) (xy 288.661937 -403.655321)
			(xy 288.708532 -403.699076) (xy 288.749276 -403.748326) (xy 288.783525 -403.802295) (xy 288.810741 -403.86013)
			(xy 288.830493 -403.920921) (xy 288.84247 -403.983707) (xy 288.846484 -404.0475) (xy 289.606441 -404.0475)
			(xy 289.610455 -403.983698) (xy 289.622434 -403.920902) (xy 289.642189 -403.860103) (xy 289.669408 -403.80226)
			(xy 289.703662 -403.748283) (xy 289.744411 -403.699026) (xy 289.791013 -403.655264) (xy 289.842731 -403.617688)
			(xy 289.898752 -403.58689) (xy 289.958191 -403.563357) (xy 290.02011 -403.547458) (xy 290.083534 -403.539446)
			(xy 290.115498 -403.538944) (xy 290.115752 -403.538944) (xy 290.147498 -403.539464) (xy 290.210494 -403.547393)
			(xy 290.272014 -403.563096) (xy 290.331102 -403.58633) (xy 290.386842 -403.616733) (xy 290.438367 -403.653834)
			(xy 290.461954 -403.675088) (xy 290.469217 -403.681272) (xy 290.486967 -403.688223) (xy 290.506029 -403.688223)
			(xy 290.523779 -403.681272) (xy 290.531042 -403.675088) (xy 290.554631 -403.653832) (xy 290.60614 -403.6167)
			(xy 290.661874 -403.586276) (xy 290.720965 -403.563035) (xy 290.782492 -403.547338) (xy 290.845495 -403.539431)
			(xy 290.877244 -403.538944) (xy 290.877498 -403.538944) (xy 290.909457 -403.539521) (xy 290.972872 -403.547532)
			(xy 291.034783 -403.563427) (xy 291.094213 -403.586957) (xy 291.150226 -403.61775) (xy 291.201937 -403.655321)
			(xy 291.248532 -403.699076) (xy 291.289276 -403.748326) (xy 291.323525 -403.802295) (xy 291.350741 -403.86013)
			(xy 291.370493 -403.920921) (xy 291.38247 -403.983707) (xy 291.386484 -404.0475) (xy 292.146441 -404.0475)
			(xy 292.150455 -403.983698) (xy 292.162434 -403.920902) (xy 292.182189 -403.860103) (xy 292.209408 -403.80226)
			(xy 292.243662 -403.748283) (xy 292.284411 -403.699026) (xy 292.331013 -403.655264) (xy 292.382731 -403.617688)
			(xy 292.438752 -403.58689) (xy 292.498191 -403.563357) (xy 292.56011 -403.547458) (xy 292.623534 -403.539446)
			(xy 292.655498 -403.538944) (xy 292.655752 -403.538944) (xy 292.687498 -403.539464) (xy 292.750494 -403.547393)
			(xy 292.812014 -403.563096) (xy 292.871102 -403.58633) (xy 292.926842 -403.616733) (xy 292.978367 -403.653834)
			(xy 293.001954 -403.675088) (xy 293.009217 -403.681272) (xy 293.026967 -403.688223) (xy 293.046029 -403.688223)
			(xy 293.063779 -403.681272) (xy 293.071042 -403.675088) (xy 293.094631 -403.653832) (xy 293.14614 -403.6167)
			(xy 293.201874 -403.586276) (xy 293.260965 -403.563035) (xy 293.322492 -403.547338) (xy 293.385495 -403.539431)
			(xy 293.417244 -403.538944) (xy 293.417498 -403.538944) (xy 293.449457 -403.539521) (xy 293.512872 -403.547532)
			(xy 293.574783 -403.563427) (xy 293.634213 -403.586957) (xy 293.690226 -403.61775) (xy 293.741937 -403.655321)
			(xy 293.788532 -403.699076) (xy 293.829276 -403.748326) (xy 293.863525 -403.802295) (xy 293.890741 -403.86013)
			(xy 293.910493 -403.920921) (xy 293.92247 -403.983707) (xy 293.926484 -404.0475) (xy 294.53602 -404.0475)
			(xy 294.540035 -403.983693) (xy 294.552015 -403.920892) (xy 294.571773 -403.860089) (xy 294.598995 -403.802241)
			(xy 294.633253 -403.748261) (xy 294.674007 -403.699001) (xy 294.720613 -403.655237) (xy 294.772338 -403.61766)
			(xy 294.828364 -403.586862) (xy 294.887809 -403.563329) (xy 294.949734 -403.547433) (xy 295.013163 -403.539423)
			(xy 295.04513 -403.538944) (xy 295.045384 -403.538944) (xy 295.077131 -403.539444) (xy 295.140127 -403.547377)
			(xy 295.201647 -403.563084) (xy 295.260736 -403.586322) (xy 295.316476 -403.616728) (xy 295.368 -403.653832)
			(xy 295.391586 -403.675088) (xy 295.398849 -403.681272) (xy 295.416599 -403.688223) (xy 295.435661 -403.688223)
			(xy 295.453411 -403.681272) (xy 295.460674 -403.675088) (xy 295.48425 -403.653817) (xy 295.535761 -403.616686)
			(xy 295.591498 -403.586265) (xy 295.650592 -403.563026) (xy 295.712121 -403.547332) (xy 295.775126 -403.539429)
			(xy 295.806876 -403.538944) (xy 295.80713 -403.538944) (xy 295.839087 -403.539544) (xy 295.902496 -403.547558)
			(xy 295.964401 -403.563455) (xy 296.023825 -403.586986) (xy 296.079832 -403.617779) (xy 296.131538 -403.655348)
			(xy 296.178128 -403.699102) (xy 296.218866 -403.748349) (xy 296.253112 -403.802314) (xy 296.280324 -403.860145)
			(xy 296.300074 -403.920931) (xy 296.312049 -403.983712) (xy 296.316063 -404.0475) (xy 297.07602 -404.0475)
			(xy 297.080035 -403.983693) (xy 297.092015 -403.920892) (xy 297.111773 -403.860089) (xy 297.138995 -403.802241)
			(xy 297.173253 -403.748261) (xy 297.214007 -403.699001) (xy 297.260613 -403.655237) (xy 297.312338 -403.61766)
			(xy 297.368364 -403.586862) (xy 297.427809 -403.563329) (xy 297.489734 -403.547433) (xy 297.553163 -403.539423)
			(xy 297.58513 -403.538944) (xy 297.585384 -403.538944) (xy 297.617131 -403.539444) (xy 297.680127 -403.547377)
			(xy 297.741647 -403.563084) (xy 297.800736 -403.586322) (xy 297.856476 -403.616728) (xy 297.908 -403.653832)
			(xy 297.931586 -403.675088) (xy 297.938849 -403.681272) (xy 297.956599 -403.688223) (xy 297.975661 -403.688223)
			(xy 297.993411 -403.681272) (xy 298.000674 -403.675088) (xy 298.02425 -403.653817) (xy 298.075761 -403.616686)
			(xy 298.131498 -403.586265) (xy 298.190592 -403.563026) (xy 298.252121 -403.547332) (xy 298.315126 -403.539429)
			(xy 298.346876 -403.538944) (xy 298.34713 -403.538944) (xy 298.379087 -403.539544) (xy 298.442496 -403.547558)
			(xy 298.504401 -403.563455) (xy 298.563825 -403.586986) (xy 298.619832 -403.617779) (xy 298.671538 -403.655348)
			(xy 298.718128 -403.699102) (xy 298.758866 -403.748349) (xy 298.793112 -403.802314) (xy 298.820324 -403.860145)
			(xy 298.836897 -403.911152) (xy 303.599054 -403.911152) (xy 303.599054 -403.856648) (xy 303.60681 -403.802698)
			(xy 303.622166 -403.7504) (xy 303.644808 -403.700821) (xy 303.674275 -403.654968) (xy 303.709967 -403.613776)
			(xy 303.751159 -403.578082) (xy 303.79701 -403.548613) (xy 303.846589 -403.52597) (xy 303.898886 -403.510613)
			(xy 303.952836 -403.502855) (xy 303.980088 -403.502368) (xy 304.843688 -403.502368) (xy 304.87094 -403.502878)
			(xy 304.924889 -403.510634) (xy 304.977185 -403.525988) (xy 305.026763 -403.548628) (xy 305.072615 -403.578094)
			(xy 305.113806 -403.613785) (xy 305.149499 -403.654976) (xy 305.178966 -403.700826) (xy 305.201608 -403.750404)
			(xy 305.216964 -403.8027) (xy 305.224721 -403.856648) (xy 305.224721 -403.911152) (xy 305.22472 -403.911156)
			(xy 306.662231 -403.911156) (xy 306.662231 -403.856644) (xy 306.669989 -403.802687) (xy 306.685348 -403.750384)
			(xy 306.707994 -403.700799) (xy 306.737466 -403.654941) (xy 306.773165 -403.613745) (xy 306.814364 -403.578049)
			(xy 306.860223 -403.54858) (xy 306.90981 -403.525938) (xy 306.962115 -403.510583) (xy 307.016072 -403.502829)
			(xy 307.043328 -403.502368) (xy 307.906928 -403.502368) (xy 307.934176 -403.502904) (xy 307.988117 -403.510663)
			(xy 308.040405 -403.52602) (xy 308.089976 -403.548661) (xy 308.13582 -403.578126) (xy 308.177004 -403.613816)
			(xy 308.21269 -403.655002) (xy 308.242152 -403.700849) (xy 308.26479 -403.750421) (xy 308.280143 -403.80271)
			(xy 308.287898 -403.856652) (xy 308.287898 -403.911148) (xy 308.287897 -403.911152) (xy 309.725554 -403.911152)
			(xy 309.725554 -403.856648) (xy 309.73331 -403.8027) (xy 309.748664 -403.750405) (xy 309.771305 -403.700826)
			(xy 309.80077 -403.654975) (xy 309.83646 -403.613783) (xy 309.877649 -403.578089) (xy 309.923498 -403.54862)
			(xy 309.973075 -403.525976) (xy 310.025369 -403.510617) (xy 310.079317 -403.502856) (xy 310.106568 -403.502368)
			(xy 310.970168 -403.502368) (xy 310.997421 -403.502877) (xy 311.051372 -403.51063) (xy 311.10367 -403.525982)
			(xy 311.153251 -403.548621) (xy 311.199105 -403.578087) (xy 311.240299 -403.613778) (xy 311.275994 -403.654969)
			(xy 311.305463 -403.700821) (xy 311.328107 -403.7504) (xy 311.343463 -403.802697) (xy 311.351221 -403.856647)
			(xy 311.351221 -403.911153) (xy 311.351221 -403.911155) (xy 312.788731 -403.911155) (xy 312.788731 -403.856645)
			(xy 312.796489 -403.80269) (xy 312.811846 -403.750388) (xy 312.834491 -403.700804) (xy 312.863961 -403.654948)
			(xy 312.899658 -403.613752) (xy 312.940854 -403.578056) (xy 312.986711 -403.548587) (xy 313.036296 -403.525943)
			(xy 313.088598 -403.510587) (xy 313.142553 -403.50283) (xy 313.169808 -403.502368) (xy 314.033408 -403.502368)
			(xy 314.060657 -403.502903) (xy 314.114601 -403.51066) (xy 314.166891 -403.526015) (xy 314.216464 -403.548655)
			(xy 314.26231 -403.578119) (xy 314.303497 -403.613809) (xy 314.339186 -403.654996) (xy 314.368649 -403.700843)
			(xy 314.391288 -403.750417) (xy 314.406642 -403.802707) (xy 314.414398 -403.856651) (xy 314.414398 -403.911149)
			(xy 314.414397 -403.911157) (xy 315.851931 -403.911157) (xy 315.851931 -403.856643) (xy 315.85969 -403.802685)
			(xy 315.875049 -403.75038) (xy 315.897697 -403.700793) (xy 315.927171 -403.654935) (xy 315.962872 -403.613738)
			(xy 316.004073 -403.578042) (xy 316.049935 -403.548574) (xy 316.099525 -403.525932) (xy 316.151832 -403.51058)
			(xy 316.205791 -403.502828) (xy 316.233048 -403.502368) (xy 317.096648 -403.502368) (xy 317.123895 -403.502905)
			(xy 317.177834 -403.510667) (xy 317.23012 -403.526025) (xy 317.279688 -403.548668) (xy 317.325529 -403.578133)
			(xy 317.366711 -403.613823) (xy 317.402395 -403.655009) (xy 317.431855 -403.700854) (xy 317.454491 -403.750425)
			(xy 317.469843 -403.802713) (xy 317.477598 -403.856653) (xy 317.477598 -403.911147) (xy 317.477597 -403.911152)
			(xy 318.915254 -403.911152) (xy 318.915254 -403.856648) (xy 318.92301 -403.802698) (xy 318.938366 -403.7504)
			(xy 318.961008 -403.700821) (xy 318.990475 -403.654968) (xy 319.026167 -403.613776) (xy 319.067359 -403.578082)
			(xy 319.11321 -403.548613) (xy 319.162789 -403.52597) (xy 319.215086 -403.510613) (xy 319.269036 -403.502855)
			(xy 319.296288 -403.502368) (xy 320.159888 -403.502368) (xy 320.18714 -403.502878) (xy 320.241089 -403.510634)
			(xy 320.293385 -403.525988) (xy 320.342963 -403.548628) (xy 320.388815 -403.578094) (xy 320.430006 -403.613785)
			(xy 320.465699 -403.654976) (xy 320.495166 -403.700826) (xy 320.517808 -403.750404) (xy 320.533164 -403.8027)
			(xy 320.540921 -403.856648) (xy 320.540921 -403.911152) (xy 320.54092 -403.911156) (xy 321.978431 -403.911156)
			(xy 321.978431 -403.856644) (xy 321.986189 -403.802687) (xy 322.001548 -403.750384) (xy 322.024194 -403.700799)
			(xy 322.053666 -403.654941) (xy 322.089365 -403.613745) (xy 322.130564 -403.578049) (xy 322.176423 -403.54858)
			(xy 322.22601 -403.525938) (xy 322.278315 -403.510583) (xy 322.332272 -403.502829) (xy 322.359528 -403.502368)
			(xy 323.223128 -403.502368) (xy 323.250376 -403.502904) (xy 323.304317 -403.510663) (xy 323.356605 -403.52602)
			(xy 323.406176 -403.548661) (xy 323.45202 -403.578126) (xy 323.493204 -403.613816) (xy 323.52889 -403.655002)
			(xy 323.558352 -403.700849) (xy 323.58099 -403.750421) (xy 323.596343 -403.80271) (xy 323.604098 -403.856652)
			(xy 323.604098 -403.911148) (xy 323.604097 -403.911152) (xy 325.041754 -403.911152) (xy 325.041754 -403.856648)
			(xy 325.04951 -403.8027) (xy 325.064864 -403.750405) (xy 325.087505 -403.700826) (xy 325.11697 -403.654975)
			(xy 325.15266 -403.613783) (xy 325.193849 -403.578089) (xy 325.239698 -403.54862) (xy 325.289275 -403.525976)
			(xy 325.341569 -403.510617) (xy 325.395517 -403.502856) (xy 325.422768 -403.502368) (xy 326.286368 -403.502368)
			(xy 326.313621 -403.502877) (xy 326.367572 -403.51063) (xy 326.41987 -403.525982) (xy 326.469451 -403.548621)
			(xy 326.515305 -403.578087) (xy 326.556499 -403.613778) (xy 326.592194 -403.654969) (xy 326.621663 -403.700821)
			(xy 326.644307 -403.7504) (xy 326.659663 -403.802697) (xy 326.667421 -403.856647) (xy 326.667421 -403.911153)
			(xy 326.667421 -403.911155) (xy 328.104931 -403.911155) (xy 328.104931 -403.856645) (xy 328.112689 -403.80269)
			(xy 328.128046 -403.750388) (xy 328.150691 -403.700804) (xy 328.180161 -403.654948) (xy 328.215858 -403.613752)
			(xy 328.257054 -403.578056) (xy 328.302911 -403.548587) (xy 328.352496 -403.525943) (xy 328.404798 -403.510587)
			(xy 328.458753 -403.50283) (xy 328.486008 -403.502368) (xy 329.349608 -403.502368) (xy 329.376857 -403.502903)
			(xy 329.430801 -403.51066) (xy 329.483091 -403.526015) (xy 329.532664 -403.548655) (xy 329.57851 -403.578119)
			(xy 329.619697 -403.613809) (xy 329.655386 -403.654996) (xy 329.684849 -403.700843) (xy 329.707488 -403.750417)
			(xy 329.722842 -403.802707) (xy 329.730598 -403.856651) (xy 329.730598 -403.911149) (xy 329.730597 -403.911157)
			(xy 331.168131 -403.911157) (xy 331.168131 -403.856643) (xy 331.17589 -403.802685) (xy 331.191249 -403.75038)
			(xy 331.213897 -403.700793) (xy 331.243371 -403.654935) (xy 331.279072 -403.613738) (xy 331.320273 -403.578042)
			(xy 331.366135 -403.548574) (xy 331.415725 -403.525932) (xy 331.468032 -403.51058) (xy 331.521991 -403.502828)
			(xy 331.549248 -403.502368) (xy 332.412848 -403.502368) (xy 332.440095 -403.502905) (xy 332.494034 -403.510667)
			(xy 332.54632 -403.526025) (xy 332.595888 -403.548668) (xy 332.641729 -403.578133) (xy 332.682911 -403.613823)
			(xy 332.718595 -403.655009) (xy 332.748055 -403.700854) (xy 332.770691 -403.750425) (xy 332.786043 -403.802713)
			(xy 332.793798 -403.856653) (xy 332.793798 -403.911147) (xy 332.793797 -403.911152) (xy 334.231454 -403.911152)
			(xy 334.231454 -403.856648) (xy 334.23921 -403.802698) (xy 334.254566 -403.7504) (xy 334.277208 -403.700821)
			(xy 334.306675 -403.654968) (xy 334.342367 -403.613776) (xy 334.383559 -403.578082) (xy 334.42941 -403.548613)
			(xy 334.478989 -403.52597) (xy 334.531286 -403.510613) (xy 334.585236 -403.502855) (xy 334.612488 -403.502368)
			(xy 335.476088 -403.502368) (xy 335.50334 -403.502878) (xy 335.557289 -403.510634) (xy 335.609585 -403.525988)
			(xy 335.659163 -403.548628) (xy 335.705015 -403.578094) (xy 335.746206 -403.613785) (xy 335.781899 -403.654976)
			(xy 335.811366 -403.700826) (xy 335.834008 -403.750404) (xy 335.849364 -403.8027) (xy 335.857121 -403.856648)
			(xy 335.857121 -403.911152) (xy 335.85712 -403.911156) (xy 337.294631 -403.911156) (xy 337.294631 -403.856644)
			(xy 337.302389 -403.802687) (xy 337.317748 -403.750384) (xy 337.340394 -403.700799) (xy 337.369866 -403.654941)
			(xy 337.405565 -403.613745) (xy 337.446764 -403.578049) (xy 337.492623 -403.54858) (xy 337.54221 -403.525938)
			(xy 337.594515 -403.510583) (xy 337.648472 -403.502829) (xy 337.675728 -403.502368) (xy 338.539328 -403.502368)
			(xy 338.566576 -403.502904) (xy 338.620517 -403.510663) (xy 338.672805 -403.52602) (xy 338.722376 -403.548661)
			(xy 338.76822 -403.578126) (xy 338.809404 -403.613816) (xy 338.84509 -403.655002) (xy 338.874552 -403.700849)
			(xy 338.89719 -403.750421) (xy 338.912543 -403.80271) (xy 338.920298 -403.856652) (xy 338.920298 -403.911148)
			(xy 338.920297 -403.911152) (xy 340.357954 -403.911152) (xy 340.357954 -403.856648) (xy 340.36571 -403.8027)
			(xy 340.381064 -403.750405) (xy 340.403705 -403.700826) (xy 340.43317 -403.654975) (xy 340.46886 -403.613783)
			(xy 340.510049 -403.578089) (xy 340.555898 -403.54862) (xy 340.605475 -403.525976) (xy 340.657769 -403.510617)
			(xy 340.711717 -403.502856) (xy 340.738968 -403.502368) (xy 341.602568 -403.502368) (xy 341.629821 -403.502877)
			(xy 341.683772 -403.51063) (xy 341.73607 -403.525982) (xy 341.785651 -403.548621) (xy 341.831505 -403.578087)
			(xy 341.872699 -403.613778) (xy 341.908394 -403.654969) (xy 341.937863 -403.700821) (xy 341.960507 -403.7504)
			(xy 341.975863 -403.802697) (xy 341.983621 -403.856647) (xy 341.983621 -403.911153) (xy 341.983621 -403.911155)
			(xy 343.421131 -403.911155) (xy 343.421131 -403.856645) (xy 343.428889 -403.80269) (xy 343.444246 -403.750388)
			(xy 343.466891 -403.700804) (xy 343.496361 -403.654948) (xy 343.532058 -403.613752) (xy 343.573254 -403.578056)
			(xy 343.619111 -403.548587) (xy 343.668696 -403.525943) (xy 343.720998 -403.510587) (xy 343.774953 -403.50283)
			(xy 343.802208 -403.502368) (xy 344.665808 -403.502368) (xy 344.693057 -403.502903) (xy 344.747001 -403.51066)
			(xy 344.799291 -403.526015) (xy 344.848864 -403.548655) (xy 344.89471 -403.578119) (xy 344.935897 -403.613809)
			(xy 344.971586 -403.654996) (xy 345.001049 -403.700843) (xy 345.023688 -403.750417) (xy 345.039042 -403.802707)
			(xy 345.046798 -403.856651) (xy 345.046798 -403.911149) (xy 345.046797 -403.911157) (xy 346.484331 -403.911157)
			(xy 346.484331 -403.856643) (xy 346.49209 -403.802685) (xy 346.507449 -403.75038) (xy 346.530097 -403.700793)
			(xy 346.559571 -403.654935) (xy 346.595272 -403.613738) (xy 346.636473 -403.578042) (xy 346.682335 -403.548574)
			(xy 346.731925 -403.525932) (xy 346.784232 -403.51058) (xy 346.838191 -403.502828) (xy 346.865448 -403.502368)
			(xy 347.729048 -403.502368) (xy 347.756295 -403.502905) (xy 347.810234 -403.510667) (xy 347.86252 -403.526025)
			(xy 347.912088 -403.548668) (xy 347.957929 -403.578133) (xy 347.999111 -403.613823) (xy 348.034795 -403.655009)
			(xy 348.064255 -403.700854) (xy 348.086891 -403.750425) (xy 348.102243 -403.802713) (xy 348.109998 -403.856653)
			(xy 348.109998 -403.911147) (xy 348.109997 -403.911152) (xy 349.547654 -403.911152) (xy 349.547654 -403.856648)
			(xy 349.55541 -403.802698) (xy 349.570766 -403.7504) (xy 349.593408 -403.700821) (xy 349.622875 -403.654968)
			(xy 349.658567 -403.613776) (xy 349.699759 -403.578082) (xy 349.74561 -403.548613) (xy 349.795189 -403.52597)
			(xy 349.847486 -403.510613) (xy 349.901436 -403.502855) (xy 349.928688 -403.502368) (xy 350.792288 -403.502368)
			(xy 350.81954 -403.502878) (xy 350.873489 -403.510634) (xy 350.925785 -403.525988) (xy 350.975363 -403.548628)
			(xy 351.021215 -403.578094) (xy 351.062406 -403.613785) (xy 351.098099 -403.654976) (xy 351.127566 -403.700826)
			(xy 351.150208 -403.750404) (xy 351.165564 -403.8027) (xy 351.173321 -403.856648) (xy 351.173321 -403.911152)
			(xy 351.17332 -403.911156) (xy 371.041831 -403.911156) (xy 371.041831 -403.856644) (xy 371.049589 -403.802687)
			(xy 371.064948 -403.750383) (xy 371.087594 -403.700798) (xy 371.117067 -403.654941) (xy 371.152766 -403.613745)
			(xy 371.193965 -403.578049) (xy 371.239824 -403.54858) (xy 371.289412 -403.525937) (xy 371.341716 -403.510583)
			(xy 371.395674 -403.502829) (xy 371.42293 -403.502368) (xy 372.28653 -403.502368) (xy 372.313778 -403.502904)
			(xy 372.367719 -403.510664) (xy 372.420007 -403.52602) (xy 372.469577 -403.548662) (xy 372.515421 -403.578127)
			(xy 372.556605 -403.613816) (xy 372.592291 -403.655003) (xy 372.621753 -403.700849) (xy 372.64439 -403.750421)
			(xy 372.659743 -403.80271) (xy 372.667498 -403.856652) (xy 372.667498 -403.911148) (xy 372.667497 -403.911152)
			(xy 374.105154 -403.911152) (xy 374.105154 -403.856648) (xy 374.11291 -403.8027) (xy 374.128265 -403.750404)
			(xy 374.150905 -403.700826) (xy 374.18037 -403.654974) (xy 374.216061 -403.613782) (xy 374.25725 -403.578088)
			(xy 374.3031 -403.548619) (xy 374.352676 -403.525975) (xy 374.404971 -403.510616) (xy 374.458918 -403.502856)
			(xy 374.48617 -403.502368) (xy 375.34977 -403.502368) (xy 375.377023 -403.502877) (xy 375.430973 -403.51063)
			(xy 375.483271 -403.525983) (xy 375.532852 -403.548622) (xy 375.578706 -403.578087) (xy 375.6199 -403.613779)
			(xy 375.655595 -403.65497) (xy 375.685064 -403.700821) (xy 375.707707 -403.7504) (xy 375.723063 -403.802697)
			(xy 375.730821 -403.856647) (xy 375.730821 -403.911153) (xy 375.730821 -403.911155) (xy 377.168331 -403.911155)
			(xy 377.168331 -403.856645) (xy 377.176089 -403.80269) (xy 377.191446 -403.750388) (xy 377.214091 -403.700804)
			(xy 377.243562 -403.654947) (xy 377.279259 -403.613752) (xy 377.320455 -403.578056) (xy 377.366313 -403.548586)
			(xy 377.415897 -403.525943) (xy 377.468199 -403.510587) (xy 377.522155 -403.50283) (xy 377.54941 -403.502368)
			(xy 378.41301 -403.502368) (xy 378.440259 -403.502903) (xy 378.494202 -403.51066) (xy 378.546492 -403.526015)
			(xy 378.596065 -403.548655) (xy 378.641911 -403.57812) (xy 378.683098 -403.613809) (xy 378.718786 -403.654997)
			(xy 378.748249 -403.700844) (xy 378.770888 -403.750417) (xy 378.786242 -403.802708) (xy 378.793998 -403.856651)
			(xy 378.793998 -403.911149) (xy 378.793998 -403.911151) (xy 380.231654 -403.911151) (xy 380.231654 -403.856649)
			(xy 380.239409 -403.802703) (xy 380.254763 -403.750409) (xy 380.277402 -403.700832) (xy 380.306865 -403.654981)
			(xy 380.342554 -403.613789) (xy 380.383741 -403.578095) (xy 380.429588 -403.548626) (xy 380.479162 -403.52598)
			(xy 380.531454 -403.51062) (xy 380.585399 -403.502857) (xy 380.61265 -403.502368) (xy 381.47625 -403.502368)
			(xy 381.503503 -403.502876) (xy 381.557456 -403.510627) (xy 381.609757 -403.525977) (xy 381.65934 -403.548616)
			(xy 381.705197 -403.57808) (xy 381.746393 -403.613772) (xy 381.78209 -403.654963) (xy 381.81156 -403.700816)
			(xy 381.834205 -403.750396) (xy 381.849563 -403.802695) (xy 381.857321 -403.856647) (xy 381.857321 -403.911153)
			(xy 383.294854 -403.911153) (xy 383.294854 -403.856647) (xy 383.302611 -403.802697) (xy 383.317966 -403.7504)
			(xy 383.340608 -403.70082) (xy 383.370075 -403.654968) (xy 383.405768 -403.613775) (xy 383.44696 -403.578081)
			(xy 383.492812 -403.548613) (xy 383.542391 -403.52597) (xy 383.594687 -403.510613) (xy 383.648638 -403.502855)
			(xy 383.67589 -403.502368) (xy 384.53949 -403.502368) (xy 384.566742 -403.502879) (xy 384.62069 -403.510634)
			(xy 384.672986 -403.525988) (xy 384.722564 -403.548629) (xy 384.768416 -403.578095) (xy 384.809607 -403.613786)
			(xy 384.845299 -403.654976) (xy 384.874767 -403.700827) (xy 384.897408 -403.750405) (xy 384.912764 -403.8027)
			(xy 384.920521 -403.856648) (xy 384.920521 -403.911152) (xy 384.92052 -403.911156) (xy 386.358031 -403.911156)
			(xy 386.358031 -403.856644) (xy 386.365789 -403.802687) (xy 386.381148 -403.750383) (xy 386.403794 -403.700798)
			(xy 386.433267 -403.654941) (xy 386.468966 -403.613745) (xy 386.510165 -403.578049) (xy 386.556024 -403.54858)
			(xy 386.605612 -403.525937) (xy 386.657916 -403.510583) (xy 386.711874 -403.502829) (xy 386.73913 -403.502368)
			(xy 387.60273 -403.502368) (xy 387.629978 -403.502904) (xy 387.683919 -403.510664) (xy 387.736207 -403.52602)
			(xy 387.785777 -403.548662) (xy 387.831621 -403.578127) (xy 387.872805 -403.613816) (xy 387.908491 -403.655003)
			(xy 387.937953 -403.700849) (xy 387.96059 -403.750421) (xy 387.975943 -403.80271) (xy 387.983698 -403.856652)
			(xy 387.983698 -403.911148) (xy 387.983697 -403.911152) (xy 389.421354 -403.911152) (xy 389.421354 -403.856648)
			(xy 389.42911 -403.8027) (xy 389.444465 -403.750404) (xy 389.467105 -403.700826) (xy 389.49657 -403.654974)
			(xy 389.532261 -403.613782) (xy 389.57345 -403.578088) (xy 389.6193 -403.548619) (xy 389.668876 -403.525975)
			(xy 389.721171 -403.510616) (xy 389.775118 -403.502856) (xy 389.80237 -403.502368) (xy 390.66597 -403.502368)
			(xy 390.693223 -403.502877) (xy 390.747173 -403.51063) (xy 390.799471 -403.525983) (xy 390.849052 -403.548622)
			(xy 390.894906 -403.578087) (xy 390.9361 -403.613779) (xy 390.971795 -403.65497) (xy 391.001264 -403.700821)
			(xy 391.023907 -403.7504) (xy 391.039263 -403.802697) (xy 391.047021 -403.856647) (xy 391.047021 -403.911153)
			(xy 391.047021 -403.911155) (xy 392.484531 -403.911155) (xy 392.484531 -403.856645) (xy 392.492289 -403.80269)
			(xy 392.507646 -403.750388) (xy 392.530291 -403.700804) (xy 392.559762 -403.654947) (xy 392.595459 -403.613752)
			(xy 392.636655 -403.578056) (xy 392.682513 -403.548586) (xy 392.732097 -403.525943) (xy 392.784399 -403.510587)
			(xy 392.838355 -403.50283) (xy 392.86561 -403.502368) (xy 393.72921 -403.502368) (xy 393.756459 -403.502903)
			(xy 393.810402 -403.51066) (xy 393.862692 -403.526015) (xy 393.912265 -403.548655) (xy 393.958111 -403.57812)
			(xy 393.999298 -403.613809) (xy 394.034986 -403.654997) (xy 394.064449 -403.700844) (xy 394.087088 -403.750417)
			(xy 394.102442 -403.802708) (xy 394.110198 -403.856651) (xy 394.110198 -403.911149) (xy 394.110198 -403.911151)
			(xy 395.547854 -403.911151) (xy 395.547854 -403.856649) (xy 395.555609 -403.802703) (xy 395.570963 -403.750409)
			(xy 395.593602 -403.700832) (xy 395.623065 -403.654981) (xy 395.658754 -403.613789) (xy 395.699941 -403.578095)
			(xy 395.745788 -403.548626) (xy 395.795362 -403.52598) (xy 395.847654 -403.51062) (xy 395.901599 -403.502857)
			(xy 395.92885 -403.502368) (xy 396.79245 -403.502368) (xy 396.819703 -403.502876) (xy 396.873656 -403.510627)
			(xy 396.925957 -403.525977) (xy 396.97554 -403.548616) (xy 397.021397 -403.57808) (xy 397.062593 -403.613772)
			(xy 397.09829 -403.654963) (xy 397.12776 -403.700816) (xy 397.150405 -403.750396) (xy 397.165763 -403.802695)
			(xy 397.173521 -403.856647) (xy 397.173521 -403.911153) (xy 398.611054 -403.911153) (xy 398.611054 -403.856647)
			(xy 398.618811 -403.802697) (xy 398.634166 -403.7504) (xy 398.656808 -403.70082) (xy 398.686275 -403.654968)
			(xy 398.721968 -403.613775) (xy 398.76316 -403.578081) (xy 398.809012 -403.548613) (xy 398.858591 -403.52597)
			(xy 398.910887 -403.510613) (xy 398.964838 -403.502855) (xy 398.99209 -403.502368) (xy 399.85569 -403.502368)
			(xy 399.882942 -403.502879) (xy 399.93689 -403.510634) (xy 399.989186 -403.525988) (xy 400.038764 -403.548629)
			(xy 400.084616 -403.578095) (xy 400.125807 -403.613786) (xy 400.161499 -403.654976) (xy 400.190967 -403.700827)
			(xy 400.213608 -403.750405) (xy 400.228964 -403.8027) (xy 400.236721 -403.856648) (xy 400.236721 -403.911152)
			(xy 400.23672 -403.911156) (xy 401.674231 -403.911156) (xy 401.674231 -403.856644) (xy 401.681989 -403.802687)
			(xy 401.697348 -403.750383) (xy 401.719994 -403.700798) (xy 401.749467 -403.654941) (xy 401.785166 -403.613745)
			(xy 401.826365 -403.578049) (xy 401.872224 -403.54858) (xy 401.921812 -403.525937) (xy 401.974116 -403.510583)
			(xy 402.028074 -403.502829) (xy 402.05533 -403.502368) (xy 402.91893 -403.502368) (xy 402.946178 -403.502904)
			(xy 403.000119 -403.510664) (xy 403.052407 -403.52602) (xy 403.101977 -403.548662) (xy 403.147821 -403.578127)
			(xy 403.189005 -403.613816) (xy 403.224691 -403.655003) (xy 403.254153 -403.700849) (xy 403.27679 -403.750421)
			(xy 403.292143 -403.80271) (xy 403.299898 -403.856652) (xy 403.299898 -403.911148) (xy 403.299897 -403.911152)
			(xy 404.737554 -403.911152) (xy 404.737554 -403.856648) (xy 404.74531 -403.8027) (xy 404.760665 -403.750404)
			(xy 404.783305 -403.700826) (xy 404.81277 -403.654974) (xy 404.848461 -403.613782) (xy 404.88965 -403.578088)
			(xy 404.9355 -403.548619) (xy 404.985076 -403.525975) (xy 405.037371 -403.510616) (xy 405.091318 -403.502856)
			(xy 405.11857 -403.502368) (xy 405.98217 -403.502368) (xy 406.009423 -403.502877) (xy 406.063373 -403.51063)
			(xy 406.115671 -403.525983) (xy 406.165252 -403.548622) (xy 406.211106 -403.578087) (xy 406.2523 -403.613779)
			(xy 406.287995 -403.65497) (xy 406.317464 -403.700821) (xy 406.340107 -403.7504) (xy 406.355463 -403.802697)
			(xy 406.363221 -403.856647) (xy 406.363221 -403.911153) (xy 406.363221 -403.911155) (xy 407.800731 -403.911155)
			(xy 407.800731 -403.856645) (xy 407.808489 -403.80269) (xy 407.823846 -403.750388) (xy 407.846491 -403.700804)
			(xy 407.875962 -403.654947) (xy 407.911659 -403.613752) (xy 407.952855 -403.578056) (xy 407.998713 -403.548586)
			(xy 408.048297 -403.525943) (xy 408.100599 -403.510587) (xy 408.154555 -403.50283) (xy 408.18181 -403.502368)
			(xy 409.04541 -403.502368) (xy 409.072659 -403.502903) (xy 409.126602 -403.51066) (xy 409.178892 -403.526015)
			(xy 409.228465 -403.548655) (xy 409.274311 -403.57812) (xy 409.315498 -403.613809) (xy 409.351186 -403.654997)
			(xy 409.380649 -403.700844) (xy 409.403288 -403.750417) (xy 409.418642 -403.802708) (xy 409.426398 -403.856651)
			(xy 409.426398 -403.911149) (xy 409.426398 -403.911151) (xy 410.864054 -403.911151) (xy 410.864054 -403.856649)
			(xy 410.871809 -403.802703) (xy 410.887163 -403.750409) (xy 410.909802 -403.700832) (xy 410.939265 -403.654981)
			(xy 410.974954 -403.613789) (xy 411.016141 -403.578095) (xy 411.061988 -403.548626) (xy 411.111562 -403.52598)
			(xy 411.163854 -403.51062) (xy 411.217799 -403.502857) (xy 411.24505 -403.502368) (xy 412.10865 -403.502368)
			(xy 412.135903 -403.502876) (xy 412.189856 -403.510627) (xy 412.242157 -403.525977) (xy 412.29174 -403.548616)
			(xy 412.337597 -403.57808) (xy 412.378793 -403.613772) (xy 412.41449 -403.654963) (xy 412.44396 -403.700816)
			(xy 412.466605 -403.750396) (xy 412.481963 -403.802695) (xy 412.489721 -403.856647) (xy 412.489721 -403.911153)
			(xy 413.927254 -403.911153) (xy 413.927254 -403.856647) (xy 413.935011 -403.802697) (xy 413.950366 -403.7504)
			(xy 413.973008 -403.70082) (xy 414.002475 -403.654968) (xy 414.038168 -403.613775) (xy 414.07936 -403.578081)
			(xy 414.125212 -403.548613) (xy 414.174791 -403.52597) (xy 414.227087 -403.510613) (xy 414.281038 -403.502855)
			(xy 414.30829 -403.502368) (xy 415.17189 -403.502368) (xy 415.199142 -403.502879) (xy 415.25309 -403.510634)
			(xy 415.305386 -403.525988) (xy 415.354964 -403.548629) (xy 415.400816 -403.578095) (xy 415.442007 -403.613786)
			(xy 415.477699 -403.654976) (xy 415.507167 -403.700827) (xy 415.529808 -403.750405) (xy 415.545164 -403.8027)
			(xy 415.552921 -403.856648) (xy 415.552921 -403.911152) (xy 415.55292 -403.911156) (xy 416.990431 -403.911156)
			(xy 416.990431 -403.856644) (xy 416.998189 -403.802687) (xy 417.013548 -403.750383) (xy 417.036194 -403.700798)
			(xy 417.065667 -403.654941) (xy 417.101366 -403.613745) (xy 417.142565 -403.578049) (xy 417.188424 -403.54858)
			(xy 417.238012 -403.525937) (xy 417.290316 -403.510583) (xy 417.344274 -403.502829) (xy 417.37153 -403.502368)
			(xy 418.23513 -403.502368) (xy 418.262378 -403.502904) (xy 418.316319 -403.510664) (xy 418.368607 -403.52602)
			(xy 418.418177 -403.548662) (xy 418.464021 -403.578127) (xy 418.505205 -403.613816) (xy 418.540891 -403.655003)
			(xy 418.570353 -403.700849) (xy 418.59299 -403.750421) (xy 418.608343 -403.80271) (xy 418.616098 -403.856652)
			(xy 418.616098 -403.911148) (xy 418.608343 -403.96509) (xy 418.59299 -404.017379) (xy 418.570353 -404.066951)
			(xy 418.540891 -404.112797) (xy 418.505205 -404.153984) (xy 418.464021 -404.189673) (xy 418.418177 -404.219138)
			(xy 418.368607 -404.24178) (xy 418.316319 -404.257136) (xy 418.262378 -404.264896) (xy 418.23513 -404.265384)
			(xy 417.37153 -404.265384) (xy 417.344274 -404.264971) (xy 417.290316 -404.257217) (xy 417.238012 -404.241863)
			(xy 417.188424 -404.21922) (xy 417.142565 -404.189751) (xy 417.101366 -404.154055) (xy 417.065667 -404.112859)
			(xy 417.036194 -404.067002) (xy 417.013548 -404.017417) (xy 416.998189 -403.965113) (xy 416.990431 -403.911156)
			(xy 415.55292 -403.911156) (xy 415.545164 -403.9651) (xy 415.529808 -404.017395) (xy 415.507167 -404.066973)
			(xy 415.477699 -404.112824) (xy 415.442007 -404.154014) (xy 415.400816 -404.189705) (xy 415.354964 -404.219171)
			(xy 415.305386 -404.241812) (xy 415.25309 -404.257166) (xy 415.199142 -404.264921) (xy 415.17189 -404.265384)
			(xy 414.30829 -404.265384) (xy 414.281038 -404.264945) (xy 414.227087 -404.257187) (xy 414.174791 -404.24183)
			(xy 414.125212 -404.219187) (xy 414.07936 -404.189719) (xy 414.038168 -404.154025) (xy 414.002475 -404.112832)
			(xy 413.973008 -404.06698) (xy 413.950366 -404.0174) (xy 413.935011 -403.965103) (xy 413.927254 -403.911153)
			(xy 412.489721 -403.911153) (xy 412.481963 -403.965105) (xy 412.466605 -404.017404) (xy 412.44396 -404.066984)
			(xy 412.41449 -404.112837) (xy 412.378793 -404.154028) (xy 412.337597 -404.18972) (xy 412.29174 -404.219184)
			(xy 412.242157 -404.241823) (xy 412.189856 -404.257173) (xy 412.135903 -404.264924) (xy 412.10865 -404.265384)
			(xy 411.24505 -404.265384) (xy 411.217799 -404.264943) (xy 411.163854 -404.25718) (xy 411.111562 -404.24182)
			(xy 411.061988 -404.219174) (xy 411.016141 -404.189705) (xy 410.974954 -404.154011) (xy 410.939265 -404.112819)
			(xy 410.909802 -404.066968) (xy 410.887163 -404.017391) (xy 410.871809 -403.965097) (xy 410.864054 -403.911151)
			(xy 409.426398 -403.911151) (xy 409.418642 -403.965092) (xy 409.403288 -404.017383) (xy 409.380649 -404.066956)
			(xy 409.351186 -404.112803) (xy 409.315498 -404.153991) (xy 409.274311 -404.18968) (xy 409.228465 -404.219145)
			(xy 409.178892 -404.241785) (xy 409.126602 -404.25714) (xy 409.072659 -404.264897) (xy 409.04541 -404.265384)
			(xy 408.18181 -404.265384) (xy 408.154555 -404.26497) (xy 408.100599 -404.257213) (xy 408.048297 -404.241857)
			(xy 407.998713 -404.219214) (xy 407.952855 -404.189744) (xy 407.911659 -404.154048) (xy 407.875962 -404.112853)
			(xy 407.846491 -404.066996) (xy 407.823846 -404.017412) (xy 407.808489 -403.96511) (xy 407.800731 -403.911155)
			(xy 406.363221 -403.911155) (xy 406.355463 -403.965103) (xy 406.340107 -404.0174) (xy 406.317464 -404.066979)
			(xy 406.287995 -404.11283) (xy 406.2523 -404.154021) (xy 406.211106 -404.189713) (xy 406.165252 -404.219178)
			(xy 406.115671 -404.241817) (xy 406.063373 -404.25717) (xy 406.009423 -404.264923) (xy 405.98217 -404.265384)
			(xy 405.11857 -404.265384) (xy 405.091318 -404.264944) (xy 405.037371 -404.257184) (xy 404.985076 -404.241825)
			(xy 404.9355 -404.219181) (xy 404.88965 -404.189712) (xy 404.848461 -404.154018) (xy 404.81277 -404.112826)
			(xy 404.783305 -404.066974) (xy 404.760665 -404.017396) (xy 404.74531 -403.9651) (xy 404.737554 -403.911152)
			(xy 403.299897 -403.911152) (xy 403.292143 -403.96509) (xy 403.27679 -404.017379) (xy 403.254153 -404.066951)
			(xy 403.224691 -404.112797) (xy 403.189005 -404.153984) (xy 403.147821 -404.189673) (xy 403.101977 -404.219138)
			(xy 403.052407 -404.24178) (xy 403.000119 -404.257136) (xy 402.946178 -404.264896) (xy 402.91893 -404.265384)
			(xy 402.05533 -404.265384) (xy 402.028074 -404.264971) (xy 401.974116 -404.257217) (xy 401.921812 -404.241863)
			(xy 401.872224 -404.21922) (xy 401.826365 -404.189751) (xy 401.785166 -404.154055) (xy 401.749467 -404.112859)
			(xy 401.719994 -404.067002) (xy 401.697348 -404.017417) (xy 401.681989 -403.965113) (xy 401.674231 -403.911156)
			(xy 400.23672 -403.911156) (xy 400.228964 -403.9651) (xy 400.213608 -404.017395) (xy 400.190967 -404.066973)
			(xy 400.161499 -404.112824) (xy 400.125807 -404.154014) (xy 400.084616 -404.189705) (xy 400.038764 -404.219171)
			(xy 399.989186 -404.241812) (xy 399.93689 -404.257166) (xy 399.882942 -404.264921) (xy 399.85569 -404.265384)
			(xy 398.99209 -404.265384) (xy 398.964838 -404.264945) (xy 398.910887 -404.257187) (xy 398.858591 -404.24183)
			(xy 398.809012 -404.219187) (xy 398.76316 -404.189719) (xy 398.721968 -404.154025) (xy 398.686275 -404.112832)
			(xy 398.656808 -404.06698) (xy 398.634166 -404.0174) (xy 398.618811 -403.965103) (xy 398.611054 -403.911153)
			(xy 397.173521 -403.911153) (xy 397.165763 -403.965105) (xy 397.150405 -404.017404) (xy 397.12776 -404.066984)
			(xy 397.09829 -404.112837) (xy 397.062593 -404.154028) (xy 397.021397 -404.18972) (xy 396.97554 -404.219184)
			(xy 396.925957 -404.241823) (xy 396.873656 -404.257173) (xy 396.819703 -404.264924) (xy 396.79245 -404.265384)
			(xy 395.92885 -404.265384) (xy 395.901599 -404.264943) (xy 395.847654 -404.25718) (xy 395.795362 -404.24182)
			(xy 395.745788 -404.219174) (xy 395.699941 -404.189705) (xy 395.658754 -404.154011) (xy 395.623065 -404.112819)
			(xy 395.593602 -404.066968) (xy 395.570963 -404.017391) (xy 395.555609 -403.965097) (xy 395.547854 -403.911151)
			(xy 394.110198 -403.911151) (xy 394.102442 -403.965092) (xy 394.087088 -404.017383) (xy 394.064449 -404.066956)
			(xy 394.034986 -404.112803) (xy 393.999298 -404.153991) (xy 393.958111 -404.18968) (xy 393.912265 -404.219145)
			(xy 393.862692 -404.241785) (xy 393.810402 -404.25714) (xy 393.756459 -404.264897) (xy 393.72921 -404.265384)
			(xy 392.86561 -404.265384) (xy 392.838355 -404.26497) (xy 392.784399 -404.257213) (xy 392.732097 -404.241857)
			(xy 392.682513 -404.219214) (xy 392.636655 -404.189744) (xy 392.595459 -404.154048) (xy 392.559762 -404.112853)
			(xy 392.530291 -404.066996) (xy 392.507646 -404.017412) (xy 392.492289 -403.96511) (xy 392.484531 -403.911155)
			(xy 391.047021 -403.911155) (xy 391.039263 -403.965103) (xy 391.023907 -404.0174) (xy 391.001264 -404.066979)
			(xy 390.971795 -404.11283) (xy 390.9361 -404.154021) (xy 390.894906 -404.189713) (xy 390.849052 -404.219178)
			(xy 390.799471 -404.241817) (xy 390.747173 -404.25717) (xy 390.693223 -404.264923) (xy 390.66597 -404.265384)
			(xy 389.80237 -404.265384) (xy 389.775118 -404.264944) (xy 389.721171 -404.257184) (xy 389.668876 -404.241825)
			(xy 389.6193 -404.219181) (xy 389.57345 -404.189712) (xy 389.532261 -404.154018) (xy 389.49657 -404.112826)
			(xy 389.467105 -404.066974) (xy 389.444465 -404.017396) (xy 389.42911 -403.9651) (xy 389.421354 -403.911152)
			(xy 387.983697 -403.911152) (xy 387.975943 -403.96509) (xy 387.96059 -404.017379) (xy 387.937953 -404.066951)
			(xy 387.908491 -404.112797) (xy 387.872805 -404.153984) (xy 387.831621 -404.189673) (xy 387.785777 -404.219138)
			(xy 387.736207 -404.24178) (xy 387.683919 -404.257136) (xy 387.629978 -404.264896) (xy 387.60273 -404.265384)
			(xy 386.73913 -404.265384) (xy 386.711874 -404.264971) (xy 386.657916 -404.257217) (xy 386.605612 -404.241863)
			(xy 386.556024 -404.21922) (xy 386.510165 -404.189751) (xy 386.468966 -404.154055) (xy 386.433267 -404.112859)
			(xy 386.403794 -404.067002) (xy 386.381148 -404.017417) (xy 386.365789 -403.965113) (xy 386.358031 -403.911156)
			(xy 384.92052 -403.911156) (xy 384.912764 -403.9651) (xy 384.897408 -404.017395) (xy 384.874767 -404.066973)
			(xy 384.845299 -404.112824) (xy 384.809607 -404.154014) (xy 384.768416 -404.189705) (xy 384.722564 -404.219171)
			(xy 384.672986 -404.241812) (xy 384.62069 -404.257166) (xy 384.566742 -404.264921) (xy 384.53949 -404.265384)
			(xy 383.67589 -404.265384) (xy 383.648638 -404.264945) (xy 383.594687 -404.257187) (xy 383.542391 -404.24183)
			(xy 383.492812 -404.219187) (xy 383.44696 -404.189719) (xy 383.405768 -404.154025) (xy 383.370075 -404.112832)
			(xy 383.340608 -404.06698) (xy 383.317966 -404.0174) (xy 383.302611 -403.965103) (xy 383.294854 -403.911153)
			(xy 381.857321 -403.911153) (xy 381.849563 -403.965105) (xy 381.834205 -404.017404) (xy 381.81156 -404.066984)
			(xy 381.78209 -404.112837) (xy 381.746393 -404.154028) (xy 381.705197 -404.18972) (xy 381.65934 -404.219184)
			(xy 381.609757 -404.241823) (xy 381.557456 -404.257173) (xy 381.503503 -404.264924) (xy 381.47625 -404.265384)
			(xy 380.61265 -404.265384) (xy 380.585399 -404.264943) (xy 380.531454 -404.25718) (xy 380.479162 -404.24182)
			(xy 380.429588 -404.219174) (xy 380.383741 -404.189705) (xy 380.342554 -404.154011) (xy 380.306865 -404.112819)
			(xy 380.277402 -404.066968) (xy 380.254763 -404.017391) (xy 380.239409 -403.965097) (xy 380.231654 -403.911151)
			(xy 378.793998 -403.911151) (xy 378.786242 -403.965092) (xy 378.770888 -404.017383) (xy 378.748249 -404.066956)
			(xy 378.718786 -404.112803) (xy 378.683098 -404.153991) (xy 378.641911 -404.18968) (xy 378.596065 -404.219145)
			(xy 378.546492 -404.241785) (xy 378.494202 -404.25714) (xy 378.440259 -404.264897) (xy 378.41301 -404.265384)
			(xy 377.54941 -404.265384) (xy 377.522155 -404.26497) (xy 377.468199 -404.257213) (xy 377.415897 -404.241857)
			(xy 377.366313 -404.219214) (xy 377.320455 -404.189744) (xy 377.279259 -404.154048) (xy 377.243562 -404.112853)
			(xy 377.214091 -404.066996) (xy 377.191446 -404.017412) (xy 377.176089 -403.96511) (xy 377.168331 -403.911155)
			(xy 375.730821 -403.911155) (xy 375.723063 -403.965103) (xy 375.707707 -404.0174) (xy 375.685064 -404.066979)
			(xy 375.655595 -404.11283) (xy 375.6199 -404.154021) (xy 375.578706 -404.189713) (xy 375.532852 -404.219178)
			(xy 375.483271 -404.241817) (xy 375.430973 -404.25717) (xy 375.377023 -404.264923) (xy 375.34977 -404.265384)
			(xy 374.48617 -404.265384) (xy 374.458918 -404.264944) (xy 374.404971 -404.257184) (xy 374.352676 -404.241825)
			(xy 374.3031 -404.219181) (xy 374.25725 -404.189712) (xy 374.216061 -404.154018) (xy 374.18037 -404.112826)
			(xy 374.150905 -404.066974) (xy 374.128265 -404.017396) (xy 374.11291 -403.9651) (xy 374.105154 -403.911152)
			(xy 372.667497 -403.911152) (xy 372.659743 -403.96509) (xy 372.64439 -404.017379) (xy 372.621753 -404.066951)
			(xy 372.592291 -404.112797) (xy 372.556605 -404.153984) (xy 372.515421 -404.189673) (xy 372.469577 -404.219138)
			(xy 372.420007 -404.24178) (xy 372.367719 -404.257136) (xy 372.313778 -404.264896) (xy 372.28653 -404.265384)
			(xy 371.42293 -404.265384) (xy 371.395674 -404.264971) (xy 371.341716 -404.257217) (xy 371.289412 -404.241863)
			(xy 371.239824 -404.21922) (xy 371.193965 -404.189751) (xy 371.152766 -404.154055) (xy 371.117067 -404.112859)
			(xy 371.087594 -404.067002) (xy 371.064948 -404.017417) (xy 371.049589 -403.965113) (xy 371.041831 -403.911156)
			(xy 351.17332 -403.911156) (xy 351.165564 -403.9651) (xy 351.150208 -404.017396) (xy 351.127566 -404.066974)
			(xy 351.098099 -404.112824) (xy 351.062406 -404.154015) (xy 351.021215 -404.189706) (xy 350.975363 -404.219172)
			(xy 350.925785 -404.241812) (xy 350.873489 -404.257166) (xy 350.81954 -404.264922) (xy 350.792288 -404.265384)
			(xy 349.928688 -404.265384) (xy 349.901436 -404.264945) (xy 349.847486 -404.257187) (xy 349.795189 -404.24183)
			(xy 349.74561 -404.219187) (xy 349.699759 -404.189718) (xy 349.658567 -404.154024) (xy 349.622875 -404.112832)
			(xy 349.593408 -404.066979) (xy 349.570766 -404.0174) (xy 349.55541 -403.965102) (xy 349.547654 -403.911152)
			(xy 348.109997 -403.911152) (xy 348.102243 -403.965087) (xy 348.086891 -404.017375) (xy 348.064255 -404.066946)
			(xy 348.034795 -404.112791) (xy 347.999111 -404.153977) (xy 347.957929 -404.189667) (xy 347.912088 -404.219132)
			(xy 347.86252 -404.241775) (xy 347.810234 -404.257133) (xy 347.756295 -404.264895) (xy 347.729048 -404.265384)
			(xy 346.865448 -404.265384) (xy 346.838191 -404.264972) (xy 346.784232 -404.25722) (xy 346.731925 -404.241868)
			(xy 346.682335 -404.219226) (xy 346.636473 -404.189758) (xy 346.595272 -404.154062) (xy 346.559571 -404.112865)
			(xy 346.530097 -404.067007) (xy 346.507449 -404.01742) (xy 346.49209 -403.965115) (xy 346.484331 -403.911157)
			(xy 345.046797 -403.911157) (xy 345.039042 -403.965093) (xy 345.023688 -404.017383) (xy 345.001049 -404.066957)
			(xy 344.971586 -404.112804) (xy 344.935897 -404.153991) (xy 344.89471 -404.189681) (xy 344.848864 -404.219145)
			(xy 344.799291 -404.241785) (xy 344.747001 -404.25714) (xy 344.693057 -404.264897) (xy 344.665808 -404.265384)
			(xy 343.802208 -404.265384) (xy 343.774953 -404.26497) (xy 343.720998 -404.257213) (xy 343.668696 -404.241857)
			(xy 343.619111 -404.219213) (xy 343.573254 -404.189744) (xy 343.532058 -404.154048) (xy 343.496361 -404.112852)
			(xy 343.466891 -404.066996) (xy 343.444246 -404.017412) (xy 343.428889 -403.96511) (xy 343.421131 -403.911155)
			(xy 341.983621 -403.911155) (xy 341.975863 -403.965103) (xy 341.960507 -404.0174) (xy 341.937863 -404.066979)
			(xy 341.908394 -404.112831) (xy 341.872699 -404.154022) (xy 341.831505 -404.189713) (xy 341.785651 -404.219179)
			(xy 341.73607 -404.241818) (xy 341.683772 -404.25717) (xy 341.629821 -404.264923) (xy 341.602568 -404.265384)
			(xy 340.738968 -404.265384) (xy 340.711717 -404.264944) (xy 340.657769 -404.257183) (xy 340.605475 -404.241824)
			(xy 340.555898 -404.21918) (xy 340.510049 -404.189711) (xy 340.46886 -404.154017) (xy 340.43317 -404.112825)
			(xy 340.403705 -404.066974) (xy 340.381064 -404.017395) (xy 340.36571 -403.9651) (xy 340.357954 -403.911152)
			(xy 338.920297 -403.911152) (xy 338.912543 -403.96509) (xy 338.89719 -404.017379) (xy 338.874552 -404.066951)
			(xy 338.84509 -404.112798) (xy 338.809404 -404.153984) (xy 338.76822 -404.189674) (xy 338.722376 -404.219139)
			(xy 338.672805 -404.24178) (xy 338.620517 -404.257137) (xy 338.566576 -404.264896) (xy 338.539328 -404.265384)
			(xy 337.675728 -404.265384) (xy 337.648472 -404.264971) (xy 337.594515 -404.257217) (xy 337.54221 -404.241862)
			(xy 337.492623 -404.21922) (xy 337.446764 -404.189751) (xy 337.405565 -404.154055) (xy 337.369866 -404.112859)
			(xy 337.340394 -404.067001) (xy 337.317748 -404.017416) (xy 337.302389 -403.965113) (xy 337.294631 -403.911156)
			(xy 335.85712 -403.911156) (xy 335.849364 -403.9651) (xy 335.834008 -404.017396) (xy 335.811366 -404.066974)
			(xy 335.781899 -404.112824) (xy 335.746206 -404.154015) (xy 335.705015 -404.189706) (xy 335.659163 -404.219172)
			(xy 335.609585 -404.241812) (xy 335.557289 -404.257166) (xy 335.50334 -404.264922) (xy 335.476088 -404.265384)
			(xy 334.612488 -404.265384) (xy 334.585236 -404.264945) (xy 334.531286 -404.257187) (xy 334.478989 -404.24183)
			(xy 334.42941 -404.219187) (xy 334.383559 -404.189718) (xy 334.342367 -404.154024) (xy 334.306675 -404.112832)
			(xy 334.277208 -404.066979) (xy 334.254566 -404.0174) (xy 334.23921 -403.965102) (xy 334.231454 -403.911152)
			(xy 332.793797 -403.911152) (xy 332.786043 -403.965087) (xy 332.770691 -404.017375) (xy 332.748055 -404.066946)
			(xy 332.718595 -404.112791) (xy 332.682911 -404.153977) (xy 332.641729 -404.189667) (xy 332.595888 -404.219132)
			(xy 332.54632 -404.241775) (xy 332.494034 -404.257133) (xy 332.440095 -404.264895) (xy 332.412848 -404.265384)
			(xy 331.549248 -404.265384) (xy 331.521991 -404.264972) (xy 331.468032 -404.25722) (xy 331.415725 -404.241868)
			(xy 331.366135 -404.219226) (xy 331.320273 -404.189758) (xy 331.279072 -404.154062) (xy 331.243371 -404.112865)
			(xy 331.213897 -404.067007) (xy 331.191249 -404.01742) (xy 331.17589 -403.965115) (xy 331.168131 -403.911157)
			(xy 329.730597 -403.911157) (xy 329.722842 -403.965093) (xy 329.707488 -404.017383) (xy 329.684849 -404.066957)
			(xy 329.655386 -404.112804) (xy 329.619697 -404.153991) (xy 329.57851 -404.189681) (xy 329.532664 -404.219145)
			(xy 329.483091 -404.241785) (xy 329.430801 -404.25714) (xy 329.376857 -404.264897) (xy 329.349608 -404.265384)
			(xy 328.486008 -404.265384) (xy 328.458753 -404.26497) (xy 328.404798 -404.257213) (xy 328.352496 -404.241857)
			(xy 328.302911 -404.219213) (xy 328.257054 -404.189744) (xy 328.215858 -404.154048) (xy 328.180161 -404.112852)
			(xy 328.150691 -404.066996) (xy 328.128046 -404.017412) (xy 328.112689 -403.96511) (xy 328.104931 -403.911155)
			(xy 326.667421 -403.911155) (xy 326.659663 -403.965103) (xy 326.644307 -404.0174) (xy 326.621663 -404.066979)
			(xy 326.592194 -404.112831) (xy 326.556499 -404.154022) (xy 326.515305 -404.189713) (xy 326.469451 -404.219179)
			(xy 326.41987 -404.241818) (xy 326.367572 -404.25717) (xy 326.313621 -404.264923) (xy 326.286368 -404.265384)
			(xy 325.422768 -404.265384) (xy 325.395517 -404.264944) (xy 325.341569 -404.257183) (xy 325.289275 -404.241824)
			(xy 325.239698 -404.21918) (xy 325.193849 -404.189711) (xy 325.15266 -404.154017) (xy 325.11697 -404.112825)
			(xy 325.087505 -404.066974) (xy 325.064864 -404.017395) (xy 325.04951 -403.9651) (xy 325.041754 -403.911152)
			(xy 323.604097 -403.911152) (xy 323.596343 -403.96509) (xy 323.58099 -404.017379) (xy 323.558352 -404.066951)
			(xy 323.52889 -404.112798) (xy 323.493204 -404.153984) (xy 323.45202 -404.189674) (xy 323.406176 -404.219139)
			(xy 323.356605 -404.24178) (xy 323.304317 -404.257137) (xy 323.250376 -404.264896) (xy 323.223128 -404.265384)
			(xy 322.359528 -404.265384) (xy 322.332272 -404.264971) (xy 322.278315 -404.257217) (xy 322.22601 -404.241862)
			(xy 322.176423 -404.21922) (xy 322.130564 -404.189751) (xy 322.089365 -404.154055) (xy 322.053666 -404.112859)
			(xy 322.024194 -404.067001) (xy 322.001548 -404.017416) (xy 321.986189 -403.965113) (xy 321.978431 -403.911156)
			(xy 320.54092 -403.911156) (xy 320.533164 -403.9651) (xy 320.517808 -404.017396) (xy 320.495166 -404.066974)
			(xy 320.465699 -404.112824) (xy 320.430006 -404.154015) (xy 320.388815 -404.189706) (xy 320.342963 -404.219172)
			(xy 320.293385 -404.241812) (xy 320.241089 -404.257166) (xy 320.18714 -404.264922) (xy 320.159888 -404.265384)
			(xy 319.296288 -404.265384) (xy 319.269036 -404.264945) (xy 319.215086 -404.257187) (xy 319.162789 -404.24183)
			(xy 319.11321 -404.219187) (xy 319.067359 -404.189718) (xy 319.026167 -404.154024) (xy 318.990475 -404.112832)
			(xy 318.961008 -404.066979) (xy 318.938366 -404.0174) (xy 318.92301 -403.965102) (xy 318.915254 -403.911152)
			(xy 317.477597 -403.911152) (xy 317.469843 -403.965087) (xy 317.454491 -404.017375) (xy 317.431855 -404.066946)
			(xy 317.402395 -404.112791) (xy 317.366711 -404.153977) (xy 317.325529 -404.189667) (xy 317.279688 -404.219132)
			(xy 317.23012 -404.241775) (xy 317.177834 -404.257133) (xy 317.123895 -404.264895) (xy 317.096648 -404.265384)
			(xy 316.233048 -404.265384) (xy 316.205791 -404.264972) (xy 316.151832 -404.25722) (xy 316.099525 -404.241868)
			(xy 316.049935 -404.219226) (xy 316.004073 -404.189758) (xy 315.962872 -404.154062) (xy 315.927171 -404.112865)
			(xy 315.897697 -404.067007) (xy 315.875049 -404.01742) (xy 315.85969 -403.965115) (xy 315.851931 -403.911157)
			(xy 314.414397 -403.911157) (xy 314.406642 -403.965093) (xy 314.391288 -404.017383) (xy 314.368649 -404.066957)
			(xy 314.339186 -404.112804) (xy 314.303497 -404.153991) (xy 314.26231 -404.189681) (xy 314.216464 -404.219145)
			(xy 314.166891 -404.241785) (xy 314.114601 -404.25714) (xy 314.060657 -404.264897) (xy 314.033408 -404.265384)
			(xy 313.169808 -404.265384) (xy 313.142553 -404.26497) (xy 313.088598 -404.257213) (xy 313.036296 -404.241857)
			(xy 312.986711 -404.219213) (xy 312.940854 -404.189744) (xy 312.899658 -404.154048) (xy 312.863961 -404.112852)
			(xy 312.834491 -404.066996) (xy 312.811846 -404.017412) (xy 312.796489 -403.96511) (xy 312.788731 -403.911155)
			(xy 311.351221 -403.911155) (xy 311.343463 -403.965103) (xy 311.328107 -404.0174) (xy 311.305463 -404.066979)
			(xy 311.275994 -404.112831) (xy 311.240299 -404.154022) (xy 311.199105 -404.189713) (xy 311.153251 -404.219179)
			(xy 311.10367 -404.241818) (xy 311.051372 -404.25717) (xy 310.997421 -404.264923) (xy 310.970168 -404.265384)
			(xy 310.106568 -404.265384) (xy 310.079317 -404.264944) (xy 310.025369 -404.257183) (xy 309.973075 -404.241824)
			(xy 309.923498 -404.21918) (xy 309.877649 -404.189711) (xy 309.83646 -404.154017) (xy 309.80077 -404.112825)
			(xy 309.771305 -404.066974) (xy 309.748664 -404.017395) (xy 309.73331 -403.9651) (xy 309.725554 -403.911152)
			(xy 308.287897 -403.911152) (xy 308.280143 -403.96509) (xy 308.26479 -404.017379) (xy 308.242152 -404.066951)
			(xy 308.21269 -404.112798) (xy 308.177004 -404.153984) (xy 308.13582 -404.189674) (xy 308.089976 -404.219139)
			(xy 308.040405 -404.24178) (xy 307.988117 -404.257137) (xy 307.934176 -404.264896) (xy 307.906928 -404.265384)
			(xy 307.043328 -404.265384) (xy 307.016072 -404.264971) (xy 306.962115 -404.257217) (xy 306.90981 -404.241862)
			(xy 306.860223 -404.21922) (xy 306.814364 -404.189751) (xy 306.773165 -404.154055) (xy 306.737466 -404.112859)
			(xy 306.707994 -404.067001) (xy 306.685348 -404.017416) (xy 306.669989 -403.965113) (xy 306.662231 -403.911156)
			(xy 305.22472 -403.911156) (xy 305.216964 -403.9651) (xy 305.201608 -404.017396) (xy 305.178966 -404.066974)
			(xy 305.149499 -404.112824) (xy 305.113806 -404.154015) (xy 305.072615 -404.189706) (xy 305.026763 -404.219172)
			(xy 304.977185 -404.241812) (xy 304.924889 -404.257166) (xy 304.87094 -404.264922) (xy 304.843688 -404.265384)
			(xy 303.980088 -404.265384) (xy 303.952836 -404.264945) (xy 303.898886 -404.257187) (xy 303.846589 -404.24183)
			(xy 303.79701 -404.219187) (xy 303.751159 -404.189718) (xy 303.709967 -404.154024) (xy 303.674275 -404.112832)
			(xy 303.644808 -404.066979) (xy 303.622166 -404.0174) (xy 303.60681 -403.965102) (xy 303.599054 -403.911152)
			(xy 298.836897 -403.911152) (xy 298.840074 -403.920931) (xy 298.852049 -403.983712) (xy 298.856063 -404.0475)
			(xy 298.852049 -404.111288) (xy 298.840074 -404.174069) (xy 298.820324 -404.234855) (xy 298.793112 -404.292686)
			(xy 298.758866 -404.346651) (xy 298.718128 -404.395898) (xy 298.671538 -404.439652) (xy 298.619832 -404.477221)
			(xy 298.563825 -404.508014) (xy 298.504401 -404.531545) (xy 298.442496 -404.547442) (xy 298.379087 -404.555456)
			(xy 298.34713 -404.55596) (xy 298.346876 -404.55596) (xy 298.315131 -404.555422) (xy 298.252136 -404.547497)
			(xy 298.190616 -404.531797) (xy 298.131527 -404.508566) (xy 298.075787 -404.478166) (xy 298.024261 -404.441069)
			(xy 298.000674 -404.419816) (xy 297.993411 -404.413632) (xy 297.975661 -404.406681) (xy 297.956599 -404.406681)
			(xy 297.938849 -404.413632) (xy 297.931586 -404.419816) (xy 297.908028 -404.441107) (xy 297.856512 -404.478235)
			(xy 297.800771 -404.508654) (xy 297.741674 -404.531889) (xy 297.680142 -404.547579) (xy 297.617135 -404.555478)
			(xy 297.585384 -404.55596) (xy 297.58513 -404.55596) (xy 297.553163 -404.555577) (xy 297.489734 -404.547567)
			(xy 297.427809 -404.531671) (xy 297.368364 -404.508138) (xy 297.312338 -404.47734) (xy 297.260613 -404.439763)
			(xy 297.214007 -404.395999) (xy 297.173253 -404.346739) (xy 297.138995 -404.292759) (xy 297.111773 -404.234911)
			(xy 297.092015 -404.174108) (xy 297.080035 -404.111307) (xy 297.07602 -404.0475) (xy 296.316063 -404.0475)
			(xy 296.312049 -404.111288) (xy 296.300074 -404.174069) (xy 296.280324 -404.234855) (xy 296.253112 -404.292686)
			(xy 296.218866 -404.346651) (xy 296.178128 -404.395898) (xy 296.131538 -404.439652) (xy 296.079832 -404.477221)
			(xy 296.023825 -404.508014) (xy 295.964401 -404.531545) (xy 295.902496 -404.547442) (xy 295.839087 -404.555456)
			(xy 295.80713 -404.55596) (xy 295.806876 -404.55596) (xy 295.775131 -404.555422) (xy 295.712136 -404.547497)
			(xy 295.650616 -404.531797) (xy 295.591527 -404.508566) (xy 295.535787 -404.478166) (xy 295.484261 -404.441069)
			(xy 295.460674 -404.419816) (xy 295.453411 -404.413632) (xy 295.435661 -404.406681) (xy 295.416599 -404.406681)
			(xy 295.398849 -404.413632) (xy 295.391586 -404.419816) (xy 295.368028 -404.441107) (xy 295.316512 -404.478235)
			(xy 295.260771 -404.508654) (xy 295.201674 -404.531889) (xy 295.140142 -404.547579) (xy 295.077135 -404.555478)
			(xy 295.045384 -404.55596) (xy 295.04513 -404.55596) (xy 295.013163 -404.555577) (xy 294.949734 -404.547567)
			(xy 294.887809 -404.531671) (xy 294.828364 -404.508138) (xy 294.772338 -404.47734) (xy 294.720613 -404.439763)
			(xy 294.674007 -404.395999) (xy 294.633253 -404.346739) (xy 294.598995 -404.292759) (xy 294.571773 -404.234911)
			(xy 294.552015 -404.174108) (xy 294.540035 -404.111307) (xy 294.53602 -404.0475) (xy 293.926484 -404.0475)
			(xy 293.92247 -404.111293) (xy 293.910493 -404.174079) (xy 293.890741 -404.23487) (xy 293.863525 -404.292705)
			(xy 293.829276 -404.346674) (xy 293.788532 -404.395924) (xy 293.741937 -404.439679) (xy 293.690226 -404.47725)
			(xy 293.634213 -404.508043) (xy 293.574783 -404.531573) (xy 293.512872 -404.547468) (xy 293.449457 -404.555479)
			(xy 293.417498 -404.55596) (xy 293.417244 -404.55596) (xy 293.385498 -404.555442) (xy 293.322502 -404.547512)
			(xy 293.260982 -404.531809) (xy 293.201894 -404.508575) (xy 293.146154 -404.478171) (xy 293.094629 -404.44107)
			(xy 293.071042 -404.419816) (xy 293.063779 -404.413632) (xy 293.046029 -404.406681) (xy 293.026967 -404.406681)
			(xy 293.009217 -404.413632) (xy 293.001954 -404.419816) (xy 292.978367 -404.441074) (xy 292.926858 -404.478206)
			(xy 292.871123 -404.50863) (xy 292.812032 -404.531871) (xy 292.750504 -404.547567) (xy 292.687501 -404.555474)
			(xy 292.655752 -404.55596) (xy 292.655498 -404.55596) (xy 292.623534 -404.555554) (xy 292.56011 -404.547542)
			(xy 292.498191 -404.531643) (xy 292.438752 -404.50811) (xy 292.382731 -404.477312) (xy 292.331013 -404.439736)
			(xy 292.284411 -404.395974) (xy 292.243662 -404.346717) (xy 292.209408 -404.29274) (xy 292.182189 -404.234897)
			(xy 292.162434 -404.174098) (xy 292.150455 -404.111302) (xy 292.146441 -404.0475) (xy 291.386484 -404.0475)
			(xy 291.38247 -404.111293) (xy 291.370493 -404.174079) (xy 291.350741 -404.23487) (xy 291.323525 -404.292705)
			(xy 291.289276 -404.346674) (xy 291.248532 -404.395924) (xy 291.201937 -404.439679) (xy 291.150226 -404.47725)
			(xy 291.094213 -404.508043) (xy 291.034783 -404.531573) (xy 290.972872 -404.547468) (xy 290.909457 -404.555479)
			(xy 290.877498 -404.55596) (xy 290.877244 -404.55596) (xy 290.845498 -404.555442) (xy 290.782502 -404.547512)
			(xy 290.720982 -404.531809) (xy 290.661894 -404.508575) (xy 290.606154 -404.478171) (xy 290.554629 -404.44107)
			(xy 290.531042 -404.419816) (xy 290.523779 -404.413632) (xy 290.506029 -404.406681) (xy 290.486967 -404.406681)
			(xy 290.469217 -404.413632) (xy 290.461954 -404.419816) (xy 290.438367 -404.441074) (xy 290.386858 -404.478206)
			(xy 290.331123 -404.50863) (xy 290.272032 -404.531871) (xy 290.210504 -404.547567) (xy 290.147501 -404.555474)
			(xy 290.115752 -404.55596) (xy 290.115498 -404.55596) (xy 290.083534 -404.555554) (xy 290.02011 -404.547542)
			(xy 289.958191 -404.531643) (xy 289.898752 -404.50811) (xy 289.842731 -404.477312) (xy 289.791013 -404.439736)
			(xy 289.744411 -404.395974) (xy 289.703662 -404.346717) (xy 289.669408 -404.29274) (xy 289.642189 -404.234897)
			(xy 289.622434 -404.174098) (xy 289.610455 -404.111302) (xy 289.606441 -404.0475) (xy 288.846484 -404.0475)
			(xy 288.84247 -404.111293) (xy 288.830493 -404.174079) (xy 288.810741 -404.23487) (xy 288.783525 -404.292705)
			(xy 288.749276 -404.346674) (xy 288.708532 -404.395924) (xy 288.661937 -404.439679) (xy 288.610226 -404.47725)
			(xy 288.554213 -404.508043) (xy 288.494783 -404.531573) (xy 288.432872 -404.547468) (xy 288.369457 -404.555479)
			(xy 288.337498 -404.55596) (xy 288.337244 -404.55596) (xy 288.305498 -404.555442) (xy 288.242502 -404.547512)
			(xy 288.180982 -404.531809) (xy 288.121894 -404.508575) (xy 288.066154 -404.478171) (xy 288.014629 -404.44107)
			(xy 287.991042 -404.419816) (xy 287.983779 -404.413632) (xy 287.966029 -404.406681) (xy 287.946967 -404.406681)
			(xy 287.929217 -404.413632) (xy 287.921954 -404.419816) (xy 287.898367 -404.441074) (xy 287.846858 -404.478206)
			(xy 287.791123 -404.50863) (xy 287.732032 -404.531871) (xy 287.670504 -404.547567) (xy 287.607501 -404.555474)
			(xy 287.575752 -404.55596) (xy 287.575498 -404.55596) (xy 287.543534 -404.555554) (xy 287.48011 -404.547542)
			(xy 287.418191 -404.531643) (xy 287.358752 -404.50811) (xy 287.302731 -404.477312) (xy 287.251013 -404.439736)
			(xy 287.204411 -404.395974) (xy 287.163662 -404.346717) (xy 287.129408 -404.29274) (xy 287.102189 -404.234897)
			(xy 287.082434 -404.174098) (xy 287.070455 -404.111302) (xy 287.066441 -404.0475) (xy 281.686508 -404.0475)
			(xy 281.686508 -405.908764) (xy 281.686046 -405.933715) (xy 281.678225 -405.982999) (xy 281.6628 -406.030457)
			(xy 281.64015 -406.074922) (xy 281.610832 -406.115303) (xy 281.593544 -406.1333) (xy 281.262328 -406.464516)
			(xy 281.244327 -406.4818) (xy 281.203952 -406.511124) (xy 281.159488 -406.533773) (xy 281.112029 -406.549188)
			(xy 281.062742 -406.556992) (xy 281.037792 -406.55748) (xy 278.18334 -406.55748) (xy 278.180546 -406.557734)
			(xy 278.171247 -406.558785) (xy 278.152566 -406.559928) (xy 278.143208 -406.56002) (xy 275.351748 -406.56002)
			(xy 275.326798 -406.559547) (xy 275.277514 -406.551728) (xy 275.230056 -406.536305) (xy 275.185591 -406.513658)
			(xy 275.145209 -406.484343) (xy 275.127212 -406.467056) (xy 275.08835 -406.428194) (xy 275.077488 -406.4181)
			(xy 275.051415 -406.404014) (xy 275.022395 -406.398003) (xy 274.992872 -406.400573) (xy 274.965328 -406.411507)
			(xy 274.94208 -406.429886) (xy 274.925085 -406.454164) (xy 274.919948 -406.468072) (xy 274.906846 -406.505801)
			(xy 274.873042 -406.578165) (xy 274.831055 -406.646108) (xy 274.781453 -406.70871) (xy 274.753578 -406.737312)
			(xy 274.459335 -407.031749) (xy 304.945298 -407.031749) (xy 304.945298 -406.977251) (xy 304.953054 -406.923307)
			(xy 304.968408 -406.871016) (xy 304.991047 -406.821442) (xy 305.02051 -406.775595) (xy 305.056199 -406.734407)
			(xy 305.097385 -406.698718) (xy 305.143232 -406.669252) (xy 305.192805 -406.646612) (xy 305.245095 -406.631257)
			(xy 305.299039 -406.623499) (xy 305.326288 -406.623012) (xy 306.189888 -406.623012) (xy 306.217143 -406.623434)
			(xy 306.271098 -406.63119) (xy 306.3234 -406.646546) (xy 306.372984 -406.669189) (xy 306.418841 -406.698658)
			(xy 306.460038 -406.734354) (xy 306.495735 -406.775549) (xy 306.525205 -406.821405) (xy 306.54785 -406.870989)
			(xy 306.563207 -406.92329) (xy 306.570965 -406.977245) (xy 306.570965 -407.031753) (xy 308.008475 -407.031753)
			(xy 308.008475 -406.977247) (xy 308.016233 -406.923297) (xy 308.031589 -406.870999) (xy 308.054233 -406.82142)
			(xy 308.083702 -406.775568) (xy 308.119397 -406.734377) (xy 308.16059 -406.698685) (xy 308.206445 -406.669219)
			(xy 308.256026 -406.64658) (xy 308.308324 -406.631227) (xy 308.362275 -406.623473) (xy 308.389528 -406.623012)
			(xy 309.253128 -406.623012) (xy 309.280379 -406.62346) (xy 309.334327 -406.63122) (xy 309.386621 -406.646578)
			(xy 309.436197 -406.669222) (xy 309.482047 -406.698691) (xy 309.523236 -406.734384) (xy 309.558926 -406.775576)
			(xy 309.588391 -406.821427) (xy 309.611032 -406.871005) (xy 309.626386 -406.923301) (xy 309.634142 -406.977249)
			(xy 309.634142 -407.031748) (xy 311.071798 -407.031748) (xy 311.071798 -406.977252) (xy 311.079553 -406.92331)
			(xy 311.094906 -406.87102) (xy 311.117544 -406.821448) (xy 311.147005 -406.775601) (xy 311.182692 -406.734414)
			(xy 311.223876 -406.698725) (xy 311.26972 -406.669259) (xy 311.31929 -406.646617) (xy 311.371578 -406.63126)
			(xy 311.42552 -406.6235) (xy 311.452768 -406.623012) (xy 312.316368 -406.623012) (xy 312.343624 -406.623433)
			(xy 312.397581 -406.631186) (xy 312.449886 -406.64654) (xy 312.499472 -406.669182) (xy 312.545332 -406.698651)
			(xy 312.586531 -406.734347) (xy 312.62223 -406.775542) (xy 312.651702 -406.821399) (xy 312.674348 -406.870984)
			(xy 312.689707 -406.923288) (xy 312.697465 -406.977244) (xy 312.697465 -407.031752) (xy 314.134975 -407.031752)
			(xy 314.134975 -406.977248) (xy 314.142732 -406.923299) (xy 314.158088 -406.871004) (xy 314.18073 -406.821426)
			(xy 314.210197 -406.775575) (xy 314.245889 -406.734384) (xy 314.287081 -406.698692) (xy 314.332933 -406.669226)
			(xy 314.382511 -406.646585) (xy 314.434807 -406.63123) (xy 314.488756 -406.623475) (xy 314.516008 -406.623012)
			(xy 315.379608 -406.623012) (xy 315.40686 -406.623458) (xy 315.46081 -406.631216) (xy 315.513107 -406.646573)
			(xy 315.562685 -406.669216) (xy 315.608537 -406.698684) (xy 315.649729 -406.734377) (xy 315.685421 -406.775569)
			(xy 315.714888 -406.821422) (xy 315.73753 -406.871001) (xy 315.752885 -406.923298) (xy 315.760642 -406.977248)
			(xy 315.760642 -407.031752) (xy 315.760642 -407.031754) (xy 317.198175 -407.031754) (xy 317.198175 -406.977246)
			(xy 317.205933 -406.923294) (xy 317.221291 -406.870995) (xy 317.243936 -406.821414) (xy 317.273407 -406.775561)
			(xy 317.309104 -406.73437) (xy 317.3503 -406.698678) (xy 317.396157 -406.669213) (xy 317.44574 -406.646574)
			(xy 317.498041 -406.631223) (xy 317.551994 -406.623472) (xy 317.579248 -406.623012) (xy 318.442848 -406.623012)
			(xy 318.470098 -406.623461) (xy 318.524044 -406.631224) (xy 318.576336 -406.646584) (xy 318.625909 -406.669229)
			(xy 318.671756 -406.698698) (xy 318.712943 -406.734391) (xy 318.748631 -406.775582) (xy 318.778094 -406.821433)
			(xy 318.800733 -406.87101) (xy 318.816087 -406.923303) (xy 318.823842 -406.97725) (xy 318.823842 -407.031749)
			(xy 320.261498 -407.031749) (xy 320.261498 -406.977251) (xy 320.269254 -406.923307) (xy 320.284608 -406.871016)
			(xy 320.307247 -406.821442) (xy 320.33671 -406.775595) (xy 320.372399 -406.734407) (xy 320.413585 -406.698718)
			(xy 320.459432 -406.669252) (xy 320.509005 -406.646612) (xy 320.561295 -406.631257) (xy 320.615239 -406.623499)
			(xy 320.642488 -406.623012) (xy 321.506088 -406.623012) (xy 321.533343 -406.623434) (xy 321.587298 -406.63119)
			(xy 321.6396 -406.646546) (xy 321.689184 -406.669189) (xy 321.735041 -406.698658) (xy 321.776238 -406.734354)
			(xy 321.811935 -406.775549) (xy 321.841405 -406.821405) (xy 321.86405 -406.870989) (xy 321.879407 -406.92329)
			(xy 321.887165 -406.977245) (xy 321.887165 -407.031753) (xy 323.324675 -407.031753) (xy 323.324675 -406.977247)
			(xy 323.332433 -406.923297) (xy 323.347789 -406.870999) (xy 323.370433 -406.82142) (xy 323.399902 -406.775568)
			(xy 323.435597 -406.734377) (xy 323.47679 -406.698685) (xy 323.522645 -406.669219) (xy 323.572226 -406.64658)
			(xy 323.624524 -406.631227) (xy 323.678475 -406.623473) (xy 323.705728 -406.623012) (xy 324.569328 -406.623012)
			(xy 324.596579 -406.62346) (xy 324.650527 -406.63122) (xy 324.702821 -406.646578) (xy 324.752397 -406.669222)
			(xy 324.798247 -406.698691) (xy 324.839436 -406.734384) (xy 324.875126 -406.775576) (xy 324.904591 -406.821427)
			(xy 324.927232 -406.871005) (xy 324.942586 -406.923301) (xy 324.950342 -406.977249) (xy 324.950342 -407.031748)
			(xy 326.387998 -407.031748) (xy 326.387998 -406.977252) (xy 326.395753 -406.92331) (xy 326.411106 -406.87102)
			(xy 326.433744 -406.821448) (xy 326.463205 -406.775601) (xy 326.498892 -406.734414) (xy 326.540076 -406.698725)
			(xy 326.58592 -406.669259) (xy 326.63549 -406.646617) (xy 326.687778 -406.63126) (xy 326.74172 -406.6235)
			(xy 326.768968 -406.623012) (xy 327.632568 -406.623012) (xy 327.659824 -406.623433) (xy 327.713781 -406.631186)
			(xy 327.766086 -406.64654) (xy 327.815672 -406.669182) (xy 327.861532 -406.698651) (xy 327.902731 -406.734347)
			(xy 327.93843 -406.775542) (xy 327.967902 -406.821399) (xy 327.990548 -406.870984) (xy 328.005907 -406.923288)
			(xy 328.013665 -406.977244) (xy 328.013665 -407.031752) (xy 329.451175 -407.031752) (xy 329.451175 -406.977248)
			(xy 329.458932 -406.923299) (xy 329.474288 -406.871004) (xy 329.49693 -406.821426) (xy 329.526397 -406.775575)
			(xy 329.562089 -406.734384) (xy 329.603281 -406.698692) (xy 329.649133 -406.669226) (xy 329.698711 -406.646585)
			(xy 329.751007 -406.63123) (xy 329.804956 -406.623475) (xy 329.832208 -406.623012) (xy 330.695808 -406.623012)
			(xy 330.72306 -406.623458) (xy 330.77701 -406.631216) (xy 330.829307 -406.646573) (xy 330.878885 -406.669216)
			(xy 330.924737 -406.698684) (xy 330.965929 -406.734377) (xy 331.001621 -406.775569) (xy 331.031088 -406.821422)
			(xy 331.05373 -406.871001) (xy 331.069085 -406.923298) (xy 331.076842 -406.977248) (xy 331.076842 -407.031752)
			(xy 331.076842 -407.031754) (xy 332.514375 -407.031754) (xy 332.514375 -406.977246) (xy 332.522133 -406.923294)
			(xy 332.537491 -406.870995) (xy 332.560136 -406.821414) (xy 332.589607 -406.775561) (xy 332.625304 -406.73437)
			(xy 332.6665 -406.698678) (xy 332.712357 -406.669213) (xy 332.76194 -406.646574) (xy 332.814241 -406.631223)
			(xy 332.868194 -406.623472) (xy 332.895448 -406.623012) (xy 333.759048 -406.623012) (xy 333.786298 -406.623461)
			(xy 333.840244 -406.631224) (xy 333.892536 -406.646584) (xy 333.942109 -406.669229) (xy 333.987956 -406.698698)
			(xy 334.029143 -406.734391) (xy 334.064831 -406.775582) (xy 334.094294 -406.821433) (xy 334.116933 -406.87101)
			(xy 334.132287 -406.923303) (xy 334.140042 -406.97725) (xy 334.140042 -407.031749) (xy 335.577698 -407.031749)
			(xy 335.577698 -406.977251) (xy 335.585454 -406.923307) (xy 335.600808 -406.871016) (xy 335.623447 -406.821442)
			(xy 335.65291 -406.775595) (xy 335.688599 -406.734407) (xy 335.729785 -406.698718) (xy 335.775632 -406.669252)
			(xy 335.825205 -406.646612) (xy 335.877495 -406.631257) (xy 335.931439 -406.623499) (xy 335.958688 -406.623012)
			(xy 336.822288 -406.623012) (xy 336.849543 -406.623434) (xy 336.903498 -406.63119) (xy 336.9558 -406.646546)
			(xy 337.005384 -406.669189) (xy 337.051241 -406.698658) (xy 337.092438 -406.734354) (xy 337.128135 -406.775549)
			(xy 337.157605 -406.821405) (xy 337.18025 -406.870989) (xy 337.195607 -406.92329) (xy 337.203365 -406.977245)
			(xy 337.203365 -407.031753) (xy 338.640875 -407.031753) (xy 338.640875 -406.977247) (xy 338.648633 -406.923297)
			(xy 338.663989 -406.870999) (xy 338.686633 -406.82142) (xy 338.716102 -406.775568) (xy 338.751797 -406.734377)
			(xy 338.79299 -406.698685) (xy 338.838845 -406.669219) (xy 338.888426 -406.64658) (xy 338.940724 -406.631227)
			(xy 338.994675 -406.623473) (xy 339.021928 -406.623012) (xy 339.885528 -406.623012) (xy 339.912779 -406.62346)
			(xy 339.966727 -406.63122) (xy 340.019021 -406.646578) (xy 340.068597 -406.669222) (xy 340.114447 -406.698691)
			(xy 340.155636 -406.734384) (xy 340.191326 -406.775576) (xy 340.220791 -406.821427) (xy 340.243432 -406.871005)
			(xy 340.258786 -406.923301) (xy 340.266542 -406.977249) (xy 340.266542 -407.031748) (xy 341.704198 -407.031748)
			(xy 341.704198 -406.977252) (xy 341.711953 -406.92331) (xy 341.727306 -406.87102) (xy 341.749944 -406.821448)
			(xy 341.779405 -406.775601) (xy 341.815092 -406.734414) (xy 341.856276 -406.698725) (xy 341.90212 -406.669259)
			(xy 341.95169 -406.646617) (xy 342.003978 -406.63126) (xy 342.05792 -406.6235) (xy 342.085168 -406.623012)
			(xy 342.948768 -406.623012) (xy 342.976024 -406.623433) (xy 343.029981 -406.631186) (xy 343.082286 -406.64654)
			(xy 343.131872 -406.669182) (xy 343.177732 -406.698651) (xy 343.218931 -406.734347) (xy 343.25463 -406.775542)
			(xy 343.284102 -406.821399) (xy 343.306748 -406.870984) (xy 343.322107 -406.923288) (xy 343.329865 -406.977244)
			(xy 343.329865 -407.031752) (xy 344.767375 -407.031752) (xy 344.767375 -406.977248) (xy 344.775132 -406.923299)
			(xy 344.790488 -406.871004) (xy 344.81313 -406.821426) (xy 344.842597 -406.775575) (xy 344.878289 -406.734384)
			(xy 344.919481 -406.698692) (xy 344.965333 -406.669226) (xy 345.014911 -406.646585) (xy 345.067207 -406.63123)
			(xy 345.121156 -406.623475) (xy 345.148408 -406.623012) (xy 346.012008 -406.623012) (xy 346.03926 -406.623458)
			(xy 346.09321 -406.631216) (xy 346.145507 -406.646573) (xy 346.195085 -406.669216) (xy 346.240937 -406.698684)
			(xy 346.282129 -406.734377) (xy 346.317821 -406.775569) (xy 346.347288 -406.821422) (xy 346.36993 -406.871001)
			(xy 346.385285 -406.923298) (xy 346.393042 -406.977248) (xy 346.393042 -407.031752) (xy 346.393042 -407.031754)
			(xy 347.830575 -407.031754) (xy 347.830575 -406.977246) (xy 347.838333 -406.923294) (xy 347.853691 -406.870995)
			(xy 347.876336 -406.821414) (xy 347.905807 -406.775561) (xy 347.941504 -406.73437) (xy 347.9827 -406.698678)
			(xy 348.028557 -406.669213) (xy 348.07814 -406.646574) (xy 348.130441 -406.631223) (xy 348.184394 -406.623472)
			(xy 348.211648 -406.623012) (xy 349.075248 -406.623012) (xy 349.102498 -406.623461) (xy 349.156444 -406.631224)
			(xy 349.208736 -406.646584) (xy 349.258309 -406.669229) (xy 349.304156 -406.698698) (xy 349.345343 -406.734391)
			(xy 349.381031 -406.775582) (xy 349.410494 -406.821433) (xy 349.433133 -406.87101) (xy 349.448487 -406.923303)
			(xy 349.456242 -406.97725) (xy 349.456242 -407.031749) (xy 350.893898 -407.031749) (xy 350.893898 -406.977251)
			(xy 350.901654 -406.923307) (xy 350.917008 -406.871016) (xy 350.939647 -406.821442) (xy 350.96911 -406.775595)
			(xy 351.004799 -406.734407) (xy 351.045985 -406.698718) (xy 351.091832 -406.669252) (xy 351.141405 -406.646612)
			(xy 351.193695 -406.631257) (xy 351.247639 -406.623499) (xy 351.274888 -406.623012) (xy 352.138488 -406.623012)
			(xy 352.165743 -406.623434) (xy 352.219698 -406.63119) (xy 352.272 -406.646546) (xy 352.321584 -406.669189)
			(xy 352.367441 -406.698658) (xy 352.408638 -406.734354) (xy 352.444335 -406.775549) (xy 352.473805 -406.821405)
			(xy 352.49645 -406.870989) (xy 352.511807 -406.92329) (xy 352.519565 -406.977245) (xy 352.519565 -407.031753)
			(xy 372.388075 -407.031753) (xy 372.388075 -406.977247) (xy 372.395833 -406.923296) (xy 372.411189 -406.870999)
			(xy 372.433833 -406.821419) (xy 372.463302 -406.775567) (xy 372.498997 -406.734376) (xy 372.540191 -406.698684)
			(xy 372.586046 -406.669219) (xy 372.635627 -406.646579) (xy 372.687926 -406.631226) (xy 372.741877 -406.623473)
			(xy 372.76913 -406.623012) (xy 373.63273 -406.623012) (xy 373.659981 -406.62346) (xy 373.713929 -406.63122)
			(xy 373.766222 -406.646579) (xy 373.815799 -406.669223) (xy 373.861648 -406.698691) (xy 373.902836 -406.734385)
			(xy 373.938527 -406.775576) (xy 373.967992 -406.821428) (xy 373.990632 -406.871006) (xy 374.005986 -406.923301)
			(xy 374.013742 -406.977249) (xy 374.013742 -407.031748) (xy 375.451398 -407.031748) (xy 375.451398 -406.977252)
			(xy 375.459153 -406.923309) (xy 375.474506 -406.87102) (xy 375.497144 -406.821447) (xy 375.526606 -406.775601)
			(xy 375.562292 -406.734414) (xy 375.603477 -406.698724) (xy 375.649321 -406.669258) (xy 375.698892 -406.646617)
			(xy 375.75118 -406.63126) (xy 375.805122 -406.6235) (xy 375.83237 -406.623012) (xy 376.69597 -406.623012)
			(xy 376.723226 -406.623433) (xy 376.777183 -406.631187) (xy 376.829487 -406.646541) (xy 376.879074 -406.669183)
			(xy 376.924933 -406.698652) (xy 376.966131 -406.734347) (xy 377.00183 -406.775543) (xy 377.031303 -406.8214)
			(xy 377.053948 -406.870985) (xy 377.069307 -406.923288) (xy 377.077065 -406.977244) (xy 377.077065 -407.031752)
			(xy 378.514575 -407.031752) (xy 378.514575 -406.977248) (xy 378.522332 -406.923299) (xy 378.537688 -406.871003)
			(xy 378.56033 -406.821425) (xy 378.589797 -406.775574) (xy 378.62549 -406.734383) (xy 378.666682 -406.698691)
			(xy 378.712534 -406.669225) (xy 378.762113 -406.646584) (xy 378.814409 -406.63123) (xy 378.868358 -406.623475)
			(xy 378.89561 -406.623012) (xy 379.75921 -406.623012) (xy 379.786462 -406.623459) (xy 379.840412 -406.631217)
			(xy 379.892708 -406.646573) (xy 379.942287 -406.669216) (xy 379.988138 -406.698684) (xy 380.029329 -406.734378)
			(xy 380.065022 -406.77557) (xy 380.094489 -406.821422) (xy 380.11713 -406.871001) (xy 380.132486 -406.923298)
			(xy 380.140242 -406.977248) (xy 380.140242 -407.031748) (xy 381.577898 -407.031748) (xy 381.577898 -406.977252)
			(xy 381.585653 -406.923312) (xy 381.601005 -406.871024) (xy 381.623641 -406.821453) (xy 381.653101 -406.775607)
			(xy 381.688785 -406.734421) (xy 381.729967 -406.698731) (xy 381.775809 -406.669265) (xy 381.825377 -406.646622)
			(xy 381.877663 -406.631264) (xy 381.931603 -406.623502) (xy 381.95885 -406.623012) (xy 382.82245 -406.623012)
			(xy 382.849707 -406.623431) (xy 382.903666 -406.631183) (xy 382.955973 -406.646536) (xy 383.005562 -406.669176)
			(xy 383.051423 -406.698645) (xy 383.092624 -406.73434) (xy 383.128325 -406.775536) (xy 383.1578 -406.821394)
			(xy 383.180447 -406.870981) (xy 383.195806 -406.923285) (xy 383.203565 -406.977243) (xy 383.203565 -407.031749)
			(xy 384.641098 -407.031749) (xy 384.641098 -406.977251) (xy 384.648854 -406.923307) (xy 384.664208 -406.871016)
			(xy 384.686847 -406.821442) (xy 384.716311 -406.775594) (xy 384.751999 -406.734406) (xy 384.793186 -406.698717)
			(xy 384.839033 -406.669252) (xy 384.888606 -406.646611) (xy 384.940897 -406.631256) (xy 384.994841 -406.623499)
			(xy 385.02209 -406.623012) (xy 385.88569 -406.623012) (xy 385.912945 -406.623434) (xy 385.9669 -406.63119)
			(xy 386.019202 -406.646546) (xy 386.068786 -406.66919) (xy 386.114642 -406.698659) (xy 386.155838 -406.734354)
			(xy 386.191535 -406.77555) (xy 386.221006 -406.821406) (xy 386.24365 -406.870989) (xy 386.259007 -406.923291)
			(xy 386.266765 -406.977245) (xy 386.266765 -407.031753) (xy 387.704275 -407.031753) (xy 387.704275 -406.977247)
			(xy 387.712033 -406.923296) (xy 387.727389 -406.870999) (xy 387.750033 -406.821419) (xy 387.779502 -406.775567)
			(xy 387.815197 -406.734376) (xy 387.856391 -406.698684) (xy 387.902246 -406.669219) (xy 387.951827 -406.646579)
			(xy 388.004126 -406.631226) (xy 388.058077 -406.623473) (xy 388.08533 -406.623012) (xy 388.94893 -406.623012)
			(xy 388.976181 -406.62346) (xy 389.030129 -406.63122) (xy 389.082422 -406.646579) (xy 389.131999 -406.669223)
			(xy 389.177848 -406.698691) (xy 389.219036 -406.734385) (xy 389.254727 -406.775576) (xy 389.284192 -406.821428)
			(xy 389.306832 -406.871006) (xy 389.322186 -406.923301) (xy 389.329942 -406.977249) (xy 389.329942 -407.031748)
			(xy 390.767598 -407.031748) (xy 390.767598 -406.977252) (xy 390.775353 -406.923309) (xy 390.790706 -406.87102)
			(xy 390.813344 -406.821447) (xy 390.842806 -406.775601) (xy 390.878492 -406.734414) (xy 390.919677 -406.698724)
			(xy 390.965521 -406.669258) (xy 391.015092 -406.646617) (xy 391.06738 -406.63126) (xy 391.121322 -406.6235)
			(xy 391.14857 -406.623012) (xy 392.01217 -406.623012) (xy 392.039426 -406.623433) (xy 392.093383 -406.631187)
			(xy 392.145687 -406.646541) (xy 392.195274 -406.669183) (xy 392.241133 -406.698652) (xy 392.282331 -406.734347)
			(xy 392.31803 -406.775543) (xy 392.347503 -406.8214) (xy 392.370148 -406.870985) (xy 392.385507 -406.923288)
			(xy 392.393265 -406.977244) (xy 392.393265 -407.031752) (xy 393.830775 -407.031752) (xy 393.830775 -406.977248)
			(xy 393.838532 -406.923299) (xy 393.853888 -406.871003) (xy 393.87653 -406.821425) (xy 393.905997 -406.775574)
			(xy 393.94169 -406.734383) (xy 393.982882 -406.698691) (xy 394.028734 -406.669225) (xy 394.078313 -406.646584)
			(xy 394.130609 -406.63123) (xy 394.184558 -406.623475) (xy 394.21181 -406.623012) (xy 395.07541 -406.623012)
			(xy 395.102662 -406.623459) (xy 395.156612 -406.631217) (xy 395.208908 -406.646573) (xy 395.258487 -406.669216)
			(xy 395.304338 -406.698684) (xy 395.345529 -406.734378) (xy 395.381222 -406.77557) (xy 395.410689 -406.821422)
			(xy 395.43333 -406.871001) (xy 395.448686 -406.923298) (xy 395.456442 -406.977248) (xy 395.456442 -407.031748)
			(xy 396.894098 -407.031748) (xy 396.894098 -406.977252) (xy 396.901853 -406.923312) (xy 396.917205 -406.871024)
			(xy 396.939841 -406.821453) (xy 396.969301 -406.775607) (xy 397.004985 -406.734421) (xy 397.046167 -406.698731)
			(xy 397.092009 -406.669265) (xy 397.141577 -406.646622) (xy 397.193863 -406.631264) (xy 397.247803 -406.623502)
			(xy 397.27505 -406.623012) (xy 398.13865 -406.623012) (xy 398.165907 -406.623431) (xy 398.219866 -406.631183)
			(xy 398.272173 -406.646536) (xy 398.321762 -406.669176) (xy 398.367623 -406.698645) (xy 398.408824 -406.73434)
			(xy 398.444525 -406.775536) (xy 398.474 -406.821394) (xy 398.496647 -406.870981) (xy 398.512006 -406.923285)
			(xy 398.519765 -406.977243) (xy 398.519765 -407.031749) (xy 399.957298 -407.031749) (xy 399.957298 -406.977251)
			(xy 399.965054 -406.923307) (xy 399.980408 -406.871016) (xy 400.003047 -406.821442) (xy 400.032511 -406.775594)
			(xy 400.068199 -406.734406) (xy 400.109386 -406.698717) (xy 400.155233 -406.669252) (xy 400.204806 -406.646611)
			(xy 400.257097 -406.631256) (xy 400.311041 -406.623499) (xy 400.33829 -406.623012) (xy 401.20189 -406.623012)
			(xy 401.229145 -406.623434) (xy 401.2831 -406.63119) (xy 401.335402 -406.646546) (xy 401.384986 -406.66919)
			(xy 401.430842 -406.698659) (xy 401.472038 -406.734354) (xy 401.507735 -406.77555) (xy 401.537206 -406.821406)
			(xy 401.55985 -406.870989) (xy 401.575207 -406.923291) (xy 401.582965 -406.977245) (xy 401.582965 -407.031753)
			(xy 403.020475 -407.031753) (xy 403.020475 -406.977247) (xy 403.028233 -406.923296) (xy 403.043589 -406.870999)
			(xy 403.066233 -406.821419) (xy 403.095702 -406.775567) (xy 403.131397 -406.734376) (xy 403.172591 -406.698684)
			(xy 403.218446 -406.669219) (xy 403.268027 -406.646579) (xy 403.320326 -406.631226) (xy 403.374277 -406.623473)
			(xy 403.40153 -406.623012) (xy 404.26513 -406.623012) (xy 404.292381 -406.62346) (xy 404.346329 -406.63122)
			(xy 404.398622 -406.646579) (xy 404.448199 -406.669223) (xy 404.494048 -406.698691) (xy 404.535236 -406.734385)
			(xy 404.570927 -406.775576) (xy 404.600392 -406.821428) (xy 404.623032 -406.871006) (xy 404.638386 -406.923301)
			(xy 404.646142 -406.977249) (xy 404.646142 -407.031748) (xy 406.083798 -407.031748) (xy 406.083798 -406.977252)
			(xy 406.091553 -406.923309) (xy 406.106906 -406.87102) (xy 406.129544 -406.821447) (xy 406.159006 -406.775601)
			(xy 406.194692 -406.734414) (xy 406.235877 -406.698724) (xy 406.281721 -406.669258) (xy 406.331292 -406.646617)
			(xy 406.38358 -406.63126) (xy 406.437522 -406.6235) (xy 406.46477 -406.623012) (xy 407.32837 -406.623012)
			(xy 407.355626 -406.623433) (xy 407.409583 -406.631187) (xy 407.461887 -406.646541) (xy 407.511474 -406.669183)
			(xy 407.557333 -406.698652) (xy 407.598531 -406.734347) (xy 407.63423 -406.775543) (xy 407.663703 -406.8214)
			(xy 407.686348 -406.870985) (xy 407.701707 -406.923288) (xy 407.709465 -406.977244) (xy 407.709465 -407.031752)
			(xy 409.146975 -407.031752) (xy 409.146975 -406.977248) (xy 409.154732 -406.923299) (xy 409.170088 -406.871003)
			(xy 409.19273 -406.821425) (xy 409.222197 -406.775574) (xy 409.25789 -406.734383) (xy 409.299082 -406.698691)
			(xy 409.344934 -406.669225) (xy 409.394513 -406.646584) (xy 409.446809 -406.63123) (xy 409.500758 -406.623475)
			(xy 409.52801 -406.623012) (xy 410.39161 -406.623012) (xy 410.418862 -406.623459) (xy 410.472812 -406.631217)
			(xy 410.525108 -406.646573) (xy 410.574687 -406.669216) (xy 410.620538 -406.698684) (xy 410.661729 -406.734378)
			(xy 410.697422 -406.77557) (xy 410.726889 -406.821422) (xy 410.74953 -406.871001) (xy 410.764886 -406.923298)
			(xy 410.772642 -406.977248) (xy 410.772642 -407.031748) (xy 412.210298 -407.031748) (xy 412.210298 -406.977252)
			(xy 412.218053 -406.923312) (xy 412.233405 -406.871024) (xy 412.256041 -406.821453) (xy 412.285501 -406.775607)
			(xy 412.321185 -406.734421) (xy 412.362367 -406.698731) (xy 412.408209 -406.669265) (xy 412.457777 -406.646622)
			(xy 412.510063 -406.631264) (xy 412.564003 -406.623502) (xy 412.59125 -406.623012) (xy 413.45485 -406.623012)
			(xy 413.482107 -406.623431) (xy 413.536066 -406.631183) (xy 413.588373 -406.646536) (xy 413.637962 -406.669176)
			(xy 413.683823 -406.698645) (xy 413.725024 -406.73434) (xy 413.760725 -406.775536) (xy 413.7902 -406.821394)
			(xy 413.812847 -406.870981) (xy 413.828206 -406.923285) (xy 413.835965 -406.977243) (xy 413.835965 -407.031749)
			(xy 415.273498 -407.031749) (xy 415.273498 -406.977251) (xy 415.281254 -406.923307) (xy 415.296608 -406.871016)
			(xy 415.319247 -406.821442) (xy 415.348711 -406.775594) (xy 415.384399 -406.734406) (xy 415.425586 -406.698717)
			(xy 415.471433 -406.669252) (xy 415.521006 -406.646611) (xy 415.573297 -406.631256) (xy 415.627241 -406.623499)
			(xy 415.65449 -406.623012) (xy 416.51809 -406.623012) (xy 416.545345 -406.623434) (xy 416.5993 -406.63119)
			(xy 416.651602 -406.646546) (xy 416.701186 -406.66919) (xy 416.747042 -406.698659) (xy 416.788238 -406.734354)
			(xy 416.823935 -406.77555) (xy 416.853406 -406.821406) (xy 416.87605 -406.870989) (xy 416.891407 -406.923291)
			(xy 416.899165 -406.977245) (xy 416.899165 -407.031753) (xy 418.336675 -407.031753) (xy 418.336675 -406.977247)
			(xy 418.344433 -406.923296) (xy 418.359789 -406.870999) (xy 418.382433 -406.821419) (xy 418.411902 -406.775567)
			(xy 418.447597 -406.734376) (xy 418.488791 -406.698684) (xy 418.534646 -406.669219) (xy 418.584227 -406.646579)
			(xy 418.636526 -406.631226) (xy 418.690477 -406.623473) (xy 418.71773 -406.623012) (xy 419.58133 -406.623012)
			(xy 419.608581 -406.62346) (xy 419.662529 -406.63122) (xy 419.714822 -406.646579) (xy 419.764399 -406.669223)
			(xy 419.810248 -406.698691) (xy 419.851436 -406.734385) (xy 419.887127 -406.775576) (xy 419.916592 -406.821428)
			(xy 419.939232 -406.871006) (xy 419.954586 -406.923301) (xy 419.962342 -406.977249) (xy 419.962342 -407.031751)
			(xy 419.954586 -407.085699) (xy 419.939232 -407.137994) (xy 419.916592 -407.187572) (xy 419.887127 -407.233424)
			(xy 419.851436 -407.274615) (xy 419.810248 -407.310309) (xy 419.764399 -407.339777) (xy 419.714822 -407.362421)
			(xy 419.662529 -407.37778) (xy 419.608581 -407.38554) (xy 419.58133 -407.386028) (xy 418.71773 -407.386028)
			(xy 418.690477 -407.385527) (xy 418.636526 -407.377774) (xy 418.584227 -407.362421) (xy 418.534646 -407.339781)
			(xy 418.488791 -407.310316) (xy 418.447597 -407.274624) (xy 418.411902 -407.233433) (xy 418.382433 -407.187581)
			(xy 418.359789 -407.138001) (xy 418.344433 -407.085704) (xy 418.336675 -407.031753) (xy 416.899165 -407.031753)
			(xy 416.899165 -407.031755) (xy 416.891407 -407.085709) (xy 416.87605 -407.138011) (xy 416.853406 -407.187594)
			(xy 416.823935 -407.23345) (xy 416.788238 -407.274646) (xy 416.747042 -407.310341) (xy 416.701186 -407.33981)
			(xy 416.651602 -407.362454) (xy 416.5993 -407.37781) (xy 416.545345 -407.385566) (xy 416.51809 -407.386028)
			(xy 415.65449 -407.386028) (xy 415.627241 -407.385501) (xy 415.573297 -407.377744) (xy 415.521006 -407.362389)
			(xy 415.471433 -407.339748) (xy 415.425586 -407.310283) (xy 415.384399 -407.274594) (xy 415.348711 -407.233406)
			(xy 415.319247 -407.187558) (xy 415.296608 -407.137984) (xy 415.281254 -407.085693) (xy 415.273498 -407.031749)
			(xy 413.835965 -407.031749) (xy 413.835965 -407.031757) (xy 413.828206 -407.085715) (xy 413.812847 -407.138019)
			(xy 413.7902 -407.187606) (xy 413.760725 -407.233464) (xy 413.725024 -407.27466) (xy 413.683823 -407.310355)
			(xy 413.637962 -407.339824) (xy 413.588373 -407.362464) (xy 413.536066 -407.377817) (xy 413.482107 -407.385569)
			(xy 413.45485 -407.386028) (xy 412.59125 -407.386028) (xy 412.564003 -407.385498) (xy 412.510063 -407.377736)
			(xy 412.457777 -407.362378) (xy 412.408209 -407.339735) (xy 412.362367 -407.310269) (xy 412.321185 -407.274579)
			(xy 412.285501 -407.233393) (xy 412.256041 -407.187547) (xy 412.233405 -407.137976) (xy 412.218053 -407.085688)
			(xy 412.210298 -407.031748) (xy 410.772642 -407.031748) (xy 410.772642 -407.031752) (xy 410.764886 -407.085702)
			(xy 410.74953 -407.137999) (xy 410.726889 -407.187578) (xy 410.697422 -407.23343) (xy 410.661729 -407.274622)
			(xy 410.620538 -407.310316) (xy 410.574687 -407.339784) (xy 410.525108 -407.362427) (xy 410.472812 -407.377783)
			(xy 410.418862 -407.385541) (xy 410.39161 -407.386028) (xy 409.52801 -407.386028) (xy 409.500758 -407.385525)
			(xy 409.446809 -407.37777) (xy 409.394513 -407.362416) (xy 409.344934 -407.339775) (xy 409.299082 -407.310309)
			(xy 409.25789 -407.274617) (xy 409.222197 -407.233426) (xy 409.19273 -407.187575) (xy 409.170088 -407.137997)
			(xy 409.154732 -407.085701) (xy 409.146975 -407.031752) (xy 407.709465 -407.031752) (xy 407.709465 -407.031756)
			(xy 407.701707 -407.085712) (xy 407.686348 -407.138015) (xy 407.663703 -407.1876) (xy 407.63423 -407.233457)
			(xy 407.598531 -407.274653) (xy 407.557333 -407.310348) (xy 407.511474 -407.339817) (xy 407.461887 -407.362459)
			(xy 407.409583 -407.377813) (xy 407.355626 -407.385567) (xy 407.32837 -407.386028) (xy 406.46477 -407.386028)
			(xy 406.437522 -407.3855) (xy 406.38358 -407.37774) (xy 406.331292 -407.362383) (xy 406.281721 -407.339742)
			(xy 406.235877 -407.310276) (xy 406.194692 -407.274586) (xy 406.159006 -407.233399) (xy 406.129544 -407.187553)
			(xy 406.106906 -407.13798) (xy 406.091553 -407.085691) (xy 406.083798 -407.031748) (xy 404.646142 -407.031748)
			(xy 404.646142 -407.031751) (xy 404.638386 -407.085699) (xy 404.623032 -407.137994) (xy 404.600392 -407.187572)
			(xy 404.570927 -407.233424) (xy 404.535236 -407.274615) (xy 404.494048 -407.310309) (xy 404.448199 -407.339777)
			(xy 404.398622 -407.362421) (xy 404.346329 -407.37778) (xy 404.292381 -407.38554) (xy 404.26513 -407.386028)
			(xy 403.40153 -407.386028) (xy 403.374277 -407.385527) (xy 403.320326 -407.377774) (xy 403.268027 -407.362421)
			(xy 403.218446 -407.339781) (xy 403.172591 -407.310316) (xy 403.131397 -407.274624) (xy 403.095702 -407.233433)
			(xy 403.066233 -407.187581) (xy 403.043589 -407.138001) (xy 403.028233 -407.085704) (xy 403.020475 -407.031753)
			(xy 401.582965 -407.031753) (xy 401.582965 -407.031755) (xy 401.575207 -407.085709) (xy 401.55985 -407.138011)
			(xy 401.537206 -407.187594) (xy 401.507735 -407.23345) (xy 401.472038 -407.274646) (xy 401.430842 -407.310341)
			(xy 401.384986 -407.33981) (xy 401.335402 -407.362454) (xy 401.2831 -407.37781) (xy 401.229145 -407.385566)
			(xy 401.20189 -407.386028) (xy 400.33829 -407.386028) (xy 400.311041 -407.385501) (xy 400.257097 -407.377744)
			(xy 400.204806 -407.362389) (xy 400.155233 -407.339748) (xy 400.109386 -407.310283) (xy 400.068199 -407.274594)
			(xy 400.032511 -407.233406) (xy 400.003047 -407.187558) (xy 399.980408 -407.137984) (xy 399.965054 -407.085693)
			(xy 399.957298 -407.031749) (xy 398.519765 -407.031749) (xy 398.519765 -407.031757) (xy 398.512006 -407.085715)
			(xy 398.496647 -407.138019) (xy 398.474 -407.187606) (xy 398.444525 -407.233464) (xy 398.408824 -407.27466)
			(xy 398.367623 -407.310355) (xy 398.321762 -407.339824) (xy 398.272173 -407.362464) (xy 398.219866 -407.377817)
			(xy 398.165907 -407.385569) (xy 398.13865 -407.386028) (xy 397.27505 -407.386028) (xy 397.247803 -407.385498)
			(xy 397.193863 -407.377736) (xy 397.141577 -407.362378) (xy 397.092009 -407.339735) (xy 397.046167 -407.310269)
			(xy 397.004985 -407.274579) (xy 396.969301 -407.233393) (xy 396.939841 -407.187547) (xy 396.917205 -407.137976)
			(xy 396.901853 -407.085688) (xy 396.894098 -407.031748) (xy 395.456442 -407.031748) (xy 395.456442 -407.031752)
			(xy 395.448686 -407.085702) (xy 395.43333 -407.137999) (xy 395.410689 -407.187578) (xy 395.381222 -407.23343)
			(xy 395.345529 -407.274622) (xy 395.304338 -407.310316) (xy 395.258487 -407.339784) (xy 395.208908 -407.362427)
			(xy 395.156612 -407.377783) (xy 395.102662 -407.385541) (xy 395.07541 -407.386028) (xy 394.21181 -407.386028)
			(xy 394.184558 -407.385525) (xy 394.130609 -407.37777) (xy 394.078313 -407.362416) (xy 394.028734 -407.339775)
			(xy 393.982882 -407.310309) (xy 393.94169 -407.274617) (xy 393.905997 -407.233426) (xy 393.87653 -407.187575)
			(xy 393.853888 -407.137997) (xy 393.838532 -407.085701) (xy 393.830775 -407.031752) (xy 392.393265 -407.031752)
			(xy 392.393265 -407.031756) (xy 392.385507 -407.085712) (xy 392.370148 -407.138015) (xy 392.347503 -407.1876)
			(xy 392.31803 -407.233457) (xy 392.282331 -407.274653) (xy 392.241133 -407.310348) (xy 392.195274 -407.339817)
			(xy 392.145687 -407.362459) (xy 392.093383 -407.377813) (xy 392.039426 -407.385567) (xy 392.01217 -407.386028)
			(xy 391.14857 -407.386028) (xy 391.121322 -407.3855) (xy 391.06738 -407.37774) (xy 391.015092 -407.362383)
			(xy 390.965521 -407.339742) (xy 390.919677 -407.310276) (xy 390.878492 -407.274586) (xy 390.842806 -407.233399)
			(xy 390.813344 -407.187553) (xy 390.790706 -407.13798) (xy 390.775353 -407.085691) (xy 390.767598 -407.031748)
			(xy 389.329942 -407.031748) (xy 389.329942 -407.031751) (xy 389.322186 -407.085699) (xy 389.306832 -407.137994)
			(xy 389.284192 -407.187572) (xy 389.254727 -407.233424) (xy 389.219036 -407.274615) (xy 389.177848 -407.310309)
			(xy 389.131999 -407.339777) (xy 389.082422 -407.362421) (xy 389.030129 -407.37778) (xy 388.976181 -407.38554)
			(xy 388.94893 -407.386028) (xy 388.08533 -407.386028) (xy 388.058077 -407.385527) (xy 388.004126 -407.377774)
			(xy 387.951827 -407.362421) (xy 387.902246 -407.339781) (xy 387.856391 -407.310316) (xy 387.815197 -407.274624)
			(xy 387.779502 -407.233433) (xy 387.750033 -407.187581) (xy 387.727389 -407.138001) (xy 387.712033 -407.085704)
			(xy 387.704275 -407.031753) (xy 386.266765 -407.031753) (xy 386.266765 -407.031755) (xy 386.259007 -407.085709)
			(xy 386.24365 -407.138011) (xy 386.221006 -407.187594) (xy 386.191535 -407.23345) (xy 386.155838 -407.274646)
			(xy 386.114642 -407.310341) (xy 386.068786 -407.33981) (xy 386.019202 -407.362454) (xy 385.9669 -407.37781)
			(xy 385.912945 -407.385566) (xy 385.88569 -407.386028) (xy 385.02209 -407.386028) (xy 384.994841 -407.385501)
			(xy 384.940897 -407.377744) (xy 384.888606 -407.362389) (xy 384.839033 -407.339748) (xy 384.793186 -407.310283)
			(xy 384.751999 -407.274594) (xy 384.716311 -407.233406) (xy 384.686847 -407.187558) (xy 384.664208 -407.137984)
			(xy 384.648854 -407.085693) (xy 384.641098 -407.031749) (xy 383.203565 -407.031749) (xy 383.203565 -407.031757)
			(xy 383.195806 -407.085715) (xy 383.180447 -407.138019) (xy 383.1578 -407.187606) (xy 383.128325 -407.233464)
			(xy 383.092624 -407.27466) (xy 383.051423 -407.310355) (xy 383.005562 -407.339824) (xy 382.955973 -407.362464)
			(xy 382.903666 -407.377817) (xy 382.849707 -407.385569) (xy 382.82245 -407.386028) (xy 381.95885 -407.386028)
			(xy 381.931603 -407.385498) (xy 381.877663 -407.377736) (xy 381.825377 -407.362378) (xy 381.775809 -407.339735)
			(xy 381.729967 -407.310269) (xy 381.688785 -407.274579) (xy 381.653101 -407.233393) (xy 381.623641 -407.187547)
			(xy 381.601005 -407.137976) (xy 381.585653 -407.085688) (xy 381.577898 -407.031748) (xy 380.140242 -407.031748)
			(xy 380.140242 -407.031752) (xy 380.132486 -407.085702) (xy 380.11713 -407.137999) (xy 380.094489 -407.187578)
			(xy 380.065022 -407.23343) (xy 380.029329 -407.274622) (xy 379.988138 -407.310316) (xy 379.942287 -407.339784)
			(xy 379.892708 -407.362427) (xy 379.840412 -407.377783) (xy 379.786462 -407.385541) (xy 379.75921 -407.386028)
			(xy 378.89561 -407.386028) (xy 378.868358 -407.385525) (xy 378.814409 -407.37777) (xy 378.762113 -407.362416)
			(xy 378.712534 -407.339775) (xy 378.666682 -407.310309) (xy 378.62549 -407.274617) (xy 378.589797 -407.233426)
			(xy 378.56033 -407.187575) (xy 378.537688 -407.137997) (xy 378.522332 -407.085701) (xy 378.514575 -407.031752)
			(xy 377.077065 -407.031752) (xy 377.077065 -407.031756) (xy 377.069307 -407.085712) (xy 377.053948 -407.138015)
			(xy 377.031303 -407.1876) (xy 377.00183 -407.233457) (xy 376.966131 -407.274653) (xy 376.924933 -407.310348)
			(xy 376.879074 -407.339817) (xy 376.829487 -407.362459) (xy 376.777183 -407.377813) (xy 376.723226 -407.385567)
			(xy 376.69597 -407.386028) (xy 375.83237 -407.386028) (xy 375.805122 -407.3855) (xy 375.75118 -407.37774)
			(xy 375.698892 -407.362383) (xy 375.649321 -407.339742) (xy 375.603477 -407.310276) (xy 375.562292 -407.274586)
			(xy 375.526606 -407.233399) (xy 375.497144 -407.187553) (xy 375.474506 -407.13798) (xy 375.459153 -407.085691)
			(xy 375.451398 -407.031748) (xy 374.013742 -407.031748) (xy 374.013742 -407.031751) (xy 374.005986 -407.085699)
			(xy 373.990632 -407.137994) (xy 373.967992 -407.187572) (xy 373.938527 -407.233424) (xy 373.902836 -407.274615)
			(xy 373.861648 -407.310309) (xy 373.815799 -407.339777) (xy 373.766222 -407.362421) (xy 373.713929 -407.37778)
			(xy 373.659981 -407.38554) (xy 373.63273 -407.386028) (xy 372.76913 -407.386028) (xy 372.741877 -407.385527)
			(xy 372.687926 -407.377774) (xy 372.635627 -407.362421) (xy 372.586046 -407.339781) (xy 372.540191 -407.310316)
			(xy 372.498997 -407.274624) (xy 372.463302 -407.233433) (xy 372.433833 -407.187581) (xy 372.411189 -407.138001)
			(xy 372.395833 -407.085704) (xy 372.388075 -407.031753) (xy 352.519565 -407.031753) (xy 352.519565 -407.031755)
			(xy 352.511807 -407.08571) (xy 352.49645 -407.138011) (xy 352.473805 -407.187595) (xy 352.444335 -407.233451)
			(xy 352.408638 -407.274646) (xy 352.367441 -407.310342) (xy 352.321584 -407.339811) (xy 352.272 -407.362454)
			(xy 352.219698 -407.37781) (xy 352.165743 -407.385566) (xy 352.138488 -407.386028) (xy 351.274888 -407.386028)
			(xy 351.247639 -407.385501) (xy 351.193695 -407.377743) (xy 351.141405 -407.362388) (xy 351.091832 -407.339748)
			(xy 351.045985 -407.310282) (xy 351.004799 -407.274593) (xy 350.96911 -407.233405) (xy 350.939647 -407.187558)
			(xy 350.917008 -407.137984) (xy 350.901654 -407.085693) (xy 350.893898 -407.031749) (xy 349.456242 -407.031749)
			(xy 349.456242 -407.03175) (xy 349.448487 -407.085697) (xy 349.433133 -407.137991) (xy 349.410494 -407.187567)
			(xy 349.381031 -407.233418) (xy 349.345343 -407.274609) (xy 349.304156 -407.310302) (xy 349.258309 -407.339771)
			(xy 349.208736 -407.362416) (xy 349.156444 -407.377776) (xy 349.102498 -407.385539) (xy 349.075248 -407.386028)
			(xy 348.211648 -407.386028) (xy 348.184394 -407.385528) (xy 348.130441 -407.377777) (xy 348.07814 -407.362426)
			(xy 348.028557 -407.339787) (xy 347.9827 -407.310322) (xy 347.941504 -407.27463) (xy 347.905807 -407.233439)
			(xy 347.876336 -407.187586) (xy 347.853691 -407.138005) (xy 347.838333 -407.085706) (xy 347.830575 -407.031754)
			(xy 346.393042 -407.031754) (xy 346.385285 -407.085702) (xy 346.36993 -407.137999) (xy 346.347288 -407.187578)
			(xy 346.317821 -407.233431) (xy 346.282129 -407.274623) (xy 346.240937 -407.310316) (xy 346.195085 -407.339784)
			(xy 346.145507 -407.362427) (xy 346.09321 -407.377784) (xy 346.03926 -407.385542) (xy 346.012008 -407.386028)
			(xy 345.148408 -407.386028) (xy 345.121156 -407.385525) (xy 345.067207 -407.37777) (xy 345.014911 -407.362415)
			(xy 344.965333 -407.339774) (xy 344.919481 -407.310308) (xy 344.878289 -407.274616) (xy 344.842597 -407.233425)
			(xy 344.81313 -407.187574) (xy 344.790488 -407.137996) (xy 344.775132 -407.085701) (xy 344.767375 -407.031752)
			(xy 343.329865 -407.031752) (xy 343.329865 -407.031756) (xy 343.322107 -407.085712) (xy 343.306748 -407.138016)
			(xy 343.284102 -407.187601) (xy 343.25463 -407.233458) (xy 343.218931 -407.274653) (xy 343.177732 -407.310349)
			(xy 343.131872 -407.339818) (xy 343.082286 -407.36246) (xy 343.029981 -407.377814) (xy 342.976024 -407.385567)
			(xy 342.948768 -407.386028) (xy 342.085168 -407.386028) (xy 342.05792 -407.3855) (xy 342.003978 -407.37774)
			(xy 341.95169 -407.362383) (xy 341.90212 -407.339741) (xy 341.856276 -407.310275) (xy 341.815092 -407.274586)
			(xy 341.779405 -407.233399) (xy 341.749944 -407.187552) (xy 341.727306 -407.13798) (xy 341.711953 -407.08569)
			(xy 341.704198 -407.031748) (xy 340.266542 -407.031748) (xy 340.266542 -407.031751) (xy 340.258786 -407.0857)
			(xy 340.243432 -407.137995) (xy 340.220791 -407.187573) (xy 340.191326 -407.233424) (xy 340.155636 -407.274616)
			(xy 340.114447 -407.310309) (xy 340.068597 -407.339778) (xy 340.019021 -407.362422) (xy 339.966727 -407.37778)
			(xy 339.912779 -407.38554) (xy 339.885528 -407.386028) (xy 339.021928 -407.386028) (xy 338.994675 -407.385527)
			(xy 338.940724 -407.377773) (xy 338.888426 -407.36242) (xy 338.838845 -407.339781) (xy 338.79299 -407.310315)
			(xy 338.751797 -407.274623) (xy 338.716102 -407.233432) (xy 338.686633 -407.18758) (xy 338.663989 -407.138001)
			(xy 338.648633 -407.085703) (xy 338.640875 -407.031753) (xy 337.203365 -407.031753) (xy 337.203365 -407.031755)
			(xy 337.195607 -407.08571) (xy 337.18025 -407.138011) (xy 337.157605 -407.187595) (xy 337.128135 -407.233451)
			(xy 337.092438 -407.274646) (xy 337.051241 -407.310342) (xy 337.005384 -407.339811) (xy 336.9558 -407.362454)
			(xy 336.903498 -407.37781) (xy 336.849543 -407.385566) (xy 336.822288 -407.386028) (xy 335.958688 -407.386028)
			(xy 335.931439 -407.385501) (xy 335.877495 -407.377743) (xy 335.825205 -407.362388) (xy 335.775632 -407.339748)
			(xy 335.729785 -407.310282) (xy 335.688599 -407.274593) (xy 335.65291 -407.233405) (xy 335.623447 -407.187558)
			(xy 335.600808 -407.137984) (xy 335.585454 -407.085693) (xy 335.577698 -407.031749) (xy 334.140042 -407.031749)
			(xy 334.140042 -407.03175) (xy 334.132287 -407.085697) (xy 334.116933 -407.137991) (xy 334.094294 -407.187567)
			(xy 334.064831 -407.233418) (xy 334.029143 -407.274609) (xy 333.987956 -407.310302) (xy 333.942109 -407.339771)
			(xy 333.892536 -407.362416) (xy 333.840244 -407.377776) (xy 333.786298 -407.385539) (xy 333.759048 -407.386028)
			(xy 332.895448 -407.386028) (xy 332.868194 -407.385528) (xy 332.814241 -407.377777) (xy 332.76194 -407.362426)
			(xy 332.712357 -407.339787) (xy 332.6665 -407.310322) (xy 332.625304 -407.27463) (xy 332.589607 -407.233439)
			(xy 332.560136 -407.187586) (xy 332.537491 -407.138005) (xy 332.522133 -407.085706) (xy 332.514375 -407.031754)
			(xy 331.076842 -407.031754) (xy 331.069085 -407.085702) (xy 331.05373 -407.137999) (xy 331.031088 -407.187578)
			(xy 331.001621 -407.233431) (xy 330.965929 -407.274623) (xy 330.924737 -407.310316) (xy 330.878885 -407.339784)
			(xy 330.829307 -407.362427) (xy 330.77701 -407.377784) (xy 330.72306 -407.385542) (xy 330.695808 -407.386028)
			(xy 329.832208 -407.386028) (xy 329.804956 -407.385525) (xy 329.751007 -407.37777) (xy 329.698711 -407.362415)
			(xy 329.649133 -407.339774) (xy 329.603281 -407.310308) (xy 329.562089 -407.274616) (xy 329.526397 -407.233425)
			(xy 329.49693 -407.187574) (xy 329.474288 -407.137996) (xy 329.458932 -407.085701) (xy 329.451175 -407.031752)
			(xy 328.013665 -407.031752) (xy 328.013665 -407.031756) (xy 328.005907 -407.085712) (xy 327.990548 -407.138016)
			(xy 327.967902 -407.187601) (xy 327.93843 -407.233458) (xy 327.902731 -407.274653) (xy 327.861532 -407.310349)
			(xy 327.815672 -407.339818) (xy 327.766086 -407.36246) (xy 327.713781 -407.377814) (xy 327.659824 -407.385567)
			(xy 327.632568 -407.386028) (xy 326.768968 -407.386028) (xy 326.74172 -407.3855) (xy 326.687778 -407.37774)
			(xy 326.63549 -407.362383) (xy 326.58592 -407.339741) (xy 326.540076 -407.310275) (xy 326.498892 -407.274586)
			(xy 326.463205 -407.233399) (xy 326.433744 -407.187552) (xy 326.411106 -407.13798) (xy 326.395753 -407.08569)
			(xy 326.387998 -407.031748) (xy 324.950342 -407.031748) (xy 324.950342 -407.031751) (xy 324.942586 -407.0857)
			(xy 324.927232 -407.137995) (xy 324.904591 -407.187573) (xy 324.875126 -407.233424) (xy 324.839436 -407.274616)
			(xy 324.798247 -407.310309) (xy 324.752397 -407.339778) (xy 324.702821 -407.362422) (xy 324.650527 -407.37778)
			(xy 324.596579 -407.38554) (xy 324.569328 -407.386028) (xy 323.705728 -407.386028) (xy 323.678475 -407.385527)
			(xy 323.624524 -407.377773) (xy 323.572226 -407.36242) (xy 323.522645 -407.339781) (xy 323.47679 -407.310315)
			(xy 323.435597 -407.274623) (xy 323.399902 -407.233432) (xy 323.370433 -407.18758) (xy 323.347789 -407.138001)
			(xy 323.332433 -407.085703) (xy 323.324675 -407.031753) (xy 321.887165 -407.031753) (xy 321.887165 -407.031755)
			(xy 321.879407 -407.08571) (xy 321.86405 -407.138011) (xy 321.841405 -407.187595) (xy 321.811935 -407.233451)
			(xy 321.776238 -407.274646) (xy 321.735041 -407.310342) (xy 321.689184 -407.339811) (xy 321.6396 -407.362454)
			(xy 321.587298 -407.37781) (xy 321.533343 -407.385566) (xy 321.506088 -407.386028) (xy 320.642488 -407.386028)
			(xy 320.615239 -407.385501) (xy 320.561295 -407.377743) (xy 320.509005 -407.362388) (xy 320.459432 -407.339748)
			(xy 320.413585 -407.310282) (xy 320.372399 -407.274593) (xy 320.33671 -407.233405) (xy 320.307247 -407.187558)
			(xy 320.284608 -407.137984) (xy 320.269254 -407.085693) (xy 320.261498 -407.031749) (xy 318.823842 -407.031749)
			(xy 318.823842 -407.03175) (xy 318.816087 -407.085697) (xy 318.800733 -407.137991) (xy 318.778094 -407.187567)
			(xy 318.748631 -407.233418) (xy 318.712943 -407.274609) (xy 318.671756 -407.310302) (xy 318.625909 -407.339771)
			(xy 318.576336 -407.362416) (xy 318.524044 -407.377776) (xy 318.470098 -407.385539) (xy 318.442848 -407.386028)
			(xy 317.579248 -407.386028) (xy 317.551994 -407.385528) (xy 317.498041 -407.377777) (xy 317.44574 -407.362426)
			(xy 317.396157 -407.339787) (xy 317.3503 -407.310322) (xy 317.309104 -407.27463) (xy 317.273407 -407.233439)
			(xy 317.243936 -407.187586) (xy 317.221291 -407.138005) (xy 317.205933 -407.085706) (xy 317.198175 -407.031754)
			(xy 315.760642 -407.031754) (xy 315.752885 -407.085702) (xy 315.73753 -407.137999) (xy 315.714888 -407.187578)
			(xy 315.685421 -407.233431) (xy 315.649729 -407.274623) (xy 315.608537 -407.310316) (xy 315.562685 -407.339784)
			(xy 315.513107 -407.362427) (xy 315.46081 -407.377784) (xy 315.40686 -407.385542) (xy 315.379608 -407.386028)
			(xy 314.516008 -407.386028) (xy 314.488756 -407.385525) (xy 314.434807 -407.37777) (xy 314.382511 -407.362415)
			(xy 314.332933 -407.339774) (xy 314.287081 -407.310308) (xy 314.245889 -407.274616) (xy 314.210197 -407.233425)
			(xy 314.18073 -407.187574) (xy 314.158088 -407.137996) (xy 314.142732 -407.085701) (xy 314.134975 -407.031752)
			(xy 312.697465 -407.031752) (xy 312.697465 -407.031756) (xy 312.689707 -407.085712) (xy 312.674348 -407.138016)
			(xy 312.651702 -407.187601) (xy 312.62223 -407.233458) (xy 312.586531 -407.274653) (xy 312.545332 -407.310349)
			(xy 312.499472 -407.339818) (xy 312.449886 -407.36246) (xy 312.397581 -407.377814) (xy 312.343624 -407.385567)
			(xy 312.316368 -407.386028) (xy 311.452768 -407.386028) (xy 311.42552 -407.3855) (xy 311.371578 -407.37774)
			(xy 311.31929 -407.362383) (xy 311.26972 -407.339741) (xy 311.223876 -407.310275) (xy 311.182692 -407.274586)
			(xy 311.147005 -407.233399) (xy 311.117544 -407.187552) (xy 311.094906 -407.13798) (xy 311.079553 -407.08569)
			(xy 311.071798 -407.031748) (xy 309.634142 -407.031748) (xy 309.634142 -407.031751) (xy 309.626386 -407.0857)
			(xy 309.611032 -407.137995) (xy 309.588391 -407.187573) (xy 309.558926 -407.233424) (xy 309.523236 -407.274616)
			(xy 309.482047 -407.310309) (xy 309.436197 -407.339778) (xy 309.386621 -407.362422) (xy 309.334327 -407.37778)
			(xy 309.280379 -407.38554) (xy 309.253128 -407.386028) (xy 308.389528 -407.386028) (xy 308.362275 -407.385527)
			(xy 308.308324 -407.377773) (xy 308.256026 -407.36242) (xy 308.206445 -407.339781) (xy 308.16059 -407.310315)
			(xy 308.119397 -407.274623) (xy 308.083702 -407.233432) (xy 308.054233 -407.18758) (xy 308.031589 -407.138001)
			(xy 308.016233 -407.085703) (xy 308.008475 -407.031753) (xy 306.570965 -407.031753) (xy 306.570965 -407.031755)
			(xy 306.563207 -407.08571) (xy 306.54785 -407.138011) (xy 306.525205 -407.187595) (xy 306.495735 -407.233451)
			(xy 306.460038 -407.274646) (xy 306.418841 -407.310342) (xy 306.372984 -407.339811) (xy 306.3234 -407.362454)
			(xy 306.271098 -407.37781) (xy 306.217143 -407.385566) (xy 306.189888 -407.386028) (xy 305.326288 -407.386028)
			(xy 305.299039 -407.385501) (xy 305.245095 -407.377743) (xy 305.192805 -407.362388) (xy 305.143232 -407.339748)
			(xy 305.097385 -407.310282) (xy 305.056199 -407.274593) (xy 305.02051 -407.233405) (xy 304.991047 -407.187558)
			(xy 304.968408 -407.137984) (xy 304.953054 -407.085693) (xy 304.945298 -407.031749) (xy 274.459335 -407.031749)
			(xy 274.369276 -407.121868) (xy 274.369276 -407.203148) (xy 274.602448 -407.43632) (xy 280.100532 -407.43632)
			(xy 280.125481 -407.436823) (xy 280.174763 -407.444637) (xy 280.222219 -407.460054) (xy 280.266685 -407.482694)
			(xy 280.307069 -407.512001) (xy 280.325068 -407.529284) (xy 280.739596 -407.943812) (xy 280.756896 -407.961798)
			(xy 280.786219 -408.002177) (xy 280.808865 -408.046645) (xy 280.824276 -408.094108) (xy 280.832075 -408.143397)
			(xy 280.83256 -408.168348) (xy 280.83256 -408.860244) (xy 305.108356 -408.860244) (xy 305.108356 -408.174444)
			(xy 305.108853 -408.162342) (xy 305.116335 -408.139323) (xy 305.130577 -408.119753) (xy 305.15018 -408.105556)
			(xy 305.173215 -408.098126) (xy 305.185318 -408.097736) (xy 305.379882 -408.097736) (xy 305.390988 -408.098102)
			(xy 305.41228 -408.104436) (xy 305.421792 -408.110182) (xy 305.715416 -408.302714) (xy 305.724781 -408.30845)
			(xy 305.745803 -408.314778) (xy 305.767756 -408.314842) (xy 305.788814 -408.308638) (xy 305.79822 -408.302968)
			(xy 306.094384 -408.110182) (xy 306.10389 -408.104425) (xy 306.125187 -408.098105) (xy 306.136294 -408.097736)
			(xy 306.330858 -408.097736) (xy 306.342945 -408.098243) (xy 306.365944 -408.105688) (xy 306.385524 -408.119864)
			(xy 306.399776 -408.139389) (xy 306.40731 -408.162359) (xy 306.40782 -408.174444) (xy 306.40782 -408.860244)
			(xy 308.171596 -408.860244) (xy 308.171596 -408.174444) (xy 308.172054 -408.162338) (xy 308.179541 -408.139313)
			(xy 308.193792 -408.119739) (xy 308.213405 -408.105543) (xy 308.236451 -408.09812) (xy 308.248558 -408.097736)
			(xy 308.443122 -408.097736) (xy 308.454226 -408.098126) (xy 308.475518 -408.104443) (xy 308.485032 -408.110182)
			(xy 308.778656 -408.302714) (xy 308.78805 -408.308399) (xy 308.809058 -408.314738) (xy 308.831001 -408.314817)
			(xy 308.852054 -408.308629) (xy 308.86146 -408.302968) (xy 309.157624 -408.110182) (xy 309.167142 -408.104447)
			(xy 309.188429 -408.098113) (xy 309.199534 -408.097736) (xy 309.394098 -408.097736) (xy 309.406187 -408.098209)
			(xy 309.429187 -408.105665) (xy 309.448766 -408.11985) (xy 309.463017 -408.139382) (xy 309.47055 -408.162357)
			(xy 309.47106 -408.174444) (xy 309.47106 -408.860244) (xy 311.234836 -408.860244) (xy 311.234836 -408.174444)
			(xy 311.235254 -408.162334) (xy 311.242746 -408.139302) (xy 311.257006 -408.119725) (xy 311.27663 -408.10553)
			(xy 311.299687 -408.098115) (xy 311.311798 -408.097736) (xy 311.506362 -408.097736) (xy 311.517468 -408.09811)
			(xy 311.538759 -408.104438) (xy 311.548272 -408.110182) (xy 311.841896 -408.302714) (xy 311.851271 -408.308433)
			(xy 311.872288 -408.314765) (xy 311.894238 -408.314834) (xy 311.915294 -408.308635) (xy 311.9247 -408.302968)
			(xy 312.220864 -408.110182) (xy 312.230374 -408.104432) (xy 312.251668 -408.098108) (xy 312.262774 -408.097736)
			(xy 312.457338 -408.097736) (xy 312.469429 -408.098175) (xy 312.49243 -408.105642) (xy 312.512009 -408.119836)
			(xy 312.526259 -408.139374) (xy 312.533791 -408.162354) (xy 312.5343 -408.174444) (xy 312.5343 -408.860244)
			(xy 314.298076 -408.860244) (xy 314.298076 -408.174444) (xy 314.298554 -408.16234) (xy 314.306038 -408.139318)
			(xy 314.320284 -408.119746) (xy 314.339892 -408.105549) (xy 314.362933 -408.098123) (xy 314.375038 -408.097736)
			(xy 314.569602 -408.097736) (xy 314.580705 -408.098134) (xy 314.601997 -408.104446) (xy 314.611512 -408.110182)
			(xy 314.905136 -408.302714) (xy 314.914492 -408.308467) (xy 314.935518 -408.314791) (xy 314.957474 -408.314851)
			(xy 314.978534 -408.308641) (xy 314.98794 -408.302968) (xy 315.284104 -408.110182) (xy 315.293606 -408.104417)
			(xy 315.314906 -408.098102) (xy 315.326014 -408.097736) (xy 315.520578 -408.097736) (xy 315.532666 -408.098226)
			(xy 315.555665 -408.105676) (xy 315.575245 -408.119857) (xy 315.589497 -408.139386) (xy 315.59703 -408.162358)
			(xy 315.59754 -408.174444) (xy 315.59754 -408.860244) (xy 317.361316 -408.860244) (xy 317.361316 -408.174444)
			(xy 317.361754 -408.162336) (xy 317.369243 -408.139307) (xy 317.383499 -408.119732) (xy 317.403117 -408.105536)
			(xy 317.426169 -408.098118) (xy 317.438278 -408.097736) (xy 317.632842 -408.097736) (xy 317.643947 -408.098118)
			(xy 317.665239 -408.104441) (xy 317.674752 -408.110182) (xy 317.968376 -408.302714) (xy 317.97776 -408.308416)
			(xy 317.998773 -408.314752) (xy 318.020719 -408.314826) (xy 318.041774 -408.308632) (xy 318.05118 -408.302968)
			(xy 318.347344 -408.110182) (xy 318.356858 -408.10444) (xy 318.378148 -408.098111) (xy 318.389254 -408.097736)
			(xy 318.583818 -408.097736) (xy 318.595908 -408.098192) (xy 318.618909 -408.105653) (xy 318.638488 -408.119843)
			(xy 318.652738 -408.139378) (xy 318.66027 -408.162355) (xy 318.66078 -408.174444) (xy 318.66078 -408.860244)
			(xy 320.424556 -408.860244) (xy 320.424556 -408.174444) (xy 320.425053 -408.162342) (xy 320.432535 -408.139323)
			(xy 320.446777 -408.119753) (xy 320.46638 -408.105556) (xy 320.489415 -408.098126) (xy 320.501518 -408.097736)
			(xy 320.696082 -408.097736) (xy 320.707188 -408.098102) (xy 320.72848 -408.104436) (xy 320.737992 -408.110182)
			(xy 321.031616 -408.302714) (xy 321.040981 -408.30845) (xy 321.062003 -408.314778) (xy 321.083956 -408.314842)
			(xy 321.105014 -408.308638) (xy 321.11442 -408.302968) (xy 321.410584 -408.110182) (xy 321.42009 -408.104425)
			(xy 321.441387 -408.098105) (xy 321.452494 -408.097736) (xy 321.647058 -408.097736) (xy 321.659145 -408.098243)
			(xy 321.682144 -408.105688) (xy 321.701724 -408.119864) (xy 321.715976 -408.139389) (xy 321.72351 -408.162359)
			(xy 321.72402 -408.174444) (xy 321.72402 -408.860244) (xy 323.487796 -408.860244) (xy 323.487796 -408.174444)
			(xy 323.488254 -408.162338) (xy 323.495741 -408.139313) (xy 323.509992 -408.119739) (xy 323.529605 -408.105543)
			(xy 323.552651 -408.09812) (xy 323.564758 -408.097736) (xy 323.759322 -408.097736) (xy 323.770426 -408.098126)
			(xy 323.791718 -408.104443) (xy 323.801232 -408.110182) (xy 324.094856 -408.302714) (xy 324.10425 -408.308399)
			(xy 324.125258 -408.314738) (xy 324.147201 -408.314817) (xy 324.168254 -408.308629) (xy 324.17766 -408.302968)
			(xy 324.473824 -408.110182) (xy 324.483342 -408.104447) (xy 324.504629 -408.098113) (xy 324.515734 -408.097736)
			(xy 324.710298 -408.097736) (xy 324.722387 -408.098209) (xy 324.745387 -408.105665) (xy 324.764966 -408.11985)
			(xy 324.779217 -408.139382) (xy 324.78675 -408.162357) (xy 324.78726 -408.174444) (xy 324.78726 -408.860244)
			(xy 326.551036 -408.860244) (xy 326.551036 -408.174444) (xy 326.551454 -408.162334) (xy 326.558946 -408.139302)
			(xy 326.573206 -408.119725) (xy 326.59283 -408.10553) (xy 326.615887 -408.098115) (xy 326.627998 -408.097736)
			(xy 326.822562 -408.097736) (xy 326.833668 -408.09811) (xy 326.854959 -408.104438) (xy 326.864472 -408.110182)
			(xy 327.158096 -408.302714) (xy 327.167471 -408.308433) (xy 327.188488 -408.314765) (xy 327.210438 -408.314834)
			(xy 327.231494 -408.308635) (xy 327.2409 -408.302968) (xy 327.537064 -408.110182) (xy 327.546574 -408.104432)
			(xy 327.567868 -408.098108) (xy 327.578974 -408.097736) (xy 327.773538 -408.097736) (xy 327.785629 -408.098175)
			(xy 327.80863 -408.105642) (xy 327.828209 -408.119836) (xy 327.842459 -408.139374) (xy 327.849991 -408.162354)
			(xy 327.8505 -408.174444) (xy 327.8505 -408.860244) (xy 329.614276 -408.860244) (xy 329.614276 -408.174444)
			(xy 329.614754 -408.16234) (xy 329.622238 -408.139318) (xy 329.636484 -408.119746) (xy 329.656092 -408.105549)
			(xy 329.679133 -408.098123) (xy 329.691238 -408.097736) (xy 329.885802 -408.097736) (xy 329.896905 -408.098134)
			(xy 329.918197 -408.104446) (xy 329.927712 -408.110182) (xy 330.221336 -408.302714) (xy 330.230692 -408.308467)
			(xy 330.251718 -408.314791) (xy 330.273674 -408.314851) (xy 330.294734 -408.308641) (xy 330.30414 -408.302968)
			(xy 330.600304 -408.110182) (xy 330.609806 -408.104417) (xy 330.631106 -408.098102) (xy 330.642214 -408.097736)
			(xy 330.836778 -408.097736) (xy 330.848866 -408.098226) (xy 330.871865 -408.105676) (xy 330.891445 -408.119857)
			(xy 330.905697 -408.139386) (xy 330.91323 -408.162358) (xy 330.91374 -408.174444) (xy 330.91374 -408.860244)
			(xy 332.677516 -408.860244) (xy 332.677516 -408.174444) (xy 332.677954 -408.162336) (xy 332.685443 -408.139307)
			(xy 332.699699 -408.119732) (xy 332.719317 -408.105536) (xy 332.742369 -408.098118) (xy 332.754478 -408.097736)
			(xy 332.949042 -408.097736) (xy 332.960147 -408.098118) (xy 332.981439 -408.104441) (xy 332.990952 -408.110182)
			(xy 333.284576 -408.302714) (xy 333.29396 -408.308416) (xy 333.314973 -408.314752) (xy 333.336919 -408.314826)
			(xy 333.357974 -408.308632) (xy 333.36738 -408.302968) (xy 333.663544 -408.110182) (xy 333.673058 -408.10444)
			(xy 333.694348 -408.098111) (xy 333.705454 -408.097736) (xy 333.900018 -408.097736) (xy 333.912108 -408.098192)
			(xy 333.935109 -408.105653) (xy 333.954688 -408.119843) (xy 333.968938 -408.139378) (xy 333.97647 -408.162355)
			(xy 333.97698 -408.174444) (xy 333.97698 -408.860244) (xy 335.740756 -408.860244) (xy 335.740756 -408.174444)
			(xy 335.741253 -408.162342) (xy 335.748735 -408.139323) (xy 335.762977 -408.119753) (xy 335.78258 -408.105556)
			(xy 335.805615 -408.098126) (xy 335.817718 -408.097736) (xy 336.012282 -408.097736) (xy 336.023388 -408.098102)
			(xy 336.04468 -408.104436) (xy 336.054192 -408.110182) (xy 336.347816 -408.302714) (xy 336.357181 -408.30845)
			(xy 336.378203 -408.314778) (xy 336.400156 -408.314842) (xy 336.421214 -408.308638) (xy 336.43062 -408.302968)
			(xy 336.726784 -408.110182) (xy 336.73629 -408.104425) (xy 336.757587 -408.098105) (xy 336.768694 -408.097736)
			(xy 336.963258 -408.097736) (xy 336.975345 -408.098243) (xy 336.998344 -408.105688) (xy 337.017924 -408.119864)
			(xy 337.032176 -408.139389) (xy 337.03971 -408.162359) (xy 337.04022 -408.174444) (xy 337.04022 -408.860244)
			(xy 338.803996 -408.860244) (xy 338.803996 -408.174444) (xy 338.804454 -408.162338) (xy 338.811941 -408.139313)
			(xy 338.826192 -408.119739) (xy 338.845805 -408.105543) (xy 338.868851 -408.09812) (xy 338.880958 -408.097736)
			(xy 339.075522 -408.097736) (xy 339.086626 -408.098126) (xy 339.107918 -408.104443) (xy 339.117432 -408.110182)
			(xy 339.411056 -408.302714) (xy 339.42045 -408.308399) (xy 339.441458 -408.314738) (xy 339.463401 -408.314817)
			(xy 339.484454 -408.308629) (xy 339.49386 -408.302968) (xy 339.790024 -408.110182) (xy 339.799542 -408.104447)
			(xy 339.820829 -408.098113) (xy 339.831934 -408.097736) (xy 340.026498 -408.097736) (xy 340.038587 -408.098209)
			(xy 340.061587 -408.105665) (xy 340.081166 -408.11985) (xy 340.095417 -408.139382) (xy 340.10295 -408.162357)
			(xy 340.10346 -408.174444) (xy 340.10346 -408.860244) (xy 341.867236 -408.860244) (xy 341.867236 -408.174444)
			(xy 341.867654 -408.162334) (xy 341.875146 -408.139302) (xy 341.889406 -408.119725) (xy 341.90903 -408.10553)
			(xy 341.932087 -408.098115) (xy 341.944198 -408.097736) (xy 342.138762 -408.097736) (xy 342.149868 -408.09811)
			(xy 342.171159 -408.104438) (xy 342.180672 -408.110182) (xy 342.474296 -408.302714) (xy 342.483671 -408.308433)
			(xy 342.504688 -408.314765) (xy 342.526638 -408.314834) (xy 342.547694 -408.308635) (xy 342.5571 -408.302968)
			(xy 342.853264 -408.110182) (xy 342.862774 -408.104432) (xy 342.884068 -408.098108) (xy 342.895174 -408.097736)
			(xy 343.089738 -408.097736) (xy 343.101829 -408.098175) (xy 343.12483 -408.105642) (xy 343.144409 -408.119836)
			(xy 343.158659 -408.139374) (xy 343.166191 -408.162354) (xy 343.1667 -408.174444) (xy 343.1667 -408.860244)
			(xy 344.930476 -408.860244) (xy 344.930476 -408.174444) (xy 344.930954 -408.16234) (xy 344.938438 -408.139318)
			(xy 344.952684 -408.119746) (xy 344.972292 -408.105549) (xy 344.995333 -408.098123) (xy 345.007438 -408.097736)
			(xy 345.202002 -408.097736) (xy 345.213105 -408.098134) (xy 345.234397 -408.104446) (xy 345.243912 -408.110182)
			(xy 345.537536 -408.302714) (xy 345.546892 -408.308467) (xy 345.567918 -408.314791) (xy 345.589874 -408.314851)
			(xy 345.610934 -408.308641) (xy 345.62034 -408.302968) (xy 345.916504 -408.110182) (xy 345.926006 -408.104417)
			(xy 345.947306 -408.098102) (xy 345.958414 -408.097736) (xy 346.152978 -408.097736) (xy 346.165066 -408.098226)
			(xy 346.188065 -408.105676) (xy 346.207645 -408.119857) (xy 346.221897 -408.139386) (xy 346.22943 -408.162358)
			(xy 346.22994 -408.174444) (xy 346.22994 -408.860244) (xy 347.993716 -408.860244) (xy 347.993716 -408.174444)
			(xy 347.994154 -408.162336) (xy 348.001643 -408.139307) (xy 348.015899 -408.119732) (xy 348.035517 -408.105536)
			(xy 348.058569 -408.098118) (xy 348.070678 -408.097736) (xy 348.265242 -408.097736) (xy 348.276347 -408.098118)
			(xy 348.297639 -408.104441) (xy 348.307152 -408.110182) (xy 348.600776 -408.302714) (xy 348.61016 -408.308416)
			(xy 348.631173 -408.314752) (xy 348.653119 -408.314826) (xy 348.674174 -408.308632) (xy 348.68358 -408.302968)
			(xy 348.979744 -408.110182) (xy 348.989258 -408.10444) (xy 349.010548 -408.098111) (xy 349.021654 -408.097736)
			(xy 349.216218 -408.097736) (xy 349.228308 -408.098192) (xy 349.251309 -408.105653) (xy 349.270888 -408.119843)
			(xy 349.285138 -408.139378) (xy 349.29267 -408.162355) (xy 349.29318 -408.174444) (xy 349.29318 -408.860244)
			(xy 351.056956 -408.860244) (xy 351.056956 -408.174444) (xy 351.057453 -408.162342) (xy 351.064935 -408.139323)
			(xy 351.079177 -408.119753) (xy 351.09878 -408.105556) (xy 351.121815 -408.098126) (xy 351.133918 -408.097736)
			(xy 351.328482 -408.097736) (xy 351.339588 -408.098102) (xy 351.36088 -408.104436) (xy 351.370392 -408.110182)
			(xy 351.664016 -408.302714) (xy 351.673381 -408.30845) (xy 351.694403 -408.314778) (xy 351.716356 -408.314842)
			(xy 351.737414 -408.308638) (xy 351.74682 -408.302968) (xy 352.042984 -408.110182) (xy 352.05249 -408.104425)
			(xy 352.073787 -408.098105) (xy 352.084894 -408.097736) (xy 352.279458 -408.097736) (xy 352.291545 -408.098243)
			(xy 352.314544 -408.105688) (xy 352.334124 -408.119864) (xy 352.348376 -408.139389) (xy 352.35591 -408.162359)
			(xy 352.35642 -408.174444) (xy 352.35642 -408.860244) (xy 372.551452 -408.860244) (xy 372.551452 -408.174444)
			(xy 372.55195 -408.162368) (xy 372.5594 -408.139393) (xy 372.573586 -408.119845) (xy 372.593118 -408.105638)
			(xy 372.616084 -408.098163) (xy 372.62816 -408.097736) (xy 372.822724 -408.097736) (xy 372.833828 -408.098125)
			(xy 372.85512 -408.104443) (xy 372.864634 -408.110182) (xy 373.158258 -408.302714) (xy 373.167651 -408.3084)
			(xy 373.188659 -408.314739) (xy 373.210603 -408.314818) (xy 373.231656 -408.308629) (xy 373.241062 -408.302968)
			(xy 373.537226 -408.110182) (xy 373.546743 -408.104446) (xy 373.568031 -408.098113) (xy 373.579136 -408.097736)
			(xy 373.7737 -408.097736) (xy 373.785787 -408.098113) (xy 373.808777 -408.105586) (xy 373.828332 -408.1198)
			(xy 373.842534 -408.139362) (xy 373.849994 -408.162357) (xy 373.850408 -408.174444) (xy 373.850408 -408.860244)
			(xy 375.614692 -408.860244) (xy 375.614692 -408.174444) (xy 375.61515 -408.162364) (xy 375.622606 -408.139382)
			(xy 375.6368 -408.119831) (xy 375.656343 -408.105626) (xy 375.67932 -408.098157) (xy 375.6914 -408.097736)
			(xy 375.885964 -408.097736) (xy 375.89707 -408.098109) (xy 375.918361 -408.104438) (xy 375.927874 -408.110182)
			(xy 376.221498 -408.302714) (xy 376.230872 -408.308435) (xy 376.251889 -408.314766) (xy 376.273839 -408.314835)
			(xy 376.294896 -408.308635) (xy 376.304302 -408.302968) (xy 376.600466 -408.110182) (xy 376.609975 -408.104432)
			(xy 376.631269 -408.098108) (xy 376.642376 -408.097736) (xy 376.83694 -408.097736) (xy 376.849029 -408.098079)
			(xy 376.872021 -408.105563) (xy 376.891574 -408.119786) (xy 376.905775 -408.139355) (xy 376.913234 -408.162354)
			(xy 376.913648 -408.174444) (xy 376.913648 -408.860244) (xy 378.677932 -408.860244) (xy 378.677932 -408.174444)
			(xy 378.678351 -408.16236) (xy 378.685811 -408.139372) (xy 378.700014 -408.119817) (xy 378.719568 -408.105613)
			(xy 378.742556 -408.098151) (xy 378.75464 -408.097736) (xy 378.949204 -408.097736) (xy 378.960307 -408.098133)
			(xy 378.981599 -408.104446) (xy 378.991114 -408.110182) (xy 379.284738 -408.302714) (xy 379.294093 -408.308469)
			(xy 379.315119 -408.314793) (xy 379.337076 -408.314852) (xy 379.358136 -408.308641) (xy 379.367542 -408.302968)
			(xy 379.663706 -408.110182) (xy 379.673207 -408.104417) (xy 379.694508 -408.098102) (xy 379.705616 -408.097736)
			(xy 379.90018 -408.097736) (xy 379.912266 -408.098131) (xy 379.935256 -408.105598) (xy 379.95481 -408.119807)
			(xy 379.969013 -408.139366) (xy 379.976473 -408.162358) (xy 379.976888 -408.174444) (xy 379.976888 -408.860244)
			(xy 381.741172 -408.860244) (xy 381.741172 -408.174444) (xy 381.74165 -408.162366) (xy 381.749103 -408.139388)
			(xy 381.763293 -408.119838) (xy 381.78283 -408.105632) (xy 381.805802 -408.09816) (xy 381.81788 -408.097736)
			(xy 382.012444 -408.097736) (xy 382.023549 -408.098117) (xy 382.044841 -408.10444) (xy 382.054354 -408.110182)
			(xy 382.347978 -408.302714) (xy 382.357361 -408.308418) (xy 382.378374 -408.314753) (xy 382.400321 -408.314826)
			(xy 382.421376 -408.308632) (xy 382.430782 -408.302968) (xy 382.726946 -408.110182) (xy 382.736459 -408.104439)
			(xy 382.75775 -408.09811) (xy 382.768856 -408.097736) (xy 382.96342 -408.097736) (xy 382.975508 -408.098096)
			(xy 382.998499 -408.105575) (xy 383.018053 -408.119793) (xy 383.032255 -408.139358) (xy 383.039714 -408.162355)
			(xy 383.040128 -408.174444) (xy 383.040128 -408.860244) (xy 384.804412 -408.860244) (xy 384.804412 -408.174444)
			(xy 384.80485 -408.162362) (xy 384.812308 -408.139377) (xy 384.826507 -408.119824) (xy 384.846055 -408.105619)
			(xy 384.869038 -408.098154) (xy 384.88112 -408.097736) (xy 385.075684 -408.097736) (xy 385.08679 -408.098101)
			(xy 385.108082 -408.104436) (xy 385.117594 -408.110182) (xy 385.411218 -408.302714) (xy 385.420582 -408.308452)
			(xy 385.441604 -408.314779) (xy 385.463558 -408.314843) (xy 385.484616 -408.308638) (xy 385.494022 -408.302968)
			(xy 385.790186 -408.110182) (xy 385.799691 -408.104424) (xy 385.820989 -408.098105) (xy 385.832096 -408.097736)
			(xy 386.02666 -408.097736) (xy 386.038745 -408.098147) (xy 386.061734 -408.105609) (xy 386.081289 -408.119814)
			(xy 386.095493 -408.13937) (xy 386.102953 -408.162359) (xy 386.103368 -408.174444) (xy 386.103368 -408.860244)
			(xy 387.867652 -408.860244) (xy 387.867652 -408.174444) (xy 387.86815 -408.162368) (xy 387.8756 -408.139393)
			(xy 387.889786 -408.119845) (xy 387.909318 -408.105638) (xy 387.932284 -408.098163) (xy 387.94436 -408.097736)
			(xy 388.138924 -408.097736) (xy 388.150028 -408.098125) (xy 388.17132 -408.104443) (xy 388.180834 -408.110182)
			(xy 388.474458 -408.302714) (xy 388.483851 -408.3084) (xy 388.504859 -408.314739) (xy 388.526803 -408.314818)
			(xy 388.547856 -408.308629) (xy 388.557262 -408.302968) (xy 388.853426 -408.110182) (xy 388.862943 -408.104446)
			(xy 388.884231 -408.098113) (xy 388.895336 -408.097736) (xy 389.0899 -408.097736) (xy 389.101987 -408.098113)
			(xy 389.124977 -408.105586) (xy 389.144532 -408.1198) (xy 389.158734 -408.139362) (xy 389.166194 -408.162357)
			(xy 389.166608 -408.174444) (xy 389.166608 -408.860244) (xy 390.930892 -408.860244) (xy 390.930892 -408.174444)
			(xy 390.93135 -408.162364) (xy 390.938806 -408.139382) (xy 390.953 -408.119831) (xy 390.972543 -408.105626)
			(xy 390.99552 -408.098157) (xy 391.0076 -408.097736) (xy 391.202164 -408.097736) (xy 391.21327 -408.098109)
			(xy 391.234561 -408.104438) (xy 391.244074 -408.110182) (xy 391.537698 -408.302714) (xy 391.547072 -408.308435)
			(xy 391.568089 -408.314766) (xy 391.590039 -408.314835) (xy 391.611096 -408.308635) (xy 391.620502 -408.302968)
			(xy 391.916666 -408.110182) (xy 391.926175 -408.104432) (xy 391.947469 -408.098108) (xy 391.958576 -408.097736)
			(xy 392.15314 -408.097736) (xy 392.165229 -408.098079) (xy 392.188221 -408.105563) (xy 392.207774 -408.119786)
			(xy 392.221975 -408.139355) (xy 392.229434 -408.162354) (xy 392.229848 -408.174444) (xy 392.229848 -408.860244)
			(xy 393.994132 -408.860244) (xy 393.994132 -408.174444) (xy 393.994551 -408.16236) (xy 394.002011 -408.139372)
			(xy 394.016214 -408.119817) (xy 394.035768 -408.105613) (xy 394.058756 -408.098151) (xy 394.07084 -408.097736)
			(xy 394.265404 -408.097736) (xy 394.276507 -408.098133) (xy 394.297799 -408.104446) (xy 394.307314 -408.110182)
			(xy 394.600938 -408.302714) (xy 394.610293 -408.308469) (xy 394.631319 -408.314793) (xy 394.653276 -408.314852)
			(xy 394.674336 -408.308641) (xy 394.683742 -408.302968) (xy 394.979906 -408.110182) (xy 394.989407 -408.104417)
			(xy 395.010708 -408.098102) (xy 395.021816 -408.097736) (xy 395.21638 -408.097736) (xy 395.228466 -408.098131)
			(xy 395.251456 -408.105598) (xy 395.27101 -408.119807) (xy 395.285213 -408.139366) (xy 395.292673 -408.162358)
			(xy 395.293088 -408.174444) (xy 395.293088 -408.860244) (xy 397.057372 -408.860244) (xy 397.057372 -408.174444)
			(xy 397.05785 -408.162366) (xy 397.065303 -408.139388) (xy 397.079493 -408.119838) (xy 397.09903 -408.105632)
			(xy 397.122002 -408.09816) (xy 397.13408 -408.097736) (xy 397.328644 -408.097736) (xy 397.339749 -408.098117)
			(xy 397.361041 -408.10444) (xy 397.370554 -408.110182) (xy 397.664178 -408.302714) (xy 397.673561 -408.308418)
			(xy 397.694574 -408.314753) (xy 397.716521 -408.314826) (xy 397.737576 -408.308632) (xy 397.746982 -408.302968)
			(xy 398.043146 -408.110182) (xy 398.052659 -408.104439) (xy 398.07395 -408.09811) (xy 398.085056 -408.097736)
			(xy 398.27962 -408.097736) (xy 398.291708 -408.098096) (xy 398.314699 -408.105575) (xy 398.334253 -408.119793)
			(xy 398.348455 -408.139358) (xy 398.355914 -408.162355) (xy 398.356328 -408.174444) (xy 398.356328 -408.860244)
			(xy 400.120612 -408.860244) (xy 400.120612 -408.174444) (xy 400.12105 -408.162362) (xy 400.128508 -408.139377)
			(xy 400.142707 -408.119824) (xy 400.162255 -408.105619) (xy 400.185238 -408.098154) (xy 400.19732 -408.097736)
			(xy 400.391884 -408.097736) (xy 400.40299 -408.098101) (xy 400.424282 -408.104436) (xy 400.433794 -408.110182)
			(xy 400.727418 -408.302714) (xy 400.736782 -408.308452) (xy 400.757804 -408.314779) (xy 400.779758 -408.314843)
			(xy 400.800816 -408.308638) (xy 400.810222 -408.302968) (xy 401.106386 -408.110182) (xy 401.115891 -408.104424)
			(xy 401.137189 -408.098105) (xy 401.148296 -408.097736) (xy 401.34286 -408.097736) (xy 401.354945 -408.098147)
			(xy 401.377934 -408.105609) (xy 401.397489 -408.119814) (xy 401.411693 -408.13937) (xy 401.419153 -408.162359)
			(xy 401.419568 -408.174444) (xy 401.419568 -408.860244) (xy 403.183852 -408.860244) (xy 403.183852 -408.174444)
			(xy 403.18435 -408.162368) (xy 403.1918 -408.139393) (xy 403.205986 -408.119845) (xy 403.225518 -408.105638)
			(xy 403.248484 -408.098163) (xy 403.26056 -408.097736) (xy 403.455124 -408.097736) (xy 403.466228 -408.098125)
			(xy 403.48752 -408.104443) (xy 403.497034 -408.110182) (xy 403.790658 -408.302714) (xy 403.800051 -408.3084)
			(xy 403.821059 -408.314739) (xy 403.843003 -408.314818) (xy 403.864056 -408.308629) (xy 403.873462 -408.302968)
			(xy 404.169626 -408.110182) (xy 404.179143 -408.104446) (xy 404.200431 -408.098113) (xy 404.211536 -408.097736)
			(xy 404.4061 -408.097736) (xy 404.418187 -408.098113) (xy 404.441177 -408.105586) (xy 404.460732 -408.1198)
			(xy 404.474934 -408.139362) (xy 404.482394 -408.162357) (xy 404.482808 -408.174444) (xy 404.482808 -408.860244)
			(xy 406.247092 -408.860244) (xy 406.247092 -408.174444) (xy 406.24755 -408.162364) (xy 406.255006 -408.139382)
			(xy 406.2692 -408.119831) (xy 406.288743 -408.105626) (xy 406.31172 -408.098157) (xy 406.3238 -408.097736)
			(xy 406.518364 -408.097736) (xy 406.52947 -408.098109) (xy 406.550761 -408.104438) (xy 406.560274 -408.110182)
			(xy 406.853898 -408.302714) (xy 406.863272 -408.308435) (xy 406.884289 -408.314766) (xy 406.906239 -408.314835)
			(xy 406.927296 -408.308635) (xy 406.936702 -408.302968) (xy 407.232866 -408.110182) (xy 407.242375 -408.104432)
			(xy 407.263669 -408.098108) (xy 407.274776 -408.097736) (xy 407.46934 -408.097736) (xy 407.481429 -408.098079)
			(xy 407.504421 -408.105563) (xy 407.523974 -408.119786) (xy 407.538175 -408.139355) (xy 407.545634 -408.162354)
			(xy 407.546048 -408.174444) (xy 407.546048 -408.860244) (xy 409.310332 -408.860244) (xy 409.310332 -408.174444)
			(xy 409.310751 -408.16236) (xy 409.318211 -408.139372) (xy 409.332414 -408.119817) (xy 409.351968 -408.105613)
			(xy 409.374956 -408.098151) (xy 409.38704 -408.097736) (xy 409.581604 -408.097736) (xy 409.592707 -408.098133)
			(xy 409.613999 -408.104446) (xy 409.623514 -408.110182) (xy 409.917138 -408.302714) (xy 409.926493 -408.308469)
			(xy 409.947519 -408.314793) (xy 409.969476 -408.314852) (xy 409.990536 -408.308641) (xy 409.999942 -408.302968)
			(xy 410.296106 -408.110182) (xy 410.305607 -408.104417) (xy 410.326908 -408.098102) (xy 410.338016 -408.097736)
			(xy 410.53258 -408.097736) (xy 410.544666 -408.098131) (xy 410.567656 -408.105598) (xy 410.58721 -408.119807)
			(xy 410.601413 -408.139366) (xy 410.608873 -408.162358) (xy 410.609288 -408.174444) (xy 410.609288 -408.860244)
			(xy 412.373572 -408.860244) (xy 412.373572 -408.174444) (xy 412.37405 -408.162366) (xy 412.381503 -408.139388)
			(xy 412.395693 -408.119838) (xy 412.41523 -408.105632) (xy 412.438202 -408.09816) (xy 412.45028 -408.097736)
			(xy 412.644844 -408.097736) (xy 412.655949 -408.098117) (xy 412.677241 -408.10444) (xy 412.686754 -408.110182)
			(xy 412.980378 -408.302714) (xy 412.989761 -408.308418) (xy 413.010774 -408.314753) (xy 413.032721 -408.314826)
			(xy 413.053776 -408.308632) (xy 413.063182 -408.302968) (xy 413.359346 -408.110182) (xy 413.368859 -408.104439)
			(xy 413.39015 -408.09811) (xy 413.401256 -408.097736) (xy 413.59582 -408.097736) (xy 413.607908 -408.098096)
			(xy 413.630899 -408.105575) (xy 413.650453 -408.119793) (xy 413.664655 -408.139358) (xy 413.672114 -408.162355)
			(xy 413.672528 -408.174444) (xy 413.672528 -408.860244) (xy 415.436812 -408.860244) (xy 415.436812 -408.174444)
			(xy 415.43725 -408.162362) (xy 415.444708 -408.139377) (xy 415.458907 -408.119824) (xy 415.478455 -408.105619)
			(xy 415.501438 -408.098154) (xy 415.51352 -408.097736) (xy 415.708084 -408.097736) (xy 415.71919 -408.098101)
			(xy 415.740482 -408.104436) (xy 415.749994 -408.110182) (xy 416.043618 -408.302714) (xy 416.052982 -408.308452)
			(xy 416.074004 -408.314779) (xy 416.095958 -408.314843) (xy 416.117016 -408.308638) (xy 416.126422 -408.302968)
			(xy 416.422586 -408.110182) (xy 416.432091 -408.104424) (xy 416.453389 -408.098105) (xy 416.464496 -408.097736)
			(xy 416.65906 -408.097736) (xy 416.671145 -408.098147) (xy 416.694134 -408.105609) (xy 416.713689 -408.119814)
			(xy 416.727893 -408.13937) (xy 416.735353 -408.162359) (xy 416.735768 -408.174444) (xy 416.735768 -408.860244)
			(xy 418.500052 -408.860244) (xy 418.500052 -408.174444) (xy 418.50055 -408.162368) (xy 418.508 -408.139393)
			(xy 418.522186 -408.119845) (xy 418.541718 -408.105638) (xy 418.564684 -408.098163) (xy 418.57676 -408.097736)
			(xy 418.771324 -408.097736) (xy 418.782428 -408.098125) (xy 418.80372 -408.104443) (xy 418.813234 -408.110182)
			(xy 419.106858 -408.302714) (xy 419.116251 -408.3084) (xy 419.137259 -408.314739) (xy 419.159203 -408.314818)
			(xy 419.180256 -408.308629) (xy 419.189662 -408.302968) (xy 419.485826 -408.110182) (xy 419.495343 -408.104446)
			(xy 419.516631 -408.098113) (xy 419.527736 -408.097736) (xy 419.7223 -408.097736) (xy 419.734387 -408.098113)
			(xy 419.757377 -408.105586) (xy 419.776932 -408.1198) (xy 419.791134 -408.139362) (xy 419.798594 -408.162357)
			(xy 419.799008 -408.174444) (xy 419.799008 -408.860244) (xy 419.798573 -408.872321) (xy 419.791099 -408.89529)
			(xy 419.776895 -408.914826) (xy 419.75735 -408.929019) (xy 419.734377 -408.93648) (xy 419.7223 -408.936952)
			(xy 419.527736 -408.936952) (xy 419.516627 -408.936602) (xy 419.495331 -408.930269) (xy 419.485826 -408.924506)
			(xy 419.190932 -408.731974) (xy 419.181545 -408.726271) (xy 419.160507 -408.719998) (xy 419.138553 -408.719998)
			(xy 419.117515 -408.726271) (xy 419.108128 -408.731974) (xy 418.814504 -408.924506) (xy 418.805 -408.930267)
			(xy 418.783702 -408.936584) (xy 418.772594 -408.936952) (xy 418.57676 -408.936952) (xy 418.564688 -408.936471)
			(xy 418.541727 -408.929003) (xy 418.522194 -408.914809) (xy 418.507999 -408.895277) (xy 418.50053 -408.872316)
			(xy 418.500052 -408.860244) (xy 416.735768 -408.860244) (xy 416.735373 -408.872325) (xy 416.727893 -408.8953)
			(xy 416.71368 -408.91484) (xy 416.694125 -408.929032) (xy 416.671141 -408.936486) (xy 416.65906 -408.936952)
			(xy 416.464496 -408.936952) (xy 416.453389 -408.936578) (xy 416.432093 -408.930261) (xy 416.422586 -408.924506)
			(xy 416.127692 -408.731974) (xy 416.118305 -408.726271) (xy 416.097267 -408.719998) (xy 416.075313 -408.719998)
			(xy 416.054275 -408.726271) (xy 416.044888 -408.731974) (xy 415.751264 -408.924506) (xy 415.741748 -408.930244)
			(xy 415.720459 -408.936576) (xy 415.709354 -408.936952) (xy 415.51352 -408.936952) (xy 415.501451 -408.936419)
			(xy 415.478492 -408.928968) (xy 415.458958 -408.914787) (xy 415.444761 -408.895266) (xy 415.437291 -408.872313)
			(xy 415.436812 -408.860244) (xy 413.672528 -408.860244) (xy 413.672074 -408.872319) (xy 413.664602 -408.895284)
			(xy 413.650402 -408.914819) (xy 413.630863 -408.929013) (xy 413.607895 -408.936478) (xy 413.59582 -408.936952)
			(xy 413.401256 -408.936952) (xy 413.390147 -408.936594) (xy 413.368851 -408.930266) (xy 413.359346 -408.924506)
			(xy 413.064452 -408.731974) (xy 413.055065 -408.726271) (xy 413.034027 -408.719998) (xy 413.012073 -408.719998)
			(xy 412.991035 -408.726271) (xy 412.981648 -408.731974) (xy 412.688024 -408.924506) (xy 412.678516 -408.930259)
			(xy 412.657221 -408.936582) (xy 412.646114 -408.936952) (xy 412.45028 -408.936952) (xy 412.438209 -408.936453)
			(xy 412.415248 -408.928991) (xy 412.395716 -408.914801) (xy 412.38152 -408.895273) (xy 412.37405 -408.872315)
			(xy 412.373572 -408.860244) (xy 410.609288 -408.860244) (xy 410.608873 -408.872323) (xy 410.601396 -408.895295)
			(xy 410.587187 -408.914833) (xy 410.567638 -408.929025) (xy 410.544659 -408.936483) (xy 410.53258 -408.936952)
			(xy 410.338016 -408.936952) (xy 410.326906 -408.936611) (xy 410.30561 -408.930271) (xy 410.296106 -408.924506)
			(xy 410.001212 -408.731974) (xy 409.991825 -408.726271) (xy 409.970787 -408.719998) (xy 409.948833 -408.719998)
			(xy 409.927795 -408.726271) (xy 409.918408 -408.731974) (xy 409.624784 -408.924506) (xy 409.615284 -408.930274)
			(xy 409.593983 -408.936587) (xy 409.582874 -408.936952) (xy 409.38704 -408.936952) (xy 409.374972 -408.936403)
			(xy 409.352013 -408.928956) (xy 409.332479 -408.91478) (xy 409.318282 -408.895262) (xy 409.310811 -408.872312)
			(xy 409.310332 -408.860244) (xy 407.546048 -408.860244) (xy 407.545574 -408.872317) (xy 407.538104 -408.895279)
			(xy 407.523909 -408.914812) (xy 407.504375 -408.929006) (xy 407.481413 -408.936475) (xy 407.46934 -408.936952)
			(xy 407.274776 -408.936952) (xy 407.263668 -408.936586) (xy 407.242372 -408.930264) (xy 407.232866 -408.924506)
			(xy 406.937972 -408.731974) (xy 406.928585 -408.726271) (xy 406.907547 -408.719998) (xy 406.885593 -408.719998)
			(xy 406.864555 -408.726271) (xy 406.855168 -408.731974) (xy 406.561544 -408.924506) (xy 406.552032 -408.930252)
			(xy 406.53074 -408.936579) (xy 406.519634 -408.936952) (xy 406.3238 -408.936952) (xy 406.31173 -408.936436)
			(xy 406.28877 -408.928979) (xy 406.269237 -408.914794) (xy 406.255041 -408.895269) (xy 406.247571 -408.872314)
			(xy 406.247092 -408.860244) (xy 404.482808 -408.860244) (xy 404.482373 -408.872321) (xy 404.474899 -408.89529)
			(xy 404.460695 -408.914826) (xy 404.44115 -408.929019) (xy 404.418177 -408.93648) (xy 404.4061 -408.936952)
			(xy 404.211536 -408.936952) (xy 404.200427 -408.936602) (xy 404.179131 -408.930269) (xy 404.169626 -408.924506)
			(xy 403.874732 -408.731974) (xy 403.865345 -408.726271) (xy 403.844307 -408.719998) (xy 403.822353 -408.719998)
			(xy 403.801315 -408.726271) (xy 403.791928 -408.731974) (xy 403.498304 -408.924506) (xy 403.4888 -408.930267)
			(xy 403.467502 -408.936584) (xy 403.456394 -408.936952) (xy 403.26056 -408.936952) (xy 403.248488 -408.936471)
			(xy 403.225527 -408.929003) (xy 403.205994 -408.914809) (xy 403.191799 -408.895277) (xy 403.18433 -408.872316)
			(xy 403.183852 -408.860244) (xy 401.419568 -408.860244) (xy 401.419173 -408.872325) (xy 401.411693 -408.8953)
			(xy 401.39748 -408.91484) (xy 401.377925 -408.929032) (xy 401.354941 -408.936486) (xy 401.34286 -408.936952)
			(xy 401.148296 -408.936952) (xy 401.137189 -408.936578) (xy 401.115893 -408.930261) (xy 401.106386 -408.924506)
			(xy 400.811492 -408.731974) (xy 400.802105 -408.726271) (xy 400.781067 -408.719998) (xy 400.759113 -408.719998)
			(xy 400.738075 -408.726271) (xy 400.728688 -408.731974) (xy 400.435064 -408.924506) (xy 400.425548 -408.930244)
			(xy 400.404259 -408.936576) (xy 400.393154 -408.936952) (xy 400.19732 -408.936952) (xy 400.185251 -408.936419)
			(xy 400.162292 -408.928968) (xy 400.142758 -408.914787) (xy 400.128561 -408.895266) (xy 400.121091 -408.872313)
			(xy 400.120612 -408.860244) (xy 398.356328 -408.860244) (xy 398.355874 -408.872319) (xy 398.348402 -408.895284)
			(xy 398.334202 -408.914819) (xy 398.314663 -408.929013) (xy 398.291695 -408.936478) (xy 398.27962 -408.936952)
			(xy 398.085056 -408.936952) (xy 398.073947 -408.936594) (xy 398.052651 -408.930266) (xy 398.043146 -408.924506)
			(xy 397.748252 -408.731974) (xy 397.738865 -408.726271) (xy 397.717827 -408.719998) (xy 397.695873 -408.719998)
			(xy 397.674835 -408.726271) (xy 397.665448 -408.731974) (xy 397.371824 -408.924506) (xy 397.362316 -408.930259)
			(xy 397.341021 -408.936582) (xy 397.329914 -408.936952) (xy 397.13408 -408.936952) (xy 397.122009 -408.936453)
			(xy 397.099048 -408.928991) (xy 397.079516 -408.914801) (xy 397.06532 -408.895273) (xy 397.05785 -408.872315)
			(xy 397.057372 -408.860244) (xy 395.293088 -408.860244) (xy 395.292673 -408.872323) (xy 395.285196 -408.895295)
			(xy 395.270987 -408.914833) (xy 395.251438 -408.929025) (xy 395.228459 -408.936483) (xy 395.21638 -408.936952)
			(xy 395.021816 -408.936952) (xy 395.010706 -408.936611) (xy 394.98941 -408.930271) (xy 394.979906 -408.924506)
			(xy 394.685012 -408.731974) (xy 394.675625 -408.726271) (xy 394.654587 -408.719998) (xy 394.632633 -408.719998)
			(xy 394.611595 -408.726271) (xy 394.602208 -408.731974) (xy 394.308584 -408.924506) (xy 394.299084 -408.930274)
			(xy 394.277783 -408.936587) (xy 394.266674 -408.936952) (xy 394.07084 -408.936952) (xy 394.058772 -408.936403)
			(xy 394.035813 -408.928956) (xy 394.016279 -408.91478) (xy 394.002082 -408.895262) (xy 393.994611 -408.872312)
			(xy 393.994132 -408.860244) (xy 392.229848 -408.860244) (xy 392.229374 -408.872317) (xy 392.221904 -408.895279)
			(xy 392.207709 -408.914812) (xy 392.188175 -408.929006) (xy 392.165213 -408.936475) (xy 392.15314 -408.936952)
			(xy 391.958576 -408.936952) (xy 391.947468 -408.936586) (xy 391.926172 -408.930264) (xy 391.916666 -408.924506)
			(xy 391.621772 -408.731974) (xy 391.612385 -408.726271) (xy 391.591347 -408.719998) (xy 391.569393 -408.719998)
			(xy 391.548355 -408.726271) (xy 391.538968 -408.731974) (xy 391.245344 -408.924506) (xy 391.235832 -408.930252)
			(xy 391.21454 -408.936579) (xy 391.203434 -408.936952) (xy 391.0076 -408.936952) (xy 390.99553 -408.936436)
			(xy 390.97257 -408.928979) (xy 390.953037 -408.914794) (xy 390.938841 -408.895269) (xy 390.931371 -408.872314)
			(xy 390.930892 -408.860244) (xy 389.166608 -408.860244) (xy 389.166173 -408.872321) (xy 389.158699 -408.89529)
			(xy 389.144495 -408.914826) (xy 389.12495 -408.929019) (xy 389.101977 -408.93648) (xy 389.0899 -408.936952)
			(xy 388.895336 -408.936952) (xy 388.884227 -408.936602) (xy 388.862931 -408.930269) (xy 388.853426 -408.924506)
			(xy 388.558532 -408.731974) (xy 388.549145 -408.726271) (xy 388.528107 -408.719998) (xy 388.506153 -408.719998)
			(xy 388.485115 -408.726271) (xy 388.475728 -408.731974) (xy 388.182104 -408.924506) (xy 388.1726 -408.930267)
			(xy 388.151302 -408.936584) (xy 388.140194 -408.936952) (xy 387.94436 -408.936952) (xy 387.932288 -408.936471)
			(xy 387.909327 -408.929003) (xy 387.889794 -408.914809) (xy 387.875599 -408.895277) (xy 387.86813 -408.872316)
			(xy 387.867652 -408.860244) (xy 386.103368 -408.860244) (xy 386.102973 -408.872325) (xy 386.095493 -408.8953)
			(xy 386.08128 -408.91484) (xy 386.061725 -408.929032) (xy 386.038741 -408.936486) (xy 386.02666 -408.936952)
			(xy 385.832096 -408.936952) (xy 385.820989 -408.936578) (xy 385.799693 -408.930261) (xy 385.790186 -408.924506)
			(xy 385.495292 -408.731974) (xy 385.485905 -408.726271) (xy 385.464867 -408.719998) (xy 385.442913 -408.719998)
			(xy 385.421875 -408.726271) (xy 385.412488 -408.731974) (xy 385.118864 -408.924506) (xy 385.109348 -408.930244)
			(xy 385.088059 -408.936576) (xy 385.076954 -408.936952) (xy 384.88112 -408.936952) (xy 384.869051 -408.936419)
			(xy 384.846092 -408.928968) (xy 384.826558 -408.914787) (xy 384.812361 -408.895266) (xy 384.804891 -408.872313)
			(xy 384.804412 -408.860244) (xy 383.040128 -408.860244) (xy 383.039674 -408.872319) (xy 383.032202 -408.895284)
			(xy 383.018002 -408.914819) (xy 382.998463 -408.929013) (xy 382.975495 -408.936478) (xy 382.96342 -408.936952)
			(xy 382.768856 -408.936952) (xy 382.757747 -408.936594) (xy 382.736451 -408.930266) (xy 382.726946 -408.924506)
			(xy 382.432052 -408.731974) (xy 382.422665 -408.726271) (xy 382.401627 -408.719998) (xy 382.379673 -408.719998)
			(xy 382.358635 -408.726271) (xy 382.349248 -408.731974) (xy 382.055624 -408.924506) (xy 382.046116 -408.930259)
			(xy 382.024821 -408.936582) (xy 382.013714 -408.936952) (xy 381.81788 -408.936952) (xy 381.805809 -408.936453)
			(xy 381.782848 -408.928991) (xy 381.763316 -408.914801) (xy 381.74912 -408.895273) (xy 381.74165 -408.872315)
			(xy 381.741172 -408.860244) (xy 379.976888 -408.860244) (xy 379.976473 -408.872323) (xy 379.968996 -408.895295)
			(xy 379.954787 -408.914833) (xy 379.935238 -408.929025) (xy 379.912259 -408.936483) (xy 379.90018 -408.936952)
			(xy 379.705616 -408.936952) (xy 379.694506 -408.936611) (xy 379.67321 -408.930271) (xy 379.663706 -408.924506)
			(xy 379.368812 -408.731974) (xy 379.359425 -408.726271) (xy 379.338387 -408.719998) (xy 379.316433 -408.719998)
			(xy 379.295395 -408.726271) (xy 379.286008 -408.731974) (xy 378.992384 -408.924506) (xy 378.982884 -408.930274)
			(xy 378.961583 -408.936587) (xy 378.950474 -408.936952) (xy 378.75464 -408.936952) (xy 378.742572 -408.936403)
			(xy 378.719613 -408.928956) (xy 378.700079 -408.91478) (xy 378.685882 -408.895262) (xy 378.678411 -408.872312)
			(xy 378.677932 -408.860244) (xy 376.913648 -408.860244) (xy 376.913174 -408.872317) (xy 376.905704 -408.895279)
			(xy 376.891509 -408.914812) (xy 376.871975 -408.929006) (xy 376.849013 -408.936475) (xy 376.83694 -408.936952)
			(xy 376.642376 -408.936952) (xy 376.631268 -408.936586) (xy 376.609972 -408.930264) (xy 376.600466 -408.924506)
			(xy 376.305572 -408.731974) (xy 376.296185 -408.726271) (xy 376.275147 -408.719998) (xy 376.253193 -408.719998)
			(xy 376.232155 -408.726271) (xy 376.222768 -408.731974) (xy 375.929144 -408.924506) (xy 375.919632 -408.930252)
			(xy 375.89834 -408.936579) (xy 375.887234 -408.936952) (xy 375.6914 -408.936952) (xy 375.67933 -408.936436)
			(xy 375.65637 -408.928979) (xy 375.636837 -408.914794) (xy 375.622641 -408.895269) (xy 375.615171 -408.872314)
			(xy 375.614692 -408.860244) (xy 373.850408 -408.860244) (xy 373.849973 -408.872321) (xy 373.842499 -408.89529)
			(xy 373.828295 -408.914826) (xy 373.80875 -408.929019) (xy 373.785777 -408.93648) (xy 373.7737 -408.936952)
			(xy 373.579136 -408.936952) (xy 373.568027 -408.936602) (xy 373.546731 -408.930269) (xy 373.537226 -408.924506)
			(xy 373.242332 -408.731974) (xy 373.232945 -408.726271) (xy 373.211907 -408.719998) (xy 373.189953 -408.719998)
			(xy 373.168915 -408.726271) (xy 373.159528 -408.731974) (xy 372.865904 -408.924506) (xy 372.8564 -408.930267)
			(xy 372.835102 -408.936584) (xy 372.823994 -408.936952) (xy 372.62816 -408.936952) (xy 372.616088 -408.936471)
			(xy 372.593127 -408.929003) (xy 372.573594 -408.914809) (xy 372.559399 -408.895277) (xy 372.55193 -408.872316)
			(xy 372.551452 -408.860244) (xy 352.35642 -408.860244) (xy 352.356021 -408.872353) (xy 352.348512 -408.895378)
			(xy 352.334245 -408.914949) (xy 352.314622 -408.929143) (xy 352.291569 -408.936566) (xy 352.279458 -408.936952)
			(xy 352.084894 -408.936952) (xy 352.073787 -408.936579) (xy 352.05249 -408.930262) (xy 352.042984 -408.924506)
			(xy 351.74809 -408.731974) (xy 351.738703 -408.726271) (xy 351.717665 -408.719998) (xy 351.695711 -408.719998)
			(xy 351.674673 -408.726271) (xy 351.665286 -408.731974) (xy 351.371662 -408.924506) (xy 351.362147 -408.930245)
			(xy 351.340857 -408.936576) (xy 351.329752 -408.936952) (xy 351.133918 -408.936952) (xy 351.121829 -408.936477)
			(xy 351.098827 -408.929024) (xy 351.079246 -408.91484) (xy 351.064995 -408.895308) (xy 351.057464 -408.872332)
			(xy 351.056956 -408.860244) (xy 349.29318 -408.860244) (xy 349.292821 -408.872357) (xy 349.285307 -408.895389)
			(xy 349.271031 -408.914963) (xy 349.251397 -408.929156) (xy 349.228333 -408.936572) (xy 349.216218 -408.936952)
			(xy 349.021654 -408.936952) (xy 349.010545 -408.936595) (xy 348.989249 -408.930267) (xy 348.979744 -408.924506)
			(xy 348.68485 -408.731974) (xy 348.675463 -408.726271) (xy 348.654425 -408.719998) (xy 348.632471 -408.719998)
			(xy 348.611433 -408.726271) (xy 348.602046 -408.731974) (xy 348.308422 -408.924506) (xy 348.298915 -408.93026)
			(xy 348.277619 -408.936582) (xy 348.266512 -408.936952) (xy 348.070678 -408.936952) (xy 348.058586 -408.936511)
			(xy 348.035584 -408.929048) (xy 348.016003 -408.914855) (xy 348.001754 -408.895315) (xy 347.994224 -408.872334)
			(xy 347.993716 -408.860244) (xy 346.22994 -408.860244) (xy 346.229522 -408.872351) (xy 346.222015 -408.895373)
			(xy 346.207752 -408.914942) (xy 346.188134 -408.929136) (xy 346.165087 -408.936563) (xy 346.152978 -408.936952)
			(xy 345.958414 -408.936952) (xy 345.947304 -408.936611) (xy 345.926008 -408.930272) (xy 345.916504 -408.924506)
			(xy 345.62161 -408.731974) (xy 345.612223 -408.726271) (xy 345.591185 -408.719998) (xy 345.569231 -408.719998)
			(xy 345.548193 -408.726271) (xy 345.538806 -408.731974) (xy 345.245182 -408.924506) (xy 345.235682 -408.930275)
			(xy 345.214381 -408.936588) (xy 345.203272 -408.936952) (xy 345.007438 -408.936952) (xy 344.99535 -408.93646)
			(xy 344.972349 -408.929013) (xy 344.952768 -408.914833) (xy 344.938516 -408.895304) (xy 344.930985 -408.872331)
			(xy 344.930476 -408.860244) (xy 343.1667 -408.860244) (xy 343.166321 -408.872355) (xy 343.15881 -408.895384)
			(xy 343.144538 -408.914956) (xy 343.124909 -408.929149) (xy 343.101851 -408.936569) (xy 343.089738 -408.936952)
			(xy 342.895174 -408.936952) (xy 342.884066 -408.936587) (xy 342.86277 -408.930264) (xy 342.853264 -408.924506)
			(xy 342.55837 -408.731974) (xy 342.548983 -408.726271) (xy 342.527945 -408.719998) (xy 342.505991 -408.719998)
			(xy 342.484953 -408.726271) (xy 342.475566 -408.731974) (xy 342.181942 -408.924506) (xy 342.172431 -408.930253)
			(xy 342.151138 -408.936579) (xy 342.140032 -408.936952) (xy 341.944198 -408.936952) (xy 341.932108 -408.936494)
			(xy 341.909106 -408.929036) (xy 341.889525 -408.914847) (xy 341.875275 -408.895311) (xy 341.867744 -408.872333)
			(xy 341.867236 -408.860244) (xy 340.10346 -408.860244) (xy 340.103121 -408.872359) (xy 340.095604 -408.895395)
			(xy 340.081324 -408.91497) (xy 340.061684 -408.929162) (xy 340.038615 -408.936575) (xy 340.026498 -408.936952)
			(xy 339.831934 -408.936952) (xy 339.820825 -408.936603) (xy 339.799529 -408.930269) (xy 339.790024 -408.924506)
			(xy 339.49513 -408.731974) (xy 339.485743 -408.726271) (xy 339.464705 -408.719998) (xy 339.442751 -408.719998)
			(xy 339.421713 -408.726271) (xy 339.412326 -408.731974) (xy 339.118702 -408.924506) (xy 339.109199 -408.930267)
			(xy 339.0879 -408.936585) (xy 339.076792 -408.936952) (xy 338.880958 -408.936952) (xy 338.868865 -408.936528)
			(xy 338.845862 -408.929059) (xy 338.826282 -408.914862) (xy 338.812033 -408.895319) (xy 338.804504 -408.872335)
			(xy 338.803996 -408.860244) (xy 337.04022 -408.860244) (xy 337.039821 -408.872353) (xy 337.032312 -408.895378)
			(xy 337.018045 -408.914949) (xy 336.998422 -408.929143) (xy 336.975369 -408.936566) (xy 336.963258 -408.936952)
			(xy 336.768694 -408.936952) (xy 336.757587 -408.936579) (xy 336.73629 -408.930262) (xy 336.726784 -408.924506)
			(xy 336.43189 -408.731974) (xy 336.422503 -408.726271) (xy 336.401465 -408.719998) (xy 336.379511 -408.719998)
			(xy 336.358473 -408.726271) (xy 336.349086 -408.731974) (xy 336.055462 -408.924506) (xy 336.045947 -408.930245)
			(xy 336.024657 -408.936576) (xy 336.013552 -408.936952) (xy 335.817718 -408.936952) (xy 335.805629 -408.936477)
			(xy 335.782627 -408.929024) (xy 335.763046 -408.91484) (xy 335.748795 -408.895308) (xy 335.741264 -408.872332)
			(xy 335.740756 -408.860244) (xy 333.97698 -408.860244) (xy 333.976621 -408.872357) (xy 333.969107 -408.895389)
			(xy 333.954831 -408.914963) (xy 333.935197 -408.929156) (xy 333.912133 -408.936572) (xy 333.900018 -408.936952)
			(xy 333.705454 -408.936952) (xy 333.694345 -408.936595) (xy 333.673049 -408.930267) (xy 333.663544 -408.924506)
			(xy 333.36865 -408.731974) (xy 333.359263 -408.726271) (xy 333.338225 -408.719998) (xy 333.316271 -408.719998)
			(xy 333.295233 -408.726271) (xy 333.285846 -408.731974) (xy 332.992222 -408.924506) (xy 332.982715 -408.93026)
			(xy 332.961419 -408.936582) (xy 332.950312 -408.936952) (xy 332.754478 -408.936952) (xy 332.742386 -408.936511)
			(xy 332.719384 -408.929048) (xy 332.699803 -408.914855) (xy 332.685554 -408.895315) (xy 332.678024 -408.872334)
			(xy 332.677516 -408.860244) (xy 330.91374 -408.860244) (xy 330.913322 -408.872351) (xy 330.905815 -408.895373)
			(xy 330.891552 -408.914942) (xy 330.871934 -408.929136) (xy 330.848887 -408.936563) (xy 330.836778 -408.936952)
			(xy 330.642214 -408.936952) (xy 330.631104 -408.936611) (xy 330.609808 -408.930272) (xy 330.600304 -408.924506)
			(xy 330.30541 -408.731974) (xy 330.296023 -408.726271) (xy 330.274985 -408.719998) (xy 330.253031 -408.719998)
			(xy 330.231993 -408.726271) (xy 330.222606 -408.731974) (xy 329.928982 -408.924506) (xy 329.919482 -408.930275)
			(xy 329.898181 -408.936588) (xy 329.887072 -408.936952) (xy 329.691238 -408.936952) (xy 329.67915 -408.93646)
			(xy 329.656149 -408.929013) (xy 329.636568 -408.914833) (xy 329.622316 -408.895304) (xy 329.614785 -408.872331)
			(xy 329.614276 -408.860244) (xy 327.8505 -408.860244) (xy 327.850121 -408.872355) (xy 327.84261 -408.895384)
			(xy 327.828338 -408.914956) (xy 327.808709 -408.929149) (xy 327.785651 -408.936569) (xy 327.773538 -408.936952)
			(xy 327.578974 -408.936952) (xy 327.567866 -408.936587) (xy 327.54657 -408.930264) (xy 327.537064 -408.924506)
			(xy 327.24217 -408.731974) (xy 327.232783 -408.726271) (xy 327.211745 -408.719998) (xy 327.189791 -408.719998)
			(xy 327.168753 -408.726271) (xy 327.159366 -408.731974) (xy 326.865742 -408.924506) (xy 326.856231 -408.930253)
			(xy 326.834938 -408.936579) (xy 326.823832 -408.936952) (xy 326.627998 -408.936952) (xy 326.615908 -408.936494)
			(xy 326.592906 -408.929036) (xy 326.573325 -408.914847) (xy 326.559075 -408.895311) (xy 326.551544 -408.872333)
			(xy 326.551036 -408.860244) (xy 324.78726 -408.860244) (xy 324.786921 -408.872359) (xy 324.779404 -408.895395)
			(xy 324.765124 -408.91497) (xy 324.745484 -408.929162) (xy 324.722415 -408.936575) (xy 324.710298 -408.936952)
			(xy 324.515734 -408.936952) (xy 324.504625 -408.936603) (xy 324.483329 -408.930269) (xy 324.473824 -408.924506)
			(xy 324.17893 -408.731974) (xy 324.169543 -408.726271) (xy 324.148505 -408.719998) (xy 324.126551 -408.719998)
			(xy 324.105513 -408.726271) (xy 324.096126 -408.731974) (xy 323.802502 -408.924506) (xy 323.792999 -408.930267)
			(xy 323.7717 -408.936585) (xy 323.760592 -408.936952) (xy 323.564758 -408.936952) (xy 323.552665 -408.936528)
			(xy 323.529662 -408.929059) (xy 323.510082 -408.914862) (xy 323.495833 -408.895319) (xy 323.488304 -408.872335)
			(xy 323.487796 -408.860244) (xy 321.72402 -408.860244) (xy 321.723621 -408.872353) (xy 321.716112 -408.895378)
			(xy 321.701845 -408.914949) (xy 321.682222 -408.929143) (xy 321.659169 -408.936566) (xy 321.647058 -408.936952)
			(xy 321.452494 -408.936952) (xy 321.441387 -408.936579) (xy 321.42009 -408.930262) (xy 321.410584 -408.924506)
			(xy 321.11569 -408.731974) (xy 321.106303 -408.726271) (xy 321.085265 -408.719998) (xy 321.063311 -408.719998)
			(xy 321.042273 -408.726271) (xy 321.032886 -408.731974) (xy 320.739262 -408.924506) (xy 320.729747 -408.930245)
			(xy 320.708457 -408.936576) (xy 320.697352 -408.936952) (xy 320.501518 -408.936952) (xy 320.489429 -408.936477)
			(xy 320.466427 -408.929024) (xy 320.446846 -408.91484) (xy 320.432595 -408.895308) (xy 320.425064 -408.872332)
			(xy 320.424556 -408.860244) (xy 318.66078 -408.860244) (xy 318.660421 -408.872357) (xy 318.652907 -408.895389)
			(xy 318.638631 -408.914963) (xy 318.618997 -408.929156) (xy 318.595933 -408.936572) (xy 318.583818 -408.936952)
			(xy 318.389254 -408.936952) (xy 318.378145 -408.936595) (xy 318.356849 -408.930267) (xy 318.347344 -408.924506)
			(xy 318.05245 -408.731974) (xy 318.043063 -408.726271) (xy 318.022025 -408.719998) (xy 318.000071 -408.719998)
			(xy 317.979033 -408.726271) (xy 317.969646 -408.731974) (xy 317.676022 -408.924506) (xy 317.666515 -408.93026)
			(xy 317.645219 -408.936582) (xy 317.634112 -408.936952) (xy 317.438278 -408.936952) (xy 317.426186 -408.936511)
			(xy 317.403184 -408.929048) (xy 317.383603 -408.914855) (xy 317.369354 -408.895315) (xy 317.361824 -408.872334)
			(xy 317.361316 -408.860244) (xy 315.59754 -408.860244) (xy 315.597122 -408.872351) (xy 315.589615 -408.895373)
			(xy 315.575352 -408.914942) (xy 315.555734 -408.929136) (xy 315.532687 -408.936563) (xy 315.520578 -408.936952)
			(xy 315.326014 -408.936952) (xy 315.314904 -408.936611) (xy 315.293608 -408.930272) (xy 315.284104 -408.924506)
			(xy 314.98921 -408.731974) (xy 314.979823 -408.726271) (xy 314.958785 -408.719998) (xy 314.936831 -408.719998)
			(xy 314.915793 -408.726271) (xy 314.906406 -408.731974) (xy 314.612782 -408.924506) (xy 314.603282 -408.930275)
			(xy 314.581981 -408.936588) (xy 314.570872 -408.936952) (xy 314.375038 -408.936952) (xy 314.36295 -408.93646)
			(xy 314.339949 -408.929013) (xy 314.320368 -408.914833) (xy 314.306116 -408.895304) (xy 314.298585 -408.872331)
			(xy 314.298076 -408.860244) (xy 312.5343 -408.860244) (xy 312.533921 -408.872355) (xy 312.52641 -408.895384)
			(xy 312.512138 -408.914956) (xy 312.492509 -408.929149) (xy 312.469451 -408.936569) (xy 312.457338 -408.936952)
			(xy 312.262774 -408.936952) (xy 312.251666 -408.936587) (xy 312.23037 -408.930264) (xy 312.220864 -408.924506)
			(xy 311.92597 -408.731974) (xy 311.916583 -408.726271) (xy 311.895545 -408.719998) (xy 311.873591 -408.719998)
			(xy 311.852553 -408.726271) (xy 311.843166 -408.731974) (xy 311.549542 -408.924506) (xy 311.540031 -408.930253)
			(xy 311.518738 -408.936579) (xy 311.507632 -408.936952) (xy 311.311798 -408.936952) (xy 311.299708 -408.936494)
			(xy 311.276706 -408.929036) (xy 311.257125 -408.914847) (xy 311.242875 -408.895311) (xy 311.235344 -408.872333)
			(xy 311.234836 -408.860244) (xy 309.47106 -408.860244) (xy 309.470721 -408.872359) (xy 309.463204 -408.895395)
			(xy 309.448924 -408.91497) (xy 309.429284 -408.929162) (xy 309.406215 -408.936575) (xy 309.394098 -408.936952)
			(xy 309.199534 -408.936952) (xy 309.188425 -408.936603) (xy 309.167129 -408.930269) (xy 309.157624 -408.924506)
			(xy 308.86273 -408.731974) (xy 308.853343 -408.726271) (xy 308.832305 -408.719998) (xy 308.810351 -408.719998)
			(xy 308.789313 -408.726271) (xy 308.779926 -408.731974) (xy 308.486302 -408.924506) (xy 308.476799 -408.930267)
			(xy 308.4555 -408.936585) (xy 308.444392 -408.936952) (xy 308.248558 -408.936952) (xy 308.236465 -408.936528)
			(xy 308.213462 -408.929059) (xy 308.193882 -408.914862) (xy 308.179633 -408.895319) (xy 308.172104 -408.872335)
			(xy 308.171596 -408.860244) (xy 306.40782 -408.860244) (xy 306.407421 -408.872353) (xy 306.399912 -408.895378)
			(xy 306.385645 -408.914949) (xy 306.366022 -408.929143) (xy 306.342969 -408.936566) (xy 306.330858 -408.936952)
			(xy 306.136294 -408.936952) (xy 306.125187 -408.936579) (xy 306.10389 -408.930262) (xy 306.094384 -408.924506)
			(xy 305.79949 -408.731974) (xy 305.790103 -408.726271) (xy 305.769065 -408.719998) (xy 305.747111 -408.719998)
			(xy 305.726073 -408.726271) (xy 305.716686 -408.731974) (xy 305.423062 -408.924506) (xy 305.413547 -408.930245)
			(xy 305.392257 -408.936576) (xy 305.381152 -408.936952) (xy 305.185318 -408.936952) (xy 305.173229 -408.936477)
			(xy 305.150227 -408.929024) (xy 305.130646 -408.91484) (xy 305.116395 -408.895308) (xy 305.108864 -408.872332)
			(xy 305.108356 -408.860244) (xy 280.83256 -408.860244) (xy 280.83256 -410.057453) (xy 304.945246 -410.057453)
			(xy 304.945246 -410.002947) (xy 304.953003 -409.948996) (xy 304.968358 -409.896698) (xy 304.991001 -409.847117)
			(xy 305.020468 -409.801263) (xy 305.056162 -409.76007) (xy 305.097354 -409.724375) (xy 305.143207 -409.694906)
			(xy 305.192786 -409.672263) (xy 305.245084 -409.656905) (xy 305.299035 -409.649147) (xy 305.326288 -409.64866)
			(xy 306.189888 -409.64866) (xy 306.217139 -409.649186) (xy 306.271087 -409.656941) (xy 306.323382 -409.672295)
			(xy 306.372959 -409.694935) (xy 306.41881 -409.7244) (xy 306.460001 -409.760091) (xy 306.495693 -409.80128)
			(xy 306.525159 -409.84713) (xy 306.547801 -409.896707) (xy 306.563156 -409.949001) (xy 306.570913 -410.002949)
			(xy 306.570913 -410.057451) (xy 306.570912 -410.057456) (xy 308.008423 -410.057456) (xy 308.008423 -410.002944)
			(xy 308.016181 -409.948986) (xy 308.03154 -409.896681) (xy 308.054187 -409.847095) (xy 308.08366 -409.801236)
			(xy 308.119359 -409.76004) (xy 308.160559 -409.724343) (xy 308.206419 -409.694873) (xy 308.256007 -409.67223)
			(xy 308.308313 -409.656875) (xy 308.362272 -409.649121) (xy 308.389528 -409.64866) (xy 309.253128 -409.64866)
			(xy 309.280376 -409.649212) (xy 309.334316 -409.656971) (xy 309.386603 -409.672327) (xy 309.436172 -409.694968)
			(xy 309.482015 -409.724433) (xy 309.523199 -409.760121) (xy 309.558884 -409.801307) (xy 309.588345 -409.847152)
			(xy 309.610982 -409.896724) (xy 309.626335 -409.949012) (xy 309.63409 -410.002952) (xy 309.63409 -410.057448)
			(xy 309.634089 -410.057452) (xy 311.071746 -410.057452) (xy 311.071746 -410.002948) (xy 311.079502 -409.948998)
			(xy 311.094857 -409.896702) (xy 311.117498 -409.847123) (xy 311.146963 -409.80127) (xy 311.182654 -409.760077)
			(xy 311.223844 -409.724383) (xy 311.269695 -409.694913) (xy 311.319272 -409.672268) (xy 311.371567 -409.656909)
			(xy 311.425516 -409.649148) (xy 311.452768 -409.64866) (xy 312.316368 -409.64866) (xy 312.34362 -409.649185)
			(xy 312.39757 -409.656938) (xy 312.449867 -409.67229) (xy 312.499447 -409.694928) (xy 312.545301 -409.724393)
			(xy 312.586494 -409.760084) (xy 312.622188 -409.801274) (xy 312.651656 -409.847125) (xy 312.674299 -409.896703)
			(xy 312.689655 -409.948999) (xy 312.697413 -410.002948) (xy 312.697413 -410.057452) (xy 312.697412 -410.057456)
			(xy 314.134923 -410.057456) (xy 314.134923 -410.002944) (xy 314.142681 -409.948988) (xy 314.158039 -409.896685)
			(xy 314.180684 -409.8471) (xy 314.210155 -409.801243) (xy 314.245852 -409.760047) (xy 314.287049 -409.72435)
			(xy 314.332907 -409.69488) (xy 314.382493 -409.672236) (xy 314.434796 -409.656879) (xy 314.488752 -409.649122)
			(xy 314.516008 -409.64866) (xy 315.379608 -409.64866) (xy 315.406857 -409.649211) (xy 315.460799 -409.656968)
			(xy 315.513088 -409.672322) (xy 315.56266 -409.694962) (xy 315.608506 -409.724426) (xy 315.649691 -409.760114)
			(xy 315.685379 -409.801301) (xy 315.714842 -409.847147) (xy 315.737481 -409.896719) (xy 315.752834 -409.949009)
			(xy 315.76059 -410.002951) (xy 315.76059 -410.057449) (xy 315.760589 -410.057457) (xy 317.198123 -410.057457)
			(xy 317.198123 -410.002943) (xy 317.205882 -409.948983) (xy 317.221242 -409.896677) (xy 317.24389 -409.847089)
			(xy 317.273365 -409.80123) (xy 317.309066 -409.760033) (xy 317.350268 -409.724336) (xy 317.396131 -409.694867)
			(xy 317.445722 -409.672225) (xy 317.49803 -409.656872) (xy 317.551991 -409.64912) (xy 317.579248 -409.64866)
			(xy 318.442848 -409.64866) (xy 318.470095 -409.649213) (xy 318.524033 -409.656975) (xy 318.576317 -409.672333)
			(xy 318.625884 -409.694975) (xy 318.671725 -409.72444) (xy 318.712906 -409.760128) (xy 318.748589 -409.801314)
			(xy 318.778048 -409.847158) (xy 318.800684 -409.896728) (xy 318.816035 -409.949014) (xy 318.82379 -410.002953)
			(xy 318.82379 -410.057447) (xy 318.823789 -410.057453) (xy 320.261446 -410.057453) (xy 320.261446 -410.002947)
			(xy 320.269203 -409.948996) (xy 320.284558 -409.896698) (xy 320.307201 -409.847117) (xy 320.336668 -409.801263)
			(xy 320.372362 -409.76007) (xy 320.413554 -409.724375) (xy 320.459407 -409.694906) (xy 320.508986 -409.672263)
			(xy 320.561284 -409.656905) (xy 320.615235 -409.649147) (xy 320.642488 -409.64866) (xy 321.506088 -409.64866)
			(xy 321.533339 -409.649186) (xy 321.587287 -409.656941) (xy 321.639582 -409.672295) (xy 321.689159 -409.694935)
			(xy 321.73501 -409.7244) (xy 321.776201 -409.760091) (xy 321.811893 -409.80128) (xy 321.841359 -409.84713)
			(xy 321.864001 -409.896707) (xy 321.879356 -409.949001) (xy 321.887113 -410.002949) (xy 321.887113 -410.057451)
			(xy 321.887112 -410.057456) (xy 323.324623 -410.057456) (xy 323.324623 -410.002944) (xy 323.332381 -409.948986)
			(xy 323.34774 -409.896681) (xy 323.370387 -409.847095) (xy 323.39986 -409.801236) (xy 323.435559 -409.76004)
			(xy 323.476759 -409.724343) (xy 323.522619 -409.694873) (xy 323.572207 -409.67223) (xy 323.624513 -409.656875)
			(xy 323.678472 -409.649121) (xy 323.705728 -409.64866) (xy 324.569328 -409.64866) (xy 324.596576 -409.649212)
			(xy 324.650516 -409.656971) (xy 324.702803 -409.672327) (xy 324.752372 -409.694968) (xy 324.798215 -409.724433)
			(xy 324.839399 -409.760121) (xy 324.875084 -409.801307) (xy 324.904545 -409.847152) (xy 324.927182 -409.896724)
			(xy 324.942535 -409.949012) (xy 324.95029 -410.002952) (xy 324.95029 -410.057448) (xy 324.950289 -410.057452)
			(xy 326.387946 -410.057452) (xy 326.387946 -410.002948) (xy 326.395702 -409.948998) (xy 326.411057 -409.896702)
			(xy 326.433698 -409.847123) (xy 326.463163 -409.80127) (xy 326.498854 -409.760077) (xy 326.540044 -409.724383)
			(xy 326.585895 -409.694913) (xy 326.635472 -409.672268) (xy 326.687767 -409.656909) (xy 326.741716 -409.649148)
			(xy 326.768968 -409.64866) (xy 327.632568 -409.64866) (xy 327.65982 -409.649185) (xy 327.71377 -409.656938)
			(xy 327.766067 -409.67229) (xy 327.815647 -409.694928) (xy 327.861501 -409.724393) (xy 327.902694 -409.760084)
			(xy 327.938388 -409.801274) (xy 327.967856 -409.847125) (xy 327.990499 -409.896703) (xy 328.005855 -409.948999)
			(xy 328.013613 -410.002948) (xy 328.013613 -410.057452) (xy 328.013612 -410.057456) (xy 329.451123 -410.057456)
			(xy 329.451123 -410.002944) (xy 329.458881 -409.948988) (xy 329.474239 -409.896685) (xy 329.496884 -409.8471)
			(xy 329.526355 -409.801243) (xy 329.562052 -409.760047) (xy 329.603249 -409.72435) (xy 329.649107 -409.69488)
			(xy 329.698693 -409.672236) (xy 329.750996 -409.656879) (xy 329.804952 -409.649122) (xy 329.832208 -409.64866)
			(xy 330.695808 -409.64866) (xy 330.723057 -409.649211) (xy 330.776999 -409.656968) (xy 330.829288 -409.672322)
			(xy 330.87886 -409.694962) (xy 330.924706 -409.724426) (xy 330.965891 -409.760114) (xy 331.001579 -409.801301)
			(xy 331.031042 -409.847147) (xy 331.053681 -409.896719) (xy 331.069034 -409.949009) (xy 331.07679 -410.002951)
			(xy 331.07679 -410.057449) (xy 331.076789 -410.057457) (xy 332.514323 -410.057457) (xy 332.514323 -410.002943)
			(xy 332.522082 -409.948983) (xy 332.537442 -409.896677) (xy 332.56009 -409.847089) (xy 332.589565 -409.80123)
			(xy 332.625266 -409.760033) (xy 332.666468 -409.724336) (xy 332.712331 -409.694867) (xy 332.761922 -409.672225)
			(xy 332.81423 -409.656872) (xy 332.868191 -409.64912) (xy 332.895448 -409.64866) (xy 333.759048 -409.64866)
			(xy 333.786295 -409.649213) (xy 333.840233 -409.656975) (xy 333.892517 -409.672333) (xy 333.942084 -409.694975)
			(xy 333.987925 -409.72444) (xy 334.029106 -409.760128) (xy 334.064789 -409.801314) (xy 334.094248 -409.847158)
			(xy 334.116884 -409.896728) (xy 334.132235 -409.949014) (xy 334.13999 -410.002953) (xy 334.13999 -410.057447)
			(xy 334.139989 -410.057453) (xy 335.577646 -410.057453) (xy 335.577646 -410.002947) (xy 335.585403 -409.948996)
			(xy 335.600758 -409.896698) (xy 335.623401 -409.847117) (xy 335.652868 -409.801263) (xy 335.688562 -409.76007)
			(xy 335.729754 -409.724375) (xy 335.775607 -409.694906) (xy 335.825186 -409.672263) (xy 335.877484 -409.656905)
			(xy 335.931435 -409.649147) (xy 335.958688 -409.64866) (xy 336.822288 -409.64866) (xy 336.849539 -409.649186)
			(xy 336.903487 -409.656941) (xy 336.955782 -409.672295) (xy 337.005359 -409.694935) (xy 337.05121 -409.7244)
			(xy 337.092401 -409.760091) (xy 337.128093 -409.80128) (xy 337.157559 -409.84713) (xy 337.180201 -409.896707)
			(xy 337.195556 -409.949001) (xy 337.203313 -410.002949) (xy 337.203313 -410.057451) (xy 337.203312 -410.057456)
			(xy 338.640823 -410.057456) (xy 338.640823 -410.002944) (xy 338.648581 -409.948986) (xy 338.66394 -409.896681)
			(xy 338.686587 -409.847095) (xy 338.71606 -409.801236) (xy 338.751759 -409.76004) (xy 338.792959 -409.724343)
			(xy 338.838819 -409.694873) (xy 338.888407 -409.67223) (xy 338.940713 -409.656875) (xy 338.994672 -409.649121)
			(xy 339.021928 -409.64866) (xy 339.885528 -409.64866) (xy 339.912776 -409.649212) (xy 339.966716 -409.656971)
			(xy 340.019003 -409.672327) (xy 340.068572 -409.694968) (xy 340.114415 -409.724433) (xy 340.155599 -409.760121)
			(xy 340.191284 -409.801307) (xy 340.220745 -409.847152) (xy 340.243382 -409.896724) (xy 340.258735 -409.949012)
			(xy 340.26649 -410.002952) (xy 340.26649 -410.057448) (xy 340.266489 -410.057452) (xy 341.704146 -410.057452)
			(xy 341.704146 -410.002948) (xy 341.711902 -409.948998) (xy 341.727257 -409.896702) (xy 341.749898 -409.847123)
			(xy 341.779363 -409.80127) (xy 341.815054 -409.760077) (xy 341.856244 -409.724383) (xy 341.902095 -409.694913)
			(xy 341.951672 -409.672268) (xy 342.003967 -409.656909) (xy 342.057916 -409.649148) (xy 342.085168 -409.64866)
			(xy 342.948768 -409.64866) (xy 342.97602 -409.649185) (xy 343.02997 -409.656938) (xy 343.082267 -409.67229)
			(xy 343.131847 -409.694928) (xy 343.177701 -409.724393) (xy 343.218894 -409.760084) (xy 343.254588 -409.801274)
			(xy 343.284056 -409.847125) (xy 343.306699 -409.896703) (xy 343.322055 -409.948999) (xy 343.329813 -410.002948)
			(xy 343.329813 -410.057452) (xy 343.329812 -410.057456) (xy 344.767323 -410.057456) (xy 344.767323 -410.002944)
			(xy 344.775081 -409.948988) (xy 344.790439 -409.896685) (xy 344.813084 -409.8471) (xy 344.842555 -409.801243)
			(xy 344.878252 -409.760047) (xy 344.919449 -409.72435) (xy 344.965307 -409.69488) (xy 345.014893 -409.672236)
			(xy 345.067196 -409.656879) (xy 345.121152 -409.649122) (xy 345.148408 -409.64866) (xy 346.012008 -409.64866)
			(xy 346.039257 -409.649211) (xy 346.093199 -409.656968) (xy 346.145488 -409.672322) (xy 346.19506 -409.694962)
			(xy 346.240906 -409.724426) (xy 346.282091 -409.760114) (xy 346.317779 -409.801301) (xy 346.347242 -409.847147)
			(xy 346.369881 -409.896719) (xy 346.385234 -409.949009) (xy 346.39299 -410.002951) (xy 346.39299 -410.057449)
			(xy 346.392989 -410.057457) (xy 347.830523 -410.057457) (xy 347.830523 -410.002943) (xy 347.838282 -409.948983)
			(xy 347.853642 -409.896677) (xy 347.87629 -409.847089) (xy 347.905765 -409.80123) (xy 347.941466 -409.760033)
			(xy 347.982668 -409.724336) (xy 348.028531 -409.694867) (xy 348.078122 -409.672225) (xy 348.13043 -409.656872)
			(xy 348.184391 -409.64912) (xy 348.211648 -409.64866) (xy 349.075248 -409.64866) (xy 349.102495 -409.649213)
			(xy 349.156433 -409.656975) (xy 349.208717 -409.672333) (xy 349.258284 -409.694975) (xy 349.304125 -409.72444)
			(xy 349.345306 -409.760128) (xy 349.380989 -409.801314) (xy 349.410448 -409.847158) (xy 349.433084 -409.896728)
			(xy 349.448435 -409.949014) (xy 349.45619 -410.002953) (xy 349.45619 -410.057447) (xy 349.456189 -410.057453)
			(xy 350.893846 -410.057453) (xy 350.893846 -410.002947) (xy 350.901603 -409.948996) (xy 350.916958 -409.896698)
			(xy 350.939601 -409.847117) (xy 350.969068 -409.801263) (xy 351.004762 -409.76007) (xy 351.045954 -409.724375)
			(xy 351.091807 -409.694906) (xy 351.141386 -409.672263) (xy 351.193684 -409.656905) (xy 351.247635 -409.649147)
			(xy 351.274888 -409.64866) (xy 352.138488 -409.64866) (xy 352.165739 -409.649186) (xy 352.219687 -409.656941)
			(xy 352.271982 -409.672295) (xy 352.321559 -409.694935) (xy 352.36741 -409.7244) (xy 352.408601 -409.760091)
			(xy 352.444293 -409.80128) (xy 352.473759 -409.84713) (xy 352.496401 -409.896707) (xy 352.511756 -409.949001)
			(xy 352.519513 -410.002949) (xy 352.519513 -410.057451) (xy 352.519512 -410.057457) (xy 372.388023 -410.057457)
			(xy 372.388023 -410.002943) (xy 372.395781 -409.948985) (xy 372.41114 -409.896681) (xy 372.433787 -409.847094)
			(xy 372.46326 -409.801236) (xy 372.49896 -409.760039) (xy 372.54016 -409.724342) (xy 372.586021 -409.694872)
			(xy 372.635609 -409.67223) (xy 372.687915 -409.656875) (xy 372.741873 -409.649121) (xy 372.76913 -409.64866)
			(xy 373.63273 -409.64866) (xy 373.659978 -409.649212) (xy 373.713917 -409.656972) (xy 373.766204 -409.672328)
			(xy 373.815773 -409.694969) (xy 373.861616 -409.724434) (xy 373.902799 -409.760122) (xy 373.938484 -409.801308)
			(xy 373.967945 -409.847153) (xy 373.990583 -409.896724) (xy 374.005935 -409.949012) (xy 374.01369 -410.002952)
			(xy 374.01369 -410.057448) (xy 374.013689 -410.057452) (xy 375.451346 -410.057452) (xy 375.451346 -410.002948)
			(xy 375.459102 -409.948998) (xy 375.474457 -409.896701) (xy 375.497098 -409.847122) (xy 375.526564 -409.801269)
			(xy 375.562255 -409.760076) (xy 375.603445 -409.724382) (xy 375.649296 -409.694912) (xy 375.698873 -409.672268)
			(xy 375.751169 -409.656909) (xy 375.805118 -409.649148) (xy 375.83237 -409.64866) (xy 376.69597 -409.64866)
			(xy 376.723222 -409.649185) (xy 376.777172 -409.656938) (xy 376.829469 -409.67229) (xy 376.879048 -409.694929)
			(xy 376.924901 -409.724394) (xy 376.966094 -409.760084) (xy 377.001788 -409.801274) (xy 377.031257 -409.847125)
			(xy 377.053899 -409.896703) (xy 377.069256 -409.948999) (xy 377.077013 -410.002948) (xy 377.077013 -410.057452)
			(xy 377.077012 -410.057456) (xy 378.514523 -410.057456) (xy 378.514523 -410.002944) (xy 378.522281 -409.948988)
			(xy 378.537639 -409.896685) (xy 378.560284 -409.8471) (xy 378.589755 -409.801242) (xy 378.625453 -409.760046)
			(xy 378.66665 -409.724349) (xy 378.712509 -409.694879) (xy 378.762094 -409.672235) (xy 378.814398 -409.656879)
			(xy 378.868354 -409.649122) (xy 378.89561 -409.64866) (xy 379.75921 -409.64866) (xy 379.786458 -409.649211)
			(xy 379.840401 -409.656968) (xy 379.89269 -409.672323) (xy 379.942261 -409.694962) (xy 379.988107 -409.724426)
			(xy 380.029292 -409.760115) (xy 380.06498 -409.801301) (xy 380.094442 -409.847147) (xy 380.117081 -409.89672)
			(xy 380.132434 -409.949009) (xy 380.14019 -410.002952) (xy 380.14019 -410.057448) (xy 380.14019 -410.057451)
			(xy 381.577846 -410.057451) (xy 381.577846 -410.002949) (xy 381.585602 -409.949001) (xy 381.600955 -409.896706)
			(xy 381.623595 -409.847128) (xy 381.653059 -409.801276) (xy 381.688748 -409.760083) (xy 381.729936 -409.724389)
			(xy 381.775784 -409.694919) (xy 381.825359 -409.672273) (xy 381.877652 -409.656912) (xy 381.931599 -409.649149)
			(xy 381.95885 -409.64866) (xy 382.82245 -409.64866) (xy 382.849703 -409.649184) (xy 382.903655 -409.656934)
			(xy 382.955954 -409.672285) (xy 383.005536 -409.694923) (xy 383.051392 -409.724387) (xy 383.092587 -409.760077)
			(xy 383.128283 -409.801268) (xy 383.157753 -409.84712) (xy 383.180398 -409.896699) (xy 383.195755 -409.948996)
			(xy 383.203513 -410.002947) (xy 383.203513 -410.057453) (xy 384.641046 -410.057453) (xy 384.641046 -410.002947)
			(xy 384.648803 -409.948996) (xy 384.664159 -409.896697) (xy 384.686801 -409.847117) (xy 384.716269 -409.801263)
			(xy 384.751962 -409.760069) (xy 384.793155 -409.724375) (xy 384.839008 -409.694906) (xy 384.888588 -409.672262)
			(xy 384.940886 -409.656905) (xy 384.994837 -409.649147) (xy 385.02209 -409.64866) (xy 385.88569 -409.64866)
			(xy 385.912941 -409.649187) (xy 385.966889 -409.656942) (xy 386.019183 -409.672296) (xy 386.06876 -409.694936)
			(xy 386.114611 -409.724401) (xy 386.155801 -409.760092) (xy 386.191493 -409.801281) (xy 386.22096 -409.847131)
			(xy 386.243601 -409.896707) (xy 386.258956 -409.949002) (xy 386.266713 -410.002949) (xy 386.266713 -410.057451)
			(xy 386.266712 -410.057457) (xy 387.704223 -410.057457) (xy 387.704223 -410.002943) (xy 387.711981 -409.948985)
			(xy 387.72734 -409.896681) (xy 387.749987 -409.847094) (xy 387.77946 -409.801236) (xy 387.81516 -409.760039)
			(xy 387.85636 -409.724342) (xy 387.902221 -409.694872) (xy 387.951809 -409.67223) (xy 388.004115 -409.656875)
			(xy 388.058073 -409.649121) (xy 388.08533 -409.64866) (xy 388.94893 -409.64866) (xy 388.976178 -409.649212)
			(xy 389.030117 -409.656972) (xy 389.082404 -409.672328) (xy 389.131973 -409.694969) (xy 389.177816 -409.724434)
			(xy 389.218999 -409.760122) (xy 389.254684 -409.801308) (xy 389.284145 -409.847153) (xy 389.306783 -409.896724)
			(xy 389.322135 -409.949012) (xy 389.32989 -410.002952) (xy 389.32989 -410.057448) (xy 389.329889 -410.057452)
			(xy 390.767546 -410.057452) (xy 390.767546 -410.002948) (xy 390.775302 -409.948998) (xy 390.790657 -409.896701)
			(xy 390.813298 -409.847122) (xy 390.842764 -409.801269) (xy 390.878455 -409.760076) (xy 390.919645 -409.724382)
			(xy 390.965496 -409.694912) (xy 391.015073 -409.672268) (xy 391.067369 -409.656909) (xy 391.121318 -409.649148)
			(xy 391.14857 -409.64866) (xy 392.01217 -409.64866) (xy 392.039422 -409.649185) (xy 392.093372 -409.656938)
			(xy 392.145669 -409.67229) (xy 392.195248 -409.694929) (xy 392.241101 -409.724394) (xy 392.282294 -409.760084)
			(xy 392.317988 -409.801274) (xy 392.347457 -409.847125) (xy 392.370099 -409.896703) (xy 392.385456 -409.948999)
			(xy 392.393213 -410.002948) (xy 392.393213 -410.057452) (xy 392.393212 -410.057456) (xy 393.830723 -410.057456)
			(xy 393.830723 -410.002944) (xy 393.838481 -409.948988) (xy 393.853839 -409.896685) (xy 393.876484 -409.8471)
			(xy 393.905955 -409.801242) (xy 393.941653 -409.760046) (xy 393.98285 -409.724349) (xy 394.028709 -409.694879)
			(xy 394.078294 -409.672235) (xy 394.130598 -409.656879) (xy 394.184554 -409.649122) (xy 394.21181 -409.64866)
			(xy 395.07541 -409.64866) (xy 395.102658 -409.649211) (xy 395.156601 -409.656968) (xy 395.20889 -409.672323)
			(xy 395.258461 -409.694962) (xy 395.304307 -409.724426) (xy 395.345492 -409.760115) (xy 395.38118 -409.801301)
			(xy 395.410642 -409.847147) (xy 395.433281 -409.89672) (xy 395.448634 -409.949009) (xy 395.45639 -410.002952)
			(xy 395.45639 -410.057448) (xy 395.45639 -410.057451) (xy 396.894046 -410.057451) (xy 396.894046 -410.002949)
			(xy 396.901802 -409.949001) (xy 396.917155 -409.896706) (xy 396.939795 -409.847128) (xy 396.969259 -409.801276)
			(xy 397.004948 -409.760083) (xy 397.046136 -409.724389) (xy 397.091984 -409.694919) (xy 397.141559 -409.672273)
			(xy 397.193852 -409.656912) (xy 397.247799 -409.649149) (xy 397.27505 -409.64866) (xy 398.13865 -409.64866)
			(xy 398.165903 -409.649184) (xy 398.219855 -409.656934) (xy 398.272154 -409.672285) (xy 398.321736 -409.694923)
			(xy 398.367592 -409.724387) (xy 398.408787 -409.760077) (xy 398.444483 -409.801268) (xy 398.473953 -409.84712)
			(xy 398.496598 -409.896699) (xy 398.511955 -409.948996) (xy 398.519713 -410.002947) (xy 398.519713 -410.057453)
			(xy 399.957246 -410.057453) (xy 399.957246 -410.002947) (xy 399.965003 -409.948996) (xy 399.980359 -409.896697)
			(xy 400.003001 -409.847117) (xy 400.032469 -409.801263) (xy 400.068162 -409.760069) (xy 400.109355 -409.724375)
			(xy 400.155208 -409.694906) (xy 400.204788 -409.672262) (xy 400.257086 -409.656905) (xy 400.311037 -409.649147)
			(xy 400.33829 -409.64866) (xy 401.20189 -409.64866) (xy 401.229141 -409.649187) (xy 401.283089 -409.656942)
			(xy 401.335383 -409.672296) (xy 401.38496 -409.694936) (xy 401.430811 -409.724401) (xy 401.472001 -409.760092)
			(xy 401.507693 -409.801281) (xy 401.53716 -409.847131) (xy 401.559801 -409.896707) (xy 401.575156 -409.949002)
			(xy 401.582913 -410.002949) (xy 401.582913 -410.057451) (xy 401.582912 -410.057457) (xy 403.020423 -410.057457)
			(xy 403.020423 -410.002943) (xy 403.028181 -409.948985) (xy 403.04354 -409.896681) (xy 403.066187 -409.847094)
			(xy 403.09566 -409.801236) (xy 403.13136 -409.760039) (xy 403.17256 -409.724342) (xy 403.218421 -409.694872)
			(xy 403.268009 -409.67223) (xy 403.320315 -409.656875) (xy 403.374273 -409.649121) (xy 403.40153 -409.64866)
			(xy 404.26513 -409.64866) (xy 404.292378 -409.649212) (xy 404.346317 -409.656972) (xy 404.398604 -409.672328)
			(xy 404.448173 -409.694969) (xy 404.494016 -409.724434) (xy 404.535199 -409.760122) (xy 404.570884 -409.801308)
			(xy 404.600345 -409.847153) (xy 404.622983 -409.896724) (xy 404.638335 -409.949012) (xy 404.64609 -410.002952)
			(xy 404.64609 -410.057448) (xy 404.646089 -410.057452) (xy 406.083746 -410.057452) (xy 406.083746 -410.002948)
			(xy 406.091502 -409.948998) (xy 406.106857 -409.896701) (xy 406.129498 -409.847122) (xy 406.158964 -409.801269)
			(xy 406.194655 -409.760076) (xy 406.235845 -409.724382) (xy 406.281696 -409.694912) (xy 406.331273 -409.672268)
			(xy 406.383569 -409.656909) (xy 406.437518 -409.649148) (xy 406.46477 -409.64866) (xy 407.32837 -409.64866)
			(xy 407.355622 -409.649185) (xy 407.409572 -409.656938) (xy 407.461869 -409.67229) (xy 407.511448 -409.694929)
			(xy 407.557301 -409.724394) (xy 407.598494 -409.760084) (xy 407.634188 -409.801274) (xy 407.663657 -409.847125)
			(xy 407.686299 -409.896703) (xy 407.701656 -409.948999) (xy 407.709413 -410.002948) (xy 407.709413 -410.057452)
			(xy 407.709412 -410.057456) (xy 409.146923 -410.057456) (xy 409.146923 -410.002944) (xy 409.154681 -409.948988)
			(xy 409.170039 -409.896685) (xy 409.192684 -409.8471) (xy 409.222155 -409.801242) (xy 409.257853 -409.760046)
			(xy 409.29905 -409.724349) (xy 409.344909 -409.694879) (xy 409.394494 -409.672235) (xy 409.446798 -409.656879)
			(xy 409.500754 -409.649122) (xy 409.52801 -409.64866) (xy 410.39161 -409.64866) (xy 410.418858 -409.649211)
			(xy 410.472801 -409.656968) (xy 410.52509 -409.672323) (xy 410.574661 -409.694962) (xy 410.620507 -409.724426)
			(xy 410.661692 -409.760115) (xy 410.69738 -409.801301) (xy 410.726842 -409.847147) (xy 410.749481 -409.89672)
			(xy 410.764834 -409.949009) (xy 410.77259 -410.002952) (xy 410.77259 -410.057448) (xy 410.77259 -410.057451)
			(xy 412.210246 -410.057451) (xy 412.210246 -410.002949) (xy 412.218002 -409.949001) (xy 412.233355 -409.896706)
			(xy 412.255995 -409.847128) (xy 412.285459 -409.801276) (xy 412.321148 -409.760083) (xy 412.362336 -409.724389)
			(xy 412.408184 -409.694919) (xy 412.457759 -409.672273) (xy 412.510052 -409.656912) (xy 412.563999 -409.649149)
			(xy 412.59125 -409.64866) (xy 413.45485 -409.64866) (xy 413.482103 -409.649184) (xy 413.536055 -409.656934)
			(xy 413.588354 -409.672285) (xy 413.637936 -409.694923) (xy 413.683792 -409.724387) (xy 413.724987 -409.760077)
			(xy 413.760683 -409.801268) (xy 413.790153 -409.84712) (xy 413.812798 -409.896699) (xy 413.828155 -409.948996)
			(xy 413.835913 -410.002947) (xy 413.835913 -410.057453) (xy 415.273446 -410.057453) (xy 415.273446 -410.002947)
			(xy 415.281203 -409.948996) (xy 415.296559 -409.896697) (xy 415.319201 -409.847117) (xy 415.348669 -409.801263)
			(xy 415.384362 -409.760069) (xy 415.425555 -409.724375) (xy 415.471408 -409.694906) (xy 415.520988 -409.672262)
			(xy 415.573286 -409.656905) (xy 415.627237 -409.649147) (xy 415.65449 -409.64866) (xy 416.51809 -409.64866)
			(xy 416.545341 -409.649187) (xy 416.599289 -409.656942) (xy 416.651583 -409.672296) (xy 416.70116 -409.694936)
			(xy 416.747011 -409.724401) (xy 416.788201 -409.760092) (xy 416.823893 -409.801281) (xy 416.85336 -409.847131)
			(xy 416.876001 -409.896707) (xy 416.891356 -409.949002) (xy 416.899113 -410.002949) (xy 416.899113 -410.057451)
			(xy 416.899112 -410.057457) (xy 418.336623 -410.057457) (xy 418.336623 -410.002943) (xy 418.344381 -409.948985)
			(xy 418.35974 -409.896681) (xy 418.382387 -409.847094) (xy 418.41186 -409.801236) (xy 418.44756 -409.760039)
			(xy 418.48876 -409.724342) (xy 418.534621 -409.694872) (xy 418.584209 -409.67223) (xy 418.636515 -409.656875)
			(xy 418.690473 -409.649121) (xy 418.71773 -409.64866) (xy 419.58133 -409.64866) (xy 419.608578 -409.649212)
			(xy 419.662517 -409.656972) (xy 419.714804 -409.672328) (xy 419.764373 -409.694969) (xy 419.810216 -409.724434)
			(xy 419.851399 -409.760122) (xy 419.887084 -409.801308) (xy 419.916545 -409.847153) (xy 419.939183 -409.896724)
			(xy 419.954535 -409.949012) (xy 419.96229 -410.002952) (xy 419.96229 -410.057448) (xy 419.954535 -410.111388)
			(xy 419.939183 -410.163676) (xy 419.916545 -410.213247) (xy 419.887084 -410.259092) (xy 419.851399 -410.300278)
			(xy 419.810216 -410.335966) (xy 419.764373 -410.365431) (xy 419.714804 -410.388072) (xy 419.662517 -410.403428)
			(xy 419.608578 -410.411188) (xy 419.58133 -410.411676) (xy 418.71773 -410.411676) (xy 418.690473 -410.411279)
			(xy 418.636515 -410.403525) (xy 418.584209 -410.38817) (xy 418.534621 -410.365528) (xy 418.48876 -410.336058)
			(xy 418.44756 -410.300361) (xy 418.41186 -410.259164) (xy 418.382387 -410.213306) (xy 418.35974 -410.163719)
			(xy 418.344381 -410.111415) (xy 418.336623 -410.057457) (xy 416.899112 -410.057457) (xy 416.891356 -410.111398)
			(xy 416.876001 -410.163693) (xy 416.85336 -410.213269) (xy 416.823893 -410.259119) (xy 416.788201 -410.300308)
			(xy 416.747011 -410.335999) (xy 416.70116 -410.365464) (xy 416.651583 -410.388104) (xy 416.599289 -410.403458)
			(xy 416.545341 -410.411213) (xy 416.51809 -410.411676) (xy 415.65449 -410.411676) (xy 415.627237 -410.411253)
			(xy 415.573286 -410.403495) (xy 415.520988 -410.388138) (xy 415.471408 -410.365494) (xy 415.425555 -410.336025)
			(xy 415.384362 -410.300331) (xy 415.348669 -410.259137) (xy 415.319201 -410.213283) (xy 415.296559 -410.163703)
			(xy 415.281203 -410.111404) (xy 415.273446 -410.057453) (xy 413.835913 -410.057453) (xy 413.828155 -410.111404)
			(xy 413.812798 -410.163701) (xy 413.790153 -410.21328) (xy 413.760683 -410.259132) (xy 413.724987 -410.300323)
			(xy 413.683792 -410.336013) (xy 413.637936 -410.365477) (xy 413.588354 -410.388115) (xy 413.536055 -410.403466)
			(xy 413.482103 -410.411216) (xy 413.45485 -410.411676) (xy 412.59125 -410.411676) (xy 412.563999 -410.411251)
			(xy 412.510052 -410.403488) (xy 412.457759 -410.388127) (xy 412.408184 -410.365481) (xy 412.362336 -410.336011)
			(xy 412.321148 -410.300317) (xy 412.285459 -410.259124) (xy 412.255995 -410.213272) (xy 412.233355 -410.163694)
			(xy 412.218002 -410.111399) (xy 412.210246 -410.057451) (xy 410.77259 -410.057451) (xy 410.764834 -410.111391)
			(xy 410.749481 -410.16368) (xy 410.726842 -410.213253) (xy 410.69738 -410.259099) (xy 410.661692 -410.300285)
			(xy 410.620507 -410.335974) (xy 410.574661 -410.365438) (xy 410.52509 -410.388077) (xy 410.472801 -410.403432)
			(xy 410.418858 -410.411189) (xy 410.39161 -410.411676) (xy 409.52801 -410.411676) (xy 409.500754 -410.411278)
			(xy 409.446798 -410.403521) (xy 409.394494 -410.388165) (xy 409.344909 -410.365521) (xy 409.29905 -410.336051)
			(xy 409.257853 -410.300354) (xy 409.222155 -410.259158) (xy 409.192684 -410.2133) (xy 409.170039 -410.163715)
			(xy 409.154681 -410.111412) (xy 409.146923 -410.057456) (xy 407.709412 -410.057456) (xy 407.701656 -410.111401)
			(xy 407.686299 -410.163697) (xy 407.663657 -410.213275) (xy 407.634188 -410.259126) (xy 407.598494 -410.300316)
			(xy 407.557301 -410.336006) (xy 407.511448 -410.365471) (xy 407.461869 -410.38811) (xy 407.409572 -410.403462)
			(xy 407.355622 -410.411215) (xy 407.32837 -410.411676) (xy 406.46477 -410.411676) (xy 406.437518 -410.411252)
			(xy 406.383569 -410.403491) (xy 406.331273 -410.388132) (xy 406.281696 -410.365488) (xy 406.235845 -410.336018)
			(xy 406.194655 -410.300324) (xy 406.158964 -410.259131) (xy 406.129498 -410.213278) (xy 406.106857 -410.163699)
			(xy 406.091502 -410.111402) (xy 406.083746 -410.057452) (xy 404.646089 -410.057452) (xy 404.638335 -410.111388)
			(xy 404.622983 -410.163676) (xy 404.600345 -410.213247) (xy 404.570884 -410.259092) (xy 404.535199 -410.300278)
			(xy 404.494016 -410.335966) (xy 404.448173 -410.365431) (xy 404.398604 -410.388072) (xy 404.346317 -410.403428)
			(xy 404.292378 -410.411188) (xy 404.26513 -410.411676) (xy 403.40153 -410.411676) (xy 403.374273 -410.411279)
			(xy 403.320315 -410.403525) (xy 403.268009 -410.38817) (xy 403.218421 -410.365528) (xy 403.17256 -410.336058)
			(xy 403.13136 -410.300361) (xy 403.09566 -410.259164) (xy 403.066187 -410.213306) (xy 403.04354 -410.163719)
			(xy 403.028181 -410.111415) (xy 403.020423 -410.057457) (xy 401.582912 -410.057457) (xy 401.575156 -410.111398)
			(xy 401.559801 -410.163693) (xy 401.53716 -410.213269) (xy 401.507693 -410.259119) (xy 401.472001 -410.300308)
			(xy 401.430811 -410.335999) (xy 401.38496 -410.365464) (xy 401.335383 -410.388104) (xy 401.283089 -410.403458)
			(xy 401.229141 -410.411213) (xy 401.20189 -410.411676) (xy 400.33829 -410.411676) (xy 400.311037 -410.411253)
			(xy 400.257086 -410.403495) (xy 400.204788 -410.388138) (xy 400.155208 -410.365494) (xy 400.109355 -410.336025)
			(xy 400.068162 -410.300331) (xy 400.032469 -410.259137) (xy 400.003001 -410.213283) (xy 399.980359 -410.163703)
			(xy 399.965003 -410.111404) (xy 399.957246 -410.057453) (xy 398.519713 -410.057453) (xy 398.511955 -410.111404)
			(xy 398.496598 -410.163701) (xy 398.473953 -410.21328) (xy 398.444483 -410.259132) (xy 398.408787 -410.300323)
			(xy 398.367592 -410.336013) (xy 398.321736 -410.365477) (xy 398.272154 -410.388115) (xy 398.219855 -410.403466)
			(xy 398.165903 -410.411216) (xy 398.13865 -410.411676) (xy 397.27505 -410.411676) (xy 397.247799 -410.411251)
			(xy 397.193852 -410.403488) (xy 397.141559 -410.388127) (xy 397.091984 -410.365481) (xy 397.046136 -410.336011)
			(xy 397.004948 -410.300317) (xy 396.969259 -410.259124) (xy 396.939795 -410.213272) (xy 396.917155 -410.163694)
			(xy 396.901802 -410.111399) (xy 396.894046 -410.057451) (xy 395.45639 -410.057451) (xy 395.448634 -410.111391)
			(xy 395.433281 -410.16368) (xy 395.410642 -410.213253) (xy 395.38118 -410.259099) (xy 395.345492 -410.300285)
			(xy 395.304307 -410.335974) (xy 395.258461 -410.365438) (xy 395.20889 -410.388077) (xy 395.156601 -410.403432)
			(xy 395.102658 -410.411189) (xy 395.07541 -410.411676) (xy 394.21181 -410.411676) (xy 394.184554 -410.411278)
			(xy 394.130598 -410.403521) (xy 394.078294 -410.388165) (xy 394.028709 -410.365521) (xy 393.98285 -410.336051)
			(xy 393.941653 -410.300354) (xy 393.905955 -410.259158) (xy 393.876484 -410.2133) (xy 393.853839 -410.163715)
			(xy 393.838481 -410.111412) (xy 393.830723 -410.057456) (xy 392.393212 -410.057456) (xy 392.385456 -410.111401)
			(xy 392.370099 -410.163697) (xy 392.347457 -410.213275) (xy 392.317988 -410.259126) (xy 392.282294 -410.300316)
			(xy 392.241101 -410.336006) (xy 392.195248 -410.365471) (xy 392.145669 -410.38811) (xy 392.093372 -410.403462)
			(xy 392.039422 -410.411215) (xy 392.01217 -410.411676) (xy 391.14857 -410.411676) (xy 391.121318 -410.411252)
			(xy 391.067369 -410.403491) (xy 391.015073 -410.388132) (xy 390.965496 -410.365488) (xy 390.919645 -410.336018)
			(xy 390.878455 -410.300324) (xy 390.842764 -410.259131) (xy 390.813298 -410.213278) (xy 390.790657 -410.163699)
			(xy 390.775302 -410.111402) (xy 390.767546 -410.057452) (xy 389.329889 -410.057452) (xy 389.322135 -410.111388)
			(xy 389.306783 -410.163676) (xy 389.284145 -410.213247) (xy 389.254684 -410.259092) (xy 389.218999 -410.300278)
			(xy 389.177816 -410.335966) (xy 389.131973 -410.365431) (xy 389.082404 -410.388072) (xy 389.030117 -410.403428)
			(xy 388.976178 -410.411188) (xy 388.94893 -410.411676) (xy 388.08533 -410.411676) (xy 388.058073 -410.411279)
			(xy 388.004115 -410.403525) (xy 387.951809 -410.38817) (xy 387.902221 -410.365528) (xy 387.85636 -410.336058)
			(xy 387.81516 -410.300361) (xy 387.77946 -410.259164) (xy 387.749987 -410.213306) (xy 387.72734 -410.163719)
			(xy 387.711981 -410.111415) (xy 387.704223 -410.057457) (xy 386.266712 -410.057457) (xy 386.258956 -410.111398)
			(xy 386.243601 -410.163693) (xy 386.22096 -410.213269) (xy 386.191493 -410.259119) (xy 386.155801 -410.300308)
			(xy 386.114611 -410.335999) (xy 386.06876 -410.365464) (xy 386.019183 -410.388104) (xy 385.966889 -410.403458)
			(xy 385.912941 -410.411213) (xy 385.88569 -410.411676) (xy 385.02209 -410.411676) (xy 384.994837 -410.411253)
			(xy 384.940886 -410.403495) (xy 384.888588 -410.388138) (xy 384.839008 -410.365494) (xy 384.793155 -410.336025)
			(xy 384.751962 -410.300331) (xy 384.716269 -410.259137) (xy 384.686801 -410.213283) (xy 384.664159 -410.163703)
			(xy 384.648803 -410.111404) (xy 384.641046 -410.057453) (xy 383.203513 -410.057453) (xy 383.195755 -410.111404)
			(xy 383.180398 -410.163701) (xy 383.157753 -410.21328) (xy 383.128283 -410.259132) (xy 383.092587 -410.300323)
			(xy 383.051392 -410.336013) (xy 383.005536 -410.365477) (xy 382.955954 -410.388115) (xy 382.903655 -410.403466)
			(xy 382.849703 -410.411216) (xy 382.82245 -410.411676) (xy 381.95885 -410.411676) (xy 381.931599 -410.411251)
			(xy 381.877652 -410.403488) (xy 381.825359 -410.388127) (xy 381.775784 -410.365481) (xy 381.729936 -410.336011)
			(xy 381.688748 -410.300317) (xy 381.653059 -410.259124) (xy 381.623595 -410.213272) (xy 381.600955 -410.163694)
			(xy 381.585602 -410.111399) (xy 381.577846 -410.057451) (xy 380.14019 -410.057451) (xy 380.132434 -410.111391)
			(xy 380.117081 -410.16368) (xy 380.094442 -410.213253) (xy 380.06498 -410.259099) (xy 380.029292 -410.300285)
			(xy 379.988107 -410.335974) (xy 379.942261 -410.365438) (xy 379.89269 -410.388077) (xy 379.840401 -410.403432)
			(xy 379.786458 -410.411189) (xy 379.75921 -410.411676) (xy 378.89561 -410.411676) (xy 378.868354 -410.411278)
			(xy 378.814398 -410.403521) (xy 378.762094 -410.388165) (xy 378.712509 -410.365521) (xy 378.66665 -410.336051)
			(xy 378.625453 -410.300354) (xy 378.589755 -410.259158) (xy 378.560284 -410.2133) (xy 378.537639 -410.163715)
			(xy 378.522281 -410.111412) (xy 378.514523 -410.057456) (xy 377.077012 -410.057456) (xy 377.069256 -410.111401)
			(xy 377.053899 -410.163697) (xy 377.031257 -410.213275) (xy 377.001788 -410.259126) (xy 376.966094 -410.300316)
			(xy 376.924901 -410.336006) (xy 376.879048 -410.365471) (xy 376.829469 -410.38811) (xy 376.777172 -410.403462)
			(xy 376.723222 -410.411215) (xy 376.69597 -410.411676) (xy 375.83237 -410.411676) (xy 375.805118 -410.411252)
			(xy 375.751169 -410.403491) (xy 375.698873 -410.388132) (xy 375.649296 -410.365488) (xy 375.603445 -410.336018)
			(xy 375.562255 -410.300324) (xy 375.526564 -410.259131) (xy 375.497098 -410.213278) (xy 375.474457 -410.163699)
			(xy 375.459102 -410.111402) (xy 375.451346 -410.057452) (xy 374.013689 -410.057452) (xy 374.005935 -410.111388)
			(xy 373.990583 -410.163676) (xy 373.967945 -410.213247) (xy 373.938484 -410.259092) (xy 373.902799 -410.300278)
			(xy 373.861616 -410.335966) (xy 373.815773 -410.365431) (xy 373.766204 -410.388072) (xy 373.713917 -410.403428)
			(xy 373.659978 -410.411188) (xy 373.63273 -410.411676) (xy 372.76913 -410.411676) (xy 372.741873 -410.411279)
			(xy 372.687915 -410.403525) (xy 372.635609 -410.38817) (xy 372.586021 -410.365528) (xy 372.54016 -410.336058)
			(xy 372.49896 -410.300361) (xy 372.46326 -410.259164) (xy 372.433787 -410.213306) (xy 372.41114 -410.163719)
			(xy 372.395781 -410.111415) (xy 372.388023 -410.057457) (xy 352.519512 -410.057457) (xy 352.511756 -410.111399)
			(xy 352.496401 -410.163693) (xy 352.473759 -410.21327) (xy 352.444293 -410.25912) (xy 352.408601 -410.300309)
			(xy 352.36741 -410.336) (xy 352.321559 -410.365465) (xy 352.271982 -410.388105) (xy 352.219687 -410.403459)
			(xy 352.165739 -410.411214) (xy 352.138488 -410.411676) (xy 351.274888 -410.411676) (xy 351.247635 -410.411253)
			(xy 351.193684 -410.403495) (xy 351.141386 -410.388137) (xy 351.091807 -410.365494) (xy 351.045954 -410.336025)
			(xy 351.004762 -410.30033) (xy 350.969068 -410.259137) (xy 350.939601 -410.213283) (xy 350.916958 -410.163702)
			(xy 350.901603 -410.111404) (xy 350.893846 -410.057453) (xy 349.456189 -410.057453) (xy 349.448435 -410.111386)
			(xy 349.433084 -410.163672) (xy 349.410448 -410.213242) (xy 349.380989 -410.259086) (xy 349.345306 -410.300272)
			(xy 349.304125 -410.33596) (xy 349.258284 -410.365425) (xy 349.208717 -410.388067) (xy 349.156433 -410.403425)
			(xy 349.102495 -410.411187) (xy 349.075248 -410.411676) (xy 348.211648 -410.411676) (xy 348.184391 -410.41128)
			(xy 348.13043 -410.403528) (xy 348.078122 -410.388175) (xy 348.028531 -410.365533) (xy 347.982668 -410.336064)
			(xy 347.941466 -410.300367) (xy 347.905765 -410.25917) (xy 347.87629 -410.213311) (xy 347.853642 -410.163723)
			(xy 347.838282 -410.111417) (xy 347.830523 -410.057457) (xy 346.392989 -410.057457) (xy 346.385234 -410.111391)
			(xy 346.369881 -410.163681) (xy 346.347242 -410.213253) (xy 346.317779 -410.259099) (xy 346.282091 -410.300286)
			(xy 346.240906 -410.335974) (xy 346.19506 -410.365438) (xy 346.145488 -410.388078) (xy 346.093199 -410.403432)
			(xy 346.039257 -410.411189) (xy 346.012008 -410.411676) (xy 345.148408 -410.411676) (xy 345.121152 -410.411278)
			(xy 345.067196 -410.403521) (xy 345.014893 -410.388164) (xy 344.965307 -410.36552) (xy 344.919449 -410.33605)
			(xy 344.878252 -410.300353) (xy 344.842555 -410.259157) (xy 344.813084 -410.2133) (xy 344.790439 -410.163715)
			(xy 344.775081 -410.111412) (xy 344.767323 -410.057456) (xy 343.329812 -410.057456) (xy 343.322055 -410.111401)
			(xy 343.306699 -410.163697) (xy 343.284056 -410.213275) (xy 343.254588 -410.259126) (xy 343.218894 -410.300316)
			(xy 343.177701 -410.336007) (xy 343.131847 -410.365472) (xy 343.082267 -410.38811) (xy 343.02997 -410.403462)
			(xy 342.97602 -410.411215) (xy 342.948768 -410.411676) (xy 342.085168 -410.411676) (xy 342.057916 -410.411252)
			(xy 342.003967 -410.403491) (xy 341.951672 -410.388132) (xy 341.902095 -410.365487) (xy 341.856244 -410.336017)
			(xy 341.815054 -410.300323) (xy 341.779363 -410.25913) (xy 341.749898 -410.213277) (xy 341.727257 -410.163698)
			(xy 341.711902 -410.111402) (xy 341.704146 -410.057452) (xy 340.266489 -410.057452) (xy 340.258735 -410.111388)
			(xy 340.243382 -410.163676) (xy 340.220745 -410.213248) (xy 340.191284 -410.259093) (xy 340.155599 -410.300279)
			(xy 340.114415 -410.335967) (xy 340.068572 -410.365432) (xy 340.019003 -410.388073) (xy 339.966716 -410.403429)
			(xy 339.912776 -410.411188) (xy 339.885528 -410.411676) (xy 339.021928 -410.411676) (xy 338.994672 -410.411279)
			(xy 338.940713 -410.403525) (xy 338.888407 -410.38817) (xy 338.838819 -410.365527) (xy 338.792959 -410.336057)
			(xy 338.751759 -410.30036) (xy 338.71606 -410.259164) (xy 338.686587 -410.213305) (xy 338.66394 -410.163719)
			(xy 338.648581 -410.111414) (xy 338.640823 -410.057456) (xy 337.203312 -410.057456) (xy 337.195556 -410.111399)
			(xy 337.180201 -410.163693) (xy 337.157559 -410.21327) (xy 337.128093 -410.25912) (xy 337.092401 -410.300309)
			(xy 337.05121 -410.336) (xy 337.005359 -410.365465) (xy 336.955782 -410.388105) (xy 336.903487 -410.403459)
			(xy 336.849539 -410.411214) (xy 336.822288 -410.411676) (xy 335.958688 -410.411676) (xy 335.931435 -410.411253)
			(xy 335.877484 -410.403495) (xy 335.825186 -410.388137) (xy 335.775607 -410.365494) (xy 335.729754 -410.336025)
			(xy 335.688562 -410.30033) (xy 335.652868 -410.259137) (xy 335.623401 -410.213283) (xy 335.600758 -410.163702)
			(xy 335.585403 -410.111404) (xy 335.577646 -410.057453) (xy 334.139989 -410.057453) (xy 334.132235 -410.111386)
			(xy 334.116884 -410.163672) (xy 334.094248 -410.213242) (xy 334.064789 -410.259086) (xy 334.029106 -410.300272)
			(xy 333.987925 -410.33596) (xy 333.942084 -410.365425) (xy 333.892517 -410.388067) (xy 333.840233 -410.403425)
			(xy 333.786295 -410.411187) (xy 333.759048 -410.411676) (xy 332.895448 -410.411676) (xy 332.868191 -410.41128)
			(xy 332.81423 -410.403528) (xy 332.761922 -410.388175) (xy 332.712331 -410.365533) (xy 332.666468 -410.336064)
			(xy 332.625266 -410.300367) (xy 332.589565 -410.25917) (xy 332.56009 -410.213311) (xy 332.537442 -410.163723)
			(xy 332.522082 -410.111417) (xy 332.514323 -410.057457) (xy 331.076789 -410.057457) (xy 331.069034 -410.111391)
			(xy 331.053681 -410.163681) (xy 331.031042 -410.213253) (xy 331.001579 -410.259099) (xy 330.965891 -410.300286)
			(xy 330.924706 -410.335974) (xy 330.87886 -410.365438) (xy 330.829288 -410.388078) (xy 330.776999 -410.403432)
			(xy 330.723057 -410.411189) (xy 330.695808 -410.411676) (xy 329.832208 -410.411676) (xy 329.804952 -410.411278)
			(xy 329.750996 -410.403521) (xy 329.698693 -410.388164) (xy 329.649107 -410.36552) (xy 329.603249 -410.33605)
			(xy 329.562052 -410.300353) (xy 329.526355 -410.259157) (xy 329.496884 -410.2133) (xy 329.474239 -410.163715)
			(xy 329.458881 -410.111412) (xy 329.451123 -410.057456) (xy 328.013612 -410.057456) (xy 328.005855 -410.111401)
			(xy 327.990499 -410.163697) (xy 327.967856 -410.213275) (xy 327.938388 -410.259126) (xy 327.902694 -410.300316)
			(xy 327.861501 -410.336007) (xy 327.815647 -410.365472) (xy 327.766067 -410.38811) (xy 327.71377 -410.403462)
			(xy 327.65982 -410.411215) (xy 327.632568 -410.411676) (xy 326.768968 -410.411676) (xy 326.741716 -410.411252)
			(xy 326.687767 -410.403491) (xy 326.635472 -410.388132) (xy 326.585895 -410.365487) (xy 326.540044 -410.336017)
			(xy 326.498854 -410.300323) (xy 326.463163 -410.25913) (xy 326.433698 -410.213277) (xy 326.411057 -410.163698)
			(xy 326.395702 -410.111402) (xy 326.387946 -410.057452) (xy 324.950289 -410.057452) (xy 324.942535 -410.111388)
			(xy 324.927182 -410.163676) (xy 324.904545 -410.213248) (xy 324.875084 -410.259093) (xy 324.839399 -410.300279)
			(xy 324.798215 -410.335967) (xy 324.752372 -410.365432) (xy 324.702803 -410.388073) (xy 324.650516 -410.403429)
			(xy 324.596576 -410.411188) (xy 324.569328 -410.411676) (xy 323.705728 -410.411676) (xy 323.678472 -410.411279)
			(xy 323.624513 -410.403525) (xy 323.572207 -410.38817) (xy 323.522619 -410.365527) (xy 323.476759 -410.336057)
			(xy 323.435559 -410.30036) (xy 323.39986 -410.259164) (xy 323.370387 -410.213305) (xy 323.34774 -410.163719)
			(xy 323.332381 -410.111414) (xy 323.324623 -410.057456) (xy 321.887112 -410.057456) (xy 321.879356 -410.111399)
			(xy 321.864001 -410.163693) (xy 321.841359 -410.21327) (xy 321.811893 -410.25912) (xy 321.776201 -410.300309)
			(xy 321.73501 -410.336) (xy 321.689159 -410.365465) (xy 321.639582 -410.388105) (xy 321.587287 -410.403459)
			(xy 321.533339 -410.411214) (xy 321.506088 -410.411676) (xy 320.642488 -410.411676) (xy 320.615235 -410.411253)
			(xy 320.561284 -410.403495) (xy 320.508986 -410.388137) (xy 320.459407 -410.365494) (xy 320.413554 -410.336025)
			(xy 320.372362 -410.30033) (xy 320.336668 -410.259137) (xy 320.307201 -410.213283) (xy 320.284558 -410.163702)
			(xy 320.269203 -410.111404) (xy 320.261446 -410.057453) (xy 318.823789 -410.057453) (xy 318.816035 -410.111386)
			(xy 318.800684 -410.163672) (xy 318.778048 -410.213242) (xy 318.748589 -410.259086) (xy 318.712906 -410.300272)
			(xy 318.671725 -410.33596) (xy 318.625884 -410.365425) (xy 318.576317 -410.388067) (xy 318.524033 -410.403425)
			(xy 318.470095 -410.411187) (xy 318.442848 -410.411676) (xy 317.579248 -410.411676) (xy 317.551991 -410.41128)
			(xy 317.49803 -410.403528) (xy 317.445722 -410.388175) (xy 317.396131 -410.365533) (xy 317.350268 -410.336064)
			(xy 317.309066 -410.300367) (xy 317.273365 -410.25917) (xy 317.24389 -410.213311) (xy 317.221242 -410.163723)
			(xy 317.205882 -410.111417) (xy 317.198123 -410.057457) (xy 315.760589 -410.057457) (xy 315.752834 -410.111391)
			(xy 315.737481 -410.163681) (xy 315.714842 -410.213253) (xy 315.685379 -410.259099) (xy 315.649691 -410.300286)
			(xy 315.608506 -410.335974) (xy 315.56266 -410.365438) (xy 315.513088 -410.388078) (xy 315.460799 -410.403432)
			(xy 315.406857 -410.411189) (xy 315.379608 -410.411676) (xy 314.516008 -410.411676) (xy 314.488752 -410.411278)
			(xy 314.434796 -410.403521) (xy 314.382493 -410.388164) (xy 314.332907 -410.36552) (xy 314.287049 -410.33605)
			(xy 314.245852 -410.300353) (xy 314.210155 -410.259157) (xy 314.180684 -410.2133) (xy 314.158039 -410.163715)
			(xy 314.142681 -410.111412) (xy 314.134923 -410.057456) (xy 312.697412 -410.057456) (xy 312.689655 -410.111401)
			(xy 312.674299 -410.163697) (xy 312.651656 -410.213275) (xy 312.622188 -410.259126) (xy 312.586494 -410.300316)
			(xy 312.545301 -410.336007) (xy 312.499447 -410.365472) (xy 312.449867 -410.38811) (xy 312.39757 -410.403462)
			(xy 312.34362 -410.411215) (xy 312.316368 -410.411676) (xy 311.452768 -410.411676) (xy 311.425516 -410.411252)
			(xy 311.371567 -410.403491) (xy 311.319272 -410.388132) (xy 311.269695 -410.365487) (xy 311.223844 -410.336017)
			(xy 311.182654 -410.300323) (xy 311.146963 -410.25913) (xy 311.117498 -410.213277) (xy 311.094857 -410.163698)
			(xy 311.079502 -410.111402) (xy 311.071746 -410.057452) (xy 309.634089 -410.057452) (xy 309.626335 -410.111388)
			(xy 309.610982 -410.163676) (xy 309.588345 -410.213248) (xy 309.558884 -410.259093) (xy 309.523199 -410.300279)
			(xy 309.482015 -410.335967) (xy 309.436172 -410.365432) (xy 309.386603 -410.388073) (xy 309.334316 -410.403429)
			(xy 309.280376 -410.411188) (xy 309.253128 -410.411676) (xy 308.389528 -410.411676) (xy 308.362272 -410.411279)
			(xy 308.308313 -410.403525) (xy 308.256007 -410.38817) (xy 308.206419 -410.365527) (xy 308.160559 -410.336057)
			(xy 308.119359 -410.30036) (xy 308.08366 -410.259164) (xy 308.054187 -410.213305) (xy 308.03154 -410.163719)
			(xy 308.016181 -410.111414) (xy 308.008423 -410.057456) (xy 306.570912 -410.057456) (xy 306.563156 -410.111399)
			(xy 306.547801 -410.163693) (xy 306.525159 -410.21327) (xy 306.495693 -410.25912) (xy 306.460001 -410.300309)
			(xy 306.41881 -410.336) (xy 306.372959 -410.365465) (xy 306.323382 -410.388105) (xy 306.271087 -410.403459)
			(xy 306.217139 -410.411214) (xy 306.189888 -410.411676) (xy 305.326288 -410.411676) (xy 305.299035 -410.411253)
			(xy 305.245084 -410.403495) (xy 305.192786 -410.388137) (xy 305.143207 -410.365494) (xy 305.097354 -410.336025)
			(xy 305.056162 -410.30033) (xy 305.020468 -410.259137) (xy 304.991001 -410.213283) (xy 304.968358 -410.163702)
			(xy 304.953003 -410.111404) (xy 304.945246 -410.057453) (xy 280.83256 -410.057453) (xy 280.83256 -415.172652)
			(xy 280.832075 -415.197601) (xy 280.824257 -415.246884) (xy 280.808837 -415.294341) (xy 280.786193 -415.338807)
			(xy 280.756881 -415.37919) (xy 280.739596 -415.397188) (xy 280.152348 -415.984436) (xy 280.134386 -416.001764)
			(xy 280.094003 -416.03109) (xy 280.04953 -416.053738) (xy 280.002061 -416.069148) (xy 279.952766 -416.076943)
			(xy 279.927812 -416.0774) (xy 275.812504 -416.0774) (xy 270.706088 -421.183816) (xy 270.688105 -421.201119)
			(xy 270.647725 -421.230441) (xy 270.603256 -421.253086) (xy 270.555793 -421.268497) (xy 270.506503 -421.276295)
			(xy 270.481552 -421.27678) (xy 233.321352 -421.27678) (xy 231.01554 -423.582592) (xy 231.01554 -424.804386)
			(xy 357.679233 -424.804386) (xy 357.679233 -424.675246) (xy 357.687183 -424.546351) (xy 357.703053 -424.418191)
			(xy 357.726782 -424.29125) (xy 357.758281 -424.166011) (xy 357.79743 -424.042948) (xy 357.844081 -423.922529)
			(xy 357.898056 -423.80521) (xy 357.959151 -423.691436) (xy 358.027134 -423.581639) (xy 358.101748 -423.476236)
			(xy 358.182709 -423.375626) (xy 358.269709 -423.280191) (xy 358.36242 -423.190292) (xy 358.46049 -423.106271)
			(xy 358.563545 -423.028447) (xy 358.671196 -422.957115) (xy 358.783035 -422.892545) (xy 358.898636 -422.834983)
			(xy 359.017561 -422.784646) (xy 359.13936 -422.741726) (xy 359.26357 -422.706385) (xy 359.389719 -422.678758)
			(xy 359.517331 -422.658949) (xy 359.64592 -422.647033) (xy 359.774998 -422.643057) (xy 359.904076 -422.647033)
			(xy 360.032665 -422.658949) (xy 360.160277 -422.678758) (xy 360.286426 -422.706385) (xy 360.410636 -422.741726)
			(xy 360.532435 -422.784646) (xy 360.65136 -422.834983) (xy 360.766961 -422.892545) (xy 360.8788 -422.957115)
			(xy 360.986451 -423.028447) (xy 361.089506 -423.106271) (xy 361.187576 -423.190292) (xy 361.280287 -423.280191)
			(xy 361.367287 -423.375626) (xy 361.448248 -423.476236) (xy 361.522862 -423.581639) (xy 361.590845 -423.691436)
			(xy 361.65194 -423.80521) (xy 361.705915 -423.922529) (xy 361.752566 -424.042948) (xy 361.791715 -424.166011)
			(xy 361.823214 -424.29125) (xy 361.846943 -424.418191) (xy 361.853367 -424.470068) (xy 421.270176 -424.470068)
			(xy 421.270176 -417.770056) (xy 421.270681 -417.664527) (xy 421.278765 -417.453623) (xy 421.294922 -417.243184)
			(xy 421.319127 -417.033518) (xy 421.351345 -416.824934) (xy 421.391528 -416.617736) (xy 421.439619 -416.412229)
			(xy 421.495545 -416.208716) (xy 421.559226 -416.007493) (xy 421.630567 -415.808858) (xy 421.709464 -415.613101)
			(xy 421.795802 -415.420509) (xy 421.889452 -415.231366) (xy 421.990279 -415.045949) (xy 422.098134 -414.864529)
			(xy 422.212858 -414.687374) (xy 422.334284 -414.514743) (xy 422.462233 -414.34689) (xy 422.596517 -414.184061)
			(xy 422.73694 -414.026495) (xy 422.883295 -413.874423) (xy 423.035367 -413.728068) (xy 423.192933 -413.587645)
			(xy 423.355762 -413.453361) (xy 423.523615 -413.325412) (xy 423.696246 -413.203986) (xy 423.873401 -413.089262)
			(xy 424.054821 -412.981407) (xy 424.240238 -412.88058) (xy 424.429381 -412.78693) (xy 424.621973 -412.700592)
			(xy 424.81773 -412.621695) (xy 425.016365 -412.550354) (xy 425.217588 -412.486673) (xy 425.421101 -412.430747)
			(xy 425.626608 -412.382656) (xy 425.833806 -412.342473) (xy 426.04239 -412.310255) (xy 426.252056 -412.28605)
			(xy 426.462495 -412.269893) (xy 426.673399 -412.261809) (xy 426.884457 -412.261809) (xy 427.095361 -412.269893)
			(xy 427.3058 -412.28605) (xy 427.515466 -412.310255) (xy 427.72405 -412.342473) (xy 427.931248 -412.382656)
			(xy 428.136755 -412.430747) (xy 428.340268 -412.486673) (xy 428.541491 -412.550354) (xy 428.740126 -412.621695)
			(xy 428.935883 -412.700592) (xy 429.128475 -412.78693) (xy 429.317618 -412.88058) (xy 429.503035 -412.981407)
			(xy 429.684455 -413.089262) (xy 429.86161 -413.203986) (xy 430.034241 -413.325412) (xy 430.202094 -413.453361)
			(xy 430.364923 -413.587645) (xy 430.522489 -413.728068) (xy 430.674561 -413.874423) (xy 430.820916 -414.026495)
			(xy 430.961339 -414.184061) (xy 431.095623 -414.34689) (xy 431.223572 -414.514743) (xy 431.344998 -414.687374)
			(xy 431.459722 -414.864529) (xy 431.567577 -415.045949) (xy 431.668404 -415.231366) (xy 431.762054 -415.420509)
			(xy 431.848392 -415.613101) (xy 431.927289 -415.808858) (xy 431.99863 -416.007493) (xy 432.062311 -416.208716)
			(xy 432.118237 -416.412229) (xy 432.166328 -416.617736) (xy 432.206511 -416.824934) (xy 432.238729 -417.033518)
			(xy 432.262934 -417.243184) (xy 432.279091 -417.453623) (xy 432.287175 -417.664527) (xy 432.28768 -417.770056)
			(xy 432.28768 -424.470068) (xy 432.287175 -424.575597) (xy 432.279091 -424.786501) (xy 432.262934 -424.99694)
			(xy 432.238729 -425.206606) (xy 432.206511 -425.41519) (xy 432.166328 -425.622388) (xy 432.118237 -425.827895)
			(xy 432.062311 -426.031408) (xy 431.99863 -426.232631) (xy 431.927289 -426.431266) (xy 431.848392 -426.627023)
			(xy 431.762054 -426.819615) (xy 431.668404 -427.008758) (xy 431.567577 -427.194175) (xy 431.459722 -427.375595)
			(xy 431.344998 -427.55275) (xy 431.223572 -427.725381) (xy 431.095623 -427.893234) (xy 430.961339 -428.056063)
			(xy 430.820916 -428.213629) (xy 430.674561 -428.365701) (xy 430.522489 -428.512056) (xy 430.364923 -428.652479)
			(xy 430.202094 -428.786763) (xy 430.034241 -428.914712) (xy 429.86161 -429.036138) (xy 429.684455 -429.150862)
			(xy 429.503035 -429.258717) (xy 429.317618 -429.359544) (xy 429.128475 -429.453194) (xy 428.935883 -429.539532)
			(xy 428.740126 -429.618429) (xy 428.541491 -429.68977) (xy 428.340268 -429.753451) (xy 428.136755 -429.809377)
			(xy 427.931248 -429.857468) (xy 427.72405 -429.897651) (xy 427.515466 -429.929869) (xy 427.3058 -429.954074)
			(xy 427.095361 -429.970231) (xy 426.884457 -429.978315) (xy 426.673399 -429.978315) (xy 426.462495 -429.970231)
			(xy 426.252056 -429.954074) (xy 426.04239 -429.929869) (xy 425.833806 -429.897651) (xy 425.626608 -429.857468)
			(xy 425.421101 -429.809377) (xy 425.217588 -429.753451) (xy 425.016365 -429.68977) (xy 424.81773 -429.618429)
			(xy 424.621973 -429.539532) (xy 424.429381 -429.453194) (xy 424.240238 -429.359544) (xy 424.054821 -429.258717)
			(xy 423.873401 -429.150862) (xy 423.696246 -429.036138) (xy 423.523615 -428.914712) (xy 423.355762 -428.786763)
			(xy 423.192933 -428.652479) (xy 423.035367 -428.512056) (xy 422.883295 -428.365701) (xy 422.73694 -428.213629)
			(xy 422.596517 -428.056063) (xy 422.462233 -427.893234) (xy 422.334284 -427.725381) (xy 422.212858 -427.55275)
			(xy 422.098134 -427.375595) (xy 421.990279 -427.194175) (xy 421.889452 -427.008758) (xy 421.795802 -426.819615)
			(xy 421.709464 -426.627023) (xy 421.630567 -426.431266) (xy 421.559226 -426.232631) (xy 421.495545 -426.031408)
			(xy 421.439619 -425.827895) (xy 421.391528 -425.622388) (xy 421.351345 -425.41519) (xy 421.319127 -425.206606)
			(xy 421.294922 -424.99694) (xy 421.278765 -424.786501) (xy 421.270681 -424.575597) (xy 421.270176 -424.470068)
			(xy 361.853367 -424.470068) (xy 361.862813 -424.546351) (xy 361.870763 -424.675246) (xy 361.87126 -424.739816)
			(xy 361.870763 -424.804386) (xy 361.862813 -424.933281) (xy 361.846943 -425.061441) (xy 361.823214 -425.188382)
			(xy 361.791715 -425.313621) (xy 361.752566 -425.436684) (xy 361.705915 -425.557103) (xy 361.65194 -425.674422)
			(xy 361.590845 -425.788196) (xy 361.522862 -425.897993) (xy 361.448248 -426.003396) (xy 361.367287 -426.104006)
			(xy 361.280287 -426.199441) (xy 361.187576 -426.28934) (xy 361.089506 -426.373361) (xy 360.986451 -426.451185)
			(xy 360.8788 -426.522517) (xy 360.766961 -426.587087) (xy 360.65136 -426.644649) (xy 360.532435 -426.694986)
			(xy 360.410636 -426.737906) (xy 360.286426 -426.773247) (xy 360.160277 -426.800874) (xy 360.032665 -426.820683)
			(xy 359.904076 -426.832599) (xy 359.774998 -426.836576) (xy 359.64592 -426.832599) (xy 359.517331 -426.820683)
			(xy 359.389719 -426.800874) (xy 359.26357 -426.773247) (xy 359.13936 -426.737906) (xy 359.017561 -426.694986)
			(xy 358.898636 -426.644649) (xy 358.783035 -426.587087) (xy 358.671196 -426.522517) (xy 358.563545 -426.451185)
			(xy 358.46049 -426.373361) (xy 358.36242 -426.28934) (xy 358.269709 -426.199441) (xy 358.182709 -426.104006)
			(xy 358.101748 -426.003396) (xy 358.027134 -425.897993) (xy 357.959151 -425.788196) (xy 357.898056 -425.674422)
			(xy 357.844081 -425.557103) (xy 357.79743 -425.436684) (xy 357.758281 -425.313621) (xy 357.726782 -425.188382)
			(xy 357.703053 -425.061441) (xy 357.687183 -424.933281) (xy 357.679233 -424.804386) (xy 231.01554 -424.804386)
			(xy 231.01554 -427.289976) (xy 314.138056 -427.289976) (xy 314.13817 -427.274891) (xy 314.139948 -427.244772)
			(xy 314.141612 -427.229778) (xy 314.141612 -426.150024) (xy 314.139943 -426.135031) (xy 314.138165 -426.104912)
			(xy 314.138056 -426.089826) (xy 314.138166 -426.07474) (xy 314.139947 -426.044622) (xy 314.141612 -426.029628)
			(xy 314.141612 -425.419012) (xy 314.142023 -425.406928) (xy 314.14949 -425.383942) (xy 314.163696 -425.36439)
			(xy 314.183249 -425.350186) (xy 314.206236 -425.342722) (xy 314.21832 -425.342304) (xy 315.15812 -425.342304)
			(xy 315.170197 -425.342748) (xy 315.193167 -425.350217) (xy 315.212704 -425.364419) (xy 315.226898 -425.383962)
			(xy 315.234357 -425.406935) (xy 315.234828 -425.419012) (xy 315.234828 -427.960536) (xy 315.234367 -427.97261)
			(xy 315.226897 -427.995576) (xy 315.212699 -428.01511) (xy 315.193161 -428.029304) (xy 315.170195 -428.036769)
			(xy 315.15812 -428.037244) (xy 314.21832 -428.037244) (xy 314.20625 -428.036719) (xy 314.18329 -428.029267)
			(xy 314.163755 -428.015085) (xy 314.149559 -427.995561) (xy 314.142089 -427.972606) (xy 314.141612 -427.960536)
			(xy 314.141612 -427.350174) (xy 314.139948 -427.33518) (xy 314.138166 -427.305062) (xy 314.138056 -427.289976)
			(xy 231.01554 -427.289976) (xy 231.01554 -428.28972) (xy 316.138052 -428.28972) (xy 316.138162 -428.274634)
			(xy 316.139943 -428.244516) (xy 316.141608 -428.229522) (xy 316.141608 -427.150022) (xy 316.139939 -427.135029)
			(xy 316.138161 -427.10491) (xy 316.138052 -427.089824) (xy 316.138162 -427.074738) (xy 316.139943 -427.04462)
			(xy 316.141608 -427.029626) (xy 316.141608 -426.41901) (xy 316.142115 -426.406924) (xy 316.149565 -426.383929)
			(xy 316.163743 -426.364352) (xy 316.183266 -426.3501) (xy 316.206232 -426.342562) (xy 316.218316 -426.342048)
			(xy 317.158116 -426.342048) (xy 317.170221 -426.342502) (xy 317.193239 -426.349999) (xy 317.212808 -426.364253)
			(xy 317.227004 -426.383863) (xy 317.234433 -426.406904) (xy 317.234824 -426.41901) (xy 317.234824 -427.289976)
			(xy 318.138048 -427.289976) (xy 318.138162 -427.274891) (xy 318.13994 -427.244772) (xy 318.141604 -427.229778)
			(xy 318.141604 -426.150024) (xy 318.139935 -426.135031) (xy 318.138157 -426.104912) (xy 318.138048 -426.089826)
			(xy 318.138158 -426.07474) (xy 318.139939 -426.044622) (xy 318.141604 -426.029628) (xy 318.141604 -425.419012)
			(xy 318.142023 -425.406929) (xy 318.149489 -425.383944) (xy 318.163693 -425.364393) (xy 318.183244 -425.350189)
			(xy 318.206229 -425.342723) (xy 318.218312 -425.342304) (xy 319.158112 -425.342304) (xy 319.170188 -425.342754)
			(xy 319.193158 -425.350222) (xy 319.212696 -425.364421) (xy 319.226889 -425.383964) (xy 319.234349 -425.406935)
			(xy 319.23482 -425.419012) (xy 319.23482 -427.960536) (xy 319.234367 -427.972611) (xy 319.226896 -427.995578)
			(xy 319.212696 -428.015113) (xy 319.193156 -428.029307) (xy 319.170187 -428.036771) (xy 319.158112 -428.037244)
			(xy 318.218312 -428.037244) (xy 318.206242 -428.036726) (xy 318.183281 -428.029271) (xy 318.163747 -428.015087)
			(xy 318.149551 -427.995562) (xy 318.142081 -427.972606) (xy 318.141604 -427.960536) (xy 318.141604 -427.350174)
			(xy 318.13994 -427.33518) (xy 318.138158 -427.305062) (xy 318.138048 -427.289976) (xy 317.234824 -427.289976)
			(xy 317.234824 -428.28972) (xy 320.138044 -428.28972) (xy 320.138154 -428.274634) (xy 320.139935 -428.244516)
			(xy 320.1416 -428.229522) (xy 320.1416 -427.150022) (xy 320.139931 -427.135029) (xy 320.138153 -427.10491)
			(xy 320.138044 -427.089824) (xy 320.138154 -427.074738) (xy 320.139935 -427.04462) (xy 320.1416 -427.029626)
			(xy 320.1416 -426.41901) (xy 320.142115 -426.406925) (xy 320.149564 -426.383931) (xy 320.16374 -426.364355)
			(xy 320.183261 -426.350103) (xy 320.206225 -426.342563) (xy 320.218308 -426.342048) (xy 321.158108 -426.342048)
			(xy 321.170212 -426.342509) (xy 321.193231 -426.350004) (xy 321.212799 -426.364256) (xy 321.226996 -426.383865)
			(xy 321.234425 -426.406905) (xy 321.234816 -426.41901) (xy 321.234816 -427.289976) (xy 322.13804 -427.289976)
			(xy 322.138155 -427.274891) (xy 322.139932 -427.244772) (xy 322.141596 -427.229778) (xy 322.141596 -426.150024)
			(xy 322.139927 -426.135031) (xy 322.138149 -426.104912) (xy 322.13804 -426.089826) (xy 322.13815 -426.07474)
			(xy 322.139931 -426.044622) (xy 322.141596 -426.029628) (xy 322.141596 -425.419012) (xy 322.142023 -425.40693)
			(xy 322.149488 -425.383947) (xy 322.16369 -425.364396) (xy 322.183239 -425.350191) (xy 322.206222 -425.342724)
			(xy 322.218304 -425.342304) (xy 323.158104 -425.342304) (xy 323.170188 -425.342709) (xy 323.193173 -425.350179)
			(xy 323.212724 -425.364387) (xy 323.226928 -425.383941) (xy 323.234393 -425.406928) (xy 323.234812 -425.419012)
			(xy 323.234812 -427.960536) (xy 323.234367 -427.972612) (xy 323.226895 -427.99558) (xy 323.212693 -428.015116)
			(xy 323.193151 -428.029309) (xy 323.17018 -428.036772) (xy 323.158104 -428.037244) (xy 322.218304 -428.037244)
			(xy 322.206233 -428.036733) (xy 322.183272 -428.029276) (xy 322.163738 -428.01509) (xy 322.149542 -427.995564)
			(xy 322.142073 -427.972607) (xy 322.141596 -427.960536) (xy 322.141596 -427.350174) (xy 322.139932 -427.33518)
			(xy 322.13815 -427.305062) (xy 322.13804 -427.289976) (xy 321.234816 -427.289976) (xy 321.234816 -428.28972)
			(xy 324.138036 -428.28972) (xy 324.138148 -428.274634) (xy 324.139929 -428.244516) (xy 324.141592 -428.229522)
			(xy 324.141592 -427.150022) (xy 324.139923 -427.135029) (xy 324.138145 -427.10491) (xy 324.138036 -427.089824)
			(xy 324.138148 -427.074738) (xy 324.139929 -427.04462) (xy 324.141592 -427.029626) (xy 324.141592 -426.41901)
			(xy 324.142115 -426.406926) (xy 324.149563 -426.383934) (xy 324.163737 -426.364358) (xy 324.183256 -426.350105)
			(xy 324.206218 -426.342564) (xy 324.2183 -426.342048) (xy 325.1581 -426.342048) (xy 325.170204 -426.342515)
			(xy 325.193222 -426.350009) (xy 325.212791 -426.364259) (xy 325.226987 -426.383866) (xy 325.234417 -426.406905)
			(xy 325.234808 -426.41901) (xy 325.234808 -427.289976) (xy 326.138032 -427.289976) (xy 326.138149 -427.274891)
			(xy 326.139927 -427.244772) (xy 326.141588 -427.229778) (xy 326.141588 -426.150024) (xy 326.139919 -426.135031)
			(xy 326.138141 -426.104912) (xy 326.138032 -426.089826) (xy 326.138144 -426.07474) (xy 326.139925 -426.044622)
			(xy 326.141588 -426.029628) (xy 326.141588 -425.419012) (xy 326.142023 -425.40693) (xy 326.149487 -425.383949)
			(xy 326.163687 -425.364399) (xy 326.183234 -425.350194) (xy 326.206214 -425.342726) (xy 326.218296 -425.342304)
			(xy 327.158096 -425.342304) (xy 327.17018 -425.342716) (xy 327.193164 -425.350184) (xy 327.212716 -425.36439)
			(xy 327.22692 -425.383943) (xy 327.234385 -425.406928) (xy 327.234804 -425.419012) (xy 327.234804 -427.960536)
			(xy 327.234367 -427.972613) (xy 327.226894 -427.995582) (xy 327.21269 -428.015119) (xy 327.193146 -428.029312)
			(xy 327.170173 -428.036773) (xy 327.158096 -428.037244) (xy 326.218296 -428.037244) (xy 326.206225 -428.03674)
			(xy 326.183264 -428.02928) (xy 326.16373 -428.015093) (xy 326.149534 -427.995565) (xy 326.142065 -427.972607)
			(xy 326.141588 -427.960536) (xy 326.141588 -427.350174) (xy 326.139924 -427.33518) (xy 326.138142 -427.305062)
			(xy 326.138032 -427.289976) (xy 325.234808 -427.289976) (xy 325.234808 -428.28972) (xy 328.138028 -428.28972)
			(xy 328.13814 -428.274634) (xy 328.139921 -428.244516) (xy 328.141584 -428.229522) (xy 328.141584 -427.150022)
			(xy 328.139915 -427.135029) (xy 328.138137 -427.10491) (xy 328.138028 -427.089824) (xy 328.13814 -427.074738)
			(xy 328.139921 -427.04462) (xy 328.141584 -427.029626) (xy 328.141584 -426.41901) (xy 328.142017 -426.406917)
			(xy 328.149476 -426.383909) (xy 328.16367 -426.364325) (xy 328.183214 -426.350076) (xy 328.2062 -426.342551)
			(xy 328.218292 -426.342048) (xy 329.158092 -426.342048) (xy 329.170195 -426.342522) (xy 329.193214 -426.350013)
			(xy 329.212782 -426.364262) (xy 329.226979 -426.383868) (xy 329.234409 -426.406906) (xy 329.2348 -426.41901)
			(xy 329.2348 -427.289976) (xy 331.138022 -427.289976) (xy 331.138113 -427.275402) (xy 331.139767 -427.246301)
			(xy 331.141324 -427.23181) (xy 331.141324 -426.147992) (xy 331.139781 -426.1335) (xy 331.138128 -426.1044)
			(xy 331.138022 -426.089826) (xy 331.138117 -426.075252) (xy 331.139769 -426.046151) (xy 331.141324 -426.03166)
			(xy 331.141324 -425.419012) (xy 331.141727 -425.406901) (xy 331.149226 -425.38387) (xy 331.16349 -425.364295)
			(xy 331.183116 -425.350101) (xy 331.206174 -425.342684) (xy 331.218286 -425.342304) (xy 332.158086 -425.342304)
			(xy 332.170171 -425.342819) (xy 332.193165 -425.350267) (xy 332.212742 -425.364443) (xy 332.226995 -425.383964)
			(xy 332.234533 -425.406929) (xy 332.235048 -425.419012) (xy 332.235048 -427.960536) (xy 332.234615 -427.972642)
			(xy 332.227111 -427.995662) (xy 332.212852 -428.01523) (xy 332.193238 -428.029426) (xy 332.170193 -428.036854)
			(xy 332.158086 -428.037244) (xy 331.218286 -428.037244) (xy 331.206194 -428.036804) (xy 331.18319 -428.029342)
			(xy 331.163609 -428.015149) (xy 331.14936 -427.995609) (xy 331.141831 -427.972627) (xy 331.141324 -427.960536)
			(xy 331.141324 -427.348142) (xy 331.139777 -427.33365) (xy 331.138127 -427.30455) (xy 331.138022 -427.289976)
			(xy 329.2348 -427.289976) (xy 329.2348 -428.28972) (xy 333.138018 -428.28972) (xy 333.138113 -428.275146)
			(xy 333.139764 -428.246045) (xy 333.14132 -428.231554) (xy 333.14132 -427.14799) (xy 333.139777 -427.133498)
			(xy 333.138124 -427.104398) (xy 333.138018 -427.089824) (xy 333.138113 -427.07525) (xy 333.139765 -427.046149)
			(xy 333.14132 -427.031658) (xy 333.14132 -426.41901) (xy 333.14182 -426.406898) (xy 333.149302 -426.383858)
			(xy 333.163538 -426.364258) (xy 333.183133 -426.350015) (xy 333.20617 -426.342525) (xy 333.218282 -426.342048)
			(xy 334.158082 -426.342048) (xy 334.170205 -426.342475) (xy 334.193265 -426.349964) (xy 334.212881 -426.364213)
			(xy 334.227132 -426.383828) (xy 334.234623 -426.406887) (xy 334.235044 -426.41901) (xy 334.235044 -427.289976)
			(xy 335.138014 -427.289976) (xy 335.138104 -427.275402) (xy 335.139759 -427.246301) (xy 335.141316 -427.23181)
			(xy 335.141316 -426.147992) (xy 335.139773 -426.1335) (xy 335.13812 -426.1044) (xy 335.138014 -426.089826)
			(xy 335.138109 -426.075252) (xy 335.13976 -426.046151) (xy 335.141316 -426.03166) (xy 335.141316 -425.419012)
			(xy 335.141727 -425.406902) (xy 335.149225 -425.383873) (xy 335.163487 -425.364298) (xy 335.183111 -425.350104)
			(xy 335.206167 -425.342685) (xy 335.218278 -425.342304) (xy 336.158078 -425.342304) (xy 336.170163 -425.342825)
			(xy 336.193157 -425.350272) (xy 336.212734 -425.364446) (xy 336.226986 -425.383966) (xy 336.234525 -425.406929)
			(xy 336.23504 -425.419012) (xy 336.23504 -427.960536) (xy 336.234615 -427.972643) (xy 336.22711 -427.995664)
			(xy 336.21285 -428.015233) (xy 336.193233 -428.029428) (xy 336.170186 -428.036855) (xy 336.158078 -428.037244)
			(xy 335.218278 -428.037244) (xy 335.206186 -428.036811) (xy 335.183182 -428.029347) (xy 335.163601 -428.015152)
			(xy 335.149351 -427.99561) (xy 335.141823 -427.972627) (xy 335.141316 -427.960536) (xy 335.141316 -427.348142)
			(xy 335.139769 -427.33365) (xy 335.138119 -427.30455) (xy 335.138014 -427.289976) (xy 334.235044 -427.289976)
			(xy 334.235044 -428.28972) (xy 337.13801 -428.28972) (xy 337.138104 -428.275146) (xy 337.139756 -428.246045)
			(xy 337.141312 -428.231554) (xy 337.141312 -427.14799) (xy 337.139769 -427.133498) (xy 337.138116 -427.104398)
			(xy 337.13801 -427.089824) (xy 337.138104 -427.07525) (xy 337.139756 -427.046149) (xy 337.141312 -427.031658)
			(xy 337.141312 -426.41901) (xy 337.14182 -426.406899) (xy 337.149301 -426.38386) (xy 337.163535 -426.36426)
			(xy 337.183128 -426.350018) (xy 337.206163 -426.342526) (xy 337.218274 -426.342048) (xy 338.158074 -426.342048)
			(xy 338.170196 -426.342482) (xy 338.193256 -426.349969) (xy 338.212872 -426.364216) (xy 338.227124 -426.38383)
			(xy 338.234615 -426.406888) (xy 338.235036 -426.41901) (xy 338.235036 -427.289976) (xy 339.138006 -427.289976)
			(xy 339.138096 -427.275402) (xy 339.139751 -427.246301) (xy 339.141308 -427.23181) (xy 339.141308 -426.147992)
			(xy 339.139765 -426.1335) (xy 339.138112 -426.1044) (xy 339.138006 -426.089826) (xy 339.138101 -426.075252)
			(xy 339.139752 -426.046151) (xy 339.141308 -426.03166) (xy 339.141308 -425.419012) (xy 339.141727 -425.406903)
			(xy 339.149224 -425.383875) (xy 339.163485 -425.364301) (xy 339.183106 -425.350106) (xy 339.20616 -425.342687)
			(xy 339.21827 -425.342304) (xy 340.15807 -425.342304) (xy 340.170154 -425.342832) (xy 340.193148 -425.350276)
			(xy 340.212725 -425.364448) (xy 340.226978 -425.383967) (xy 340.234517 -425.40693) (xy 340.235032 -425.419012)
			(xy 340.235032 -427.960536) (xy 340.234615 -427.972644) (xy 340.227109 -427.995667) (xy 340.212847 -428.015236)
			(xy 340.193228 -428.029431) (xy 340.170179 -428.036856) (xy 340.15807 -428.037244) (xy 339.21827 -428.037244)
			(xy 339.206177 -428.036818) (xy 339.183173 -428.029351) (xy 339.163592 -428.015154) (xy 339.149343 -427.995612)
			(xy 339.141815 -427.972627) (xy 339.141308 -427.960536) (xy 339.141308 -427.348142) (xy 339.139761 -427.33365)
			(xy 339.138111 -427.30455) (xy 339.138006 -427.289976) (xy 338.235036 -427.289976) (xy 338.235036 -428.28972)
			(xy 341.138002 -428.28972) (xy 341.138096 -428.275146) (xy 341.139748 -428.246045) (xy 341.141304 -428.231554)
			(xy 341.141304 -427.14799) (xy 341.139761 -427.133498) (xy 341.138108 -427.104398) (xy 341.138002 -427.089824)
			(xy 341.138096 -427.07525) (xy 341.139748 -427.046149) (xy 341.141304 -427.031658) (xy 341.141304 -426.41901)
			(xy 341.14182 -426.406899) (xy 341.1493 -426.383862) (xy 341.163532 -426.364263) (xy 341.183123 -426.35002)
			(xy 341.206156 -426.342527) (xy 341.218266 -426.342048) (xy 342.158066 -426.342048) (xy 342.170188 -426.342489)
			(xy 342.193247 -426.349973) (xy 342.212864 -426.364219) (xy 342.227116 -426.383831) (xy 342.234607 -426.406888)
			(xy 342.235028 -426.41901) (xy 342.235028 -427.289976) (xy 343.137998 -427.289976) (xy 343.138088 -427.275402)
			(xy 343.139743 -427.246301) (xy 343.1413 -427.23181) (xy 343.1413 -426.147992) (xy 343.139757 -426.1335)
			(xy 343.138104 -426.1044) (xy 343.137998 -426.089826) (xy 343.138093 -426.075252) (xy 343.139744 -426.046151)
			(xy 343.1413 -426.03166) (xy 343.1413 -425.419012) (xy 343.141727 -425.406904) (xy 343.149223 -425.383877)
			(xy 343.163482 -425.364304) (xy 343.183101 -425.350109) (xy 343.206152 -425.342688) (xy 343.218262 -425.342304)
			(xy 344.158062 -425.342304) (xy 344.170146 -425.342839) (xy 344.193139 -425.350281) (xy 344.212717 -425.364451)
			(xy 344.22697 -425.383968) (xy 344.234509 -425.40693) (xy 344.235024 -425.419012) (xy 344.235024 -427.960536)
			(xy 344.234615 -427.972644) (xy 344.227108 -427.995669) (xy 344.212844 -428.015239) (xy 344.193223 -428.029433)
			(xy 344.170172 -428.036857) (xy 344.158062 -428.037244) (xy 343.218262 -428.037244) (xy 343.206169 -428.036825)
			(xy 343.183164 -428.029356) (xy 343.163584 -428.015157) (xy 343.149335 -427.995613) (xy 343.141807 -427.972628)
			(xy 343.1413 -427.960536) (xy 343.1413 -427.348142) (xy 343.139753 -427.33365) (xy 343.138103 -427.30455)
			(xy 343.137998 -427.289976) (xy 342.235028 -427.289976) (xy 342.235028 -428.28972) (xy 345.137994 -428.28972)
			(xy 345.138088 -428.275146) (xy 345.13974 -428.246045) (xy 345.141296 -428.231554) (xy 345.141296 -427.14799)
			(xy 345.139753 -427.133498) (xy 345.1381 -427.104398) (xy 345.137994 -427.089824) (xy 345.138088 -427.07525)
			(xy 345.13974 -427.046149) (xy 345.141296 -427.031658) (xy 345.141296 -426.41901) (xy 345.14182 -426.4069)
			(xy 345.149299 -426.383864) (xy 345.163529 -426.364266) (xy 345.183118 -426.350023) (xy 345.206148 -426.342528)
			(xy 345.218258 -426.342048) (xy 346.158058 -426.342048) (xy 346.17018 -426.342496) (xy 346.193239 -426.349978)
			(xy 346.212855 -426.364222) (xy 346.227108 -426.383833) (xy 346.234599 -426.406889) (xy 346.23502 -426.41901)
			(xy 346.23502 -427.289976) (xy 381.237998 -427.289976) (xy 381.238088 -427.275402) (xy 381.239743 -427.246301)
			(xy 381.2413 -427.23181) (xy 381.2413 -426.147992) (xy 381.239757 -426.1335) (xy 381.238104 -426.1044)
			(xy 381.237998 -426.089826) (xy 381.238093 -426.075252) (xy 381.239744 -426.046151) (xy 381.2413 -426.03166)
			(xy 381.2413 -425.419012) (xy 381.241727 -425.406904) (xy 381.249223 -425.383877) (xy 381.263482 -425.364304)
			(xy 381.283101 -425.350109) (xy 381.306152 -425.342688) (xy 381.318262 -425.342304) (xy 382.258062 -425.342304)
			(xy 382.270146 -425.342839) (xy 382.293139 -425.350281) (xy 382.312717 -425.364451) (xy 382.32697 -425.383968)
			(xy 382.334509 -425.40693) (xy 382.335024 -425.419012) (xy 382.335024 -427.960536) (xy 382.334615 -427.972644)
			(xy 382.327108 -427.995669) (xy 382.312844 -428.015239) (xy 382.293223 -428.029433) (xy 382.270172 -428.036857)
			(xy 382.258062 -428.037244) (xy 381.318262 -428.037244) (xy 381.306169 -428.036825) (xy 381.283164 -428.029356)
			(xy 381.263584 -428.015157) (xy 381.249335 -427.995613) (xy 381.241807 -427.972628) (xy 381.2413 -427.960536)
			(xy 381.2413 -427.348142) (xy 381.239753 -427.33365) (xy 381.238103 -427.30455) (xy 381.237998 -427.289976)
			(xy 346.23502 -427.289976) (xy 346.23502 -428.960534) (xy 346.234669 -428.972663) (xy 346.227162 -428.99573)
			(xy 346.212894 -429.015348) (xy 346.193262 -429.029597) (xy 346.170187 -429.03708) (xy 346.158058 -429.037496)
			(xy 345.218258 -429.037496) (xy 345.206145 -429.037025) (xy 345.183106 -429.02953) (xy 345.163508 -429.015287)
			(xy 345.149266 -428.995687) (xy 345.141774 -428.972647) (xy 345.141296 -428.960534) (xy 345.141296 -428.347886)
			(xy 345.139753 -428.333394) (xy 345.1381 -428.304294) (xy 345.137994 -428.28972) (xy 342.235028 -428.28972)
			(xy 342.235028 -428.960534) (xy 342.234617 -428.972654) (xy 342.227116 -428.995704) (xy 342.21286 -429.015308)
			(xy 342.193243 -429.029547) (xy 342.170186 -429.037027) (xy 342.158066 -429.037496) (xy 341.218266 -429.037496)
			(xy 341.206153 -429.037018) (xy 341.183114 -429.029525) (xy 341.163516 -429.015284) (xy 341.149275 -428.995686)
			(xy 341.141782 -428.972647) (xy 341.141304 -428.960534) (xy 341.141304 -428.347886) (xy 341.139761 -428.333394)
			(xy 341.138108 -428.304294) (xy 341.138002 -428.28972) (xy 338.235036 -428.28972) (xy 338.235036 -428.960534)
			(xy 338.234617 -428.972653) (xy 338.227117 -428.995702) (xy 338.212862 -429.015305) (xy 338.193248 -429.029545)
			(xy 338.170193 -429.037026) (xy 338.158074 -429.037496) (xy 337.218274 -429.037496) (xy 337.206161 -429.037011)
			(xy 337.183123 -429.029521) (xy 337.163525 -429.015281) (xy 337.149283 -428.995684) (xy 337.14179 -428.972646)
			(xy 337.141312 -428.960534) (xy 337.141312 -428.347886) (xy 337.139769 -428.333394) (xy 337.138116 -428.304294)
			(xy 337.13801 -428.28972) (xy 334.235044 -428.28972) (xy 334.235044 -428.960534) (xy 334.234617 -428.972652)
			(xy 334.227118 -428.9957) (xy 334.212865 -429.015302) (xy 334.193253 -429.029542) (xy 334.1702 -429.037025)
			(xy 334.158082 -429.037496) (xy 333.218282 -429.037496) (xy 333.20617 -429.037004) (xy 333.183132 -429.029516)
			(xy 333.163533 -429.015278) (xy 333.149291 -428.995683) (xy 333.141798 -428.972646) (xy 333.14132 -428.960534)
			(xy 333.14132 -428.347886) (xy 333.139777 -428.333394) (xy 333.138124 -428.304294) (xy 333.138018 -428.28972)
			(xy 329.2348 -428.28972) (xy 329.2348 -428.960534) (xy 329.234322 -428.972621) (xy 329.226861 -428.995616)
			(xy 329.212676 -429.015192) (xy 329.193148 -429.029443) (xy 329.170178 -429.036981) (xy 329.158092 -429.037496)
			(xy 328.218292 -429.037496) (xy 328.206182 -429.037091) (xy 328.183154 -429.029588) (xy 328.163581 -429.015324)
			(xy 328.149386 -428.9957) (xy 328.141967 -428.972645) (xy 328.141584 -428.960534) (xy 328.141584 -428.349918)
			(xy 328.139915 -428.334925) (xy 328.138137 -428.304806) (xy 328.138028 -428.28972) (xy 325.234808 -428.28972)
			(xy 325.234808 -428.960534) (xy 325.234323 -428.972621) (xy 325.226862 -428.995614) (xy 325.212679 -429.01519)
			(xy 325.193153 -429.029441) (xy 325.170185 -429.03698) (xy 325.1581 -429.037496) (xy 324.2183 -429.037496)
			(xy 324.206191 -429.037084) (xy 324.183163 -429.029584) (xy 324.163589 -429.015321) (xy 324.149395 -428.995699)
			(xy 324.141975 -428.972645) (xy 324.141592 -428.960534) (xy 324.141592 -428.349918) (xy 324.139923 -428.334925)
			(xy 324.138145 -428.304806) (xy 324.138036 -428.28972) (xy 321.234816 -428.28972) (xy 321.234816 -428.960534)
			(xy 321.234421 -428.97263) (xy 321.226949 -428.995639) (xy 321.212746 -429.015222) (xy 321.193195 -429.02947)
			(xy 321.170203 -429.036993) (xy 321.158108 -429.037496) (xy 320.218308 -429.037496) (xy 320.206199 -429.037077)
			(xy 320.183171 -429.029579) (xy 320.163598 -429.015319) (xy 320.149403 -428.995697) (xy 320.141983 -428.972644)
			(xy 320.1416 -428.960534) (xy 320.1416 -428.349918) (xy 320.139931 -428.334925) (xy 320.138153 -428.304806)
			(xy 320.138044 -428.28972) (xy 317.234824 -428.28972) (xy 317.234824 -428.960534) (xy 317.234421 -428.972629)
			(xy 317.226951 -428.995637) (xy 317.212749 -429.015219) (xy 317.1932 -429.029467) (xy 317.17021 -429.036992)
			(xy 317.158116 -429.037496) (xy 316.218316 -429.037496) (xy 316.206208 -429.03707) (xy 316.18318 -429.029574)
			(xy 316.163607 -429.015315) (xy 316.149412 -428.995695) (xy 316.141991 -428.972644) (xy 316.141608 -428.960534)
			(xy 316.141608 -428.349918) (xy 316.139939 -428.334925) (xy 316.138161 -428.304806) (xy 316.138052 -428.28972)
			(xy 231.01554 -428.28972) (xy 231.01554 -433.130695) (xy 266.885917 -433.130695) (xy 266.885917 -432.953425)
			(xy 266.89387 -432.776334) (xy 266.909761 -432.599778) (xy 266.933556 -432.424113) (xy 266.965209 -432.249692)
			(xy 267.004655 -432.076867) (xy 267.051815 -431.905986) (xy 267.106594 -431.737392) (xy 267.168882 -431.571427)
			(xy 267.238554 -431.408422) (xy 267.315468 -431.248708) (xy 267.399471 -431.092605) (xy 267.490392 -430.940428)
			(xy 267.588049 -430.792484) (xy 267.692246 -430.64907) (xy 267.802772 -430.510475) (xy 267.919404 -430.376978)
			(xy 268.041909 -430.248849) (xy 268.170038 -430.126344) (xy 268.303535 -430.009712) (xy 268.44213 -429.899186)
			(xy 268.585544 -429.794989) (xy 268.733488 -429.697332) (xy 268.885665 -429.606411) (xy 269.041768 -429.522408)
			(xy 269.201482 -429.445494) (xy 269.364487 -429.375822) (xy 269.530452 -429.313534) (xy 269.699046 -429.258755)
			(xy 269.869927 -429.211595) (xy 270.042752 -429.172149) (xy 270.217173 -429.140496) (xy 270.392838 -429.116701)
			(xy 270.569394 -429.10081) (xy 270.746485 -429.092857) (xy 270.923755 -429.092857) (xy 271.100846 -429.10081)
			(xy 271.277402 -429.116701) (xy 271.453067 -429.140496) (xy 271.627488 -429.172149) (xy 271.800313 -429.211595)
			(xy 271.971194 -429.258755) (xy 272.139788 -429.313534) (xy 272.305753 -429.375822) (xy 272.468758 -429.445494)
			(xy 272.628472 -429.522408) (xy 272.784575 -429.606411) (xy 272.936752 -429.697332) (xy 273.084696 -429.794989)
			(xy 273.22811 -429.899186) (xy 273.366705 -430.009712) (xy 273.500202 -430.126344) (xy 273.628331 -430.248849)
			(xy 273.750836 -430.376978) (xy 273.867468 -430.510475) (xy 273.977994 -430.64907) (xy 274.082191 -430.792484)
			(xy 274.146507 -430.889918) (xy 314.138056 -430.889918) (xy 314.138165 -430.874832) (xy 314.139947 -430.844714)
			(xy 314.141612 -430.82972) (xy 314.141612 -429.749966) (xy 314.139947 -429.734972) (xy 314.138166 -429.704854)
			(xy 314.138056 -429.689768) (xy 314.13817 -429.674682) (xy 314.139948 -429.644564) (xy 314.141612 -429.62957)
			(xy 314.141612 -429.018954) (xy 314.142068 -429.006865) (xy 314.149534 -428.983867) (xy 314.163724 -428.964291)
			(xy 314.183258 -428.950041) (xy 314.206232 -428.942505) (xy 314.21832 -428.941992) (xy 315.15812 -428.941992)
			(xy 315.170229 -428.942399) (xy 315.193256 -428.949903) (xy 315.212828 -428.964167) (xy 315.227022 -428.98379)
			(xy 315.234444 -429.006843) (xy 315.234828 -429.018954) (xy 315.234828 -431.560478) (xy 315.234373 -431.57257)
			(xy 315.226919 -431.595575) (xy 315.21273 -431.615158) (xy 315.193192 -431.629408) (xy 315.17021 -431.636935)
			(xy 315.15812 -431.63744) (xy 314.21832 -431.63744) (xy 314.206216 -431.636967) (xy 314.183196 -431.629478)
			(xy 314.163627 -431.61523) (xy 314.14943 -431.595622) (xy 314.142001 -431.572583) (xy 314.141612 -431.560478)
			(xy 314.141612 -430.950116) (xy 314.139943 -430.935123) (xy 314.138165 -430.905004) (xy 314.138056 -430.889918)
			(xy 274.146507 -430.889918) (xy 274.179848 -430.940428) (xy 274.270769 -431.092605) (xy 274.354772 -431.248708)
			(xy 274.431686 -431.408422) (xy 274.501358 -431.571427) (xy 274.563646 -431.737392) (xy 274.613204 -431.889916)
			(xy 316.138052 -431.889916) (xy 316.138161 -431.87483) (xy 316.139943 -431.844712) (xy 316.141608 -431.829718)
			(xy 316.141608 -430.749964) (xy 316.139943 -430.73497) (xy 316.138162 -430.704852) (xy 316.138052 -430.689766)
			(xy 316.138166 -430.67468) (xy 316.139944 -430.644562) (xy 316.141608 -430.629568) (xy 316.141608 -430.018952)
			(xy 316.142023 -430.006873) (xy 316.149501 -429.983902) (xy 316.16371 -429.964364) (xy 316.183259 -429.950172)
			(xy 316.206237 -429.942713) (xy 316.218316 -429.942244) (xy 317.158116 -429.942244) (xy 317.170187 -429.94275)
			(xy 317.193146 -429.950211) (xy 317.212679 -429.964399) (xy 317.226874 -429.983925) (xy 317.234345 -430.006882)
			(xy 317.234824 -430.018952) (xy 317.234824 -430.889918) (xy 318.138048 -430.889918) (xy 318.138157 -430.874832)
			(xy 318.139939 -430.844714) (xy 318.141604 -430.82972) (xy 318.141604 -429.749966) (xy 318.139939 -429.734972)
			(xy 318.138158 -429.704854) (xy 318.138048 -429.689768) (xy 318.138162 -429.674682) (xy 318.13994 -429.644564)
			(xy 318.141604 -429.62957) (xy 318.141604 -429.018954) (xy 318.142067 -429.006866) (xy 318.149532 -428.98387)
			(xy 318.163721 -428.964293) (xy 318.183253 -428.950043) (xy 318.206225 -428.942506) (xy 318.218312 -428.941992)
			(xy 319.158112 -428.941992) (xy 319.170221 -428.942406) (xy 319.193247 -428.949908) (xy 319.212819 -428.96417)
			(xy 319.227014 -428.983792) (xy 319.234436 -429.006844) (xy 319.23482 -429.018954) (xy 319.23482 -431.560478)
			(xy 319.234373 -431.57257) (xy 319.226918 -431.595577) (xy 319.212727 -431.615161) (xy 319.193187 -431.629411)
			(xy 319.170203 -431.636936) (xy 319.158112 -431.63744) (xy 318.218312 -431.63744) (xy 318.206208 -431.636974)
			(xy 318.183188 -431.629483) (xy 318.163618 -431.615232) (xy 318.149422 -431.595624) (xy 318.141993 -431.572583)
			(xy 318.141604 -431.560478) (xy 318.141604 -430.950116) (xy 318.139935 -430.935123) (xy 318.138157 -430.905004)
			(xy 318.138048 -430.889918) (xy 317.234824 -430.889918) (xy 317.234824 -431.889916) (xy 320.138044 -431.889916)
			(xy 320.138153 -431.87483) (xy 320.139935 -431.844712) (xy 320.1416 -431.829718) (xy 320.1416 -430.749964)
			(xy 320.139935 -430.73497) (xy 320.138154 -430.704852) (xy 320.138044 -430.689766) (xy 320.138158 -430.67468)
			(xy 320.139936 -430.644562) (xy 320.1416 -430.629568) (xy 320.1416 -430.018952) (xy 320.142023 -430.006874)
			(xy 320.1495 -429.983904) (xy 320.163707 -429.964367) (xy 320.183254 -429.950174) (xy 320.20623 -429.942714)
			(xy 320.218308 -429.942244) (xy 321.158108 -429.942244) (xy 321.170178 -429.942757) (xy 321.193137 -429.950216)
			(xy 321.21267 -429.964401) (xy 321.226866 -429.983927) (xy 321.234337 -430.006882) (xy 321.234816 -430.018952)
			(xy 321.234816 -430.889918) (xy 322.13804 -430.889918) (xy 322.138151 -430.874832) (xy 322.139933 -430.844714)
			(xy 322.141596 -430.82972) (xy 322.141596 -429.749966) (xy 322.139931 -429.734972) (xy 322.13815 -429.704854)
			(xy 322.13804 -429.689768) (xy 322.138154 -429.674682) (xy 322.139932 -429.644564) (xy 322.141596 -429.62957)
			(xy 322.141596 -429.018954) (xy 322.142067 -429.006866) (xy 322.149531 -428.983872) (xy 322.163718 -428.964296)
			(xy 322.183248 -428.950046) (xy 322.206218 -428.942507) (xy 322.218304 -428.941992) (xy 323.158104 -428.941992)
			(xy 323.170212 -428.942413) (xy 323.193238 -428.949912) (xy 323.212811 -428.964173) (xy 323.227006 -428.983793)
			(xy 323.234428 -429.006844) (xy 323.234812 -429.018954) (xy 323.234812 -431.560478) (xy 323.234373 -431.572571)
			(xy 323.226916 -431.595579) (xy 323.212724 -431.615164) (xy 323.193182 -431.629413) (xy 323.170196 -431.636937)
			(xy 323.158104 -431.63744) (xy 322.218304 -431.63744) (xy 322.206199 -431.636981) (xy 322.183179 -431.629488)
			(xy 322.163609 -431.615236) (xy 322.149413 -431.595625) (xy 322.141985 -431.572584) (xy 322.141596 -431.560478)
			(xy 322.141596 -430.950116) (xy 322.139927 -430.935123) (xy 322.138149 -430.905004) (xy 322.13804 -430.889918)
			(xy 321.234816 -430.889918) (xy 321.234816 -431.889916) (xy 324.138036 -431.889916) (xy 324.138147 -431.87483)
			(xy 324.139929 -431.844712) (xy 324.141592 -431.829718) (xy 324.141592 -430.749964) (xy 324.139927 -430.73497)
			(xy 324.138146 -430.704852) (xy 324.138036 -430.689766) (xy 324.138152 -430.674681) (xy 324.13993 -430.644562)
			(xy 324.141592 -430.629568) (xy 324.141592 -430.018952) (xy 324.142023 -430.006875) (xy 324.149499 -429.983906)
			(xy 324.163704 -429.96437) (xy 324.183249 -429.950177) (xy 324.206223 -429.942716) (xy 324.2183 -429.942244)
			(xy 325.1581 -429.942244) (xy 325.17017 -429.942764) (xy 325.193129 -429.95022) (xy 325.212662 -429.964404)
			(xy 325.226858 -429.983928) (xy 325.234329 -430.006883) (xy 325.234808 -430.018952) (xy 325.234808 -430.889918)
			(xy 326.138032 -430.889918) (xy 326.138143 -430.874832) (xy 326.139925 -430.844714) (xy 326.141588 -430.82972)
			(xy 326.141588 -429.749966) (xy 326.139923 -429.734972) (xy 326.138142 -429.704854) (xy 326.138032 -429.689768)
			(xy 326.138148 -429.674683) (xy 326.139926 -429.644564) (xy 326.141588 -429.62957) (xy 326.141588 -429.018954)
			(xy 326.141969 -429.006857) (xy 326.149444 -428.983847) (xy 326.163651 -428.964264) (xy 326.183205 -428.950016)
			(xy 326.2062 -428.942494) (xy 326.218296 -428.941992) (xy 327.158096 -428.941992) (xy 327.170204 -428.942419)
			(xy 327.19323 -428.949917) (xy 327.212802 -428.964176) (xy 327.226997 -428.983795) (xy 327.23442 -429.006845)
			(xy 327.234804 -429.018954) (xy 327.234804 -431.560478) (xy 327.234275 -431.572562) (xy 327.226829 -431.595555)
			(xy 327.212657 -431.615131) (xy 327.19314 -431.629384) (xy 327.170178 -431.636924) (xy 327.158096 -431.63744)
			(xy 326.218296 -431.63744) (xy 326.206191 -431.636988) (xy 326.18317 -431.629492) (xy 326.163601 -431.615238)
			(xy 326.149405 -431.595627) (xy 326.141977 -431.572584) (xy 326.141588 -431.560478) (xy 326.141588 -430.950116)
			(xy 326.139919 -430.935123) (xy 326.138141 -430.905004) (xy 326.138032 -430.889918) (xy 325.234808 -430.889918)
			(xy 325.234808 -431.889916) (xy 328.138028 -431.889916) (xy 328.138139 -431.87483) (xy 328.139921 -431.844712)
			(xy 328.141584 -431.829718) (xy 328.141584 -430.749964) (xy 328.139919 -430.73497) (xy 328.138138 -430.704852)
			(xy 328.138028 -430.689766) (xy 328.138144 -430.674681) (xy 328.139922 -430.644562) (xy 328.141584 -430.629568)
			(xy 328.141584 -430.018952) (xy 328.142023 -430.006876) (xy 328.149498 -429.983908) (xy 328.163701 -429.964373)
			(xy 328.183244 -429.95018) (xy 328.206215 -429.942717) (xy 328.218292 -429.942244) (xy 329.158092 -429.942244)
			(xy 329.170161 -429.94277) (xy 329.19312 -429.950225) (xy 329.212653 -429.964407) (xy 329.22685 -429.98393)
			(xy 329.234321 -430.006883) (xy 329.2348 -430.018952) (xy 329.2348 -430.889918) (xy 331.138022 -430.889918)
			(xy 331.138116 -430.875344) (xy 331.139768 -430.846243) (xy 331.141324 -430.831752) (xy 331.141324 -429.747934)
			(xy 331.139776 -429.733442) (xy 331.138126 -429.704342) (xy 331.138022 -429.689768) (xy 331.138121 -429.675194)
			(xy 331.13977 -429.646093) (xy 331.141324 -429.631602) (xy 331.141324 -429.018954) (xy 331.141772 -429.006838)
			(xy 331.14927 -428.983796) (xy 331.163519 -428.964196) (xy 331.183125 -428.949956) (xy 331.20617 -428.942467)
			(xy 331.218286 -428.941992) (xy 332.158086 -428.941992) (xy 332.170195 -428.942523) (xy 332.19323 -428.950001)
			(xy 332.212828 -428.964229) (xy 332.227072 -428.983816) (xy 332.234568 -429.006845) (xy 332.235048 -429.018954)
			(xy 332.235048 -431.560478) (xy 332.234621 -431.572601) (xy 332.227133 -431.595662) (xy 332.212884 -431.615278)
			(xy 332.193269 -431.62953) (xy 332.170209 -431.63702) (xy 332.158086 -431.63744) (xy 331.218286 -431.63744)
			(xy 331.20616 -431.637051) (xy 331.183097 -431.629553) (xy 331.163481 -431.615294) (xy 331.149231 -431.59567)
			(xy 331.141743 -431.572604) (xy 331.141324 -431.560478) (xy 331.141324 -430.948084) (xy 331.139781 -430.933592)
			(xy 331.138128 -430.904492) (xy 331.138022 -430.889918) (xy 329.2348 -430.889918) (xy 329.2348 -431.889916)
			(xy 333.138018 -431.889916) (xy 333.138112 -431.875342) (xy 333.139764 -431.846241) (xy 333.14132 -431.83175)
			(xy 333.14132 -430.747932) (xy 333.139772 -430.73344) (xy 333.138122 -430.70434) (xy 333.138018 -430.689766)
			(xy 333.138117 -430.675192) (xy 333.139766 -430.646091) (xy 333.14132 -430.6316) (xy 333.14132 -430.018952)
			(xy 333.141676 -430.006839) (xy 333.149191 -429.983806) (xy 333.163467 -429.964232) (xy 333.183103 -429.95004)
			(xy 333.206167 -429.942624) (xy 333.218282 -429.942244) (xy 334.158082 -429.942244) (xy 334.170171 -429.942723)
			(xy 334.193172 -429.950175) (xy 334.212752 -429.964358) (xy 334.227003 -429.98389) (xy 334.234535 -430.006865)
			(xy 334.235044 -430.018952) (xy 334.235044 -430.889918) (xy 335.138014 -430.889918) (xy 335.138108 -430.875344)
			(xy 335.13976 -430.846243) (xy 335.141316 -430.831752) (xy 335.141316 -429.747934) (xy 335.139768 -429.733442)
			(xy 335.138118 -429.704342) (xy 335.138014 -429.689768) (xy 335.138112 -429.675194) (xy 335.139762 -429.646093)
			(xy 335.141316 -429.631602) (xy 335.141316 -429.018954) (xy 335.141772 -429.006839) (xy 335.149269 -428.983798)
			(xy 335.163516 -428.964199) (xy 335.18312 -428.949958) (xy 335.206163 -428.942468) (xy 335.218278 -428.941992)
			(xy 336.158078 -428.941992) (xy 336.170187 -428.94253) (xy 336.193222 -428.950005) (xy 336.21282 -428.964232)
			(xy 336.227064 -428.983817) (xy 336.234559 -429.006846) (xy 336.23504 -429.018954) (xy 336.23504 -431.560478)
			(xy 336.234621 -431.572602) (xy 336.227132 -431.595664) (xy 336.212881 -431.615281) (xy 336.193264 -431.629532)
			(xy 336.170202 -431.637021) (xy 336.158078 -431.63744) (xy 335.218278 -431.63744) (xy 335.20616 -431.637007)
			(xy 335.183112 -431.629511) (xy 335.163509 -431.61526) (xy 335.149269 -431.595648) (xy 335.141786 -431.572596)
			(xy 335.141316 -431.560478) (xy 335.141316 -430.948084) (xy 335.139773 -430.933592) (xy 335.13812 -430.904492)
			(xy 335.138014 -430.889918) (xy 334.235044 -430.889918) (xy 334.235044 -431.889916) (xy 337.13801 -431.889916)
			(xy 337.138104 -431.875342) (xy 337.139756 -431.846241) (xy 337.141312 -431.83175) (xy 337.141312 -430.747932)
			(xy 337.139764 -430.73344) (xy 337.138114 -430.70434) (xy 337.13801 -430.689766) (xy 337.138108 -430.675192)
			(xy 337.139757 -430.646091) (xy 337.141312 -430.6316) (xy 337.141312 -430.018952) (xy 337.141676 -430.006839)
			(xy 337.14919 -429.983809) (xy 337.163465 -429.964235) (xy 337.183098 -429.950043) (xy 337.20616 -429.942625)
			(xy 337.218274 -429.942244) (xy 338.158074 -429.942244) (xy 338.170163 -429.94273) (xy 338.193163 -429.95018)
			(xy 338.212744 -429.964361) (xy 338.226995 -429.983891) (xy 338.234527 -430.006865) (xy 338.235036 -430.018952)
			(xy 338.235036 -430.889918) (xy 339.138006 -430.889918) (xy 339.1381 -430.875344) (xy 339.139752 -430.846243)
			(xy 339.141308 -430.831752) (xy 339.141308 -429.747934) (xy 339.13976 -429.733442) (xy 339.13811 -429.704342)
			(xy 339.138006 -429.689768) (xy 339.138104 -429.675194) (xy 339.139754 -429.646093) (xy 339.141308 -429.631602)
			(xy 339.141308 -429.018954) (xy 339.141772 -429.00684) (xy 339.149268 -428.9838) (xy 339.163513 -428.964202)
			(xy 339.183115 -428.949961) (xy 339.206156 -428.94247) (xy 339.21827 -428.941992) (xy 340.15807 -428.941992)
			(xy 340.170178 -428.942537) (xy 340.193213 -428.95001) (xy 340.212811 -428.964235) (xy 340.227055 -428.983819)
			(xy 340.234551 -429.006846) (xy 340.235032 -429.018954) (xy 340.235032 -431.560478) (xy 340.234621 -431.572603)
			(xy 340.227131 -431.595666) (xy 340.212878 -431.615284) (xy 340.193259 -431.629535) (xy 340.170195 -431.637022)
			(xy 340.15807 -431.63744) (xy 339.21827 -431.63744) (xy 339.206152 -431.637014) (xy 339.183104 -431.629515)
			(xy 339.163501 -431.615262) (xy 339.149261 -431.59565) (xy 339.141778 -431.572597) (xy 339.141308 -431.560478)
			(xy 339.141308 -430.948084) (xy 339.139764 -430.933592) (xy 339.138112 -430.904492) (xy 339.138006 -430.889918)
			(xy 338.235036 -430.889918) (xy 338.235036 -431.889916) (xy 341.138002 -431.889916) (xy 341.138096 -431.875342)
			(xy 341.139748 -431.846241) (xy 341.141304 -431.83175) (xy 341.141304 -430.747932) (xy 341.139756 -430.73344)
			(xy 341.138106 -430.70434) (xy 341.138002 -430.689766) (xy 341.1381 -430.675192) (xy 341.13975 -430.646091)
			(xy 341.141304 -430.6316) (xy 341.141304 -430.018952) (xy 341.141676 -430.00684) (xy 341.149189 -429.983811)
			(xy 341.163462 -429.964238) (xy 341.183093 -429.950045) (xy 341.206153 -429.942626) (xy 341.218266 -429.942244)
			(xy 342.158066 -429.942244) (xy 342.170154 -429.942736) (xy 342.193154 -429.950184) (xy 342.212735 -429.964364)
			(xy 342.226987 -429.983893) (xy 342.234519 -430.006866) (xy 342.235028 -430.018952) (xy 342.235028 -430.889918)
			(xy 343.137998 -430.889918) (xy 343.138092 -430.875344) (xy 343.139744 -430.846243) (xy 343.1413 -430.831752)
			(xy 343.1413 -429.747934) (xy 343.139752 -429.733442) (xy 343.138102 -429.704342) (xy 343.137998 -429.689768)
			(xy 343.138096 -429.675194) (xy 343.139746 -429.646093) (xy 343.1413 -429.631602) (xy 343.1413 -429.018954)
			(xy 343.141772 -429.006841) (xy 343.149267 -428.983803) (xy 343.163511 -428.964205) (xy 343.18311 -428.949964)
			(xy 343.206149 -428.942471) (xy 343.218262 -428.941992) (xy 344.158062 -428.941992) (xy 344.17017 -428.942543)
			(xy 344.193204 -428.950015) (xy 344.212803 -428.964238) (xy 344.227047 -428.98382) (xy 344.234543 -429.006847)
			(xy 344.235024 -429.018954) (xy 344.235024 -431.560478) (xy 344.234621 -431.572603) (xy 344.22713 -431.595668)
			(xy 344.212875 -431.615287) (xy 344.193254 -431.629537) (xy 344.170187 -431.637023) (xy 344.158062 -431.63744)
			(xy 343.218262 -431.63744) (xy 343.206143 -431.63702) (xy 343.183095 -431.62952) (xy 343.163492 -431.615265)
			(xy 343.149253 -431.595651) (xy 343.14177 -431.572597) (xy 343.1413 -431.560478) (xy 343.1413 -430.948084)
			(xy 343.139756 -430.933592) (xy 343.138104 -430.904492) (xy 343.137998 -430.889918) (xy 342.235028 -430.889918)
			(xy 342.235028 -431.889916) (xy 345.137994 -431.889916) (xy 345.138088 -431.875342) (xy 345.13974 -431.846241)
			(xy 345.141296 -431.83175) (xy 345.141296 -430.747932) (xy 345.139748 -430.73344) (xy 345.138098 -430.70434)
			(xy 345.137994 -430.689766) (xy 345.138092 -430.675192) (xy 345.139742 -430.646091) (xy 345.141296 -430.6316)
			(xy 345.141296 -430.018952) (xy 345.141676 -430.006841) (xy 345.149188 -429.983813) (xy 345.163459 -429.964241)
			(xy 345.183088 -429.950048) (xy 345.206145 -429.942628) (xy 345.218258 -429.942244) (xy 346.158058 -429.942244)
			(xy 346.170146 -429.942743) (xy 346.193146 -429.950189) (xy 346.212727 -429.964367) (xy 346.226979 -429.983894)
			(xy 346.234511 -430.006866) (xy 346.23502 -430.018952) (xy 346.23502 -431.359818) (xy 356.154736 -431.359818)
			(xy 356.155234 -431.274938) (xy 356.163191 -431.105365) (xy 356.179087 -430.936351) (xy 356.202888 -430.768268)
			(xy 356.234542 -430.601485) (xy 356.273978 -430.436369) (xy 356.32111 -430.273284) (xy 356.375834 -430.112586)
			(xy 356.438031 -429.954631) (xy 356.507563 -429.799764) (xy 356.584278 -429.648327) (xy 356.668006 -429.500651)
			(xy 356.758564 -429.357063) (xy 356.855753 -429.217877) (xy 356.95936 -429.0834) (xy 357.069155 -428.953927)
			(xy 357.184899 -428.829742) (xy 357.306336 -428.711119) (xy 357.4332 -428.598318) (xy 357.565211 -428.491588)
			(xy 357.702081 -428.391163) (xy 357.843506 -428.297264) (xy 357.989178 -428.210096) (xy 358.138776 -428.129853)
			(xy 358.29197 -428.056709) (xy 358.448424 -427.990827) (xy 358.607794 -427.93235) (xy 358.76973 -427.881408)
			(xy 358.933876 -427.838112) (xy 359.099871 -427.802557) (xy 359.26735 -427.774822) (xy 359.435945 -427.754968)
			(xy 359.605285 -427.743038) (xy 359.774998 -427.739059) (xy 359.944711 -427.743038) (xy 360.114051 -427.754968)
			(xy 360.282646 -427.774822) (xy 360.450125 -427.802557) (xy 360.61612 -427.838112) (xy 360.780266 -427.881408)
			(xy 360.942202 -427.93235) (xy 361.101572 -427.990827) (xy 361.258026 -428.056709) (xy 361.41122 -428.129853)
			(xy 361.560818 -428.210096) (xy 361.693883 -428.28972) (xy 383.237994 -428.28972) (xy 383.238088 -428.275146)
			(xy 383.23974 -428.246045) (xy 383.241296 -428.231554) (xy 383.241296 -427.14799) (xy 383.239753 -427.133498)
			(xy 383.2381 -427.104398) (xy 383.237994 -427.089824) (xy 383.238088 -427.07525) (xy 383.23974 -427.046149)
			(xy 383.241296 -427.031658) (xy 383.241296 -426.41901) (xy 383.24182 -426.4069) (xy 383.249299 -426.383864)
			(xy 383.263529 -426.364266) (xy 383.283118 -426.350023) (xy 383.306148 -426.342528) (xy 383.318258 -426.342048)
			(xy 384.258058 -426.342048) (xy 384.27018 -426.342496) (xy 384.293239 -426.349978) (xy 384.312855 -426.364222)
			(xy 384.327108 -426.383833) (xy 384.334599 -426.406889) (xy 384.33502 -426.41901) (xy 384.33502 -427.289976)
			(xy 385.23799 -427.289976) (xy 385.23808 -427.275402) (xy 385.239735 -427.246301) (xy 385.241292 -427.23181)
			(xy 385.241292 -426.147992) (xy 385.239749 -426.1335) (xy 385.238096 -426.1044) (xy 385.23799 -426.089826)
			(xy 385.238085 -426.075252) (xy 385.239736 -426.046151) (xy 385.241292 -426.03166) (xy 385.241292 -425.419012)
			(xy 385.241727 -425.406905) (xy 385.249222 -425.383879) (xy 385.263479 -425.364307) (xy 385.283096 -425.350111)
			(xy 385.306145 -425.342689) (xy 385.318254 -425.342304) (xy 386.258054 -425.342304) (xy 386.270138 -425.342846)
			(xy 386.293131 -425.350286) (xy 386.312708 -425.364454) (xy 386.326962 -425.38397) (xy 386.334501 -425.40693)
			(xy 386.335016 -425.419012) (xy 386.335016 -427.960536) (xy 386.334615 -427.972645) (xy 386.327107 -427.995671)
			(xy 386.312841 -428.015242) (xy 386.293218 -428.029436) (xy 386.270165 -428.036859) (xy 386.258054 -428.037244)
			(xy 385.318254 -428.037244) (xy 385.30616 -428.036832) (xy 385.283156 -428.02936) (xy 385.263575 -428.01516)
			(xy 385.249327 -427.995615) (xy 385.241799 -427.972628) (xy 385.241292 -427.960536) (xy 385.241292 -427.348142)
			(xy 385.239745 -427.33365) (xy 385.238095 -427.30455) (xy 385.23799 -427.289976) (xy 384.33502 -427.289976)
			(xy 384.33502 -428.28972) (xy 387.237986 -428.28972) (xy 387.23808 -428.275146) (xy 387.239732 -428.246045)
			(xy 387.241288 -428.231554) (xy 387.241288 -427.14799) (xy 387.239745 -427.133498) (xy 387.238092 -427.104398)
			(xy 387.237986 -427.089824) (xy 387.238081 -427.07525) (xy 387.239732 -427.046149) (xy 387.241288 -427.031658)
			(xy 387.241288 -426.41901) (xy 387.24182 -426.406901) (xy 387.249298 -426.383867) (xy 387.263526 -426.364269)
			(xy 387.283113 -426.350025) (xy 387.306141 -426.342529) (xy 387.31825 -426.342048) (xy 388.25805 -426.342048)
			(xy 388.270168 -426.342469) (xy 388.293215 -426.349972) (xy 388.312816 -426.364226) (xy 388.327056 -426.383839)
			(xy 388.33454 -426.406891) (xy 388.335012 -426.41901) (xy 388.335012 -427.289976) (xy 389.237982 -427.289976)
			(xy 389.238072 -427.275402) (xy 389.239727 -427.246301) (xy 389.241284 -427.23181) (xy 389.241284 -426.147992)
			(xy 389.239741 -426.1335) (xy 389.238088 -426.1044) (xy 389.237982 -426.089826) (xy 389.238077 -426.075252)
			(xy 389.239728 -426.046151) (xy 389.241284 -426.03166) (xy 389.241284 -425.419012) (xy 389.241727 -425.406905)
			(xy 389.249221 -425.383881) (xy 389.263476 -425.364309) (xy 389.283091 -425.350114) (xy 389.306138 -425.34269)
			(xy 389.318246 -425.342304) (xy 390.258046 -425.342304) (xy 390.270134 -425.342767) (xy 390.29313 -425.350232)
			(xy 390.312707 -425.364421) (xy 390.326957 -425.383953) (xy 390.334494 -425.406925) (xy 390.335008 -425.419012)
			(xy 390.335008 -427.960536) (xy 390.334614 -427.972646) (xy 390.327106 -427.995673) (xy 390.312838 -428.015245)
			(xy 390.293213 -428.029438) (xy 390.270157 -428.03686) (xy 390.258046 -428.037244) (xy 389.318246 -428.037244)
			(xy 389.306157 -428.036753) (xy 389.283155 -428.029307) (xy 389.263573 -428.015127) (xy 389.249322 -427.995597)
			(xy 389.241791 -427.972623) (xy 389.241284 -427.960536) (xy 389.241284 -427.348142) (xy 389.239737 -427.33365)
			(xy 389.238087 -427.30455) (xy 389.237982 -427.289976) (xy 388.335012 -427.289976) (xy 388.335012 -428.28972)
			(xy 391.237978 -428.28972) (xy 391.238072 -428.275146) (xy 391.239724 -428.246045) (xy 391.24128 -428.231554)
			(xy 391.24128 -427.14799) (xy 391.239737 -427.133498) (xy 391.238084 -427.104398) (xy 391.237978 -427.089824)
			(xy 391.238073 -427.07525) (xy 391.239724 -427.046149) (xy 391.24128 -427.031658) (xy 391.24128 -426.41901)
			(xy 391.241669 -426.406884) (xy 391.249164 -426.383818) (xy 391.263422 -426.364199) (xy 391.283047 -426.349949)
			(xy 391.306115 -426.342464) (xy 391.318242 -426.342048) (xy 392.258042 -426.342048) (xy 392.27016 -426.342476)
			(xy 392.293206 -426.349976) (xy 392.312808 -426.364229) (xy 392.327048 -426.383841) (xy 392.334532 -426.406892)
			(xy 392.335004 -426.41901) (xy 392.335004 -427.289976) (xy 393.237974 -427.289976) (xy 393.238064 -427.275402)
			(xy 393.239719 -427.246301) (xy 393.241276 -427.23181) (xy 393.241276 -426.147992) (xy 393.239733 -426.1335)
			(xy 393.23808 -426.1044) (xy 393.237974 -426.089826) (xy 393.238069 -426.075252) (xy 393.23972 -426.046151)
			(xy 393.241276 -426.03166) (xy 393.241276 -425.419012) (xy 393.241726 -425.406906) (xy 393.24922 -425.383883)
			(xy 393.263473 -425.364312) (xy 393.283086 -425.350116) (xy 393.306131 -425.342691) (xy 393.318238 -425.342304)
			(xy 394.258038 -425.342304) (xy 394.270126 -425.342774) (xy 394.293122 -425.350237) (xy 394.312698 -425.364424)
			(xy 394.326949 -425.383954) (xy 394.334486 -425.406926) (xy 394.335 -425.419012) (xy 394.335 -427.960536)
			(xy 394.334614 -427.972647) (xy 394.327105 -427.995675) (xy 394.312835 -428.015248) (xy 394.293208 -428.029441)
			(xy 394.27015 -428.036861) (xy 394.258038 -428.037244) (xy 393.318238 -428.037244) (xy 393.306149 -428.03676)
			(xy 393.283147 -428.029312) (xy 393.263565 -428.01513) (xy 393.249314 -427.995599) (xy 393.241783 -427.972623)
			(xy 393.241276 -427.960536) (xy 393.241276 -427.348142) (xy 393.239729 -427.33365) (xy 393.238079 -427.30455)
			(xy 393.237974 -427.289976) (xy 392.335004 -427.289976) (xy 392.335004 -428.28972) (xy 395.23797 -428.28972)
			(xy 395.238064 -428.275146) (xy 395.239716 -428.246045) (xy 395.241272 -428.231554) (xy 395.241272 -427.14799)
			(xy 395.239729 -427.133498) (xy 395.238076 -427.104398) (xy 395.23797 -427.089824) (xy 395.238065 -427.07525)
			(xy 395.239716 -427.046149) (xy 395.241272 -427.031658) (xy 395.241272 -426.41901) (xy 395.241669 -426.406884)
			(xy 395.249163 -426.38382) (xy 395.263419 -426.364202) (xy 395.283042 -426.349952) (xy 395.306108 -426.342465)
			(xy 395.318234 -426.342048) (xy 396.258034 -426.342048) (xy 396.270151 -426.342483) (xy 396.293197 -426.349981)
			(xy 396.312799 -426.364232) (xy 396.327039 -426.383842) (xy 396.334524 -426.406892) (xy 396.334996 -426.41901)
			(xy 396.334996 -427.289976) (xy 398.237964 -427.289976) (xy 398.238078 -427.274891) (xy 398.239856 -427.244772)
			(xy 398.24152 -427.229778) (xy 398.24152 -426.150024) (xy 398.239851 -426.135031) (xy 398.238073 -426.104912)
			(xy 398.237964 -426.089826) (xy 398.238074 -426.07474) (xy 398.239855 -426.044622) (xy 398.24152 -426.029628)
			(xy 398.24152 -425.419012) (xy 398.241924 -425.406927) (xy 398.249391 -425.38394) (xy 398.263599 -425.364387)
			(xy 398.283154 -425.350184) (xy 398.306143 -425.342721) (xy 398.318228 -425.342304) (xy 399.258028 -425.342304)
			(xy 399.270105 -425.34274) (xy 399.293075 -425.350212) (xy 399.312613 -425.364415) (xy 399.326806 -425.38396)
			(xy 399.334266 -425.406935) (xy 399.334736 -425.419012) (xy 399.334736 -427.960536) (xy 399.334267 -427.97261)
			(xy 399.326798 -427.995573) (xy 399.312602 -428.015107) (xy 399.293066 -428.029302) (xy 399.270102 -428.036768)
			(xy 399.258028 -428.037244) (xy 398.318228 -428.037244) (xy 398.306158 -428.036713) (xy 398.283198 -428.029262)
			(xy 398.263664 -428.015082) (xy 398.249467 -427.995559) (xy 398.241997 -427.972605) (xy 398.24152 -427.960536)
			(xy 398.24152 -427.350174) (xy 398.239856 -427.33518) (xy 398.238074 -427.305062) (xy 398.237964 -427.289976)
			(xy 396.334996 -427.289976) (xy 396.334996 -428.28972) (xy 400.23796 -428.28972) (xy 400.238069 -428.274634)
			(xy 400.239851 -428.244516) (xy 400.241516 -428.229522) (xy 400.241516 -427.150022) (xy 400.239847 -427.135029)
			(xy 400.238069 -427.10491) (xy 400.23796 -427.089824) (xy 400.23807 -427.074738) (xy 400.239851 -427.04462)
			(xy 400.241516 -427.029626) (xy 400.241516 -426.41901) (xy 400.242016 -426.406923) (xy 400.249467 -426.383927)
			(xy 400.263646 -426.364349) (xy 400.283171 -426.350097) (xy 400.306139 -426.342561) (xy 400.318224 -426.342048)
			(xy 401.258024 -426.342048) (xy 401.270129 -426.342495) (xy 401.293148 -426.349995) (xy 401.312716 -426.36425)
			(xy 401.326912 -426.383862) (xy 401.334341 -426.406904) (xy 401.334732 -426.41901) (xy 401.334732 -427.289976)
			(xy 402.237956 -427.289976) (xy 402.23807 -427.274891) (xy 402.239848 -427.244772) (xy 402.241512 -427.229778)
			(xy 402.241512 -426.150024) (xy 402.239843 -426.135031) (xy 402.238065 -426.104912) (xy 402.237956 -426.089826)
			(xy 402.238066 -426.07474) (xy 402.239847 -426.044622) (xy 402.241512 -426.029628) (xy 402.241512 -425.419012)
			(xy 402.241923 -425.406928) (xy 402.24939 -425.383942) (xy 402.263596 -425.36439) (xy 402.283149 -425.350186)
			(xy 402.306136 -425.342722) (xy 402.31822 -425.342304) (xy 403.25802 -425.342304) (xy 403.270097 -425.342748)
			(xy 403.293067 -425.350217) (xy 403.312604 -425.364419) (xy 403.326798 -425.383962) (xy 403.334257 -425.406935)
			(xy 403.334728 -425.419012) (xy 403.334728 -427.960536) (xy 403.334267 -427.97261) (xy 403.326797 -427.995576)
			(xy 403.312599 -428.01511) (xy 403.293061 -428.029304) (xy 403.270095 -428.036769) (xy 403.25802 -428.037244)
			(xy 402.31822 -428.037244) (xy 402.30615 -428.036719) (xy 402.28319 -428.029267) (xy 402.263655 -428.015085)
			(xy 402.249459 -427.995561) (xy 402.241989 -427.972606) (xy 402.241512 -427.960536) (xy 402.241512 -427.350174)
			(xy 402.239848 -427.33518) (xy 402.238066 -427.305062) (xy 402.237956 -427.289976) (xy 401.334732 -427.289976)
			(xy 401.334732 -428.28972) (xy 404.237952 -428.28972) (xy 404.238062 -428.274634) (xy 404.239843 -428.244516)
			(xy 404.241508 -428.229522) (xy 404.241508 -427.150022) (xy 404.239839 -427.135029) (xy 404.238061 -427.10491)
			(xy 404.237952 -427.089824) (xy 404.238062 -427.074738) (xy 404.239843 -427.04462) (xy 404.241508 -427.029626)
			(xy 404.241508 -426.41901) (xy 404.242015 -426.406924) (xy 404.249465 -426.383929) (xy 404.263643 -426.364352)
			(xy 404.283166 -426.3501) (xy 404.306132 -426.342562) (xy 404.318216 -426.342048) (xy 405.258016 -426.342048)
			(xy 405.270121 -426.342502) (xy 405.293139 -426.349999) (xy 405.312708 -426.364253) (xy 405.326904 -426.383863)
			(xy 405.334333 -426.406904) (xy 405.334724 -426.41901) (xy 405.334724 -427.289976) (xy 406.237948 -427.289976)
			(xy 406.238062 -427.274891) (xy 406.23984 -427.244772) (xy 406.241504 -427.229778) (xy 406.241504 -426.150024)
			(xy 406.239835 -426.135031) (xy 406.238057 -426.104912) (xy 406.237948 -426.089826) (xy 406.238058 -426.07474)
			(xy 406.239839 -426.044622) (xy 406.241504 -426.029628) (xy 406.241504 -425.419012) (xy 406.241923 -425.406929)
			(xy 406.249389 -425.383944) (xy 406.263593 -425.364393) (xy 406.283144 -425.350189) (xy 406.306129 -425.342723)
			(xy 406.318212 -425.342304) (xy 407.258012 -425.342304) (xy 407.270088 -425.342754) (xy 407.293058 -425.350222)
			(xy 407.312596 -425.364421) (xy 407.326789 -425.383964) (xy 407.334249 -425.406935) (xy 407.33472 -425.419012)
			(xy 407.33472 -427.960536) (xy 407.334267 -427.972611) (xy 407.326796 -427.995578) (xy 407.312596 -428.015113)
			(xy 407.293056 -428.029307) (xy 407.270087 -428.036771) (xy 407.258012 -428.037244) (xy 406.318212 -428.037244)
			(xy 406.306142 -428.036726) (xy 406.283181 -428.029271) (xy 406.263647 -428.015087) (xy 406.249451 -427.995562)
			(xy 406.241981 -427.972606) (xy 406.241504 -427.960536) (xy 406.241504 -427.350174) (xy 406.23984 -427.33518)
			(xy 406.238058 -427.305062) (xy 406.237948 -427.289976) (xy 405.334724 -427.289976) (xy 405.334724 -428.28972)
			(xy 408.237944 -428.28972) (xy 408.238054 -428.274634) (xy 408.239835 -428.244516) (xy 408.2415 -428.229522)
			(xy 408.2415 -427.150022) (xy 408.239831 -427.135029) (xy 408.238053 -427.10491) (xy 408.237944 -427.089824)
			(xy 408.238054 -427.074738) (xy 408.239835 -427.04462) (xy 408.2415 -427.029626) (xy 408.2415 -426.41901)
			(xy 408.242015 -426.406925) (xy 408.249464 -426.383931) (xy 408.26364 -426.364355) (xy 408.283161 -426.350103)
			(xy 408.306125 -426.342563) (xy 408.318208 -426.342048) (xy 409.258008 -426.342048) (xy 409.270112 -426.342509)
			(xy 409.293131 -426.350004) (xy 409.312699 -426.364256) (xy 409.326896 -426.383865) (xy 409.334325 -426.406905)
			(xy 409.334716 -426.41901) (xy 409.334716 -427.289976) (xy 410.23794 -427.289976) (xy 410.238055 -427.274891)
			(xy 410.239832 -427.244772) (xy 410.241496 -427.229778) (xy 410.241496 -426.150024) (xy 410.239827 -426.135031)
			(xy 410.238049 -426.104912) (xy 410.23794 -426.089826) (xy 410.23805 -426.07474) (xy 410.239831 -426.044622)
			(xy 410.241496 -426.029628) (xy 410.241496 -425.419012) (xy 410.241923 -425.40693) (xy 410.249388 -425.383947)
			(xy 410.26359 -425.364396) (xy 410.283139 -425.350191) (xy 410.306122 -425.342724) (xy 410.318204 -425.342304)
			(xy 411.258004 -425.342304) (xy 411.270088 -425.342709) (xy 411.293073 -425.350179) (xy 411.312624 -425.364387)
			(xy 411.326828 -425.383941) (xy 411.334293 -425.406928) (xy 411.334712 -425.419012) (xy 411.334712 -427.960536)
			(xy 411.334267 -427.972612) (xy 411.326795 -427.99558) (xy 411.312593 -428.015116) (xy 411.293051 -428.029309)
			(xy 411.27008 -428.036772) (xy 411.258004 -428.037244) (xy 410.318204 -428.037244) (xy 410.306133 -428.036733)
			(xy 410.283172 -428.029276) (xy 410.263638 -428.01509) (xy 410.249442 -427.995564) (xy 410.241973 -427.972607)
			(xy 410.241496 -427.960536) (xy 410.241496 -427.350174) (xy 410.239832 -427.33518) (xy 410.23805 -427.305062)
			(xy 410.23794 -427.289976) (xy 409.334716 -427.289976) (xy 409.334716 -428.28972) (xy 412.237936 -428.28972)
			(xy 412.238048 -428.274634) (xy 412.239829 -428.244516) (xy 412.241492 -428.229522) (xy 412.241492 -427.150022)
			(xy 412.239823 -427.135029) (xy 412.238045 -427.10491) (xy 412.237936 -427.089824) (xy 412.238048 -427.074738)
			(xy 412.239829 -427.04462) (xy 412.241492 -427.029626) (xy 412.241492 -426.41901) (xy 412.242015 -426.406926)
			(xy 412.249463 -426.383934) (xy 412.263637 -426.364358) (xy 412.283156 -426.350105) (xy 412.306118 -426.342564)
			(xy 412.3182 -426.342048) (xy 413.258 -426.342048) (xy 413.270104 -426.342515) (xy 413.293122 -426.350009)
			(xy 413.312691 -426.364259) (xy 413.326887 -426.383866) (xy 413.334317 -426.406905) (xy 413.334708 -426.41901)
			(xy 413.334708 -428.960534) (xy 413.334223 -428.972621) (xy 413.326762 -428.995614) (xy 413.312579 -429.01519)
			(xy 413.293053 -429.029441) (xy 413.270085 -429.03698) (xy 413.258 -429.037496) (xy 412.3182 -429.037496)
			(xy 412.306091 -429.037084) (xy 412.283063 -429.029584) (xy 412.263489 -429.015321) (xy 412.249295 -428.995699)
			(xy 412.241875 -428.972645) (xy 412.241492 -428.960534) (xy 412.241492 -428.349918) (xy 412.239823 -428.334925)
			(xy 412.238045 -428.304806) (xy 412.237936 -428.28972) (xy 409.334716 -428.28972) (xy 409.334716 -428.960534)
			(xy 409.334321 -428.97263) (xy 409.326849 -428.995639) (xy 409.312646 -429.015222) (xy 409.293095 -429.02947)
			(xy 409.270103 -429.036993) (xy 409.258008 -429.037496) (xy 408.318208 -429.037496) (xy 408.306099 -429.037077)
			(xy 408.283071 -429.029579) (xy 408.263498 -429.015319) (xy 408.249303 -428.995697) (xy 408.241883 -428.972644)
			(xy 408.2415 -428.960534) (xy 408.2415 -428.349918) (xy 408.239831 -428.334925) (xy 408.238053 -428.304806)
			(xy 408.237944 -428.28972) (xy 405.334724 -428.28972) (xy 405.334724 -428.960534) (xy 405.334321 -428.972629)
			(xy 405.326851 -428.995637) (xy 405.312649 -429.015219) (xy 405.2931 -429.029467) (xy 405.27011 -429.036992)
			(xy 405.258016 -429.037496) (xy 404.318216 -429.037496) (xy 404.306108 -429.03707) (xy 404.28308 -429.029574)
			(xy 404.263507 -429.015315) (xy 404.249312 -428.995695) (xy 404.241891 -428.972644) (xy 404.241508 -428.960534)
			(xy 404.241508 -428.349918) (xy 404.239839 -428.334925) (xy 404.238061 -428.304806) (xy 404.237952 -428.28972)
			(xy 401.334732 -428.28972) (xy 401.334732 -428.960534) (xy 401.334321 -428.972628) (xy 401.326852 -428.995635)
			(xy 401.312652 -429.015216) (xy 401.293105 -429.029465) (xy 401.270117 -429.036991) (xy 401.258024 -429.037496)
			(xy 400.318224 -429.037496) (xy 400.306116 -429.037063) (xy 400.283089 -429.02957) (xy 400.263515 -429.015313)
			(xy 400.24932 -428.995694) (xy 400.241899 -428.972643) (xy 400.241516 -428.960534) (xy 400.241516 -428.349918)
			(xy 400.239847 -428.334925) (xy 400.238069 -428.304806) (xy 400.23796 -428.28972) (xy 396.334996 -428.28972)
			(xy 396.334996 -428.960534) (xy 396.334518 -428.972647) (xy 396.327025 -428.995686) (xy 396.312784 -429.015284)
			(xy 396.293186 -429.029525) (xy 396.270147 -429.037018) (xy 396.258034 -429.037496) (xy 395.318234 -429.037496)
			(xy 395.306125 -429.03696) (xy 395.283088 -429.029486) (xy 395.263489 -429.01526) (xy 395.249245 -428.995673)
			(xy 395.241751 -428.972643) (xy 395.241272 -428.960534) (xy 395.241272 -428.347886) (xy 395.239729 -428.333394)
			(xy 395.238076 -428.304294) (xy 395.23797 -428.28972) (xy 392.335004 -428.28972) (xy 392.335004 -428.960534)
			(xy 392.334518 -428.972646) (xy 392.327027 -428.995683) (xy 392.312787 -429.015281) (xy 392.293191 -429.029523)
			(xy 392.270154 -429.037017) (xy 392.258042 -429.037496) (xy 391.318242 -429.037496) (xy 391.306125 -429.037005)
			(xy 391.283073 -429.029528) (xy 391.26346 -429.015294) (xy 391.249206 -428.995695) (xy 391.241707 -428.972651)
			(xy 391.24128 -428.960534) (xy 391.24128 -428.347886) (xy 391.239737 -428.333394) (xy 391.238084 -428.304294)
			(xy 391.237978 -428.28972) (xy 388.335012 -428.28972) (xy 388.335012 -428.960534) (xy 388.334518 -428.972645)
			(xy 388.327028 -428.995681) (xy 388.31279 -429.015278) (xy 388.293196 -429.02952) (xy 388.270161 -429.037016)
			(xy 388.25805 -429.037496) (xy 387.31825 -429.037496) (xy 387.306136 -429.037031) (xy 387.283097 -429.029535)
			(xy 387.263499 -429.015289) (xy 387.249258 -428.995689) (xy 387.241766 -428.972648) (xy 387.241288 -428.960534)
			(xy 387.241288 -428.347886) (xy 387.239745 -428.333394) (xy 387.238092 -428.304294) (xy 387.237986 -428.28972)
			(xy 384.33502 -428.28972) (xy 384.33502 -428.960534) (xy 384.334669 -428.972663) (xy 384.327162 -428.99573)
			(xy 384.312894 -429.015348) (xy 384.293262 -429.029597) (xy 384.270187 -429.03708) (xy 384.258058 -429.037496)
			(xy 383.318258 -429.037496) (xy 383.306145 -429.037025) (xy 383.283106 -429.02953) (xy 383.263508 -429.015287)
			(xy 383.249266 -428.995687) (xy 383.241774 -428.972647) (xy 383.241296 -428.960534) (xy 383.241296 -428.347886)
			(xy 383.239753 -428.333394) (xy 383.2381 -428.304294) (xy 383.237994 -428.28972) (xy 361.693883 -428.28972)
			(xy 361.70649 -428.297264) (xy 361.847915 -428.391163) (xy 361.984785 -428.491588) (xy 362.116796 -428.598318)
			(xy 362.24366 -428.711119) (xy 362.365097 -428.829742) (xy 362.480841 -428.953927) (xy 362.590636 -429.0834)
			(xy 362.694243 -429.217877) (xy 362.791432 -429.357063) (xy 362.88199 -429.500651) (xy 362.965718 -429.648327)
			(xy 363.042433 -429.799764) (xy 363.111965 -429.954631) (xy 363.174162 -430.112586) (xy 363.228886 -430.273284)
			(xy 363.276018 -430.436369) (xy 363.315454 -430.601485) (xy 363.347108 -430.768268) (xy 363.364334 -430.889918)
			(xy 381.237998 -430.889918) (xy 381.238092 -430.875344) (xy 381.239744 -430.846243) (xy 381.2413 -430.831752)
			(xy 381.2413 -429.747934) (xy 381.239752 -429.733442) (xy 381.238102 -429.704342) (xy 381.237998 -429.689768)
			(xy 381.238096 -429.675194) (xy 381.239746 -429.646093) (xy 381.2413 -429.631602) (xy 381.2413 -429.018954)
			(xy 381.241772 -429.006841) (xy 381.249267 -428.983803) (xy 381.263511 -428.964205) (xy 381.28311 -428.949964)
			(xy 381.306149 -428.942471) (xy 381.318262 -428.941992) (xy 382.258062 -428.941992) (xy 382.27017 -428.942543)
			(xy 382.293204 -428.950015) (xy 382.312803 -428.964238) (xy 382.327047 -428.98382) (xy 382.334543 -429.006847)
			(xy 382.335024 -429.018954) (xy 382.335024 -431.560478) (xy 382.334621 -431.572603) (xy 382.32713 -431.595668)
			(xy 382.312875 -431.615287) (xy 382.293254 -431.629537) (xy 382.270187 -431.637023) (xy 382.258062 -431.63744)
			(xy 381.318262 -431.63744) (xy 381.306143 -431.63702) (xy 381.283095 -431.62952) (xy 381.263492 -431.615265)
			(xy 381.249253 -431.595651) (xy 381.24177 -431.572597) (xy 381.2413 -431.560478) (xy 381.2413 -430.948084)
			(xy 381.239756 -430.933592) (xy 381.238104 -430.904492) (xy 381.237998 -430.889918) (xy 363.364334 -430.889918)
			(xy 363.370909 -430.936351) (xy 363.386805 -431.105365) (xy 363.394762 -431.274938) (xy 363.39526 -431.359818)
			(xy 363.39483 -431.445421) (xy 363.38674 -431.616436) (xy 363.370574 -431.786877) (xy 363.355859 -431.889916)
			(xy 383.237994 -431.889916) (xy 383.238088 -431.875342) (xy 383.23974 -431.846241) (xy 383.241296 -431.83175)
			(xy 383.241296 -430.747932) (xy 383.239748 -430.73344) (xy 383.238098 -430.70434) (xy 383.237994 -430.689766)
			(xy 383.238092 -430.675192) (xy 383.239742 -430.646091) (xy 383.241296 -430.6316) (xy 383.241296 -430.018952)
			(xy 383.241676 -430.006841) (xy 383.249188 -429.983813) (xy 383.263459 -429.964241) (xy 383.283088 -429.950048)
			(xy 383.306145 -429.942628) (xy 383.318258 -429.942244) (xy 384.258058 -429.942244) (xy 384.270146 -429.942743)
			(xy 384.293146 -429.950189) (xy 384.312727 -429.964367) (xy 384.326979 -429.983894) (xy 384.334511 -430.006866)
			(xy 384.33502 -430.018952) (xy 384.33502 -430.889918) (xy 385.23799 -430.889918) (xy 385.238084 -430.875344)
			(xy 385.239736 -430.846243) (xy 385.241292 -430.831752) (xy 385.241292 -429.747934) (xy 385.239745 -429.733442)
			(xy 385.238094 -429.704342) (xy 385.23799 -429.689768) (xy 385.238088 -429.675194) (xy 385.239738 -429.646093)
			(xy 385.241292 -429.631602) (xy 385.241292 -429.018954) (xy 385.241772 -429.006842) (xy 385.249266 -428.983805)
			(xy 385.263508 -428.964208) (xy 385.283105 -428.949966) (xy 385.306142 -428.942472) (xy 385.318254 -428.941992)
			(xy 386.258054 -428.941992) (xy 386.270162 -428.94255) (xy 386.293196 -428.950019) (xy 386.312794 -428.96424)
			(xy 386.327039 -428.983822) (xy 386.334535 -429.006847) (xy 386.335016 -429.018954) (xy 386.335016 -431.560478)
			(xy 386.334621 -431.572604) (xy 386.327129 -431.59567) (xy 386.312872 -431.61529) (xy 386.293249 -431.62954)
			(xy 386.27018 -431.637024) (xy 386.258054 -431.63744) (xy 385.318254 -431.63744) (xy 385.306135 -431.637027)
			(xy 385.283086 -431.629525) (xy 385.263484 -431.615268) (xy 385.249244 -431.595653) (xy 385.241762 -431.572598)
			(xy 385.241292 -431.560478) (xy 385.241292 -430.948084) (xy 385.239749 -430.933592) (xy 385.238096 -430.904492)
			(xy 385.23799 -430.889918) (xy 384.33502 -430.889918) (xy 384.33502 -431.889916) (xy 387.237986 -431.889916)
			(xy 387.23808 -431.875342) (xy 387.239732 -431.846241) (xy 387.241288 -431.83175) (xy 387.241288 -430.747932)
			(xy 387.23974 -430.73344) (xy 387.23809 -430.70434) (xy 387.237986 -430.689766) (xy 387.238084 -430.675192)
			(xy 387.239734 -430.646091) (xy 387.241288 -430.6316) (xy 387.241288 -430.018952) (xy 387.241675 -430.006842)
			(xy 387.249187 -429.983815) (xy 387.263456 -429.964244) (xy 387.283083 -429.95005) (xy 387.306138 -429.942629)
			(xy 387.31825 -429.942244) (xy 388.25805 -429.942244) (xy 388.270137 -429.94275) (xy 388.293137 -429.950193)
			(xy 388.312718 -429.96437) (xy 388.32697 -429.983896) (xy 388.334503 -430.006866) (xy 388.335012 -430.018952)
			(xy 388.335012 -430.889918) (xy 389.237982 -430.889918) (xy 389.238076 -430.875344) (xy 389.239728 -430.846243)
			(xy 389.241284 -430.831752) (xy 389.241284 -429.747934) (xy 389.239737 -429.733442) (xy 389.238086 -429.704342)
			(xy 389.237982 -429.689768) (xy 389.23808 -429.675194) (xy 389.23973 -429.646093) (xy 389.241284 -429.631602)
			(xy 389.241284 -429.018954) (xy 389.241673 -429.006832) (xy 389.249179 -428.98378) (xy 389.26344 -428.964175)
			(xy 389.283062 -428.949937) (xy 389.306124 -428.942459) (xy 389.318246 -428.941992) (xy 390.258046 -428.941992)
			(xy 390.270158 -428.942472) (xy 390.293195 -428.949966) (xy 390.312792 -428.964208) (xy 390.327034 -428.983805)
			(xy 390.334528 -429.006842) (xy 390.335008 -429.018954) (xy 390.335008 -431.560478) (xy 390.33447 -431.572587)
			(xy 390.326995 -431.595622) (xy 390.312768 -431.61522) (xy 390.293183 -431.629464) (xy 390.270154 -431.636959)
			(xy 390.258046 -431.63744) (xy 389.318246 -431.63744) (xy 389.306123 -431.637001) (xy 389.283062 -431.629518)
			(xy 389.263445 -431.615273) (xy 389.249193 -431.595659) (xy 389.241703 -431.5726) (xy 389.241284 -431.560478)
			(xy 389.241284 -430.948084) (xy 389.239741 -430.933592) (xy 389.238088 -430.904492) (xy 389.237982 -430.889918)
			(xy 388.335012 -430.889918) (xy 388.335012 -431.889916) (xy 391.237978 -431.889916) (xy 391.238072 -431.875342)
			(xy 391.239724 -431.846241) (xy 391.24128 -431.83175) (xy 391.24128 -430.747932) (xy 391.239732 -430.73344)
			(xy 391.238082 -430.70434) (xy 391.237978 -430.689766) (xy 391.238076 -430.675192) (xy 391.239726 -430.646091)
			(xy 391.24128 -430.6316) (xy 391.24128 -430.018952) (xy 391.241675 -430.006843) (xy 391.249186 -429.983817)
			(xy 391.263453 -429.964247) (xy 391.283077 -429.950053) (xy 391.306131 -429.94263) (xy 391.318242 -429.942244)
			(xy 392.258042 -429.942244) (xy 392.270134 -429.942672) (xy 392.293137 -429.95014) (xy 392.312716 -429.964337)
			(xy 392.326965 -429.983879) (xy 392.334496 -430.006861) (xy 392.335004 -430.018952) (xy 392.335004 -430.889918)
			(xy 393.237974 -430.889918) (xy 393.238068 -430.875344) (xy 393.23972 -430.846243) (xy 393.241276 -430.831752)
			(xy 393.241276 -429.747934) (xy 393.239729 -429.733442) (xy 393.238078 -429.704342) (xy 393.237974 -429.689768)
			(xy 393.238072 -429.675194) (xy 393.239722 -429.646093) (xy 393.241276 -429.631602) (xy 393.241276 -429.018954)
			(xy 393.241673 -429.006833) (xy 393.249178 -428.983782) (xy 393.263438 -428.964178) (xy 393.283057 -428.949939)
			(xy 393.306117 -428.94246) (xy 393.318238 -428.941992) (xy 394.258038 -428.941992) (xy 394.27015 -428.942479)
			(xy 394.293187 -428.949971) (xy 394.312784 -428.964211) (xy 394.327026 -428.983806) (xy 394.33452 -429.006842)
			(xy 394.335 -429.018954) (xy 394.335 -431.560478) (xy 394.33447 -431.572588) (xy 394.326994 -431.595624)
			(xy 394.312765 -431.615223) (xy 394.293177 -431.629466) (xy 394.270147 -431.636961) (xy 394.258038 -431.63744)
			(xy 393.318238 -431.63744) (xy 393.306115 -431.637007) (xy 393.283054 -431.629523) (xy 393.263436 -431.615275)
			(xy 393.249184 -431.595661) (xy 393.241695 -431.572601) (xy 393.241276 -431.560478) (xy 393.241276 -430.948084)
			(xy 393.239733 -430.933592) (xy 393.23808 -430.904492) (xy 393.237974 -430.889918) (xy 392.335004 -430.889918)
			(xy 392.335004 -431.889916) (xy 395.23797 -431.889916) (xy 395.238064 -431.875342) (xy 395.239716 -431.846241)
			(xy 395.241272 -431.83175) (xy 395.241272 -430.747932) (xy 395.239724 -430.73344) (xy 395.238074 -430.70434)
			(xy 395.23797 -430.689766) (xy 395.238068 -430.675192) (xy 395.239718 -430.646091) (xy 395.241272 -430.6316)
			(xy 395.241272 -430.018952) (xy 395.241675 -430.006843) (xy 395.249184 -429.983819) (xy 395.26345 -429.96425)
			(xy 395.283072 -429.950056) (xy 395.306124 -429.942631) (xy 395.318234 -429.942244) (xy 396.258034 -429.942244)
			(xy 396.270126 -429.942678) (xy 396.293128 -429.950145) (xy 396.312708 -429.96434) (xy 396.326957 -429.98388)
			(xy 396.334488 -430.006862) (xy 396.334996 -430.018952) (xy 396.334996 -430.889918) (xy 398.237964 -430.889918)
			(xy 398.238073 -430.874832) (xy 398.239855 -430.844714) (xy 398.24152 -430.82972) (xy 398.24152 -429.749966)
			(xy 398.239855 -429.734972) (xy 398.238074 -429.704854) (xy 398.237964 -429.689768) (xy 398.238078 -429.674682)
			(xy 398.239856 -429.644564) (xy 398.24152 -429.62957) (xy 398.24152 -429.018954) (xy 398.241968 -429.006864)
			(xy 398.249435 -428.983865) (xy 398.263627 -428.964288) (xy 398.283163 -428.950038) (xy 398.306139 -428.942504)
			(xy 398.318228 -428.941992) (xy 399.258028 -428.941992) (xy 399.270138 -428.942392) (xy 399.293164 -428.949899)
			(xy 399.312736 -428.964165) (xy 399.32693 -428.983789) (xy 399.334352 -429.006843) (xy 399.334736 -429.018954)
			(xy 399.334736 -431.560478) (xy 399.334273 -431.572569) (xy 399.32682 -431.595573) (xy 399.312633 -431.615155)
			(xy 399.293097 -431.629405) (xy 399.270117 -431.636934) (xy 399.258028 -431.63744) (xy 398.318228 -431.63744)
			(xy 398.306125 -431.63696) (xy 398.283105 -431.629473) (xy 398.263535 -431.615227) (xy 398.249338 -431.595621)
			(xy 398.241909 -431.572582) (xy 398.24152 -431.560478) (xy 398.24152 -430.950116) (xy 398.239851 -430.935123)
			(xy 398.238073 -430.905004) (xy 398.237964 -430.889918) (xy 396.334996 -430.889918) (xy 396.334996 -431.889916)
			(xy 400.23796 -431.889916) (xy 400.238069 -431.87483) (xy 400.239851 -431.844712) (xy 400.241516 -431.829718)
			(xy 400.241516 -430.749964) (xy 400.239851 -430.73497) (xy 400.23807 -430.704852) (xy 400.23796 -430.689766)
			(xy 400.238074 -430.67468) (xy 400.239852 -430.644562) (xy 400.241516 -430.629568) (xy 400.241516 -430.018952)
			(xy 400.241924 -430.006873) (xy 400.249402 -429.9839) (xy 400.263613 -429.964361) (xy 400.283164 -429.950169)
			(xy 400.306144 -429.942712) (xy 400.318224 -429.942244) (xy 401.258024 -429.942244) (xy 401.270095 -429.942743)
			(xy 401.293055 -429.950206) (xy 401.312587 -429.964396) (xy 401.326783 -429.983924) (xy 401.334253 -430.006881)
			(xy 401.334732 -430.018952) (xy 401.334732 -430.889918) (xy 402.237956 -430.889918) (xy 402.238065 -430.874832)
			(xy 402.239847 -430.844714) (xy 402.241512 -430.82972) (xy 402.241512 -429.749966) (xy 402.239847 -429.734972)
			(xy 402.238066 -429.704854) (xy 402.237956 -429.689768) (xy 402.23807 -429.674682) (xy 402.239848 -429.644564)
			(xy 402.241512 -429.62957) (xy 402.241512 -429.018954) (xy 402.241968 -429.006865) (xy 402.249434 -428.983867)
			(xy 402.263624 -428.964291) (xy 402.283158 -428.950041) (xy 402.306132 -428.942505) (xy 402.31822 -428.941992)
			(xy 403.25802 -428.941992) (xy 403.270129 -428.942399) (xy 403.293156 -428.949903) (xy 403.312728 -428.964167)
			(xy 403.326922 -428.98379) (xy 403.334344 -429.006843) (xy 403.334728 -429.018954) (xy 403.334728 -431.560478)
			(xy 403.334273 -431.57257) (xy 403.326819 -431.595575) (xy 403.31263 -431.615158) (xy 403.293092 -431.629408)
			(xy 403.27011 -431.636935) (xy 403.25802 -431.63744) (xy 402.31822 -431.63744) (xy 402.306116 -431.636967)
			(xy 402.283096 -431.629478) (xy 402.263527 -431.61523) (xy 402.24933 -431.595622) (xy 402.241901 -431.572583)
			(xy 402.241512 -431.560478) (xy 402.241512 -430.950116) (xy 402.239843 -430.935123) (xy 402.238065 -430.905004)
			(xy 402.237956 -430.889918) (xy 401.334732 -430.889918) (xy 401.334732 -431.889916) (xy 404.237952 -431.889916)
			(xy 404.238061 -431.87483) (xy 404.239843 -431.844712) (xy 404.241508 -431.829718) (xy 404.241508 -430.749964)
			(xy 404.239843 -430.73497) (xy 404.238062 -430.704852) (xy 404.237952 -430.689766) (xy 404.238066 -430.67468)
			(xy 404.239844 -430.644562) (xy 404.241508 -430.629568) (xy 404.241508 -430.018952) (xy 404.241923 -430.006873)
			(xy 404.249401 -429.983902) (xy 404.26361 -429.964364) (xy 404.283159 -429.950172) (xy 404.306137 -429.942713)
			(xy 404.318216 -429.942244) (xy 405.258016 -429.942244) (xy 405.270087 -429.94275) (xy 405.293046 -429.950211)
			(xy 405.312579 -429.964399) (xy 405.326774 -429.983925) (xy 405.334245 -430.006882) (xy 405.334724 -430.018952)
			(xy 405.334724 -430.889918) (xy 406.237948 -430.889918) (xy 406.238057 -430.874832) (xy 406.239839 -430.844714)
			(xy 406.241504 -430.82972) (xy 406.241504 -429.749966) (xy 406.239839 -429.734972) (xy 406.238058 -429.704854)
			(xy 406.237948 -429.689768) (xy 406.238062 -429.674682) (xy 406.23984 -429.644564) (xy 406.241504 -429.62957)
			(xy 406.241504 -429.018954) (xy 406.241967 -429.006866) (xy 406.249432 -428.98387) (xy 406.263621 -428.964293)
			(xy 406.283153 -428.950043) (xy 406.306125 -428.942506) (xy 406.318212 -428.941992) (xy 407.258012 -428.941992)
			(xy 407.270121 -428.942406) (xy 407.293147 -428.949908) (xy 407.312719 -428.96417) (xy 407.326914 -428.983792)
			(xy 407.334336 -429.006844) (xy 407.33472 -429.018954) (xy 407.33472 -431.560478) (xy 407.334273 -431.57257)
			(xy 407.326818 -431.595577) (xy 407.312627 -431.615161) (xy 407.293087 -431.629411) (xy 407.270103 -431.636936)
			(xy 407.258012 -431.63744) (xy 406.318212 -431.63744) (xy 406.306108 -431.636974) (xy 406.283088 -431.629483)
			(xy 406.263518 -431.615232) (xy 406.249322 -431.595624) (xy 406.241893 -431.572583) (xy 406.241504 -431.560478)
			(xy 406.241504 -430.950116) (xy 406.239835 -430.935123) (xy 406.238057 -430.905004) (xy 406.237948 -430.889918)
			(xy 405.334724 -430.889918) (xy 405.334724 -431.889916) (xy 408.237944 -431.889916) (xy 408.238053 -431.87483)
			(xy 408.239835 -431.844712) (xy 408.2415 -431.829718) (xy 408.2415 -430.749964) (xy 408.239835 -430.73497)
			(xy 408.238054 -430.704852) (xy 408.237944 -430.689766) (xy 408.238058 -430.67468) (xy 408.239836 -430.644562)
			(xy 408.2415 -430.629568) (xy 408.2415 -430.018952) (xy 408.241923 -430.006874) (xy 408.2494 -429.983904)
			(xy 408.263607 -429.964367) (xy 408.283154 -429.950174) (xy 408.30613 -429.942714) (xy 408.318208 -429.942244)
			(xy 409.258008 -429.942244) (xy 409.270078 -429.942757) (xy 409.293037 -429.950216) (xy 409.31257 -429.964401)
			(xy 409.326766 -429.983927) (xy 409.334237 -430.006882) (xy 409.334716 -430.018952) (xy 409.334716 -430.889918)
			(xy 410.23794 -430.889918) (xy 410.238051 -430.874832) (xy 410.239833 -430.844714) (xy 410.241496 -430.82972)
			(xy 410.241496 -429.749966) (xy 410.239831 -429.734972) (xy 410.23805 -429.704854) (xy 410.23794 -429.689768)
			(xy 410.238054 -429.674682) (xy 410.239832 -429.644564) (xy 410.241496 -429.62957) (xy 410.241496 -429.018954)
			(xy 410.241967 -429.006866) (xy 410.249431 -428.983872) (xy 410.263618 -428.964296) (xy 410.283148 -428.950046)
			(xy 410.306118 -428.942507) (xy 410.318204 -428.941992) (xy 411.258004 -428.941992) (xy 411.270112 -428.942413)
			(xy 411.293138 -428.949912) (xy 411.312711 -428.964173) (xy 411.326906 -428.983793) (xy 411.334328 -429.006844)
			(xy 411.334712 -429.018954) (xy 411.334712 -431.560478) (xy 411.334273 -431.572571) (xy 411.326816 -431.595579)
			(xy 411.312624 -431.615164) (xy 411.293082 -431.629413) (xy 411.270096 -431.636937) (xy 411.258004 -431.63744)
			(xy 410.318204 -431.63744) (xy 410.306099 -431.636981) (xy 410.283079 -431.629488) (xy 410.263509 -431.615236)
			(xy 410.249313 -431.595625) (xy 410.241885 -431.572584) (xy 410.241496 -431.560478) (xy 410.241496 -430.950116)
			(xy 410.239827 -430.935123) (xy 410.238049 -430.905004) (xy 410.23794 -430.889918) (xy 409.334716 -430.889918)
			(xy 409.334716 -431.889916) (xy 412.237936 -431.889916) (xy 412.238047 -431.87483) (xy 412.239829 -431.844712)
			(xy 412.241492 -431.829718) (xy 412.241492 -430.749964) (xy 412.239827 -430.73497) (xy 412.238046 -430.704852)
			(xy 412.237936 -430.689766) (xy 412.238052 -430.674681) (xy 412.23983 -430.644562) (xy 412.241492 -430.629568)
			(xy 412.241492 -430.018952) (xy 412.241923 -430.006875) (xy 412.249399 -429.983906) (xy 412.263604 -429.96437)
			(xy 412.283149 -429.950177) (xy 412.306123 -429.942716) (xy 412.3182 -429.942244) (xy 413.258 -429.942244)
			(xy 413.27007 -429.942764) (xy 413.293029 -429.95022) (xy 413.312562 -429.964404) (xy 413.326758 -429.983928)
			(xy 413.334229 -430.006883) (xy 413.334708 -430.018952) (xy 413.334708 -432.560476) (xy 413.334267 -432.572557)
			(xy 413.326806 -432.595539) (xy 413.312607 -432.61509) (xy 413.293061 -432.629295) (xy 413.270081 -432.636763)
			(xy 413.258 -432.637184) (xy 412.3182 -432.637184) (xy 412.306115 -432.636787) (xy 412.283128 -432.629317)
			(xy 412.263576 -432.615107) (xy 412.249372 -432.59555) (xy 412.241909 -432.572561) (xy 412.241492 -432.560476)
			(xy 412.241492 -431.950114) (xy 412.239822 -431.935121) (xy 412.238045 -431.905002) (xy 412.237936 -431.889916)
			(xy 409.334716 -431.889916) (xy 409.334716 -432.560476) (xy 409.334267 -432.572557) (xy 409.326807 -432.595537)
			(xy 409.31261 -432.615087) (xy 409.293066 -432.629292) (xy 409.270088 -432.636762) (xy 409.258008 -432.637184)
			(xy 408.318208 -432.637184) (xy 408.306123 -432.63678) (xy 408.283137 -432.629312) (xy 408.263584 -432.615105)
			(xy 408.249381 -432.595549) (xy 408.241917 -432.572561) (xy 408.2415 -432.560476) (xy 408.2415 -431.950114)
			(xy 408.23983 -431.935121) (xy 408.238053 -431.905002) (xy 408.237944 -431.889916) (xy 405.334724 -431.889916)
			(xy 405.334724 -432.560476) (xy 405.334267 -432.572556) (xy 405.326808 -432.595535) (xy 405.312613 -432.615084)
			(xy 405.293071 -432.62929) (xy 405.270096 -432.636761) (xy 405.258016 -432.637184) (xy 404.318216 -432.637184)
			(xy 404.306132 -432.636773) (xy 404.283146 -432.629307) (xy 404.263593 -432.615101) (xy 404.249389 -432.595547)
			(xy 404.241926 -432.57256) (xy 404.241508 -432.560476) (xy 404.241508 -431.950114) (xy 404.239838 -431.935121)
			(xy 404.238061 -431.905002) (xy 404.237952 -431.889916) (xy 401.334732 -431.889916) (xy 401.334732 -432.560476)
			(xy 401.334216 -432.572547) (xy 401.326763 -432.595509) (xy 401.312579 -432.615045) (xy 401.293052 -432.629241)
			(xy 401.270095 -432.636708) (xy 401.258024 -432.637184) (xy 400.318224 -432.637184) (xy 400.30614 -432.636766)
			(xy 400.283154 -432.629303) (xy 400.263601 -432.615099) (xy 400.249397 -432.595546) (xy 400.241934 -432.57256)
			(xy 400.241516 -432.560476) (xy 400.241516 -431.950114) (xy 400.239846 -431.935121) (xy 400.238069 -431.905002)
			(xy 400.23796 -431.889916) (xy 396.334996 -431.889916) (xy 396.334996 -432.560476) (xy 396.334563 -432.572584)
			(xy 396.32707 -432.595611) (xy 396.312813 -432.615185) (xy 396.293194 -432.62938) (xy 396.270143 -432.636801)
			(xy 396.258034 -432.637184) (xy 395.318234 -432.637184) (xy 395.306149 -432.636664) (xy 395.283153 -432.62922)
			(xy 395.263575 -432.615046) (xy 395.249322 -432.595525) (xy 395.241785 -432.572559) (xy 395.241272 -432.560476)
			(xy 395.241272 -431.948082) (xy 395.239729 -431.93359) (xy 395.238076 -431.90449) (xy 395.23797 -431.889916)
			(xy 392.335004 -431.889916) (xy 392.335004 -432.560476) (xy 392.334563 -432.572583) (xy 392.327071 -432.595609)
			(xy 392.312815 -432.615182) (xy 392.293199 -432.629378) (xy 392.27015 -432.6368) (xy 392.258042 -432.637184)
			(xy 391.318242 -432.637184) (xy 391.306157 -432.636657) (xy 391.283162 -432.629215) (xy 391.263583 -432.615043)
			(xy 391.24933 -432.595523) (xy 391.241793 -432.572559) (xy 391.24128 -432.560476) (xy 391.24128 -431.948082)
			(xy 391.239737 -431.93359) (xy 391.238084 -431.90449) (xy 391.237978 -431.889916) (xy 388.335012 -431.889916)
			(xy 388.335012 -432.560476) (xy 388.334563 -432.572582) (xy 388.327072 -432.595607) (xy 388.312818 -432.615179)
			(xy 388.293204 -432.629375) (xy 388.270158 -432.636799) (xy 388.25805 -432.637184) (xy 387.31825 -432.637184)
			(xy 387.306165 -432.636651) (xy 387.28317 -432.62921) (xy 387.263592 -432.61504) (xy 387.249339 -432.595522)
			(xy 387.241801 -432.572559) (xy 387.241288 -432.560476) (xy 387.241288 -431.948082) (xy 387.239745 -431.93359)
			(xy 387.238092 -431.90449) (xy 387.237986 -431.889916) (xy 384.33502 -431.889916) (xy 384.33502 -432.560476)
			(xy 384.334563 -432.572582) (xy 384.327073 -432.595605) (xy 384.312821 -432.615176) (xy 384.293209 -432.629373)
			(xy 384.270165 -432.636797) (xy 384.258058 -432.637184) (xy 383.318258 -432.637184) (xy 383.306169 -432.636729)
			(xy 383.283171 -432.629264) (xy 383.263593 -432.615073) (xy 383.249343 -432.595539) (xy 383.241808 -432.572564)
			(xy 383.241296 -432.560476) (xy 383.241296 -431.948082) (xy 383.239753 -431.93359) (xy 383.2381 -431.90449)
			(xy 383.237994 -431.889916) (xy 363.355859 -431.889916) (xy 363.346369 -431.956363) (xy 363.314178 -432.124516)
			(xy 363.274074 -432.290959) (xy 363.226145 -432.455319) (xy 363.170501 -432.61723) (xy 363.107264 -432.776329)
			(xy 363.036576 -432.932261) (xy 362.958595 -433.084677) (xy 362.873496 -433.233236) (xy 362.781469 -433.377605)
			(xy 362.68272 -433.517463) (xy 362.577469 -433.652495) (xy 362.465953 -433.782401) (xy 362.348419 -433.90689)
			(xy 362.225132 -434.025683) (xy 362.096367 -434.138515) (xy 361.962411 -434.245133) (xy 361.823565 -434.345299)
			(xy 361.680139 -434.438789) (xy 361.593049 -434.48986) (xy 381.237998 -434.48986) (xy 381.238096 -434.475286)
			(xy 381.239745 -434.446185) (xy 381.2413 -434.431694) (xy 381.2413 -433.34813) (xy 381.239752 -433.333638)
			(xy 381.238102 -433.304538) (xy 381.237998 -433.289964) (xy 381.238096 -433.27539) (xy 381.239745 -433.246289)
			(xy 381.2413 -433.231798) (xy 381.2413 -432.618896) (xy 381.241713 -432.606787) (xy 381.249213 -432.583759)
			(xy 381.263476 -432.564186) (xy 381.283098 -432.549992) (xy 381.306152 -432.542571) (xy 381.318262 -432.542188)
			(xy 382.258062 -432.542188) (xy 382.270154 -432.542641) (xy 382.293162 -432.550093) (xy 382.312747 -432.564281)
			(xy 382.326997 -432.583821) (xy 382.334521 -432.606805) (xy 382.335024 -432.618896) (xy 382.335024 -435.16042)
			(xy 382.334601 -435.172528) (xy 382.327099 -435.195551) (xy 382.312838 -435.215122) (xy 382.29322 -435.229317)
			(xy 382.270171 -435.236741) (xy 382.258062 -435.237128) (xy 381.318262 -435.237128) (xy 381.306167 -435.236724)
			(xy 381.28316 -435.229253) (xy 381.263578 -435.215052) (xy 381.24933 -435.195503) (xy 381.241804 -435.172514)
			(xy 381.2413 -435.16042) (xy 381.2413 -434.548026) (xy 381.239752 -434.533534) (xy 381.238102 -434.504434)
			(xy 381.237998 -434.48986) (xy 361.593049 -434.48986) (xy 361.532453 -434.525394) (xy 361.380838 -434.60492)
			(xy 361.225633 -434.67719) (xy 361.146598 -434.710078) (xy 361.132966 -434.716266) (xy 361.109724 -434.735103)
			(xy 361.092944 -434.759873) (xy 361.084069 -434.788444) (xy 361.083862 -434.818361) (xy 361.092341 -434.847052)
			(xy 361.108777 -434.872051) (xy 361.119928 -434.882036) (xy 361.169374 -434.924045) (xy 361.263563 -435.013299)
			(xy 361.352051 -435.108208) (xy 361.434498 -435.208409) (xy 361.510589 -435.313518) (xy 361.580032 -435.423133)
			(xy 361.616728 -435.489858) (xy 383.237994 -435.489858) (xy 383.238091 -435.475284) (xy 383.239741 -435.446183)
			(xy 383.241296 -435.431692) (xy 383.241296 -434.348128) (xy 383.239748 -434.333636) (xy 383.238098 -434.304536)
			(xy 383.237994 -434.289962) (xy 383.238092 -434.275388) (xy 383.239741 -434.246287) (xy 383.241296 -434.231796)
			(xy 383.241296 -433.618894) (xy 383.241806 -433.606783) (xy 383.24929 -433.583747) (xy 383.263524 -433.564149)
			(xy 383.283115 -433.549906) (xy 383.306148 -433.542412) (xy 383.318258 -433.541932) (xy 384.258058 -433.541932)
			(xy 384.270178 -433.542396) (xy 384.293234 -433.549876) (xy 384.31285 -433.564116) (xy 384.327103 -433.583722)
			(xy 384.334597 -433.606774) (xy 384.33502 -433.618894) (xy 384.33502 -434.48986) (xy 385.23799 -434.48986)
			(xy 385.238088 -434.475286) (xy 385.239737 -434.446185) (xy 385.241292 -434.431694) (xy 385.241292 -433.34813)
			(xy 385.239744 -433.333638) (xy 385.238094 -433.304538) (xy 385.23799 -433.289964) (xy 385.238088 -433.27539)
			(xy 385.239737 -433.246289) (xy 385.241292 -433.231798) (xy 385.241292 -432.618896) (xy 385.241713 -432.606788)
			(xy 385.249212 -432.583762) (xy 385.263473 -432.564189) (xy 385.283093 -432.549994) (xy 385.306144 -432.542572)
			(xy 385.318254 -432.542188) (xy 386.258054 -432.542188) (xy 386.270146 -432.542647) (xy 386.293153 -432.550097)
			(xy 386.312738 -432.564284) (xy 386.326988 -432.583823) (xy 386.334513 -432.606806) (xy 386.335016 -432.618896)
			(xy 386.335016 -435.16042) (xy 386.334601 -435.172528) (xy 386.327098 -435.195554) (xy 386.312836 -435.215125)
			(xy 386.293215 -435.229319) (xy 386.270164 -435.236743) (xy 386.258054 -435.237128) (xy 385.318254 -435.237128)
			(xy 385.306159 -435.236731) (xy 385.283151 -435.229258) (xy 385.263569 -435.215054) (xy 385.249322 -435.195505)
			(xy 385.241796 -435.172514) (xy 385.241292 -435.16042) (xy 385.241292 -434.548026) (xy 385.239744 -434.533534)
			(xy 385.238094 -434.504434) (xy 385.23799 -434.48986) (xy 384.33502 -434.48986) (xy 384.33502 -435.489858)
			(xy 387.237986 -435.489858) (xy 387.238083 -435.475284) (xy 387.239733 -435.446183) (xy 387.241288 -435.431692)
			(xy 387.241288 -434.348128) (xy 387.23974 -434.333636) (xy 387.23809 -434.304536) (xy 387.237986 -434.289962)
			(xy 387.238084 -434.275388) (xy 387.239733 -434.246287) (xy 387.241288 -434.231796) (xy 387.241288 -433.618894)
			(xy 387.241806 -433.606784) (xy 387.249289 -433.583749) (xy 387.263521 -433.564152) (xy 387.28311 -433.549909)
			(xy 387.30614 -433.542413) (xy 387.31825 -433.541932) (xy 388.25805 -433.541932) (xy 388.270167 -433.542369)
			(xy 388.29321 -433.549869) (xy 388.312811 -433.564121) (xy 388.327051 -433.583729) (xy 388.334538 -433.606777)
			(xy 388.335012 -433.618894) (xy 388.335012 -434.48986) (xy 389.237982 -434.48986) (xy 389.23808 -434.475286)
			(xy 389.239729 -434.446185) (xy 389.241284 -434.431694) (xy 389.241284 -433.34813) (xy 389.239736 -433.333638)
			(xy 389.238086 -433.304538) (xy 389.237982 -433.289964) (xy 389.23808 -433.27539) (xy 389.23973 -433.246289)
			(xy 389.241284 -433.231798) (xy 389.241284 -432.618896) (xy 389.241713 -432.606789) (xy 389.249211 -432.583764)
			(xy 389.26347 -432.564192) (xy 389.283088 -432.549997) (xy 389.306137 -432.542573) (xy 389.318246 -432.542188)
			(xy 390.258046 -432.542188) (xy 390.270143 -432.542569) (xy 390.293153 -432.550044) (xy 390.312736 -432.564251)
			(xy 390.326984 -432.583805) (xy 390.334506 -432.6068) (xy 390.335008 -432.618896) (xy 390.335008 -435.16042)
			(xy 390.334601 -435.172529) (xy 390.327097 -435.195556) (xy 390.312833 -435.215128) (xy 390.29321 -435.229322)
			(xy 390.270157 -435.236744) (xy 390.258046 -435.237128) (xy 389.318246 -435.237128) (xy 389.306156 -435.236653)
			(xy 389.283151 -435.229205) (xy 389.263568 -435.215022) (xy 389.249317 -435.195487) (xy 389.241789 -435.172509)
			(xy 389.241284 -435.16042) (xy 389.241284 -434.548026) (xy 389.239736 -434.533534) (xy 389.238086 -434.504434)
			(xy 389.237982 -434.48986) (xy 388.335012 -434.48986) (xy 388.335012 -435.489858) (xy 391.237978 -435.489858)
			(xy 391.238076 -435.475284) (xy 391.239725 -435.446183) (xy 391.24128 -435.431692) (xy 391.24128 -434.348128)
			(xy 391.239732 -434.333636) (xy 391.238082 -434.304536) (xy 391.237978 -434.289962) (xy 391.238076 -434.275388)
			(xy 391.239725 -434.246287) (xy 391.24128 -434.231796) (xy 391.24128 -433.618894) (xy 391.241656 -433.606767)
			(xy 391.249155 -433.583701) (xy 391.263416 -433.564082) (xy 391.283044 -433.549833) (xy 391.306115 -433.542348)
			(xy 391.318242 -433.541932) (xy 392.258042 -433.541932) (xy 392.270158 -433.542376) (xy 392.293202 -433.549874)
			(xy 392.312802 -433.564123) (xy 392.327043 -433.583731) (xy 392.33453 -433.606778) (xy 392.335004 -433.618894)
			(xy 392.335004 -434.48986) (xy 393.237974 -434.48986) (xy 393.238072 -434.475286) (xy 393.239721 -434.446185)
			(xy 393.241276 -434.431694) (xy 393.241276 -433.34813) (xy 393.239728 -433.333638) (xy 393.238078 -433.304538)
			(xy 393.237974 -433.289964) (xy 393.238072 -433.27539) (xy 393.239722 -433.246289) (xy 393.241276 -433.231798)
			(xy 393.241276 -432.618896) (xy 393.241712 -432.606789) (xy 393.24921 -432.583766) (xy 393.263467 -432.564195)
			(xy 393.283083 -432.55) (xy 393.30613 -432.542575) (xy 393.318238 -432.542188) (xy 394.258038 -432.542188)
			(xy 394.270134 -432.542576) (xy 394.293144 -432.550049) (xy 394.312728 -432.564254) (xy 394.326975 -432.583807)
			(xy 394.334498 -432.606801) (xy 394.335 -432.618896) (xy 394.335 -435.16042) (xy 394.334601 -435.17253)
			(xy 394.327096 -435.195558) (xy 394.31283 -435.215131) (xy 394.293205 -435.229325) (xy 394.270149 -435.236745)
			(xy 394.258038 -435.237128) (xy 393.318238 -435.237128) (xy 393.306147 -435.23666) (xy 393.283142 -435.22921)
			(xy 393.263559 -435.215024) (xy 393.249308 -435.195489) (xy 393.241781 -435.172509) (xy 393.241276 -435.16042)
			(xy 393.241276 -434.548026) (xy 393.239728 -434.533534) (xy 393.238078 -434.504434) (xy 393.237974 -434.48986)
			(xy 392.335004 -434.48986) (xy 392.335004 -435.489858) (xy 395.23797 -435.489858) (xy 395.238068 -435.475284)
			(xy 395.239717 -435.446183) (xy 395.241272 -435.431692) (xy 395.241272 -434.348128) (xy 395.239724 -434.333636)
			(xy 395.238074 -434.304536) (xy 395.23797 -434.289962) (xy 395.238068 -434.275388) (xy 395.239717 -434.246287)
			(xy 395.241272 -434.231796) (xy 395.241272 -433.618894) (xy 395.241656 -433.606768) (xy 395.249154 -433.583703)
			(xy 395.263413 -433.564085) (xy 395.283039 -433.549835) (xy 395.306107 -433.542349) (xy 395.318234 -433.541932)
			(xy 396.258034 -433.541932) (xy 396.27015 -433.542383) (xy 396.293193 -433.549878) (xy 396.312794 -433.564126)
			(xy 396.327034 -433.583732) (xy 396.334522 -433.606778) (xy 396.334996 -433.618894) (xy 396.334996 -434.48986)
			(xy 398.237964 -434.48986) (xy 398.238077 -434.474774) (xy 398.239856 -434.444656) (xy 398.24152 -434.429662)
			(xy 398.24152 -433.350162) (xy 398.239855 -433.335168) (xy 398.238074 -433.30505) (xy 398.237964 -433.289964)
			(xy 398.238077 -433.274878) (xy 398.239856 -433.24476) (xy 398.24152 -433.229766) (xy 398.24152 -432.618896)
			(xy 398.241909 -432.60681) (xy 398.249382 -432.583823) (xy 398.263593 -432.56427) (xy 398.283151 -432.550067)
			(xy 398.306142 -432.542604) (xy 398.318228 -432.542188) (xy 399.258028 -432.542188) (xy 399.270104 -432.54264)
			(xy 399.293071 -432.55011) (xy 399.312607 -432.56431) (xy 399.326801 -432.58385) (xy 399.334264 -432.60682)
			(xy 399.334736 -432.618896) (xy 399.334736 -435.16042) (xy 399.334253 -435.172493) (xy 399.326788 -435.195456)
			(xy 399.312596 -435.21499) (xy 399.293063 -435.229185) (xy 399.270101 -435.236652) (xy 399.258028 -435.237128)
			(xy 398.318228 -435.237128) (xy 398.306149 -435.236664) (xy 398.28317 -435.229206) (xy 398.263621 -435.215013)
			(xy 398.249416 -435.195473) (xy 398.241944 -435.172499) (xy 398.24152 -435.16042) (xy 398.24152 -434.550058)
			(xy 398.239854 -434.535064) (xy 398.238074 -434.504946) (xy 398.237964 -434.48986) (xy 396.334996 -434.48986)
			(xy 396.334996 -435.489858) (xy 400.23796 -435.489858) (xy 400.238073 -435.474772) (xy 400.239852 -435.444654)
			(xy 400.241516 -435.42966) (xy 400.241516 -434.35016) (xy 400.239851 -434.335166) (xy 400.23807 -434.305048)
			(xy 400.23796 -434.289962) (xy 400.238073 -434.274876) (xy 400.239852 -434.244758) (xy 400.241516 -434.229764)
			(xy 400.241516 -433.618894) (xy 400.242002 -433.606807) (xy 400.249457 -433.58381) (xy 400.26364 -433.564232)
			(xy 400.283168 -433.549981) (xy 400.306138 -433.542445) (xy 400.318224 -433.541932) (xy 401.258024 -433.541932)
			(xy 401.270137 -433.542296) (xy 401.293171 -433.549806) (xy 401.312746 -433.56408) (xy 401.326939 -433.583715)
			(xy 401.334353 -433.606779) (xy 401.334732 -433.618894) (xy 401.334732 -434.48986) (xy 402.237956 -434.48986)
			(xy 402.238069 -434.474774) (xy 402.239848 -434.444656) (xy 402.241512 -434.429662) (xy 402.241512 -433.350162)
			(xy 402.239847 -433.335168) (xy 402.238066 -433.30505) (xy 402.237956 -433.289964) (xy 402.238069 -433.274878)
			(xy 402.239848 -433.24476) (xy 402.241512 -433.229766) (xy 402.241512 -432.618896) (xy 402.241909 -432.606811)
			(xy 402.24938 -432.583825) (xy 402.26359 -432.564273) (xy 402.283146 -432.550069) (xy 402.306135 -432.542606)
			(xy 402.31822 -432.542188) (xy 403.25802 -432.542188) (xy 403.270095 -432.542647) (xy 403.293062 -432.550115)
			(xy 403.312599 -432.564313) (xy 403.326793 -432.583852) (xy 403.334255 -432.606821) (xy 403.334728 -432.618896)
			(xy 403.334728 -435.16042) (xy 403.334253 -435.172494) (xy 403.326787 -435.195458) (xy 403.312593 -435.214993)
			(xy 403.293058 -435.229187) (xy 403.270094 -435.236653) (xy 403.25802 -435.237128) (xy 402.31822 -435.237128)
			(xy 402.306148 -435.236619) (xy 402.283185 -435.229165) (xy 402.26365 -435.214979) (xy 402.249454 -435.195451)
			(xy 402.241987 -435.172491) (xy 402.241512 -435.16042) (xy 402.241512 -434.550058) (xy 402.239846 -434.535064)
			(xy 402.238066 -434.504946) (xy 402.237956 -434.48986) (xy 401.334732 -434.48986) (xy 401.334732 -435.489858)
			(xy 404.237952 -435.489858) (xy 404.238065 -435.474772) (xy 404.239844 -435.444654) (xy 404.241508 -435.42966)
			(xy 404.241508 -434.35016) (xy 404.239843 -434.335166) (xy 404.238062 -434.305048) (xy 404.237952 -434.289962)
			(xy 404.238065 -434.274876) (xy 404.239844 -434.244758) (xy 404.241508 -434.229764) (xy 404.241508 -433.618894)
			(xy 404.242002 -433.606807) (xy 404.249456 -433.583812) (xy 404.263637 -433.564235) (xy 404.283163 -433.549984)
			(xy 404.306131 -433.542446) (xy 404.318216 -433.541932) (xy 405.258016 -433.541932) (xy 405.270129 -433.542303)
			(xy 405.293162 -433.549811) (xy 405.312738 -433.564083) (xy 405.326931 -433.583716) (xy 405.334345 -433.606779)
			(xy 405.334724 -433.618894) (xy 405.334724 -434.48986) (xy 406.237948 -434.48986) (xy 406.238061 -434.474774)
			(xy 406.23984 -434.444656) (xy 406.241504 -434.429662) (xy 406.241504 -433.350162) (xy 406.239839 -433.335168)
			(xy 406.238058 -433.30505) (xy 406.237948 -433.289964) (xy 406.238061 -433.274878) (xy 406.23984 -433.24476)
			(xy 406.241504 -433.229766) (xy 406.241504 -432.618896) (xy 406.241909 -432.606812) (xy 406.249379 -432.583827)
			(xy 406.263587 -432.564276) (xy 406.283141 -432.550072) (xy 406.306128 -432.542607) (xy 406.318212 -432.542188)
			(xy 407.258012 -432.542188) (xy 407.270087 -432.542654) (xy 407.293054 -432.550119) (xy 407.31259 -432.564316)
			(xy 407.326784 -432.583854) (xy 407.334247 -432.606821) (xy 407.33472 -432.618896) (xy 407.33472 -435.16042)
			(xy 407.334253 -435.172494) (xy 407.326786 -435.19546) (xy 407.31259 -435.214996) (xy 407.293053 -435.22919)
			(xy 407.270086 -435.236654) (xy 407.258012 -435.237128) (xy 406.318212 -435.237128) (xy 406.30614 -435.236626)
			(xy 406.283177 -435.229169) (xy 406.263641 -435.214982) (xy 406.249446 -435.195452) (xy 406.241979 -435.172492)
			(xy 406.241504 -435.16042) (xy 406.241504 -434.550058) (xy 406.239838 -434.535064) (xy 406.238058 -434.504946)
			(xy 406.237948 -434.48986) (xy 405.334724 -434.48986) (xy 405.334724 -435.489858) (xy 408.237944 -435.489858)
			(xy 408.238057 -435.474772) (xy 408.239836 -435.444654) (xy 408.2415 -435.42966) (xy 408.2415 -434.35016)
			(xy 408.239834 -434.335166) (xy 408.238054 -434.305048) (xy 408.237944 -434.289962) (xy 408.238057 -434.274876)
			(xy 408.239836 -434.244758) (xy 408.2415 -434.229764) (xy 408.2415 -433.618894) (xy 408.242002 -433.606808)
			(xy 408.249455 -433.583814) (xy 408.263634 -433.564238) (xy 408.283158 -433.549986) (xy 408.306124 -433.542447)
			(xy 408.318208 -433.541932) (xy 409.258008 -433.541932) (xy 409.270121 -433.54231) (xy 409.293154 -433.549815)
			(xy 409.312729 -433.564086) (xy 409.326923 -433.583717) (xy 409.334337 -433.60678) (xy 409.334716 -433.618894)
			(xy 409.334716 -434.48986) (xy 410.23794 -434.48986) (xy 410.238053 -434.474774) (xy 410.239832 -434.444656)
			(xy 410.241496 -434.429662) (xy 410.241496 -433.350162) (xy 410.239831 -433.335168) (xy 410.23805 -433.30505)
			(xy 410.23794 -433.289964) (xy 410.238053 -433.274878) (xy 410.239832 -433.24476) (xy 410.241496 -433.229766)
			(xy 410.241496 -432.618896) (xy 410.241961 -432.606821) (xy 410.249425 -432.583853) (xy 410.263621 -432.564316)
			(xy 410.28316 -432.550121) (xy 410.306129 -432.54266) (xy 410.318204 -432.542188) (xy 411.258004 -432.542188)
			(xy 411.270078 -432.542661) (xy 411.293045 -432.550124) (xy 411.312582 -432.564318) (xy 411.326776 -432.583855)
			(xy 411.334239 -432.606822) (xy 411.334712 -432.618896) (xy 411.334712 -435.16042) (xy 411.334253 -435.172495)
			(xy 411.326785 -435.195462) (xy 411.312587 -435.214999) (xy 411.293048 -435.229193) (xy 411.270079 -435.236655)
			(xy 411.258004 -435.237128) (xy 410.318204 -435.237128) (xy 410.306132 -435.236633) (xy 410.283168 -435.229174)
			(xy 410.263633 -435.214984) (xy 410.249437 -435.195454) (xy 410.241971 -435.172492) (xy 410.241496 -435.16042)
			(xy 410.241496 -434.550058) (xy 410.23983 -434.535064) (xy 410.23805 -434.504946) (xy 410.23794 -434.48986)
			(xy 409.334716 -434.48986) (xy 409.334716 -435.489858) (xy 412.237936 -435.489858) (xy 412.238051 -435.474773)
			(xy 412.23983 -435.444654) (xy 412.241492 -435.42966) (xy 412.241492 -434.35016) (xy 412.239826 -434.335166)
			(xy 412.238046 -434.305048) (xy 412.237936 -434.289962) (xy 412.238051 -434.274877) (xy 412.23983 -434.244758)
			(xy 412.241492 -434.229764) (xy 412.241492 -433.618894) (xy 412.242002 -433.606809) (xy 412.249454 -433.583816)
			(xy 412.263631 -433.564241) (xy 412.283153 -433.549989) (xy 412.306117 -433.542448) (xy 412.3182 -433.541932)
			(xy 413.258 -433.541932) (xy 413.270112 -433.542317) (xy 413.293145 -433.54982) (xy 413.312721 -433.564088)
			(xy 413.326914 -433.583719) (xy 413.334329 -433.60678) (xy 413.334708 -433.618894) (xy 413.334708 -436.160418)
			(xy 413.334209 -436.172504) (xy 413.326753 -436.195497) (xy 413.312573 -436.215072) (xy 413.29305 -436.229324)
			(xy 413.270084 -436.236864) (xy 413.258 -436.23738) (xy 412.3182 -436.23738) (xy 412.306089 -436.236984)
			(xy 412.283058 -436.229482) (xy 412.263483 -436.215216) (xy 412.24929 -436.195589) (xy 412.241872 -436.17253)
			(xy 412.241492 -436.160418) (xy 412.241492 -435.550056) (xy 412.239826 -435.535062) (xy 412.238046 -435.504944)
			(xy 412.237936 -435.489858) (xy 409.334716 -435.489858) (xy 409.334716 -436.160418) (xy 409.334307 -436.172513)
			(xy 409.32684 -436.195522) (xy 409.31264 -436.215105) (xy 409.293092 -436.229353) (xy 409.270102 -436.236877)
			(xy 409.258008 -436.23738) (xy 408.318208 -436.23738) (xy 408.306098 -436.236977) (xy 408.283067 -436.229477)
			(xy 408.263492 -436.215213) (xy 408.249298 -436.195587) (xy 408.24188 -436.17253) (xy 408.2415 -436.160418)
			(xy 408.2415 -435.550056) (xy 408.239834 -435.535062) (xy 408.238054 -435.504944) (xy 408.237944 -435.489858)
			(xy 405.334724 -435.489858) (xy 405.334724 -436.160418) (xy 405.334307 -436.172512) (xy 405.326841 -436.195519)
			(xy 405.312643 -436.215102) (xy 405.293097 -436.229351) (xy 405.270109 -436.236876) (xy 405.258016 -436.23738)
			(xy 404.318216 -436.23738) (xy 404.306106 -436.23697) (xy 404.283076 -436.229472) (xy 404.263501 -436.21521)
			(xy 404.249306 -436.195585) (xy 404.241889 -436.172529) (xy 404.241508 -436.160418) (xy 404.241508 -435.550056)
			(xy 404.239842 -435.535062) (xy 404.238062 -435.504944) (xy 404.237952 -435.489858) (xy 401.334732 -435.489858)
			(xy 401.334732 -436.160418) (xy 401.334308 -436.172511) (xy 401.326843 -436.195517) (xy 401.312646 -436.215099)
			(xy 401.293102 -436.229348) (xy 401.270116 -436.236875) (xy 401.258024 -436.23738) (xy 400.318224 -436.23738)
			(xy 400.306114 -436.236963) (xy 400.283085 -436.229468) (xy 400.263509 -436.215207) (xy 400.249315 -436.195584)
			(xy 400.241897 -436.172529) (xy 400.241516 -436.160418) (xy 400.241516 -435.550056) (xy 400.23985 -435.535062)
			(xy 400.23807 -435.504944) (xy 400.23796 -435.489858) (xy 396.334996 -435.489858) (xy 396.334996 -436.160418)
			(xy 396.334504 -436.17253) (xy 396.327016 -436.195568) (xy 396.312778 -436.215167) (xy 396.293183 -436.229409)
			(xy 396.270146 -436.236902) (xy 396.258034 -436.23738) (xy 395.318234 -436.23738) (xy 395.306115 -436.236911)
			(xy 395.28306 -436.229431) (xy 395.263446 -436.215191) (xy 395.249193 -436.195587) (xy 395.241697 -436.172537)
			(xy 395.241272 -436.160418) (xy 395.241272 -435.548024) (xy 395.239724 -435.533532) (xy 395.238074 -435.504432)
			(xy 395.23797 -435.489858) (xy 392.335004 -435.489858) (xy 392.335004 -436.160418) (xy 392.334504 -436.172529)
			(xy 392.327017 -436.195566) (xy 392.312781 -436.215164) (xy 392.293188 -436.229406) (xy 392.270153 -436.236901)
			(xy 392.258042 -436.23738) (xy 391.318242 -436.23738) (xy 391.306123 -436.236905) (xy 391.283069 -436.229426)
			(xy 391.263455 -436.215188) (xy 391.249201 -436.195585) (xy 391.241705 -436.172536) (xy 391.24128 -436.160418)
			(xy 391.24128 -435.548024) (xy 391.239732 -435.533532) (xy 391.238082 -435.504432) (xy 391.237978 -435.489858)
			(xy 388.335012 -435.489858) (xy 388.335012 -436.160418) (xy 388.334505 -436.172529) (xy 388.327018 -436.195564)
			(xy 388.312784 -436.215161) (xy 388.293193 -436.229404) (xy 388.27016 -436.2369) (xy 388.25805 -436.23738)
			(xy 387.31825 -436.23738) (xy 387.306135 -436.236931) (xy 387.283093 -436.229432) (xy 387.263493 -436.215184)
			(xy 387.249253 -436.195578) (xy 387.241764 -436.172534) (xy 387.241288 -436.160418) (xy 387.241288 -435.548024)
			(xy 387.23974 -435.533532) (xy 387.23809 -435.504432) (xy 387.237986 -435.489858) (xy 384.33502 -435.489858)
			(xy 384.33502 -436.160418) (xy 384.334654 -436.172546) (xy 384.327152 -436.195612) (xy 384.312888 -436.215231)
			(xy 384.293258 -436.22948) (xy 384.270186 -436.236964) (xy 384.258058 -436.23738) (xy 383.318258 -436.23738)
			(xy 383.306143 -436.236924) (xy 383.283101 -436.229428) (xy 383.263502 -436.215181) (xy 383.249261 -436.195577)
			(xy 383.241772 -436.172533) (xy 383.241296 -436.160418) (xy 383.241296 -435.548024) (xy 383.239748 -435.533532)
			(xy 383.238098 -435.504432) (xy 383.237994 -435.489858) (xy 361.616728 -435.489858) (xy 361.642562 -435.536833)
			(xy 361.697938 -435.654184) (xy 361.74595 -435.774736) (xy 361.786412 -435.898026) (xy 361.81917 -436.023584)
			(xy 361.844098 -436.150927) (xy 361.861101 -436.279569) (xy 361.870114 -436.409016) (xy 361.871103 -436.538773)
			(xy 361.864062 -436.668342) (xy 361.849021 -436.797228) (xy 361.826035 -436.924936) (xy 361.795194 -437.050978)
			(xy 361.756614 -437.174871) (xy 361.710445 -437.29614) (xy 361.656862 -437.41432) (xy 361.596072 -437.52896)
			(xy 361.528306 -437.63962) (xy 361.453825 -437.745876) (xy 361.372914 -437.847321) (xy 361.285882 -437.943567)
			(xy 361.193064 -438.034245) (xy 361.128666 -438.089802) (xy 381.237998 -438.089802) (xy 381.238091 -438.075228)
			(xy 381.239744 -438.046127) (xy 381.2413 -438.031636) (xy 381.2413 -436.948072) (xy 381.239755 -436.93358)
			(xy 381.238103 -436.90448) (xy 381.237998 -436.889906) (xy 381.238091 -436.875332) (xy 381.239744 -436.846231)
			(xy 381.2413 -436.83174) (xy 381.2413 -436.219092) (xy 381.241709 -436.206983) (xy 381.249211 -436.183955)
			(xy 381.263474 -436.164382) (xy 381.283097 -436.150188) (xy 381.306151 -436.142767) (xy 381.318262 -436.142384)
			(xy 382.258062 -436.142384) (xy 382.270154 -436.142841) (xy 382.293161 -436.150292) (xy 382.312745 -436.16448)
			(xy 382.326995 -436.184019) (xy 382.334521 -436.207002) (xy 382.335024 -436.219092) (xy 382.335024 -438.760616)
			(xy 382.334598 -438.772723) (xy 382.327097 -438.795747) (xy 382.312837 -438.815318) (xy 382.293219 -438.829513)
			(xy 382.270171 -438.836937) (xy 382.258062 -438.837324) (xy 381.318262 -438.837324) (xy 381.306167 -438.836924)
			(xy 381.283159 -438.829453) (xy 381.263577 -438.81525) (xy 381.249329 -438.795701) (xy 381.241804 -438.77271)
			(xy 381.2413 -438.760616) (xy 381.2413 -438.147968) (xy 381.239755 -438.133476) (xy 381.238103 -438.104376)
			(xy 381.237998 -438.089802) (xy 361.128666 -438.089802) (xy 361.094814 -438.119007) (xy 360.991508 -438.19753)
			(xy 360.883543 -438.269512) (xy 360.771333 -438.334677) (xy 360.655306 -438.392776) (xy 360.535907 -438.443587)
			(xy 360.413594 -438.486915) (xy 360.288835 -438.522593) (xy 360.162108 -438.550485) (xy 360.033898 -438.570485)
			(xy 359.904696 -438.582516) (xy 359.774998 -438.586531) (xy 359.6453 -438.582516) (xy 359.516098 -438.570485)
			(xy 359.387888 -438.550485) (xy 359.261161 -438.522593) (xy 359.136402 -438.486915) (xy 359.014089 -438.443587)
			(xy 358.89469 -438.392776) (xy 358.778663 -438.334677) (xy 358.666453 -438.269512) (xy 358.558488 -438.19753)
			(xy 358.455182 -438.119007) (xy 358.356932 -438.034245) (xy 358.264114 -437.943567) (xy 358.177082 -437.847321)
			(xy 358.096171 -437.745876) (xy 358.02169 -437.63962) (xy 357.953924 -437.52896) (xy 357.893134 -437.41432)
			(xy 357.839551 -437.29614) (xy 357.793382 -437.174871) (xy 357.754802 -437.050978) (xy 357.723961 -436.924936)
			(xy 357.700975 -436.797228) (xy 357.685934 -436.668342) (xy 357.678893 -436.538773) (xy 357.679882 -436.409016)
			(xy 357.688895 -436.279569) (xy 357.705898 -436.150927) (xy 357.730826 -436.023584) (xy 357.763584 -435.898026)
			(xy 357.804046 -435.774736) (xy 357.852058 -435.654184) (xy 357.907434 -435.536833) (xy 357.969964 -435.423133)
			(xy 358.039407 -435.313518) (xy 358.115498 -435.208409) (xy 358.197945 -435.108208) (xy 358.286433 -435.013299)
			(xy 358.380622 -434.924045) (xy 358.430068 -434.882036) (xy 358.441235 -434.872067) (xy 358.457661 -434.847056)
			(xy 358.466134 -434.818358) (xy 358.465926 -434.788437) (xy 358.457055 -434.759859) (xy 358.440283 -434.735079)
			(xy 358.417049 -434.716224) (xy 358.403398 -434.710078) (xy 358.324356 -434.677212) (xy 358.169157 -434.604934)
			(xy 358.017549 -434.5254) (xy 357.869871 -434.438788) (xy 357.726451 -434.345291) (xy 357.587612 -434.24512)
			(xy 357.453663 -434.138498) (xy 357.324904 -434.025662) (xy 357.201623 -433.906867) (xy 357.084096 -433.782376)
			(xy 356.972584 -433.652469) (xy 356.867339 -433.517435) (xy 356.768594 -433.377578) (xy 356.676571 -433.233209)
			(xy 356.591476 -433.084651) (xy 356.513498 -432.932237) (xy 356.442812 -432.776307) (xy 356.379576 -432.61721)
			(xy 356.323932 -432.455301) (xy 356.276004 -432.290943) (xy 356.235899 -432.124503) (xy 356.203706 -431.956354)
			(xy 356.179498 -431.78687) (xy 356.163329 -431.616432) (xy 356.155235 -431.44542) (xy 356.154736 -431.359818)
			(xy 346.23502 -431.359818) (xy 346.23502 -432.560476) (xy 346.234563 -432.572582) (xy 346.227073 -432.595605)
			(xy 346.212821 -432.615176) (xy 346.193209 -432.629373) (xy 346.170165 -432.636797) (xy 346.158058 -432.637184)
			(xy 345.218258 -432.637184) (xy 345.206169 -432.636729) (xy 345.183171 -432.629264) (xy 345.163593 -432.615073)
			(xy 345.149343 -432.595539) (xy 345.141808 -432.572564) (xy 345.141296 -432.560476) (xy 345.141296 -431.948082)
			(xy 345.139753 -431.93359) (xy 345.1381 -431.90449) (xy 345.137994 -431.889916) (xy 342.235028 -431.889916)
			(xy 342.235028 -432.560476) (xy 342.234563 -432.572581) (xy 342.227074 -432.595602) (xy 342.212824 -432.615174)
			(xy 342.193214 -432.62937) (xy 342.170172 -432.636796) (xy 342.158066 -432.637184) (xy 341.218266 -432.637184)
			(xy 341.206177 -432.636722) (xy 341.183179 -432.629259) (xy 341.163602 -432.61507) (xy 341.149352 -432.595538)
			(xy 341.141816 -432.572563) (xy 341.141304 -432.560476) (xy 341.141304 -431.948082) (xy 341.13976 -431.93359)
			(xy 341.138108 -431.90449) (xy 341.138002 -431.889916) (xy 338.235036 -431.889916) (xy 338.235036 -432.560476)
			(xy 338.234564 -432.57258) (xy 338.227075 -432.5956) (xy 338.212827 -432.615171) (xy 338.193219 -432.629367)
			(xy 338.170179 -432.636795) (xy 338.158074 -432.637184) (xy 337.218274 -432.637184) (xy 337.206185 -432.636715)
			(xy 337.183188 -432.629254) (xy 337.163611 -432.615067) (xy 337.14936 -432.595536) (xy 337.141824 -432.572563)
			(xy 337.141312 -432.560476) (xy 337.141312 -431.948082) (xy 337.139768 -431.93359) (xy 337.138116 -431.90449)
			(xy 337.13801 -431.889916) (xy 334.235044 -431.889916) (xy 334.235044 -432.560476) (xy 334.234564 -432.572579)
			(xy 334.227076 -432.595598) (xy 334.21283 -432.615168) (xy 334.193224 -432.629365) (xy 334.170186 -432.636794)
			(xy 334.158082 -432.637184) (xy 333.218282 -432.637184) (xy 333.206194 -432.636709) (xy 333.183197 -432.62925)
			(xy 333.163619 -432.615065) (xy 333.149368 -432.595535) (xy 333.141832 -432.572563) (xy 333.14132 -432.560476)
			(xy 333.14132 -431.948082) (xy 333.139776 -431.93359) (xy 333.138124 -431.90449) (xy 333.138018 -431.889916)
			(xy 329.2348 -431.889916) (xy 329.2348 -432.560476) (xy 329.234367 -432.572558) (xy 329.226905 -432.595542)
			(xy 329.212704 -432.615093) (xy 329.193156 -432.629297) (xy 329.170174 -432.636764) (xy 329.158092 -432.637184)
			(xy 328.218292 -432.637184) (xy 328.206206 -432.636794) (xy 328.183219 -432.629321) (xy 328.163667 -432.61511)
			(xy 328.149464 -432.595552) (xy 328.142001 -432.572562) (xy 328.141584 -432.560476) (xy 328.141584 -431.950114)
			(xy 328.139914 -431.935121) (xy 328.138137 -431.905002) (xy 328.138028 -431.889916) (xy 325.234808 -431.889916)
			(xy 325.234808 -432.560476) (xy 325.234367 -432.572557) (xy 325.226906 -432.595539) (xy 325.212707 -432.61509)
			(xy 325.193161 -432.629295) (xy 325.170181 -432.636763) (xy 325.1581 -432.637184) (xy 324.2183 -432.637184)
			(xy 324.206215 -432.636787) (xy 324.183228 -432.629317) (xy 324.163676 -432.615107) (xy 324.149472 -432.59555)
			(xy 324.142009 -432.572561) (xy 324.141592 -432.560476) (xy 324.141592 -431.950114) (xy 324.139922 -431.935121)
			(xy 324.138145 -431.905002) (xy 324.138036 -431.889916) (xy 321.234816 -431.889916) (xy 321.234816 -432.560476)
			(xy 321.234367 -432.572557) (xy 321.226907 -432.595537) (xy 321.21271 -432.615087) (xy 321.193166 -432.629292)
			(xy 321.170188 -432.636762) (xy 321.158108 -432.637184) (xy 320.218308 -432.637184) (xy 320.206223 -432.63678)
			(xy 320.183237 -432.629312) (xy 320.163684 -432.615105) (xy 320.149481 -432.595549) (xy 320.142017 -432.572561)
			(xy 320.1416 -432.560476) (xy 320.1416 -431.950114) (xy 320.13993 -431.935121) (xy 320.138153 -431.905002)
			(xy 320.138044 -431.889916) (xy 317.234824 -431.889916) (xy 317.234824 -432.560476) (xy 317.234367 -432.572556)
			(xy 317.226908 -432.595535) (xy 317.212713 -432.615084) (xy 317.193171 -432.62929) (xy 317.170196 -432.636761)
			(xy 317.158116 -432.637184) (xy 316.218316 -432.637184) (xy 316.206232 -432.636773) (xy 316.183246 -432.629307)
			(xy 316.163693 -432.615101) (xy 316.149489 -432.595547) (xy 316.142026 -432.57256) (xy 316.141608 -432.560476)
			(xy 316.141608 -431.950114) (xy 316.139938 -431.935121) (xy 316.138161 -431.905002) (xy 316.138052 -431.889916)
			(xy 274.613204 -431.889916) (xy 274.618425 -431.905986) (xy 274.665585 -432.076867) (xy 274.705031 -432.249692)
			(xy 274.736684 -432.424113) (xy 274.760479 -432.599778) (xy 274.77637 -432.776334) (xy 274.784323 -432.953425)
			(xy 274.78482 -433.04206) (xy 274.784323 -433.130695) (xy 274.77637 -433.307786) (xy 274.760479 -433.484342)
			(xy 274.736684 -433.660007) (xy 274.705031 -433.834428) (xy 274.665585 -434.007253) (xy 274.618425 -434.178134)
			(xy 274.563646 -434.346728) (xy 274.509927 -434.48986) (xy 314.138056 -434.48986) (xy 314.138169 -434.474774)
			(xy 314.139948 -434.444656) (xy 314.141612 -434.429662) (xy 314.141612 -433.350162) (xy 314.139947 -433.335168)
			(xy 314.138166 -433.30505) (xy 314.138056 -433.289964) (xy 314.138169 -433.274878) (xy 314.139948 -433.24476)
			(xy 314.141612 -433.229766) (xy 314.141612 -432.618896) (xy 314.142009 -432.606811) (xy 314.14948 -432.583825)
			(xy 314.16369 -432.564273) (xy 314.183246 -432.550069) (xy 314.206235 -432.542606) (xy 314.21832 -432.542188)
			(xy 315.15812 -432.542188) (xy 315.170195 -432.542647) (xy 315.193162 -432.550115) (xy 315.212699 -432.564313)
			(xy 315.226893 -432.583852) (xy 315.234355 -432.606821) (xy 315.234828 -432.618896) (xy 315.234828 -435.16042)
			(xy 315.234353 -435.172494) (xy 315.226887 -435.195458) (xy 315.212693 -435.214993) (xy 315.193158 -435.229187)
			(xy 315.170194 -435.236653) (xy 315.15812 -435.237128) (xy 314.21832 -435.237128) (xy 314.206248 -435.236619)
			(xy 314.183285 -435.229165) (xy 314.16375 -435.214979) (xy 314.149554 -435.195451) (xy 314.142087 -435.172491)
			(xy 314.141612 -435.16042) (xy 314.141612 -434.550058) (xy 314.139946 -434.535064) (xy 314.138166 -434.504946)
			(xy 314.138056 -434.48986) (xy 274.509927 -434.48986) (xy 274.501358 -434.512693) (xy 274.431686 -434.675698)
			(xy 274.354772 -434.835412) (xy 274.270769 -434.991515) (xy 274.179848 -435.143692) (xy 274.082191 -435.291636)
			(xy 273.977994 -435.43505) (xy 273.934286 -435.489858) (xy 316.138052 -435.489858) (xy 316.138165 -435.474772)
			(xy 316.139944 -435.444654) (xy 316.141608 -435.42966) (xy 316.141608 -434.35016) (xy 316.139943 -434.335166)
			(xy 316.138162 -434.305048) (xy 316.138052 -434.289962) (xy 316.138165 -434.274876) (xy 316.139944 -434.244758)
			(xy 316.141608 -434.229764) (xy 316.141608 -433.618894) (xy 316.142102 -433.606807) (xy 316.149556 -433.583812)
			(xy 316.163737 -433.564235) (xy 316.183263 -433.549984) (xy 316.206231 -433.542446) (xy 316.218316 -433.541932)
			(xy 317.158116 -433.541932) (xy 317.170229 -433.542303) (xy 317.193262 -433.549811) (xy 317.212838 -433.564083)
			(xy 317.227031 -433.583716) (xy 317.234445 -433.606779) (xy 317.234824 -433.618894) (xy 317.234824 -434.48986)
			(xy 318.138048 -434.48986) (xy 318.138161 -434.474774) (xy 318.13994 -434.444656) (xy 318.141604 -434.429662)
			(xy 318.141604 -433.350162) (xy 318.139939 -433.335168) (xy 318.138158 -433.30505) (xy 318.138048 -433.289964)
			(xy 318.138161 -433.274878) (xy 318.13994 -433.24476) (xy 318.141604 -433.229766) (xy 318.141604 -432.618896)
			(xy 318.142009 -432.606812) (xy 318.149479 -432.583827) (xy 318.163687 -432.564276) (xy 318.183241 -432.550072)
			(xy 318.206228 -432.542607) (xy 318.218312 -432.542188) (xy 319.158112 -432.542188) (xy 319.170187 -432.542654)
			(xy 319.193154 -432.550119) (xy 319.21269 -432.564316) (xy 319.226884 -432.583854) (xy 319.234347 -432.606821)
			(xy 319.23482 -432.618896) (xy 319.23482 -435.16042) (xy 319.234353 -435.172494) (xy 319.226886 -435.19546)
			(xy 319.21269 -435.214996) (xy 319.193153 -435.22919) (xy 319.170186 -435.236654) (xy 319.158112 -435.237128)
			(xy 318.218312 -435.237128) (xy 318.20624 -435.236626) (xy 318.183277 -435.229169) (xy 318.163741 -435.214982)
			(xy 318.149546 -435.195452) (xy 318.142079 -435.172492) (xy 318.141604 -435.16042) (xy 318.141604 -434.550058)
			(xy 318.139938 -434.535064) (xy 318.138158 -434.504946) (xy 318.138048 -434.48986) (xy 317.234824 -434.48986)
			(xy 317.234824 -435.489858) (xy 320.138044 -435.489858) (xy 320.138157 -435.474772) (xy 320.139936 -435.444654)
			(xy 320.1416 -435.42966) (xy 320.1416 -434.35016) (xy 320.139934 -434.335166) (xy 320.138154 -434.305048)
			(xy 320.138044 -434.289962) (xy 320.138157 -434.274876) (xy 320.139936 -434.244758) (xy 320.1416 -434.229764)
			(xy 320.1416 -433.618894) (xy 320.142102 -433.606808) (xy 320.149555 -433.583814) (xy 320.163734 -433.564238)
			(xy 320.183258 -433.549986) (xy 320.206224 -433.542447) (xy 320.218308 -433.541932) (xy 321.158108 -433.541932)
			(xy 321.170221 -433.54231) (xy 321.193254 -433.549815) (xy 321.212829 -433.564086) (xy 321.227023 -433.583717)
			(xy 321.234437 -433.60678) (xy 321.234816 -433.618894) (xy 321.234816 -434.48986) (xy 322.13804 -434.48986)
			(xy 322.138153 -434.474774) (xy 322.139932 -434.444656) (xy 322.141596 -434.429662) (xy 322.141596 -433.350162)
			(xy 322.139931 -433.335168) (xy 322.13815 -433.30505) (xy 322.13804 -433.289964) (xy 322.138153 -433.274878)
			(xy 322.139932 -433.24476) (xy 322.141596 -433.229766) (xy 322.141596 -432.618896) (xy 322.142061 -432.606821)
			(xy 322.149525 -432.583853) (xy 322.163721 -432.564316) (xy 322.18326 -432.550121) (xy 322.206229 -432.54266)
			(xy 322.218304 -432.542188) (xy 323.158104 -432.542188) (xy 323.170178 -432.542661) (xy 323.193145 -432.550124)
			(xy 323.212682 -432.564318) (xy 323.226876 -432.583855) (xy 323.234339 -432.606822) (xy 323.234812 -432.618896)
			(xy 323.234812 -435.16042) (xy 323.234353 -435.172495) (xy 323.226885 -435.195462) (xy 323.212687 -435.214999)
			(xy 323.193148 -435.229193) (xy 323.170179 -435.236655) (xy 323.158104 -435.237128) (xy 322.218304 -435.237128)
			(xy 322.206232 -435.236633) (xy 322.183268 -435.229174) (xy 322.163733 -435.214984) (xy 322.149537 -435.195454)
			(xy 322.142071 -435.172492) (xy 322.141596 -435.16042) (xy 322.141596 -434.550058) (xy 322.13993 -434.535064)
			(xy 322.13815 -434.504946) (xy 322.13804 -434.48986) (xy 321.234816 -434.48986) (xy 321.234816 -435.489858)
			(xy 324.138036 -435.489858) (xy 324.138151 -435.474773) (xy 324.13993 -435.444654) (xy 324.141592 -435.42966)
			(xy 324.141592 -434.35016) (xy 324.139926 -434.335166) (xy 324.138146 -434.305048) (xy 324.138036 -434.289962)
			(xy 324.138151 -434.274877) (xy 324.13993 -434.244758) (xy 324.141592 -434.229764) (xy 324.141592 -433.618894)
			(xy 324.142102 -433.606809) (xy 324.149554 -433.583816) (xy 324.163731 -433.564241) (xy 324.183253 -433.549989)
			(xy 324.206217 -433.542448) (xy 324.2183 -433.541932) (xy 325.1581 -433.541932) (xy 325.170212 -433.542317)
			(xy 325.193245 -433.54982) (xy 325.212821 -433.564088) (xy 325.227014 -433.583719) (xy 325.234429 -433.60678)
			(xy 325.234808 -433.618894) (xy 325.234808 -434.48986) (xy 326.138032 -434.48986) (xy 326.138147 -434.474775)
			(xy 326.139926 -434.444656) (xy 326.141588 -434.429662) (xy 326.141588 -433.350162) (xy 326.139923 -433.335168)
			(xy 326.138142 -433.30505) (xy 326.138032 -433.289964) (xy 326.138148 -433.274879) (xy 326.139926 -433.24476)
			(xy 326.141588 -433.229766) (xy 326.141588 -432.618896) (xy 326.142061 -432.606822) (xy 326.149524 -432.583855)
			(xy 326.163718 -432.564318) (xy 326.183255 -432.550124) (xy 326.206222 -432.542661) (xy 326.218296 -432.542188)
			(xy 327.158096 -432.542188) (xy 327.17017 -432.542668) (xy 327.193136 -432.550129) (xy 327.212673 -432.564321)
			(xy 327.226868 -432.583857) (xy 327.234331 -432.606822) (xy 327.234804 -432.618896) (xy 327.234804 -435.16042)
			(xy 327.234353 -435.172496) (xy 327.226884 -435.195464) (xy 327.212684 -435.215001) (xy 327.193143 -435.229195)
			(xy 327.170172 -435.236656) (xy 327.158096 -435.237128) (xy 326.218296 -435.237128) (xy 326.206223 -435.236639)
			(xy 326.183259 -435.229178) (xy 326.163724 -435.214987) (xy 326.149529 -435.195455) (xy 326.142063 -435.172493)
			(xy 326.141588 -435.16042) (xy 326.141588 -434.550058) (xy 326.139922 -434.535064) (xy 326.138142 -434.504946)
			(xy 326.138032 -434.48986) (xy 325.234808 -434.48986) (xy 325.234808 -435.489858) (xy 328.138028 -435.489858)
			(xy 328.138143 -435.474773) (xy 328.139922 -435.444654) (xy 328.141584 -435.42966) (xy 328.141584 -434.35016)
			(xy 328.139918 -434.335166) (xy 328.138138 -434.305048) (xy 328.138028 -434.289962) (xy 328.138143 -434.274877)
			(xy 328.139922 -434.244758) (xy 328.141584 -434.229764) (xy 328.141584 -433.618894) (xy 328.142003 -433.6068)
			(xy 328.149467 -433.583792) (xy 328.163664 -433.564208) (xy 328.183211 -433.549959) (xy 328.206199 -433.542435)
			(xy 328.218292 -433.541932) (xy 329.158092 -433.541932) (xy 329.170204 -433.542323) (xy 329.193236 -433.549824)
			(xy 329.212812 -433.564091) (xy 329.227006 -433.58372) (xy 329.234421 -433.606781) (xy 329.2348 -433.618894)
			(xy 329.2348 -434.48986) (xy 331.138022 -434.48986) (xy 331.13812 -434.475286) (xy 331.13977 -434.446185)
			(xy 331.141324 -434.431694) (xy 331.141324 -433.34813) (xy 331.139776 -433.333638) (xy 331.138126 -433.304538)
			(xy 331.138022 -433.289964) (xy 331.13812 -433.27539) (xy 331.13977 -433.246289) (xy 331.141324 -433.231798)
			(xy 331.141324 -432.618896) (xy 331.141713 -432.606785) (xy 331.149217 -432.583753) (xy 331.163484 -432.564178)
			(xy 331.183113 -432.549984) (xy 331.206173 -432.542568) (xy 331.218286 -432.542188) (xy 332.158086 -432.542188)
			(xy 332.17018 -432.54262) (xy 332.193188 -432.550079) (xy 332.212772 -432.564273) (xy 332.227021 -432.583817)
			(xy 332.234545 -432.606804) (xy 332.235048 -432.618896) (xy 332.235048 -435.16042) (xy 332.234601 -435.172525)
			(xy 332.227102 -435.195545) (xy 332.212847 -435.215113) (xy 332.193235 -435.229309) (xy 332.170192 -435.236738)
			(xy 332.158086 -435.237128) (xy 331.218286 -435.237128) (xy 331.206192 -435.236704) (xy 331.183186 -435.22924)
			(xy 331.163603 -435.215043) (xy 331.149354 -435.195499) (xy 331.141828 -435.172512) (xy 331.141324 -435.16042)
			(xy 331.141324 -434.548026) (xy 331.139776 -434.533534) (xy 331.138126 -434.504434) (xy 331.138022 -434.48986)
			(xy 329.2348 -434.48986) (xy 329.2348 -435.489858) (xy 333.138018 -435.489858) (xy 333.138116 -435.475284)
			(xy 333.139766 -435.446183) (xy 333.14132 -435.431692) (xy 333.14132 -434.348128) (xy 333.139772 -434.333636)
			(xy 333.138122 -434.304536) (xy 333.138018 -434.289962) (xy 333.138116 -434.275388) (xy 333.139766 -434.246287)
			(xy 333.14132 -434.231796) (xy 333.14132 -433.618894) (xy 333.141807 -433.606781) (xy 333.149293 -433.583741)
			(xy 333.163532 -433.564141) (xy 333.18313 -433.549899) (xy 333.206169 -433.542408) (xy 333.218282 -433.541932)
			(xy 334.158082 -433.541932) (xy 334.170203 -433.542375) (xy 334.19326 -433.549862) (xy 334.212875 -433.564108)
			(xy 334.227127 -433.583718) (xy 334.234621 -433.606773) (xy 334.235044 -433.618894) (xy 334.235044 -434.48986)
			(xy 335.138014 -434.48986) (xy 335.138111 -434.475286) (xy 335.139761 -434.446185) (xy 335.141316 -434.431694)
			(xy 335.141316 -433.34813) (xy 335.139768 -433.333638) (xy 335.138118 -433.304538) (xy 335.138014 -433.289964)
			(xy 335.138112 -433.27539) (xy 335.139761 -433.246289) (xy 335.141316 -433.231798) (xy 335.141316 -432.618896)
			(xy 335.141713 -432.606785) (xy 335.149215 -432.583755) (xy 335.163481 -432.564181) (xy 335.183108 -432.549987)
			(xy 335.206166 -432.542569) (xy 335.218278 -432.542188) (xy 336.158078 -432.542188) (xy 336.170171 -432.542627)
			(xy 336.193179 -432.550084) (xy 336.212764 -432.564276) (xy 336.227013 -432.583818) (xy 336.234537 -432.606804)
			(xy 336.23504 -432.618896) (xy 336.23504 -435.16042) (xy 336.234601 -435.172526) (xy 336.227101 -435.195547)
			(xy 336.212844 -435.215116) (xy 336.19323 -435.229312) (xy 336.170185 -435.236739) (xy 336.158078 -435.237128)
			(xy 335.218278 -435.237128) (xy 335.206184 -435.236711) (xy 335.183177 -435.229244) (xy 335.163595 -435.215046)
			(xy 335.149346 -435.1955) (xy 335.14182 -435.172513) (xy 335.141316 -435.16042) (xy 335.141316 -434.548026)
			(xy 335.139768 -434.533534) (xy 335.138118 -434.504434) (xy 335.138014 -434.48986) (xy 334.235044 -434.48986)
			(xy 334.235044 -435.489858) (xy 337.13801 -435.489858) (xy 337.138107 -435.475284) (xy 337.139757 -435.446183)
			(xy 337.141312 -435.431692) (xy 337.141312 -434.348128) (xy 337.139764 -434.333636) (xy 337.138114 -434.304536)
			(xy 337.13801 -434.289962) (xy 337.138108 -434.275388) (xy 337.139757 -434.246287) (xy 337.141312 -434.231796)
			(xy 337.141312 -433.618894) (xy 337.141806 -433.606782) (xy 337.149292 -433.583743) (xy 337.163529 -433.564143)
			(xy 337.183125 -433.549901) (xy 337.206162 -433.54241) (xy 337.218274 -433.541932) (xy 338.158074 -433.541932)
			(xy 338.170195 -433.542382) (xy 338.193252 -433.549866) (xy 338.212867 -433.56411) (xy 338.227119 -433.58372)
			(xy 338.234613 -433.606773) (xy 338.235036 -433.618894) (xy 338.235036 -434.48986) (xy 339.138006 -434.48986)
			(xy 339.138104 -434.475286) (xy 339.139753 -434.446185) (xy 339.141308 -434.431694) (xy 339.141308 -433.34813)
			(xy 339.13976 -433.333638) (xy 339.13811 -433.304538) (xy 339.138006 -433.289964) (xy 339.138104 -433.27539)
			(xy 339.139753 -433.246289) (xy 339.141308 -433.231798) (xy 339.141308 -432.618896) (xy 339.141713 -432.606786)
			(xy 339.149214 -432.583757) (xy 339.163479 -432.564184) (xy 339.183103 -432.549989) (xy 339.206159 -432.54257)
			(xy 339.21827 -432.542188) (xy 340.15807 -432.542188) (xy 340.170163 -432.542634) (xy 340.19317 -432.550088)
			(xy 340.212755 -432.564278) (xy 340.227005 -432.58382) (xy 340.234529 -432.606805) (xy 340.235032 -432.618896)
			(xy 340.235032 -435.16042) (xy 340.234601 -435.172527) (xy 340.2271 -435.195549) (xy 340.212841 -435.215119)
			(xy 340.193225 -435.229314) (xy 340.170178 -435.23674) (xy 340.15807 -435.237128) (xy 339.21827 -435.237128)
			(xy 339.206176 -435.236718) (xy 339.183169 -435.229249) (xy 339.163586 -435.215049) (xy 339.149338 -435.195502)
			(xy 339.141812 -435.172513) (xy 339.141308 -435.16042) (xy 339.141308 -434.548026) (xy 339.13976 -434.533534)
			(xy 339.13811 -434.504434) (xy 339.138006 -434.48986) (xy 338.235036 -434.48986) (xy 338.235036 -435.489858)
			(xy 341.138002 -435.489858) (xy 341.138099 -435.475284) (xy 341.139749 -435.446183) (xy 341.141304 -435.431692)
			(xy 341.141304 -434.348128) (xy 341.139756 -434.333636) (xy 341.138106 -434.304536) (xy 341.138002 -434.289962)
			(xy 341.1381 -434.275388) (xy 341.139749 -434.246287) (xy 341.141304 -434.231796) (xy 341.141304 -433.618894)
			(xy 341.141806 -433.606783) (xy 341.149291 -433.583745) (xy 341.163526 -433.564146) (xy 341.18312 -433.549904)
			(xy 341.206155 -433.542411) (xy 341.218266 -433.541932) (xy 342.158066 -433.541932) (xy 342.170186 -433.542389)
			(xy 342.193243 -433.549871) (xy 342.212858 -433.564113) (xy 342.227111 -433.583721) (xy 342.234605 -433.606774)
			(xy 342.235028 -433.618894) (xy 342.235028 -434.48986) (xy 343.137998 -434.48986) (xy 343.138096 -434.475286)
			(xy 343.139745 -434.446185) (xy 343.1413 -434.431694) (xy 343.1413 -433.34813) (xy 343.139752 -433.333638)
			(xy 343.138102 -433.304538) (xy 343.137998 -433.289964) (xy 343.138096 -433.27539) (xy 343.139745 -433.246289)
			(xy 343.1413 -433.231798) (xy 343.1413 -432.618896) (xy 343.141713 -432.606787) (xy 343.149213 -432.583759)
			(xy 343.163476 -432.564186) (xy 343.183098 -432.549992) (xy 343.206152 -432.542571) (xy 343.218262 -432.542188)
			(xy 344.158062 -432.542188) (xy 344.170154 -432.542641) (xy 344.193162 -432.550093) (xy 344.212747 -432.564281)
			(xy 344.226997 -432.583821) (xy 344.234521 -432.606805) (xy 344.235024 -432.618896) (xy 344.235024 -435.16042)
			(xy 344.234601 -435.172528) (xy 344.227099 -435.195551) (xy 344.212838 -435.215122) (xy 344.19322 -435.229317)
			(xy 344.170171 -435.236741) (xy 344.158062 -435.237128) (xy 343.218262 -435.237128) (xy 343.206167 -435.236724)
			(xy 343.18316 -435.229253) (xy 343.163578 -435.215052) (xy 343.14933 -435.195503) (xy 343.141804 -435.172514)
			(xy 343.1413 -435.16042) (xy 343.1413 -434.548026) (xy 343.139752 -434.533534) (xy 343.138102 -434.504434)
			(xy 343.137998 -434.48986) (xy 342.235028 -434.48986) (xy 342.235028 -435.489858) (xy 345.137994 -435.489858)
			(xy 345.138091 -435.475284) (xy 345.139741 -435.446183) (xy 345.141296 -435.431692) (xy 345.141296 -434.348128)
			(xy 345.139748 -434.333636) (xy 345.138098 -434.304536) (xy 345.137994 -434.289962) (xy 345.138092 -434.275388)
			(xy 345.139741 -434.246287) (xy 345.141296 -434.231796) (xy 345.141296 -433.618894) (xy 345.141806 -433.606783)
			(xy 345.14929 -433.583747) (xy 345.163524 -433.564149) (xy 345.183115 -433.549906) (xy 345.206148 -433.542412)
			(xy 345.218258 -433.541932) (xy 346.158058 -433.541932) (xy 346.170178 -433.542396) (xy 346.193234 -433.549876)
			(xy 346.21285 -433.564116) (xy 346.227103 -433.583722) (xy 346.234597 -433.606774) (xy 346.23502 -433.618894)
			(xy 346.23502 -436.160418) (xy 346.234654 -436.172546) (xy 346.227152 -436.195612) (xy 346.212888 -436.215231)
			(xy 346.193258 -436.22948) (xy 346.170186 -436.236964) (xy 346.158058 -436.23738) (xy 345.218258 -436.23738)
			(xy 345.206143 -436.236924) (xy 345.183101 -436.229428) (xy 345.163502 -436.215181) (xy 345.149261 -436.195577)
			(xy 345.141772 -436.172533) (xy 345.141296 -436.160418) (xy 345.141296 -435.548024) (xy 345.139748 -435.533532)
			(xy 345.138098 -435.504432) (xy 345.137994 -435.489858) (xy 342.235028 -435.489858) (xy 342.235028 -436.160418)
			(xy 342.234655 -436.172545) (xy 342.227153 -436.19561) (xy 342.212891 -436.215228) (xy 342.193264 -436.229477)
			(xy 342.170193 -436.236963) (xy 342.158066 -436.23738) (xy 341.218266 -436.23738) (xy 341.206151 -436.236918)
			(xy 341.18311 -436.229423) (xy 341.16351 -436.215178) (xy 341.149269 -436.195576) (xy 341.14178 -436.172533)
			(xy 341.141304 -436.160418) (xy 341.141304 -435.548024) (xy 341.139755 -435.533532) (xy 341.138106 -435.504432)
			(xy 341.138002 -435.489858) (xy 338.235036 -435.489858) (xy 338.235036 -436.160418) (xy 338.234655 -436.172544)
			(xy 338.227154 -436.195608) (xy 338.212894 -436.215225) (xy 338.193269 -436.229474) (xy 338.1702 -436.236962)
			(xy 338.158074 -436.23738) (xy 337.218274 -436.23738) (xy 337.20616 -436.236911) (xy 337.183119 -436.229419)
			(xy 337.163519 -436.215175) (xy 337.149278 -436.195574) (xy 337.141788 -436.172532) (xy 337.141312 -436.160418)
			(xy 337.141312 -435.548024) (xy 337.139763 -435.533532) (xy 337.138114 -435.504432) (xy 337.13801 -435.489858)
			(xy 334.235044 -435.489858) (xy 334.235044 -436.160418) (xy 334.234604 -436.172535) (xy 334.227109 -436.195582)
			(xy 334.21286 -436.215185) (xy 334.19325 -436.229426) (xy 334.1702 -436.236909) (xy 334.158082 -436.23738)
			(xy 333.218282 -436.23738) (xy 333.206168 -436.236904) (xy 333.183127 -436.229414) (xy 333.163528 -436.215172)
			(xy 333.149286 -436.195573) (xy 333.141796 -436.172532) (xy 333.14132 -436.160418) (xy 333.14132 -435.548024)
			(xy 333.139771 -435.533532) (xy 333.138122 -435.504432) (xy 333.138018 -435.489858) (xy 329.2348 -435.489858)
			(xy 329.2348 -436.160418) (xy 329.234309 -436.172505) (xy 329.226852 -436.195499) (xy 329.21267 -436.215075)
			(xy 329.193145 -436.229327) (xy 329.170177 -436.236865) (xy 329.158092 -436.23738) (xy 328.218292 -436.23738)
			(xy 328.206181 -436.23699) (xy 328.18315 -436.229486) (xy 328.163575 -436.215219) (xy 328.149381 -436.19559)
			(xy 328.141964 -436.172531) (xy 328.141584 -436.160418) (xy 328.141584 -435.550056) (xy 328.139918 -435.535062)
			(xy 328.138138 -435.504944) (xy 328.138028 -435.489858) (xy 325.234808 -435.489858) (xy 325.234808 -436.160418)
			(xy 325.234309 -436.172504) (xy 325.226853 -436.195497) (xy 325.212673 -436.215072) (xy 325.19315 -436.229324)
			(xy 325.170184 -436.236864) (xy 325.1581 -436.23738) (xy 324.2183 -436.23738) (xy 324.206189 -436.236984)
			(xy 324.183158 -436.229482) (xy 324.163583 -436.215216) (xy 324.14939 -436.195589) (xy 324.141972 -436.17253)
			(xy 324.141592 -436.160418) (xy 324.141592 -435.550056) (xy 324.139926 -435.535062) (xy 324.138146 -435.504944)
			(xy 324.138036 -435.489858) (xy 321.234816 -435.489858) (xy 321.234816 -436.160418) (xy 321.234407 -436.172513)
			(xy 321.22694 -436.195522) (xy 321.21274 -436.215105) (xy 321.193192 -436.229353) (xy 321.170202 -436.236877)
			(xy 321.158108 -436.23738) (xy 320.218308 -436.23738) (xy 320.206198 -436.236977) (xy 320.183167 -436.229477)
			(xy 320.163592 -436.215213) (xy 320.149398 -436.195587) (xy 320.14198 -436.17253) (xy 320.1416 -436.160418)
			(xy 320.1416 -435.550056) (xy 320.139934 -435.535062) (xy 320.138154 -435.504944) (xy 320.138044 -435.489858)
			(xy 317.234824 -435.489858) (xy 317.234824 -436.160418) (xy 317.234407 -436.172512) (xy 317.226941 -436.195519)
			(xy 317.212743 -436.215102) (xy 317.193197 -436.229351) (xy 317.170209 -436.236876) (xy 317.158116 -436.23738)
			(xy 316.218316 -436.23738) (xy 316.206206 -436.23697) (xy 316.183176 -436.229472) (xy 316.163601 -436.21521)
			(xy 316.149406 -436.195585) (xy 316.141989 -436.172529) (xy 316.141608 -436.160418) (xy 316.141608 -435.550056)
			(xy 316.139942 -435.535062) (xy 316.138162 -435.504944) (xy 316.138052 -435.489858) (xy 273.934286 -435.489858)
			(xy 273.867468 -435.573645) (xy 273.750836 -435.707142) (xy 273.628331 -435.835271) (xy 273.500202 -435.957776)
			(xy 273.366705 -436.074408) (xy 273.22811 -436.184934) (xy 273.084696 -436.289131) (xy 272.936752 -436.386788)
			(xy 272.784575 -436.477709) (xy 272.628472 -436.561712) (xy 272.468758 -436.638626) (xy 272.305753 -436.708298)
			(xy 272.139788 -436.770586) (xy 271.971194 -436.825365) (xy 271.800313 -436.872525) (xy 271.627488 -436.911971)
			(xy 271.453067 -436.943624) (xy 271.277402 -436.967419) (xy 271.100846 -436.98331) (xy 270.923755 -436.991263)
			(xy 270.746485 -436.991263) (xy 270.569394 -436.98331) (xy 270.392838 -436.967419) (xy 270.217173 -436.943624)
			(xy 270.042752 -436.911971) (xy 269.869927 -436.872525) (xy 269.699046 -436.825365) (xy 269.530452 -436.770586)
			(xy 269.364487 -436.708298) (xy 269.201482 -436.638626) (xy 269.041768 -436.561712) (xy 268.885665 -436.477709)
			(xy 268.733488 -436.386788) (xy 268.585544 -436.289131) (xy 268.44213 -436.184934) (xy 268.303535 -436.074408)
			(xy 268.170038 -435.957776) (xy 268.041909 -435.835271) (xy 267.919404 -435.707142) (xy 267.802772 -435.573645)
			(xy 267.692246 -435.43505) (xy 267.588049 -435.291636) (xy 267.490392 -435.143692) (xy 267.399471 -434.991515)
			(xy 267.315468 -434.835412) (xy 267.238554 -434.675698) (xy 267.168882 -434.512693) (xy 267.106594 -434.346728)
			(xy 267.051815 -434.178134) (xy 267.004655 -434.007253) (xy 266.965209 -433.834428) (xy 266.933556 -433.660007)
			(xy 266.909761 -433.484342) (xy 266.89387 -433.307786) (xy 266.885917 -433.130695) (xy 231.01554 -433.130695)
			(xy 231.01554 -435.063392) (xy 231.015024 -435.08834) (xy 231.007214 -435.137622) (xy 230.991802 -435.185079)
			(xy 230.969165 -435.229545) (xy 230.939859 -435.269929) (xy 230.922576 -435.287928) (xy 229.133908 -437.076596)
			(xy 229.115913 -437.093886) (xy 229.075537 -437.12321) (xy 229.031071 -437.145858) (xy 228.98361 -437.161272)
			(xy 228.934323 -437.169073) (xy 228.909372 -437.16956) (xy 207.503268 -437.16956) (xy 207.478319 -437.169063)
			(xy 207.429037 -437.161248) (xy 207.38158 -437.14583) (xy 207.337114 -437.123189) (xy 207.296731 -437.09388)
			(xy 207.278732 -437.076596) (xy 205.949804 -435.747668) (xy 205.932495 -435.72969) (xy 205.903173 -435.68931)
			(xy 205.880529 -435.64484) (xy 205.865119 -435.597375) (xy 205.857324 -435.548084) (xy 205.85684 -435.523132)
			(xy 205.85684 -429.817784) (xy 197.285356 -421.2463) (xy 192.73774 -421.2463) (xy 192.712789 -421.245838)
			(xy 192.663505 -421.238017) (xy 192.616047 -421.222592) (xy 192.571582 -421.199943) (xy 192.531201 -421.170625)
			(xy 192.513204 -421.153336) (xy 184.804304 -413.444436) (xy 184.802526 -413.443166) (xy 184.785091 -413.427985)
			(xy 184.754335 -413.393473) (xy 184.728914 -413.354862) (xy 184.709364 -413.312972) (xy 184.696099 -413.268688)
			(xy 184.689401 -413.222948) (xy 184.688988 -413.199834) (xy 184.688988 -408.491182) (xy 184.68948 -408.466233)
			(xy 184.697294 -408.416949) (xy 184.712712 -408.369492) (xy 184.735355 -408.325026) (xy 184.764667 -408.284644)
			(xy 184.781952 -408.266646) (xy 184.892188 -408.15641) (xy 184.892188 -407.290778) (xy 184.874462 -407.269826)
			(xy 184.844586 -407.223792) (xy 184.821621 -407.173948) (xy 184.806044 -407.121325) (xy 184.798176 -407.067012)
			(xy 184.7977 -407.039572) (xy 184.798716 -407.01341) (xy 184.80024 -406.99055) (xy 184.654952 -406.845262)
			(xy 184.637629 -406.827296) (xy 184.608302 -406.786914) (xy 184.585654 -406.742442) (xy 184.570242 -406.694974)
			(xy 184.562446 -406.64568) (xy 184.561988 -406.620726) (xy 16.741648 -406.620726) (xy 16.741648 -407.031753)
			(xy 48.944975 -407.031753) (xy 48.944975 -406.977247) (xy 48.952733 -406.923295) (xy 48.96809 -406.870997)
			(xy 48.990734 -406.821417) (xy 49.020204 -406.775565) (xy 49.0559 -406.734373) (xy 49.097095 -406.698681)
			(xy 49.142951 -406.669216) (xy 49.192533 -406.646577) (xy 49.244833 -406.631225) (xy 49.298785 -406.623473)
			(xy 49.326038 -406.623012) (xy 50.189638 -406.623012) (xy 50.216889 -406.62346) (xy 50.270835 -406.631222)
			(xy 50.323128 -406.646581) (xy 50.372703 -406.669225) (xy 50.418551 -406.698694) (xy 50.459739 -406.734388)
			(xy 50.495428 -406.775579) (xy 50.524893 -406.82143) (xy 50.547532 -406.871007) (xy 50.562886 -406.923302)
			(xy 50.570642 -406.977249) (xy 50.570642 -407.031749) (xy 52.008298 -407.031749) (xy 52.008298 -406.977251)
			(xy 52.016054 -406.923308) (xy 52.031407 -406.871018) (xy 52.054045 -406.821445) (xy 52.083508 -406.775598)
			(xy 52.119195 -406.734411) (xy 52.16038 -406.698721) (xy 52.206226 -406.669256) (xy 52.255797 -406.646615)
			(xy 52.308087 -406.631258) (xy 52.362029 -406.6235) (xy 52.389278 -406.623012) (xy 53.252878 -406.623012)
			(xy 53.280133 -406.623433) (xy 53.33409 -406.631188) (xy 53.386393 -406.646543) (xy 53.435978 -406.669186)
			(xy 53.481837 -406.698655) (xy 53.523034 -406.73435) (xy 53.558732 -406.775546) (xy 53.588204 -406.821402)
			(xy 53.610849 -406.870987) (xy 53.626207 -406.923289) (xy 53.633965 -406.977245) (xy 53.633965 -407.031752)
			(xy 55.071475 -407.031752) (xy 55.071475 -406.977248) (xy 55.079232 -406.923298) (xy 55.094589 -406.871002)
			(xy 55.117231 -406.821423) (xy 55.146699 -406.775571) (xy 55.182393 -406.73438) (xy 55.223586 -406.698688)
			(xy 55.269439 -406.669222) (xy 55.319018 -406.646582) (xy 55.371316 -406.631229) (xy 55.425266 -406.623474)
			(xy 55.452518 -406.623012) (xy 56.316118 -406.623012) (xy 56.34337 -406.623459) (xy 56.397318 -406.631218)
			(xy 56.449614 -406.646576) (xy 56.499191 -406.669219) (xy 56.545042 -406.698687) (xy 56.586232 -406.734381)
			(xy 56.621924 -406.775573) (xy 56.65139 -406.821424) (xy 56.674031 -406.871003) (xy 56.689386 -406.923299)
			(xy 56.697142 -406.977248) (xy 56.697142 -407.031748) (xy 58.134798 -407.031748) (xy 58.134798 -406.977252)
			(xy 58.142553 -406.923311) (xy 58.157905 -406.871022) (xy 58.180542 -406.821451) (xy 58.210003 -406.775605)
			(xy 58.245688 -406.734418) (xy 58.286871 -406.698728) (xy 58.332714 -406.669262) (xy 58.382283 -406.64662)
			(xy 58.43457 -406.631262) (xy 58.48851 -406.623501) (xy 58.515758 -406.623012) (xy 59.379358 -406.623012)
			(xy 59.406614 -406.623432) (xy 59.460573 -406.631185) (xy 59.512878 -406.646538) (xy 59.562466 -406.669179)
			(xy 59.608327 -406.698648) (xy 59.649527 -406.734343) (xy 59.685227 -406.775539) (xy 59.714701 -406.821397)
			(xy 59.737348 -406.870982) (xy 59.752707 -406.923286) (xy 59.760465 -406.977244) (xy 59.760465 -407.03175)
			(xy 61.197998 -407.03175) (xy 61.197998 -406.97725) (xy 61.205754 -406.923306) (xy 61.221108 -406.871014)
			(xy 61.243748 -406.821439) (xy 61.273213 -406.775592) (xy 61.308902 -406.734404) (xy 61.35009 -406.698714)
			(xy 61.395938 -406.669249) (xy 61.445512 -406.646609) (xy 61.497804 -406.631255) (xy 61.551748 -406.623498)
			(xy 61.578998 -406.623012) (xy 62.442598 -406.623012) (xy 62.469852 -406.623435) (xy 62.523806 -406.631192)
			(xy 62.576107 -406.646549) (xy 62.62569 -406.669192) (xy 62.671546 -406.698662) (xy 62.712741 -406.734357)
			(xy 62.748437 -406.775552) (xy 62.777907 -406.821408) (xy 62.800551 -406.870991) (xy 62.815908 -406.923292)
			(xy 62.823665 -406.977246) (xy 62.823665 -407.031753) (xy 64.261175 -407.031753) (xy 64.261175 -406.977247)
			(xy 64.268933 -406.923295) (xy 64.28429 -406.870997) (xy 64.306934 -406.821417) (xy 64.336404 -406.775565)
			(xy 64.3721 -406.734373) (xy 64.413295 -406.698681) (xy 64.459151 -406.669216) (xy 64.508733 -406.646577)
			(xy 64.561033 -406.631225) (xy 64.614985 -406.623473) (xy 64.642238 -406.623012) (xy 65.505838 -406.623012)
			(xy 65.533089 -406.62346) (xy 65.587035 -406.631222) (xy 65.639328 -406.646581) (xy 65.688903 -406.669225)
			(xy 65.734751 -406.698694) (xy 65.775939 -406.734388) (xy 65.811628 -406.775579) (xy 65.841093 -406.82143)
			(xy 65.863732 -406.871007) (xy 65.879086 -406.923302) (xy 65.886842 -406.977249) (xy 65.886842 -407.031749)
			(xy 67.324498 -407.031749) (xy 67.324498 -406.977251) (xy 67.332254 -406.923308) (xy 67.347607 -406.871018)
			(xy 67.370245 -406.821445) (xy 67.399708 -406.775598) (xy 67.435395 -406.734411) (xy 67.47658 -406.698721)
			(xy 67.522426 -406.669256) (xy 67.571997 -406.646615) (xy 67.624287 -406.631258) (xy 67.678229 -406.6235)
			(xy 67.705478 -406.623012) (xy 68.569078 -406.623012) (xy 68.596333 -406.623433) (xy 68.65029 -406.631188)
			(xy 68.702593 -406.646543) (xy 68.752178 -406.669186) (xy 68.798037 -406.698655) (xy 68.839234 -406.73435)
			(xy 68.874932 -406.775546) (xy 68.904404 -406.821402) (xy 68.927049 -406.870987) (xy 68.942407 -406.923289)
			(xy 68.950165 -406.977245) (xy 68.950165 -407.031752) (xy 70.387675 -407.031752) (xy 70.387675 -406.977248)
			(xy 70.395432 -406.923298) (xy 70.410789 -406.871002) (xy 70.433431 -406.821423) (xy 70.462899 -406.775571)
			(xy 70.498593 -406.73438) (xy 70.539786 -406.698688) (xy 70.585639 -406.669222) (xy 70.635218 -406.646582)
			(xy 70.687516 -406.631229) (xy 70.741466 -406.623474) (xy 70.768718 -406.623012) (xy 71.632318 -406.623012)
			(xy 71.65957 -406.623459) (xy 71.713518 -406.631218) (xy 71.765814 -406.646576) (xy 71.815391 -406.669219)
			(xy 71.861242 -406.698687) (xy 71.902432 -406.734381) (xy 71.938124 -406.775573) (xy 71.96759 -406.821424)
			(xy 71.990231 -406.871003) (xy 72.005586 -406.923299) (xy 72.013342 -406.977248) (xy 72.013342 -407.031748)
			(xy 73.450998 -407.031748) (xy 73.450998 -406.977252) (xy 73.458753 -406.923311) (xy 73.474105 -406.871022)
			(xy 73.496742 -406.821451) (xy 73.526203 -406.775605) (xy 73.561888 -406.734418) (xy 73.603071 -406.698728)
			(xy 73.648914 -406.669262) (xy 73.698483 -406.64662) (xy 73.75077 -406.631262) (xy 73.80471 -406.623501)
			(xy 73.831958 -406.623012) (xy 74.695558 -406.623012) (xy 74.722814 -406.623432) (xy 74.776773 -406.631185)
			(xy 74.829078 -406.646538) (xy 74.878666 -406.669179) (xy 74.924527 -406.698648) (xy 74.965727 -406.734343)
			(xy 75.001427 -406.775539) (xy 75.030901 -406.821397) (xy 75.053548 -406.870982) (xy 75.068907 -406.923286)
			(xy 75.076665 -406.977244) (xy 75.076665 -407.03175) (xy 76.514198 -407.03175) (xy 76.514198 -406.97725)
			(xy 76.521954 -406.923306) (xy 76.537308 -406.871014) (xy 76.559948 -406.821439) (xy 76.589413 -406.775592)
			(xy 76.625102 -406.734404) (xy 76.66629 -406.698714) (xy 76.712138 -406.669249) (xy 76.761712 -406.646609)
			(xy 76.814004 -406.631255) (xy 76.867948 -406.623498) (xy 76.895198 -406.623012) (xy 77.758798 -406.623012)
			(xy 77.786052 -406.623435) (xy 77.840006 -406.631192) (xy 77.892307 -406.646549) (xy 77.94189 -406.669192)
			(xy 77.987746 -406.698662) (xy 78.028941 -406.734357) (xy 78.064637 -406.775552) (xy 78.094107 -406.821408)
			(xy 78.116751 -406.870991) (xy 78.132108 -406.923292) (xy 78.139865 -406.977246) (xy 78.139865 -407.031753)
			(xy 79.577375 -407.031753) (xy 79.577375 -406.977247) (xy 79.585133 -406.923295) (xy 79.60049 -406.870997)
			(xy 79.623134 -406.821417) (xy 79.652604 -406.775565) (xy 79.6883 -406.734373) (xy 79.729495 -406.698681)
			(xy 79.775351 -406.669216) (xy 79.824933 -406.646577) (xy 79.877233 -406.631225) (xy 79.931185 -406.623473)
			(xy 79.958438 -406.623012) (xy 80.822038 -406.623012) (xy 80.849289 -406.62346) (xy 80.903235 -406.631222)
			(xy 80.955528 -406.646581) (xy 81.005103 -406.669225) (xy 81.050951 -406.698694) (xy 81.092139 -406.734388)
			(xy 81.127828 -406.775579) (xy 81.157293 -406.82143) (xy 81.179932 -406.871007) (xy 81.195286 -406.923302)
			(xy 81.203042 -406.977249) (xy 81.203042 -407.031749) (xy 82.640698 -407.031749) (xy 82.640698 -406.977251)
			(xy 82.648454 -406.923308) (xy 82.663807 -406.871018) (xy 82.686445 -406.821445) (xy 82.715908 -406.775598)
			(xy 82.751595 -406.734411) (xy 82.79278 -406.698721) (xy 82.838626 -406.669256) (xy 82.888197 -406.646615)
			(xy 82.940487 -406.631258) (xy 82.994429 -406.6235) (xy 83.021678 -406.623012) (xy 83.885278 -406.623012)
			(xy 83.912533 -406.623433) (xy 83.96649 -406.631188) (xy 84.018793 -406.646543) (xy 84.068378 -406.669186)
			(xy 84.114237 -406.698655) (xy 84.155434 -406.73435) (xy 84.191132 -406.775546) (xy 84.220604 -406.821402)
			(xy 84.243249 -406.870987) (xy 84.258607 -406.923289) (xy 84.266365 -406.977245) (xy 84.266365 -407.031752)
			(xy 85.703875 -407.031752) (xy 85.703875 -406.977248) (xy 85.711632 -406.923298) (xy 85.726989 -406.871002)
			(xy 85.749631 -406.821423) (xy 85.779099 -406.775571) (xy 85.814793 -406.73438) (xy 85.855986 -406.698688)
			(xy 85.901839 -406.669222) (xy 85.951418 -406.646582) (xy 86.003716 -406.631229) (xy 86.057666 -406.623474)
			(xy 86.084918 -406.623012) (xy 86.948518 -406.623012) (xy 86.97577 -406.623459) (xy 87.029718 -406.631218)
			(xy 87.082014 -406.646576) (xy 87.131591 -406.669219) (xy 87.177442 -406.698687) (xy 87.218632 -406.734381)
			(xy 87.254324 -406.775573) (xy 87.28379 -406.821424) (xy 87.306431 -406.871003) (xy 87.321786 -406.923299)
			(xy 87.329542 -406.977248) (xy 87.329542 -407.031748) (xy 88.767198 -407.031748) (xy 88.767198 -406.977252)
			(xy 88.774953 -406.923311) (xy 88.790305 -406.871022) (xy 88.812942 -406.821451) (xy 88.842403 -406.775605)
			(xy 88.878088 -406.734418) (xy 88.919271 -406.698728) (xy 88.965114 -406.669262) (xy 89.014683 -406.64662)
			(xy 89.06697 -406.631262) (xy 89.12091 -406.623501) (xy 89.148158 -406.623012) (xy 90.011758 -406.623012)
			(xy 90.039014 -406.623432) (xy 90.092973 -406.631185) (xy 90.145278 -406.646538) (xy 90.194866 -406.669179)
			(xy 90.240727 -406.698648) (xy 90.281927 -406.734343) (xy 90.317627 -406.775539) (xy 90.347101 -406.821397)
			(xy 90.369748 -406.870982) (xy 90.385107 -406.923286) (xy 90.392865 -406.977244) (xy 90.392865 -407.03175)
			(xy 91.830398 -407.03175) (xy 91.830398 -406.97725) (xy 91.838154 -406.923306) (xy 91.853508 -406.871014)
			(xy 91.876148 -406.821439) (xy 91.905613 -406.775592) (xy 91.941302 -406.734404) (xy 91.98249 -406.698714)
			(xy 92.028338 -406.669249) (xy 92.077912 -406.646609) (xy 92.130204 -406.631255) (xy 92.184148 -406.623498)
			(xy 92.211398 -406.623012) (xy 93.074998 -406.623012) (xy 93.102252 -406.623435) (xy 93.156206 -406.631192)
			(xy 93.208507 -406.646549) (xy 93.25809 -406.669192) (xy 93.303946 -406.698662) (xy 93.345141 -406.734357)
			(xy 93.380837 -406.775552) (xy 93.410307 -406.821408) (xy 93.432951 -406.870991) (xy 93.448308 -406.923292)
			(xy 93.456065 -406.977246) (xy 93.456065 -407.031753) (xy 94.893575 -407.031753) (xy 94.893575 -406.977247)
			(xy 94.901333 -406.923295) (xy 94.91669 -406.870997) (xy 94.939334 -406.821417) (xy 94.968804 -406.775565)
			(xy 95.0045 -406.734373) (xy 95.045695 -406.698681) (xy 95.091551 -406.669216) (xy 95.141133 -406.646577)
			(xy 95.193433 -406.631225) (xy 95.247385 -406.623473) (xy 95.274638 -406.623012) (xy 96.138238 -406.623012)
			(xy 96.165489 -406.62346) (xy 96.219435 -406.631222) (xy 96.271728 -406.646581) (xy 96.321303 -406.669225)
			(xy 96.367151 -406.698694) (xy 96.408339 -406.734388) (xy 96.444028 -406.775579) (xy 96.473493 -406.82143)
			(xy 96.496132 -406.871007) (xy 96.511486 -406.923302) (xy 96.519242 -406.977249) (xy 96.519242 -407.031751)
			(xy 96.511486 -407.085698) (xy 96.496132 -407.137993) (xy 96.495694 -407.138953) (xy 106.243063 -407.138953)
			(xy 106.243063 -407.084447) (xy 106.250821 -407.030495) (xy 106.266177 -406.978197) (xy 106.288821 -406.928617)
			(xy 106.31829 -406.882763) (xy 106.353985 -406.841571) (xy 106.395179 -406.805878) (xy 106.441034 -406.776411)
			(xy 106.490616 -406.75377) (xy 106.542915 -406.738416) (xy 106.596867 -406.730662) (xy 106.62412 -406.7302)
			(xy 107.48772 -406.7302) (xy 107.514971 -406.730671) (xy 107.568918 -406.73843) (xy 107.621211 -406.753787)
			(xy 107.670787 -406.77643) (xy 107.716636 -406.805898) (xy 107.757824 -406.84159) (xy 107.793514 -406.88278)
			(xy 107.82298 -406.928631) (xy 107.84562 -406.978208) (xy 107.860974 -407.030502) (xy 107.861153 -407.031748)
			(xy 121.120198 -407.031748) (xy 121.120198 -406.977252) (xy 121.127953 -406.923312) (xy 121.143305 -406.871023)
			(xy 121.165942 -406.821452) (xy 121.195402 -406.775606) (xy 121.231087 -406.734419) (xy 121.272269 -406.69873)
			(xy 121.318111 -406.669264) (xy 121.36768 -406.646621) (xy 121.419967 -406.631263) (xy 121.473906 -406.623501)
			(xy 121.501154 -406.623012) (xy 122.364754 -406.623012) (xy 122.39201 -406.623432) (xy 122.445969 -406.631184)
			(xy 122.498275 -406.646537) (xy 122.547864 -406.669178) (xy 122.593725 -406.698646) (xy 122.634926 -406.734342)
			(xy 122.670626 -406.775538) (xy 122.7001 -406.821396) (xy 122.722747 -406.870981) (xy 122.738106 -406.923286)
			(xy 122.745865 -406.977244) (xy 122.745865 -407.03175) (xy 124.183398 -407.03175) (xy 124.183398 -406.97725)
			(xy 124.191154 -406.923306) (xy 124.206508 -406.871015) (xy 124.229148 -406.821441) (xy 124.258612 -406.775593)
			(xy 124.294301 -406.734405) (xy 124.335488 -406.698715) (xy 124.381335 -406.669251) (xy 124.430909 -406.64661)
			(xy 124.4832 -406.631255) (xy 124.537144 -406.623499) (xy 124.564394 -406.623012) (xy 125.427994 -406.623012)
			(xy 125.455249 -406.623434) (xy 125.509203 -406.631191) (xy 125.561504 -406.646548) (xy 125.611088 -406.669191)
			(xy 125.656944 -406.69866) (xy 125.69814 -406.734356) (xy 125.733836 -406.775551) (xy 125.763306 -406.821407)
			(xy 125.78595 -406.87099) (xy 125.801308 -406.923291) (xy 125.809065 -406.977245) (xy 125.809065 -407.031753)
			(xy 127.246575 -407.031753) (xy 127.246575 -406.977247) (xy 127.254333 -406.923296) (xy 127.26969 -406.870998)
			(xy 127.292334 -406.821418) (xy 127.321803 -406.775566) (xy 127.357499 -406.734375) (xy 127.398693 -406.698683)
			(xy 127.444548 -406.669217) (xy 127.49413 -406.646578) (xy 127.546429 -406.631226) (xy 127.600381 -406.623473)
			(xy 127.627634 -406.623012) (xy 128.491234 -406.623012) (xy 128.518485 -406.62346) (xy 128.572432 -406.631221)
			(xy 128.624725 -406.64658) (xy 128.674301 -406.669224) (xy 128.720149 -406.698693) (xy 128.761338 -406.734386)
			(xy 128.797028 -406.775578) (xy 128.826492 -406.821429) (xy 128.849132 -406.871007) (xy 128.864486 -406.923301)
			(xy 128.872242 -406.977249) (xy 128.872242 -407.031749) (xy 130.309898 -407.031749) (xy 130.309898 -406.977251)
			(xy 130.317654 -406.923309) (xy 130.333007 -406.871019) (xy 130.355645 -406.821446) (xy 130.385107 -406.775599)
			(xy 130.420794 -406.734412) (xy 130.461979 -406.698722) (xy 130.507823 -406.669257) (xy 130.557395 -406.646616)
			(xy 130.609683 -406.631259) (xy 130.663625 -406.6235) (xy 130.690874 -406.623012) (xy 131.554474 -406.623012)
			(xy 131.58173 -406.623433) (xy 131.635686 -406.631187) (xy 131.68799 -406.646542) (xy 131.737576 -406.669184)
			(xy 131.783435 -406.698653) (xy 131.824633 -406.734349) (xy 131.860331 -406.775544) (xy 131.889803 -406.821401)
			(xy 131.912449 -406.870986) (xy 131.927807 -406.923288) (xy 131.935565 -406.977245) (xy 131.935565 -407.031752)
			(xy 133.373075 -407.031752) (xy 133.373075 -406.977248) (xy 133.380832 -406.923299) (xy 133.396188 -406.871002)
			(xy 133.418831 -406.821424) (xy 133.448298 -406.775573) (xy 133.483992 -406.734382) (xy 133.525184 -406.69869)
			(xy 133.571036 -406.669224) (xy 133.620616 -406.646583) (xy 133.672912 -406.631229) (xy 133.726862 -406.623474)
			(xy 133.754114 -406.623012) (xy 134.617714 -406.623012) (xy 134.644966 -406.623459) (xy 134.698915 -406.631217)
			(xy 134.751211 -406.646574) (xy 134.800789 -406.669218) (xy 134.84664 -406.698686) (xy 134.887831 -406.734379)
			(xy 134.923523 -406.775571) (xy 134.952989 -406.821423) (xy 134.97563 -406.871002) (xy 134.990986 -406.923299)
			(xy 134.998742 -406.977248) (xy 134.998742 -407.031748) (xy 136.436398 -407.031748) (xy 136.436398 -406.977252)
			(xy 136.444153 -406.923312) (xy 136.459505 -406.871023) (xy 136.482142 -406.821452) (xy 136.511602 -406.775606)
			(xy 136.547287 -406.734419) (xy 136.588469 -406.69873) (xy 136.634311 -406.669264) (xy 136.68388 -406.646621)
			(xy 136.736167 -406.631263) (xy 136.790106 -406.623501) (xy 136.817354 -406.623012) (xy 137.680954 -406.623012)
			(xy 137.70821 -406.623432) (xy 137.762169 -406.631184) (xy 137.814475 -406.646537) (xy 137.864064 -406.669178)
			(xy 137.909925 -406.698646) (xy 137.951126 -406.734342) (xy 137.986826 -406.775538) (xy 138.0163 -406.821396)
			(xy 138.038947 -406.870981) (xy 138.054306 -406.923286) (xy 138.062065 -406.977244) (xy 138.062065 -407.03175)
			(xy 139.499598 -407.03175) (xy 139.499598 -406.97725) (xy 139.507354 -406.923306) (xy 139.522708 -406.871015)
			(xy 139.545348 -406.821441) (xy 139.574812 -406.775593) (xy 139.610501 -406.734405) (xy 139.651688 -406.698715)
			(xy 139.697535 -406.669251) (xy 139.747109 -406.64661) (xy 139.7994 -406.631255) (xy 139.853344 -406.623499)
			(xy 139.880594 -406.623012) (xy 140.744194 -406.623012) (xy 140.771449 -406.623434) (xy 140.825403 -406.631191)
			(xy 140.877704 -406.646548) (xy 140.927288 -406.669191) (xy 140.973144 -406.69866) (xy 141.01434 -406.734356)
			(xy 141.050036 -406.775551) (xy 141.079506 -406.821407) (xy 141.10215 -406.87099) (xy 141.117508 -406.923291)
			(xy 141.125265 -406.977245) (xy 141.125265 -407.031753) (xy 142.562775 -407.031753) (xy 142.562775 -406.977247)
			(xy 142.570533 -406.923296) (xy 142.58589 -406.870998) (xy 142.608534 -406.821418) (xy 142.638003 -406.775566)
			(xy 142.673699 -406.734375) (xy 142.714893 -406.698683) (xy 142.760748 -406.669217) (xy 142.81033 -406.646578)
			(xy 142.862629 -406.631226) (xy 142.916581 -406.623473) (xy 142.943834 -406.623012) (xy 143.807434 -406.623012)
			(xy 143.834685 -406.62346) (xy 143.888632 -406.631221) (xy 143.940925 -406.64658) (xy 143.990501 -406.669224)
			(xy 144.036349 -406.698693) (xy 144.077538 -406.734386) (xy 144.113228 -406.775578) (xy 144.142692 -406.821429)
			(xy 144.165332 -406.871007) (xy 144.180686 -406.923301) (xy 144.188442 -406.977249) (xy 144.188442 -407.031749)
			(xy 145.626098 -407.031749) (xy 145.626098 -406.977251) (xy 145.633854 -406.923309) (xy 145.649207 -406.871019)
			(xy 145.671845 -406.821446) (xy 145.701307 -406.775599) (xy 145.736994 -406.734412) (xy 145.778179 -406.698722)
			(xy 145.824023 -406.669257) (xy 145.873595 -406.646616) (xy 145.925883 -406.631259) (xy 145.979825 -406.6235)
			(xy 146.007074 -406.623012) (xy 146.870674 -406.623012) (xy 146.89793 -406.623433) (xy 146.951886 -406.631187)
			(xy 147.00419 -406.646542) (xy 147.053776 -406.669184) (xy 147.099635 -406.698653) (xy 147.140833 -406.734349)
			(xy 147.176531 -406.775544) (xy 147.206003 -406.821401) (xy 147.228649 -406.870986) (xy 147.244007 -406.923288)
			(xy 147.251765 -406.977245) (xy 147.251765 -407.031752) (xy 148.689275 -407.031752) (xy 148.689275 -406.977248)
			(xy 148.697032 -406.923299) (xy 148.712388 -406.871002) (xy 148.735031 -406.821424) (xy 148.764498 -406.775573)
			(xy 148.800192 -406.734382) (xy 148.841384 -406.69869) (xy 148.887236 -406.669224) (xy 148.936816 -406.646583)
			(xy 148.989112 -406.631229) (xy 149.043062 -406.623474) (xy 149.070314 -406.623012) (xy 149.933914 -406.623012)
			(xy 149.961166 -406.623459) (xy 150.015115 -406.631217) (xy 150.067411 -406.646574) (xy 150.116989 -406.669218)
			(xy 150.16284 -406.698686) (xy 150.204031 -406.734379) (xy 150.239723 -406.775571) (xy 150.269189 -406.821423)
			(xy 150.29183 -406.871002) (xy 150.307186 -406.923299) (xy 150.314942 -406.977248) (xy 150.314942 -407.031748)
			(xy 151.752598 -407.031748) (xy 151.752598 -406.977252) (xy 151.760353 -406.923312) (xy 151.775705 -406.871023)
			(xy 151.798342 -406.821452) (xy 151.827802 -406.775606) (xy 151.863487 -406.734419) (xy 151.904669 -406.69873)
			(xy 151.950511 -406.669264) (xy 152.00008 -406.646621) (xy 152.052367 -406.631263) (xy 152.106306 -406.623501)
			(xy 152.133554 -406.623012) (xy 152.997154 -406.623012) (xy 153.02441 -406.623432) (xy 153.078369 -406.631184)
			(xy 153.130675 -406.646537) (xy 153.180264 -406.669178) (xy 153.226125 -406.698646) (xy 153.267326 -406.734342)
			(xy 153.303026 -406.775538) (xy 153.3325 -406.821396) (xy 153.355147 -406.870981) (xy 153.370506 -406.923286)
			(xy 153.378265 -406.977244) (xy 153.378265 -407.03175) (xy 154.815798 -407.03175) (xy 154.815798 -406.97725)
			(xy 154.823554 -406.923306) (xy 154.838908 -406.871015) (xy 154.861548 -406.821441) (xy 154.891012 -406.775593)
			(xy 154.926701 -406.734405) (xy 154.967888 -406.698715) (xy 155.013735 -406.669251) (xy 155.063309 -406.64661)
			(xy 155.1156 -406.631255) (xy 155.169544 -406.623499) (xy 155.196794 -406.623012) (xy 156.060394 -406.623012)
			(xy 156.087649 -406.623434) (xy 156.141603 -406.631191) (xy 156.193904 -406.646548) (xy 156.243488 -406.669191)
			(xy 156.289344 -406.69866) (xy 156.33054 -406.734356) (xy 156.366236 -406.775551) (xy 156.395706 -406.821407)
			(xy 156.41835 -406.87099) (xy 156.433708 -406.923291) (xy 156.441465 -406.977245) (xy 156.441465 -407.031753)
			(xy 157.878975 -407.031753) (xy 157.878975 -406.977247) (xy 157.886733 -406.923296) (xy 157.90209 -406.870998)
			(xy 157.924734 -406.821418) (xy 157.954203 -406.775566) (xy 157.989899 -406.734375) (xy 158.031093 -406.698683)
			(xy 158.076948 -406.669217) (xy 158.12653 -406.646578) (xy 158.178829 -406.631226) (xy 158.232781 -406.623473)
			(xy 158.260034 -406.623012) (xy 159.123634 -406.623012) (xy 159.150885 -406.62346) (xy 159.204832 -406.631221)
			(xy 159.257125 -406.64658) (xy 159.306701 -406.669224) (xy 159.352549 -406.698693) (xy 159.393738 -406.734386)
			(xy 159.429428 -406.775578) (xy 159.458892 -406.821429) (xy 159.481532 -406.871007) (xy 159.496886 -406.923301)
			(xy 159.504642 -406.977249) (xy 159.504642 -407.031749) (xy 160.942298 -407.031749) (xy 160.942298 -406.977251)
			(xy 160.950054 -406.923309) (xy 160.965407 -406.871019) (xy 160.988045 -406.821446) (xy 161.017507 -406.775599)
			(xy 161.053194 -406.734412) (xy 161.094379 -406.698722) (xy 161.140223 -406.669257) (xy 161.189795 -406.646616)
			(xy 161.242083 -406.631259) (xy 161.296025 -406.6235) (xy 161.323274 -406.623012) (xy 162.186874 -406.623012)
			(xy 162.21413 -406.623433) (xy 162.268086 -406.631187) (xy 162.32039 -406.646542) (xy 162.369976 -406.669184)
			(xy 162.415835 -406.698653) (xy 162.457033 -406.734349) (xy 162.492731 -406.775544) (xy 162.522203 -406.821401)
			(xy 162.544849 -406.870986) (xy 162.560207 -406.923288) (xy 162.567965 -406.977245) (xy 162.567965 -407.031752)
			(xy 164.005475 -407.031752) (xy 164.005475 -406.977248) (xy 164.013232 -406.923299) (xy 164.028588 -406.871002)
			(xy 164.051231 -406.821424) (xy 164.080698 -406.775573) (xy 164.116392 -406.734382) (xy 164.157584 -406.69869)
			(xy 164.203436 -406.669224) (xy 164.253016 -406.646583) (xy 164.305312 -406.631229) (xy 164.359262 -406.623474)
			(xy 164.386514 -406.623012) (xy 165.250114 -406.623012) (xy 165.277366 -406.623459) (xy 165.331315 -406.631217)
			(xy 165.383611 -406.646574) (xy 165.433189 -406.669218) (xy 165.47904 -406.698686) (xy 165.520231 -406.734379)
			(xy 165.555923 -406.775571) (xy 165.585389 -406.821423) (xy 165.60803 -406.871002) (xy 165.623386 -406.923299)
			(xy 165.631142 -406.977248) (xy 165.631142 -407.031748) (xy 167.068798 -407.031748) (xy 167.068798 -406.977252)
			(xy 167.076553 -406.923312) (xy 167.091905 -406.871023) (xy 167.114542 -406.821452) (xy 167.144002 -406.775606)
			(xy 167.179687 -406.734419) (xy 167.220869 -406.69873) (xy 167.266711 -406.669264) (xy 167.31628 -406.646621)
			(xy 167.368567 -406.631263) (xy 167.422506 -406.623501) (xy 167.449754 -406.623012) (xy 168.313354 -406.623012)
			(xy 168.34061 -406.623432) (xy 168.394569 -406.631184) (xy 168.446875 -406.646537) (xy 168.496464 -406.669178)
			(xy 168.542325 -406.698646) (xy 168.583526 -406.734342) (xy 168.619226 -406.775538) (xy 168.6487 -406.821396)
			(xy 168.671347 -406.870981) (xy 168.686706 -406.923286) (xy 168.694465 -406.977244) (xy 168.694465 -407.031756)
			(xy 168.686706 -407.085714) (xy 168.671347 -407.138019) (xy 168.6487 -407.187604) (xy 168.619226 -407.233462)
			(xy 168.583526 -407.274658) (xy 168.542325 -407.310354) (xy 168.496464 -407.339822) (xy 168.446875 -407.362463)
			(xy 168.394569 -407.377816) (xy 168.34061 -407.385568) (xy 168.313354 -407.386028) (xy 167.449754 -407.386028)
			(xy 167.422506 -407.385499) (xy 167.368567 -407.377737) (xy 167.31628 -407.362379) (xy 167.266711 -407.339736)
			(xy 167.220869 -407.31027) (xy 167.179687 -407.274581) (xy 167.144002 -407.233394) (xy 167.114542 -407.187548)
			(xy 167.091905 -407.137977) (xy 167.076553 -407.085688) (xy 167.068798 -407.031748) (xy 165.631142 -407.031748)
			(xy 165.631142 -407.031752) (xy 165.623386 -407.085701) (xy 165.60803 -407.137998) (xy 165.585389 -407.187577)
			(xy 165.555923 -407.233429) (xy 165.520231 -407.274621) (xy 165.47904 -407.310314) (xy 165.433189 -407.339782)
			(xy 165.383611 -407.362426) (xy 165.331315 -407.377783) (xy 165.277366 -407.385541) (xy 165.250114 -407.386028)
			(xy 164.386514 -407.386028) (xy 164.359262 -407.385526) (xy 164.305312 -407.377771) (xy 164.253016 -407.362417)
			(xy 164.203436 -407.339776) (xy 164.157584 -407.31031) (xy 164.116392 -407.274618) (xy 164.080698 -407.233427)
			(xy 164.051231 -407.187576) (xy 164.028588 -407.137998) (xy 164.013232 -407.085701) (xy 164.005475 -407.031752)
			(xy 162.567965 -407.031752) (xy 162.567965 -407.031755) (xy 162.560207 -407.085712) (xy 162.544849 -407.138014)
			(xy 162.522203 -407.187599) (xy 162.492731 -407.233456) (xy 162.457033 -407.274651) (xy 162.415835 -407.310347)
			(xy 162.369976 -407.339816) (xy 162.32039 -407.362458) (xy 162.268086 -407.377813) (xy 162.21413 -407.385567)
			(xy 162.186874 -407.386028) (xy 161.323274 -407.386028) (xy 161.296025 -407.3855) (xy 161.242083 -407.377741)
			(xy 161.189795 -407.362384) (xy 161.140223 -407.339743) (xy 161.094379 -407.310278) (xy 161.053194 -407.274588)
			(xy 161.017507 -407.233401) (xy 160.988045 -407.187554) (xy 160.965407 -407.137981) (xy 160.950054 -407.085691)
			(xy 160.942298 -407.031749) (xy 159.504642 -407.031749) (xy 159.504642 -407.031751) (xy 159.496886 -407.085699)
			(xy 159.481532 -407.137993) (xy 159.458892 -407.187571) (xy 159.429428 -407.233422) (xy 159.393738 -407.274614)
			(xy 159.352549 -407.310307) (xy 159.306701 -407.339776) (xy 159.257125 -407.36242) (xy 159.204832 -407.377779)
			(xy 159.150885 -407.38554) (xy 159.123634 -407.386028) (xy 158.260034 -407.386028) (xy 158.232781 -407.385527)
			(xy 158.178829 -407.377774) (xy 158.12653 -407.362422) (xy 158.076948 -407.339783) (xy 158.031093 -407.310317)
			(xy 157.989899 -407.274625) (xy 157.954203 -407.233434) (xy 157.924734 -407.187582) (xy 157.90209 -407.138002)
			(xy 157.886733 -407.085704) (xy 157.878975 -407.031753) (xy 156.441465 -407.031753) (xy 156.441465 -407.031755)
			(xy 156.433708 -407.085709) (xy 156.41835 -407.13801) (xy 156.395706 -407.187593) (xy 156.366236 -407.233449)
			(xy 156.33054 -407.274644) (xy 156.289344 -407.31034) (xy 156.243488 -407.339809) (xy 156.193904 -407.362452)
			(xy 156.141603 -407.377809) (xy 156.087649 -407.385566) (xy 156.060394 -407.386028) (xy 155.196794 -407.386028)
			(xy 155.169544 -407.385501) (xy 155.1156 -407.377745) (xy 155.063309 -407.36239) (xy 155.013735 -407.339749)
			(xy 154.967888 -407.310285) (xy 154.926701 -407.274595) (xy 154.891012 -407.233407) (xy 154.861548 -407.187559)
			(xy 154.838908 -407.137985) (xy 154.823554 -407.085694) (xy 154.815798 -407.03175) (xy 153.378265 -407.03175)
			(xy 153.378265 -407.031756) (xy 153.370506 -407.085714) (xy 153.355147 -407.138019) (xy 153.3325 -407.187604)
			(xy 153.303026 -407.233462) (xy 153.267326 -407.274658) (xy 153.226125 -407.310354) (xy 153.180264 -407.339822)
			(xy 153.130675 -407.362463) (xy 153.078369 -407.377816) (xy 153.02441 -407.385568) (xy 152.997154 -407.386028)
			(xy 152.133554 -407.386028) (xy 152.106306 -407.385499) (xy 152.052367 -407.377737) (xy 152.00008 -407.362379)
			(xy 151.950511 -407.339736) (xy 151.904669 -407.31027) (xy 151.863487 -407.274581) (xy 151.827802 -407.233394)
			(xy 151.798342 -407.187548) (xy 151.775705 -407.137977) (xy 151.760353 -407.085688) (xy 151.752598 -407.031748)
			(xy 150.314942 -407.031748) (xy 150.314942 -407.031752) (xy 150.307186 -407.085701) (xy 150.29183 -407.137998)
			(xy 150.269189 -407.187577) (xy 150.239723 -407.233429) (xy 150.204031 -407.274621) (xy 150.16284 -407.310314)
			(xy 150.116989 -407.339782) (xy 150.067411 -407.362426) (xy 150.015115 -407.377783) (xy 149.961166 -407.385541)
			(xy 149.933914 -407.386028) (xy 149.070314 -407.386028) (xy 149.043062 -407.385526) (xy 148.989112 -407.377771)
			(xy 148.936816 -407.362417) (xy 148.887236 -407.339776) (xy 148.841384 -407.31031) (xy 148.800192 -407.274618)
			(xy 148.764498 -407.233427) (xy 148.735031 -407.187576) (xy 148.712388 -407.137998) (xy 148.697032 -407.085701)
			(xy 148.689275 -407.031752) (xy 147.251765 -407.031752) (xy 147.251765 -407.031755) (xy 147.244007 -407.085712)
			(xy 147.228649 -407.138014) (xy 147.206003 -407.187599) (xy 147.176531 -407.233456) (xy 147.140833 -407.274651)
			(xy 147.099635 -407.310347) (xy 147.053776 -407.339816) (xy 147.00419 -407.362458) (xy 146.951886 -407.377813)
			(xy 146.89793 -407.385567) (xy 146.870674 -407.386028) (xy 146.007074 -407.386028) (xy 145.979825 -407.3855)
			(xy 145.925883 -407.377741) (xy 145.873595 -407.362384) (xy 145.824023 -407.339743) (xy 145.778179 -407.310278)
			(xy 145.736994 -407.274588) (xy 145.701307 -407.233401) (xy 145.671845 -407.187554) (xy 145.649207 -407.137981)
			(xy 145.633854 -407.085691) (xy 145.626098 -407.031749) (xy 144.188442 -407.031749) (xy 144.188442 -407.031751)
			(xy 144.180686 -407.085699) (xy 144.165332 -407.137993) (xy 144.142692 -407.187571) (xy 144.113228 -407.233422)
			(xy 144.077538 -407.274614) (xy 144.036349 -407.310307) (xy 143.990501 -407.339776) (xy 143.940925 -407.36242)
			(xy 143.888632 -407.377779) (xy 143.834685 -407.38554) (xy 143.807434 -407.386028) (xy 142.943834 -407.386028)
			(xy 142.916581 -407.385527) (xy 142.862629 -407.377774) (xy 142.81033 -407.362422) (xy 142.760748 -407.339783)
			(xy 142.714893 -407.310317) (xy 142.673699 -407.274625) (xy 142.638003 -407.233434) (xy 142.608534 -407.187582)
			(xy 142.58589 -407.138002) (xy 142.570533 -407.085704) (xy 142.562775 -407.031753) (xy 141.125265 -407.031753)
			(xy 141.125265 -407.031755) (xy 141.117508 -407.085709) (xy 141.10215 -407.13801) (xy 141.079506 -407.187593)
			(xy 141.050036 -407.233449) (xy 141.01434 -407.274644) (xy 140.973144 -407.31034) (xy 140.927288 -407.339809)
			(xy 140.877704 -407.362452) (xy 140.825403 -407.377809) (xy 140.771449 -407.385566) (xy 140.744194 -407.386028)
			(xy 139.880594 -407.386028) (xy 139.853344 -407.385501) (xy 139.7994 -407.377745) (xy 139.747109 -407.36239)
			(xy 139.697535 -407.339749) (xy 139.651688 -407.310285) (xy 139.610501 -407.274595) (xy 139.574812 -407.233407)
			(xy 139.545348 -407.187559) (xy 139.522708 -407.137985) (xy 139.507354 -407.085694) (xy 139.499598 -407.03175)
			(xy 138.062065 -407.03175) (xy 138.062065 -407.031756) (xy 138.054306 -407.085714) (xy 138.038947 -407.138019)
			(xy 138.0163 -407.187604) (xy 137.986826 -407.233462) (xy 137.951126 -407.274658) (xy 137.909925 -407.310354)
			(xy 137.864064 -407.339822) (xy 137.814475 -407.362463) (xy 137.762169 -407.377816) (xy 137.70821 -407.385568)
			(xy 137.680954 -407.386028) (xy 136.817354 -407.386028) (xy 136.790106 -407.385499) (xy 136.736167 -407.377737)
			(xy 136.68388 -407.362379) (xy 136.634311 -407.339736) (xy 136.588469 -407.31027) (xy 136.547287 -407.274581)
			(xy 136.511602 -407.233394) (xy 136.482142 -407.187548) (xy 136.459505 -407.137977) (xy 136.444153 -407.085688)
			(xy 136.436398 -407.031748) (xy 134.998742 -407.031748) (xy 134.998742 -407.031752) (xy 134.990986 -407.085701)
			(xy 134.97563 -407.137998) (xy 134.952989 -407.187577) (xy 134.923523 -407.233429) (xy 134.887831 -407.274621)
			(xy 134.84664 -407.310314) (xy 134.800789 -407.339782) (xy 134.751211 -407.362426) (xy 134.698915 -407.377783)
			(xy 134.644966 -407.385541) (xy 134.617714 -407.386028) (xy 133.754114 -407.386028) (xy 133.726862 -407.385526)
			(xy 133.672912 -407.377771) (xy 133.620616 -407.362417) (xy 133.571036 -407.339776) (xy 133.525184 -407.31031)
			(xy 133.483992 -407.274618) (xy 133.448298 -407.233427) (xy 133.418831 -407.187576) (xy 133.396188 -407.137998)
			(xy 133.380832 -407.085701) (xy 133.373075 -407.031752) (xy 131.935565 -407.031752) (xy 131.935565 -407.031755)
			(xy 131.927807 -407.085712) (xy 131.912449 -407.138014) (xy 131.889803 -407.187599) (xy 131.860331 -407.233456)
			(xy 131.824633 -407.274651) (xy 131.783435 -407.310347) (xy 131.737576 -407.339816) (xy 131.68799 -407.362458)
			(xy 131.635686 -407.377813) (xy 131.58173 -407.385567) (xy 131.554474 -407.386028) (xy 130.690874 -407.386028)
			(xy 130.663625 -407.3855) (xy 130.609683 -407.377741) (xy 130.557395 -407.362384) (xy 130.507823 -407.339743)
			(xy 130.461979 -407.310278) (xy 130.420794 -407.274588) (xy 130.385107 -407.233401) (xy 130.355645 -407.187554)
			(xy 130.333007 -407.137981) (xy 130.317654 -407.085691) (xy 130.309898 -407.031749) (xy 128.872242 -407.031749)
			(xy 128.872242 -407.031751) (xy 128.864486 -407.085699) (xy 128.849132 -407.137993) (xy 128.826492 -407.187571)
			(xy 128.797028 -407.233422) (xy 128.761338 -407.274614) (xy 128.720149 -407.310307) (xy 128.674301 -407.339776)
			(xy 128.624725 -407.36242) (xy 128.572432 -407.377779) (xy 128.518485 -407.38554) (xy 128.491234 -407.386028)
			(xy 127.627634 -407.386028) (xy 127.600381 -407.385527) (xy 127.546429 -407.377774) (xy 127.49413 -407.362422)
			(xy 127.444548 -407.339783) (xy 127.398693 -407.310317) (xy 127.357499 -407.274625) (xy 127.321803 -407.233434)
			(xy 127.292334 -407.187582) (xy 127.26969 -407.138002) (xy 127.254333 -407.085704) (xy 127.246575 -407.031753)
			(xy 125.809065 -407.031753) (xy 125.809065 -407.031755) (xy 125.801308 -407.085709) (xy 125.78595 -407.13801)
			(xy 125.763306 -407.187593) (xy 125.733836 -407.233449) (xy 125.69814 -407.274644) (xy 125.656944 -407.31034)
			(xy 125.611088 -407.339809) (xy 125.561504 -407.362452) (xy 125.509203 -407.377809) (xy 125.455249 -407.385566)
			(xy 125.427994 -407.386028) (xy 124.564394 -407.386028) (xy 124.537144 -407.385501) (xy 124.4832 -407.377745)
			(xy 124.430909 -407.36239) (xy 124.381335 -407.339749) (xy 124.335488 -407.310285) (xy 124.294301 -407.274595)
			(xy 124.258612 -407.233407) (xy 124.229148 -407.187559) (xy 124.206508 -407.137985) (xy 124.191154 -407.085694)
			(xy 124.183398 -407.03175) (xy 122.745865 -407.03175) (xy 122.745865 -407.031756) (xy 122.738106 -407.085714)
			(xy 122.722747 -407.138019) (xy 122.7001 -407.187604) (xy 122.670626 -407.233462) (xy 122.634926 -407.274658)
			(xy 122.593725 -407.310354) (xy 122.547864 -407.339822) (xy 122.498275 -407.362463) (xy 122.445969 -407.377816)
			(xy 122.39201 -407.385568) (xy 122.364754 -407.386028) (xy 121.501154 -407.386028) (xy 121.473906 -407.385499)
			(xy 121.419967 -407.377737) (xy 121.36768 -407.362379) (xy 121.318111 -407.339736) (xy 121.272269 -407.31027)
			(xy 121.231087 -407.274581) (xy 121.195402 -407.233394) (xy 121.165942 -407.187548) (xy 121.143305 -407.137977)
			(xy 121.127953 -407.085688) (xy 121.120198 -407.031748) (xy 107.861153 -407.031748) (xy 107.86873 -407.084449)
			(xy 107.86873 -407.138951) (xy 107.860974 -407.192898) (xy 107.84562 -407.245192) (xy 107.822979 -407.294769)
			(xy 107.793514 -407.34062) (xy 107.757824 -407.38181) (xy 107.716636 -407.417502) (xy 107.670787 -407.44697)
			(xy 107.621211 -407.469613) (xy 107.568918 -407.48497) (xy 107.514971 -407.492729) (xy 107.48772 -407.493216)
			(xy 106.62412 -407.493216) (xy 106.596867 -407.492738) (xy 106.542915 -407.484984) (xy 106.490616 -407.46963)
			(xy 106.441034 -407.446989) (xy 106.395179 -407.417522) (xy 106.353985 -407.381829) (xy 106.31829 -407.340637)
			(xy 106.288821 -407.294783) (xy 106.266177 -407.245203) (xy 106.250821 -407.192905) (xy 106.243063 -407.138953)
			(xy 96.495694 -407.138953) (xy 96.473493 -407.18757) (xy 96.444028 -407.233421) (xy 96.408339 -407.274612)
			(xy 96.367151 -407.310306) (xy 96.321303 -407.339775) (xy 96.271728 -407.362419) (xy 96.219435 -407.377778)
			(xy 96.165489 -407.38554) (xy 96.138238 -407.386028) (xy 95.274638 -407.386028) (xy 95.247385 -407.385527)
			(xy 95.193433 -407.377775) (xy 95.141133 -407.362423) (xy 95.091551 -407.339784) (xy 95.045695 -407.310319)
			(xy 95.0045 -407.274627) (xy 94.968804 -407.233435) (xy 94.939334 -407.187583) (xy 94.91669 -407.138003)
			(xy 94.901333 -407.085705) (xy 94.893575 -407.031753) (xy 93.456065 -407.031753) (xy 93.456065 -407.031754)
			(xy 93.448308 -407.085708) (xy 93.432951 -407.138009) (xy 93.410307 -407.187592) (xy 93.380837 -407.233448)
			(xy 93.345141 -407.274643) (xy 93.303946 -407.310338) (xy 93.25809 -407.339808) (xy 93.208507 -407.362451)
			(xy 93.156206 -407.377808) (xy 93.102252 -407.385565) (xy 93.074998 -407.386028) (xy 92.211398 -407.386028)
			(xy 92.184148 -407.385502) (xy 92.130204 -407.377745) (xy 92.077912 -407.362391) (xy 92.028338 -407.339751)
			(xy 91.98249 -407.310286) (xy 91.941302 -407.274596) (xy 91.905613 -407.233408) (xy 91.876148 -407.187561)
			(xy 91.853508 -407.137986) (xy 91.838154 -407.085694) (xy 91.830398 -407.03175) (xy 90.392865 -407.03175)
			(xy 90.392865 -407.031756) (xy 90.385107 -407.085714) (xy 90.369748 -407.138018) (xy 90.347101 -407.187603)
			(xy 90.317627 -407.233461) (xy 90.281927 -407.274657) (xy 90.240727 -407.310352) (xy 90.194866 -407.339821)
			(xy 90.145278 -407.362462) (xy 90.092973 -407.377815) (xy 90.039014 -407.385568) (xy 90.011758 -407.386028)
			(xy 89.148158 -407.386028) (xy 89.12091 -407.385499) (xy 89.06697 -407.377738) (xy 89.014683 -407.36238)
			(xy 88.965114 -407.339738) (xy 88.919271 -407.310272) (xy 88.878088 -407.274582) (xy 88.842403 -407.233395)
			(xy 88.812942 -407.187549) (xy 88.790305 -407.137978) (xy 88.774953 -407.085689) (xy 88.767198 -407.031748)
			(xy 87.329542 -407.031748) (xy 87.329542 -407.031752) (xy 87.321786 -407.085701) (xy 87.306431 -407.137997)
			(xy 87.28379 -407.187576) (xy 87.254324 -407.233427) (xy 87.218632 -407.274619) (xy 87.177442 -407.310313)
			(xy 87.131591 -407.339781) (xy 87.082014 -407.362424) (xy 87.029718 -407.377782) (xy 86.97577 -407.385541)
			(xy 86.948518 -407.386028) (xy 86.084918 -407.386028) (xy 86.057666 -407.385526) (xy 86.003716 -407.377771)
			(xy 85.951418 -407.362418) (xy 85.901839 -407.339778) (xy 85.855986 -407.310312) (xy 85.814793 -407.27462)
			(xy 85.779099 -407.233429) (xy 85.749631 -407.187577) (xy 85.726989 -407.137998) (xy 85.711632 -407.085702)
			(xy 85.703875 -407.031752) (xy 84.266365 -407.031752) (xy 84.266365 -407.031755) (xy 84.258607 -407.085711)
			(xy 84.243249 -407.138013) (xy 84.220604 -407.187598) (xy 84.191132 -407.233454) (xy 84.155434 -407.27465)
			(xy 84.114237 -407.310345) (xy 84.068378 -407.339814) (xy 84.018793 -407.362457) (xy 83.96649 -407.377812)
			(xy 83.912533 -407.385567) (xy 83.885278 -407.386028) (xy 83.021678 -407.386028) (xy 82.994429 -407.3855)
			(xy 82.940487 -407.377742) (xy 82.888197 -407.362385) (xy 82.838626 -407.339744) (xy 82.79278 -407.310279)
			(xy 82.751595 -407.274589) (xy 82.715908 -407.233402) (xy 82.686445 -407.187555) (xy 82.663807 -407.137982)
			(xy 82.648454 -407.085692) (xy 82.640698 -407.031749) (xy 81.203042 -407.031749) (xy 81.203042 -407.031751)
			(xy 81.195286 -407.085698) (xy 81.179932 -407.137993) (xy 81.157293 -407.18757) (xy 81.127828 -407.233421)
			(xy 81.092139 -407.274612) (xy 81.050951 -407.310306) (xy 81.005103 -407.339775) (xy 80.955528 -407.362419)
			(xy 80.903235 -407.377778) (xy 80.849289 -407.38554) (xy 80.822038 -407.386028) (xy 79.958438 -407.386028)
			(xy 79.931185 -407.385527) (xy 79.877233 -407.377775) (xy 79.824933 -407.362423) (xy 79.775351 -407.339784)
			(xy 79.729495 -407.310319) (xy 79.6883 -407.274627) (xy 79.652604 -407.233435) (xy 79.623134 -407.187583)
			(xy 79.60049 -407.138003) (xy 79.585133 -407.085705) (xy 79.577375 -407.031753) (xy 78.139865 -407.031753)
			(xy 78.139865 -407.031754) (xy 78.132108 -407.085708) (xy 78.116751 -407.138009) (xy 78.094107 -407.187592)
			(xy 78.064637 -407.233448) (xy 78.028941 -407.274643) (xy 77.987746 -407.310338) (xy 77.94189 -407.339808)
			(xy 77.892307 -407.362451) (xy 77.840006 -407.377808) (xy 77.786052 -407.385565) (xy 77.758798 -407.386028)
			(xy 76.895198 -407.386028) (xy 76.867948 -407.385502) (xy 76.814004 -407.377745) (xy 76.761712 -407.362391)
			(xy 76.712138 -407.339751) (xy 76.66629 -407.310286) (xy 76.625102 -407.274596) (xy 76.589413 -407.233408)
			(xy 76.559948 -407.187561) (xy 76.537308 -407.137986) (xy 76.521954 -407.085694) (xy 76.514198 -407.03175)
			(xy 75.076665 -407.03175) (xy 75.076665 -407.031756) (xy 75.068907 -407.085714) (xy 75.053548 -407.138018)
			(xy 75.030901 -407.187603) (xy 75.001427 -407.233461) (xy 74.965727 -407.274657) (xy 74.924527 -407.310352)
			(xy 74.878666 -407.339821) (xy 74.829078 -407.362462) (xy 74.776773 -407.377815) (xy 74.722814 -407.385568)
			(xy 74.695558 -407.386028) (xy 73.831958 -407.386028) (xy 73.80471 -407.385499) (xy 73.75077 -407.377738)
			(xy 73.698483 -407.36238) (xy 73.648914 -407.339738) (xy 73.603071 -407.310272) (xy 73.561888 -407.274582)
			(xy 73.526203 -407.233395) (xy 73.496742 -407.187549) (xy 73.474105 -407.137978) (xy 73.458753 -407.085689)
			(xy 73.450998 -407.031748) (xy 72.013342 -407.031748) (xy 72.013342 -407.031752) (xy 72.005586 -407.085701)
			(xy 71.990231 -407.137997) (xy 71.96759 -407.187576) (xy 71.938124 -407.233427) (xy 71.902432 -407.274619)
			(xy 71.861242 -407.310313) (xy 71.815391 -407.339781) (xy 71.765814 -407.362424) (xy 71.713518 -407.377782)
			(xy 71.65957 -407.385541) (xy 71.632318 -407.386028) (xy 70.768718 -407.386028) (xy 70.741466 -407.385526)
			(xy 70.687516 -407.377771) (xy 70.635218 -407.362418) (xy 70.585639 -407.339778) (xy 70.539786 -407.310312)
			(xy 70.498593 -407.27462) (xy 70.462899 -407.233429) (xy 70.433431 -407.187577) (xy 70.410789 -407.137998)
			(xy 70.395432 -407.085702) (xy 70.387675 -407.031752) (xy 68.950165 -407.031752) (xy 68.950165 -407.031755)
			(xy 68.942407 -407.085711) (xy 68.927049 -407.138013) (xy 68.904404 -407.187598) (xy 68.874932 -407.233454)
			(xy 68.839234 -407.27465) (xy 68.798037 -407.310345) (xy 68.752178 -407.339814) (xy 68.702593 -407.362457)
			(xy 68.65029 -407.377812) (xy 68.596333 -407.385567) (xy 68.569078 -407.386028) (xy 67.705478 -407.386028)
			(xy 67.678229 -407.3855) (xy 67.624287 -407.377742) (xy 67.571997 -407.362385) (xy 67.522426 -407.339744)
			(xy 67.47658 -407.310279) (xy 67.435395 -407.274589) (xy 67.399708 -407.233402) (xy 67.370245 -407.187555)
			(xy 67.347607 -407.137982) (xy 67.332254 -407.085692) (xy 67.324498 -407.031749) (xy 65.886842 -407.031749)
			(xy 65.886842 -407.031751) (xy 65.879086 -407.085698) (xy 65.863732 -407.137993) (xy 65.841093 -407.18757)
			(xy 65.811628 -407.233421) (xy 65.775939 -407.274612) (xy 65.734751 -407.310306) (xy 65.688903 -407.339775)
			(xy 65.639328 -407.362419) (xy 65.587035 -407.377778) (xy 65.533089 -407.38554) (xy 65.505838 -407.386028)
			(xy 64.642238 -407.386028) (xy 64.614985 -407.385527) (xy 64.561033 -407.377775) (xy 64.508733 -407.362423)
			(xy 64.459151 -407.339784) (xy 64.413295 -407.310319) (xy 64.3721 -407.274627) (xy 64.336404 -407.233435)
			(xy 64.306934 -407.187583) (xy 64.28429 -407.138003) (xy 64.268933 -407.085705) (xy 64.261175 -407.031753)
			(xy 62.823665 -407.031753) (xy 62.823665 -407.031754) (xy 62.815908 -407.085708) (xy 62.800551 -407.138009)
			(xy 62.777907 -407.187592) (xy 62.748437 -407.233448) (xy 62.712741 -407.274643) (xy 62.671546 -407.310338)
			(xy 62.62569 -407.339808) (xy 62.576107 -407.362451) (xy 62.523806 -407.377808) (xy 62.469852 -407.385565)
			(xy 62.442598 -407.386028) (xy 61.578998 -407.386028) (xy 61.551748 -407.385502) (xy 61.497804 -407.377745)
			(xy 61.445512 -407.362391) (xy 61.395938 -407.339751) (xy 61.35009 -407.310286) (xy 61.308902 -407.274596)
			(xy 61.273213 -407.233408) (xy 61.243748 -407.187561) (xy 61.221108 -407.137986) (xy 61.205754 -407.085694)
			(xy 61.197998 -407.03175) (xy 59.760465 -407.03175) (xy 59.760465 -407.031756) (xy 59.752707 -407.085714)
			(xy 59.737348 -407.138018) (xy 59.714701 -407.187603) (xy 59.685227 -407.233461) (xy 59.649527 -407.274657)
			(xy 59.608327 -407.310352) (xy 59.562466 -407.339821) (xy 59.512878 -407.362462) (xy 59.460573 -407.377815)
			(xy 59.406614 -407.385568) (xy 59.379358 -407.386028) (xy 58.515758 -407.386028) (xy 58.48851 -407.385499)
			(xy 58.43457 -407.377738) (xy 58.382283 -407.36238) (xy 58.332714 -407.339738) (xy 58.286871 -407.310272)
			(xy 58.245688 -407.274582) (xy 58.210003 -407.233395) (xy 58.180542 -407.187549) (xy 58.157905 -407.137978)
			(xy 58.142553 -407.085689) (xy 58.134798 -407.031748) (xy 56.697142 -407.031748) (xy 56.697142 -407.031752)
			(xy 56.689386 -407.085701) (xy 56.674031 -407.137997) (xy 56.65139 -407.187576) (xy 56.621924 -407.233427)
			(xy 56.586232 -407.274619) (xy 56.545042 -407.310313) (xy 56.499191 -407.339781) (xy 56.449614 -407.362424)
			(xy 56.397318 -407.377782) (xy 56.34337 -407.385541) (xy 56.316118 -407.386028) (xy 55.452518 -407.386028)
			(xy 55.425266 -407.385526) (xy 55.371316 -407.377771) (xy 55.319018 -407.362418) (xy 55.269439 -407.339778)
			(xy 55.223586 -407.310312) (xy 55.182393 -407.27462) (xy 55.146699 -407.233429) (xy 55.117231 -407.187577)
			(xy 55.094589 -407.137998) (xy 55.079232 -407.085702) (xy 55.071475 -407.031752) (xy 53.633965 -407.031752)
			(xy 53.633965 -407.031755) (xy 53.626207 -407.085711) (xy 53.610849 -407.138013) (xy 53.588204 -407.187598)
			(xy 53.558732 -407.233454) (xy 53.523034 -407.27465) (xy 53.481837 -407.310345) (xy 53.435978 -407.339814)
			(xy 53.386393 -407.362457) (xy 53.33409 -407.377812) (xy 53.280133 -407.385567) (xy 53.252878 -407.386028)
			(xy 52.389278 -407.386028) (xy 52.362029 -407.3855) (xy 52.308087 -407.377742) (xy 52.255797 -407.362385)
			(xy 52.206226 -407.339744) (xy 52.16038 -407.310279) (xy 52.119195 -407.274589) (xy 52.083508 -407.233402)
			(xy 52.054045 -407.187555) (xy 52.031407 -407.137982) (xy 52.016054 -407.085692) (xy 52.008298 -407.031749)
			(xy 50.570642 -407.031749) (xy 50.570642 -407.031751) (xy 50.562886 -407.085698) (xy 50.547532 -407.137993)
			(xy 50.524893 -407.18757) (xy 50.495428 -407.233421) (xy 50.459739 -407.274612) (xy 50.418551 -407.310306)
			(xy 50.372703 -407.339775) (xy 50.323128 -407.362419) (xy 50.270835 -407.377778) (xy 50.216889 -407.38554)
			(xy 50.189638 -407.386028) (xy 49.326038 -407.386028) (xy 49.298785 -407.385527) (xy 49.244833 -407.377775)
			(xy 49.192533 -407.362423) (xy 49.142951 -407.339784) (xy 49.097095 -407.310319) (xy 49.0559 -407.274627)
			(xy 49.020204 -407.233435) (xy 48.990734 -407.187583) (xy 48.96809 -407.138003) (xy 48.952733 -407.085705)
			(xy 48.944975 -407.031753) (xy 16.741648 -407.031753) (xy 16.741648 -407.035508) (xy 16.741162 -407.062759)
			(xy 16.733406 -407.116707) (xy 16.718051 -407.169002) (xy 16.695409 -407.218579) (xy 16.665943 -407.264429)
			(xy 16.630252 -407.30562) (xy 16.589061 -407.341311) (xy 16.543211 -407.370777) (xy 16.493634 -407.393419)
			(xy 16.441339 -407.408774) (xy 16.387391 -407.41653) (xy 16.332889 -407.41653) (xy 16.278941 -407.408774)
			(xy 16.226646 -407.393419) (xy 16.177069 -407.370777) (xy 16.131219 -407.341311) (xy 16.090028 -407.30562)
			(xy 16.054337 -407.264429) (xy 16.024871 -407.218579) (xy 16.002229 -407.169002) (xy 15.986874 -407.116707)
			(xy 15.979118 -407.062759) (xy 15.978632 -407.035508) (xy 5.555234 -407.035508) (xy 6.274054 -407.754328)
			(xy 6.323476 -407.804436) (xy 6.417282 -407.909377) (xy 6.505056 -408.019414) (xy 6.586523 -408.134198)
			(xy 6.661426 -408.25337) (xy 6.729529 -408.376554) (xy 6.790618 -408.503362) (xy 6.844501 -408.633397)
			(xy 6.891008 -408.766247) (xy 6.918102 -408.860244) (xy 49.10836 -408.860244) (xy 49.10836 -408.174444)
			(xy 49.10885 -408.162367) (xy 49.116301 -408.139391) (xy 49.130489 -408.119843) (xy 49.150023 -408.105636)
			(xy 49.172991 -408.098162) (xy 49.185068 -408.097736) (xy 49.379632 -408.097736) (xy 49.390736 -408.098122)
			(xy 49.412029 -408.104442) (xy 49.421542 -408.110182) (xy 49.715166 -408.302714) (xy 49.724555 -408.308408)
			(xy 49.745565 -408.314745) (xy 49.76751 -408.314821) (xy 49.788564 -408.308631) (xy 49.79797 -408.302968)
			(xy 50.094134 -408.110182) (xy 50.10365 -408.104443) (xy 50.124939 -408.098112) (xy 50.136044 -408.097736)
			(xy 50.330608 -408.097736) (xy 50.342696 -408.098106) (xy 50.365686 -408.105581) (xy 50.38524 -408.119797)
			(xy 50.399442 -408.139361) (xy 50.406902 -408.162356) (xy 50.407316 -408.174444) (xy 50.407316 -408.860244)
			(xy 52.1716 -408.860244) (xy 52.1716 -408.174444) (xy 52.17205 -408.162363) (xy 52.179507 -408.13938)
			(xy 52.193703 -408.119828) (xy 52.213248 -408.105623) (xy 52.236227 -408.098156) (xy 52.248308 -408.097736)
			(xy 52.442872 -408.097736) (xy 52.453978 -408.098106) (xy 52.47527 -408.104437) (xy 52.484782 -408.110182)
			(xy 52.778406 -408.302714) (xy 52.787776 -408.308442) (xy 52.808795 -408.314771) (xy 52.830747 -408.314838)
			(xy 52.851804 -408.308636) (xy 52.86121 -408.302968) (xy 53.157374 -408.110182) (xy 53.166882 -408.104429)
			(xy 53.188177 -408.098106) (xy 53.199284 -408.097736) (xy 53.393848 -408.097736) (xy 53.405929 -408.098124)
			(xy 53.428906 -408.105605) (xy 53.448446 -408.11982) (xy 53.462637 -408.139377) (xy 53.470091 -408.162362)
			(xy 53.470556 -408.174444) (xy 53.470556 -408.860244) (xy 55.23484 -408.860244) (xy 55.23484 -408.174444)
			(xy 55.235251 -408.162359) (xy 55.242712 -408.139369) (xy 55.256917 -408.119814) (xy 55.276473 -408.10561)
			(xy 55.299463 -408.09815) (xy 55.311548 -408.097736) (xy 55.506112 -408.097736) (xy 55.517216 -408.09813)
			(xy 55.538508 -408.104444) (xy 55.548022 -408.110182) (xy 55.841646 -408.302714) (xy 55.850997 -408.308476)
			(xy 55.872025 -408.314798) (xy 55.893983 -408.314855) (xy 55.915044 -408.308642) (xy 55.92445 -408.302968)
			(xy 56.220614 -408.110182) (xy 56.230114 -408.104414) (xy 56.251415 -408.098101) (xy 56.262524 -408.097736)
			(xy 56.457088 -408.097736) (xy 56.469174 -408.098124) (xy 56.492164 -408.105593) (xy 56.511718 -408.119804)
			(xy 56.525921 -408.139365) (xy 56.533381 -408.162357) (xy 56.533796 -408.174444) (xy 56.533796 -408.860244)
			(xy 58.29808 -408.860244) (xy 58.29808 -408.174444) (xy 58.29855 -408.162365) (xy 58.306004 -408.139386)
			(xy 58.320196 -408.119836) (xy 58.339735 -408.10563) (xy 58.362709 -408.098159) (xy 58.374788 -408.097736)
			(xy 58.569352 -408.097736) (xy 58.580457 -408.098114) (xy 58.601749 -408.104439) (xy 58.611262 -408.110182)
			(xy 58.904886 -408.302714) (xy 58.914265 -408.308425) (xy 58.93528 -408.314758) (xy 58.957228 -408.31483)
			(xy 58.978284 -408.308634) (xy 58.98769 -408.302968) (xy 59.283854 -408.110182) (xy 59.293366 -408.104436)
			(xy 59.314658 -408.098109) (xy 59.325764 -408.097736) (xy 59.520328 -408.097736) (xy 59.532417 -408.098089)
			(xy 59.555408 -408.10557) (xy 59.574961 -408.11979) (xy 59.589163 -408.139357) (xy 59.596622 -408.162355)
			(xy 59.597036 -408.174444) (xy 59.597036 -408.860244) (xy 61.36132 -408.860244) (xy 61.36132 -408.174444)
			(xy 61.361751 -408.162361) (xy 61.369209 -408.139375) (xy 61.38341 -408.119821) (xy 61.40296 -408.105617)
			(xy 61.425945 -408.098153) (xy 61.438028 -408.097736) (xy 61.632592 -408.097736) (xy 61.643699 -408.098098)
			(xy 61.66499 -408.104435) (xy 61.674502 -408.110182) (xy 61.968126 -408.302714) (xy 61.977487 -408.308459)
			(xy 61.99851 -408.314785) (xy 62.020465 -408.314847) (xy 62.041524 -408.308639) (xy 62.05093 -408.302968)
			(xy 62.347094 -408.110182) (xy 62.356598 -408.104421) (xy 62.377896 -408.098104) (xy 62.389004 -408.097736)
			(xy 62.583568 -408.097736) (xy 62.595653 -408.098141) (xy 62.618643 -408.105605) (xy 62.638197 -408.119811)
			(xy 62.652401 -408.139368) (xy 62.659861 -408.162359) (xy 62.660276 -408.174444) (xy 62.660276 -408.860244)
			(xy 64.42456 -408.860244) (xy 64.42456 -408.174444) (xy 64.42505 -408.162367) (xy 64.432501 -408.139391)
			(xy 64.446689 -408.119843) (xy 64.466223 -408.105636) (xy 64.489191 -408.098162) (xy 64.501268 -408.097736)
			(xy 64.695832 -408.097736) (xy 64.706936 -408.098122) (xy 64.728229 -408.104442) (xy 64.737742 -408.110182)
			(xy 65.031366 -408.302714) (xy 65.040755 -408.308408) (xy 65.061765 -408.314745) (xy 65.08371 -408.314821)
			(xy 65.104764 -408.308631) (xy 65.11417 -408.302968) (xy 65.410334 -408.110182) (xy 65.41985 -408.104443)
			(xy 65.441139 -408.098112) (xy 65.452244 -408.097736) (xy 65.646808 -408.097736) (xy 65.658896 -408.098106)
			(xy 65.681886 -408.105581) (xy 65.70144 -408.119797) (xy 65.715642 -408.139361) (xy 65.723102 -408.162356)
			(xy 65.723516 -408.174444) (xy 65.723516 -408.860244) (xy 67.4878 -408.860244) (xy 67.4878 -408.174444)
			(xy 67.48825 -408.162363) (xy 67.495707 -408.13938) (xy 67.509903 -408.119828) (xy 67.529448 -408.105623)
			(xy 67.552427 -408.098156) (xy 67.564508 -408.097736) (xy 67.759072 -408.097736) (xy 67.770178 -408.098106)
			(xy 67.79147 -408.104437) (xy 67.800982 -408.110182) (xy 68.094606 -408.302714) (xy 68.103976 -408.308442)
			(xy 68.124995 -408.314771) (xy 68.146947 -408.314838) (xy 68.168004 -408.308636) (xy 68.17741 -408.302968)
			(xy 68.473574 -408.110182) (xy 68.483082 -408.104429) (xy 68.504377 -408.098106) (xy 68.515484 -408.097736)
			(xy 68.710048 -408.097736) (xy 68.722129 -408.098124) (xy 68.745106 -408.105605) (xy 68.764646 -408.11982)
			(xy 68.778837 -408.139377) (xy 68.786291 -408.162362) (xy 68.786756 -408.174444) (xy 68.786756 -408.860244)
			(xy 70.55104 -408.860244) (xy 70.55104 -408.174444) (xy 70.551451 -408.162359) (xy 70.558912 -408.139369)
			(xy 70.573117 -408.119814) (xy 70.592673 -408.10561) (xy 70.615663 -408.09815) (xy 70.627748 -408.097736)
			(xy 70.822312 -408.097736) (xy 70.833416 -408.09813) (xy 70.854708 -408.104444) (xy 70.864222 -408.110182)
			(xy 71.157846 -408.302714) (xy 71.167197 -408.308476) (xy 71.188225 -408.314798) (xy 71.210183 -408.314855)
			(xy 71.231244 -408.308642) (xy 71.24065 -408.302968) (xy 71.536814 -408.110182) (xy 71.546314 -408.104414)
			(xy 71.567615 -408.098101) (xy 71.578724 -408.097736) (xy 71.773288 -408.097736) (xy 71.785374 -408.098124)
			(xy 71.808364 -408.105593) (xy 71.827918 -408.119804) (xy 71.842121 -408.139365) (xy 71.849581 -408.162357)
			(xy 71.849996 -408.174444) (xy 71.849996 -408.860244) (xy 73.61428 -408.860244) (xy 73.61428 -408.174444)
			(xy 73.61475 -408.162365) (xy 73.622204 -408.139386) (xy 73.636396 -408.119836) (xy 73.655935 -408.10563)
			(xy 73.678909 -408.098159) (xy 73.690988 -408.097736) (xy 73.885552 -408.097736) (xy 73.896657 -408.098114)
			(xy 73.917949 -408.104439) (xy 73.927462 -408.110182) (xy 74.221086 -408.302714) (xy 74.230465 -408.308425)
			(xy 74.25148 -408.314758) (xy 74.273428 -408.31483) (xy 74.294484 -408.308634) (xy 74.30389 -408.302968)
			(xy 74.600054 -408.110182) (xy 74.609566 -408.104436) (xy 74.630858 -408.098109) (xy 74.641964 -408.097736)
			(xy 74.836528 -408.097736) (xy 74.848617 -408.098089) (xy 74.871608 -408.10557) (xy 74.891161 -408.11979)
			(xy 74.905363 -408.139357) (xy 74.912822 -408.162355) (xy 74.913236 -408.174444) (xy 74.913236 -408.860244)
			(xy 76.67752 -408.860244) (xy 76.67752 -408.174444) (xy 76.677951 -408.162361) (xy 76.685409 -408.139375)
			(xy 76.69961 -408.119821) (xy 76.71916 -408.105617) (xy 76.742145 -408.098153) (xy 76.754228 -408.097736)
			(xy 76.948792 -408.097736) (xy 76.959899 -408.098098) (xy 76.98119 -408.104435) (xy 76.990702 -408.110182)
			(xy 77.284326 -408.302714) (xy 77.293687 -408.308459) (xy 77.31471 -408.314785) (xy 77.336665 -408.314847)
			(xy 77.357724 -408.308639) (xy 77.36713 -408.302968) (xy 77.663294 -408.110182) (xy 77.672798 -408.104421)
			(xy 77.694096 -408.098104) (xy 77.705204 -408.097736) (xy 77.899768 -408.097736) (xy 77.911853 -408.098141)
			(xy 77.934843 -408.105605) (xy 77.954397 -408.119811) (xy 77.968601 -408.139368) (xy 77.976061 -408.162359)
			(xy 77.976476 -408.174444) (xy 77.976476 -408.860244) (xy 79.74076 -408.860244) (xy 79.74076 -408.174444)
			(xy 79.74125 -408.162367) (xy 79.748701 -408.139391) (xy 79.762889 -408.119843) (xy 79.782423 -408.105636)
			(xy 79.805391 -408.098162) (xy 79.817468 -408.097736) (xy 80.012032 -408.097736) (xy 80.023136 -408.098122)
			(xy 80.044429 -408.104442) (xy 80.053942 -408.110182) (xy 80.347566 -408.302714) (xy 80.356955 -408.308408)
			(xy 80.377965 -408.314745) (xy 80.39991 -408.314821) (xy 80.420964 -408.308631) (xy 80.43037 -408.302968)
			(xy 80.726534 -408.110182) (xy 80.73605 -408.104443) (xy 80.757339 -408.098112) (xy 80.768444 -408.097736)
			(xy 80.963008 -408.097736) (xy 80.975096 -408.098106) (xy 80.998086 -408.105581) (xy 81.01764 -408.119797)
			(xy 81.031842 -408.139361) (xy 81.039302 -408.162356) (xy 81.039716 -408.174444) (xy 81.039716 -408.860244)
			(xy 82.804 -408.860244) (xy 82.804 -408.174444) (xy 82.80445 -408.162363) (xy 82.811907 -408.13938)
			(xy 82.826103 -408.119828) (xy 82.845648 -408.105623) (xy 82.868627 -408.098156) (xy 82.880708 -408.097736)
			(xy 83.075272 -408.097736) (xy 83.086378 -408.098106) (xy 83.10767 -408.104437) (xy 83.117182 -408.110182)
			(xy 83.410806 -408.302714) (xy 83.420176 -408.308442) (xy 83.441195 -408.314771) (xy 83.463147 -408.314838)
			(xy 83.484204 -408.308636) (xy 83.49361 -408.302968) (xy 83.789774 -408.110182) (xy 83.799282 -408.104429)
			(xy 83.820577 -408.098106) (xy 83.831684 -408.097736) (xy 84.026248 -408.097736) (xy 84.038329 -408.098124)
			(xy 84.061306 -408.105605) (xy 84.080846 -408.11982) (xy 84.095037 -408.139377) (xy 84.102491 -408.162362)
			(xy 84.102956 -408.174444) (xy 84.102956 -408.860244) (xy 85.86724 -408.860244) (xy 85.86724 -408.174444)
			(xy 85.867651 -408.162359) (xy 85.875112 -408.139369) (xy 85.889317 -408.119814) (xy 85.908873 -408.10561)
			(xy 85.931863 -408.09815) (xy 85.943948 -408.097736) (xy 86.138512 -408.097736) (xy 86.149616 -408.09813)
			(xy 86.170908 -408.104444) (xy 86.180422 -408.110182) (xy 86.474046 -408.302714) (xy 86.483397 -408.308476)
			(xy 86.504425 -408.314798) (xy 86.526383 -408.314855) (xy 86.547444 -408.308642) (xy 86.55685 -408.302968)
			(xy 86.853014 -408.110182) (xy 86.862514 -408.104414) (xy 86.883815 -408.098101) (xy 86.894924 -408.097736)
			(xy 87.089488 -408.097736) (xy 87.101574 -408.098124) (xy 87.124564 -408.105593) (xy 87.144118 -408.119804)
			(xy 87.158321 -408.139365) (xy 87.165781 -408.162357) (xy 87.166196 -408.174444) (xy 87.166196 -408.860244)
			(xy 88.93048 -408.860244) (xy 88.93048 -408.174444) (xy 88.93095 -408.162365) (xy 88.938404 -408.139386)
			(xy 88.952596 -408.119836) (xy 88.972135 -408.10563) (xy 88.995109 -408.098159) (xy 89.007188 -408.097736)
			(xy 89.201752 -408.097736) (xy 89.212857 -408.098114) (xy 89.234149 -408.104439) (xy 89.243662 -408.110182)
			(xy 89.537286 -408.302714) (xy 89.546665 -408.308425) (xy 89.56768 -408.314758) (xy 89.589628 -408.31483)
			(xy 89.610684 -408.308634) (xy 89.62009 -408.302968) (xy 89.916254 -408.110182) (xy 89.925766 -408.104436)
			(xy 89.947058 -408.098109) (xy 89.958164 -408.097736) (xy 90.152728 -408.097736) (xy 90.164817 -408.098089)
			(xy 90.187808 -408.10557) (xy 90.207361 -408.11979) (xy 90.221563 -408.139357) (xy 90.229022 -408.162355)
			(xy 90.229436 -408.174444) (xy 90.229436 -408.860244) (xy 91.99372 -408.860244) (xy 91.99372 -408.174444)
			(xy 91.994151 -408.162361) (xy 92.001609 -408.139375) (xy 92.01581 -408.119821) (xy 92.03536 -408.105617)
			(xy 92.058345 -408.098153) (xy 92.070428 -408.097736) (xy 92.264992 -408.097736) (xy 92.276099 -408.098098)
			(xy 92.29739 -408.104435) (xy 92.306902 -408.110182) (xy 92.600526 -408.302714) (xy 92.609887 -408.308459)
			(xy 92.63091 -408.314785) (xy 92.652865 -408.314847) (xy 92.673924 -408.308639) (xy 92.68333 -408.302968)
			(xy 92.979494 -408.110182) (xy 92.988998 -408.104421) (xy 93.010296 -408.098104) (xy 93.021404 -408.097736)
			(xy 93.215968 -408.097736) (xy 93.228053 -408.098141) (xy 93.251043 -408.105605) (xy 93.270597 -408.119811)
			(xy 93.284801 -408.139368) (xy 93.292261 -408.162359) (xy 93.292676 -408.174444) (xy 93.292676 -408.860244)
			(xy 95.05696 -408.860244) (xy 95.05696 -408.174444) (xy 95.05745 -408.162367) (xy 95.064901 -408.139391)
			(xy 95.079089 -408.119843) (xy 95.098623 -408.105636) (xy 95.121591 -408.098162) (xy 95.133668 -408.097736)
			(xy 95.328232 -408.097736) (xy 95.339336 -408.098122) (xy 95.360629 -408.104442) (xy 95.370142 -408.110182)
			(xy 95.663766 -408.302714) (xy 95.673155 -408.308408) (xy 95.694165 -408.314745) (xy 95.71611 -408.314821)
			(xy 95.737164 -408.308631) (xy 95.74657 -408.302968) (xy 96.042734 -408.110182) (xy 96.05225 -408.104443)
			(xy 96.073539 -408.098112) (xy 96.084644 -408.097736) (xy 96.279208 -408.097736) (xy 96.291296 -408.098106)
			(xy 96.314286 -408.105581) (xy 96.33384 -408.119797) (xy 96.348042 -408.139361) (xy 96.355502 -408.162356)
			(xy 96.355916 -408.174444) (xy 96.355916 -408.860244) (xy 121.283476 -408.860244) (xy 121.283476 -408.174444)
			(xy 121.28395 -408.162365) (xy 121.291403 -408.139387) (xy 121.305594 -408.119837) (xy 121.325133 -408.105631)
			(xy 121.348106 -408.098159) (xy 121.360184 -408.097736) (xy 121.554748 -408.097736) (xy 121.565853 -408.098115)
			(xy 121.587145 -408.10444) (xy 121.596658 -408.110182) (xy 121.890282 -408.302714) (xy 121.899663 -408.308421)
			(xy 121.920677 -408.314756) (xy 121.942625 -408.314828) (xy 121.96368 -408.308633) (xy 121.973086 -408.302968)
			(xy 122.26925 -408.110182) (xy 122.278762 -408.104437) (xy 122.300054 -408.09811) (xy 122.31116 -408.097736)
			(xy 122.505724 -408.097736) (xy 122.517812 -408.098093) (xy 122.540803 -408.105572) (xy 122.560357 -408.119791)
			(xy 122.574559 -408.139358) (xy 122.582018 -408.162355) (xy 122.582432 -408.174444) (xy 122.582432 -408.860244)
			(xy 124.346716 -408.860244) (xy 124.346716 -408.174444) (xy 124.347151 -408.162361) (xy 124.354609 -408.139376)
			(xy 124.368808 -408.119823) (xy 124.388358 -408.105618) (xy 124.411341 -408.098154) (xy 124.423424 -408.097736)
			(xy 124.617988 -408.097736) (xy 124.629094 -408.098099) (xy 124.650386 -408.104435) (xy 124.659898 -408.110182)
			(xy 124.953522 -408.302714) (xy 124.962884 -408.308455) (xy 124.983907 -408.314782) (xy 125.005861 -408.314845)
			(xy 125.02692 -408.308639) (xy 125.036326 -408.302968) (xy 125.33249 -408.110182) (xy 125.341995 -408.104423)
			(xy 125.363292 -408.098104) (xy 125.3744 -408.097736) (xy 125.568964 -408.097736) (xy 125.581049 -408.098144)
			(xy 125.604038 -408.105607) (xy 125.623593 -408.119813) (xy 125.637797 -408.139369) (xy 125.645257 -408.162359)
			(xy 125.645672 -408.174444) (xy 125.645672 -408.860244) (xy 127.409956 -408.860244) (xy 127.409956 -408.174444)
			(xy 127.41045 -408.162367) (xy 127.417901 -408.139392) (xy 127.432087 -408.119844) (xy 127.45162 -408.105637)
			(xy 127.474588 -408.098162) (xy 127.486664 -408.097736) (xy 127.681228 -408.097736) (xy 127.692332 -408.098123)
			(xy 127.713624 -408.104442) (xy 127.723138 -408.110182) (xy 128.016762 -408.302714) (xy 128.026153 -408.308404)
			(xy 128.047162 -408.314742) (xy 128.069107 -408.314819) (xy 128.09016 -408.30863) (xy 128.099566 -408.302968)
			(xy 128.39573 -408.110182) (xy 128.405246 -408.104445) (xy 128.426535 -408.098113) (xy 128.43764 -408.097736)
			(xy 128.632204 -408.097736) (xy 128.644291 -408.09811) (xy 128.667282 -408.105584) (xy 128.686836 -408.119798)
			(xy 128.701038 -408.139361) (xy 128.708498 -408.162356) (xy 128.708912 -408.174444) (xy 128.708912 -408.860244)
			(xy 130.473196 -408.860244) (xy 130.473196 -408.174444) (xy 130.47365 -408.162363) (xy 130.481106 -408.139381)
			(xy 130.495301 -408.11983) (xy 130.514845 -408.105624) (xy 130.537823 -408.098157) (xy 130.549904 -408.097736)
			(xy 130.744468 -408.097736) (xy 130.755574 -408.098107) (xy 130.776866 -408.104438) (xy 130.786378 -408.110182)
			(xy 131.080002 -408.302714) (xy 131.089374 -408.308438) (xy 131.110392 -408.314769) (xy 131.132343 -408.314837)
			(xy 131.1534 -408.308636) (xy 131.162806 -408.302968) (xy 131.45897 -408.110182) (xy 131.468478 -408.10443)
			(xy 131.489773 -408.098107) (xy 131.50088 -408.097736) (xy 131.695444 -408.097736) (xy 131.707525 -408.098127)
			(xy 131.730501 -408.105607) (xy 131.750042 -408.119821) (xy 131.764233 -408.139378) (xy 131.771687 -408.162362)
			(xy 131.772152 -408.174444) (xy 131.772152 -408.860244) (xy 133.536436 -408.860244) (xy 133.536436 -408.174444)
			(xy 133.536851 -408.162359) (xy 133.544312 -408.13937) (xy 133.558516 -408.119816) (xy 133.57807 -408.105612)
			(xy 133.601059 -408.098151) (xy 133.613144 -408.097736) (xy 133.807708 -408.097736) (xy 133.818812 -408.098131)
			(xy 133.840104 -408.104445) (xy 133.849618 -408.110182) (xy 134.143242 -408.302714) (xy 134.152595 -408.308472)
			(xy 134.173622 -408.314795) (xy 134.195579 -408.314853) (xy 134.21664 -408.308642) (xy 134.226046 -408.302968)
			(xy 134.52221 -408.110182) (xy 134.531711 -408.104415) (xy 134.553011 -408.098101) (xy 134.56412 -408.097736)
			(xy 134.758684 -408.097736) (xy 134.77077 -408.098127) (xy 134.79376 -408.105596) (xy 134.813314 -408.119806)
			(xy 134.827517 -408.139365) (xy 134.834977 -408.162358) (xy 134.835392 -408.174444) (xy 134.835392 -408.860244)
			(xy 136.599676 -408.860244) (xy 136.599676 -408.174444) (xy 136.60015 -408.162365) (xy 136.607603 -408.139387)
			(xy 136.621794 -408.119837) (xy 136.641333 -408.105631) (xy 136.664306 -408.098159) (xy 136.676384 -408.097736)
			(xy 136.870948 -408.097736) (xy 136.882053 -408.098115) (xy 136.903345 -408.10444) (xy 136.912858 -408.110182)
			(xy 137.206482 -408.302714) (xy 137.215863 -408.308421) (xy 137.236877 -408.314756) (xy 137.258825 -408.314828)
			(xy 137.27988 -408.308633) (xy 137.289286 -408.302968) (xy 137.58545 -408.110182) (xy 137.594962 -408.104437)
			(xy 137.616254 -408.09811) (xy 137.62736 -408.097736) (xy 137.821924 -408.097736) (xy 137.834012 -408.098093)
			(xy 137.857003 -408.105572) (xy 137.876557 -408.119791) (xy 137.890759 -408.139358) (xy 137.898218 -408.162355)
			(xy 137.898632 -408.174444) (xy 137.898632 -408.860244) (xy 139.662916 -408.860244) (xy 139.662916 -408.174444)
			(xy 139.663351 -408.162361) (xy 139.670809 -408.139376) (xy 139.685008 -408.119823) (xy 139.704558 -408.105618)
			(xy 139.727541 -408.098154) (xy 139.739624 -408.097736) (xy 139.934188 -408.097736) (xy 139.945294 -408.098099)
			(xy 139.966586 -408.104435) (xy 139.976098 -408.110182) (xy 140.269722 -408.302714) (xy 140.279084 -408.308455)
			(xy 140.300107 -408.314782) (xy 140.322061 -408.314845) (xy 140.34312 -408.308639) (xy 140.352526 -408.302968)
			(xy 140.64869 -408.110182) (xy 140.658195 -408.104423) (xy 140.679492 -408.098104) (xy 140.6906 -408.097736)
			(xy 140.885164 -408.097736) (xy 140.897249 -408.098144) (xy 140.920238 -408.105607) (xy 140.939793 -408.119813)
			(xy 140.953997 -408.139369) (xy 140.961457 -408.162359) (xy 140.961872 -408.174444) (xy 140.961872 -408.860244)
			(xy 142.726156 -408.860244) (xy 142.726156 -408.174444) (xy 142.72665 -408.162367) (xy 142.734101 -408.139392)
			(xy 142.748287 -408.119844) (xy 142.76782 -408.105637) (xy 142.790788 -408.098162) (xy 142.802864 -408.097736)
			(xy 142.997428 -408.097736) (xy 143.008532 -408.098123) (xy 143.029824 -408.104442) (xy 143.039338 -408.110182)
			(xy 143.332962 -408.302714) (xy 143.342353 -408.308404) (xy 143.363362 -408.314742) (xy 143.385307 -408.314819)
			(xy 143.40636 -408.30863) (xy 143.415766 -408.302968) (xy 143.71193 -408.110182) (xy 143.721446 -408.104445)
			(xy 143.742735 -408.098113) (xy 143.75384 -408.097736) (xy 143.948404 -408.097736) (xy 143.960491 -408.09811)
			(xy 143.983482 -408.105584) (xy 144.003036 -408.119798) (xy 144.017238 -408.139361) (xy 144.024698 -408.162356)
			(xy 144.025112 -408.174444) (xy 144.025112 -408.860244) (xy 145.789396 -408.860244) (xy 145.789396 -408.174444)
			(xy 145.78985 -408.162363) (xy 145.797306 -408.139381) (xy 145.811501 -408.11983) (xy 145.831045 -408.105624)
			(xy 145.854023 -408.098157) (xy 145.866104 -408.097736) (xy 146.060668 -408.097736) (xy 146.071774 -408.098107)
			(xy 146.093066 -408.104438) (xy 146.102578 -408.110182) (xy 146.396202 -408.302714) (xy 146.405574 -408.308438)
			(xy 146.426592 -408.314769) (xy 146.448543 -408.314837) (xy 146.4696 -408.308636) (xy 146.479006 -408.302968)
			(xy 146.77517 -408.110182) (xy 146.784678 -408.10443) (xy 146.805973 -408.098107) (xy 146.81708 -408.097736)
			(xy 147.011644 -408.097736) (xy 147.023725 -408.098127) (xy 147.046701 -408.105607) (xy 147.066242 -408.119821)
			(xy 147.080433 -408.139378) (xy 147.087887 -408.162362) (xy 147.088352 -408.174444) (xy 147.088352 -408.860244)
			(xy 148.852636 -408.860244) (xy 148.852636 -408.174444) (xy 148.853051 -408.162359) (xy 148.860512 -408.13937)
			(xy 148.874716 -408.119816) (xy 148.89427 -408.105612) (xy 148.917259 -408.098151) (xy 148.929344 -408.097736)
			(xy 149.123908 -408.097736) (xy 149.135012 -408.098131) (xy 149.156304 -408.104445) (xy 149.165818 -408.110182)
			(xy 149.459442 -408.302714) (xy 149.468795 -408.308472) (xy 149.489822 -408.314795) (xy 149.511779 -408.314853)
			(xy 149.53284 -408.308642) (xy 149.542246 -408.302968) (xy 149.83841 -408.110182) (xy 149.847911 -408.104415)
			(xy 149.869211 -408.098101) (xy 149.88032 -408.097736) (xy 150.074884 -408.097736) (xy 150.08697 -408.098127)
			(xy 150.10996 -408.105596) (xy 150.129514 -408.119806) (xy 150.143717 -408.139365) (xy 150.151177 -408.162358)
			(xy 150.151592 -408.174444) (xy 150.151592 -408.860244) (xy 151.915876 -408.860244) (xy 151.915876 -408.174444)
			(xy 151.91635 -408.162365) (xy 151.923803 -408.139387) (xy 151.937994 -408.119837) (xy 151.957533 -408.105631)
			(xy 151.980506 -408.098159) (xy 151.992584 -408.097736) (xy 152.187148 -408.097736) (xy 152.198253 -408.098115)
			(xy 152.219545 -408.10444) (xy 152.229058 -408.110182) (xy 152.522682 -408.302714) (xy 152.532063 -408.308421)
			(xy 152.553077 -408.314756) (xy 152.575025 -408.314828) (xy 152.59608 -408.308633) (xy 152.605486 -408.302968)
			(xy 152.90165 -408.110182) (xy 152.911162 -408.104437) (xy 152.932454 -408.09811) (xy 152.94356 -408.097736)
			(xy 153.138124 -408.097736) (xy 153.150212 -408.098093) (xy 153.173203 -408.105572) (xy 153.192757 -408.119791)
			(xy 153.206959 -408.139358) (xy 153.214418 -408.162355) (xy 153.214832 -408.174444) (xy 153.214832 -408.860244)
			(xy 154.979116 -408.860244) (xy 154.979116 -408.174444) (xy 154.979551 -408.162361) (xy 154.987009 -408.139376)
			(xy 155.001208 -408.119823) (xy 155.020758 -408.105618) (xy 155.043741 -408.098154) (xy 155.055824 -408.097736)
			(xy 155.250388 -408.097736) (xy 155.261494 -408.098099) (xy 155.282786 -408.104435) (xy 155.292298 -408.110182)
			(xy 155.585922 -408.302714) (xy 155.595284 -408.308455) (xy 155.616307 -408.314782) (xy 155.638261 -408.314845)
			(xy 155.65932 -408.308639) (xy 155.668726 -408.302968) (xy 155.96489 -408.110182) (xy 155.974395 -408.104423)
			(xy 155.995692 -408.098104) (xy 156.0068 -408.097736) (xy 156.201364 -408.097736) (xy 156.213449 -408.098144)
			(xy 156.236438 -408.105607) (xy 156.255993 -408.119813) (xy 156.270197 -408.139369) (xy 156.277657 -408.162359)
			(xy 156.278072 -408.174444) (xy 156.278072 -408.860244) (xy 158.042356 -408.860244) (xy 158.042356 -408.174444)
			(xy 158.04285 -408.162367) (xy 158.050301 -408.139392) (xy 158.064487 -408.119844) (xy 158.08402 -408.105637)
			(xy 158.106988 -408.098162) (xy 158.119064 -408.097736) (xy 158.313628 -408.097736) (xy 158.324732 -408.098123)
			(xy 158.346024 -408.104442) (xy 158.355538 -408.110182) (xy 158.649162 -408.302714) (xy 158.658553 -408.308404)
			(xy 158.679562 -408.314742) (xy 158.701507 -408.314819) (xy 158.72256 -408.30863) (xy 158.731966 -408.302968)
			(xy 159.02813 -408.110182) (xy 159.037646 -408.104445) (xy 159.058935 -408.098113) (xy 159.07004 -408.097736)
			(xy 159.264604 -408.097736) (xy 159.276691 -408.09811) (xy 159.299682 -408.105584) (xy 159.319236 -408.119798)
			(xy 159.333438 -408.139361) (xy 159.340898 -408.162356) (xy 159.341312 -408.174444) (xy 159.341312 -408.860244)
			(xy 161.105596 -408.860244) (xy 161.105596 -408.174444) (xy 161.10605 -408.162363) (xy 161.113506 -408.139381)
			(xy 161.127701 -408.11983) (xy 161.147245 -408.105624) (xy 161.170223 -408.098157) (xy 161.182304 -408.097736)
			(xy 161.376868 -408.097736) (xy 161.387974 -408.098107) (xy 161.409266 -408.104438) (xy 161.418778 -408.110182)
			(xy 161.712402 -408.302714) (xy 161.721774 -408.308438) (xy 161.742792 -408.314769) (xy 161.764743 -408.314837)
			(xy 161.7858 -408.308636) (xy 161.795206 -408.302968) (xy 162.09137 -408.110182) (xy 162.100878 -408.10443)
			(xy 162.122173 -408.098107) (xy 162.13328 -408.097736) (xy 162.327844 -408.097736) (xy 162.339925 -408.098127)
			(xy 162.362901 -408.105607) (xy 162.382442 -408.119821) (xy 162.396633 -408.139378) (xy 162.404087 -408.162362)
			(xy 162.404552 -408.174444) (xy 162.404552 -408.860244) (xy 164.168836 -408.860244) (xy 164.168836 -408.174444)
			(xy 164.169251 -408.162359) (xy 164.176712 -408.13937) (xy 164.190916 -408.119816) (xy 164.21047 -408.105612)
			(xy 164.233459 -408.098151) (xy 164.245544 -408.097736) (xy 164.440108 -408.097736) (xy 164.451212 -408.098131)
			(xy 164.472504 -408.104445) (xy 164.482018 -408.110182) (xy 164.775642 -408.302714) (xy 164.784995 -408.308472)
			(xy 164.806022 -408.314795) (xy 164.827979 -408.314853) (xy 164.84904 -408.308642) (xy 164.858446 -408.302968)
			(xy 165.15461 -408.110182) (xy 165.164111 -408.104415) (xy 165.185411 -408.098101) (xy 165.19652 -408.097736)
			(xy 165.391084 -408.097736) (xy 165.40317 -408.098127) (xy 165.42616 -408.105596) (xy 165.445714 -408.119806)
			(xy 165.459917 -408.139365) (xy 165.467377 -408.162358) (xy 165.467792 -408.174444) (xy 165.467792 -408.860244)
			(xy 167.232076 -408.860244) (xy 167.232076 -408.174444) (xy 167.23255 -408.162365) (xy 167.240003 -408.139387)
			(xy 167.254194 -408.119837) (xy 167.273733 -408.105631) (xy 167.296706 -408.098159) (xy 167.308784 -408.097736)
			(xy 167.503348 -408.097736) (xy 167.514453 -408.098115) (xy 167.535745 -408.10444) (xy 167.545258 -408.110182)
			(xy 167.838882 -408.302714) (xy 167.848263 -408.308421) (xy 167.869277 -408.314756) (xy 167.891225 -408.314828)
			(xy 167.91228 -408.308633) (xy 167.921686 -408.302968) (xy 168.21785 -408.110182) (xy 168.227362 -408.104437)
			(xy 168.248654 -408.09811) (xy 168.25976 -408.097736) (xy 168.454324 -408.097736) (xy 168.466412 -408.098093)
			(xy 168.489403 -408.105572) (xy 168.508957 -408.119791) (xy 168.523159 -408.139358) (xy 168.530618 -408.162355)
			(xy 168.531032 -408.174444) (xy 168.531032 -408.860244) (xy 168.530574 -408.872318) (xy 168.523102 -408.895283)
			(xy 168.508903 -408.914817) (xy 168.489365 -408.929011) (xy 168.466399 -408.936477) (xy 168.454324 -408.936952)
			(xy 168.25976 -408.936952) (xy 168.248652 -408.936593) (xy 168.227355 -408.930266) (xy 168.21785 -408.924506)
			(xy 167.922956 -408.731974) (xy 167.913569 -408.726271) (xy 167.892531 -408.719998) (xy 167.870577 -408.719998)
			(xy 167.849539 -408.726271) (xy 167.840152 -408.731974) (xy 167.546528 -408.924506) (xy 167.537019 -408.930258)
			(xy 167.515725 -408.936581) (xy 167.504618 -408.936952) (xy 167.308784 -408.936952) (xy 167.296713 -408.93645)
			(xy 167.273753 -408.928988) (xy 167.25422 -408.9148) (xy 167.240024 -408.895272) (xy 167.232554 -408.872315)
			(xy 167.232076 -408.860244) (xy 165.467792 -408.860244) (xy 165.467373 -408.872322) (xy 165.459897 -408.895294)
			(xy 165.445689 -408.914832) (xy 165.42614 -408.929024) (xy 165.403163 -408.936483) (xy 165.391084 -408.936952)
			(xy 165.19652 -408.936952) (xy 165.18541 -408.936609) (xy 165.164114 -408.930271) (xy 165.15461 -408.924506)
			(xy 164.859716 -408.731974) (xy 164.850329 -408.726271) (xy 164.829291 -408.719998) (xy 164.807337 -408.719998)
			(xy 164.786299 -408.726271) (xy 164.776912 -408.731974) (xy 164.483288 -408.924506) (xy 164.473787 -408.930273)
			(xy 164.452487 -408.936587) (xy 164.441378 -408.936952) (xy 164.245544 -408.936952) (xy 164.233476 -408.936399)
			(xy 164.210518 -408.928954) (xy 164.190984 -408.914779) (xy 164.176786 -408.895261) (xy 164.169315 -408.872311)
			(xy 164.168836 -408.860244) (xy 162.404552 -408.860244) (xy 162.404074 -408.872316) (xy 162.396605 -408.895278)
			(xy 162.38241 -408.91481) (xy 162.362878 -408.929005) (xy 162.339916 -408.936474) (xy 162.327844 -408.936952)
			(xy 162.13328 -408.936952) (xy 162.122172 -408.936585) (xy 162.100876 -408.930263) (xy 162.09137 -408.924506)
			(xy 161.796476 -408.731974) (xy 161.787089 -408.726271) (xy 161.766051 -408.719998) (xy 161.744097 -408.719998)
			(xy 161.723059 -408.726271) (xy 161.713672 -408.731974) (xy 161.420048 -408.924506) (xy 161.410535 -408.93025)
			(xy 161.389244 -408.936578) (xy 161.378138 -408.936952) (xy 161.182304 -408.936952) (xy 161.170234 -408.936433)
			(xy 161.147274 -408.928977) (xy 161.127741 -408.914793) (xy 161.113545 -408.895269) (xy 161.106075 -408.872314)
			(xy 161.105596 -408.860244) (xy 159.341312 -408.860244) (xy 159.340873 -408.87232) (xy 159.333399 -408.895288)
			(xy 159.319196 -408.914824) (xy 159.299653 -408.929018) (xy 159.276681 -408.93648) (xy 159.264604 -408.936952)
			(xy 159.07004 -408.936952) (xy 159.058931 -408.936601) (xy 159.037635 -408.930268) (xy 159.02813 -408.924506)
			(xy 158.733236 -408.731974) (xy 158.723849 -408.726271) (xy 158.702811 -408.719998) (xy 158.680857 -408.719998)
			(xy 158.659819 -408.726271) (xy 158.650432 -408.731974) (xy 158.356808 -408.924506) (xy 158.347303 -408.930265)
			(xy 158.326006 -408.936584) (xy 158.314898 -408.936952) (xy 158.119064 -408.936952) (xy 158.106992 -408.936467)
			(xy 158.084031 -408.929) (xy 158.064498 -408.914807) (xy 158.050303 -408.895276) (xy 158.042834 -408.872316)
			(xy 158.042356 -408.860244) (xy 156.278072 -408.860244) (xy 156.277673 -408.872324) (xy 156.270194 -408.895299)
			(xy 156.255982 -408.914839) (xy 156.236427 -408.92903) (xy 156.213445 -408.936485) (xy 156.201364 -408.936952)
			(xy 156.0068 -408.936952) (xy 155.995693 -408.936576) (xy 155.974397 -408.93026) (xy 155.96489 -408.924506)
			(xy 155.669996 -408.731974) (xy 155.660609 -408.726271) (xy 155.639571 -408.719998) (xy 155.617617 -408.719998)
			(xy 155.596579 -408.726271) (xy 155.587192 -408.731974) (xy 155.293568 -408.924506) (xy 155.284051 -408.930243)
			(xy 155.262763 -408.936576) (xy 155.251658 -408.936952) (xy 155.055824 -408.936952) (xy 155.043755 -408.936416)
			(xy 155.020796 -408.928966) (xy 155.001262 -408.914786) (xy 154.987066 -408.895265) (xy 154.979595 -408.872313)
			(xy 154.979116 -408.860244) (xy 153.214832 -408.860244) (xy 153.214374 -408.872318) (xy 153.206902 -408.895283)
			(xy 153.192703 -408.914817) (xy 153.173165 -408.929011) (xy 153.150199 -408.936477) (xy 153.138124 -408.936952)
			(xy 152.94356 -408.936952) (xy 152.932452 -408.936593) (xy 152.911155 -408.930266) (xy 152.90165 -408.924506)
			(xy 152.606756 -408.731974) (xy 152.597369 -408.726271) (xy 152.576331 -408.719998) (xy 152.554377 -408.719998)
			(xy 152.533339 -408.726271) (xy 152.523952 -408.731974) (xy 152.230328 -408.924506) (xy 152.220819 -408.930258)
			(xy 152.199525 -408.936581) (xy 152.188418 -408.936952) (xy 151.992584 -408.936952) (xy 151.980513 -408.93645)
			(xy 151.957553 -408.928988) (xy 151.93802 -408.9148) (xy 151.923824 -408.895272) (xy 151.916354 -408.872315)
			(xy 151.915876 -408.860244) (xy 150.151592 -408.860244) (xy 150.151173 -408.872322) (xy 150.143697 -408.895294)
			(xy 150.129489 -408.914832) (xy 150.10994 -408.929024) (xy 150.086963 -408.936483) (xy 150.074884 -408.936952)
			(xy 149.88032 -408.936952) (xy 149.86921 -408.936609) (xy 149.847914 -408.930271) (xy 149.83841 -408.924506)
			(xy 149.543516 -408.731974) (xy 149.534129 -408.726271) (xy 149.513091 -408.719998) (xy 149.491137 -408.719998)
			(xy 149.470099 -408.726271) (xy 149.460712 -408.731974) (xy 149.167088 -408.924506) (xy 149.157587 -408.930273)
			(xy 149.136287 -408.936587) (xy 149.125178 -408.936952) (xy 148.929344 -408.936952) (xy 148.917276 -408.936399)
			(xy 148.894318 -408.928954) (xy 148.874784 -408.914779) (xy 148.860586 -408.895261) (xy 148.853115 -408.872311)
			(xy 148.852636 -408.860244) (xy 147.088352 -408.860244) (xy 147.087874 -408.872316) (xy 147.080405 -408.895278)
			(xy 147.06621 -408.91481) (xy 147.046678 -408.929005) (xy 147.023716 -408.936474) (xy 147.011644 -408.936952)
			(xy 146.81708 -408.936952) (xy 146.805972 -408.936585) (xy 146.784676 -408.930263) (xy 146.77517 -408.924506)
			(xy 146.480276 -408.731974) (xy 146.470889 -408.726271) (xy 146.449851 -408.719998) (xy 146.427897 -408.719998)
			(xy 146.406859 -408.726271) (xy 146.397472 -408.731974) (xy 146.103848 -408.924506) (xy 146.094335 -408.93025)
			(xy 146.073044 -408.936578) (xy 146.061938 -408.936952) (xy 145.866104 -408.936952) (xy 145.854034 -408.936433)
			(xy 145.831074 -408.928977) (xy 145.811541 -408.914793) (xy 145.797345 -408.895269) (xy 145.789875 -408.872314)
			(xy 145.789396 -408.860244) (xy 144.025112 -408.860244) (xy 144.024673 -408.87232) (xy 144.017199 -408.895288)
			(xy 144.002996 -408.914824) (xy 143.983453 -408.929018) (xy 143.960481 -408.93648) (xy 143.948404 -408.936952)
			(xy 143.75384 -408.936952) (xy 143.742731 -408.936601) (xy 143.721435 -408.930268) (xy 143.71193 -408.924506)
			(xy 143.417036 -408.731974) (xy 143.407649 -408.726271) (xy 143.386611 -408.719998) (xy 143.364657 -408.719998)
			(xy 143.343619 -408.726271) (xy 143.334232 -408.731974) (xy 143.040608 -408.924506) (xy 143.031103 -408.930265)
			(xy 143.009806 -408.936584) (xy 142.998698 -408.936952) (xy 142.802864 -408.936952) (xy 142.790792 -408.936467)
			(xy 142.767831 -408.929) (xy 142.748298 -408.914807) (xy 142.734103 -408.895276) (xy 142.726634 -408.872316)
			(xy 142.726156 -408.860244) (xy 140.961872 -408.860244) (xy 140.961473 -408.872324) (xy 140.953994 -408.895299)
			(xy 140.939782 -408.914839) (xy 140.920227 -408.92903) (xy 140.897245 -408.936485) (xy 140.885164 -408.936952)
			(xy 140.6906 -408.936952) (xy 140.679493 -408.936576) (xy 140.658197 -408.93026) (xy 140.64869 -408.924506)
			(xy 140.353796 -408.731974) (xy 140.344409 -408.726271) (xy 140.323371 -408.719998) (xy 140.301417 -408.719998)
			(xy 140.280379 -408.726271) (xy 140.270992 -408.731974) (xy 139.977368 -408.924506) (xy 139.967851 -408.930243)
			(xy 139.946563 -408.936576) (xy 139.935458 -408.936952) (xy 139.739624 -408.936952) (xy 139.727555 -408.936416)
			(xy 139.704596 -408.928966) (xy 139.685062 -408.914786) (xy 139.670866 -408.895265) (xy 139.663395 -408.872313)
			(xy 139.662916 -408.860244) (xy 137.898632 -408.860244) (xy 137.898174 -408.872318) (xy 137.890702 -408.895283)
			(xy 137.876503 -408.914817) (xy 137.856965 -408.929011) (xy 137.833999 -408.936477) (xy 137.821924 -408.936952)
			(xy 137.62736 -408.936952) (xy 137.616252 -408.936593) (xy 137.594955 -408.930266) (xy 137.58545 -408.924506)
			(xy 137.290556 -408.731974) (xy 137.281169 -408.726271) (xy 137.260131 -408.719998) (xy 137.238177 -408.719998)
			(xy 137.217139 -408.726271) (xy 137.207752 -408.731974) (xy 136.914128 -408.924506) (xy 136.904619 -408.930258)
			(xy 136.883325 -408.936581) (xy 136.872218 -408.936952) (xy 136.676384 -408.936952) (xy 136.664313 -408.93645)
			(xy 136.641353 -408.928988) (xy 136.62182 -408.9148) (xy 136.607624 -408.895272) (xy 136.600154 -408.872315)
			(xy 136.599676 -408.860244) (xy 134.835392 -408.860244) (xy 134.834973 -408.872322) (xy 134.827497 -408.895294)
			(xy 134.813289 -408.914832) (xy 134.79374 -408.929024) (xy 134.770763 -408.936483) (xy 134.758684 -408.936952)
			(xy 134.56412 -408.936952) (xy 134.55301 -408.936609) (xy 134.531714 -408.930271) (xy 134.52221 -408.924506)
			(xy 134.227316 -408.731974) (xy 134.217929 -408.726271) (xy 134.196891 -408.719998) (xy 134.174937 -408.719998)
			(xy 134.153899 -408.726271) (xy 134.144512 -408.731974) (xy 133.850888 -408.924506) (xy 133.841387 -408.930273)
			(xy 133.820087 -408.936587) (xy 133.808978 -408.936952) (xy 133.613144 -408.936952) (xy 133.601076 -408.936399)
			(xy 133.578118 -408.928954) (xy 133.558584 -408.914779) (xy 133.544386 -408.895261) (xy 133.536915 -408.872311)
			(xy 133.536436 -408.860244) (xy 131.772152 -408.860244) (xy 131.771674 -408.872316) (xy 131.764205 -408.895278)
			(xy 131.75001 -408.91481) (xy 131.730478 -408.929005) (xy 131.707516 -408.936474) (xy 131.695444 -408.936952)
			(xy 131.50088 -408.936952) (xy 131.489772 -408.936585) (xy 131.468476 -408.930263) (xy 131.45897 -408.924506)
			(xy 131.164076 -408.731974) (xy 131.154689 -408.726271) (xy 131.133651 -408.719998) (xy 131.111697 -408.719998)
			(xy 131.090659 -408.726271) (xy 131.081272 -408.731974) (xy 130.787648 -408.924506) (xy 130.778135 -408.93025)
			(xy 130.756844 -408.936578) (xy 130.745738 -408.936952) (xy 130.549904 -408.936952) (xy 130.537834 -408.936433)
			(xy 130.514874 -408.928977) (xy 130.495341 -408.914793) (xy 130.481145 -408.895269) (xy 130.473675 -408.872314)
			(xy 130.473196 -408.860244) (xy 128.708912 -408.860244) (xy 128.708473 -408.87232) (xy 128.700999 -408.895288)
			(xy 128.686796 -408.914824) (xy 128.667253 -408.929018) (xy 128.644281 -408.93648) (xy 128.632204 -408.936952)
			(xy 128.43764 -408.936952) (xy 128.426531 -408.936601) (xy 128.405235 -408.930268) (xy 128.39573 -408.924506)
			(xy 128.100836 -408.731974) (xy 128.091449 -408.726271) (xy 128.070411 -408.719998) (xy 128.048457 -408.719998)
			(xy 128.027419 -408.726271) (xy 128.018032 -408.731974) (xy 127.724408 -408.924506) (xy 127.714903 -408.930265)
			(xy 127.693606 -408.936584) (xy 127.682498 -408.936952) (xy 127.486664 -408.936952) (xy 127.474592 -408.936467)
			(xy 127.451631 -408.929) (xy 127.432098 -408.914807) (xy 127.417903 -408.895276) (xy 127.410434 -408.872316)
			(xy 127.409956 -408.860244) (xy 125.645672 -408.860244) (xy 125.645273 -408.872324) (xy 125.637794 -408.895299)
			(xy 125.623582 -408.914839) (xy 125.604027 -408.92903) (xy 125.581045 -408.936485) (xy 125.568964 -408.936952)
			(xy 125.3744 -408.936952) (xy 125.363293 -408.936576) (xy 125.341997 -408.93026) (xy 125.33249 -408.924506)
			(xy 125.037596 -408.731974) (xy 125.028209 -408.726271) (xy 125.007171 -408.719998) (xy 124.985217 -408.719998)
			(xy 124.964179 -408.726271) (xy 124.954792 -408.731974) (xy 124.661168 -408.924506) (xy 124.651651 -408.930243)
			(xy 124.630363 -408.936576) (xy 124.619258 -408.936952) (xy 124.423424 -408.936952) (xy 124.411355 -408.936416)
			(xy 124.388396 -408.928966) (xy 124.368862 -408.914786) (xy 124.354666 -408.895265) (xy 124.347195 -408.872313)
			(xy 124.346716 -408.860244) (xy 122.582432 -408.860244) (xy 122.581974 -408.872318) (xy 122.574502 -408.895283)
			(xy 122.560303 -408.914817) (xy 122.540765 -408.929011) (xy 122.517799 -408.936477) (xy 122.505724 -408.936952)
			(xy 122.31116 -408.936952) (xy 122.300052 -408.936593) (xy 122.278755 -408.930266) (xy 122.26925 -408.924506)
			(xy 121.974356 -408.731974) (xy 121.964969 -408.726271) (xy 121.943931 -408.719998) (xy 121.921977 -408.719998)
			(xy 121.900939 -408.726271) (xy 121.891552 -408.731974) (xy 121.597928 -408.924506) (xy 121.588419 -408.930258)
			(xy 121.567125 -408.936581) (xy 121.556018 -408.936952) (xy 121.360184 -408.936952) (xy 121.348113 -408.93645)
			(xy 121.325153 -408.928988) (xy 121.30562 -408.9148) (xy 121.291424 -408.895272) (xy 121.283954 -408.872315)
			(xy 121.283476 -408.860244) (xy 96.355916 -408.860244) (xy 96.355474 -408.87232) (xy 96.348 -408.895287)
			(xy 96.333797 -408.914823) (xy 96.314255 -408.929016) (xy 96.291284 -408.936479) (xy 96.279208 -408.936952)
			(xy 96.084644 -408.936952) (xy 96.073535 -408.936599) (xy 96.052239 -408.930268) (xy 96.042734 -408.924506)
			(xy 95.74784 -408.731974) (xy 95.738453 -408.726271) (xy 95.717415 -408.719998) (xy 95.695461 -408.719998)
			(xy 95.674423 -408.726271) (xy 95.665036 -408.731974) (xy 95.371412 -408.924506) (xy 95.361907 -408.930264)
			(xy 95.340609 -408.936583) (xy 95.329502 -408.936952) (xy 95.133668 -408.936952) (xy 95.121596 -408.936464)
			(xy 95.098635 -408.928998) (xy 95.079103 -408.914806) (xy 95.064907 -408.895275) (xy 95.057438 -408.872316)
			(xy 95.05696 -408.860244) (xy 93.292676 -408.860244) (xy 93.292273 -408.872324) (xy 93.284794 -408.895298)
			(xy 93.270583 -408.914837) (xy 93.25103 -408.929029) (xy 93.228049 -408.936485) (xy 93.215968 -408.936952)
			(xy 93.021404 -408.936952) (xy 93.010297 -408.936575) (xy 92.989001 -408.93026) (xy 92.979494 -408.924506)
			(xy 92.6846 -408.731974) (xy 92.675213 -408.726271) (xy 92.654175 -408.719998) (xy 92.632221 -408.719998)
			(xy 92.611183 -408.726271) (xy 92.601796 -408.731974) (xy 92.308172 -408.924506) (xy 92.298655 -408.930241)
			(xy 92.277367 -408.936575) (xy 92.266262 -408.936952) (xy 92.070428 -408.936952) (xy 92.058359 -408.936413)
			(xy 92.0354 -408.928963) (xy 92.015867 -408.914785) (xy 92.00167 -408.895264) (xy 91.994199 -408.872312)
			(xy 91.99372 -408.860244) (xy 90.229436 -408.860244) (xy 90.228974 -408.872318) (xy 90.221503 -408.895282)
			(xy 90.207305 -408.914816) (xy 90.187768 -408.92901) (xy 90.164802 -408.936476) (xy 90.152728 -408.936952)
			(xy 89.958164 -408.936952) (xy 89.947056 -408.936591) (xy 89.92576 -408.930265) (xy 89.916254 -408.924506)
			(xy 89.62136 -408.731974) (xy 89.611973 -408.726271) (xy 89.590935 -408.719998) (xy 89.568981 -408.719998)
			(xy 89.547943 -408.726271) (xy 89.538556 -408.731974) (xy 89.244932 -408.924506) (xy 89.235423 -408.930256)
			(xy 89.214129 -408.936581) (xy 89.203022 -408.936952) (xy 89.007188 -408.936952) (xy 88.995117 -408.936447)
			(xy 88.972157 -408.928986) (xy 88.952624 -408.914799) (xy 88.938428 -408.895272) (xy 88.930958 -408.872315)
			(xy 88.93048 -408.860244) (xy 87.166196 -408.860244) (xy 87.165773 -408.872322) (xy 87.158297 -408.895293)
			(xy 87.14409 -408.91483) (xy 87.124543 -408.929023) (xy 87.101566 -408.936482) (xy 87.089488 -408.936952)
			(xy 86.894924 -408.936952) (xy 86.883814 -408.936607) (xy 86.862518 -408.93027) (xy 86.853014 -408.924506)
			(xy 86.55812 -408.731974) (xy 86.548733 -408.726271) (xy 86.527695 -408.719998) (xy 86.505741 -408.719998)
			(xy 86.484703 -408.726271) (xy 86.475316 -408.731974) (xy 86.181692 -408.924506) (xy 86.17219 -408.930271)
			(xy 86.15089 -408.936586) (xy 86.139782 -408.936952) (xy 85.943948 -408.936952) (xy 85.931872 -408.936447)
			(xy 85.908898 -408.928998) (xy 85.889351 -408.914814) (xy 85.875144 -408.895284) (xy 85.867667 -408.872319)
			(xy 85.86724 -408.860244) (xy 84.102956 -408.860244) (xy 84.102474 -408.872316) (xy 84.095005 -408.895277)
			(xy 84.080812 -408.914809) (xy 84.06128 -408.929004) (xy 84.03832 -408.936474) (xy 84.026248 -408.936952)
			(xy 83.831684 -408.936952) (xy 83.820576 -408.936583) (xy 83.79928 -408.930263) (xy 83.789774 -408.924506)
			(xy 83.49488 -408.731974) (xy 83.485493 -408.726271) (xy 83.464455 -408.719998) (xy 83.442501 -408.719998)
			(xy 83.421463 -408.726271) (xy 83.412076 -408.731974) (xy 83.118452 -408.924506) (xy 83.108939 -408.930249)
			(xy 83.087648 -408.936578) (xy 83.076542 -408.936952) (xy 82.880708 -408.936952) (xy 82.868638 -408.93643)
			(xy 82.845679 -408.928975) (xy 82.826145 -408.914792) (xy 82.811949 -408.895268) (xy 82.804479 -408.872313)
			(xy 82.804 -408.860244) (xy 81.039716 -408.860244) (xy 81.039274 -408.87232) (xy 81.0318 -408.895287)
			(xy 81.017597 -408.914823) (xy 80.998055 -408.929016) (xy 80.975084 -408.936479) (xy 80.963008 -408.936952)
			(xy 80.768444 -408.936952) (xy 80.757335 -408.936599) (xy 80.736039 -408.930268) (xy 80.726534 -408.924506)
			(xy 80.43164 -408.731974) (xy 80.422253 -408.726271) (xy 80.401215 -408.719998) (xy 80.379261 -408.719998)
			(xy 80.358223 -408.726271) (xy 80.348836 -408.731974) (xy 80.055212 -408.924506) (xy 80.045707 -408.930264)
			(xy 80.024409 -408.936583) (xy 80.013302 -408.936952) (xy 79.817468 -408.936952) (xy 79.805396 -408.936464)
			(xy 79.782435 -408.928998) (xy 79.762903 -408.914806) (xy 79.748707 -408.895275) (xy 79.741238 -408.872316)
			(xy 79.74076 -408.860244) (xy 77.976476 -408.860244) (xy 77.976073 -408.872324) (xy 77.968594 -408.895298)
			(xy 77.954383 -408.914837) (xy 77.93483 -408.929029) (xy 77.911849 -408.936485) (xy 77.899768 -408.936952)
			(xy 77.705204 -408.936952) (xy 77.694097 -408.936575) (xy 77.672801 -408.93026) (xy 77.663294 -408.924506)
			(xy 77.3684 -408.731974) (xy 77.359013 -408.726271) (xy 77.337975 -408.719998) (xy 77.316021 -408.719998)
			(xy 77.294983 -408.726271) (xy 77.285596 -408.731974) (xy 76.991972 -408.924506) (xy 76.982455 -408.930241)
			(xy 76.961167 -408.936575) (xy 76.950062 -408.936952) (xy 76.754228 -408.936952) (xy 76.742159 -408.936413)
			(xy 76.7192 -408.928963) (xy 76.699667 -408.914785) (xy 76.68547 -408.895264) (xy 76.677999 -408.872312)
			(xy 76.67752 -408.860244) (xy 74.913236 -408.860244) (xy 74.912774 -408.872318) (xy 74.905303 -408.895282)
			(xy 74.891105 -408.914816) (xy 74.871568 -408.92901) (xy 74.848602 -408.936476) (xy 74.836528 -408.936952)
			(xy 74.641964 -408.936952) (xy 74.630856 -408.936591) (xy 74.60956 -408.930265) (xy 74.600054 -408.924506)
			(xy 74.30516 -408.731974) (xy 74.295773 -408.726271) (xy 74.274735 -408.719998) (xy 74.252781 -408.719998)
			(xy 74.231743 -408.726271) (xy 74.222356 -408.731974) (xy 73.928732 -408.924506) (xy 73.919223 -408.930256)
			(xy 73.897929 -408.936581) (xy 73.886822 -408.936952) (xy 73.690988 -408.936952) (xy 73.678917 -408.936447)
			(xy 73.655957 -408.928986) (xy 73.636424 -408.914799) (xy 73.622228 -408.895272) (xy 73.614758 -408.872315)
			(xy 73.61428 -408.860244) (xy 71.849996 -408.860244) (xy 71.849573 -408.872322) (xy 71.842097 -408.895293)
			(xy 71.82789 -408.91483) (xy 71.808343 -408.929023) (xy 71.785366 -408.936482) (xy 71.773288 -408.936952)
			(xy 71.578724 -408.936952) (xy 71.567614 -408.936607) (xy 71.546318 -408.93027) (xy 71.536814 -408.924506)
			(xy 71.24192 -408.731974) (xy 71.232533 -408.726271) (xy 71.211495 -408.719998) (xy 71.189541 -408.719998)
			(xy 71.168503 -408.726271) (xy 71.159116 -408.731974) (xy 70.865492 -408.924506) (xy 70.85599 -408.930271)
			(xy 70.83469 -408.936586) (xy 70.823582 -408.936952) (xy 70.627748 -408.936952) (xy 70.615672 -408.936447)
			(xy 70.592698 -408.928998) (xy 70.573151 -408.914814) (xy 70.558944 -408.895284) (xy 70.551467 -408.872319)
			(xy 70.55104 -408.860244) (xy 68.786756 -408.860244) (xy 68.786274 -408.872316) (xy 68.778805 -408.895277)
			(xy 68.764612 -408.914809) (xy 68.74508 -408.929004) (xy 68.72212 -408.936474) (xy 68.710048 -408.936952)
			(xy 68.515484 -408.936952) (xy 68.504376 -408.936583) (xy 68.48308 -408.930263) (xy 68.473574 -408.924506)
			(xy 68.17868 -408.731974) (xy 68.169293 -408.726271) (xy 68.148255 -408.719998) (xy 68.126301 -408.719998)
			(xy 68.105263 -408.726271) (xy 68.095876 -408.731974) (xy 67.802252 -408.924506) (xy 67.792739 -408.930249)
			(xy 67.771448 -408.936578) (xy 67.760342 -408.936952) (xy 67.564508 -408.936952) (xy 67.552438 -408.93643)
			(xy 67.529479 -408.928975) (xy 67.509945 -408.914792) (xy 67.495749 -408.895268) (xy 67.488279 -408.872313)
			(xy 67.4878 -408.860244) (xy 65.723516 -408.860244) (xy 65.723074 -408.87232) (xy 65.7156 -408.895287)
			(xy 65.701397 -408.914823) (xy 65.681855 -408.929016) (xy 65.658884 -408.936479) (xy 65.646808 -408.936952)
			(xy 65.452244 -408.936952) (xy 65.441135 -408.936599) (xy 65.419839 -408.930268) (xy 65.410334 -408.924506)
			(xy 65.11544 -408.731974) (xy 65.106053 -408.726271) (xy 65.085015 -408.719998) (xy 65.063061 -408.719998)
			(xy 65.042023 -408.726271) (xy 65.032636 -408.731974) (xy 64.739012 -408.924506) (xy 64.729507 -408.930264)
			(xy 64.708209 -408.936583) (xy 64.697102 -408.936952) (xy 64.501268 -408.936952) (xy 64.489196 -408.936464)
			(xy 64.466235 -408.928998) (xy 64.446703 -408.914806) (xy 64.432507 -408.895275) (xy 64.425038 -408.872316)
			(xy 64.42456 -408.860244) (xy 62.660276 -408.860244) (xy 62.659873 -408.872324) (xy 62.652394 -408.895298)
			(xy 62.638183 -408.914837) (xy 62.61863 -408.929029) (xy 62.595649 -408.936485) (xy 62.583568 -408.936952)
			(xy 62.389004 -408.936952) (xy 62.377897 -408.936575) (xy 62.356601 -408.93026) (xy 62.347094 -408.924506)
			(xy 62.0522 -408.731974) (xy 62.042813 -408.726271) (xy 62.021775 -408.719998) (xy 61.999821 -408.719998)
			(xy 61.978783 -408.726271) (xy 61.969396 -408.731974) (xy 61.675772 -408.924506) (xy 61.666255 -408.930241)
			(xy 61.644967 -408.936575) (xy 61.633862 -408.936952) (xy 61.438028 -408.936952) (xy 61.425959 -408.936413)
			(xy 61.403 -408.928963) (xy 61.383467 -408.914785) (xy 61.36927 -408.895264) (xy 61.361799 -408.872312)
			(xy 61.36132 -408.860244) (xy 59.597036 -408.860244) (xy 59.596574 -408.872318) (xy 59.589103 -408.895282)
			(xy 59.574905 -408.914816) (xy 59.555368 -408.92901) (xy 59.532402 -408.936476) (xy 59.520328 -408.936952)
			(xy 59.325764 -408.936952) (xy 59.314656 -408.936591) (xy 59.29336 -408.930265) (xy 59.283854 -408.924506)
			(xy 58.98896 -408.731974) (xy 58.979573 -408.726271) (xy 58.958535 -408.719998) (xy 58.936581 -408.719998)
			(xy 58.915543 -408.726271) (xy 58.906156 -408.731974) (xy 58.612532 -408.924506) (xy 58.603023 -408.930256)
			(xy 58.581729 -408.936581) (xy 58.570622 -408.936952) (xy 58.374788 -408.936952) (xy 58.362717 -408.936447)
			(xy 58.339757 -408.928986) (xy 58.320224 -408.914799) (xy 58.306028 -408.895272) (xy 58.298558 -408.872315)
			(xy 58.29808 -408.860244) (xy 56.533796 -408.860244) (xy 56.533373 -408.872322) (xy 56.525897 -408.895293)
			(xy 56.51169 -408.91483) (xy 56.492143 -408.929023) (xy 56.469166 -408.936482) (xy 56.457088 -408.936952)
			(xy 56.262524 -408.936952) (xy 56.251414 -408.936607) (xy 56.230118 -408.93027) (xy 56.220614 -408.924506)
			(xy 55.92572 -408.731974) (xy 55.916333 -408.726271) (xy 55.895295 -408.719998) (xy 55.873341 -408.719998)
			(xy 55.852303 -408.726271) (xy 55.842916 -408.731974) (xy 55.549292 -408.924506) (xy 55.53979 -408.930271)
			(xy 55.51849 -408.936586) (xy 55.507382 -408.936952) (xy 55.311548 -408.936952) (xy 55.299472 -408.936447)
			(xy 55.276498 -408.928998) (xy 55.256951 -408.914814) (xy 55.242744 -408.895284) (xy 55.235267 -408.872319)
			(xy 55.23484 -408.860244) (xy 53.470556 -408.860244) (xy 53.470074 -408.872316) (xy 53.462605 -408.895277)
			(xy 53.448412 -408.914809) (xy 53.42888 -408.929004) (xy 53.40592 -408.936474) (xy 53.393848 -408.936952)
			(xy 53.199284 -408.936952) (xy 53.188176 -408.936583) (xy 53.16688 -408.930263) (xy 53.157374 -408.924506)
			(xy 52.86248 -408.731974) (xy 52.853093 -408.726271) (xy 52.832055 -408.719998) (xy 52.810101 -408.719998)
			(xy 52.789063 -408.726271) (xy 52.779676 -408.731974) (xy 52.486052 -408.924506) (xy 52.476539 -408.930249)
			(xy 52.455248 -408.936578) (xy 52.444142 -408.936952) (xy 52.248308 -408.936952) (xy 52.236238 -408.93643)
			(xy 52.213279 -408.928975) (xy 52.193745 -408.914792) (xy 52.179549 -408.895268) (xy 52.172079 -408.872313)
			(xy 52.1716 -408.860244) (xy 50.407316 -408.860244) (xy 50.406874 -408.87232) (xy 50.3994 -408.895287)
			(xy 50.385197 -408.914823) (xy 50.365655 -408.929016) (xy 50.342684 -408.936479) (xy 50.330608 -408.936952)
			(xy 50.136044 -408.936952) (xy 50.124935 -408.936599) (xy 50.103639 -408.930268) (xy 50.094134 -408.924506)
			(xy 49.79924 -408.731974) (xy 49.789853 -408.726271) (xy 49.768815 -408.719998) (xy 49.746861 -408.719998)
			(xy 49.725823 -408.726271) (xy 49.716436 -408.731974) (xy 49.422812 -408.924506) (xy 49.413307 -408.930264)
			(xy 49.392009 -408.936583) (xy 49.380902 -408.936952) (xy 49.185068 -408.936952) (xy 49.172996 -408.936464)
			(xy 49.150035 -408.928998) (xy 49.130503 -408.914806) (xy 49.116307 -408.895275) (xy 49.108838 -408.872316)
			(xy 49.10836 -408.860244) (xy 6.918102 -408.860244) (xy 6.929993 -408.901497) (xy 6.961334 -409.03872)
			(xy 6.984932 -409.177484) (xy 7.000712 -409.317352) (xy 7.007496 -409.43784) (xy 102.064312 -409.43784)
			(xy 102.064312 -409.18384) (xy 102.064751 -409.171732) (xy 102.07224 -409.148704) (xy 102.086496 -409.129129)
			(xy 102.106114 -409.114934) (xy 102.129165 -409.107514) (xy 102.141274 -409.107132) (xy 102.471474 -409.107132)
			(xy 102.483561 -409.107629) (xy 102.50656 -409.115078) (xy 102.526139 -409.129257) (xy 102.540391 -409.148784)
			(xy 102.547925 -409.171754) (xy 102.548436 -409.18384) (xy 102.548436 -409.43784) (xy 102.861364 -409.43784)
			(xy 102.861364 -409.18384) (xy 102.86185 -409.171737) (xy 102.869334 -409.148717) (xy 102.883579 -409.129146)
			(xy 102.903184 -409.114949) (xy 102.926222 -409.107521) (xy 102.938326 -409.107132) (xy 103.268526 -409.107132)
			(xy 103.280616 -409.107585) (xy 103.303616 -409.115048) (xy 103.323195 -409.129238) (xy 103.337445 -409.148774)
			(xy 103.344978 -409.171751) (xy 103.345488 -409.18384) (xy 103.345488 -409.43784) (xy 103.345118 -409.449952)
			(xy 103.337606 -409.472983) (xy 103.323333 -409.492556) (xy 103.303701 -409.506749) (xy 103.28064 -409.514167)
			(xy 103.268526 -409.514548) (xy 102.938326 -409.514548) (xy 102.926237 -409.51407) (xy 102.903235 -409.506619)
			(xy 102.883653 -409.492436) (xy 102.869402 -409.472904) (xy 102.861872 -409.449928) (xy 102.861364 -409.43784)
			(xy 102.548436 -409.43784) (xy 102.548018 -409.449947) (xy 102.540512 -409.47297) (xy 102.52625 -409.492539)
			(xy 102.506631 -409.506734) (xy 102.483583 -409.51416) (xy 102.471474 -409.514548) (xy 102.141274 -409.514548)
			(xy 102.129182 -409.514115) (xy 102.106178 -409.506649) (xy 102.086598 -409.492454) (xy 102.072349 -409.472913)
			(xy 102.064819 -409.449931) (xy 102.064312 -409.43784) (xy 7.007496 -409.43784) (xy 7.008625 -409.457886)
			(xy 7.00913 -409.528264) (xy 7.00913 -410.057457) (xy 48.944923 -410.057457) (xy 48.944923 -410.002943)
			(xy 48.952682 -409.948984) (xy 48.968041 -409.896679) (xy 48.990688 -409.847092) (xy 49.020162 -409.801233)
			(xy 49.055863 -409.760036) (xy 49.097064 -409.724339) (xy 49.142925 -409.69487) (xy 49.192515 -409.672228)
			(xy 49.244821 -409.656874) (xy 49.298781 -409.64912) (xy 49.326038 -409.64866) (xy 50.189638 -409.64866)
			(xy 50.216885 -409.649213) (xy 50.270824 -409.656973) (xy 50.32311 -409.67233) (xy 50.372678 -409.694972)
			(xy 50.41852 -409.724436) (xy 50.459702 -409.760125) (xy 50.495386 -409.801311) (xy 50.524847 -409.847155)
			(xy 50.547483 -409.896726) (xy 50.562835 -409.949013) (xy 50.57059 -410.002953) (xy 50.57059 -410.057447)
			(xy 50.570589 -410.057453) (xy 52.008246 -410.057453) (xy 52.008246 -410.002947) (xy 52.016002 -409.948997)
			(xy 52.031358 -409.8967) (xy 52.053999 -409.84712) (xy 52.083466 -409.801267) (xy 52.119158 -409.760074)
			(xy 52.160349 -409.724379) (xy 52.206201 -409.69491) (xy 52.255779 -409.672265) (xy 52.308076 -409.656907)
			(xy 52.362025 -409.649147) (xy 52.389278 -409.64866) (xy 53.252878 -409.64866) (xy 53.28013 -409.649186)
			(xy 53.334078 -409.65694) (xy 53.386374 -409.672292) (xy 53.435953 -409.694932) (xy 53.481805 -409.724397)
			(xy 53.522997 -409.760087) (xy 53.55869 -409.801277) (xy 53.588158 -409.847127) (xy 53.6108 -409.896705)
			(xy 53.626156 -409.949) (xy 53.633913 -410.002948) (xy 53.633913 -410.057452) (xy 53.633912 -410.057456)
			(xy 55.071423 -410.057456) (xy 55.071423 -410.002944) (xy 55.079181 -409.948987) (xy 55.094539 -409.896683)
			(xy 55.117185 -409.847098) (xy 55.146657 -409.80124) (xy 55.182356 -409.760043) (xy 55.223554 -409.724346)
			(xy 55.269413 -409.694876) (xy 55.319 -409.672233) (xy 55.371305 -409.656877) (xy 55.425262 -409.649122)
			(xy 55.452518 -409.64866) (xy 56.316118 -409.64866) (xy 56.343366 -409.649211) (xy 56.397307 -409.656969)
			(xy 56.449595 -409.672325) (xy 56.499166 -409.694965) (xy 56.54501 -409.724429) (xy 56.586195 -409.760118)
			(xy 56.621882 -409.801304) (xy 56.651344 -409.84715) (xy 56.673982 -409.896721) (xy 56.689334 -409.94901)
			(xy 56.69709 -410.002952) (xy 56.69709 -410.057448) (xy 56.697089 -410.057452) (xy 58.134746 -410.057452)
			(xy 58.134746 -410.002948) (xy 58.142502 -409.949) (xy 58.157856 -409.896704) (xy 58.180496 -409.847125)
			(xy 58.209961 -409.801273) (xy 58.245651 -409.760081) (xy 58.28684 -409.724386) (xy 58.332689 -409.694916)
			(xy 58.382265 -409.672271) (xy 58.434559 -409.656911) (xy 58.488506 -409.649149) (xy 58.515758 -409.64866)
			(xy 59.379358 -409.64866) (xy 59.406611 -409.649184) (xy 59.460561 -409.656936) (xy 59.51286 -409.672287)
			(xy 59.562441 -409.694925) (xy 59.608296 -409.72439) (xy 59.64949 -409.76008) (xy 59.685185 -409.801271)
			(xy 59.714655 -409.847122) (xy 59.737298 -409.896701) (xy 59.752655 -409.948997) (xy 59.760413 -410.002948)
			(xy 59.760413 -410.057452) (xy 59.760413 -410.057453) (xy 61.197946 -410.057453) (xy 61.197946 -410.002947)
			(xy 61.205703 -409.948994) (xy 61.221059 -409.896695) (xy 61.243702 -409.847114) (xy 61.273171 -409.80126)
			(xy 61.308865 -409.760066) (xy 61.350059 -409.724372) (xy 61.395913 -409.694903) (xy 61.445494 -409.67226)
			(xy 61.497793 -409.656903) (xy 61.551745 -409.649146) (xy 61.578998 -409.64866) (xy 62.442598 -409.64866)
			(xy 62.469849 -409.649187) (xy 62.523795 -409.656943) (xy 62.576089 -409.672298) (xy 62.625665 -409.694938)
			(xy 62.671515 -409.724404) (xy 62.712704 -409.760094) (xy 62.748395 -409.801284) (xy 62.777861 -409.847133)
			(xy 62.800502 -409.896709) (xy 62.815856 -409.949003) (xy 62.823613 -410.002949) (xy 62.823613 -410.057451)
			(xy 62.823612 -410.057457) (xy 64.261123 -410.057457) (xy 64.261123 -410.002943) (xy 64.268882 -409.948984)
			(xy 64.284241 -409.896679) (xy 64.306888 -409.847092) (xy 64.336362 -409.801233) (xy 64.372063 -409.760036)
			(xy 64.413264 -409.724339) (xy 64.459125 -409.69487) (xy 64.508715 -409.672228) (xy 64.561021 -409.656874)
			(xy 64.614981 -409.64912) (xy 64.642238 -409.64866) (xy 65.505838 -409.64866) (xy 65.533085 -409.649213)
			(xy 65.587024 -409.656973) (xy 65.63931 -409.67233) (xy 65.688878 -409.694972) (xy 65.73472 -409.724436)
			(xy 65.775902 -409.760125) (xy 65.811586 -409.801311) (xy 65.841047 -409.847155) (xy 65.863683 -409.896726)
			(xy 65.879035 -409.949013) (xy 65.88679 -410.002953) (xy 65.88679 -410.057447) (xy 65.886789 -410.057453)
			(xy 67.324446 -410.057453) (xy 67.324446 -410.002947) (xy 67.332202 -409.948997) (xy 67.347558 -409.8967)
			(xy 67.370199 -409.84712) (xy 67.399666 -409.801267) (xy 67.435358 -409.760074) (xy 67.476549 -409.724379)
			(xy 67.522401 -409.69491) (xy 67.571979 -409.672265) (xy 67.624276 -409.656907) (xy 67.678225 -409.649147)
			(xy 67.705478 -409.64866) (xy 68.569078 -409.64866) (xy 68.59633 -409.649186) (xy 68.650278 -409.65694)
			(xy 68.702574 -409.672292) (xy 68.752153 -409.694932) (xy 68.798005 -409.724397) (xy 68.839197 -409.760087)
			(xy 68.87489 -409.801277) (xy 68.904358 -409.847127) (xy 68.927 -409.896705) (xy 68.942356 -409.949)
			(xy 68.950113 -410.002948) (xy 68.950113 -410.057452) (xy 68.950112 -410.057456) (xy 70.387623 -410.057456)
			(xy 70.387623 -410.002944) (xy 70.395381 -409.948987) (xy 70.410739 -409.896683) (xy 70.433385 -409.847098)
			(xy 70.462857 -409.80124) (xy 70.498556 -409.760043) (xy 70.539754 -409.724346) (xy 70.585613 -409.694876)
			(xy 70.6352 -409.672233) (xy 70.687505 -409.656877) (xy 70.741462 -409.649122) (xy 70.768718 -409.64866)
			(xy 71.632318 -409.64866) (xy 71.659566 -409.649211) (xy 71.713507 -409.656969) (xy 71.765795 -409.672325)
			(xy 71.815366 -409.694965) (xy 71.86121 -409.724429) (xy 71.902395 -409.760118) (xy 71.938082 -409.801304)
			(xy 71.967544 -409.84715) (xy 71.990182 -409.896721) (xy 72.005534 -409.94901) (xy 72.01329 -410.002952)
			(xy 72.01329 -410.057448) (xy 72.013289 -410.057452) (xy 73.450946 -410.057452) (xy 73.450946 -410.002948)
			(xy 73.458702 -409.949) (xy 73.474056 -409.896704) (xy 73.496696 -409.847125) (xy 73.526161 -409.801273)
			(xy 73.561851 -409.760081) (xy 73.60304 -409.724386) (xy 73.648889 -409.694916) (xy 73.698465 -409.672271)
			(xy 73.750759 -409.656911) (xy 73.804706 -409.649149) (xy 73.831958 -409.64866) (xy 74.695558 -409.64866)
			(xy 74.722811 -409.649184) (xy 74.776761 -409.656936) (xy 74.82906 -409.672287) (xy 74.878641 -409.694925)
			(xy 74.924496 -409.72439) (xy 74.96569 -409.76008) (xy 75.001385 -409.801271) (xy 75.030855 -409.847122)
			(xy 75.053498 -409.896701) (xy 75.068855 -409.948997) (xy 75.076613 -410.002948) (xy 75.076613 -410.057452)
			(xy 75.076613 -410.057453) (xy 76.514146 -410.057453) (xy 76.514146 -410.002947) (xy 76.521903 -409.948994)
			(xy 76.537259 -409.896695) (xy 76.559902 -409.847114) (xy 76.589371 -409.80126) (xy 76.625065 -409.760066)
			(xy 76.666259 -409.724372) (xy 76.712113 -409.694903) (xy 76.761694 -409.67226) (xy 76.813993 -409.656903)
			(xy 76.867945 -409.649146) (xy 76.895198 -409.64866) (xy 77.758798 -409.64866) (xy 77.786049 -409.649187)
			(xy 77.839995 -409.656943) (xy 77.892289 -409.672298) (xy 77.941865 -409.694938) (xy 77.987715 -409.724404)
			(xy 78.028904 -409.760094) (xy 78.064595 -409.801284) (xy 78.094061 -409.847133) (xy 78.116702 -409.896709)
			(xy 78.132056 -409.949003) (xy 78.139813 -410.002949) (xy 78.139813 -410.057451) (xy 78.139812 -410.057457)
			(xy 79.577323 -410.057457) (xy 79.577323 -410.002943) (xy 79.585082 -409.948984) (xy 79.600441 -409.896679)
			(xy 79.623088 -409.847092) (xy 79.652562 -409.801233) (xy 79.688263 -409.760036) (xy 79.729464 -409.724339)
			(xy 79.775325 -409.69487) (xy 79.824915 -409.672228) (xy 79.877221 -409.656874) (xy 79.931181 -409.64912)
			(xy 79.958438 -409.64866) (xy 80.822038 -409.64866) (xy 80.849285 -409.649213) (xy 80.903224 -409.656973)
			(xy 80.95551 -409.67233) (xy 81.005078 -409.694972) (xy 81.05092 -409.724436) (xy 81.092102 -409.760125)
			(xy 81.127786 -409.801311) (xy 81.157247 -409.847155) (xy 81.179883 -409.896726) (xy 81.195235 -409.949013)
			(xy 81.20299 -410.002953) (xy 81.20299 -410.057447) (xy 81.202989 -410.057453) (xy 82.640646 -410.057453)
			(xy 82.640646 -410.002947) (xy 82.648402 -409.948997) (xy 82.663758 -409.8967) (xy 82.686399 -409.84712)
			(xy 82.715866 -409.801267) (xy 82.751558 -409.760074) (xy 82.792749 -409.724379) (xy 82.838601 -409.69491)
			(xy 82.888179 -409.672265) (xy 82.940476 -409.656907) (xy 82.994425 -409.649147) (xy 83.021678 -409.64866)
			(xy 83.885278 -409.64866) (xy 83.91253 -409.649186) (xy 83.966478 -409.65694) (xy 84.018774 -409.672292)
			(xy 84.068353 -409.694932) (xy 84.114205 -409.724397) (xy 84.155397 -409.760087) (xy 84.19109 -409.801277)
			(xy 84.220558 -409.847127) (xy 84.2432 -409.896705) (xy 84.258556 -409.949) (xy 84.266313 -410.002948)
			(xy 84.266313 -410.057452) (xy 84.266312 -410.057456) (xy 85.703823 -410.057456) (xy 85.703823 -410.002944)
			(xy 85.711581 -409.948987) (xy 85.726939 -409.896683) (xy 85.749585 -409.847098) (xy 85.779057 -409.80124)
			(xy 85.814756 -409.760043) (xy 85.855954 -409.724346) (xy 85.901813 -409.694876) (xy 85.9514 -409.672233)
			(xy 86.003705 -409.656877) (xy 86.057662 -409.649122) (xy 86.084918 -409.64866) (xy 86.948518 -409.64866)
			(xy 86.975766 -409.649211) (xy 87.029707 -409.656969) (xy 87.081995 -409.672325) (xy 87.131566 -409.694965)
			(xy 87.17741 -409.724429) (xy 87.218595 -409.760118) (xy 87.254282 -409.801304) (xy 87.283744 -409.84715)
			(xy 87.306382 -409.896721) (xy 87.321734 -409.94901) (xy 87.32949 -410.002952) (xy 87.32949 -410.057448)
			(xy 87.329489 -410.057452) (xy 88.767146 -410.057452) (xy 88.767146 -410.002948) (xy 88.774902 -409.949)
			(xy 88.790256 -409.896704) (xy 88.812896 -409.847125) (xy 88.842361 -409.801273) (xy 88.878051 -409.760081)
			(xy 88.91924 -409.724386) (xy 88.965089 -409.694916) (xy 89.014665 -409.672271) (xy 89.066959 -409.656911)
			(xy 89.120906 -409.649149) (xy 89.148158 -409.64866) (xy 90.011758 -409.64866) (xy 90.039011 -409.649184)
			(xy 90.092961 -409.656936) (xy 90.14526 -409.672287) (xy 90.194841 -409.694925) (xy 90.240696 -409.72439)
			(xy 90.28189 -409.76008) (xy 90.317585 -409.801271) (xy 90.347055 -409.847122) (xy 90.369698 -409.896701)
			(xy 90.385055 -409.948997) (xy 90.392813 -410.002948) (xy 90.392813 -410.057452) (xy 90.392813 -410.057453)
			(xy 91.830346 -410.057453) (xy 91.830346 -410.002947) (xy 91.838103 -409.948994) (xy 91.853459 -409.896695)
			(xy 91.876102 -409.847114) (xy 91.905571 -409.80126) (xy 91.941265 -409.760066) (xy 91.982459 -409.724372)
			(xy 92.028313 -409.694903) (xy 92.077894 -409.67226) (xy 92.130193 -409.656903) (xy 92.184145 -409.649146)
			(xy 92.211398 -409.64866) (xy 93.074998 -409.64866) (xy 93.102249 -409.649187) (xy 93.156195 -409.656943)
			(xy 93.208489 -409.672298) (xy 93.258065 -409.694938) (xy 93.303915 -409.724404) (xy 93.345104 -409.760094)
			(xy 93.380795 -409.801284) (xy 93.410261 -409.847133) (xy 93.432902 -409.896709) (xy 93.448256 -409.949003)
			(xy 93.456013 -410.002949) (xy 93.456013 -410.057451) (xy 93.456012 -410.057457) (xy 94.893523 -410.057457)
			(xy 94.893523 -410.002943) (xy 94.901282 -409.948984) (xy 94.916641 -409.896679) (xy 94.939288 -409.847092)
			(xy 94.968762 -409.801233) (xy 95.004463 -409.760036) (xy 95.045664 -409.724339) (xy 95.091525 -409.69487)
			(xy 95.141115 -409.672228) (xy 95.193421 -409.656874) (xy 95.247381 -409.64912) (xy 95.274638 -409.64866)
			(xy 96.138238 -409.64866) (xy 96.165485 -409.649213) (xy 96.219424 -409.656973) (xy 96.27171 -409.67233)
			(xy 96.321278 -409.694972) (xy 96.36712 -409.724436) (xy 96.408302 -409.760125) (xy 96.443986 -409.801311)
			(xy 96.473447 -409.847155) (xy 96.496083 -409.896726) (xy 96.511435 -409.949013) (xy 96.514631 -409.97124)
			(xy 102.064312 -409.97124) (xy 102.064312 -409.71724) (xy 102.064751 -409.705132) (xy 102.07224 -409.682104)
			(xy 102.086496 -409.662529) (xy 102.106114 -409.648334) (xy 102.129165 -409.640914) (xy 102.141274 -409.640532)
			(xy 102.471474 -409.640532) (xy 102.483561 -409.641029) (xy 102.50656 -409.648478) (xy 102.526139 -409.662657)
			(xy 102.540391 -409.682184) (xy 102.547925 -409.705154) (xy 102.548436 -409.71724) (xy 102.548436 -409.97124)
			(xy 102.861364 -409.97124) (xy 102.861364 -409.71724) (xy 102.86185 -409.705137) (xy 102.869334 -409.682117)
			(xy 102.883579 -409.662546) (xy 102.903184 -409.648349) (xy 102.926222 -409.640921) (xy 102.938326 -409.640532)
			(xy 103.268526 -409.640532) (xy 103.280616 -409.640985) (xy 103.303616 -409.648448) (xy 103.323195 -409.662638)
			(xy 103.337445 -409.682174) (xy 103.344978 -409.705151) (xy 103.345488 -409.71724) (xy 103.345488 -409.97124)
			(xy 103.345118 -409.983352) (xy 103.337606 -410.006383) (xy 103.323333 -410.025956) (xy 103.303701 -410.040149)
			(xy 103.28064 -410.047567) (xy 103.268526 -410.047948) (xy 102.938326 -410.047948) (xy 102.926237 -410.04747)
			(xy 102.903235 -410.040019) (xy 102.883653 -410.025836) (xy 102.869402 -410.006304) (xy 102.861872 -409.983328)
			(xy 102.861364 -409.97124) (xy 102.548436 -409.97124) (xy 102.548018 -409.983347) (xy 102.540512 -410.00637)
			(xy 102.52625 -410.025939) (xy 102.506631 -410.040134) (xy 102.483583 -410.04756) (xy 102.471474 -410.047948)
			(xy 102.141274 -410.047948) (xy 102.129182 -410.047515) (xy 102.106178 -410.040049) (xy 102.086598 -410.025854)
			(xy 102.072349 -410.006313) (xy 102.064819 -409.983331) (xy 102.064312 -409.97124) (xy 96.514631 -409.97124)
			(xy 96.51919 -410.002953) (xy 96.51919 -410.057447) (xy 96.519189 -410.057451) (xy 121.120146 -410.057451)
			(xy 121.120146 -410.002949) (xy 121.127902 -409.949) (xy 121.143256 -409.896705) (xy 121.165895 -409.847127)
			(xy 121.19536 -409.801275) (xy 121.231049 -409.760082) (xy 121.272238 -409.724388) (xy 121.318086 -409.694918)
			(xy 121.367662 -409.672272) (xy 121.419955 -409.656911) (xy 121.473903 -409.649149) (xy 121.501154 -409.64866)
			(xy 122.364754 -409.64866) (xy 122.392007 -409.649184) (xy 122.445958 -409.656935) (xy 122.498257 -409.672286)
			(xy 122.547839 -409.694924) (xy 122.593694 -409.724388) (xy 122.634889 -409.760079) (xy 122.670584 -409.801269)
			(xy 122.700054 -409.847121) (xy 122.722698 -409.8967) (xy 122.738055 -409.948997) (xy 122.745813 -410.002947)
			(xy 122.745813 -410.057453) (xy 124.183346 -410.057453) (xy 124.183346 -410.002947) (xy 124.191103 -409.948995)
			(xy 124.206459 -409.896696) (xy 124.229102 -409.847115) (xy 124.25857 -409.801261) (xy 124.294264 -409.760068)
			(xy 124.335457 -409.724373) (xy 124.38131 -409.694904) (xy 124.430891 -409.672261) (xy 124.483189 -409.656904)
			(xy 124.537141 -409.649146) (xy 124.564394 -409.64866) (xy 125.427994 -409.64866) (xy 125.455245 -409.649187)
			(xy 125.509192 -409.656942) (xy 125.561486 -409.672297) (xy 125.611063 -409.694937) (xy 125.656913 -409.724402)
			(xy 125.698103 -409.760093) (xy 125.733794 -409.801282) (xy 125.76326 -409.847132) (xy 125.785901 -409.896708)
			(xy 125.801256 -409.949002) (xy 125.809013 -410.002949) (xy 125.809013 -410.057451) (xy 125.809012 -410.057457)
			(xy 127.246523 -410.057457) (xy 127.246523 -410.002943) (xy 127.254282 -409.948985) (xy 127.269641 -409.89668)
			(xy 127.292287 -409.847093) (xy 127.321761 -409.801235) (xy 127.357462 -409.760037) (xy 127.398662 -409.724341)
			(xy 127.444523 -409.694871) (xy 127.494112 -409.672229) (xy 127.546418 -409.656874) (xy 127.600377 -409.649121)
			(xy 127.627634 -409.64866) (xy 128.491234 -409.64866) (xy 128.518481 -409.649213) (xy 128.572421 -409.656972)
			(xy 128.624707 -409.672329) (xy 128.674276 -409.69497) (xy 128.720118 -409.724435) (xy 128.761301 -409.760123)
			(xy 128.796985 -409.801309) (xy 128.826446 -409.847154) (xy 128.849083 -409.896725) (xy 128.864435 -409.949012)
			(xy 128.87219 -410.002953) (xy 128.87219 -410.057447) (xy 128.872189 -410.057452) (xy 130.309846 -410.057452)
			(xy 130.309846 -410.002948) (xy 130.317602 -409.948998) (xy 130.332957 -409.896701) (xy 130.355599 -409.847121)
			(xy 130.385065 -409.801268) (xy 130.420757 -409.760075) (xy 130.461947 -409.72438) (xy 130.507798 -409.694911)
			(xy 130.557376 -409.672266) (xy 130.609672 -409.656908) (xy 130.663622 -409.649148) (xy 130.690874 -409.64866)
			(xy 131.554474 -409.64866) (xy 131.581726 -409.649185) (xy 131.635675 -409.656939) (xy 131.687972 -409.672291)
			(xy 131.737551 -409.69493) (xy 131.783403 -409.724395) (xy 131.824596 -409.760086) (xy 131.860289 -409.801276)
			(xy 131.889757 -409.847126) (xy 131.9124 -409.896704) (xy 131.927756 -409.949) (xy 131.935513 -410.002948)
			(xy 131.935513 -410.057452) (xy 131.935512 -410.057456) (xy 133.373023 -410.057456) (xy 133.373023 -410.002944)
			(xy 133.380781 -409.948987) (xy 133.396139 -409.896684) (xy 133.418784 -409.847099) (xy 133.448256 -409.801241)
			(xy 133.483954 -409.760045) (xy 133.525152 -409.724348) (xy 133.571011 -409.694878) (xy 133.620597 -409.672234)
			(xy 133.672901 -409.656878) (xy 133.726858 -409.649122) (xy 133.754114 -409.64866) (xy 134.617714 -409.64866)
			(xy 134.644962 -409.649211) (xy 134.698904 -409.656969) (xy 134.751193 -409.672324) (xy 134.800764 -409.694964)
			(xy 134.846609 -409.724428) (xy 134.887794 -409.760116) (xy 134.923481 -409.801303) (xy 134.952943 -409.847149)
			(xy 134.975581 -409.896721) (xy 134.990934 -409.94901) (xy 134.99869 -410.002952) (xy 134.99869 -410.057448)
			(xy 134.99869 -410.057451) (xy 136.436346 -410.057451) (xy 136.436346 -410.002949) (xy 136.444102 -409.949)
			(xy 136.459456 -409.896705) (xy 136.482095 -409.847127) (xy 136.51156 -409.801275) (xy 136.547249 -409.760082)
			(xy 136.588438 -409.724388) (xy 136.634286 -409.694918) (xy 136.683862 -409.672272) (xy 136.736155 -409.656911)
			(xy 136.790103 -409.649149) (xy 136.817354 -409.64866) (xy 137.680954 -409.64866) (xy 137.708207 -409.649184)
			(xy 137.762158 -409.656935) (xy 137.814457 -409.672286) (xy 137.864039 -409.694924) (xy 137.909894 -409.724388)
			(xy 137.951089 -409.760079) (xy 137.986784 -409.801269) (xy 138.016254 -409.847121) (xy 138.038898 -409.8967)
			(xy 138.054255 -409.948997) (xy 138.062013 -410.002947) (xy 138.062013 -410.057453) (xy 139.499546 -410.057453)
			(xy 139.499546 -410.002947) (xy 139.507303 -409.948995) (xy 139.522659 -409.896696) (xy 139.545302 -409.847115)
			(xy 139.57477 -409.801261) (xy 139.610464 -409.760068) (xy 139.651657 -409.724373) (xy 139.69751 -409.694904)
			(xy 139.747091 -409.672261) (xy 139.799389 -409.656904) (xy 139.853341 -409.649146) (xy 139.880594 -409.64866)
			(xy 140.744194 -409.64866) (xy 140.771445 -409.649187) (xy 140.825392 -409.656942) (xy 140.877686 -409.672297)
			(xy 140.927263 -409.694937) (xy 140.973113 -409.724402) (xy 141.014303 -409.760093) (xy 141.049994 -409.801282)
			(xy 141.07946 -409.847132) (xy 141.102101 -409.896708) (xy 141.117456 -409.949002) (xy 141.125213 -410.002949)
			(xy 141.125213 -410.057451) (xy 141.125212 -410.057457) (xy 142.562723 -410.057457) (xy 142.562723 -410.002943)
			(xy 142.570482 -409.948985) (xy 142.585841 -409.89668) (xy 142.608487 -409.847093) (xy 142.637961 -409.801235)
			(xy 142.673662 -409.760037) (xy 142.714862 -409.724341) (xy 142.760723 -409.694871) (xy 142.810312 -409.672229)
			(xy 142.862618 -409.656874) (xy 142.916577 -409.649121) (xy 142.943834 -409.64866) (xy 143.807434 -409.64866)
			(xy 143.834681 -409.649213) (xy 143.888621 -409.656972) (xy 143.940907 -409.672329) (xy 143.990476 -409.69497)
			(xy 144.036318 -409.724435) (xy 144.077501 -409.760123) (xy 144.113185 -409.801309) (xy 144.142646 -409.847154)
			(xy 144.165283 -409.896725) (xy 144.180635 -409.949012) (xy 144.18839 -410.002953) (xy 144.18839 -410.057447)
			(xy 144.188389 -410.057452) (xy 145.626046 -410.057452) (xy 145.626046 -410.002948) (xy 145.633802 -409.948998)
			(xy 145.649157 -409.896701) (xy 145.671799 -409.847121) (xy 145.701265 -409.801268) (xy 145.736957 -409.760075)
			(xy 145.778147 -409.72438) (xy 145.823998 -409.694911) (xy 145.873576 -409.672266) (xy 145.925872 -409.656908)
			(xy 145.979822 -409.649148) (xy 146.007074 -409.64866) (xy 146.870674 -409.64866) (xy 146.897926 -409.649185)
			(xy 146.951875 -409.656939) (xy 147.004172 -409.672291) (xy 147.053751 -409.69493) (xy 147.099603 -409.724395)
			(xy 147.140796 -409.760086) (xy 147.176489 -409.801276) (xy 147.205957 -409.847126) (xy 147.2286 -409.896704)
			(xy 147.243956 -409.949) (xy 147.251713 -410.002948) (xy 147.251713 -410.057452) (xy 147.251712 -410.057456)
			(xy 148.689223 -410.057456) (xy 148.689223 -410.002944) (xy 148.696981 -409.948987) (xy 148.712339 -409.896684)
			(xy 148.734984 -409.847099) (xy 148.764456 -409.801241) (xy 148.800154 -409.760045) (xy 148.841352 -409.724348)
			(xy 148.887211 -409.694878) (xy 148.936797 -409.672234) (xy 148.989101 -409.656878) (xy 149.043058 -409.649122)
			(xy 149.070314 -409.64866) (xy 149.933914 -409.64866) (xy 149.961162 -409.649211) (xy 150.015104 -409.656969)
			(xy 150.067393 -409.672324) (xy 150.116964 -409.694964) (xy 150.162809 -409.724428) (xy 150.203994 -409.760116)
			(xy 150.239681 -409.801303) (xy 150.269143 -409.847149) (xy 150.291781 -409.896721) (xy 150.307134 -409.94901)
			(xy 150.31489 -410.002952) (xy 150.31489 -410.057448) (xy 150.31489 -410.057451) (xy 151.752546 -410.057451)
			(xy 151.752546 -410.002949) (xy 151.760302 -409.949) (xy 151.775656 -409.896705) (xy 151.798295 -409.847127)
			(xy 151.82776 -409.801275) (xy 151.863449 -409.760082) (xy 151.904638 -409.724388) (xy 151.950486 -409.694918)
			(xy 152.000062 -409.672272) (xy 152.052355 -409.656911) (xy 152.106303 -409.649149) (xy 152.133554 -409.64866)
			(xy 152.997154 -409.64866) (xy 153.024407 -409.649184) (xy 153.078358 -409.656935) (xy 153.130657 -409.672286)
			(xy 153.180239 -409.694924) (xy 153.226094 -409.724388) (xy 153.267289 -409.760079) (xy 153.302984 -409.801269)
			(xy 153.332454 -409.847121) (xy 153.355098 -409.8967) (xy 153.370455 -409.948997) (xy 153.378213 -410.002947)
			(xy 153.378213 -410.057453) (xy 154.815746 -410.057453) (xy 154.815746 -410.002947) (xy 154.823503 -409.948995)
			(xy 154.838859 -409.896696) (xy 154.861502 -409.847115) (xy 154.89097 -409.801261) (xy 154.926664 -409.760068)
			(xy 154.967857 -409.724373) (xy 155.01371 -409.694904) (xy 155.063291 -409.672261) (xy 155.115589 -409.656904)
			(xy 155.169541 -409.649146) (xy 155.196794 -409.64866) (xy 156.060394 -409.64866) (xy 156.087645 -409.649187)
			(xy 156.141592 -409.656942) (xy 156.193886 -409.672297) (xy 156.243463 -409.694937) (xy 156.289313 -409.724402)
			(xy 156.330503 -409.760093) (xy 156.366194 -409.801282) (xy 156.39566 -409.847132) (xy 156.418301 -409.896708)
			(xy 156.433656 -409.949002) (xy 156.441413 -410.002949) (xy 156.441413 -410.057451) (xy 156.441412 -410.057457)
			(xy 157.878923 -410.057457) (xy 157.878923 -410.002943) (xy 157.886682 -409.948985) (xy 157.902041 -409.89668)
			(xy 157.924687 -409.847093) (xy 157.954161 -409.801235) (xy 157.989862 -409.760037) (xy 158.031062 -409.724341)
			(xy 158.076923 -409.694871) (xy 158.126512 -409.672229) (xy 158.178818 -409.656874) (xy 158.232777 -409.649121)
			(xy 158.260034 -409.64866) (xy 159.123634 -409.64866) (xy 159.150881 -409.649213) (xy 159.204821 -409.656972)
			(xy 159.257107 -409.672329) (xy 159.306676 -409.69497) (xy 159.352518 -409.724435) (xy 159.393701 -409.760123)
			(xy 159.429385 -409.801309) (xy 159.458846 -409.847154) (xy 159.481483 -409.896725) (xy 159.496835 -409.949012)
			(xy 159.50459 -410.002953) (xy 159.50459 -410.057447) (xy 159.504589 -410.057452) (xy 160.942246 -410.057452)
			(xy 160.942246 -410.002948) (xy 160.950002 -409.948998) (xy 160.965357 -409.896701) (xy 160.987999 -409.847121)
			(xy 161.017465 -409.801268) (xy 161.053157 -409.760075) (xy 161.094347 -409.72438) (xy 161.140198 -409.694911)
			(xy 161.189776 -409.672266) (xy 161.242072 -409.656908) (xy 161.296022 -409.649148) (xy 161.323274 -409.64866)
			(xy 162.186874 -409.64866) (xy 162.214126 -409.649185) (xy 162.268075 -409.656939) (xy 162.320372 -409.672291)
			(xy 162.369951 -409.69493) (xy 162.415803 -409.724395) (xy 162.456996 -409.760086) (xy 162.492689 -409.801276)
			(xy 162.522157 -409.847126) (xy 162.5448 -409.896704) (xy 162.560156 -409.949) (xy 162.567913 -410.002948)
			(xy 162.567913 -410.057452) (xy 162.567912 -410.057456) (xy 164.005423 -410.057456) (xy 164.005423 -410.002944)
			(xy 164.013181 -409.948987) (xy 164.028539 -409.896684) (xy 164.051184 -409.847099) (xy 164.080656 -409.801241)
			(xy 164.116354 -409.760045) (xy 164.157552 -409.724348) (xy 164.203411 -409.694878) (xy 164.252997 -409.672234)
			(xy 164.305301 -409.656878) (xy 164.359258 -409.649122) (xy 164.386514 -409.64866) (xy 165.250114 -409.64866)
			(xy 165.277362 -409.649211) (xy 165.331304 -409.656969) (xy 165.383593 -409.672324) (xy 165.433164 -409.694964)
			(xy 165.479009 -409.724428) (xy 165.520194 -409.760116) (xy 165.555881 -409.801303) (xy 165.585343 -409.847149)
			(xy 165.607981 -409.896721) (xy 165.623334 -409.94901) (xy 165.63109 -410.002952) (xy 165.63109 -410.057448)
			(xy 165.63109 -410.057451) (xy 167.068746 -410.057451) (xy 167.068746 -410.002949) (xy 167.076502 -409.949)
			(xy 167.091856 -409.896705) (xy 167.114495 -409.847127) (xy 167.14396 -409.801275) (xy 167.179649 -409.760082)
			(xy 167.220838 -409.724388) (xy 167.266686 -409.694918) (xy 167.316262 -409.672272) (xy 167.368555 -409.656911)
			(xy 167.422503 -409.649149) (xy 167.449754 -409.64866) (xy 168.313354 -409.64866) (xy 168.340607 -409.649184)
			(xy 168.394558 -409.656935) (xy 168.446857 -409.672286) (xy 168.496439 -409.694924) (xy 168.542294 -409.724388)
			(xy 168.583489 -409.760079) (xy 168.619184 -409.801269) (xy 168.648654 -409.847121) (xy 168.671298 -409.8967)
			(xy 168.686655 -409.948997) (xy 168.694413 -410.002947) (xy 168.694413 -410.057453) (xy 168.686655 -410.111403)
			(xy 168.671298 -410.1637) (xy 168.648654 -410.213279) (xy 168.619184 -410.259131) (xy 168.583489 -410.300321)
			(xy 168.542294 -410.336012) (xy 168.496439 -410.365476) (xy 168.446857 -410.388114) (xy 168.394558 -410.403465)
			(xy 168.340607 -410.411216) (xy 168.313354 -410.411676) (xy 167.449754 -410.411676) (xy 167.422503 -410.411251)
			(xy 167.368555 -410.403489) (xy 167.316262 -410.388128) (xy 167.266686 -410.365482) (xy 167.220838 -410.336012)
			(xy 167.179649 -410.300318) (xy 167.14396 -410.259125) (xy 167.114495 -410.213273) (xy 167.091856 -410.163695)
			(xy 167.076502 -410.1114) (xy 167.068746 -410.057451) (xy 165.63109 -410.057451) (xy 165.623334 -410.11139)
			(xy 165.607981 -410.163679) (xy 165.585343 -410.213251) (xy 165.555881 -410.259097) (xy 165.520194 -410.300284)
			(xy 165.479009 -410.335972) (xy 165.433164 -410.365436) (xy 165.383593 -410.388076) (xy 165.331304 -410.403431)
			(xy 165.277362 -410.411189) (xy 165.250114 -410.411676) (xy 164.386514 -410.411676) (xy 164.359258 -410.411278)
			(xy 164.305301 -410.403522) (xy 164.252997 -410.388166) (xy 164.203411 -410.365522) (xy 164.157552 -410.336052)
			(xy 164.116354 -410.300355) (xy 164.080656 -410.259159) (xy 164.051184 -410.213301) (xy 164.028539 -410.163716)
			(xy 164.013181 -410.111413) (xy 164.005423 -410.057456) (xy 162.567912 -410.057456) (xy 162.560156 -410.1114)
			(xy 162.5448 -410.163696) (xy 162.522157 -410.213274) (xy 162.492689 -410.259124) (xy 162.456996 -410.300314)
			(xy 162.415803 -410.336005) (xy 162.369951 -410.36547) (xy 162.320372 -410.388109) (xy 162.268075 -410.403461)
			(xy 162.214126 -410.411215) (xy 162.186874 -410.411676) (xy 161.323274 -410.411676) (xy 161.296022 -410.411252)
			(xy 161.242072 -410.403492) (xy 161.189776 -410.388134) (xy 161.140198 -410.365489) (xy 161.094347 -410.33602)
			(xy 161.053157 -410.300325) (xy 161.017465 -410.259132) (xy 160.987999 -410.213279) (xy 160.965357 -410.163699)
			(xy 160.950002 -410.111402) (xy 160.942246 -410.057452) (xy 159.504589 -410.057452) (xy 159.496835 -410.111388)
			(xy 159.481483 -410.163675) (xy 159.458846 -410.213246) (xy 159.429385 -410.259091) (xy 159.393701 -410.300277)
			(xy 159.352518 -410.335965) (xy 159.306676 -410.36543) (xy 159.257107 -410.388071) (xy 159.204821 -410.403428)
			(xy 159.150881 -410.411187) (xy 159.123634 -410.411676) (xy 158.260034 -410.411676) (xy 158.232777 -410.411279)
			(xy 158.178818 -410.403526) (xy 158.126512 -410.388171) (xy 158.076923 -410.365529) (xy 158.031062 -410.336059)
			(xy 157.989862 -410.300363) (xy 157.954161 -410.259165) (xy 157.924687 -410.213307) (xy 157.902041 -410.16372)
			(xy 157.886682 -410.111415) (xy 157.878923 -410.057457) (xy 156.441412 -410.057457) (xy 156.433656 -410.111398)
			(xy 156.418301 -410.163692) (xy 156.39566 -410.213268) (xy 156.366194 -410.259118) (xy 156.330503 -410.300307)
			(xy 156.289313 -410.335998) (xy 156.243463 -410.365463) (xy 156.193886 -410.388103) (xy 156.141592 -410.403458)
			(xy 156.087645 -410.411213) (xy 156.060394 -410.411676) (xy 155.196794 -410.411676) (xy 155.169541 -410.411254)
			(xy 155.115589 -410.403496) (xy 155.063291 -410.388139) (xy 155.01371 -410.365496) (xy 154.967857 -410.336027)
			(xy 154.926664 -410.300332) (xy 154.89097 -410.259139) (xy 154.861502 -410.213285) (xy 154.838859 -410.163704)
			(xy 154.823503 -410.111405) (xy 154.815746 -410.057453) (xy 153.378213 -410.057453) (xy 153.370455 -410.111403)
			(xy 153.355098 -410.1637) (xy 153.332454 -410.213279) (xy 153.302984 -410.259131) (xy 153.267289 -410.300321)
			(xy 153.226094 -410.336012) (xy 153.180239 -410.365476) (xy 153.130657 -410.388114) (xy 153.078358 -410.403465)
			(xy 153.024407 -410.411216) (xy 152.997154 -410.411676) (xy 152.133554 -410.411676) (xy 152.106303 -410.411251)
			(xy 152.052355 -410.403489) (xy 152.000062 -410.388128) (xy 151.950486 -410.365482) (xy 151.904638 -410.336012)
			(xy 151.863449 -410.300318) (xy 151.82776 -410.259125) (xy 151.798295 -410.213273) (xy 151.775656 -410.163695)
			(xy 151.760302 -410.1114) (xy 151.752546 -410.057451) (xy 150.31489 -410.057451) (xy 150.307134 -410.11139)
			(xy 150.291781 -410.163679) (xy 150.269143 -410.213251) (xy 150.239681 -410.259097) (xy 150.203994 -410.300284)
			(xy 150.162809 -410.335972) (xy 150.116964 -410.365436) (xy 150.067393 -410.388076) (xy 150.015104 -410.403431)
			(xy 149.961162 -410.411189) (xy 149.933914 -410.411676) (xy 149.070314 -410.411676) (xy 149.043058 -410.411278)
			(xy 148.989101 -410.403522) (xy 148.936797 -410.388166) (xy 148.887211 -410.365522) (xy 148.841352 -410.336052)
			(xy 148.800154 -410.300355) (xy 148.764456 -410.259159) (xy 148.734984 -410.213301) (xy 148.712339 -410.163716)
			(xy 148.696981 -410.111413) (xy 148.689223 -410.057456) (xy 147.251712 -410.057456) (xy 147.243956 -410.1114)
			(xy 147.2286 -410.163696) (xy 147.205957 -410.213274) (xy 147.176489 -410.259124) (xy 147.140796 -410.300314)
			(xy 147.099603 -410.336005) (xy 147.053751 -410.36547) (xy 147.004172 -410.388109) (xy 146.951875 -410.403461)
			(xy 146.897926 -410.411215) (xy 146.870674 -410.411676) (xy 146.007074 -410.411676) (xy 145.979822 -410.411252)
			(xy 145.925872 -410.403492) (xy 145.873576 -410.388134) (xy 145.823998 -410.365489) (xy 145.778147 -410.33602)
			(xy 145.736957 -410.300325) (xy 145.701265 -410.259132) (xy 145.671799 -410.213279) (xy 145.649157 -410.163699)
			(xy 145.633802 -410.111402) (xy 145.626046 -410.057452) (xy 144.188389 -410.057452) (xy 144.180635 -410.111388)
			(xy 144.165283 -410.163675) (xy 144.142646 -410.213246) (xy 144.113185 -410.259091) (xy 144.077501 -410.300277)
			(xy 144.036318 -410.335965) (xy 143.990476 -410.36543) (xy 143.940907 -410.388071) (xy 143.888621 -410.403428)
			(xy 143.834681 -410.411187) (xy 143.807434 -410.411676) (xy 142.943834 -410.411676) (xy 142.916577 -410.411279)
			(xy 142.862618 -410.403526) (xy 142.810312 -410.388171) (xy 142.760723 -410.365529) (xy 142.714862 -410.336059)
			(xy 142.673662 -410.300363) (xy 142.637961 -410.259165) (xy 142.608487 -410.213307) (xy 142.585841 -410.16372)
			(xy 142.570482 -410.111415) (xy 142.562723 -410.057457) (xy 141.125212 -410.057457) (xy 141.117456 -410.111398)
			(xy 141.102101 -410.163692) (xy 141.07946 -410.213268) (xy 141.049994 -410.259118) (xy 141.014303 -410.300307)
			(xy 140.973113 -410.335998) (xy 140.927263 -410.365463) (xy 140.877686 -410.388103) (xy 140.825392 -410.403458)
			(xy 140.771445 -410.411213) (xy 140.744194 -410.411676) (xy 139.880594 -410.411676) (xy 139.853341 -410.411254)
			(xy 139.799389 -410.403496) (xy 139.747091 -410.388139) (xy 139.69751 -410.365496) (xy 139.651657 -410.336027)
			(xy 139.610464 -410.300332) (xy 139.57477 -410.259139) (xy 139.545302 -410.213285) (xy 139.522659 -410.163704)
			(xy 139.507303 -410.111405) (xy 139.499546 -410.057453) (xy 138.062013 -410.057453) (xy 138.054255 -410.111403)
			(xy 138.038898 -410.1637) (xy 138.016254 -410.213279) (xy 137.986784 -410.259131) (xy 137.951089 -410.300321)
			(xy 137.909894 -410.336012) (xy 137.864039 -410.365476) (xy 137.814457 -410.388114) (xy 137.762158 -410.403465)
			(xy 137.708207 -410.411216) (xy 137.680954 -410.411676) (xy 136.817354 -410.411676) (xy 136.790103 -410.411251)
			(xy 136.736155 -410.403489) (xy 136.683862 -410.388128) (xy 136.634286 -410.365482) (xy 136.588438 -410.336012)
			(xy 136.547249 -410.300318) (xy 136.51156 -410.259125) (xy 136.482095 -410.213273) (xy 136.459456 -410.163695)
			(xy 136.444102 -410.1114) (xy 136.436346 -410.057451) (xy 134.99869 -410.057451) (xy 134.990934 -410.11139)
			(xy 134.975581 -410.163679) (xy 134.952943 -410.213251) (xy 134.923481 -410.259097) (xy 134.887794 -410.300284)
			(xy 134.846609 -410.335972) (xy 134.800764 -410.365436) (xy 134.751193 -410.388076) (xy 134.698904 -410.403431)
			(xy 134.644962 -410.411189) (xy 134.617714 -410.411676) (xy 133.754114 -410.411676) (xy 133.726858 -410.411278)
			(xy 133.672901 -410.403522) (xy 133.620597 -410.388166) (xy 133.571011 -410.365522) (xy 133.525152 -410.336052)
			(xy 133.483954 -410.300355) (xy 133.448256 -410.259159) (xy 133.418784 -410.213301) (xy 133.396139 -410.163716)
			(xy 133.380781 -410.111413) (xy 133.373023 -410.057456) (xy 131.935512 -410.057456) (xy 131.927756 -410.1114)
			(xy 131.9124 -410.163696) (xy 131.889757 -410.213274) (xy 131.860289 -410.259124) (xy 131.824596 -410.300314)
			(xy 131.783403 -410.336005) (xy 131.737551 -410.36547) (xy 131.687972 -410.388109) (xy 131.635675 -410.403461)
			(xy 131.581726 -410.411215) (xy 131.554474 -410.411676) (xy 130.690874 -410.411676) (xy 130.663622 -410.411252)
			(xy 130.609672 -410.403492) (xy 130.557376 -410.388134) (xy 130.507798 -410.365489) (xy 130.461947 -410.33602)
			(xy 130.420757 -410.300325) (xy 130.385065 -410.259132) (xy 130.355599 -410.213279) (xy 130.332957 -410.163699)
			(xy 130.317602 -410.111402) (xy 130.309846 -410.057452) (xy 128.872189 -410.057452) (xy 128.864435 -410.111388)
			(xy 128.849083 -410.163675) (xy 128.826446 -410.213246) (xy 128.796985 -410.259091) (xy 128.761301 -410.300277)
			(xy 128.720118 -410.335965) (xy 128.674276 -410.36543) (xy 128.624707 -410.388071) (xy 128.572421 -410.403428)
			(xy 128.518481 -410.411187) (xy 128.491234 -410.411676) (xy 127.627634 -410.411676) (xy 127.600377 -410.411279)
			(xy 127.546418 -410.403526) (xy 127.494112 -410.388171) (xy 127.444523 -410.365529) (xy 127.398662 -410.336059)
			(xy 127.357462 -410.300363) (xy 127.321761 -410.259165) (xy 127.292287 -410.213307) (xy 127.269641 -410.16372)
			(xy 127.254282 -410.111415) (xy 127.246523 -410.057457) (xy 125.809012 -410.057457) (xy 125.801256 -410.111398)
			(xy 125.785901 -410.163692) (xy 125.76326 -410.213268) (xy 125.733794 -410.259118) (xy 125.698103 -410.300307)
			(xy 125.656913 -410.335998) (xy 125.611063 -410.365463) (xy 125.561486 -410.388103) (xy 125.509192 -410.403458)
			(xy 125.455245 -410.411213) (xy 125.427994 -410.411676) (xy 124.564394 -410.411676) (xy 124.537141 -410.411254)
			(xy 124.483189 -410.403496) (xy 124.430891 -410.388139) (xy 124.38131 -410.365496) (xy 124.335457 -410.336027)
			(xy 124.294264 -410.300332) (xy 124.25857 -410.259139) (xy 124.229102 -410.213285) (xy 124.206459 -410.163704)
			(xy 124.191103 -410.111405) (xy 124.183346 -410.057453) (xy 122.745813 -410.057453) (xy 122.738055 -410.111403)
			(xy 122.722698 -410.1637) (xy 122.700054 -410.213279) (xy 122.670584 -410.259131) (xy 122.634889 -410.300321)
			(xy 122.593694 -410.336012) (xy 122.547839 -410.365476) (xy 122.498257 -410.388114) (xy 122.445958 -410.403465)
			(xy 122.392007 -410.411216) (xy 122.364754 -410.411676) (xy 121.501154 -410.411676) (xy 121.473903 -410.411251)
			(xy 121.419955 -410.403489) (xy 121.367662 -410.388128) (xy 121.318086 -410.365482) (xy 121.272238 -410.336012)
			(xy 121.231049 -410.300318) (xy 121.19536 -410.259125) (xy 121.165895 -410.213273) (xy 121.143256 -410.163695)
			(xy 121.127902 -410.1114) (xy 121.120146 -410.057451) (xy 96.519189 -410.057451) (xy 96.511435 -410.111387)
			(xy 96.496083 -410.163674) (xy 96.473447 -410.213245) (xy 96.443986 -410.259089) (xy 96.408302 -410.300275)
			(xy 96.36712 -410.335964) (xy 96.321278 -410.365428) (xy 96.27171 -410.38807) (xy 96.219424 -410.403427)
			(xy 96.165485 -410.411187) (xy 96.138238 -410.411676) (xy 95.274638 -410.411676) (xy 95.247381 -410.41128)
			(xy 95.193421 -410.403526) (xy 95.141115 -410.388172) (xy 95.091525 -410.36553) (xy 95.045664 -410.336061)
			(xy 95.004463 -410.300364) (xy 94.968762 -410.259167) (xy 94.939288 -410.213308) (xy 94.916641 -410.163721)
			(xy 94.901282 -410.111416) (xy 94.893523 -410.057457) (xy 93.456012 -410.057457) (xy 93.448256 -410.111397)
			(xy 93.432902 -410.163691) (xy 93.410261 -410.213267) (xy 93.380795 -410.259116) (xy 93.345104 -410.300306)
			(xy 93.303915 -410.335996) (xy 93.258065 -410.365462) (xy 93.208489 -410.388102) (xy 93.156195 -410.403457)
			(xy 93.102249 -410.411213) (xy 93.074998 -410.411676) (xy 92.211398 -410.411676) (xy 92.184145 -410.411254)
			(xy 92.130193 -410.403497) (xy 92.077894 -410.38814) (xy 92.028313 -410.365497) (xy 91.982459 -410.336028)
			(xy 91.941265 -410.300334) (xy 91.905571 -410.25914) (xy 91.876102 -410.213286) (xy 91.853459 -410.163705)
			(xy 91.838103 -410.111406) (xy 91.830346 -410.057453) (xy 90.392813 -410.057453) (xy 90.385055 -410.111403)
			(xy 90.369698 -410.163699) (xy 90.347055 -410.213278) (xy 90.317585 -410.259129) (xy 90.28189 -410.30032)
			(xy 90.240696 -410.33601) (xy 90.194841 -410.365475) (xy 90.14526 -410.388113) (xy 90.092961 -410.403464)
			(xy 90.039011 -410.411216) (xy 90.011758 -410.411676) (xy 89.148158 -410.411676) (xy 89.120906 -410.411251)
			(xy 89.066959 -410.403489) (xy 89.014665 -410.388129) (xy 88.965089 -410.365484) (xy 88.91924 -410.336014)
			(xy 88.878051 -410.300319) (xy 88.842361 -410.259127) (xy 88.812896 -410.213275) (xy 88.790256 -410.163696)
			(xy 88.774902 -410.1114) (xy 88.767146 -410.057452) (xy 87.329489 -410.057452) (xy 87.321734 -410.11139)
			(xy 87.306382 -410.163679) (xy 87.283744 -410.21325) (xy 87.254282 -410.259096) (xy 87.218595 -410.300282)
			(xy 87.17741 -410.335971) (xy 87.131566 -410.365435) (xy 87.081995 -410.388075) (xy 87.029707 -410.403431)
			(xy 86.975766 -410.411189) (xy 86.948518 -410.411676) (xy 86.084918 -410.411676) (xy 86.057662 -410.411278)
			(xy 86.003705 -410.403523) (xy 85.9514 -410.388167) (xy 85.901813 -410.365524) (xy 85.855954 -410.336054)
			(xy 85.814756 -410.300357) (xy 85.779057 -410.25916) (xy 85.749585 -410.213302) (xy 85.726939 -410.163717)
			(xy 85.711581 -410.111413) (xy 85.703823 -410.057456) (xy 84.266312 -410.057456) (xy 84.258556 -410.1114)
			(xy 84.2432 -410.163695) (xy 84.220558 -410.213273) (xy 84.19109 -410.259123) (xy 84.155397 -410.300313)
			(xy 84.114205 -410.336003) (xy 84.068353 -410.365468) (xy 84.018774 -410.388108) (xy 83.966478 -410.40346)
			(xy 83.91253 -410.411214) (xy 83.885278 -410.411676) (xy 83.021678 -410.411676) (xy 82.994425 -410.411253)
			(xy 82.940476 -410.403493) (xy 82.888179 -410.388135) (xy 82.838601 -410.36549) (xy 82.792749 -410.336021)
			(xy 82.751558 -410.300326) (xy 82.715866 -410.259133) (xy 82.686399 -410.21328) (xy 82.663758 -410.1637)
			(xy 82.648402 -410.111403) (xy 82.640646 -410.057453) (xy 81.202989 -410.057453) (xy 81.195235 -410.111387)
			(xy 81.179883 -410.163674) (xy 81.157247 -410.213245) (xy 81.127786 -410.259089) (xy 81.092102 -410.300275)
			(xy 81.05092 -410.335964) (xy 81.005078 -410.365428) (xy 80.95551 -410.38807) (xy 80.903224 -410.403427)
			(xy 80.849285 -410.411187) (xy 80.822038 -410.411676) (xy 79.958438 -410.411676) (xy 79.931181 -410.41128)
			(xy 79.877221 -410.403526) (xy 79.824915 -410.388172) (xy 79.775325 -410.36553) (xy 79.729464 -410.336061)
			(xy 79.688263 -410.300364) (xy 79.652562 -410.259167) (xy 79.623088 -410.213308) (xy 79.600441 -410.163721)
			(xy 79.585082 -410.111416) (xy 79.577323 -410.057457) (xy 78.139812 -410.057457) (xy 78.132056 -410.111397)
			(xy 78.116702 -410.163691) (xy 78.094061 -410.213267) (xy 78.064595 -410.259116) (xy 78.028904 -410.300306)
			(xy 77.987715 -410.335996) (xy 77.941865 -410.365462) (xy 77.892289 -410.388102) (xy 77.839995 -410.403457)
			(xy 77.786049 -410.411213) (xy 77.758798 -410.411676) (xy 76.895198 -410.411676) (xy 76.867945 -410.411254)
			(xy 76.813993 -410.403497) (xy 76.761694 -410.38814) (xy 76.712113 -410.365497) (xy 76.666259 -410.336028)
			(xy 76.625065 -410.300334) (xy 76.589371 -410.25914) (xy 76.559902 -410.213286) (xy 76.537259 -410.163705)
			(xy 76.521903 -410.111406) (xy 76.514146 -410.057453) (xy 75.076613 -410.057453) (xy 75.068855 -410.111403)
			(xy 75.053498 -410.163699) (xy 75.030855 -410.213278) (xy 75.001385 -410.259129) (xy 74.96569 -410.30032)
			(xy 74.924496 -410.33601) (xy 74.878641 -410.365475) (xy 74.82906 -410.388113) (xy 74.776761 -410.403464)
			(xy 74.722811 -410.411216) (xy 74.695558 -410.411676) (xy 73.831958 -410.411676) (xy 73.804706 -410.411251)
			(xy 73.750759 -410.403489) (xy 73.698465 -410.388129) (xy 73.648889 -410.365484) (xy 73.60304 -410.336014)
			(xy 73.561851 -410.300319) (xy 73.526161 -410.259127) (xy 73.496696 -410.213275) (xy 73.474056 -410.163696)
			(xy 73.458702 -410.1114) (xy 73.450946 -410.057452) (xy 72.013289 -410.057452) (xy 72.005534 -410.11139)
			(xy 71.990182 -410.163679) (xy 71.967544 -410.21325) (xy 71.938082 -410.259096) (xy 71.902395 -410.300282)
			(xy 71.86121 -410.335971) (xy 71.815366 -410.365435) (xy 71.765795 -410.388075) (xy 71.713507 -410.403431)
			(xy 71.659566 -410.411189) (xy 71.632318 -410.411676) (xy 70.768718 -410.411676) (xy 70.741462 -410.411278)
			(xy 70.687505 -410.403523) (xy 70.6352 -410.388167) (xy 70.585613 -410.365524) (xy 70.539754 -410.336054)
			(xy 70.498556 -410.300357) (xy 70.462857 -410.25916) (xy 70.433385 -410.213302) (xy 70.410739 -410.163717)
			(xy 70.395381 -410.111413) (xy 70.387623 -410.057456) (xy 68.950112 -410.057456) (xy 68.942356 -410.1114)
			(xy 68.927 -410.163695) (xy 68.904358 -410.213273) (xy 68.87489 -410.259123) (xy 68.839197 -410.300313)
			(xy 68.798005 -410.336003) (xy 68.752153 -410.365468) (xy 68.702574 -410.388108) (xy 68.650278 -410.40346)
			(xy 68.59633 -410.411214) (xy 68.569078 -410.411676) (xy 67.705478 -410.411676) (xy 67.678225 -410.411253)
			(xy 67.624276 -410.403493) (xy 67.571979 -410.388135) (xy 67.522401 -410.36549) (xy 67.476549 -410.336021)
			(xy 67.435358 -410.300326) (xy 67.399666 -410.259133) (xy 67.370199 -410.21328) (xy 67.347558 -410.1637)
			(xy 67.332202 -410.111403) (xy 67.324446 -410.057453) (xy 65.886789 -410.057453) (xy 65.879035 -410.111387)
			(xy 65.863683 -410.163674) (xy 65.841047 -410.213245) (xy 65.811586 -410.259089) (xy 65.775902 -410.300275)
			(xy 65.73472 -410.335964) (xy 65.688878 -410.365428) (xy 65.63931 -410.38807) (xy 65.587024 -410.403427)
			(xy 65.533085 -410.411187) (xy 65.505838 -410.411676) (xy 64.642238 -410.411676) (xy 64.614981 -410.41128)
			(xy 64.561021 -410.403526) (xy 64.508715 -410.388172) (xy 64.459125 -410.36553) (xy 64.413264 -410.336061)
			(xy 64.372063 -410.300364) (xy 64.336362 -410.259167) (xy 64.306888 -410.213308) (xy 64.284241 -410.163721)
			(xy 64.268882 -410.111416) (xy 64.261123 -410.057457) (xy 62.823612 -410.057457) (xy 62.815856 -410.111397)
			(xy 62.800502 -410.163691) (xy 62.777861 -410.213267) (xy 62.748395 -410.259116) (xy 62.712704 -410.300306)
			(xy 62.671515 -410.335996) (xy 62.625665 -410.365462) (xy 62.576089 -410.388102) (xy 62.523795 -410.403457)
			(xy 62.469849 -410.411213) (xy 62.442598 -410.411676) (xy 61.578998 -410.411676) (xy 61.551745 -410.411254)
			(xy 61.497793 -410.403497) (xy 61.445494 -410.38814) (xy 61.395913 -410.365497) (xy 61.350059 -410.336028)
			(xy 61.308865 -410.300334) (xy 61.273171 -410.25914) (xy 61.243702 -410.213286) (xy 61.221059 -410.163705)
			(xy 61.205703 -410.111406) (xy 61.197946 -410.057453) (xy 59.760413 -410.057453) (xy 59.752655 -410.111403)
			(xy 59.737298 -410.163699) (xy 59.714655 -410.213278) (xy 59.685185 -410.259129) (xy 59.64949 -410.30032)
			(xy 59.608296 -410.33601) (xy 59.562441 -410.365475) (xy 59.51286 -410.388113) (xy 59.460561 -410.403464)
			(xy 59.406611 -410.411216) (xy 59.379358 -410.411676) (xy 58.515758 -410.411676) (xy 58.488506 -410.411251)
			(xy 58.434559 -410.403489) (xy 58.382265 -410.388129) (xy 58.332689 -410.365484) (xy 58.28684 -410.336014)
			(xy 58.245651 -410.300319) (xy 58.209961 -410.259127) (xy 58.180496 -410.213275) (xy 58.157856 -410.163696)
			(xy 58.142502 -410.1114) (xy 58.134746 -410.057452) (xy 56.697089 -410.057452) (xy 56.689334 -410.11139)
			(xy 56.673982 -410.163679) (xy 56.651344 -410.21325) (xy 56.621882 -410.259096) (xy 56.586195 -410.300282)
			(xy 56.54501 -410.335971) (xy 56.499166 -410.365435) (xy 56.449595 -410.388075) (xy 56.397307 -410.403431)
			(xy 56.343366 -410.411189) (xy 56.316118 -410.411676) (xy 55.452518 -410.411676) (xy 55.425262 -410.411278)
			(xy 55.371305 -410.403523) (xy 55.319 -410.388167) (xy 55.269413 -410.365524) (xy 55.223554 -410.336054)
			(xy 55.182356 -410.300357) (xy 55.146657 -410.25916) (xy 55.117185 -410.213302) (xy 55.094539 -410.163717)
			(xy 55.079181 -410.111413) (xy 55.071423 -410.057456) (xy 53.633912 -410.057456) (xy 53.626156 -410.1114)
			(xy 53.6108 -410.163695) (xy 53.588158 -410.213273) (xy 53.55869 -410.259123) (xy 53.522997 -410.300313)
			(xy 53.481805 -410.336003) (xy 53.435953 -410.365468) (xy 53.386374 -410.388108) (xy 53.334078 -410.40346)
			(xy 53.28013 -410.411214) (xy 53.252878 -410.411676) (xy 52.389278 -410.411676) (xy 52.362025 -410.411253)
			(xy 52.308076 -410.403493) (xy 52.255779 -410.388135) (xy 52.206201 -410.36549) (xy 52.160349 -410.336021)
			(xy 52.119158 -410.300326) (xy 52.083466 -410.259133) (xy 52.053999 -410.21328) (xy 52.031358 -410.1637)
			(xy 52.016002 -410.111403) (xy 52.008246 -410.057453) (xy 50.570589 -410.057453) (xy 50.562835 -410.111387)
			(xy 50.547483 -410.163674) (xy 50.524847 -410.213245) (xy 50.495386 -410.259089) (xy 50.459702 -410.300275)
			(xy 50.41852 -410.335964) (xy 50.372678 -410.365428) (xy 50.32311 -410.38807) (xy 50.270824 -410.403427)
			(xy 50.216885 -410.411187) (xy 50.189638 -410.411676) (xy 49.326038 -410.411676) (xy 49.298781 -410.41128)
			(xy 49.244821 -410.403526) (xy 49.192515 -410.388172) (xy 49.142925 -410.36553) (xy 49.097064 -410.336061)
			(xy 49.055863 -410.300364) (xy 49.020162 -410.259167) (xy 48.990688 -410.213308) (xy 48.968041 -410.163721)
			(xy 48.952682 -410.111416) (xy 48.944923 -410.057457) (xy 7.00913 -410.057457) (xy 7.00913 -411.241049)
			(xy 101.876886 -411.241049) (xy 101.876886 -411.186551) (xy 101.884641 -411.132608) (xy 101.899994 -411.080318)
			(xy 101.922631 -411.030744) (xy 101.952093 -410.984897) (xy 101.98778 -410.943708) (xy 102.028964 -410.908017)
			(xy 102.074809 -410.878551) (xy 102.12438 -410.855908) (xy 102.176669 -410.840549) (xy 102.230611 -410.832788)
			(xy 102.25786 -410.8323) (xy 103.12146 -410.8323) (xy 103.148715 -410.832745) (xy 103.202672 -410.840497)
			(xy 103.254975 -410.85585) (xy 103.304562 -410.878491) (xy 103.350421 -410.907958) (xy 103.391619 -410.943653)
			(xy 103.427318 -410.984847) (xy 103.45679 -411.030703) (xy 103.479436 -411.080287) (xy 103.494794 -411.132589)
			(xy 103.502553 -411.186545) (xy 103.502553 -411.241055) (xy 103.494794 -411.295011) (xy 103.479436 -411.347313)
			(xy 103.45679 -411.396897) (xy 103.427318 -411.442753) (xy 103.391619 -411.483947) (xy 103.350421 -411.519642)
			(xy 103.304562 -411.549109) (xy 103.254975 -411.57175) (xy 103.202672 -411.587103) (xy 103.148715 -411.594855)
			(xy 103.12146 -411.595316) (xy 102.25786 -411.595316) (xy 102.230611 -411.594812) (xy 102.176669 -411.587051)
			(xy 102.12438 -411.571692) (xy 102.074809 -411.549049) (xy 102.028964 -411.519583) (xy 101.98778 -411.483892)
			(xy 101.952093 -411.442703) (xy 101.922631 -411.396856) (xy 101.899994 -411.347282) (xy 101.884641 -411.294992)
			(xy 101.876886 -411.241049) (xy 7.00913 -411.241049) (xy 7.00913 -424.470068) (xy 39.528496 -424.470068)
			(xy 39.528496 -417.770056) (xy 39.529001 -417.664532) (xy 39.537085 -417.453638) (xy 39.553241 -417.243209)
			(xy 39.577444 -417.033552) (xy 39.609661 -416.824977) (xy 39.649843 -416.617789) (xy 39.697931 -416.412292)
			(xy 39.753855 -416.208788) (xy 39.817532 -416.007575) (xy 39.88887 -415.808948) (xy 39.967764 -415.6132)
			(xy 40.054097 -415.420618) (xy 40.147744 -415.231483) (xy 40.248566 -415.046074) (xy 40.356416 -414.864663)
			(xy 40.471135 -414.687516) (xy 40.592555 -414.514894) (xy 40.720498 -414.347048) (xy 40.854776 -414.184226)
			(xy 40.995192 -414.026667) (xy 41.14154 -413.874602) (xy 41.293605 -413.728254) (xy 41.451164 -413.587838)
			(xy 41.613986 -413.45356) (xy 41.781832 -413.325617) (xy 41.954454 -413.204197) (xy 42.131601 -413.089478)
			(xy 42.313012 -412.981628) (xy 42.498421 -412.880806) (xy 42.687556 -412.787159) (xy 42.880138 -412.700826)
			(xy 43.075886 -412.621932) (xy 43.274513 -412.550594) (xy 43.475726 -412.486917) (xy 43.67923 -412.430993)
			(xy 43.884727 -412.382905) (xy 44.091915 -412.342723) (xy 44.30049 -412.310506) (xy 44.510147 -412.286303)
			(xy 44.720576 -412.270147) (xy 44.93147 -412.262063) (xy 45.142518 -412.262063) (xy 45.353412 -412.270147)
			(xy 45.563841 -412.286303) (xy 45.773498 -412.310506) (xy 45.982073 -412.342723) (xy 46.189261 -412.382905)
			(xy 46.394758 -412.430993) (xy 46.598262 -412.486917) (xy 46.799475 -412.550594) (xy 46.998102 -412.621932)
			(xy 47.19385 -412.700826) (xy 47.386432 -412.787159) (xy 47.575567 -412.880806) (xy 47.760976 -412.981628)
			(xy 47.942387 -413.089478) (xy 48.119534 -413.204197) (xy 48.292156 -413.325617) (xy 48.460002 -413.45356)
			(xy 48.622824 -413.587838) (xy 48.649451 -413.611568) (xy 104.877616 -413.611568) (xy 104.877616 -412.747968)
			(xy 104.878102 -412.720717) (xy 104.885858 -412.666769) (xy 104.901213 -412.614474) (xy 104.923855 -412.564897)
			(xy 104.953321 -412.519047) (xy 104.989012 -412.477856) (xy 105.030203 -412.442165) (xy 105.076053 -412.412699)
			(xy 105.12563 -412.390057) (xy 105.177925 -412.374702) (xy 105.231873 -412.366946) (xy 105.286375 -412.366946)
			(xy 105.340323 -412.374702) (xy 105.392618 -412.390057) (xy 105.442195 -412.412699) (xy 105.488045 -412.442165)
			(xy 105.529236 -412.477856) (xy 105.564927 -412.519047) (xy 105.594393 -412.564897) (xy 105.617035 -412.614474)
			(xy 105.63239 -412.666769) (xy 105.640146 -412.720717) (xy 105.640632 -412.747968) (xy 105.640632 -413.611568)
			(xy 105.640146 -413.638819) (xy 105.63239 -413.692767) (xy 105.617035 -413.745062) (xy 105.594393 -413.794639)
			(xy 105.584722 -413.809688) (xy 116.689632 -413.809688) (xy 116.689632 -412.946088) (xy 116.690118 -412.918837)
			(xy 116.697874 -412.864889) (xy 116.713229 -412.812594) (xy 116.735871 -412.763017) (xy 116.765337 -412.717167)
			(xy 116.801028 -412.675976) (xy 116.842219 -412.640285) (xy 116.888069 -412.610819) (xy 116.937646 -412.588177)
			(xy 116.989941 -412.572822) (xy 117.043889 -412.565066) (xy 117.098391 -412.565066) (xy 117.152339 -412.572822)
			(xy 117.204634 -412.588177) (xy 117.254211 -412.610819) (xy 117.300061 -412.640285) (xy 117.341252 -412.675976)
			(xy 117.376943 -412.717167) (xy 117.406409 -412.763017) (xy 117.429051 -412.812594) (xy 117.444406 -412.864889)
			(xy 117.452162 -412.918837) (xy 117.452648 -412.946088) (xy 117.452648 -413.809688) (xy 117.452162 -413.836939)
			(xy 117.444406 -413.890887) (xy 117.429051 -413.943182) (xy 117.406409 -413.992759) (xy 117.376943 -414.038609)
			(xy 117.341252 -414.0798) (xy 117.300061 -414.115491) (xy 117.254211 -414.144957) (xy 117.204634 -414.167599)
			(xy 117.152339 -414.182954) (xy 117.098391 -414.19071) (xy 117.043889 -414.19071) (xy 116.989941 -414.182954)
			(xy 116.937646 -414.167599) (xy 116.888069 -414.144957) (xy 116.842219 -414.115491) (xy 116.801028 -414.0798)
			(xy 116.765337 -414.038609) (xy 116.735871 -413.992759) (xy 116.713229 -413.943182) (xy 116.697874 -413.890887)
			(xy 116.690118 -413.836939) (xy 116.689632 -413.809688) (xy 105.584722 -413.809688) (xy 105.564927 -413.840489)
			(xy 105.529236 -413.88168) (xy 105.488045 -413.917371) (xy 105.442195 -413.946837) (xy 105.392618 -413.969479)
			(xy 105.340323 -413.984834) (xy 105.286375 -413.99259) (xy 105.231873 -413.99259) (xy 105.177925 -413.984834)
			(xy 105.12563 -413.969479) (xy 105.076053 -413.946837) (xy 105.030203 -413.917371) (xy 104.989012 -413.88168)
			(xy 104.953321 -413.840489) (xy 104.923855 -413.794639) (xy 104.901213 -413.745062) (xy 104.885858 -413.692767)
			(xy 104.878102 -413.638819) (xy 104.877616 -413.611568) (xy 48.649451 -413.611568) (xy 48.780383 -413.728254)
			(xy 48.932448 -413.874602) (xy 49.078796 -414.026667) (xy 49.219212 -414.184226) (xy 49.35349 -414.347048)
			(xy 49.481433 -414.514894) (xy 49.602853 -414.687516) (xy 49.717572 -414.864663) (xy 49.825422 -415.046074)
			(xy 49.926244 -415.231483) (xy 50.019891 -415.420618) (xy 50.106224 -415.6132) (xy 50.133819 -415.681668)
			(xy 100.559616 -415.681668) (xy 100.559616 -414.818068) (xy 100.560102 -414.790817) (xy 100.567858 -414.736869)
			(xy 100.583213 -414.684574) (xy 100.605855 -414.634997) (xy 100.635321 -414.589147) (xy 100.671012 -414.547956)
			(xy 100.712203 -414.512265) (xy 100.758053 -414.482799) (xy 100.80763 -414.460157) (xy 100.859925 -414.444802)
			(xy 100.913873 -414.437046) (xy 100.968375 -414.437046) (xy 101.022323 -414.444802) (xy 101.074618 -414.460157)
			(xy 101.124195 -414.482799) (xy 101.170045 -414.512265) (xy 101.211236 -414.547956) (xy 101.246927 -414.589147)
			(xy 101.276393 -414.634997) (xy 101.299035 -414.684574) (xy 101.31439 -414.736869) (xy 101.322146 -414.790817)
			(xy 101.322632 -414.818068) (xy 101.322632 -415.681668) (xy 101.322146 -415.708919) (xy 101.31439 -415.762867)
			(xy 101.299035 -415.815162) (xy 101.276393 -415.864739) (xy 101.246927 -415.910589) (xy 101.211236 -415.95178)
			(xy 101.170045 -415.987471) (xy 101.124195 -416.016937) (xy 101.074618 -416.039579) (xy 101.022323 -416.054934)
			(xy 100.968375 -416.06269) (xy 100.913873 -416.06269) (xy 100.859925 -416.054934) (xy 100.80763 -416.039579)
			(xy 100.758053 -416.016937) (xy 100.712203 -415.987471) (xy 100.671012 -415.95178) (xy 100.635321 -415.910589)
			(xy 100.605855 -415.864739) (xy 100.583213 -415.815162) (xy 100.567858 -415.762867) (xy 100.560102 -415.708919)
			(xy 100.559616 -415.681668) (xy 50.133819 -415.681668) (xy 50.185118 -415.808948) (xy 50.256456 -416.007575)
			(xy 50.320133 -416.208788) (xy 50.376057 -416.412292) (xy 50.424145 -416.617789) (xy 50.464327 -416.824977)
			(xy 50.496544 -417.033552) (xy 50.520747 -417.243209) (xy 50.536903 -417.453638) (xy 50.544987 -417.664532)
			(xy 50.545492 -417.770056) (xy 50.545492 -420.089838) (xy 58.13806 -420.089838) (xy 58.138171 -420.074752)
			(xy 58.139951 -420.044634) (xy 58.141616 -420.02964) (xy 58.141616 -418.95014) (xy 58.139949 -418.935146)
			(xy 58.138169 -418.905028) (xy 58.13806 -418.889942) (xy 58.138171 -418.874856) (xy 58.139951 -418.844738)
			(xy 58.141616 -418.829744) (xy 58.141616 -418.218874) (xy 58.142085 -418.206785) (xy 58.149546 -418.183788)
			(xy 58.163733 -418.164211) (xy 58.183264 -418.14996) (xy 58.206237 -418.142424) (xy 58.218324 -418.141912)
			(xy 59.158124 -418.141912) (xy 59.170235 -418.142296) (xy 59.193265 -418.149803) (xy 59.212839 -418.164073)
			(xy 59.227033 -418.183702) (xy 59.234451 -418.206761) (xy 59.234832 -418.218874) (xy 59.234832 -420.760398)
			(xy 59.23439 -420.77249) (xy 59.226931 -420.795495) (xy 59.212739 -420.815078) (xy 59.193198 -420.829327)
			(xy 59.170215 -420.836854) (xy 59.158124 -420.83736) (xy 58.218324 -420.83736) (xy 58.206212 -420.836963)
			(xy 58.183179 -420.829465) (xy 58.163602 -420.8152) (xy 58.149408 -420.795571) (xy 58.141994 -420.772511)
			(xy 58.141616 -420.760398) (xy 58.141616 -420.150036) (xy 58.139948 -420.135042) (xy 58.138169 -420.104924)
			(xy 58.13806 -420.089838) (xy 50.545492 -420.089838) (xy 50.545492 -421.089836) (xy 60.138056 -421.089836)
			(xy 60.138167 -421.07475) (xy 60.139947 -421.044632) (xy 60.141612 -421.029638) (xy 60.141612 -419.950138)
			(xy 60.139945 -419.935144) (xy 60.138165 -419.905026) (xy 60.138056 -419.88994) (xy 60.138167 -419.874854)
			(xy 60.139947 -419.844736) (xy 60.141612 -419.829742) (xy 60.141612 -419.218872) (xy 60.14204 -419.206794)
			(xy 60.149513 -419.183822) (xy 60.163718 -419.164284) (xy 60.183265 -419.150091) (xy 60.206242 -419.142633)
			(xy 60.21832 -419.142164) (xy 61.15812 -419.142164) (xy 61.170193 -419.142647) (xy 61.193156 -419.150112)
			(xy 61.21269 -419.164304) (xy 61.226885 -419.183837) (xy 61.234352 -419.206799) (xy 61.234828 -419.218872)
			(xy 61.234828 -421.089836) (xy 68.13804 -421.089836) (xy 68.138151 -421.07475) (xy 68.139931 -421.044632)
			(xy 68.141596 -421.029638) (xy 68.141596 -419.950138) (xy 68.139929 -419.935144) (xy 68.138149 -419.905026)
			(xy 68.13804 -419.88994) (xy 68.138151 -419.874854) (xy 68.139931 -419.844736) (xy 68.141596 -419.829742)
			(xy 68.141596 -419.218872) (xy 68.14204 -419.206796) (xy 68.149511 -419.183827) (xy 68.163712 -419.16429)
			(xy 68.183255 -419.150096) (xy 68.206227 -419.142635) (xy 68.218304 -419.142164) (xy 69.158104 -419.142164)
			(xy 69.170176 -419.14266) (xy 69.193139 -419.150121) (xy 69.212673 -419.16431) (xy 69.226868 -419.18384)
			(xy 69.234336 -419.2068) (xy 69.234812 -419.218872) (xy 69.234812 -420.089838) (xy 70.138036 -420.089838)
			(xy 70.138149 -420.074753) (xy 70.139929 -420.044634) (xy 70.141592 -420.02964) (xy 70.141592 -418.95014)
			(xy 70.139925 -418.935146) (xy 70.138145 -418.905028) (xy 70.138036 -418.889942) (xy 70.13815 -418.874857)
			(xy 70.139929 -418.844738) (xy 70.141592 -418.829744) (xy 70.141592 -418.218874) (xy 70.142084 -418.206788)
			(xy 70.149542 -418.183794) (xy 70.163724 -418.164219) (xy 70.183249 -418.149968) (xy 70.206216 -418.142428)
			(xy 70.2183 -418.141912) (xy 71.1581 -418.141912) (xy 71.17021 -418.142316) (xy 71.193239 -418.149817)
			(xy 71.212814 -418.164081) (xy 71.227008 -418.183706) (xy 71.234426 -418.206762) (xy 71.234808 -418.218874)
			(xy 71.234808 -420.760398) (xy 71.234292 -420.772483) (xy 71.226841 -420.795475) (xy 71.212666 -420.815051)
			(xy 71.193146 -420.829303) (xy 71.170183 -420.836844) (xy 71.1581 -420.83736) (xy 70.2183 -420.83736)
			(xy 70.206187 -420.836983) (xy 70.183153 -420.829479) (xy 70.163576 -420.815209) (xy 70.149383 -420.795576)
			(xy 70.14197 -420.772512) (xy 70.141592 -420.760398) (xy 70.141592 -420.150036) (xy 70.139924 -420.135042)
			(xy 70.138145 -420.104924) (xy 70.138036 -420.089838) (xy 69.234812 -420.089838) (xy 69.234812 -421.089836)
			(xy 72.138032 -421.089836) (xy 72.138145 -421.074751) (xy 72.139925 -421.044632) (xy 72.141588 -421.029638)
			(xy 72.141588 -419.950138) (xy 72.13992 -419.935144) (xy 72.138141 -419.905026) (xy 72.138032 -419.88994)
			(xy 72.138145 -419.874855) (xy 72.139925 -419.844736) (xy 72.141588 -419.829742) (xy 72.141588 -419.218872)
			(xy 72.14204 -419.206796) (xy 72.14951 -419.183829) (xy 72.16371 -419.164293) (xy 72.18325 -419.150099)
			(xy 72.20622 -419.142636) (xy 72.218296 -419.142164) (xy 73.158096 -419.142164) (xy 73.170168 -419.142667)
			(xy 73.19313 -419.150125) (xy 73.212665 -419.164313) (xy 73.22686 -419.183841) (xy 73.234328 -419.206801)
			(xy 73.234804 -419.218872) (xy 73.234804 -419.702852) (xy 110.957342 -419.702852) (xy 110.957342 -419.648348)
			(xy 110.965098 -419.594399) (xy 110.980453 -419.542102) (xy 111.003093 -419.492523) (xy 111.032558 -419.44667)
			(xy 111.068249 -419.405477) (xy 111.109438 -419.369782) (xy 111.155288 -419.340312) (xy 111.204865 -419.317667)
			(xy 111.25716 -419.302306) (xy 111.311108 -419.294545) (xy 111.33836 -419.294056) (xy 112.20196 -419.294056)
			(xy 112.229212 -419.294589) (xy 112.283162 -419.30234) (xy 112.33546 -419.317691) (xy 112.385041 -419.340329)
			(xy 112.430894 -419.369793) (xy 112.472088 -419.405484) (xy 112.507783 -419.446674) (xy 112.537251 -419.492524)
			(xy 112.559895 -419.542102) (xy 112.575251 -419.594399) (xy 112.583009 -419.648348) (xy 112.583009 -419.702852)
			(xy 112.575251 -419.756801) (xy 112.559895 -419.809098) (xy 112.537251 -419.858676) (xy 112.507783 -419.904526)
			(xy 112.472088 -419.945716) (xy 112.430894 -419.981407) (xy 112.385041 -420.010871) (xy 112.33546 -420.033509)
			(xy 112.283162 -420.04886) (xy 112.229212 -420.056611) (xy 112.20196 -420.057072) (xy 111.33836 -420.057072)
			(xy 111.311108 -420.056655) (xy 111.25716 -420.048894) (xy 111.204865 -420.033533) (xy 111.155288 -420.010888)
			(xy 111.109438 -419.981418) (xy 111.068249 -419.945723) (xy 111.032558 -419.90453) (xy 111.003093 -419.858677)
			(xy 110.980453 -419.809098) (xy 110.965098 -419.756801) (xy 110.957342 -419.702852) (xy 73.234804 -419.702852)
			(xy 73.234804 -421.760396) (xy 73.234384 -421.772479) (xy 73.226917 -421.795462) (xy 73.212713 -421.815013)
			(xy 73.193162 -421.829217) (xy 73.170179 -421.836684) (xy 73.158096 -421.837104) (xy 72.218296 -421.837104)
			(xy 72.206221 -421.836639) (xy 72.183253 -421.829175) (xy 72.163716 -421.814979) (xy 72.149521 -421.79544)
			(xy 72.14206 -421.772471) (xy 72.141588 -421.760396) (xy 72.141588 -421.150034) (xy 72.13992 -421.13504)
			(xy 72.138141 -421.104922) (xy 72.138032 -421.089836) (xy 69.234812 -421.089836) (xy 69.234812 -421.760396)
			(xy 69.234332 -421.77247) (xy 69.226871 -421.795436) (xy 69.212679 -421.814973) (xy 69.193143 -421.829168)
			(xy 69.170178 -421.836631) (xy 69.158104 -421.837104) (xy 68.218304 -421.837104) (xy 68.206221 -421.836684)
			(xy 68.183238 -421.829217) (xy 68.163687 -421.815013) (xy 68.149483 -421.795462) (xy 68.142016 -421.772479)
			(xy 68.141596 -421.760396) (xy 68.141596 -421.150034) (xy 68.139928 -421.13504) (xy 68.138149 -421.104922)
			(xy 68.13804 -421.089836) (xy 61.234828 -421.089836) (xy 61.234828 -421.760396) (xy 61.234333 -421.772468)
			(xy 61.226874 -421.795432) (xy 61.212684 -421.814967) (xy 61.193154 -421.829163) (xy 61.170192 -421.836629)
			(xy 61.15812 -421.837104) (xy 60.21832 -421.837104) (xy 60.206238 -421.83667) (xy 60.183255 -421.829208)
			(xy 60.163704 -421.815007) (xy 60.1495 -421.795459) (xy 60.142032 -421.772478) (xy 60.141612 -421.760396)
			(xy 60.141612 -421.150034) (xy 60.139944 -421.13504) (xy 60.138165 -421.104922) (xy 60.138056 -421.089836)
			(xy 50.545492 -421.089836) (xy 50.545492 -423.68978) (xy 58.13806 -423.68978) (xy 58.138175 -423.674695)
			(xy 58.139953 -423.644576) (xy 58.141616 -423.629582) (xy 58.141616 -422.550082) (xy 58.139952 -422.535088)
			(xy 58.138171 -422.50497) (xy 58.13806 -422.489884) (xy 58.138175 -422.474799) (xy 58.139953 -422.44468)
			(xy 58.141616 -422.429686) (xy 58.141616 -421.81907) (xy 58.142081 -421.806981) (xy 58.149543 -421.783984)
			(xy 58.163731 -421.764406) (xy 58.183263 -421.750156) (xy 58.206237 -421.74262) (xy 58.218324 -421.742108)
			(xy 59.158124 -421.742108) (xy 59.170235 -421.742496) (xy 59.193264 -421.750003) (xy 59.212838 -421.764272)
			(xy 59.227031 -421.783899) (xy 59.23445 -421.806958) (xy 59.234832 -421.81907) (xy 59.234832 -423.68978)
			(xy 62.138052 -423.68978) (xy 62.138167 -423.674695) (xy 62.139945 -423.644576) (xy 62.141608 -423.629582)
			(xy 62.141608 -422.550082) (xy 62.139944 -422.535088) (xy 62.138163 -422.50497) (xy 62.138052 -422.489884)
			(xy 62.138167 -422.474799) (xy 62.139945 -422.44468) (xy 62.141608 -422.429686) (xy 62.141608 -421.81907)
			(xy 62.142081 -421.806982) (xy 62.149542 -421.783986) (xy 62.163728 -421.764409) (xy 62.183258 -421.750158)
			(xy 62.20623 -421.742621) (xy 62.218316 -421.742108) (xy 63.158116 -421.742108) (xy 63.170227 -421.742503)
			(xy 63.193256 -421.750008) (xy 63.212829 -421.764274) (xy 63.227023 -421.783901) (xy 63.234442 -421.806958)
			(xy 63.234824 -421.81907) (xy 63.234824 -424.360594) (xy 63.234387 -424.372687) (xy 63.226927 -424.395693)
			(xy 63.212734 -424.415276) (xy 63.193192 -424.429526) (xy 63.170207 -424.437051) (xy 63.158116 -424.437556)
			(xy 62.218316 -424.437556) (xy 62.206214 -424.437071) (xy 62.183196 -424.429582) (xy 62.163628 -424.415337)
			(xy 62.149431 -424.395733) (xy 62.142 -424.372697) (xy 62.141608 -424.360594) (xy 62.141608 -423.749978)
			(xy 62.139944 -423.734984) (xy 62.138162 -423.704866) (xy 62.138052 -423.68978) (xy 59.234832 -423.68978)
			(xy 59.234832 -424.360594) (xy 59.234387 -424.372686) (xy 59.226928 -424.395691) (xy 59.212737 -424.415274)
			(xy 59.193197 -424.429523) (xy 59.170215 -424.43705) (xy 59.158124 -424.437556) (xy 58.218324 -424.437556)
			(xy 58.206222 -424.437064) (xy 58.183205 -424.429578) (xy 58.163637 -424.415334) (xy 58.149439 -424.395732)
			(xy 58.142008 -424.372697) (xy 58.141616 -424.360594) (xy 58.141616 -423.749978) (xy 58.139952 -423.734984)
			(xy 58.13817 -423.704866) (xy 58.13806 -423.68978) (xy 50.545492 -423.68978) (xy 50.545492 -424.470068)
			(xy 50.544987 -424.575592) (xy 50.54061 -424.689778) (xy 64.138048 -424.689778) (xy 64.138163 -424.674693)
			(xy 64.139941 -424.644574) (xy 64.141604 -424.62958) (xy 64.141604 -423.55008) (xy 64.13994 -423.535086)
			(xy 64.138158 -423.504968) (xy 64.138048 -423.489882) (xy 64.138163 -423.474797) (xy 64.139941 -423.444678)
			(xy 64.141604 -423.429684) (xy 64.141604 -422.819068) (xy 64.142037 -422.806991) (xy 64.14951 -422.78402)
			(xy 64.163714 -422.764483) (xy 64.18326 -422.75029) (xy 64.206234 -422.74283) (xy 64.218312 -422.74236)
			(xy 65.158112 -422.74236) (xy 65.170184 -422.742854) (xy 65.193146 -422.750316) (xy 65.21268 -422.764506)
			(xy 65.226875 -422.784036) (xy 65.234343 -422.806996) (xy 65.23482 -422.819068) (xy 65.23482 -424.689778)
			(xy 68.13804 -424.689778) (xy 68.138155 -424.674693) (xy 68.139933 -424.644574) (xy 68.141596 -424.62958)
			(xy 68.141596 -423.55008) (xy 68.139932 -423.535086) (xy 68.13815 -423.504968) (xy 68.13804 -423.489882)
			(xy 68.138155 -423.474797) (xy 68.139933 -423.444678) (xy 68.141596 -423.429684) (xy 68.141596 -422.819068)
			(xy 68.142037 -422.806991) (xy 68.149509 -422.784022) (xy 68.163711 -422.764485) (xy 68.183255 -422.750292)
			(xy 68.206227 -422.742831) (xy 68.218304 -422.74236) (xy 69.158104 -422.74236) (xy 69.170176 -422.74286)
			(xy 69.193137 -422.75032) (xy 69.212672 -422.764508) (xy 69.226867 -422.784037) (xy 69.234335 -422.806997)
			(xy 69.234812 -422.819068) (xy 69.234812 -423.68978) (xy 70.138036 -423.68978) (xy 70.138153 -423.674695)
			(xy 70.139931 -423.644576) (xy 70.141592 -423.629582) (xy 70.141592 -422.550082) (xy 70.139928 -422.535088)
			(xy 70.138147 -422.50497) (xy 70.138036 -422.489884) (xy 70.138153 -422.474799) (xy 70.139931 -422.44468)
			(xy 70.141592 -422.429686) (xy 70.141592 -421.81907) (xy 70.142081 -421.806984) (xy 70.14954 -421.78399)
			(xy 70.163723 -421.764415) (xy 70.183248 -421.750163) (xy 70.206215 -421.742624) (xy 70.2183 -421.742108)
			(xy 71.1581 -421.742108) (xy 71.17021 -421.742516) (xy 71.193238 -421.750017) (xy 71.212812 -421.76428)
			(xy 71.227007 -421.783904) (xy 71.234426 -421.806959) (xy 71.234808 -421.81907) (xy 71.234808 -424.360594)
			(xy 71.234288 -424.372678) (xy 71.226839 -424.395671) (xy 71.212664 -424.415247) (xy 71.193145 -424.429499)
			(xy 71.170183 -424.43704) (xy 71.1581 -424.437556) (xy 70.2183 -424.437556) (xy 70.206197 -424.437085)
			(xy 70.183179 -424.429592) (xy 70.163611 -424.415343) (xy 70.149414 -424.395736) (xy 70.141983 -424.372698)
			(xy 70.141592 -424.360594) (xy 70.141592 -423.749978) (xy 70.139928 -423.734984) (xy 70.138146 -423.704866)
			(xy 70.138036 -423.68978) (xy 69.234812 -423.68978) (xy 69.234812 -424.689778) (xy 72.138032 -424.689778)
			(xy 72.138149 -424.674693) (xy 72.139927 -424.644574) (xy 72.141588 -424.62958) (xy 72.141588 -423.55008)
			(xy 72.139924 -423.535086) (xy 72.138142 -423.504968) (xy 72.138032 -423.489882) (xy 72.138149 -423.474797)
			(xy 72.139927 -423.444678) (xy 72.141588 -423.429684) (xy 72.141588 -422.819068) (xy 72.142037 -422.806992)
			(xy 72.149508 -422.784025) (xy 72.163708 -422.764488) (xy 72.18325 -422.750295) (xy 72.20622 -422.742832)
			(xy 72.218296 -422.74236) (xy 73.158096 -422.74236) (xy 73.170167 -422.742867) (xy 73.193129 -422.750325)
			(xy 73.212663 -422.764511) (xy 73.226859 -422.784039) (xy 73.234327 -422.806997) (xy 73.234804 -422.819068)
			(xy 73.234804 -424.80464) (xy 109.929157 -424.80464) (xy 109.929157 -424.6755) (xy 109.937107 -424.546605)
			(xy 109.952977 -424.418445) (xy 109.976706 -424.291504) (xy 110.008205 -424.166265) (xy 110.047354 -424.043202)
			(xy 110.094005 -423.922783) (xy 110.14798 -423.805464) (xy 110.209075 -423.69169) (xy 110.277058 -423.581893)
			(xy 110.351672 -423.47649) (xy 110.432633 -423.37588) (xy 110.519633 -423.280445) (xy 110.612344 -423.190546)
			(xy 110.710414 -423.106525) (xy 110.813469 -423.028701) (xy 110.92112 -422.957369) (xy 111.032959 -422.892799)
			(xy 111.14856 -422.835237) (xy 111.267485 -422.7849) (xy 111.389284 -422.74198) (xy 111.513494 -422.706639)
			(xy 111.639643 -422.679012) (xy 111.767255 -422.659203) (xy 111.895844 -422.647287) (xy 112.024922 -422.643311)
			(xy 112.154 -422.647287) (xy 112.282589 -422.659203) (xy 112.410201 -422.679012) (xy 112.53635 -422.706639)
			(xy 112.66056 -422.74198) (xy 112.782359 -422.7849) (xy 112.901284 -422.835237) (xy 113.016885 -422.892799)
			(xy 113.128724 -422.957369) (xy 113.236375 -423.028701) (xy 113.33943 -423.106525) (xy 113.4375 -423.190546)
			(xy 113.530211 -423.280445) (xy 113.617211 -423.37588) (xy 113.698172 -423.47649) (xy 113.772786 -423.581893)
			(xy 113.840769 -423.69169) (xy 113.901864 -423.805464) (xy 113.955839 -423.922783) (xy 114.00249 -424.043202)
			(xy 114.041639 -424.166265) (xy 114.073138 -424.291504) (xy 114.096867 -424.418445) (xy 114.112737 -424.546605)
			(xy 114.120687 -424.6755) (xy 114.121184 -424.74007) (xy 114.120687 -424.80464) (xy 114.112737 -424.933535)
			(xy 114.096867 -425.061695) (xy 114.073138 -425.188636) (xy 114.041639 -425.313875) (xy 114.00249 -425.436938)
			(xy 113.955839 -425.557357) (xy 113.901864 -425.674676) (xy 113.840769 -425.78845) (xy 113.772786 -425.898247)
			(xy 113.698172 -426.00365) (xy 113.617211 -426.10426) (xy 113.530211 -426.199695) (xy 113.4375 -426.289594)
			(xy 113.33943 -426.373615) (xy 113.236375 -426.451439) (xy 113.128724 -426.522771) (xy 113.016885 -426.587341)
			(xy 112.901284 -426.644903) (xy 112.782359 -426.69524) (xy 112.66056 -426.73816) (xy 112.53635 -426.773501)
			(xy 112.410201 -426.801128) (xy 112.282589 -426.820937) (xy 112.154 -426.832853) (xy 112.024922 -426.83683)
			(xy 111.895844 -426.832853) (xy 111.767255 -426.820937) (xy 111.639643 -426.801128) (xy 111.513494 -426.773501)
			(xy 111.389284 -426.73816) (xy 111.267485 -426.69524) (xy 111.14856 -426.644903) (xy 111.032959 -426.587341)
			(xy 110.92112 -426.522771) (xy 110.813469 -426.451439) (xy 110.710414 -426.373615) (xy 110.612344 -426.289594)
			(xy 110.519633 -426.199695) (xy 110.432633 -426.10426) (xy 110.351672 -426.00365) (xy 110.277058 -425.898247)
			(xy 110.209075 -425.78845) (xy 110.14798 -425.674676) (xy 110.094005 -425.557357) (xy 110.047354 -425.436938)
			(xy 110.008205 -425.313875) (xy 109.976706 -425.188636) (xy 109.952977 -425.061695) (xy 109.937107 -424.933535)
			(xy 109.929157 -424.80464) (xy 73.234804 -424.80464) (xy 73.234804 -425.360592) (xy 73.234381 -425.372675)
			(xy 73.226915 -425.395658) (xy 73.212712 -425.415209) (xy 73.193162 -425.429413) (xy 73.170179 -425.43688)
			(xy 73.158096 -425.4373) (xy 72.218296 -425.4373) (xy 72.206212 -425.436891) (xy 72.183228 -425.429421)
			(xy 72.163677 -425.415214) (xy 72.149473 -425.395661) (xy 72.142007 -425.372676) (xy 72.141588 -425.360592)
			(xy 72.141588 -424.749976) (xy 72.139924 -424.734982) (xy 72.138142 -424.704864) (xy 72.138032 -424.689778)
			(xy 69.234812 -424.689778) (xy 69.234812 -425.360592) (xy 69.234381 -425.372674) (xy 69.226916 -425.395656)
			(xy 69.212714 -425.415206) (xy 69.193167 -425.429411) (xy 69.170186 -425.436879) (xy 69.158104 -425.4373)
			(xy 68.218304 -425.4373) (xy 68.206221 -425.436884) (xy 68.183237 -425.429417) (xy 68.163686 -425.415212)
			(xy 68.149482 -425.39566) (xy 68.142015 -425.372675) (xy 68.141596 -425.360592) (xy 68.141596 -424.749976)
			(xy 68.139932 -424.734982) (xy 68.13815 -424.704864) (xy 68.13804 -424.689778) (xy 65.23482 -424.689778)
			(xy 65.23482 -425.360592) (xy 65.234329 -425.372665) (xy 65.22687 -425.39563) (xy 65.21268 -425.415166)
			(xy 65.193148 -425.429361) (xy 65.170185 -425.436826) (xy 65.158112 -425.4373) (xy 64.218312 -425.4373)
			(xy 64.206229 -425.436877) (xy 64.183246 -425.429412) (xy 64.163694 -425.415208) (xy 64.14949 -425.395658)
			(xy 64.142024 -425.372675) (xy 64.141604 -425.360592) (xy 64.141604 -424.749976) (xy 64.13994 -424.734982)
			(xy 64.138158 -424.704864) (xy 64.138048 -424.689778) (xy 50.54061 -424.689778) (xy 50.536903 -424.786486)
			(xy 50.520747 -424.996915) (xy 50.496544 -425.206572) (xy 50.464327 -425.415147) (xy 50.424145 -425.622335)
			(xy 50.376057 -425.827832) (xy 50.320133 -426.031336) (xy 50.256456 -426.232549) (xy 50.185118 -426.431176)
			(xy 50.106224 -426.626924) (xy 50.019891 -426.819506) (xy 49.926244 -427.008641) (xy 49.825422 -427.19405)
			(xy 49.768393 -427.289976) (xy 58.13806 -427.289976) (xy 58.138174 -427.274891) (xy 58.139952 -427.244772)
			(xy 58.141616 -427.229778) (xy 58.141616 -426.150024) (xy 58.139947 -426.135031) (xy 58.138169 -426.104912)
			(xy 58.13806 -426.089826) (xy 58.13817 -426.07474) (xy 58.139951 -426.044622) (xy 58.141616 -426.029628)
			(xy 58.141616 -425.419012) (xy 58.142023 -425.406928) (xy 58.149491 -425.383941) (xy 58.163697 -425.364389)
			(xy 58.183252 -425.350185) (xy 58.206239 -425.342722) (xy 58.218324 -425.342304) (xy 59.158124 -425.342304)
			(xy 59.170201 -425.342744) (xy 59.193171 -425.350215) (xy 59.212709 -425.364417) (xy 59.226902 -425.383961)
			(xy 59.234361 -425.406935) (xy 59.234832 -425.419012) (xy 59.234832 -427.960536) (xy 59.234367 -427.97261)
			(xy 59.226898 -427.995574) (xy 59.2127 -428.015109) (xy 59.193164 -428.029303) (xy 59.170198 -428.036769)
			(xy 59.158124 -428.037244) (xy 58.218324 -428.037244) (xy 58.206254 -428.036716) (xy 58.183294 -428.029264)
			(xy 58.16376 -428.015083) (xy 58.149563 -427.99556) (xy 58.142093 -427.972605) (xy 58.141616 -427.960536)
			(xy 58.141616 -427.350174) (xy 58.139952 -427.33518) (xy 58.13817 -427.305062) (xy 58.13806 -427.289976)
			(xy 49.768393 -427.289976) (xy 49.717572 -427.375461) (xy 49.602853 -427.552608) (xy 49.481433 -427.72523)
			(xy 49.35349 -427.893076) (xy 49.219212 -428.055898) (xy 49.078796 -428.213457) (xy 49.0054 -428.28972)
			(xy 60.138056 -428.28972) (xy 60.138166 -428.274634) (xy 60.139947 -428.244516) (xy 60.141612 -428.229522)
			(xy 60.141612 -427.150022) (xy 60.139943 -427.135029) (xy 60.138165 -427.10491) (xy 60.138056 -427.089824)
			(xy 60.138166 -427.074738) (xy 60.139947 -427.04462) (xy 60.141612 -427.029626) (xy 60.141612 -426.41901)
			(xy 60.142115 -426.406924) (xy 60.149566 -426.383928) (xy 60.163744 -426.364351) (xy 60.183268 -426.350099)
			(xy 60.206236 -426.342562) (xy 60.21832 -426.342048) (xy 61.15812 -426.342048) (xy 61.170225 -426.342499)
			(xy 61.193244 -426.349997) (xy 61.212812 -426.364252) (xy 61.227008 -426.383863) (xy 61.234437 -426.406904)
			(xy 61.234828 -426.41901) (xy 61.234828 -427.289976) (xy 62.138052 -427.289976) (xy 62.138166 -427.274891)
			(xy 62.139944 -427.244772) (xy 62.141608 -427.229778) (xy 62.141608 -426.150024) (xy 62.139939 -426.135031)
			(xy 62.138161 -426.104912) (xy 62.138052 -426.089826) (xy 62.138162 -426.07474) (xy 62.139943 -426.044622)
			(xy 62.141608 -426.029628) (xy 62.141608 -425.419012) (xy 62.142023 -425.406928) (xy 62.149489 -425.383943)
			(xy 62.163694 -425.364392) (xy 62.183247 -425.350188) (xy 62.206232 -425.342723) (xy 62.218316 -425.342304)
			(xy 63.158116 -425.342304) (xy 63.170193 -425.342751) (xy 63.193162 -425.350219) (xy 63.2127 -425.36442)
			(xy 63.226894 -425.383963) (xy 63.234353 -425.406935) (xy 63.234824 -425.419012) (xy 63.234824 -427.960536)
			(xy 63.234367 -427.972611) (xy 63.226896 -427.995577) (xy 63.212697 -428.015112) (xy 63.193159 -428.029306)
			(xy 63.170191 -428.03677) (xy 63.158116 -428.037244) (xy 62.218316 -428.037244) (xy 62.206246 -428.036723)
			(xy 62.183285 -428.029269) (xy 62.163751 -428.015086) (xy 62.149555 -427.995561) (xy 62.142085 -427.972606)
			(xy 62.141608 -427.960536) (xy 62.141608 -427.350174) (xy 62.139944 -427.33518) (xy 62.138162 -427.305062)
			(xy 62.138052 -427.289976) (xy 61.234828 -427.289976) (xy 61.234828 -428.28972) (xy 64.138048 -428.28972)
			(xy 64.138158 -428.274634) (xy 64.139939 -428.244516) (xy 64.141604 -428.229522) (xy 64.141604 -427.150022)
			(xy 64.139935 -427.135029) (xy 64.138157 -427.10491) (xy 64.138048 -427.089824) (xy 64.138158 -427.074738)
			(xy 64.139939 -427.04462) (xy 64.141604 -427.029626) (xy 64.141604 -426.41901) (xy 64.142115 -426.406925)
			(xy 64.149565 -426.38393) (xy 64.163741 -426.364353) (xy 64.183263 -426.350101) (xy 64.206228 -426.342563)
			(xy 64.218312 -426.342048) (xy 65.158112 -426.342048) (xy 65.170216 -426.342505) (xy 65.193235 -426.350002)
			(xy 65.212804 -426.364255) (xy 65.227 -426.383864) (xy 65.234429 -426.406905) (xy 65.23482 -426.41901)
			(xy 65.23482 -427.289976) (xy 66.138044 -427.289976) (xy 66.138159 -427.274891) (xy 66.139936 -427.244772)
			(xy 66.1416 -427.229778) (xy 66.1416 -426.150024) (xy 66.139931 -426.135031) (xy 66.138153 -426.104912)
			(xy 66.138044 -426.089826) (xy 66.138154 -426.07474) (xy 66.139935 -426.044622) (xy 66.1416 -426.029628)
			(xy 66.1416 -425.419012) (xy 66.142023 -425.406929) (xy 66.149488 -425.383946) (xy 66.163692 -425.364394)
			(xy 66.183242 -425.35019) (xy 66.206225 -425.342724) (xy 66.218308 -425.342304) (xy 67.158108 -425.342304)
			(xy 67.170192 -425.342706) (xy 67.193177 -425.350177) (xy 67.212729 -425.364386) (xy 67.226932 -425.383941)
			(xy 67.234397 -425.406928) (xy 67.234816 -425.419012) (xy 67.234816 -427.960536) (xy 67.234367 -427.972612)
			(xy 67.226895 -427.995579) (xy 67.212695 -428.015115) (xy 67.193154 -428.029308) (xy 67.170184 -428.036771)
			(xy 67.158108 -428.037244) (xy 66.218308 -428.037244) (xy 66.206237 -428.03673) (xy 66.183277 -428.029274)
			(xy 66.163743 -428.015089) (xy 66.149547 -427.995563) (xy 66.142077 -427.972606) (xy 66.1416 -427.960536)
			(xy 66.1416 -427.350174) (xy 66.139936 -427.33518) (xy 66.138154 -427.305062) (xy 66.138044 -427.289976)
			(xy 65.23482 -427.289976) (xy 65.23482 -428.28972) (xy 68.13804 -428.28972) (xy 68.138152 -428.274634)
			(xy 68.139933 -428.244516) (xy 68.141596 -428.229522) (xy 68.141596 -427.150022) (xy 68.139927 -427.135029)
			(xy 68.138149 -427.10491) (xy 68.13804 -427.089824) (xy 68.13815 -427.074738) (xy 68.139931 -427.04462)
			(xy 68.141596 -427.029626) (xy 68.141596 -426.41901) (xy 68.142115 -426.406925) (xy 68.149564 -426.383932)
			(xy 68.163739 -426.364356) (xy 68.183258 -426.350104) (xy 68.206221 -426.342564) (xy 68.218304 -426.342048)
			(xy 69.158104 -426.342048) (xy 69.170208 -426.342512) (xy 69.193227 -426.350006) (xy 69.212795 -426.364257)
			(xy 69.226991 -426.383866) (xy 69.234421 -426.406905) (xy 69.234812 -426.41901) (xy 69.234812 -427.289976)
			(xy 70.138036 -427.289976) (xy 70.138153 -427.274891) (xy 70.13993 -427.244772) (xy 70.141592 -427.229778)
			(xy 70.141592 -426.150024) (xy 70.139923 -426.135031) (xy 70.138145 -426.104912) (xy 70.138036 -426.089826)
			(xy 70.138148 -426.07474) (xy 70.139929 -426.044622) (xy 70.141592 -426.029628) (xy 70.141592 -425.419012)
			(xy 70.142023 -425.40693) (xy 70.149487 -425.383948) (xy 70.163689 -425.364397) (xy 70.183237 -425.350193)
			(xy 70.206218 -425.342725) (xy 70.2183 -425.342304) (xy 71.1581 -425.342304) (xy 71.170184 -425.342713)
			(xy 71.193169 -425.350182) (xy 71.21272 -425.364388) (xy 71.226924 -425.383942) (xy 71.234389 -425.406928)
			(xy 71.234808 -425.419012) (xy 71.234808 -427.960536) (xy 71.234367 -427.972612) (xy 71.226894 -427.995581)
			(xy 71.212692 -428.015117) (xy 71.193149 -428.029311) (xy 71.170177 -428.036772) (xy 71.1581 -428.037244)
			(xy 70.2183 -428.037244) (xy 70.206229 -428.036736) (xy 70.183268 -428.029278) (xy 70.163734 -428.015092)
			(xy 70.149538 -427.995564) (xy 70.142069 -427.972607) (xy 70.141592 -427.960536) (xy 70.141592 -427.350174)
			(xy 70.139928 -427.33518) (xy 70.138146 -427.305062) (xy 70.138036 -427.289976) (xy 69.234812 -427.289976)
			(xy 69.234812 -428.28972) (xy 72.138032 -428.28972) (xy 72.138144 -428.274634) (xy 72.139925 -428.244516)
			(xy 72.141588 -428.229522) (xy 72.141588 -427.150022) (xy 72.139919 -427.135029) (xy 72.138141 -427.10491)
			(xy 72.138032 -427.089824) (xy 72.138144 -427.074738) (xy 72.139925 -427.04462) (xy 72.141588 -427.029626)
			(xy 72.141588 -426.41901) (xy 72.142017 -426.406916) (xy 72.149477 -426.383908) (xy 72.163671 -426.364324)
			(xy 72.183216 -426.350075) (xy 72.206204 -426.342551) (xy 72.218296 -426.342048) (xy 73.158096 -426.342048)
			(xy 73.170199 -426.342519) (xy 73.193218 -426.350011) (xy 73.212787 -426.36426) (xy 73.226983 -426.383867)
			(xy 73.234413 -426.406905) (xy 73.234804 -426.41901) (xy 73.234804 -427.289976) (xy 75.138026 -427.289976)
			(xy 75.138117 -427.275402) (xy 75.139771 -427.246301) (xy 75.141328 -427.23181) (xy 75.141328 -426.147992)
			(xy 75.139785 -426.1335) (xy 75.138132 -426.1044) (xy 75.138026 -426.089826) (xy 75.138121 -426.075252)
			(xy 75.139773 -426.046151) (xy 75.141328 -426.03166) (xy 75.141328 -425.419012) (xy 75.141727 -425.406901)
			(xy 75.149227 -425.383869) (xy 75.163492 -425.364294) (xy 75.183119 -425.3501) (xy 75.206178 -425.342684)
			(xy 75.21829 -425.342304) (xy 76.15809 -425.342304) (xy 76.170175 -425.342815) (xy 76.19317 -425.350265)
			(xy 76.212747 -425.364441) (xy 76.226999 -425.383963) (xy 76.234537 -425.406928) (xy 76.235052 -425.419012)
			(xy 76.235052 -427.960536) (xy 76.234615 -427.972642) (xy 76.227112 -427.995661) (xy 76.212854 -428.015229)
			(xy 76.19324 -428.029424) (xy 76.170197 -428.036854) (xy 76.15809 -428.037244) (xy 75.21829 -428.037244)
			(xy 75.206198 -428.036801) (xy 75.183195 -428.029339) (xy 75.163614 -428.015147) (xy 75.149364 -427.995608)
			(xy 75.141835 -427.972626) (xy 75.141328 -427.960536) (xy 75.141328 -427.348142) (xy 75.139781 -427.33365)
			(xy 75.138131 -427.30455) (xy 75.138026 -427.289976) (xy 73.234804 -427.289976) (xy 73.234804 -428.28972)
			(xy 77.138022 -428.28972) (xy 77.138117 -428.275146) (xy 77.139768 -428.246045) (xy 77.141324 -428.231554)
			(xy 77.141324 -427.14799) (xy 77.139781 -427.133498) (xy 77.138128 -427.104398) (xy 77.138022 -427.089824)
			(xy 77.138117 -427.07525) (xy 77.139769 -427.046149) (xy 77.141324 -427.031658) (xy 77.141324 -426.41901)
			(xy 77.14182 -426.406897) (xy 77.149303 -426.383857) (xy 77.163539 -426.364256) (xy 77.183135 -426.350014)
			(xy 77.206174 -426.342524) (xy 77.218286 -426.342048) (xy 78.158086 -426.342048) (xy 78.170209 -426.342472)
			(xy 78.193269 -426.349962) (xy 78.212885 -426.364212) (xy 78.227136 -426.383827) (xy 78.234627 -426.406887)
			(xy 78.235048 -426.41901) (xy 78.235048 -427.289976) (xy 79.138018 -427.289976) (xy 79.138109 -427.275402)
			(xy 79.139763 -427.246301) (xy 79.14132 -427.23181) (xy 79.14132 -426.147992) (xy 79.139777 -426.1335)
			(xy 79.138124 -426.1044) (xy 79.138018 -426.089826) (xy 79.138113 -426.075252) (xy 79.139765 -426.046151)
			(xy 79.14132 -426.03166) (xy 79.14132 -425.419012) (xy 79.141727 -425.406902) (xy 79.149226 -425.383872)
			(xy 79.163489 -425.364297) (xy 79.183114 -425.350102) (xy 79.20617 -425.342685) (xy 79.218282 -425.342304)
			(xy 80.158082 -425.342304) (xy 80.170167 -425.342822) (xy 80.193161 -425.35027) (xy 80.212738 -425.364444)
			(xy 80.226991 -425.383965) (xy 80.234529 -425.406929) (xy 80.235044 -425.419012) (xy 80.235044 -427.960536)
			(xy 80.234615 -427.972642) (xy 80.227111 -427.995663) (xy 80.212851 -428.015232) (xy 80.193235 -428.029427)
			(xy 80.17019 -428.036855) (xy 80.158082 -428.037244) (xy 79.218282 -428.037244) (xy 79.20619 -428.036808)
			(xy 79.183186 -428.029344) (xy 79.163605 -428.01515) (xy 79.149355 -427.995609) (xy 79.141827 -427.972627)
			(xy 79.14132 -427.960536) (xy 79.14132 -427.348142) (xy 79.139773 -427.33365) (xy 79.138123 -427.30455)
			(xy 79.138018 -427.289976) (xy 78.235048 -427.289976) (xy 78.235048 -428.28972) (xy 81.138014 -428.28972)
			(xy 81.138108 -428.275146) (xy 81.13976 -428.246045) (xy 81.141316 -428.231554) (xy 81.141316 -427.14799)
			(xy 81.139773 -427.133498) (xy 81.13812 -427.104398) (xy 81.138014 -427.089824) (xy 81.138108 -427.07525)
			(xy 81.13976 -427.046149) (xy 81.141316 -427.031658) (xy 81.141316 -426.41901) (xy 81.14182 -426.406898)
			(xy 81.149302 -426.383859) (xy 81.163536 -426.364259) (xy 81.18313 -426.350016) (xy 81.206166 -426.342525)
			(xy 81.218278 -426.342048) (xy 82.158078 -426.342048) (xy 82.170201 -426.342479) (xy 82.19326 -426.349966)
			(xy 82.212877 -426.364215) (xy 82.227128 -426.383829) (xy 82.234619 -426.406887) (xy 82.23504 -426.41901)
			(xy 82.23504 -427.289976) (xy 83.13801 -427.289976) (xy 83.1381 -427.275402) (xy 83.139755 -427.246301)
			(xy 83.141312 -427.23181) (xy 83.141312 -426.147992) (xy 83.139769 -426.1335) (xy 83.138116 -426.1044)
			(xy 83.13801 -426.089826) (xy 83.138105 -426.075252) (xy 83.139756 -426.046151) (xy 83.141312 -426.03166)
			(xy 83.141312 -425.419012) (xy 83.141727 -425.406903) (xy 83.149224 -425.383874) (xy 83.163486 -425.364299)
			(xy 83.183109 -425.350105) (xy 83.206163 -425.342686) (xy 83.218274 -425.342304) (xy 84.158074 -425.342304)
			(xy 84.170159 -425.342829) (xy 84.193152 -425.350274) (xy 84.21273 -425.364447) (xy 84.226982 -425.383966)
			(xy 84.234521 -425.406929) (xy 84.235036 -425.419012) (xy 84.235036 -427.960536) (xy 84.234615 -427.972643)
			(xy 84.22711 -427.995665) (xy 84.212848 -428.015235) (xy 84.19323 -428.029429) (xy 84.170183 -428.036856)
			(xy 84.158074 -428.037244) (xy 83.218274 -428.037244) (xy 83.206181 -428.036815) (xy 83.183177 -428.029349)
			(xy 83.163596 -428.015153) (xy 83.149347 -427.995611) (xy 83.141819 -427.972627) (xy 83.141312 -427.960536)
			(xy 83.141312 -427.348142) (xy 83.139765 -427.33365) (xy 83.138115 -427.30455) (xy 83.13801 -427.289976)
			(xy 82.23504 -427.289976) (xy 82.23504 -428.28972) (xy 85.138006 -428.28972) (xy 85.1381 -428.275146)
			(xy 85.139752 -428.246045) (xy 85.141308 -428.231554) (xy 85.141308 -427.14799) (xy 85.139765 -427.133498)
			(xy 85.138112 -427.104398) (xy 85.138006 -427.089824) (xy 85.1381 -427.07525) (xy 85.139752 -427.046149)
			(xy 85.141308 -427.031658) (xy 85.141308 -426.41901) (xy 85.14182 -426.406899) (xy 85.149301 -426.383861)
			(xy 85.163533 -426.364262) (xy 85.183125 -426.350019) (xy 85.206159 -426.342526) (xy 85.21827 -426.342048)
			(xy 86.15807 -426.342048) (xy 86.170192 -426.342486) (xy 86.193252 -426.349971) (xy 86.212868 -426.364218)
			(xy 86.22712 -426.38383) (xy 86.234611 -426.406888) (xy 86.235032 -426.41901) (xy 86.235032 -427.289976)
			(xy 87.138002 -427.289976) (xy 87.138092 -427.275402) (xy 87.139747 -427.246301) (xy 87.141304 -427.23181)
			(xy 87.141304 -426.147992) (xy 87.139761 -426.1335) (xy 87.138108 -426.1044) (xy 87.138002 -426.089826)
			(xy 87.138097 -426.075252) (xy 87.139748 -426.046151) (xy 87.141304 -426.03166) (xy 87.141304 -425.419012)
			(xy 87.141727 -425.406903) (xy 87.149223 -425.383876) (xy 87.163483 -425.364302) (xy 87.183104 -425.350107)
			(xy 87.206156 -425.342687) (xy 87.218266 -425.342304) (xy 88.158066 -425.342304) (xy 88.17015 -425.342836)
			(xy 88.193144 -425.350279) (xy 88.212721 -425.36445) (xy 88.226974 -425.383968) (xy 88.234513 -425.40693)
			(xy 88.235028 -425.419012) (xy 88.235028 -427.960536) (xy 88.234615 -427.972644) (xy 88.227109 -427.995668)
			(xy 88.212845 -428.015238) (xy 88.193225 -428.029432) (xy 88.170175 -428.036857) (xy 88.158066 -428.037244)
			(xy 87.218266 -428.037244) (xy 87.206173 -428.036821) (xy 87.183169 -428.029353) (xy 87.163588 -428.015156)
			(xy 87.149339 -427.995612) (xy 87.141811 -427.972628) (xy 87.141304 -427.960536) (xy 87.141304 -427.348142)
			(xy 87.139757 -427.33365) (xy 87.138107 -427.30455) (xy 87.138002 -427.289976) (xy 86.235032 -427.289976)
			(xy 86.235032 -428.28972) (xy 89.137998 -428.28972) (xy 89.138092 -428.275146) (xy 89.139744 -428.246045)
			(xy 89.1413 -428.231554) (xy 89.1413 -427.14799) (xy 89.139757 -427.133498) (xy 89.138104 -427.104398)
			(xy 89.137998 -427.089824) (xy 89.138092 -427.07525) (xy 89.139744 -427.046149) (xy 89.1413 -427.031658)
			(xy 89.1413 -426.41901) (xy 89.14182 -426.4069) (xy 89.1493 -426.383863) (xy 89.163531 -426.364265)
			(xy 89.18312 -426.350022) (xy 89.206152 -426.342527) (xy 89.218262 -426.342048) (xy 90.158062 -426.342048)
			(xy 90.170184 -426.342492) (xy 90.193243 -426.349975) (xy 90.21286 -426.36422) (xy 90.227112 -426.383832)
			(xy 90.234603 -426.406888) (xy 90.235024 -426.41901) (xy 90.235024 -427.289976) (xy 125.238002 -427.289976)
			(xy 125.238092 -427.275402) (xy 125.239747 -427.246301) (xy 125.241304 -427.23181) (xy 125.241304 -426.147992)
			(xy 125.239761 -426.1335) (xy 125.238108 -426.1044) (xy 125.238002 -426.089826) (xy 125.238097 -426.075252)
			(xy 125.239748 -426.046151) (xy 125.241304 -426.03166) (xy 125.241304 -425.419012) (xy 125.241727 -425.406903)
			(xy 125.249223 -425.383876) (xy 125.263483 -425.364302) (xy 125.283104 -425.350107) (xy 125.306156 -425.342687)
			(xy 125.318266 -425.342304) (xy 126.258066 -425.342304) (xy 126.27015 -425.342836) (xy 126.293144 -425.350279)
			(xy 126.312721 -425.36445) (xy 126.326974 -425.383968) (xy 126.334513 -425.40693) (xy 126.335028 -425.419012)
			(xy 126.335028 -427.960536) (xy 126.334615 -427.972644) (xy 126.327109 -427.995668) (xy 126.312845 -428.015238)
			(xy 126.293225 -428.029432) (xy 126.270175 -428.036857) (xy 126.258066 -428.037244) (xy 125.318266 -428.037244)
			(xy 125.306173 -428.036821) (xy 125.283169 -428.029353) (xy 125.263588 -428.015156) (xy 125.249339 -427.995612)
			(xy 125.241811 -427.972628) (xy 125.241304 -427.960536) (xy 125.241304 -427.348142) (xy 125.239757 -427.33365)
			(xy 125.238107 -427.30455) (xy 125.238002 -427.289976) (xy 90.235024 -427.289976) (xy 90.235024 -428.960534)
			(xy 90.234669 -428.972662) (xy 90.227162 -428.995729) (xy 90.212895 -429.015347) (xy 90.193264 -429.029595)
			(xy 90.170191 -429.03708) (xy 90.158062 -429.037496) (xy 89.218262 -429.037496) (xy 89.206149 -429.037021)
			(xy 89.18311 -429.029528) (xy 89.163512 -429.015285) (xy 89.14927 -428.995686) (xy 89.141778 -428.972647)
			(xy 89.1413 -428.960534) (xy 89.1413 -428.347886) (xy 89.139757 -428.333394) (xy 89.138104 -428.304294)
			(xy 89.137998 -428.28972) (xy 86.235032 -428.28972) (xy 86.235032 -428.960534) (xy 86.234617 -428.972653)
			(xy 86.227117 -428.995703) (xy 86.212861 -429.015307) (xy 86.193245 -429.029546) (xy 86.17019 -429.037027)
			(xy 86.15807 -429.037496) (xy 85.21827 -429.037496) (xy 85.206157 -429.037014) (xy 85.183119 -429.029523)
			(xy 85.16352 -429.015282) (xy 85.149279 -428.995685) (xy 85.141786 -428.972647) (xy 85.141308 -428.960534)
			(xy 85.141308 -428.347886) (xy 85.139765 -428.333394) (xy 85.138112 -428.304294) (xy 85.138006 -428.28972)
			(xy 82.23504 -428.28972) (xy 82.23504 -428.960534) (xy 82.234617 -428.972653) (xy 82.227118 -428.995701)
			(xy 82.212864 -429.015304) (xy 82.19325 -429.029543) (xy 82.170197 -429.037026) (xy 82.158078 -429.037496)
			(xy 81.218278 -429.037496) (xy 81.206166 -429.037008) (xy 81.183127 -429.029519) (xy 81.163529 -429.01528)
			(xy 81.149287 -428.995683) (xy 81.141794 -428.972646) (xy 81.141316 -428.960534) (xy 81.141316 -428.347886)
			(xy 81.139773 -428.333394) (xy 81.13812 -428.304294) (xy 81.138014 -428.28972) (xy 78.235048 -428.28972)
			(xy 78.235048 -428.960534) (xy 78.234617 -428.972652) (xy 78.227119 -428.995698) (xy 78.212867 -429.015301)
			(xy 78.193255 -429.029541) (xy 78.170204 -429.037025) (xy 78.158086 -429.037496) (xy 77.218286 -429.037496)
			(xy 77.206174 -429.037001) (xy 77.183136 -429.029514) (xy 77.163537 -429.015277) (xy 77.149295 -428.995682)
			(xy 77.141802 -428.972646) (xy 77.141324 -428.960534) (xy 77.141324 -428.347886) (xy 77.139781 -428.333394)
			(xy 77.138128 -428.304294) (xy 77.138022 -428.28972) (xy 73.234804 -428.28972) (xy 73.234804 -428.960534)
			(xy 73.234323 -428.972621) (xy 73.226862 -428.995615) (xy 73.212677 -429.015191) (xy 73.19315 -429.029442)
			(xy 73.170181 -429.036981) (xy 73.158096 -429.037496) (xy 72.218296 -429.037496) (xy 72.206187 -429.037087)
			(xy 72.183158 -429.029586) (xy 72.163585 -429.015323) (xy 72.149391 -428.995699) (xy 72.141971 -428.972645)
			(xy 72.141588 -428.960534) (xy 72.141588 -428.349918) (xy 72.139919 -428.334925) (xy 72.138141 -428.304806)
			(xy 72.138032 -428.28972) (xy 69.234812 -428.28972) (xy 69.234812 -428.960534) (xy 69.234421 -428.97263)
			(xy 69.226949 -428.99564) (xy 69.212744 -429.015223) (xy 69.193192 -429.029471) (xy 69.170199 -429.036994)
			(xy 69.158104 -429.037496) (xy 68.218304 -429.037496) (xy 68.206195 -429.03708) (xy 68.183167 -429.029582)
			(xy 68.163593 -429.01532) (xy 68.149399 -428.995698) (xy 68.141979 -428.972644) (xy 68.141596 -428.960534)
			(xy 68.141596 -428.349918) (xy 68.139927 -428.334925) (xy 68.138149 -428.304806) (xy 68.13804 -428.28972)
			(xy 65.23482 -428.28972) (xy 65.23482 -428.960534) (xy 65.234421 -428.972629) (xy 65.22695 -428.995638)
			(xy 65.212747 -429.015221) (xy 65.193197 -429.029469) (xy 65.170206 -429.036993) (xy 65.158112 -429.037496)
			(xy 64.218312 -429.037496) (xy 64.206203 -429.037073) (xy 64.183176 -429.029577) (xy 64.163602 -429.015317)
			(xy 64.149407 -428.995696) (xy 64.141987 -428.972644) (xy 64.141604 -428.960534) (xy 64.141604 -428.349918)
			(xy 64.139935 -428.334925) (xy 64.138157 -428.304806) (xy 64.138048 -428.28972) (xy 61.234828 -428.28972)
			(xy 61.234828 -428.960534) (xy 61.234421 -428.972629) (xy 61.226951 -428.995636) (xy 61.21275 -429.015218)
			(xy 61.193202 -429.029466) (xy 61.170213 -429.036992) (xy 61.15812 -429.037496) (xy 60.21832 -429.037496)
			(xy 60.206212 -429.037066) (xy 60.183185 -429.029572) (xy 60.163611 -429.015314) (xy 60.149416 -428.995695)
			(xy 60.141995 -428.972643) (xy 60.141612 -428.960534) (xy 60.141612 -428.349918) (xy 60.139943 -428.334925)
			(xy 60.138165 -428.304806) (xy 60.138056 -428.28972) (xy 49.0054 -428.28972) (xy 48.932448 -428.365522)
			(xy 48.780383 -428.51187) (xy 48.622824 -428.652286) (xy 48.460002 -428.786564) (xy 48.292156 -428.914507)
			(xy 48.119534 -429.035927) (xy 47.942387 -429.150646) (xy 47.760976 -429.258496) (xy 47.575567 -429.359318)
			(xy 47.386432 -429.452965) (xy 47.19385 -429.539298) (xy 46.998102 -429.618192) (xy 46.799475 -429.68953)
			(xy 46.598262 -429.753207) (xy 46.394758 -429.809131) (xy 46.189261 -429.857219) (xy 45.982073 -429.897401)
			(xy 45.773498 -429.929618) (xy 45.563841 -429.953821) (xy 45.353412 -429.969977) (xy 45.142518 -429.978061)
			(xy 44.93147 -429.978061) (xy 44.720576 -429.969977) (xy 44.510147 -429.953821) (xy 44.30049 -429.929618)
			(xy 44.091915 -429.897401) (xy 43.884727 -429.857219) (xy 43.67923 -429.809131) (xy 43.475726 -429.753207)
			(xy 43.274513 -429.68953) (xy 43.075886 -429.618192) (xy 42.880138 -429.539298) (xy 42.687556 -429.452965)
			(xy 42.498421 -429.359318) (xy 42.313012 -429.258496) (xy 42.131601 -429.150646) (xy 41.954454 -429.035927)
			(xy 41.781832 -428.914507) (xy 41.613986 -428.786564) (xy 41.451164 -428.652286) (xy 41.293605 -428.51187)
			(xy 41.14154 -428.365522) (xy 40.995192 -428.213457) (xy 40.854776 -428.055898) (xy 40.720498 -427.893076)
			(xy 40.592555 -427.72523) (xy 40.471135 -427.552608) (xy 40.356416 -427.375461) (xy 40.248566 -427.19405)
			(xy 40.147744 -427.008641) (xy 40.054097 -426.819506) (xy 39.967764 -426.626924) (xy 39.88887 -426.431176)
			(xy 39.817532 -426.232549) (xy 39.753855 -426.031336) (xy 39.697931 -425.827832) (xy 39.649843 -425.622335)
			(xy 39.609661 -425.415147) (xy 39.577444 -425.206572) (xy 39.553241 -424.996915) (xy 39.537085 -424.786486)
			(xy 39.529001 -424.575592) (xy 39.528496 -424.470068) (xy 7.00913 -424.470068) (xy 7.00913 -430.889918)
			(xy 58.13806 -430.889918) (xy 58.138169 -430.874832) (xy 58.139951 -430.844714) (xy 58.141616 -430.82972)
			(xy 58.141616 -429.749966) (xy 58.139951 -429.734972) (xy 58.13817 -429.704854) (xy 58.13806 -429.689768)
			(xy 58.138174 -429.674682) (xy 58.139952 -429.644564) (xy 58.141616 -429.62957) (xy 58.141616 -429.018954)
			(xy 58.142068 -429.006864) (xy 58.149534 -428.983866) (xy 58.163726 -428.964289) (xy 58.18326 -428.950039)
			(xy 58.206236 -428.942504) (xy 58.218324 -428.941992) (xy 59.158124 -428.941992) (xy 59.170233 -428.942396)
			(xy 59.19326 -428.949901) (xy 59.212832 -428.964166) (xy 59.227026 -428.983789) (xy 59.234448 -429.006843)
			(xy 59.234832 -429.018954) (xy 59.234832 -431.560478) (xy 59.234373 -431.572569) (xy 59.226919 -431.595574)
			(xy 59.212732 -431.615156) (xy 59.193194 -431.629407) (xy 59.170214 -431.636934) (xy 59.158124 -431.63744)
			(xy 58.218324 -431.63744) (xy 58.20622 -431.636964) (xy 58.183201 -431.629476) (xy 58.163631 -431.615228)
			(xy 58.149434 -431.595622) (xy 58.142005 -431.572583) (xy 58.141616 -431.560478) (xy 58.141616 -430.950116)
			(xy 58.139947 -430.935123) (xy 58.138169 -430.905004) (xy 58.13806 -430.889918) (xy 7.00913 -430.889918)
			(xy 7.00913 -431.889916) (xy 60.138056 -431.889916) (xy 60.138165 -431.87483) (xy 60.139947 -431.844712)
			(xy 60.141612 -431.829718) (xy 60.141612 -430.749964) (xy 60.139947 -430.73497) (xy 60.138166 -430.704852)
			(xy 60.138056 -430.689766) (xy 60.13817 -430.67468) (xy 60.139948 -430.644562) (xy 60.141612 -430.629568)
			(xy 60.141612 -430.018952) (xy 60.142024 -430.006873) (xy 60.149502 -429.983901) (xy 60.163711 -429.964363)
			(xy 60.183262 -429.950171) (xy 60.206241 -429.942713) (xy 60.21832 -429.942244) (xy 61.15812 -429.942244)
			(xy 61.170191 -429.942747) (xy 61.19315 -429.950209) (xy 61.212683 -429.964397) (xy 61.226878 -429.983924)
			(xy 61.234349 -430.006881) (xy 61.234828 -430.018952) (xy 61.234828 -430.889918) (xy 62.138052 -430.889918)
			(xy 62.138161 -430.874832) (xy 62.139943 -430.844714) (xy 62.141608 -430.82972) (xy 62.141608 -429.749966)
			(xy 62.139943 -429.734972) (xy 62.138162 -429.704854) (xy 62.138052 -429.689768) (xy 62.138166 -429.674682)
			(xy 62.139944 -429.644564) (xy 62.141608 -429.62957) (xy 62.141608 -429.018954) (xy 62.142068 -429.006865)
			(xy 62.149533 -428.983868) (xy 62.163723 -428.964292) (xy 62.183255 -428.950042) (xy 62.206229 -428.942505)
			(xy 62.218316 -428.941992) (xy 63.158116 -428.941992) (xy 63.170225 -428.942402) (xy 63.193251 -428.949905)
			(xy 63.212824 -428.964169) (xy 63.227018 -428.983791) (xy 63.23444 -429.006844) (xy 63.234824 -429.018954)
			(xy 63.234824 -431.560478) (xy 63.234373 -431.57257) (xy 63.226918 -431.595576) (xy 63.212729 -431.615159)
			(xy 63.193189 -431.629409) (xy 63.170206 -431.636935) (xy 63.158116 -431.63744) (xy 62.218316 -431.63744)
			(xy 62.206212 -431.63697) (xy 62.183192 -431.62948) (xy 62.163622 -431.615231) (xy 62.149426 -431.595623)
			(xy 62.141997 -431.572583) (xy 62.141608 -431.560478) (xy 62.141608 -430.950116) (xy 62.139939 -430.935123)
			(xy 62.138161 -430.905004) (xy 62.138052 -430.889918) (xy 61.234828 -430.889918) (xy 61.234828 -431.889916)
			(xy 64.138048 -431.889916) (xy 64.138157 -431.87483) (xy 64.139939 -431.844712) (xy 64.141604 -431.829718)
			(xy 64.141604 -430.749964) (xy 64.139939 -430.73497) (xy 64.138158 -430.704852) (xy 64.138048 -430.689766)
			(xy 64.138162 -430.67468) (xy 64.13994 -430.644562) (xy 64.141604 -430.629568) (xy 64.141604 -430.018952)
			(xy 64.142023 -430.006874) (xy 64.149501 -429.983903) (xy 64.163708 -429.964366) (xy 64.183257 -429.950173)
			(xy 64.206233 -429.942714) (xy 64.218312 -429.942244) (xy 65.158112 -429.942244) (xy 65.170182 -429.942753)
			(xy 65.193142 -429.950213) (xy 65.212674 -429.9644) (xy 65.22687 -429.983926) (xy 65.234341 -430.006882)
			(xy 65.23482 -430.018952) (xy 65.23482 -430.889918) (xy 66.138044 -430.889918) (xy 66.138153 -430.874832)
			(xy 66.139935 -430.844714) (xy 66.1416 -430.82972) (xy 66.1416 -429.749966) (xy 66.139935 -429.734972)
			(xy 66.138154 -429.704854) (xy 66.138044 -429.689768) (xy 66.138158 -429.674682) (xy 66.139936 -429.644564)
			(xy 66.1416 -429.62957) (xy 66.1416 -429.018954) (xy 66.142067 -429.006866) (xy 66.149532 -428.983871)
			(xy 66.16372 -428.964295) (xy 66.18325 -428.950044) (xy 66.206222 -428.942507) (xy 66.218308 -428.941992)
			(xy 67.158108 -428.941992) (xy 67.170217 -428.942409) (xy 67.193243 -428.94991) (xy 67.212815 -428.964172)
			(xy 67.22701 -428.983792) (xy 67.234432 -429.006844) (xy 67.234816 -429.018954) (xy 67.234816 -431.560478)
			(xy 67.234373 -431.572571) (xy 67.226917 -431.595578) (xy 67.212726 -431.615162) (xy 67.193184 -431.629412)
			(xy 67.170199 -431.636937) (xy 67.158108 -431.63744) (xy 66.218308 -431.63744) (xy 66.206204 -431.636978)
			(xy 66.183183 -431.629485) (xy 66.163613 -431.615234) (xy 66.149417 -431.595625) (xy 66.141989 -431.572584)
			(xy 66.1416 -431.560478) (xy 66.1416 -430.950116) (xy 66.139931 -430.935123) (xy 66.138153 -430.905004)
			(xy 66.138044 -430.889918) (xy 65.23482 -430.889918) (xy 65.23482 -431.889916) (xy 68.13804 -431.889916)
			(xy 68.138151 -431.87483) (xy 68.139933 -431.844712) (xy 68.141596 -431.829718) (xy 68.141596 -430.749964)
			(xy 68.139931 -430.73497) (xy 68.13815 -430.704852) (xy 68.13804 -430.689766) (xy 68.138154 -430.67468)
			(xy 68.139932 -430.644562) (xy 68.141596 -430.629568) (xy 68.141596 -430.018952) (xy 68.142023 -430.006875)
			(xy 68.149499 -429.983905) (xy 68.163705 -429.964368) (xy 68.183252 -429.950176) (xy 68.206226 -429.942715)
			(xy 68.218304 -429.942244) (xy 69.158104 -429.942244) (xy 69.170174 -429.94276) (xy 69.193133 -429.950218)
			(xy 69.212666 -429.964403) (xy 69.226862 -429.983927) (xy 69.234333 -430.006882) (xy 69.234812 -430.018952)
			(xy 69.234812 -430.889918) (xy 70.138036 -430.889918) (xy 70.138147 -430.874832) (xy 70.139929 -430.844714)
			(xy 70.141592 -430.82972) (xy 70.141592 -429.749966) (xy 70.139927 -429.734972) (xy 70.138146 -429.704854)
			(xy 70.138036 -429.689768) (xy 70.138152 -429.674683) (xy 70.13993 -429.644564) (xy 70.141592 -429.62957)
			(xy 70.141592 -429.018954) (xy 70.142067 -429.006867) (xy 70.149531 -428.983873) (xy 70.163717 -428.964298)
			(xy 70.183245 -428.950047) (xy 70.206214 -428.942508) (xy 70.2183 -428.941992) (xy 71.1581 -428.941992)
			(xy 71.170208 -428.942416) (xy 71.193234 -428.949914) (xy 71.212807 -428.964174) (xy 71.227001 -428.983794)
			(xy 71.234424 -429.006845) (xy 71.234808 -429.018954) (xy 71.234808 -431.560478) (xy 71.234275 -431.572562)
			(xy 71.22683 -431.595553) (xy 71.212659 -431.61513) (xy 71.193142 -431.629383) (xy 71.170182 -431.636924)
			(xy 71.1581 -431.63744) (xy 70.2183 -431.63744) (xy 70.206195 -431.636984) (xy 70.183175 -431.62949)
			(xy 70.163605 -431.615237) (xy 70.149409 -431.595626) (xy 70.141981 -431.572584) (xy 70.141592 -431.560478)
			(xy 70.141592 -430.950116) (xy 70.139923 -430.935123) (xy 70.138145 -430.905004) (xy 70.138036 -430.889918)
			(xy 69.234812 -430.889918) (xy 69.234812 -431.889916) (xy 72.138032 -431.889916) (xy 72.138143 -431.87483)
			(xy 72.139925 -431.844712) (xy 72.141588 -431.829718) (xy 72.141588 -430.749964) (xy 72.139923 -430.73497)
			(xy 72.138142 -430.704852) (xy 72.138032 -430.689766) (xy 72.138148 -430.674681) (xy 72.139926 -430.644562)
			(xy 72.141588 -430.629568) (xy 72.141588 -430.018952) (xy 72.142023 -430.006875) (xy 72.149498 -429.983907)
			(xy 72.163703 -429.964371) (xy 72.183247 -429.950178) (xy 72.206219 -429.942716) (xy 72.218296 -429.942244)
			(xy 73.158096 -429.942244) (xy 73.170166 -429.942767) (xy 73.193124 -429.950222) (xy 73.212657 -429.964406)
			(xy 73.226854 -429.983929) (xy 73.234325 -430.006883) (xy 73.234804 -430.018952) (xy 73.234804 -430.889918)
			(xy 75.138026 -430.889918) (xy 75.13812 -430.875344) (xy 75.139772 -430.846243) (xy 75.141328 -430.831752)
			(xy 75.141328 -429.747934) (xy 75.13978 -429.733442) (xy 75.13813 -429.704342) (xy 75.138026 -429.689768)
			(xy 75.138125 -429.675194) (xy 75.139774 -429.646093) (xy 75.141328 -429.631602) (xy 75.141328 -429.018954)
			(xy 75.141772 -429.006838) (xy 75.149271 -428.983795) (xy 75.163521 -428.964195) (xy 75.183127 -428.949955)
			(xy 75.206174 -428.942467) (xy 75.21829 -428.941992) (xy 76.15809 -428.941992) (xy 76.170199 -428.94252)
			(xy 76.193235 -428.949999) (xy 76.212832 -428.964228) (xy 76.227076 -428.983815) (xy 76.234572 -429.006845)
			(xy 76.235052 -429.018954) (xy 76.235052 -431.560478) (xy 76.234621 -431.572601) (xy 76.227134 -431.59566)
			(xy 76.212885 -431.615277) (xy 76.193271 -431.629528) (xy 76.170213 -431.637019) (xy 76.15809 -431.63744)
			(xy 75.21829 -431.63744) (xy 75.206165 -431.637048) (xy 75.183102 -431.62955) (xy 75.163485 -431.615292)
			(xy 75.149235 -431.59567) (xy 75.141747 -431.572604) (xy 75.141328 -431.560478) (xy 75.141328 -430.948084)
			(xy 75.139785 -430.933592) (xy 75.138132 -430.904492) (xy 75.138026 -430.889918) (xy 73.234804 -430.889918)
			(xy 73.234804 -431.889916) (xy 77.138022 -431.889916) (xy 77.138116 -431.875342) (xy 77.139768 -431.846241)
			(xy 77.141324 -431.83175) (xy 77.141324 -430.747932) (xy 77.139776 -430.73344) (xy 77.138126 -430.70434)
			(xy 77.138022 -430.689766) (xy 77.138121 -430.675192) (xy 77.13977 -430.646091) (xy 77.141324 -430.6316)
			(xy 77.141324 -430.018952) (xy 77.141676 -430.006838) (xy 77.149191 -429.983805) (xy 77.163469 -429.964231)
			(xy 77.183105 -429.950039) (xy 77.20617 -429.942624) (xy 77.218286 -429.942244) (xy 78.158086 -429.942244)
			(xy 78.170175 -429.942719) (xy 78.193176 -429.950173) (xy 78.212757 -429.964357) (xy 78.227007 -429.983889)
			(xy 78.234539 -430.006864) (xy 78.235048 -430.018952) (xy 78.235048 -430.889918) (xy 79.138018 -430.889918)
			(xy 79.138112 -430.875344) (xy 79.139764 -430.846243) (xy 79.14132 -430.831752) (xy 79.14132 -429.747934)
			(xy 79.139772 -429.733442) (xy 79.138122 -429.704342) (xy 79.138018 -429.689768) (xy 79.138117 -429.675194)
			(xy 79.139766 -429.646093) (xy 79.14132 -429.631602) (xy 79.14132 -429.018954) (xy 79.141772 -429.006839)
			(xy 79.14927 -428.983797) (xy 79.163518 -428.964198) (xy 79.183122 -428.949957) (xy 79.206167 -428.942468)
			(xy 79.218282 -428.941992) (xy 80.158082 -428.941992) (xy 80.170191 -428.942526) (xy 80.193226 -428.950003)
			(xy 80.212824 -428.964231) (xy 80.227068 -428.983817) (xy 80.234563 -429.006845) (xy 80.235044 -429.018954)
			(xy 80.235044 -431.560478) (xy 80.234621 -431.572601) (xy 80.227133 -431.595663) (xy 80.212882 -431.61528)
			(xy 80.193266 -431.629531) (xy 80.170205 -431.63702) (xy 80.158082 -431.63744) (xy 79.218282 -431.63744)
			(xy 79.206156 -431.637055) (xy 79.183093 -431.629555) (xy 79.163476 -431.615295) (xy 79.149227 -431.595671)
			(xy 79.141739 -431.572604) (xy 79.14132 -431.560478) (xy 79.14132 -430.948084) (xy 79.139777 -430.933592)
			(xy 79.138124 -430.904492) (xy 79.138018 -430.889918) (xy 78.235048 -430.889918) (xy 78.235048 -431.889916)
			(xy 81.138014 -431.889916) (xy 81.138108 -431.875342) (xy 81.13976 -431.846241) (xy 81.141316 -431.83175)
			(xy 81.141316 -430.747932) (xy 81.139768 -430.73344) (xy 81.138118 -430.70434) (xy 81.138014 -430.689766)
			(xy 81.138112 -430.675192) (xy 81.139761 -430.646091) (xy 81.141316 -430.6316) (xy 81.141316 -430.018952)
			(xy 81.141676 -430.006839) (xy 81.14919 -429.983807) (xy 81.163466 -429.964234) (xy 81.1831 -429.950041)
			(xy 81.206163 -429.942625) (xy 81.218278 -429.942244) (xy 82.158078 -429.942244) (xy 82.170167 -429.942726)
			(xy 82.193167 -429.950177) (xy 82.212748 -429.96436) (xy 82.226999 -429.983891) (xy 82.234531 -430.006865)
			(xy 82.23504 -430.018952) (xy 82.23504 -430.889918) (xy 83.13801 -430.889918) (xy 83.138104 -430.875344)
			(xy 83.139756 -430.846243) (xy 83.141312 -430.831752) (xy 83.141312 -429.747934) (xy 83.139764 -429.733442)
			(xy 83.138114 -429.704342) (xy 83.13801 -429.689768) (xy 83.138108 -429.675194) (xy 83.139758 -429.646093)
			(xy 83.141312 -429.631602) (xy 83.141312 -429.018954) (xy 83.141772 -429.00684) (xy 83.149269 -428.983799)
			(xy 83.163515 -428.964201) (xy 83.183117 -428.94996) (xy 83.20616 -428.942469) (xy 83.218274 -428.941992)
			(xy 84.158074 -428.941992) (xy 84.170183 -428.942533) (xy 84.193217 -428.950008) (xy 84.212815 -428.964233)
			(xy 84.227059 -428.983818) (xy 84.234555 -429.006846) (xy 84.235036 -429.018954) (xy 84.235036 -431.560478)
			(xy 84.234621 -431.572602) (xy 84.227132 -431.595665) (xy 84.21288 -431.615282) (xy 84.193261 -431.629533)
			(xy 84.170198 -431.637022) (xy 84.158074 -431.63744) (xy 83.218274 -431.63744) (xy 83.206156 -431.63701)
			(xy 83.183108 -431.629513) (xy 83.163505 -431.615261) (xy 83.149265 -431.595649) (xy 83.141782 -431.572596)
			(xy 83.141312 -431.560478) (xy 83.141312 -430.948084) (xy 83.139769 -430.933592) (xy 83.138116 -430.904492)
			(xy 83.13801 -430.889918) (xy 82.23504 -430.889918) (xy 82.23504 -431.889916) (xy 85.138006 -431.889916)
			(xy 85.1381 -431.875342) (xy 85.139752 -431.846241) (xy 85.141308 -431.83175) (xy 85.141308 -430.747932)
			(xy 85.13976 -430.73344) (xy 85.13811 -430.70434) (xy 85.138006 -430.689766) (xy 85.138104 -430.675192)
			(xy 85.139753 -430.646091) (xy 85.141308 -430.6316) (xy 85.141308 -430.018952) (xy 85.141676 -430.00684)
			(xy 85.149189 -429.98381) (xy 85.163463 -429.964237) (xy 85.183095 -429.950044) (xy 85.206156 -429.942626)
			(xy 85.21827 -429.942244) (xy 86.15807 -429.942244) (xy 86.170158 -429.942733) (xy 86.193159 -429.950182)
			(xy 86.212739 -429.964363) (xy 86.226991 -429.983892) (xy 86.234523 -430.006865) (xy 86.235032 -430.018952)
			(xy 86.235032 -430.889918) (xy 87.138002 -430.889918) (xy 87.138096 -430.875344) (xy 87.139748 -430.846243)
			(xy 87.141304 -430.831752) (xy 87.141304 -429.747934) (xy 87.139756 -429.733442) (xy 87.138106 -429.704342)
			(xy 87.138002 -429.689768) (xy 87.1381 -429.675194) (xy 87.13975 -429.646093) (xy 87.141304 -429.631602)
			(xy 87.141304 -429.018954) (xy 87.141772 -429.00684) (xy 87.149268 -428.983801) (xy 87.163512 -428.964203)
			(xy 87.183112 -428.949962) (xy 87.206152 -428.94247) (xy 87.218266 -428.941992) (xy 88.158066 -428.941992)
			(xy 88.170174 -428.94254) (xy 88.193209 -428.950012) (xy 88.212807 -428.964236) (xy 88.227051 -428.98382)
			(xy 88.234547 -429.006846) (xy 88.235028 -429.018954) (xy 88.235028 -431.560478) (xy 88.234621 -431.572603)
			(xy 88.22713 -431.595667) (xy 88.212877 -431.615285) (xy 88.193256 -431.629536) (xy 88.170191 -431.637023)
			(xy 88.158066 -431.63744) (xy 87.218266 -431.63744) (xy 87.206147 -431.637017) (xy 87.183099 -431.629518)
			(xy 87.163496 -431.615264) (xy 87.149257 -431.59565) (xy 87.141774 -431.572597) (xy 87.141304 -431.560478)
			(xy 87.141304 -430.948084) (xy 87.13976 -430.933592) (xy 87.138108 -430.904492) (xy 87.138002 -430.889918)
			(xy 86.235032 -430.889918) (xy 86.235032 -431.889916) (xy 89.137998 -431.889916) (xy 89.138092 -431.875342)
			(xy 89.139744 -431.846241) (xy 89.1413 -431.83175) (xy 89.1413 -430.747932) (xy 89.139752 -430.73344)
			(xy 89.138102 -430.70434) (xy 89.137998 -430.689766) (xy 89.138096 -430.675192) (xy 89.139746 -430.646091)
			(xy 89.1413 -430.6316) (xy 89.1413 -430.018952) (xy 89.141676 -430.006841) (xy 89.149188 -429.983812)
			(xy 89.16346 -429.96424) (xy 89.18309 -429.950047) (xy 89.206149 -429.942627) (xy 89.218262 -429.942244)
			(xy 90.158062 -429.942244) (xy 90.17015 -429.94274) (xy 90.19315 -429.950187) (xy 90.212731 -429.964366)
			(xy 90.226983 -429.983894) (xy 90.234515 -430.006866) (xy 90.235024 -430.018952) (xy 90.235024 -431.360072)
			(xy 108.40466 -431.360072) (xy 108.405158 -431.275192) (xy 108.413115 -431.105619) (xy 108.429011 -430.936605)
			(xy 108.452812 -430.768522) (xy 108.484466 -430.601739) (xy 108.523902 -430.436623) (xy 108.571034 -430.273538)
			(xy 108.625758 -430.11284) (xy 108.687955 -429.954885) (xy 108.757487 -429.800018) (xy 108.834202 -429.648581)
			(xy 108.91793 -429.500905) (xy 109.008488 -429.357317) (xy 109.105677 -429.218131) (xy 109.209284 -429.083654)
			(xy 109.319079 -428.954181) (xy 109.434823 -428.829996) (xy 109.55626 -428.711373) (xy 109.683124 -428.598572)
			(xy 109.815135 -428.491842) (xy 109.952005 -428.391417) (xy 110.09343 -428.297518) (xy 110.239102 -428.21035)
			(xy 110.3887 -428.130107) (xy 110.541894 -428.056963) (xy 110.698348 -427.991081) (xy 110.857718 -427.932604)
			(xy 111.019654 -427.881662) (xy 111.1838 -427.838366) (xy 111.349795 -427.802811) (xy 111.517274 -427.775076)
			(xy 111.685869 -427.755222) (xy 111.855209 -427.743292) (xy 112.024922 -427.739313) (xy 112.194635 -427.743292)
			(xy 112.363975 -427.755222) (xy 112.53257 -427.775076) (xy 112.700049 -427.802811) (xy 112.866044 -427.838366)
			(xy 113.03019 -427.881662) (xy 113.192126 -427.932604) (xy 113.351496 -427.991081) (xy 113.50795 -428.056963)
			(xy 113.661144 -428.130107) (xy 113.810742 -428.21035) (xy 113.943382 -428.28972) (xy 127.237998 -428.28972)
			(xy 127.238092 -428.275146) (xy 127.239744 -428.246045) (xy 127.2413 -428.231554) (xy 127.2413 -427.14799)
			(xy 127.239757 -427.133498) (xy 127.238104 -427.104398) (xy 127.237998 -427.089824) (xy 127.238092 -427.07525)
			(xy 127.239744 -427.046149) (xy 127.2413 -427.031658) (xy 127.2413 -426.41901) (xy 127.24182 -426.4069)
			(xy 127.2493 -426.383863) (xy 127.263531 -426.364265) (xy 127.28312 -426.350022) (xy 127.306152 -426.342527)
			(xy 127.318262 -426.342048) (xy 128.258062 -426.342048) (xy 128.270184 -426.342492) (xy 128.293243 -426.349975)
			(xy 128.31286 -426.36422) (xy 128.327112 -426.383832) (xy 128.334603 -426.406888) (xy 128.335024 -426.41901)
			(xy 128.335024 -427.289976) (xy 129.237994 -427.289976) (xy 129.238084 -427.275402) (xy 129.239739 -427.246301)
			(xy 129.241296 -427.23181) (xy 129.241296 -426.147992) (xy 129.239753 -426.1335) (xy 129.2381 -426.1044)
			(xy 129.237994 -426.089826) (xy 129.238089 -426.075252) (xy 129.23974 -426.046151) (xy 129.241296 -426.03166)
			(xy 129.241296 -425.419012) (xy 129.241727 -425.406904) (xy 129.249222 -425.383878) (xy 129.26348 -425.364305)
			(xy 129.283099 -425.35011) (xy 129.306149 -425.342688) (xy 129.318258 -425.342304) (xy 130.258058 -425.342304)
			(xy 130.270142 -425.342842) (xy 130.293135 -425.350283) (xy 130.312713 -425.364453) (xy 130.326966 -425.383969)
			(xy 130.334505 -425.40693) (xy 130.33502 -425.419012) (xy 130.33502 -427.960536) (xy 130.334615 -427.972645)
			(xy 130.327108 -427.99567) (xy 130.312843 -428.01524) (xy 130.29322 -428.029435) (xy 130.270168 -428.036858)
			(xy 130.258058 -428.037244) (xy 129.318258 -428.037244) (xy 129.306165 -428.036828) (xy 129.28316 -428.029358)
			(xy 129.263579 -428.015159) (xy 129.249331 -427.995614) (xy 129.241803 -427.972628) (xy 129.241296 -427.960536)
			(xy 129.241296 -427.348142) (xy 129.239749 -427.33365) (xy 129.238099 -427.30455) (xy 129.237994 -427.289976)
			(xy 128.335024 -427.289976) (xy 128.335024 -428.28972) (xy 131.23799 -428.28972) (xy 131.238084 -428.275146)
			(xy 131.239736 -428.246045) (xy 131.241292 -428.231554) (xy 131.241292 -427.14799) (xy 131.239749 -427.133498)
			(xy 131.238096 -427.104398) (xy 131.23799 -427.089824) (xy 131.238085 -427.07525) (xy 131.239736 -427.046149)
			(xy 131.241292 -427.031658) (xy 131.241292 -426.41901) (xy 131.24182 -426.406901) (xy 131.249299 -426.383865)
			(xy 131.263528 -426.364268) (xy 131.283115 -426.350024) (xy 131.306145 -426.342528) (xy 131.318254 -426.342048)
			(xy 132.258054 -426.342048) (xy 132.270175 -426.342499) (xy 132.293234 -426.34998) (xy 132.312851 -426.364223)
			(xy 132.327104 -426.383833) (xy 132.334595 -426.406889) (xy 132.335016 -426.41901) (xy 132.335016 -427.289976)
			(xy 133.237986 -427.289976) (xy 133.238076 -427.275402) (xy 133.239731 -427.246301) (xy 133.241288 -427.23181)
			(xy 133.241288 -426.147992) (xy 133.239745 -426.1335) (xy 133.238092 -426.1044) (xy 133.237986 -426.089826)
			(xy 133.238081 -426.075252) (xy 133.239732 -426.046151) (xy 133.241288 -426.03166) (xy 133.241288 -425.419012)
			(xy 133.241727 -425.406905) (xy 133.249221 -425.38388) (xy 133.263477 -425.364308) (xy 133.283094 -425.350113)
			(xy 133.306142 -425.342689) (xy 133.31825 -425.342304) (xy 134.25805 -425.342304) (xy 134.270133 -425.342849)
			(xy 134.293126 -425.350288) (xy 134.312704 -425.364455) (xy 134.326958 -425.383971) (xy 134.334497 -425.406931)
			(xy 134.335012 -425.419012) (xy 134.335012 -427.960536) (xy 134.334614 -427.972646) (xy 134.327107 -427.995672)
			(xy 134.31284 -428.015243) (xy 134.293215 -428.029437) (xy 134.270161 -428.036859) (xy 134.25805 -428.037244)
			(xy 133.31825 -428.037244) (xy 133.306161 -428.03675) (xy 133.28316 -428.029305) (xy 133.263578 -428.015126)
			(xy 133.249326 -427.995597) (xy 133.241795 -427.972623) (xy 133.241288 -427.960536) (xy 133.241288 -427.348142)
			(xy 133.239741 -427.33365) (xy 133.238091 -427.30455) (xy 133.237986 -427.289976) (xy 132.335016 -427.289976)
			(xy 132.335016 -428.28972) (xy 135.237982 -428.28972) (xy 135.238076 -428.275146) (xy 135.239728 -428.246045)
			(xy 135.241284 -428.231554) (xy 135.241284 -427.14799) (xy 135.239741 -427.133498) (xy 135.238088 -427.104398)
			(xy 135.237982 -427.089824) (xy 135.238077 -427.07525) (xy 135.239728 -427.046149) (xy 135.241284 -427.031658)
			(xy 135.241284 -426.41901) (xy 135.241669 -426.406883) (xy 135.249164 -426.383817) (xy 135.263423 -426.364198)
			(xy 135.283049 -426.349948) (xy 135.306119 -426.342464) (xy 135.318246 -426.342048) (xy 136.258046 -426.342048)
			(xy 136.270164 -426.342473) (xy 136.29321 -426.349974) (xy 136.312812 -426.364228) (xy 136.327052 -426.38384)
			(xy 136.334536 -426.406892) (xy 136.335008 -426.41901) (xy 136.335008 -427.289976) (xy 137.237978 -427.289976)
			(xy 137.238068 -427.275402) (xy 137.239723 -427.246301) (xy 137.24128 -427.23181) (xy 137.24128 -426.147992)
			(xy 137.239737 -426.1335) (xy 137.238084 -426.1044) (xy 137.237978 -426.089826) (xy 137.238073 -426.075252)
			(xy 137.239724 -426.046151) (xy 137.24128 -426.03166) (xy 137.24128 -425.419012) (xy 137.241727 -425.406906)
			(xy 137.24922 -425.383882) (xy 137.263475 -425.364311) (xy 137.283089 -425.350115) (xy 137.306135 -425.342691)
			(xy 137.318242 -425.342304) (xy 138.258042 -425.342304) (xy 138.27013 -425.342771) (xy 138.293126 -425.350235)
			(xy 138.312702 -425.364423) (xy 138.326953 -425.383953) (xy 138.33449 -425.406925) (xy 138.335004 -425.419012)
			(xy 138.335004 -427.960536) (xy 138.334614 -427.972646) (xy 138.327106 -427.995674) (xy 138.312837 -428.015246)
			(xy 138.29321 -428.02944) (xy 138.270154 -428.03686) (xy 138.258042 -428.037244) (xy 137.318242 -428.037244)
			(xy 137.306153 -428.036757) (xy 137.283151 -428.029309) (xy 137.263569 -428.015129) (xy 137.249318 -427.995598)
			(xy 137.241787 -427.972623) (xy 137.24128 -427.960536) (xy 137.24128 -427.348142) (xy 137.239733 -427.33365)
			(xy 137.238083 -427.30455) (xy 137.237978 -427.289976) (xy 136.335008 -427.289976) (xy 136.335008 -428.28972)
			(xy 139.237974 -428.28972) (xy 139.238068 -428.275146) (xy 139.23972 -428.246045) (xy 139.241276 -428.231554)
			(xy 139.241276 -427.14799) (xy 139.239733 -427.133498) (xy 139.23808 -427.104398) (xy 139.237974 -427.089824)
			(xy 139.238069 -427.07525) (xy 139.23972 -427.046149) (xy 139.241276 -427.031658) (xy 139.241276 -426.41901)
			(xy 139.241669 -426.406884) (xy 139.249163 -426.383819) (xy 139.26342 -426.364201) (xy 139.283044 -426.34995)
			(xy 139.306112 -426.342465) (xy 139.318238 -426.342048) (xy 140.258038 -426.342048) (xy 140.270156 -426.342479)
			(xy 140.293202 -426.349978) (xy 140.312804 -426.36423) (xy 140.327044 -426.383841) (xy 140.334528 -426.406892)
			(xy 140.335 -426.41901) (xy 140.335 -427.289976) (xy 142.237968 -427.289976) (xy 142.238082 -427.274891)
			(xy 142.23986 -427.244772) (xy 142.241524 -427.229778) (xy 142.241524 -426.150024) (xy 142.239855 -426.135031)
			(xy 142.238077 -426.104912) (xy 142.237968 -426.089826) (xy 142.238078 -426.07474) (xy 142.239859 -426.044622)
			(xy 142.241524 -426.029628) (xy 142.241524 -425.419012) (xy 142.241924 -425.406927) (xy 142.249392 -425.383939)
			(xy 142.2636 -425.364386) (xy 142.283157 -425.350183) (xy 142.306147 -425.34272) (xy 142.318232 -425.342304)
			(xy 143.258032 -425.342304) (xy 143.270109 -425.342737) (xy 143.29308 -425.35021) (xy 143.312617 -425.364414)
			(xy 143.32681 -425.38396) (xy 143.33427 -425.406934) (xy 143.33474 -425.419012) (xy 143.33474 -427.960536)
			(xy 143.334267 -427.972609) (xy 143.326799 -427.995572) (xy 143.312603 -428.015106) (xy 143.293069 -428.0293)
			(xy 143.270105 -428.036768) (xy 143.258032 -428.037244) (xy 142.318232 -428.037244) (xy 142.306163 -428.036709)
			(xy 142.283203 -428.02926) (xy 142.263668 -428.01508) (xy 142.249471 -427.995558) (xy 142.242001 -427.972605)
			(xy 142.241524 -427.960536) (xy 142.241524 -427.350174) (xy 142.23986 -427.33518) (xy 142.238078 -427.305062)
			(xy 142.237968 -427.289976) (xy 140.335 -427.289976) (xy 140.335 -428.28972) (xy 144.237964 -428.28972)
			(xy 144.238073 -428.274634) (xy 144.239855 -428.244516) (xy 144.24152 -428.229522) (xy 144.24152 -427.150022)
			(xy 144.239851 -427.135029) (xy 144.238073 -427.10491) (xy 144.237964 -427.089824) (xy 144.238074 -427.074738)
			(xy 144.239855 -427.04462) (xy 144.24152 -427.029626) (xy 144.24152 -426.41901) (xy 144.242016 -426.406923)
			(xy 144.249467 -426.383926) (xy 144.263647 -426.364348) (xy 144.283173 -426.350096) (xy 144.306143 -426.34256)
			(xy 144.318228 -426.342048) (xy 145.258028 -426.342048) (xy 145.270133 -426.342492) (xy 145.293152 -426.349993)
			(xy 145.312721 -426.364249) (xy 145.326916 -426.383861) (xy 145.334345 -426.406904) (xy 145.334736 -426.41901)
			(xy 145.334736 -427.289976) (xy 146.23796 -427.289976) (xy 146.238074 -427.274891) (xy 146.239852 -427.244772)
			(xy 146.241516 -427.229778) (xy 146.241516 -426.150024) (xy 146.239847 -426.135031) (xy 146.238069 -426.104912)
			(xy 146.23796 -426.089826) (xy 146.23807 -426.07474) (xy 146.239851 -426.044622) (xy 146.241516 -426.029628)
			(xy 146.241516 -425.419012) (xy 146.241923 -425.406928) (xy 146.249391 -425.383941) (xy 146.263597 -425.364389)
			(xy 146.283152 -425.350185) (xy 146.306139 -425.342722) (xy 146.318224 -425.342304) (xy 147.258024 -425.342304)
			(xy 147.270101 -425.342744) (xy 147.293071 -425.350215) (xy 147.312609 -425.364417) (xy 147.326802 -425.383961)
			(xy 147.334261 -425.406935) (xy 147.334732 -425.419012) (xy 147.334732 -427.960536) (xy 147.334267 -427.97261)
			(xy 147.326798 -427.995574) (xy 147.3126 -428.015109) (xy 147.293064 -428.029303) (xy 147.270098 -428.036769)
			(xy 147.258024 -428.037244) (xy 146.318224 -428.037244) (xy 146.306154 -428.036716) (xy 146.283194 -428.029264)
			(xy 146.26366 -428.015083) (xy 146.249463 -427.99556) (xy 146.241993 -427.972605) (xy 146.241516 -427.960536)
			(xy 146.241516 -427.350174) (xy 146.239852 -427.33518) (xy 146.23807 -427.305062) (xy 146.23796 -427.289976)
			(xy 145.334736 -427.289976) (xy 145.334736 -428.28972) (xy 148.237956 -428.28972) (xy 148.238066 -428.274634)
			(xy 148.239847 -428.244516) (xy 148.241512 -428.229522) (xy 148.241512 -427.150022) (xy 148.239843 -427.135029)
			(xy 148.238065 -427.10491) (xy 148.237956 -427.089824) (xy 148.238066 -427.074738) (xy 148.239847 -427.04462)
			(xy 148.241512 -427.029626) (xy 148.241512 -426.41901) (xy 148.242015 -426.406924) (xy 148.249466 -426.383928)
			(xy 148.263644 -426.364351) (xy 148.283168 -426.350099) (xy 148.306136 -426.342562) (xy 148.31822 -426.342048)
			(xy 149.25802 -426.342048) (xy 149.270125 -426.342499) (xy 149.293144 -426.349997) (xy 149.312712 -426.364252)
			(xy 149.326908 -426.383863) (xy 149.334337 -426.406904) (xy 149.334728 -426.41901) (xy 149.334728 -427.289976)
			(xy 150.237952 -427.289976) (xy 150.238066 -427.274891) (xy 150.239844 -427.244772) (xy 150.241508 -427.229778)
			(xy 150.241508 -426.150024) (xy 150.239839 -426.135031) (xy 150.238061 -426.104912) (xy 150.237952 -426.089826)
			(xy 150.238062 -426.07474) (xy 150.239843 -426.044622) (xy 150.241508 -426.029628) (xy 150.241508 -425.419012)
			(xy 150.241923 -425.406928) (xy 150.249389 -425.383943) (xy 150.263594 -425.364392) (xy 150.283147 -425.350188)
			(xy 150.306132 -425.342723) (xy 150.318216 -425.342304) (xy 151.258016 -425.342304) (xy 151.270093 -425.342751)
			(xy 151.293062 -425.350219) (xy 151.3126 -425.36442) (xy 151.326794 -425.383963) (xy 151.334253 -425.406935)
			(xy 151.334724 -425.419012) (xy 151.334724 -427.960536) (xy 151.334267 -427.972611) (xy 151.326796 -427.995577)
			(xy 151.312597 -428.015112) (xy 151.293059 -428.029306) (xy 151.270091 -428.03677) (xy 151.258016 -428.037244)
			(xy 150.318216 -428.037244) (xy 150.306146 -428.036723) (xy 150.283185 -428.029269) (xy 150.263651 -428.015086)
			(xy 150.249455 -427.995561) (xy 150.241985 -427.972606) (xy 150.241508 -427.960536) (xy 150.241508 -427.350174)
			(xy 150.239844 -427.33518) (xy 150.238062 -427.305062) (xy 150.237952 -427.289976) (xy 149.334728 -427.289976)
			(xy 149.334728 -428.28972) (xy 152.237948 -428.28972) (xy 152.238058 -428.274634) (xy 152.239839 -428.244516)
			(xy 152.241504 -428.229522) (xy 152.241504 -427.150022) (xy 152.239835 -427.135029) (xy 152.238057 -427.10491)
			(xy 152.237948 -427.089824) (xy 152.238058 -427.074738) (xy 152.239839 -427.04462) (xy 152.241504 -427.029626)
			(xy 152.241504 -426.41901) (xy 152.242015 -426.406925) (xy 152.249465 -426.38393) (xy 152.263641 -426.364353)
			(xy 152.283163 -426.350101) (xy 152.306128 -426.342563) (xy 152.318212 -426.342048) (xy 153.258012 -426.342048)
			(xy 153.270116 -426.342505) (xy 153.293135 -426.350002) (xy 153.312704 -426.364255) (xy 153.3269 -426.383864)
			(xy 153.334329 -426.406905) (xy 153.33472 -426.41901) (xy 153.33472 -427.289976) (xy 154.237944 -427.289976)
			(xy 154.238059 -427.274891) (xy 154.239836 -427.244772) (xy 154.2415 -427.229778) (xy 154.2415 -426.150024)
			(xy 154.239831 -426.135031) (xy 154.238053 -426.104912) (xy 154.237944 -426.089826) (xy 154.238054 -426.07474)
			(xy 154.239835 -426.044622) (xy 154.2415 -426.029628) (xy 154.2415 -425.419012) (xy 154.241923 -425.406929)
			(xy 154.249388 -425.383946) (xy 154.263592 -425.364394) (xy 154.283142 -425.35019) (xy 154.306125 -425.342724)
			(xy 154.318208 -425.342304) (xy 155.258008 -425.342304) (xy 155.270092 -425.342706) (xy 155.293077 -425.350177)
			(xy 155.312629 -425.364386) (xy 155.326832 -425.383941) (xy 155.334297 -425.406928) (xy 155.334716 -425.419012)
			(xy 155.334716 -427.960536) (xy 155.334267 -427.972612) (xy 155.326795 -427.995579) (xy 155.312595 -428.015115)
			(xy 155.293054 -428.029308) (xy 155.270084 -428.036771) (xy 155.258008 -428.037244) (xy 154.318208 -428.037244)
			(xy 154.306137 -428.03673) (xy 154.283177 -428.029274) (xy 154.263643 -428.015089) (xy 154.249447 -427.995563)
			(xy 154.241977 -427.972606) (xy 154.2415 -427.960536) (xy 154.2415 -427.350174) (xy 154.239836 -427.33518)
			(xy 154.238054 -427.305062) (xy 154.237944 -427.289976) (xy 153.33472 -427.289976) (xy 153.33472 -428.28972)
			(xy 156.23794 -428.28972) (xy 156.238052 -428.274634) (xy 156.239833 -428.244516) (xy 156.241496 -428.229522)
			(xy 156.241496 -427.150022) (xy 156.239827 -427.135029) (xy 156.238049 -427.10491) (xy 156.23794 -427.089824)
			(xy 156.23805 -427.074738) (xy 156.239831 -427.04462) (xy 156.241496 -427.029626) (xy 156.241496 -426.41901)
			(xy 156.242015 -426.406925) (xy 156.249464 -426.383932) (xy 156.263639 -426.364356) (xy 156.283158 -426.350104)
			(xy 156.306121 -426.342564) (xy 156.318204 -426.342048) (xy 157.258004 -426.342048) (xy 157.270108 -426.342512)
			(xy 157.293127 -426.350006) (xy 157.312695 -426.364257) (xy 157.326891 -426.383866) (xy 157.334321 -426.406905)
			(xy 157.334712 -426.41901) (xy 157.334712 -428.960534) (xy 157.334321 -428.97263) (xy 157.326849 -428.99564)
			(xy 157.312644 -429.015223) (xy 157.293092 -429.029471) (xy 157.270099 -429.036994) (xy 157.258004 -429.037496)
			(xy 156.318204 -429.037496) (xy 156.306095 -429.03708) (xy 156.283067 -429.029582) (xy 156.263493 -429.01532)
			(xy 156.249299 -428.995698) (xy 156.241879 -428.972644) (xy 156.241496 -428.960534) (xy 156.241496 -428.349918)
			(xy 156.239827 -428.334925) (xy 156.238049 -428.304806) (xy 156.23794 -428.28972) (xy 153.33472 -428.28972)
			(xy 153.33472 -428.960534) (xy 153.334321 -428.972629) (xy 153.32685 -428.995638) (xy 153.312647 -429.015221)
			(xy 153.293097 -429.029469) (xy 153.270106 -429.036993) (xy 153.258012 -429.037496) (xy 152.318212 -429.037496)
			(xy 152.306103 -429.037073) (xy 152.283076 -429.029577) (xy 152.263502 -429.015317) (xy 152.249307 -428.995696)
			(xy 152.241887 -428.972644) (xy 152.241504 -428.960534) (xy 152.241504 -428.349918) (xy 152.239835 -428.334925)
			(xy 152.238057 -428.304806) (xy 152.237948 -428.28972) (xy 149.334728 -428.28972) (xy 149.334728 -428.960534)
			(xy 149.334321 -428.972629) (xy 149.326851 -428.995636) (xy 149.31265 -429.015218) (xy 149.293102 -429.029466)
			(xy 149.270113 -429.036992) (xy 149.25802 -429.037496) (xy 148.31822 -429.037496) (xy 148.306112 -429.037066)
			(xy 148.283085 -429.029572) (xy 148.263511 -429.015314) (xy 148.249316 -428.995695) (xy 148.241895 -428.972643)
			(xy 148.241512 -428.960534) (xy 148.241512 -428.349918) (xy 148.239843 -428.334925) (xy 148.238065 -428.304806)
			(xy 148.237956 -428.28972) (xy 145.334736 -428.28972) (xy 145.334736 -428.960534) (xy 145.334321 -428.972628)
			(xy 145.326852 -428.995634) (xy 145.312653 -429.015215) (xy 145.293107 -429.029464) (xy 145.27012 -429.03699)
			(xy 145.258028 -429.037496) (xy 144.318228 -429.037496) (xy 144.30612 -429.03706) (xy 144.283093 -429.029567)
			(xy 144.263519 -429.015311) (xy 144.249324 -428.995693) (xy 144.241903 -428.972643) (xy 144.24152 -428.960534)
			(xy 144.24152 -428.349918) (xy 144.239851 -428.334925) (xy 144.238073 -428.304806) (xy 144.237964 -428.28972)
			(xy 140.335 -428.28972) (xy 140.335 -428.960534) (xy 140.334518 -428.972647) (xy 140.327026 -428.995684)
			(xy 140.312785 -429.015282) (xy 140.293188 -429.029524) (xy 140.270151 -429.037017) (xy 140.258038 -429.037496)
			(xy 139.318238 -429.037496) (xy 139.306121 -429.037008) (xy 139.283069 -429.029531) (xy 139.263456 -429.015295)
			(xy 139.249202 -428.995696) (xy 139.241703 -428.972651) (xy 139.241276 -428.960534) (xy 139.241276 -428.347886)
			(xy 139.239733 -428.333394) (xy 139.23808 -428.304294) (xy 139.237974 -428.28972) (xy 136.335008 -428.28972)
			(xy 136.335008 -428.960534) (xy 136.334518 -428.972646) (xy 136.327027 -428.995682) (xy 136.312788 -429.01528)
			(xy 136.293193 -429.029522) (xy 136.270158 -429.037016) (xy 136.258046 -429.037496) (xy 135.318246 -429.037496)
			(xy 135.306129 -429.037002) (xy 135.283077 -429.029526) (xy 135.263464 -429.015292) (xy 135.249211 -428.995694)
			(xy 135.241711 -428.972651) (xy 135.241284 -428.960534) (xy 135.241284 -428.347886) (xy 135.239741 -428.333394)
			(xy 135.238088 -428.304294) (xy 135.237982 -428.28972) (xy 132.335016 -428.28972) (xy 132.335016 -428.960534)
			(xy 132.334668 -428.972663) (xy 132.327161 -428.995731) (xy 132.312892 -429.015349) (xy 132.293259 -429.029598)
			(xy 132.270184 -429.037081) (xy 132.258054 -429.037496) (xy 131.318254 -429.037496) (xy 131.30614 -429.037028)
			(xy 131.283101 -429.029532) (xy 131.263503 -429.015288) (xy 131.249262 -428.995688) (xy 131.24177 -428.972648)
			(xy 131.241292 -428.960534) (xy 131.241292 -428.347886) (xy 131.239749 -428.333394) (xy 131.238096 -428.304294)
			(xy 131.23799 -428.28972) (xy 128.335024 -428.28972) (xy 128.335024 -428.960534) (xy 128.334669 -428.972662)
			(xy 128.327162 -428.995729) (xy 128.312895 -429.015347) (xy 128.293264 -429.029595) (xy 128.270191 -429.03708)
			(xy 128.258062 -429.037496) (xy 127.318262 -429.037496) (xy 127.306149 -429.037021) (xy 127.28311 -429.029528)
			(xy 127.263512 -429.015285) (xy 127.24927 -428.995686) (xy 127.241778 -428.972647) (xy 127.2413 -428.960534)
			(xy 127.2413 -428.347886) (xy 127.239757 -428.333394) (xy 127.238104 -428.304294) (xy 127.237998 -428.28972)
			(xy 113.943382 -428.28972) (xy 113.956414 -428.297518) (xy 114.097839 -428.391417) (xy 114.234709 -428.491842)
			(xy 114.36672 -428.598572) (xy 114.493584 -428.711373) (xy 114.615021 -428.829996) (xy 114.730765 -428.954181)
			(xy 114.84056 -429.083654) (xy 114.944167 -429.218131) (xy 115.041356 -429.357317) (xy 115.131914 -429.500905)
			(xy 115.215642 -429.648581) (xy 115.292357 -429.800018) (xy 115.361889 -429.954885) (xy 115.424086 -430.11284)
			(xy 115.47881 -430.273538) (xy 115.525942 -430.436623) (xy 115.565378 -430.601739) (xy 115.597032 -430.768522)
			(xy 115.614222 -430.889918) (xy 125.238002 -430.889918) (xy 125.238096 -430.875344) (xy 125.239748 -430.846243)
			(xy 125.241304 -430.831752) (xy 125.241304 -429.747934) (xy 125.239756 -429.733442) (xy 125.238106 -429.704342)
			(xy 125.238002 -429.689768) (xy 125.2381 -429.675194) (xy 125.23975 -429.646093) (xy 125.241304 -429.631602)
			(xy 125.241304 -429.018954) (xy 125.241772 -429.00684) (xy 125.249268 -428.983801) (xy 125.263512 -428.964203)
			(xy 125.283112 -428.949962) (xy 125.306152 -428.94247) (xy 125.318266 -428.941992) (xy 126.258066 -428.941992)
			(xy 126.270174 -428.94254) (xy 126.293209 -428.950012) (xy 126.312807 -428.964236) (xy 126.327051 -428.98382)
			(xy 126.334547 -429.006846) (xy 126.335028 -429.018954) (xy 126.335028 -431.560478) (xy 126.334621 -431.572603)
			(xy 126.32713 -431.595667) (xy 126.312877 -431.615285) (xy 126.293256 -431.629536) (xy 126.270191 -431.637023)
			(xy 126.258066 -431.63744) (xy 125.318266 -431.63744) (xy 125.306147 -431.637017) (xy 125.283099 -431.629518)
			(xy 125.263496 -431.615264) (xy 125.249257 -431.59565) (xy 125.241774 -431.572597) (xy 125.241304 -431.560478)
			(xy 125.241304 -430.948084) (xy 125.23976 -430.933592) (xy 125.238108 -430.904492) (xy 125.238002 -430.889918)
			(xy 115.614222 -430.889918) (xy 115.620833 -430.936605) (xy 115.636729 -431.105619) (xy 115.644686 -431.275192)
			(xy 115.645184 -431.360072) (xy 115.644698 -431.445674) (xy 115.63661 -431.616688) (xy 115.620446 -431.787128)
			(xy 115.605768 -431.889916) (xy 127.237998 -431.889916) (xy 127.238092 -431.875342) (xy 127.239744 -431.846241)
			(xy 127.2413 -431.83175) (xy 127.2413 -430.747932) (xy 127.239752 -430.73344) (xy 127.238102 -430.70434)
			(xy 127.237998 -430.689766) (xy 127.238096 -430.675192) (xy 127.239746 -430.646091) (xy 127.2413 -430.6316)
			(xy 127.2413 -430.018952) (xy 127.241676 -430.006841) (xy 127.249188 -429.983812) (xy 127.26346 -429.96424)
			(xy 127.28309 -429.950047) (xy 127.306149 -429.942627) (xy 127.318262 -429.942244) (xy 128.258062 -429.942244)
			(xy 128.27015 -429.94274) (xy 128.29315 -429.950187) (xy 128.312731 -429.964366) (xy 128.326983 -429.983894)
			(xy 128.334515 -430.006866) (xy 128.335024 -430.018952) (xy 128.335024 -430.889918) (xy 129.237994 -430.889918)
			(xy 129.238088 -430.875344) (xy 129.23974 -430.846243) (xy 129.241296 -430.831752) (xy 129.241296 -429.747934)
			(xy 129.239749 -429.733442) (xy 129.238098 -429.704342) (xy 129.237994 -429.689768) (xy 129.238092 -429.675194)
			(xy 129.239742 -429.646093) (xy 129.241296 -429.631602) (xy 129.241296 -429.018954) (xy 129.241772 -429.006841)
			(xy 129.249267 -428.983804) (xy 129.263509 -428.964206) (xy 129.283107 -428.949965) (xy 129.306145 -428.942471)
			(xy 129.318258 -428.941992) (xy 130.258058 -428.941992) (xy 130.270166 -428.942547) (xy 130.2932 -428.950017)
			(xy 130.312798 -428.964239) (xy 130.327043 -428.983821) (xy 130.334539 -429.006847) (xy 130.33502 -429.018954)
			(xy 130.33502 -431.560478) (xy 130.334621 -431.572604) (xy 130.327129 -431.595669) (xy 130.312874 -431.615288)
			(xy 130.293251 -431.629538) (xy 130.270184 -431.637024) (xy 130.258058 -431.63744) (xy 129.318258 -431.63744)
			(xy 129.306139 -431.637024) (xy 129.283091 -431.629522) (xy 129.263488 -431.615267) (xy 129.249248 -431.595652)
			(xy 129.241766 -431.572597) (xy 129.241296 -431.560478) (xy 129.241296 -430.948084) (xy 129.239753 -430.933592)
			(xy 129.2381 -430.904492) (xy 129.237994 -430.889918) (xy 128.335024 -430.889918) (xy 128.335024 -431.889916)
			(xy 131.23799 -431.889916) (xy 131.238084 -431.875342) (xy 131.239736 -431.846241) (xy 131.241292 -431.83175)
			(xy 131.241292 -430.747932) (xy 131.239744 -430.73344) (xy 131.238094 -430.70434) (xy 131.23799 -430.689766)
			(xy 131.238088 -430.675192) (xy 131.239738 -430.646091) (xy 131.241292 -430.6316) (xy 131.241292 -430.018952)
			(xy 131.241675 -430.006841) (xy 131.249187 -429.983814) (xy 131.263458 -429.964242) (xy 131.283085 -429.950049)
			(xy 131.306142 -429.942628) (xy 131.318254 -429.942244) (xy 132.258054 -429.942244) (xy 132.270142 -429.942747)
			(xy 132.293141 -429.950191) (xy 132.312722 -429.964368) (xy 132.326974 -429.983895) (xy 132.334507 -430.006866)
			(xy 132.335016 -430.018952) (xy 132.335016 -430.889918) (xy 133.237986 -430.889918) (xy 133.23808 -430.875344)
			(xy 133.239732 -430.846243) (xy 133.241288 -430.831752) (xy 133.241288 -429.747934) (xy 133.239741 -429.733442)
			(xy 133.23809 -429.704342) (xy 133.237986 -429.689768) (xy 133.238084 -429.675194) (xy 133.239734 -429.646093)
			(xy 133.241288 -429.631602) (xy 133.241288 -429.018954) (xy 133.241772 -429.006842) (xy 133.249266 -428.983806)
			(xy 133.263506 -428.964209) (xy 133.283102 -428.949967) (xy 133.306138 -428.942472) (xy 133.31825 -428.941992)
			(xy 134.25805 -428.941992) (xy 134.270163 -428.942468) (xy 134.2932 -428.949964) (xy 134.312797 -428.964206)
			(xy 134.327038 -428.983804) (xy 134.334532 -429.006841) (xy 134.335012 -429.018954) (xy 134.335012 -431.560478)
			(xy 134.33447 -431.572586) (xy 134.326995 -431.59562) (xy 134.312769 -431.615218) (xy 134.293185 -431.629462)
			(xy 134.270158 -431.636959) (xy 134.25805 -431.63744) (xy 133.31825 -431.63744) (xy 133.306131 -431.63703)
			(xy 133.283082 -431.629527) (xy 133.263479 -431.615269) (xy 133.24924 -431.595653) (xy 133.241758 -431.572598)
			(xy 133.241288 -431.560478) (xy 133.241288 -430.948084) (xy 133.239745 -430.933592) (xy 133.238092 -430.904492)
			(xy 133.237986 -430.889918) (xy 132.335016 -430.889918) (xy 132.335016 -431.889916) (xy 135.237982 -431.889916)
			(xy 135.238076 -431.875342) (xy 135.239728 -431.846241) (xy 135.241284 -431.83175) (xy 135.241284 -430.747932)
			(xy 135.239736 -430.73344) (xy 135.238086 -430.70434) (xy 135.237982 -430.689766) (xy 135.23808 -430.675192)
			(xy 135.23973 -430.646091) (xy 135.241284 -430.6316) (xy 135.241284 -430.018952) (xy 135.241675 -430.006842)
			(xy 135.249186 -429.983816) (xy 135.263455 -429.964245) (xy 135.28308 -429.950052) (xy 135.306135 -429.942629)
			(xy 135.318246 -429.942244) (xy 136.258046 -429.942244) (xy 136.270138 -429.942668) (xy 136.293141 -429.950138)
			(xy 136.312721 -429.964336) (xy 136.32697 -429.983878) (xy 136.3345 -430.006861) (xy 136.335008 -430.018952)
			(xy 136.335008 -430.889918) (xy 137.237978 -430.889918) (xy 137.238072 -430.875344) (xy 137.239724 -430.846243)
			(xy 137.24128 -430.831752) (xy 137.24128 -429.747934) (xy 137.239733 -429.733442) (xy 137.238082 -429.704342)
			(xy 137.237978 -429.689768) (xy 137.238076 -429.675194) (xy 137.239726 -429.646093) (xy 137.24128 -429.631602)
			(xy 137.24128 -429.018954) (xy 137.241673 -429.006833) (xy 137.249178 -428.983781) (xy 137.263439 -428.964176)
			(xy 137.28306 -428.949938) (xy 137.30612 -428.942459) (xy 137.318242 -428.941992) (xy 138.258042 -428.941992)
			(xy 138.270154 -428.942475) (xy 138.293191 -428.949968) (xy 138.312788 -428.964209) (xy 138.32703 -428.983805)
			(xy 138.334524 -429.006842) (xy 138.335004 -429.018954) (xy 138.335004 -431.560478) (xy 138.33447 -431.572587)
			(xy 138.326994 -431.595623) (xy 138.312767 -431.615221) (xy 138.29318 -431.629465) (xy 138.270151 -431.63696)
			(xy 138.258042 -431.63744) (xy 137.318242 -431.63744) (xy 137.306119 -431.637004) (xy 137.283058 -431.629521)
			(xy 137.26344 -431.615274) (xy 137.249188 -431.59566) (xy 137.241699 -431.572601) (xy 137.24128 -431.560478)
			(xy 137.24128 -430.948084) (xy 137.239737 -430.933592) (xy 137.238084 -430.904492) (xy 137.237978 -430.889918)
			(xy 136.335008 -430.889918) (xy 136.335008 -431.889916) (xy 139.237974 -431.889916) (xy 139.238068 -431.875342)
			(xy 139.23972 -431.846241) (xy 139.241276 -431.83175) (xy 139.241276 -430.747932) (xy 139.239728 -430.73344)
			(xy 139.238078 -430.70434) (xy 139.237974 -430.689766) (xy 139.238072 -430.675192) (xy 139.239722 -430.646091)
			(xy 139.241276 -430.6316) (xy 139.241276 -430.018952) (xy 139.241675 -430.006843) (xy 139.249185 -429.983818)
			(xy 139.263452 -429.964248) (xy 139.283075 -429.950054) (xy 139.306128 -429.94263) (xy 139.318238 -429.942244)
			(xy 140.258038 -429.942244) (xy 140.27013 -429.942675) (xy 140.293133 -429.950143) (xy 140.312712 -429.964338)
			(xy 140.326961 -429.983879) (xy 140.334492 -430.006861) (xy 140.335 -430.018952) (xy 140.335 -430.889918)
			(xy 142.237968 -430.889918) (xy 142.238077 -430.874832) (xy 142.239859 -430.844714) (xy 142.241524 -430.82972)
			(xy 142.241524 -429.749966) (xy 142.239859 -429.734972) (xy 142.238078 -429.704854) (xy 142.237968 -429.689768)
			(xy 142.238082 -429.674682) (xy 142.23986 -429.644564) (xy 142.241524 -429.62957) (xy 142.241524 -429.018954)
			(xy 142.241968 -429.006864) (xy 142.249435 -428.983864) (xy 142.263628 -428.964286) (xy 142.283165 -428.950037)
			(xy 142.306143 -428.942503) (xy 142.318232 -428.941992) (xy 143.258032 -428.941992) (xy 143.270142 -428.942389)
			(xy 143.293169 -428.949896) (xy 143.312741 -428.964163) (xy 143.326934 -428.983788) (xy 143.334356 -429.006843)
			(xy 143.33474 -429.018954) (xy 143.33474 -431.560478) (xy 143.334273 -431.572568) (xy 143.32682 -431.595572)
			(xy 143.312634 -431.615154) (xy 143.293099 -431.629404) (xy 143.270121 -431.636933) (xy 143.258032 -431.63744)
			(xy 142.318232 -431.63744) (xy 142.306129 -431.636957) (xy 142.283109 -431.629471) (xy 142.263539 -431.615225)
			(xy 142.249342 -431.59562) (xy 142.241913 -431.572582) (xy 142.241524 -431.560478) (xy 142.241524 -430.950116)
			(xy 142.239855 -430.935123) (xy 142.238077 -430.905004) (xy 142.237968 -430.889918) (xy 140.335 -430.889918)
			(xy 140.335 -431.889916) (xy 144.237964 -431.889916) (xy 144.238073 -431.87483) (xy 144.239855 -431.844712)
			(xy 144.24152 -431.829718) (xy 144.24152 -430.749964) (xy 144.239855 -430.73497) (xy 144.238074 -430.704852)
			(xy 144.237964 -430.689766) (xy 144.238078 -430.67468) (xy 144.239856 -430.644562) (xy 144.24152 -430.629568)
			(xy 144.24152 -430.018952) (xy 144.241924 -430.006872) (xy 144.249403 -429.983899) (xy 144.263614 -429.96436)
			(xy 144.283167 -429.950168) (xy 144.306148 -429.942712) (xy 144.318228 -429.942244) (xy 145.258028 -429.942244)
			(xy 145.270099 -429.942739) (xy 145.293059 -429.950204) (xy 145.312592 -429.964394) (xy 145.326787 -429.983923)
			(xy 145.334258 -430.006881) (xy 145.334736 -430.018952) (xy 145.334736 -430.889918) (xy 146.23796 -430.889918)
			(xy 146.238069 -430.874832) (xy 146.239851 -430.844714) (xy 146.241516 -430.82972) (xy 146.241516 -429.749966)
			(xy 146.239851 -429.734972) (xy 146.23807 -429.704854) (xy 146.23796 -429.689768) (xy 146.238074 -429.674682)
			(xy 146.239852 -429.644564) (xy 146.241516 -429.62957) (xy 146.241516 -429.018954) (xy 146.241968 -429.006864)
			(xy 146.249434 -428.983866) (xy 146.263626 -428.964289) (xy 146.28316 -428.950039) (xy 146.306136 -428.942504)
			(xy 146.318224 -428.941992) (xy 147.258024 -428.941992) (xy 147.270133 -428.942396) (xy 147.29316 -428.949901)
			(xy 147.312732 -428.964166) (xy 147.326926 -428.983789) (xy 147.334348 -429.006843) (xy 147.334732 -429.018954)
			(xy 147.334732 -431.560478) (xy 147.334273 -431.572569) (xy 147.326819 -431.595574) (xy 147.312632 -431.615156)
			(xy 147.293094 -431.629407) (xy 147.270114 -431.636934) (xy 147.258024 -431.63744) (xy 146.318224 -431.63744)
			(xy 146.30612 -431.636964) (xy 146.283101 -431.629476) (xy 146.263531 -431.615228) (xy 146.249334 -431.595622)
			(xy 146.241905 -431.572583) (xy 146.241516 -431.560478) (xy 146.241516 -430.950116) (xy 146.239847 -430.935123)
			(xy 146.238069 -430.905004) (xy 146.23796 -430.889918) (xy 145.334736 -430.889918) (xy 145.334736 -431.889916)
			(xy 148.237956 -431.889916) (xy 148.238065 -431.87483) (xy 148.239847 -431.844712) (xy 148.241512 -431.829718)
			(xy 148.241512 -430.749964) (xy 148.239847 -430.73497) (xy 148.238066 -430.704852) (xy 148.237956 -430.689766)
			(xy 148.23807 -430.67468) (xy 148.239848 -430.644562) (xy 148.241512 -430.629568) (xy 148.241512 -430.018952)
			(xy 148.241924 -430.006873) (xy 148.249402 -429.983901) (xy 148.263611 -429.964363) (xy 148.283162 -429.950171)
			(xy 148.306141 -429.942713) (xy 148.31822 -429.942244) (xy 149.25802 -429.942244) (xy 149.270091 -429.942747)
			(xy 149.29305 -429.950209) (xy 149.312583 -429.964397) (xy 149.326778 -429.983924) (xy 149.334249 -430.006881)
			(xy 149.334728 -430.018952) (xy 149.334728 -430.889918) (xy 150.237952 -430.889918) (xy 150.238061 -430.874832)
			(xy 150.239843 -430.844714) (xy 150.241508 -430.82972) (xy 150.241508 -429.749966) (xy 150.239843 -429.734972)
			(xy 150.238062 -429.704854) (xy 150.237952 -429.689768) (xy 150.238066 -429.674682) (xy 150.239844 -429.644564)
			(xy 150.241508 -429.62957) (xy 150.241508 -429.018954) (xy 150.241968 -429.006865) (xy 150.249433 -428.983868)
			(xy 150.263623 -428.964292) (xy 150.283155 -428.950042) (xy 150.306129 -428.942505) (xy 150.318216 -428.941992)
			(xy 151.258016 -428.941992) (xy 151.270125 -428.942402) (xy 151.293151 -428.949905) (xy 151.312724 -428.964169)
			(xy 151.326918 -428.983791) (xy 151.33434 -429.006844) (xy 151.334724 -429.018954) (xy 151.334724 -431.560478)
			(xy 151.334273 -431.57257) (xy 151.326818 -431.595576) (xy 151.312629 -431.615159) (xy 151.293089 -431.629409)
			(xy 151.270106 -431.636935) (xy 151.258016 -431.63744) (xy 150.318216 -431.63744) (xy 150.306112 -431.63697)
			(xy 150.283092 -431.62948) (xy 150.263522 -431.615231) (xy 150.249326 -431.595623) (xy 150.241897 -431.572583)
			(xy 150.241508 -431.560478) (xy 150.241508 -430.950116) (xy 150.239839 -430.935123) (xy 150.238061 -430.905004)
			(xy 150.237952 -430.889918) (xy 149.334728 -430.889918) (xy 149.334728 -431.889916) (xy 152.237948 -431.889916)
			(xy 152.238057 -431.87483) (xy 152.239839 -431.844712) (xy 152.241504 -431.829718) (xy 152.241504 -430.749964)
			(xy 152.239839 -430.73497) (xy 152.238058 -430.704852) (xy 152.237948 -430.689766) (xy 152.238062 -430.67468)
			(xy 152.23984 -430.644562) (xy 152.241504 -430.629568) (xy 152.241504 -430.018952) (xy 152.241923 -430.006874)
			(xy 152.249401 -429.983903) (xy 152.263608 -429.964366) (xy 152.283157 -429.950173) (xy 152.306133 -429.942714)
			(xy 152.318212 -429.942244) (xy 153.258012 -429.942244) (xy 153.270082 -429.942753) (xy 153.293042 -429.950213)
			(xy 153.312574 -429.9644) (xy 153.32677 -429.983926) (xy 153.334241 -430.006882) (xy 153.33472 -430.018952)
			(xy 153.33472 -430.889918) (xy 154.237944 -430.889918) (xy 154.238053 -430.874832) (xy 154.239835 -430.844714)
			(xy 154.2415 -430.82972) (xy 154.2415 -429.749966) (xy 154.239835 -429.734972) (xy 154.238054 -429.704854)
			(xy 154.237944 -429.689768) (xy 154.238058 -429.674682) (xy 154.239836 -429.644564) (xy 154.2415 -429.62957)
			(xy 154.2415 -429.018954) (xy 154.241967 -429.006866) (xy 154.249432 -428.983871) (xy 154.26362 -428.964295)
			(xy 154.28315 -428.950044) (xy 154.306122 -428.942507) (xy 154.318208 -428.941992) (xy 155.258008 -428.941992)
			(xy 155.270117 -428.942409) (xy 155.293143 -428.94991) (xy 155.312715 -428.964172) (xy 155.32691 -428.983792)
			(xy 155.334332 -429.006844) (xy 155.334716 -429.018954) (xy 155.334716 -431.560478) (xy 155.334273 -431.572571)
			(xy 155.326817 -431.595578) (xy 155.312626 -431.615162) (xy 155.293084 -431.629412) (xy 155.270099 -431.636937)
			(xy 155.258008 -431.63744) (xy 154.318208 -431.63744) (xy 154.306104 -431.636978) (xy 154.283083 -431.629485)
			(xy 154.263513 -431.615234) (xy 154.249317 -431.595625) (xy 154.241889 -431.572584) (xy 154.2415 -431.560478)
			(xy 154.2415 -430.950116) (xy 154.239831 -430.935123) (xy 154.238053 -430.905004) (xy 154.237944 -430.889918)
			(xy 153.33472 -430.889918) (xy 153.33472 -431.889916) (xy 156.23794 -431.889916) (xy 156.238051 -431.87483)
			(xy 156.239833 -431.844712) (xy 156.241496 -431.829718) (xy 156.241496 -430.749964) (xy 156.239831 -430.73497)
			(xy 156.23805 -430.704852) (xy 156.23794 -430.689766) (xy 156.238054 -430.67468) (xy 156.239832 -430.644562)
			(xy 156.241496 -430.629568) (xy 156.241496 -430.018952) (xy 156.241923 -430.006875) (xy 156.249399 -429.983905)
			(xy 156.263605 -429.964368) (xy 156.283152 -429.950176) (xy 156.306126 -429.942715) (xy 156.318204 -429.942244)
			(xy 157.258004 -429.942244) (xy 157.270074 -429.94276) (xy 157.293033 -429.950218) (xy 157.312566 -429.964403)
			(xy 157.326762 -429.983927) (xy 157.334233 -430.006882) (xy 157.334712 -430.018952) (xy 157.334712 -432.560476)
			(xy 157.334267 -432.572557) (xy 157.326806 -432.595538) (xy 157.312609 -432.615089) (xy 157.293063 -432.629294)
			(xy 157.270085 -432.636762) (xy 157.258004 -432.637184) (xy 156.318204 -432.637184) (xy 156.306119 -432.636784)
			(xy 156.283132 -432.629314) (xy 156.26358 -432.615106) (xy 156.249376 -432.59555) (xy 156.241913 -432.572561)
			(xy 156.241496 -432.560476) (xy 156.241496 -431.950114) (xy 156.239826 -431.935121) (xy 156.238049 -431.905002)
			(xy 156.23794 -431.889916) (xy 153.33472 -431.889916) (xy 153.33472 -432.560476) (xy 153.334267 -432.572556)
			(xy 153.326807 -432.595536) (xy 153.312611 -432.615086) (xy 153.293068 -432.629291) (xy 153.270092 -432.636761)
			(xy 153.258012 -432.637184) (xy 152.318212 -432.637184) (xy 152.306128 -432.636777) (xy 152.283141 -432.629309)
			(xy 152.263589 -432.615103) (xy 152.249385 -432.595548) (xy 152.241922 -432.572561) (xy 152.241504 -432.560476)
			(xy 152.241504 -431.950114) (xy 152.239834 -431.935121) (xy 152.238057 -431.905002) (xy 152.237948 -431.889916)
			(xy 149.334728 -431.889916) (xy 149.334728 -432.560476) (xy 149.334267 -432.572555) (xy 149.326809 -432.595534)
			(xy 149.312614 -432.615083) (xy 149.293073 -432.629288) (xy 149.270099 -432.63676) (xy 149.25802 -432.637184)
			(xy 148.31822 -432.637184) (xy 148.306136 -432.63677) (xy 148.28315 -432.629305) (xy 148.263597 -432.6151)
			(xy 148.249393 -432.595547) (xy 148.24193 -432.57256) (xy 148.241512 -432.560476) (xy 148.241512 -431.950114)
			(xy 148.239842 -431.935121) (xy 148.238065 -431.905002) (xy 148.237956 -431.889916) (xy 145.334736 -431.889916)
			(xy 145.334736 -432.560476) (xy 145.334216 -432.572547) (xy 145.326763 -432.595508) (xy 145.31258 -432.615043)
			(xy 145.293055 -432.62924) (xy 145.270098 -432.636708) (xy 145.258028 -432.637184) (xy 144.318228 -432.637184)
			(xy 144.306144 -432.636763) (xy 144.283159 -432.6293) (xy 144.263606 -432.615097) (xy 144.249402 -432.595545)
			(xy 144.241938 -432.57256) (xy 144.24152 -432.560476) (xy 144.24152 -431.950114) (xy 144.23985 -431.935121)
			(xy 144.238073 -431.905002) (xy 144.237964 -431.889916) (xy 140.335 -431.889916) (xy 140.335 -432.560476)
			(xy 140.334563 -432.572584) (xy 140.32707 -432.59561) (xy 140.312814 -432.615184) (xy 140.293196 -432.629379)
			(xy 140.270147 -432.6368) (xy 140.258038 -432.637184) (xy 139.318238 -432.637184) (xy 139.306153 -432.636661)
			(xy 139.283157 -432.629217) (xy 139.263579 -432.615044) (xy 139.249326 -432.595524) (xy 139.241789 -432.572559)
			(xy 139.241276 -432.560476) (xy 139.241276 -431.948082) (xy 139.239733 -431.93359) (xy 139.23808 -431.90449)
			(xy 139.237974 -431.889916) (xy 136.335008 -431.889916) (xy 136.335008 -432.560476) (xy 136.334563 -432.572583)
			(xy 136.327071 -432.595608) (xy 136.312817 -432.615181) (xy 136.293201 -432.629376) (xy 136.270154 -432.636799)
			(xy 136.258046 -432.637184) (xy 135.318246 -432.637184) (xy 135.306161 -432.636654) (xy 135.283166 -432.629213)
			(xy 135.263587 -432.615042) (xy 135.249334 -432.595522) (xy 135.241797 -432.572559) (xy 135.241284 -432.560476)
			(xy 135.241284 -431.948082) (xy 135.239741 -431.93359) (xy 135.238088 -431.90449) (xy 135.237982 -431.889916)
			(xy 132.335016 -431.889916) (xy 132.335016 -432.560476) (xy 132.334563 -432.572582) (xy 132.327072 -432.595606)
			(xy 132.31282 -432.615178) (xy 132.293206 -432.629374) (xy 132.270161 -432.636798) (xy 132.258054 -432.637184)
			(xy 131.318254 -432.637184) (xy 131.306164 -432.636732) (xy 131.283166 -432.629266) (xy 131.263589 -432.615074)
			(xy 131.249339 -432.59554) (xy 131.241804 -432.572564) (xy 131.241292 -432.560476) (xy 131.241292 -431.948082)
			(xy 131.239749 -431.93359) (xy 131.238096 -431.90449) (xy 131.23799 -431.889916) (xy 128.335024 -431.889916)
			(xy 128.335024 -432.560476) (xy 128.334563 -432.572581) (xy 128.327074 -432.595604) (xy 128.312823 -432.615175)
			(xy 128.293212 -432.629371) (xy 128.270168 -432.636797) (xy 128.258062 -432.637184) (xy 127.318262 -432.637184)
			(xy 127.306173 -432.636726) (xy 127.283175 -432.629261) (xy 127.263598 -432.615072) (xy 127.249348 -432.595538)
			(xy 127.241812 -432.572564) (xy 127.2413 -432.560476) (xy 127.2413 -431.948082) (xy 127.239756 -431.93359)
			(xy 127.238104 -431.90449) (xy 127.237998 -431.889916) (xy 115.605768 -431.889916) (xy 115.596243 -431.956613)
			(xy 115.564055 -432.124765) (xy 115.523953 -432.291207) (xy 115.476027 -432.455567) (xy 115.420385 -432.617477)
			(xy 115.35715 -432.776576) (xy 115.286464 -432.932508) (xy 115.208486 -433.084923) (xy 115.12339 -433.233482)
			(xy 115.031365 -433.377851) (xy 114.932619 -433.517709) (xy 114.82737 -433.652742) (xy 114.715856 -433.782648)
			(xy 114.598325 -433.907137) (xy 114.47504 -434.02593) (xy 114.346277 -434.138763) (xy 114.212324 -434.245381)
			(xy 114.07348 -434.345548) (xy 113.930056 -434.439039) (xy 113.843394 -434.48986) (xy 125.238002 -434.48986)
			(xy 125.2381 -434.475286) (xy 125.239749 -434.446185) (xy 125.241304 -434.431694) (xy 125.241304 -433.34813)
			(xy 125.239756 -433.333638) (xy 125.238106 -433.304538) (xy 125.238002 -433.289964) (xy 125.2381 -433.27539)
			(xy 125.239749 -433.246289) (xy 125.241304 -433.231798) (xy 125.241304 -432.618896) (xy 125.241713 -432.606787)
			(xy 125.249214 -432.583758) (xy 125.263477 -432.564185) (xy 125.283101 -432.549991) (xy 125.306155 -432.542571)
			(xy 125.318266 -432.542188) (xy 126.258066 -432.542188) (xy 126.270159 -432.542637) (xy 126.293166 -432.55009)
			(xy 126.312751 -432.56428) (xy 126.327001 -432.583821) (xy 126.334525 -432.606805) (xy 126.335028 -432.618896)
			(xy 126.335028 -435.16042) (xy 126.334601 -435.172527) (xy 126.3271 -435.19555) (xy 126.31284 -435.215121)
			(xy 126.293222 -435.229316) (xy 126.270174 -435.236741) (xy 126.258066 -435.237128) (xy 125.318266 -435.237128)
			(xy 125.306171 -435.236721) (xy 125.283164 -435.229251) (xy 125.263582 -435.21505) (xy 125.249334 -435.195502)
			(xy 125.241808 -435.172513) (xy 125.241304 -435.16042) (xy 125.241304 -434.548026) (xy 125.239756 -434.533534)
			(xy 125.238106 -434.504434) (xy 125.238002 -434.48986) (xy 113.843394 -434.48986) (xy 113.782372 -434.525645)
			(xy 113.630759 -434.605172) (xy 113.475556 -434.677443) (xy 113.396522 -434.710332) (xy 113.382851 -434.716444)
			(xy 113.359598 -434.735293) (xy 113.342813 -434.760077) (xy 113.333939 -434.788665) (xy 113.333741 -434.818598)
			(xy 113.342235 -434.847301) (xy 113.358691 -434.872305) (xy 113.369852 -434.88229) (xy 113.419298 -434.924299)
			(xy 113.513487 -435.013553) (xy 113.601975 -435.108462) (xy 113.684422 -435.208663) (xy 113.760513 -435.313772)
			(xy 113.829956 -435.423387) (xy 113.866512 -435.489858) (xy 127.237998 -435.489858) (xy 127.238095 -435.475284)
			(xy 127.239745 -435.446183) (xy 127.2413 -435.431692) (xy 127.2413 -434.348128) (xy 127.239752 -434.333636)
			(xy 127.238102 -434.304536) (xy 127.237998 -434.289962) (xy 127.238096 -434.275388) (xy 127.239745 -434.246287)
			(xy 127.2413 -434.231796) (xy 127.2413 -433.618894) (xy 127.241806 -433.606783) (xy 127.24929 -433.583746)
			(xy 127.263525 -433.564148) (xy 127.283117 -433.549905) (xy 127.306151 -433.542411) (xy 127.318262 -433.541932)
			(xy 128.258062 -433.541932) (xy 128.270182 -433.542392) (xy 128.293239 -433.549873) (xy 128.312854 -433.564115)
			(xy 128.327107 -433.583722) (xy 128.334601 -433.606774) (xy 128.335024 -433.618894) (xy 128.335024 -434.48986)
			(xy 129.237994 -434.48986) (xy 129.238092 -434.475286) (xy 129.239741 -434.446185) (xy 129.241296 -434.431694)
			(xy 129.241296 -433.34813) (xy 129.239748 -433.333638) (xy 129.238098 -433.304538) (xy 129.237994 -433.289964)
			(xy 129.238092 -433.27539) (xy 129.239741 -433.246289) (xy 129.241296 -433.231798) (xy 129.241296 -432.618896)
			(xy 129.241713 -432.606787) (xy 129.249213 -432.583761) (xy 129.263474 -432.564188) (xy 129.283096 -432.549993)
			(xy 129.306148 -432.542572) (xy 129.318258 -432.542188) (xy 130.258058 -432.542188) (xy 130.27015 -432.542644)
			(xy 130.293158 -432.550095) (xy 130.312742 -432.564283) (xy 130.326993 -432.583822) (xy 130.334517 -432.606805)
			(xy 130.33502 -432.618896) (xy 130.33502 -435.16042) (xy 130.334601 -435.172528) (xy 130.327099 -435.195552)
			(xy 130.312837 -435.215123) (xy 130.293217 -435.229318) (xy 130.270167 -435.236742) (xy 130.258058 -435.237128)
			(xy 129.318258 -435.237128) (xy 129.306163 -435.236728) (xy 129.283156 -435.229256) (xy 129.263574 -435.215053)
			(xy 129.249326 -435.195504) (xy 129.2418 -435.172514) (xy 129.241296 -435.16042) (xy 129.241296 -434.548026)
			(xy 129.239748 -434.533534) (xy 129.238098 -434.504434) (xy 129.237994 -434.48986) (xy 128.335024 -434.48986)
			(xy 128.335024 -435.489858) (xy 131.23799 -435.489858) (xy 131.238087 -435.475284) (xy 131.239737 -435.446183)
			(xy 131.241292 -435.431692) (xy 131.241292 -434.348128) (xy 131.239744 -434.333636) (xy 131.238094 -434.304536)
			(xy 131.23799 -434.289962) (xy 131.238088 -434.275388) (xy 131.239737 -434.246287) (xy 131.241292 -434.231796)
			(xy 131.241292 -433.618894) (xy 131.241806 -433.606784) (xy 131.249289 -433.583748) (xy 131.263522 -433.564151)
			(xy 131.283112 -433.549908) (xy 131.306144 -433.542412) (xy 131.318254 -433.541932) (xy 132.258054 -433.541932)
			(xy 132.270174 -433.542399) (xy 132.29323 -433.549878) (xy 132.312846 -433.564117) (xy 132.327098 -433.583723)
			(xy 132.334593 -433.606775) (xy 132.335016 -433.618894) (xy 132.335016 -434.48986) (xy 133.237986 -434.48986)
			(xy 133.238084 -434.475286) (xy 133.239733 -434.446185) (xy 133.241288 -434.431694) (xy 133.241288 -433.34813)
			(xy 133.23974 -433.333638) (xy 133.23809 -433.304538) (xy 133.237986 -433.289964) (xy 133.238084 -433.27539)
			(xy 133.239733 -433.246289) (xy 133.241288 -433.231798) (xy 133.241288 -432.618896) (xy 133.241713 -432.606788)
			(xy 133.249212 -432.583763) (xy 133.263472 -432.564191) (xy 133.283091 -432.549996) (xy 133.306141 -432.542573)
			(xy 133.31825 -432.542188) (xy 134.25805 -432.542188) (xy 134.270142 -432.542651) (xy 134.293149 -432.5501)
			(xy 134.312734 -432.564285) (xy 134.326984 -432.583823) (xy 134.334509 -432.606806) (xy 134.335012 -432.618896)
			(xy 134.335012 -435.16042) (xy 134.334601 -435.172529) (xy 134.327097 -435.195555) (xy 134.312834 -435.215126)
			(xy 134.293212 -435.229321) (xy 134.27016 -435.236743) (xy 134.25805 -435.237128) (xy 133.31825 -435.237128)
			(xy 133.30616 -435.23665) (xy 133.283155 -435.229203) (xy 133.263572 -435.21502) (xy 133.249321 -435.195487)
			(xy 133.241793 -435.172508) (xy 133.241288 -435.16042) (xy 133.241288 -434.548026) (xy 133.23974 -434.533534)
			(xy 133.23809 -434.504434) (xy 133.237986 -434.48986) (xy 132.335016 -434.48986) (xy 132.335016 -435.489858)
			(xy 135.237982 -435.489858) (xy 135.238079 -435.475284) (xy 135.239729 -435.446183) (xy 135.241284 -435.431692)
			(xy 135.241284 -434.348128) (xy 135.239736 -434.333636) (xy 135.238086 -434.304536) (xy 135.237982 -434.289962)
			(xy 135.23808 -434.275388) (xy 135.239729 -434.246287) (xy 135.241284 -434.231796) (xy 135.241284 -433.618894)
			(xy 135.241656 -433.606766) (xy 135.249155 -433.5837) (xy 135.263418 -433.564081) (xy 135.283046 -433.549831)
			(xy 135.306118 -433.542348) (xy 135.318246 -433.541932) (xy 136.258046 -433.541932) (xy 136.270162 -433.542372)
			(xy 136.293206 -433.549872) (xy 136.312807 -433.564122) (xy 136.327047 -433.58373) (xy 136.334534 -433.606777)
			(xy 136.335008 -433.618894) (xy 136.335008 -434.48986) (xy 137.237978 -434.48986) (xy 137.238076 -434.475286)
			(xy 137.239725 -434.446185) (xy 137.24128 -434.431694) (xy 137.24128 -433.34813) (xy 137.239732 -433.333638)
			(xy 137.238082 -433.304538) (xy 137.237978 -433.289964) (xy 137.238076 -433.27539) (xy 137.239726 -433.246289)
			(xy 137.24128 -433.231798) (xy 137.24128 -432.618896) (xy 137.241712 -432.606789) (xy 137.249211 -432.583765)
			(xy 137.263469 -432.564194) (xy 137.283086 -432.549998) (xy 137.306134 -432.542574) (xy 137.318242 -432.542188)
			(xy 138.258042 -432.542188) (xy 138.270139 -432.542572) (xy 138.293149 -432.550047) (xy 138.312732 -432.564253)
			(xy 138.326979 -432.583806) (xy 138.334502 -432.606801) (xy 138.335004 -432.618896) (xy 138.335004 -435.16042)
			(xy 138.334601 -435.17253) (xy 138.327096 -435.195557) (xy 138.312831 -435.215129) (xy 138.293207 -435.229323)
			(xy 138.270153 -435.236744) (xy 138.258042 -435.237128) (xy 137.318242 -435.237128) (xy 137.306151 -435.236656)
			(xy 137.283147 -435.229207) (xy 137.263563 -435.215023) (xy 137.249313 -435.195488) (xy 137.241785 -435.172509)
			(xy 137.24128 -435.16042) (xy 137.24128 -434.548026) (xy 137.239732 -434.533534) (xy 137.238082 -434.504434)
			(xy 137.237978 -434.48986) (xy 136.335008 -434.48986) (xy 136.335008 -435.489858) (xy 139.237974 -435.489858)
			(xy 139.238072 -435.475284) (xy 139.239721 -435.446183) (xy 139.241276 -435.431692) (xy 139.241276 -434.348128)
			(xy 139.239728 -434.333636) (xy 139.238078 -434.304536) (xy 139.237974 -434.289962) (xy 139.238072 -434.275388)
			(xy 139.239721 -434.246287) (xy 139.241276 -434.231796) (xy 139.241276 -433.618894) (xy 139.241656 -433.606767)
			(xy 139.249154 -433.583702) (xy 139.263415 -433.564084) (xy 139.283041 -433.549834) (xy 139.306111 -433.542349)
			(xy 139.318238 -433.541932) (xy 140.258038 -433.541932) (xy 140.270154 -433.542379) (xy 140.293197 -433.549876)
			(xy 140.312798 -433.564125) (xy 140.327038 -433.583731) (xy 140.334526 -433.606778) (xy 140.335 -433.618894)
			(xy 140.335 -434.48986) (xy 142.237968 -434.48986) (xy 142.238081 -434.474774) (xy 142.23986 -434.444656)
			(xy 142.241524 -434.429662) (xy 142.241524 -433.350162) (xy 142.239859 -433.335168) (xy 142.238078 -433.30505)
			(xy 142.237968 -433.289964) (xy 142.238081 -433.274878) (xy 142.23986 -433.24476) (xy 142.241524 -433.229766)
			(xy 142.241524 -432.618896) (xy 142.24191 -432.60681) (xy 142.249382 -432.583822) (xy 142.263594 -432.564268)
			(xy 142.283154 -432.550066) (xy 142.306146 -432.542604) (xy 142.318232 -432.542188) (xy 143.258032 -432.542188)
			(xy 143.270108 -432.542637) (xy 143.293075 -432.550108) (xy 143.312612 -432.564308) (xy 143.326805 -432.58385)
			(xy 143.334268 -432.60682) (xy 143.33474 -432.618896) (xy 143.33474 -435.16042) (xy 143.334253 -435.172492)
			(xy 143.326789 -435.195455) (xy 143.312597 -435.214989) (xy 143.293065 -435.229184) (xy 143.270104 -435.236651)
			(xy 143.258032 -435.237128) (xy 142.318232 -435.237128) (xy 142.306153 -435.23666) (xy 142.283175 -435.229204)
			(xy 142.263626 -435.215011) (xy 142.24942 -435.195472) (xy 142.241948 -435.172499) (xy 142.241524 -435.16042)
			(xy 142.241524 -434.550058) (xy 142.239858 -434.535064) (xy 142.238078 -434.504946) (xy 142.237968 -434.48986)
			(xy 140.335 -434.48986) (xy 140.335 -435.489858) (xy 144.237964 -435.489858) (xy 144.238077 -435.474772)
			(xy 144.239856 -435.444654) (xy 144.24152 -435.42966) (xy 144.24152 -434.35016) (xy 144.239855 -434.335166)
			(xy 144.238074 -434.305048) (xy 144.237964 -434.289962) (xy 144.238077 -434.274876) (xy 144.239856 -434.244758)
			(xy 144.24152 -434.229764) (xy 144.24152 -433.618894) (xy 144.242002 -433.606806) (xy 144.249458 -433.583809)
			(xy 144.263641 -433.564231) (xy 144.28317 -433.54998) (xy 144.306142 -433.542444) (xy 144.318228 -433.541932)
			(xy 145.258028 -433.541932) (xy 145.270142 -433.542293) (xy 145.293175 -433.549804) (xy 145.312751 -433.564079)
			(xy 145.326943 -433.583714) (xy 145.334357 -433.606779) (xy 145.334736 -433.618894) (xy 145.334736 -434.48986)
			(xy 146.23796 -434.48986) (xy 146.238073 -434.474774) (xy 146.239852 -434.444656) (xy 146.241516 -434.429662)
			(xy 146.241516 -433.350162) (xy 146.239851 -433.335168) (xy 146.23807 -433.30505) (xy 146.23796 -433.289964)
			(xy 146.238073 -433.274878) (xy 146.239852 -433.24476) (xy 146.241516 -433.229766) (xy 146.241516 -432.618896)
			(xy 146.241909 -432.606811) (xy 146.249381 -432.583824) (xy 146.263591 -432.564271) (xy 146.283149 -432.550068)
			(xy 146.306138 -432.542605) (xy 146.318224 -432.542188) (xy 147.258024 -432.542188) (xy 147.270099 -432.542644)
			(xy 147.293067 -432.550113) (xy 147.312603 -432.564311) (xy 147.326797 -432.583851) (xy 147.334259 -432.606821)
			(xy 147.334732 -432.618896) (xy 147.334732 -435.16042) (xy 147.334253 -435.172493) (xy 147.326788 -435.195457)
			(xy 147.312594 -435.214991) (xy 147.29306 -435.229186) (xy 147.270097 -435.236652) (xy 147.258024 -435.237128)
			(xy 146.318224 -435.237128) (xy 146.306145 -435.236667) (xy 146.283166 -435.229209) (xy 146.263617 -435.215014)
			(xy 146.249412 -435.195473) (xy 146.24194 -435.172499) (xy 146.241516 -435.16042) (xy 146.241516 -434.550058)
			(xy 146.23985 -434.535064) (xy 146.23807 -434.504946) (xy 146.23796 -434.48986) (xy 145.334736 -434.48986)
			(xy 145.334736 -435.489858) (xy 148.237956 -435.489858) (xy 148.238069 -435.474772) (xy 148.239848 -435.444654)
			(xy 148.241512 -435.42966) (xy 148.241512 -434.35016) (xy 148.239847 -434.335166) (xy 148.238066 -434.305048)
			(xy 148.237956 -434.289962) (xy 148.238069 -434.274876) (xy 148.239848 -434.244758) (xy 148.241512 -434.229764)
			(xy 148.241512 -433.618894) (xy 148.242002 -433.606807) (xy 148.249457 -433.583811) (xy 148.263639 -433.564234)
			(xy 148.283165 -433.549982) (xy 148.306135 -433.542445) (xy 148.31822 -433.541932) (xy 149.25802 -433.541932)
			(xy 149.270133 -433.5423) (xy 149.293167 -433.549808) (xy 149.312742 -433.564081) (xy 149.326935 -433.583715)
			(xy 149.334349 -433.606779) (xy 149.334728 -433.618894) (xy 149.334728 -434.48986) (xy 150.237952 -434.48986)
			(xy 150.238065 -434.474774) (xy 150.239844 -434.444656) (xy 150.241508 -434.429662) (xy 150.241508 -433.350162)
			(xy 150.239843 -433.335168) (xy 150.238062 -433.30505) (xy 150.237952 -433.289964) (xy 150.238065 -433.274878)
			(xy 150.239844 -433.24476) (xy 150.241508 -433.229766) (xy 150.241508 -432.618896) (xy 150.241909 -432.606811)
			(xy 150.24938 -432.583826) (xy 150.263588 -432.564274) (xy 150.283144 -432.550071) (xy 150.306131 -432.542606)
			(xy 150.318216 -432.542188) (xy 151.258016 -432.542188) (xy 151.270091 -432.542651) (xy 151.293058 -432.550117)
			(xy 151.312594 -432.564314) (xy 151.326788 -432.583853) (xy 151.334251 -432.606821) (xy 151.334724 -432.618896)
			(xy 151.334724 -435.16042) (xy 151.334253 -435.172494) (xy 151.326787 -435.195459) (xy 151.312591 -435.214994)
			(xy 151.293055 -435.229189) (xy 151.27009 -435.236654) (xy 151.258016 -435.237128) (xy 150.318216 -435.237128)
			(xy 150.306144 -435.236622) (xy 150.283181 -435.229167) (xy 150.263645 -435.21498) (xy 150.24945 -435.195451)
			(xy 150.241983 -435.172492) (xy 150.241508 -435.16042) (xy 150.241508 -434.550058) (xy 150.239842 -434.535064)
			(xy 150.238062 -434.504946) (xy 150.237952 -434.48986) (xy 149.334728 -434.48986) (xy 149.334728 -435.489858)
			(xy 152.237948 -435.489858) (xy 152.238061 -435.474772) (xy 152.23984 -435.444654) (xy 152.241504 -435.42966)
			(xy 152.241504 -434.35016) (xy 152.239838 -434.335166) (xy 152.238058 -434.305048) (xy 152.237948 -434.289962)
			(xy 152.238061 -434.274876) (xy 152.23984 -434.244758) (xy 152.241504 -434.229764) (xy 152.241504 -433.618894)
			(xy 152.242002 -433.606808) (xy 152.249456 -433.583813) (xy 152.263636 -433.564236) (xy 152.28316 -433.549985)
			(xy 152.306128 -433.542447) (xy 152.318212 -433.541932) (xy 153.258012 -433.541932) (xy 153.270125 -433.542306)
			(xy 153.293158 -433.549813) (xy 153.312734 -433.564084) (xy 153.326927 -433.583717) (xy 153.334341 -433.60678)
			(xy 153.33472 -433.618894) (xy 153.33472 -434.48986) (xy 154.237944 -434.48986) (xy 154.238057 -434.474774)
			(xy 154.239836 -434.444656) (xy 154.2415 -434.429662) (xy 154.2415 -433.350162) (xy 154.239835 -433.335168)
			(xy 154.238054 -433.30505) (xy 154.237944 -433.289964) (xy 154.238057 -433.274878) (xy 154.239836 -433.24476)
			(xy 154.2415 -433.229766) (xy 154.2415 -432.618896) (xy 154.241909 -432.606812) (xy 154.249379 -432.583828)
			(xy 154.263586 -432.564277) (xy 154.283139 -432.550073) (xy 154.306124 -432.542607) (xy 154.318208 -432.542188)
			(xy 155.258008 -432.542188) (xy 155.270083 -432.542657) (xy 155.293049 -432.550122) (xy 155.312586 -432.564317)
			(xy 155.32678 -432.583854) (xy 155.334243 -432.606821) (xy 155.334716 -432.618896) (xy 155.334716 -433.130695)
			(xy 197.035917 -433.130695) (xy 197.035917 -432.953425) (xy 197.04387 -432.776334) (xy 197.059761 -432.599778)
			(xy 197.083556 -432.424113) (xy 197.115209 -432.249692) (xy 197.154655 -432.076867) (xy 197.201815 -431.905986)
			(xy 197.256594 -431.737392) (xy 197.318882 -431.571427) (xy 197.388554 -431.408422) (xy 197.465468 -431.248708)
			(xy 197.549471 -431.092605) (xy 197.640392 -430.940428) (xy 197.738049 -430.792484) (xy 197.842246 -430.64907)
			(xy 197.952772 -430.510475) (xy 198.069404 -430.376978) (xy 198.191909 -430.248849) (xy 198.320038 -430.126344)
			(xy 198.453535 -430.009712) (xy 198.59213 -429.899186) (xy 198.735544 -429.794989) (xy 198.883488 -429.697332)
			(xy 199.035665 -429.606411) (xy 199.191768 -429.522408) (xy 199.351482 -429.445494) (xy 199.514487 -429.375822)
			(xy 199.680452 -429.313534) (xy 199.849046 -429.258755) (xy 200.019927 -429.211595) (xy 200.192752 -429.172149)
			(xy 200.367173 -429.140496) (xy 200.542838 -429.116701) (xy 200.719394 -429.10081) (xy 200.896485 -429.092857)
			(xy 201.073755 -429.092857) (xy 201.250846 -429.10081) (xy 201.427402 -429.116701) (xy 201.603067 -429.140496)
			(xy 201.777488 -429.172149) (xy 201.950313 -429.211595) (xy 202.121194 -429.258755) (xy 202.289788 -429.313534)
			(xy 202.455753 -429.375822) (xy 202.618758 -429.445494) (xy 202.778472 -429.522408) (xy 202.934575 -429.606411)
			(xy 203.086752 -429.697332) (xy 203.234696 -429.794989) (xy 203.37811 -429.899186) (xy 203.516705 -430.009712)
			(xy 203.650202 -430.126344) (xy 203.778331 -430.248849) (xy 203.900836 -430.376978) (xy 204.017468 -430.510475)
			(xy 204.127994 -430.64907) (xy 204.232191 -430.792484) (xy 204.329848 -430.940428) (xy 204.420769 -431.092605)
			(xy 204.504772 -431.248708) (xy 204.581686 -431.408422) (xy 204.651358 -431.571427) (xy 204.713646 -431.737392)
			(xy 204.768425 -431.905986) (xy 204.815585 -432.076867) (xy 204.855031 -432.249692) (xy 204.886684 -432.424113)
			(xy 204.910479 -432.599778) (xy 204.92637 -432.776334) (xy 204.934323 -432.953425) (xy 204.93482 -433.04206)
			(xy 204.934323 -433.130695) (xy 204.92637 -433.307786) (xy 204.910479 -433.484342) (xy 204.886684 -433.660007)
			(xy 204.855031 -433.834428) (xy 204.815585 -434.007253) (xy 204.768425 -434.178134) (xy 204.713646 -434.346728)
			(xy 204.651358 -434.512693) (xy 204.581686 -434.675698) (xy 204.504772 -434.835412) (xy 204.420769 -434.991515)
			(xy 204.329848 -435.143692) (xy 204.232191 -435.291636) (xy 204.127994 -435.43505) (xy 204.017468 -435.573645)
			(xy 203.900836 -435.707142) (xy 203.778331 -435.835271) (xy 203.650202 -435.957776) (xy 203.516705 -436.074408)
			(xy 203.37811 -436.184934) (xy 203.234696 -436.289131) (xy 203.086752 -436.386788) (xy 202.934575 -436.477709)
			(xy 202.778472 -436.561712) (xy 202.618758 -436.638626) (xy 202.455753 -436.708298) (xy 202.289788 -436.770586)
			(xy 202.121194 -436.825365) (xy 201.950313 -436.872525) (xy 201.777488 -436.911971) (xy 201.603067 -436.943624)
			(xy 201.427402 -436.967419) (xy 201.250846 -436.98331) (xy 201.073755 -436.991263) (xy 200.896485 -436.991263)
			(xy 200.719394 -436.98331) (xy 200.542838 -436.967419) (xy 200.367173 -436.943624) (xy 200.192752 -436.911971)
			(xy 200.019927 -436.872525) (xy 199.849046 -436.825365) (xy 199.680452 -436.770586) (xy 199.514487 -436.708298)
			(xy 199.351482 -436.638626) (xy 199.191768 -436.561712) (xy 199.035665 -436.477709) (xy 198.883488 -436.386788)
			(xy 198.735544 -436.289131) (xy 198.59213 -436.184934) (xy 198.453535 -436.074408) (xy 198.320038 -435.957776)
			(xy 198.191909 -435.835271) (xy 198.069404 -435.707142) (xy 197.952772 -435.573645) (xy 197.842246 -435.43505)
			(xy 197.738049 -435.291636) (xy 197.640392 -435.143692) (xy 197.549471 -434.991515) (xy 197.465468 -434.835412)
			(xy 197.388554 -434.675698) (xy 197.318882 -434.512693) (xy 197.256594 -434.346728) (xy 197.201815 -434.178134)
			(xy 197.154655 -434.007253) (xy 197.115209 -433.834428) (xy 197.083556 -433.660007) (xy 197.059761 -433.484342)
			(xy 197.04387 -433.307786) (xy 197.035917 -433.130695) (xy 155.334716 -433.130695) (xy 155.334716 -435.16042)
			(xy 155.334253 -435.172495) (xy 155.326786 -435.195461) (xy 155.312589 -435.214997) (xy 155.29305 -435.229191)
			(xy 155.270083 -435.236655) (xy 155.258008 -435.237128) (xy 154.318208 -435.237128) (xy 154.306136 -435.236629)
			(xy 154.283172 -435.229171) (xy 154.263637 -435.214983) (xy 154.249441 -435.195453) (xy 154.241975 -435.172492)
			(xy 154.2415 -435.16042) (xy 154.2415 -434.550058) (xy 154.239834 -434.535064) (xy 154.238054 -434.504946)
			(xy 154.237944 -434.48986) (xy 153.33472 -434.48986) (xy 153.33472 -435.489858) (xy 156.23794 -435.489858)
			(xy 156.238053 -435.474772) (xy 156.239832 -435.444654) (xy 156.241496 -435.42966) (xy 156.241496 -434.35016)
			(xy 156.23983 -434.335166) (xy 156.23805 -434.305048) (xy 156.23794 -434.289962) (xy 156.238053 -434.274876)
			(xy 156.239832 -434.244758) (xy 156.241496 -434.229764) (xy 156.241496 -433.618894) (xy 156.242002 -433.606809)
			(xy 156.249455 -433.583815) (xy 156.263633 -433.564239) (xy 156.283155 -433.549987) (xy 156.30612 -433.542448)
			(xy 156.318204 -433.541932) (xy 157.258004 -433.541932) (xy 157.270116 -433.542313) (xy 157.293149 -433.549818)
			(xy 157.312725 -433.564087) (xy 157.326918 -433.583718) (xy 157.334333 -433.60678) (xy 157.334712 -433.618894)
			(xy 157.334712 -436.160418) (xy 157.334307 -436.172513) (xy 157.32684 -436.195523) (xy 157.312639 -436.215106)
			(xy 157.293089 -436.229355) (xy 157.270098 -436.236878) (xy 157.258004 -436.23738) (xy 156.318204 -436.23738)
			(xy 156.306093 -436.23698) (xy 156.283063 -436.229479) (xy 156.263488 -436.215214) (xy 156.249294 -436.195588)
			(xy 156.241876 -436.17253) (xy 156.241496 -436.160418) (xy 156.241496 -435.550056) (xy 156.23983 -435.535062)
			(xy 156.23805 -435.504944) (xy 156.23794 -435.489858) (xy 153.33472 -435.489858) (xy 153.33472 -436.160418)
			(xy 153.334307 -436.172513) (xy 153.326841 -436.195521) (xy 153.312642 -436.215104) (xy 153.293094 -436.229352)
			(xy 153.270105 -436.236877) (xy 153.258012 -436.23738) (xy 152.318212 -436.23738) (xy 152.306102 -436.236973)
			(xy 152.283072 -436.229474) (xy 152.263497 -436.215211) (xy 152.249302 -436.195586) (xy 152.241885 -436.17253)
			(xy 152.241504 -436.160418) (xy 152.241504 -435.550056) (xy 152.239838 -435.535062) (xy 152.238058 -435.504944)
			(xy 152.237948 -435.489858) (xy 149.334728 -435.489858) (xy 149.334728 -436.160418) (xy 149.334308 -436.172512)
			(xy 149.326842 -436.195518) (xy 149.312645 -436.215101) (xy 149.293099 -436.22935) (xy 149.270112 -436.236876)
			(xy 149.25802 -436.23738) (xy 148.31822 -436.23738) (xy 148.30611 -436.236966) (xy 148.28308 -436.22947)
			(xy 148.263505 -436.215208) (xy 148.249311 -436.195585) (xy 148.241893 -436.172529) (xy 148.241512 -436.160418)
			(xy 148.241512 -435.550056) (xy 148.239846 -435.535062) (xy 148.238066 -435.504944) (xy 148.237956 -435.489858)
			(xy 145.334736 -435.489858) (xy 145.334736 -436.160418) (xy 145.334308 -436.172511) (xy 145.326843 -436.195516)
			(xy 145.312647 -436.215098) (xy 145.293104 -436.229347) (xy 145.27012 -436.236874) (xy 145.258028 -436.23738)
			(xy 144.318228 -436.23738) (xy 144.306119 -436.236959) (xy 144.283089 -436.229465) (xy 144.263514 -436.215206)
			(xy 144.249319 -436.195583) (xy 144.241901 -436.172529) (xy 144.24152 -436.160418) (xy 144.24152 -435.550056)
			(xy 144.239854 -435.535062) (xy 144.238074 -435.504944) (xy 144.237964 -435.489858) (xy 140.335 -435.489858)
			(xy 140.335 -436.160418) (xy 140.334504 -436.17253) (xy 140.327017 -436.195567) (xy 140.31278 -436.215165)
			(xy 140.293185 -436.229408) (xy 140.27015 -436.236901) (xy 140.258038 -436.23738) (xy 139.318238 -436.23738)
			(xy 139.306119 -436.236908) (xy 139.283064 -436.229428) (xy 139.26345 -436.21519) (xy 139.249197 -436.195586)
			(xy 139.241701 -436.172537) (xy 139.241276 -436.160418) (xy 139.241276 -435.548024) (xy 139.239728 -435.533532)
			(xy 139.238078 -435.504432) (xy 139.237974 -435.489858) (xy 136.335008 -435.489858) (xy 136.335008 -436.160418)
			(xy 136.334505 -436.172529) (xy 136.327018 -436.195565) (xy 136.312782 -436.215163) (xy 136.29319 -436.229405)
			(xy 136.270157 -436.2369) (xy 136.258046 -436.23738) (xy 135.318246 -436.23738) (xy 135.306127 -436.236901)
			(xy 135.283073 -436.229424) (xy 135.263459 -436.215187) (xy 135.249205 -436.195584) (xy 135.241709 -436.172536)
			(xy 135.241284 -436.160418) (xy 135.241284 -435.548024) (xy 135.239736 -435.533532) (xy 135.238086 -435.504432)
			(xy 135.237982 -435.489858) (xy 132.335016 -435.489858) (xy 132.335016 -436.160418) (xy 132.334654 -436.172546)
			(xy 132.327152 -436.195613) (xy 132.312886 -436.215232) (xy 132.293256 -436.229481) (xy 132.270183 -436.236965)
			(xy 132.258054 -436.23738) (xy 131.318254 -436.23738) (xy 131.306139 -436.236928) (xy 131.283097 -436.22943)
			(xy 131.263498 -436.215182) (xy 131.249257 -436.195578) (xy 131.241768 -436.172533) (xy 131.241292 -436.160418)
			(xy 131.241292 -435.548024) (xy 131.239744 -435.533532) (xy 131.238094 -435.504432) (xy 131.23799 -435.489858)
			(xy 128.335024 -435.489858) (xy 128.335024 -436.160418) (xy 128.334655 -436.172545) (xy 128.327153 -436.195611)
			(xy 128.312889 -436.215229) (xy 128.293261 -436.229478) (xy 128.27019 -436.236963) (xy 128.258062 -436.23738)
			(xy 127.318262 -436.23738) (xy 127.306147 -436.236921) (xy 127.283106 -436.229425) (xy 127.263506 -436.21518)
			(xy 127.249265 -436.195576) (xy 127.241776 -436.172533) (xy 127.2413 -436.160418) (xy 127.2413 -435.548024)
			(xy 127.239751 -435.533532) (xy 127.238102 -435.504432) (xy 127.237998 -435.489858) (xy 113.866512 -435.489858)
			(xy 113.892486 -435.537087) (xy 113.947862 -435.654438) (xy 113.995874 -435.77499) (xy 114.036336 -435.89828)
			(xy 114.069094 -436.023838) (xy 114.094022 -436.151181) (xy 114.111025 -436.279823) (xy 114.120038 -436.40927)
			(xy 114.121027 -436.539027) (xy 114.113986 -436.668596) (xy 114.098945 -436.797482) (xy 114.075959 -436.92519)
			(xy 114.045118 -437.051232) (xy 114.006538 -437.175125) (xy 113.960369 -437.296394) (xy 113.906786 -437.414574)
			(xy 113.845996 -437.529214) (xy 113.77823 -437.639874) (xy 113.703749 -437.74613) (xy 113.622838 -437.847575)
			(xy 113.535806 -437.943821) (xy 113.442988 -438.034499) (xy 113.378885 -438.089802) (xy 125.238002 -438.089802)
			(xy 125.238095 -438.075228) (xy 125.239748 -438.046127) (xy 125.241304 -438.031636) (xy 125.241304 -436.948072)
			(xy 125.239759 -436.93358) (xy 125.238107 -436.90448) (xy 125.238002 -436.889906) (xy 125.238095 -436.875332)
			(xy 125.239748 -436.846231) (xy 125.241304 -436.83174) (xy 125.241304 -436.219092) (xy 125.241709 -436.206982)
			(xy 125.249212 -436.183954) (xy 125.263476 -436.164381) (xy 125.2831 -436.150186) (xy 125.306155 -436.142767)
			(xy 125.318266 -436.142384) (xy 126.258066 -436.142384) (xy 126.270158 -436.142837) (xy 126.293165 -436.15029)
			(xy 126.312749 -436.164478) (xy 126.327 -436.184018) (xy 126.334525 -436.207001) (xy 126.335028 -436.219092)
			(xy 126.335028 -438.760616) (xy 126.334598 -438.772723) (xy 126.327097 -438.795746) (xy 126.312838 -438.815316)
			(xy 126.293222 -438.829511) (xy 126.270174 -438.836937) (xy 126.258066 -438.837324) (xy 125.318266 -438.837324)
			(xy 125.306171 -438.836921) (xy 125.283163 -438.829451) (xy 125.263581 -438.815249) (xy 125.249333 -438.7957)
			(xy 125.241808 -438.77271) (xy 125.241304 -438.760616) (xy 125.241304 -438.147968) (xy 125.239759 -438.133476)
			(xy 125.238107 -438.104376) (xy 125.238002 -438.089802) (xy 113.378885 -438.089802) (xy 113.344738 -438.119261)
			(xy 113.241432 -438.197784) (xy 113.133467 -438.269766) (xy 113.021257 -438.334931) (xy 112.90523 -438.39303)
			(xy 112.785831 -438.443841) (xy 112.663518 -438.487169) (xy 112.538759 -438.522847) (xy 112.412032 -438.550739)
			(xy 112.283822 -438.570739) (xy 112.15462 -438.58277) (xy 112.024922 -438.586785) (xy 111.895224 -438.58277)
			(xy 111.766022 -438.570739) (xy 111.637812 -438.550739) (xy 111.511085 -438.522847) (xy 111.386326 -438.487169)
			(xy 111.264013 -438.443841) (xy 111.144614 -438.39303) (xy 111.028587 -438.334931) (xy 110.916377 -438.269766)
			(xy 110.808412 -438.197784) (xy 110.705106 -438.119261) (xy 110.606856 -438.034499) (xy 110.514038 -437.943821)
			(xy 110.427006 -437.847575) (xy 110.346095 -437.74613) (xy 110.271614 -437.639874) (xy 110.203848 -437.529214)
			(xy 110.143058 -437.414574) (xy 110.089475 -437.296394) (xy 110.043306 -437.175125) (xy 110.004726 -437.051232)
			(xy 109.973885 -436.92519) (xy 109.950899 -436.797482) (xy 109.935858 -436.668596) (xy 109.928817 -436.539027)
			(xy 109.929806 -436.40927) (xy 109.938819 -436.279823) (xy 109.955822 -436.151181) (xy 109.98075 -436.023838)
			(xy 110.013508 -435.89828) (xy 110.05397 -435.77499) (xy 110.101982 -435.654438) (xy 110.157358 -435.537087)
			(xy 110.219888 -435.423387) (xy 110.289331 -435.313772) (xy 110.365422 -435.208663) (xy 110.447869 -435.108462)
			(xy 110.536357 -435.013553) (xy 110.630546 -434.924299) (xy 110.679992 -434.88229) (xy 110.691093 -434.872254)
			(xy 110.707515 -434.847259) (xy 110.71599 -434.818578) (xy 110.71579 -434.788672) (xy 110.706933 -434.760107)
			(xy 110.690178 -434.735334) (xy 110.666963 -434.71648) (xy 110.653322 -434.710332) (xy 110.574304 -434.677407)
			(xy 110.419107 -434.605131) (xy 110.267499 -434.5256) (xy 110.119821 -434.438991) (xy 109.976402 -434.345497)
			(xy 109.837562 -434.245328) (xy 109.703613 -434.138709) (xy 109.574854 -434.025876) (xy 109.451573 -433.907083)
			(xy 109.334045 -433.782595) (xy 109.222533 -433.65269) (xy 109.117287 -433.517659) (xy 109.018541 -433.377804)
			(xy 108.926517 -433.233438) (xy 108.84142 -433.084883) (xy 108.763441 -432.932471) (xy 108.692754 -432.776543)
			(xy 108.629516 -432.617449) (xy 108.57387 -432.455542) (xy 108.52594 -432.291187) (xy 108.485833 -432.124749)
			(xy 108.453638 -431.956601) (xy 108.429428 -431.78712) (xy 108.413257 -431.616683) (xy 108.405161 -431.445673)
			(xy 108.40466 -431.360072) (xy 90.235024 -431.360072) (xy 90.235024 -432.560476) (xy 90.234563 -432.572581)
			(xy 90.227074 -432.595604) (xy 90.212823 -432.615175) (xy 90.193212 -432.629371) (xy 90.170168 -432.636797)
			(xy 90.158062 -432.637184) (xy 89.218262 -432.637184) (xy 89.206173 -432.636726) (xy 89.183175 -432.629261)
			(xy 89.163598 -432.615072) (xy 89.149348 -432.595538) (xy 89.141812 -432.572564) (xy 89.1413 -432.560476)
			(xy 89.1413 -431.948082) (xy 89.139756 -431.93359) (xy 89.138104 -431.90449) (xy 89.137998 -431.889916)
			(xy 86.235032 -431.889916) (xy 86.235032 -432.560476) (xy 86.234563 -432.57258) (xy 86.227075 -432.595601)
			(xy 86.212825 -432.615172) (xy 86.193217 -432.629369) (xy 86.170175 -432.636796) (xy 86.15807 -432.637184)
			(xy 85.21827 -432.637184) (xy 85.206181 -432.636719) (xy 85.183184 -432.629257) (xy 85.163606 -432.615069)
			(xy 85.149356 -432.595537) (xy 85.14182 -432.572563) (xy 85.141308 -432.560476) (xy 85.141308 -431.948082)
			(xy 85.139764 -431.93359) (xy 85.138112 -431.90449) (xy 85.138006 -431.889916) (xy 82.23504 -431.889916)
			(xy 82.23504 -432.560476) (xy 82.234564 -432.57258) (xy 82.227076 -432.595599) (xy 82.212828 -432.615169)
			(xy 82.193222 -432.629366) (xy 82.170183 -432.636795) (xy 82.158078 -432.637184) (xy 81.218278 -432.637184)
			(xy 81.20619 -432.636712) (xy 81.183192 -432.629252) (xy 81.163615 -432.615066) (xy 81.149364 -432.595535)
			(xy 81.141828 -432.572563) (xy 81.141316 -432.560476) (xy 81.141316 -431.948082) (xy 81.139772 -431.93359)
			(xy 81.13812 -431.90449) (xy 81.138014 -431.889916) (xy 78.235048 -431.889916) (xy 78.235048 -432.560476)
			(xy 78.234564 -432.572579) (xy 78.227077 -432.595597) (xy 78.212831 -432.615166) (xy 78.193227 -432.629364)
			(xy 78.17019 -432.636793) (xy 78.158086 -432.637184) (xy 77.218286 -432.637184) (xy 77.206198 -432.636705)
			(xy 77.183201 -432.629248) (xy 77.163623 -432.615063) (xy 77.149372 -432.595534) (xy 77.141836 -432.572562)
			(xy 77.141324 -432.560476) (xy 77.141324 -431.948082) (xy 77.13978 -431.93359) (xy 77.138128 -431.90449)
			(xy 77.138022 -431.889916) (xy 73.234804 -431.889916) (xy 73.234804 -432.560476) (xy 73.234367 -432.572558)
			(xy 73.226905 -432.59554) (xy 73.212706 -432.615091) (xy 73.193158 -432.629296) (xy 73.170178 -432.636764)
			(xy 73.158096 -432.637184) (xy 72.218296 -432.637184) (xy 72.206211 -432.636791) (xy 72.183224 -432.629319)
			(xy 72.163671 -432.615109) (xy 72.149468 -432.595551) (xy 72.142005 -432.572562) (xy 72.141588 -432.560476)
			(xy 72.141588 -431.950114) (xy 72.139918 -431.935121) (xy 72.138141 -431.905002) (xy 72.138032 -431.889916)
			(xy 69.234812 -431.889916) (xy 69.234812 -432.560476) (xy 69.234367 -432.572557) (xy 69.226906 -432.595538)
			(xy 69.212709 -432.615089) (xy 69.193163 -432.629294) (xy 69.170185 -432.636762) (xy 69.158104 -432.637184)
			(xy 68.218304 -432.637184) (xy 68.206219 -432.636784) (xy 68.183232 -432.629314) (xy 68.16368 -432.615106)
			(xy 68.149476 -432.59555) (xy 68.142013 -432.572561) (xy 68.141596 -432.560476) (xy 68.141596 -431.950114)
			(xy 68.139926 -431.935121) (xy 68.138149 -431.905002) (xy 68.13804 -431.889916) (xy 65.23482 -431.889916)
			(xy 65.23482 -432.560476) (xy 65.234367 -432.572556) (xy 65.226907 -432.595536) (xy 65.212711 -432.615086)
			(xy 65.193168 -432.629291) (xy 65.170192 -432.636761) (xy 65.158112 -432.637184) (xy 64.218312 -432.637184)
			(xy 64.206228 -432.636777) (xy 64.183241 -432.629309) (xy 64.163689 -432.615103) (xy 64.149485 -432.595548)
			(xy 64.142022 -432.572561) (xy 64.141604 -432.560476) (xy 64.141604 -431.950114) (xy 64.139934 -431.935121)
			(xy 64.138157 -431.905002) (xy 64.138048 -431.889916) (xy 61.234828 -431.889916) (xy 61.234828 -432.560476)
			(xy 61.234367 -432.572555) (xy 61.226909 -432.595534) (xy 61.212714 -432.615083) (xy 61.193173 -432.629288)
			(xy 61.170199 -432.63676) (xy 61.15812 -432.637184) (xy 60.21832 -432.637184) (xy 60.206236 -432.63677)
			(xy 60.18325 -432.629305) (xy 60.163697 -432.6151) (xy 60.149493 -432.595547) (xy 60.14203 -432.57256)
			(xy 60.141612 -432.560476) (xy 60.141612 -431.950114) (xy 60.139942 -431.935121) (xy 60.138165 -431.905002)
			(xy 60.138056 -431.889916) (xy 7.00913 -431.889916) (xy 7.00913 -434.48986) (xy 58.13806 -434.48986)
			(xy 58.138173 -434.474774) (xy 58.139952 -434.444656) (xy 58.141616 -434.429662) (xy 58.141616 -433.350162)
			(xy 58.139951 -433.335168) (xy 58.13817 -433.30505) (xy 58.13806 -433.289964) (xy 58.138173 -433.274878)
			(xy 58.139952 -433.24476) (xy 58.141616 -433.229766) (xy 58.141616 -432.618896) (xy 58.142009 -432.606811)
			(xy 58.149481 -432.583824) (xy 58.163691 -432.564271) (xy 58.183249 -432.550068) (xy 58.206238 -432.542605)
			(xy 58.218324 -432.542188) (xy 59.158124 -432.542188) (xy 59.170199 -432.542644) (xy 59.193167 -432.550113)
			(xy 59.212703 -432.564311) (xy 59.226897 -432.583851) (xy 59.234359 -432.606821) (xy 59.234832 -432.618896)
			(xy 59.234832 -435.16042) (xy 59.234353 -435.172493) (xy 59.226888 -435.195457) (xy 59.212694 -435.214991)
			(xy 59.19316 -435.229186) (xy 59.170197 -435.236652) (xy 59.158124 -435.237128) (xy 58.218324 -435.237128)
			(xy 58.206245 -435.236667) (xy 58.183266 -435.229209) (xy 58.163717 -435.215014) (xy 58.149512 -435.195473)
			(xy 58.14204 -435.172499) (xy 58.141616 -435.16042) (xy 58.141616 -434.550058) (xy 58.13995 -434.535064)
			(xy 58.13817 -434.504946) (xy 58.13806 -434.48986) (xy 7.00913 -434.48986) (xy 7.00913 -435.489858)
			(xy 60.138056 -435.489858) (xy 60.138169 -435.474772) (xy 60.139948 -435.444654) (xy 60.141612 -435.42966)
			(xy 60.141612 -434.35016) (xy 60.139947 -434.335166) (xy 60.138166 -434.305048) (xy 60.138056 -434.289962)
			(xy 60.138169 -434.274876) (xy 60.139948 -434.244758) (xy 60.141612 -434.229764) (xy 60.141612 -433.618894)
			(xy 60.142102 -433.606807) (xy 60.149557 -433.583811) (xy 60.163739 -433.564234) (xy 60.183265 -433.549982)
			(xy 60.206235 -433.542445) (xy 60.21832 -433.541932) (xy 61.15812 -433.541932) (xy 61.170233 -433.5423)
			(xy 61.193267 -433.549808) (xy 61.212842 -433.564081) (xy 61.227035 -433.583715) (xy 61.234449 -433.606779)
			(xy 61.234828 -433.618894) (xy 61.234828 -434.48986) (xy 62.138052 -434.48986) (xy 62.138165 -434.474774)
			(xy 62.139944 -434.444656) (xy 62.141608 -434.429662) (xy 62.141608 -433.350162) (xy 62.139943 -433.335168)
			(xy 62.138162 -433.30505) (xy 62.138052 -433.289964) (xy 62.138165 -433.274878) (xy 62.139944 -433.24476)
			(xy 62.141608 -433.229766) (xy 62.141608 -432.618896) (xy 62.142009 -432.606811) (xy 62.14948 -432.583826)
			(xy 62.163688 -432.564274) (xy 62.183244 -432.550071) (xy 62.206231 -432.542606) (xy 62.218316 -432.542188)
			(xy 63.158116 -432.542188) (xy 63.170191 -432.542651) (xy 63.193158 -432.550117) (xy 63.212694 -432.564314)
			(xy 63.226888 -432.583853) (xy 63.234351 -432.606821) (xy 63.234824 -432.618896) (xy 63.234824 -435.16042)
			(xy 63.234353 -435.172494) (xy 63.226887 -435.195459) (xy 63.212691 -435.214994) (xy 63.193155 -435.229189)
			(xy 63.17019 -435.236654) (xy 63.158116 -435.237128) (xy 62.218316 -435.237128) (xy 62.206244 -435.236622)
			(xy 62.183281 -435.229167) (xy 62.163745 -435.21498) (xy 62.14955 -435.195451) (xy 62.142083 -435.172492)
			(xy 62.141608 -435.16042) (xy 62.141608 -434.550058) (xy 62.139942 -434.535064) (xy 62.138162 -434.504946)
			(xy 62.138052 -434.48986) (xy 61.234828 -434.48986) (xy 61.234828 -435.489858) (xy 64.138048 -435.489858)
			(xy 64.138161 -435.474772) (xy 64.13994 -435.444654) (xy 64.141604 -435.42966) (xy 64.141604 -434.35016)
			(xy 64.139938 -434.335166) (xy 64.138158 -434.305048) (xy 64.138048 -434.289962) (xy 64.138161 -434.274876)
			(xy 64.13994 -434.244758) (xy 64.141604 -434.229764) (xy 64.141604 -433.618894) (xy 64.142102 -433.606808)
			(xy 64.149556 -433.583813) (xy 64.163736 -433.564236) (xy 64.18326 -433.549985) (xy 64.206228 -433.542447)
			(xy 64.218312 -433.541932) (xy 65.158112 -433.541932) (xy 65.170225 -433.542306) (xy 65.193258 -433.549813)
			(xy 65.212834 -433.564084) (xy 65.227027 -433.583717) (xy 65.234441 -433.60678) (xy 65.23482 -433.618894)
			(xy 65.23482 -434.48986) (xy 66.138044 -434.48986) (xy 66.138157 -434.474774) (xy 66.139936 -434.444656)
			(xy 66.1416 -434.429662) (xy 66.1416 -433.350162) (xy 66.139935 -433.335168) (xy 66.138154 -433.30505)
			(xy 66.138044 -433.289964) (xy 66.138157 -433.274878) (xy 66.139936 -433.24476) (xy 66.1416 -433.229766)
			(xy 66.1416 -432.618896) (xy 66.142009 -432.606812) (xy 66.149479 -432.583828) (xy 66.163686 -432.564277)
			(xy 66.183239 -432.550073) (xy 66.206224 -432.542607) (xy 66.218308 -432.542188) (xy 67.158108 -432.542188)
			(xy 67.170183 -432.542657) (xy 67.193149 -432.550122) (xy 67.212686 -432.564317) (xy 67.22688 -432.583854)
			(xy 67.234343 -432.606821) (xy 67.234816 -432.618896) (xy 67.234816 -435.16042) (xy 67.234353 -435.172495)
			(xy 67.226886 -435.195461) (xy 67.212689 -435.214997) (xy 67.19315 -435.229191) (xy 67.170183 -435.236655)
			(xy 67.158108 -435.237128) (xy 66.218308 -435.237128) (xy 66.206236 -435.236629) (xy 66.183272 -435.229171)
			(xy 66.163737 -435.214983) (xy 66.149541 -435.195453) (xy 66.142075 -435.172492) (xy 66.1416 -435.16042)
			(xy 66.1416 -434.550058) (xy 66.139934 -434.535064) (xy 66.138154 -434.504946) (xy 66.138044 -434.48986)
			(xy 65.23482 -434.48986) (xy 65.23482 -435.489858) (xy 68.13804 -435.489858) (xy 68.138153 -435.474772)
			(xy 68.139932 -435.444654) (xy 68.141596 -435.42966) (xy 68.141596 -434.35016) (xy 68.13993 -434.335166)
			(xy 68.13815 -434.305048) (xy 68.13804 -434.289962) (xy 68.138153 -434.274876) (xy 68.139932 -434.244758)
			(xy 68.141596 -434.229764) (xy 68.141596 -433.618894) (xy 68.142102 -433.606809) (xy 68.149555 -433.583815)
			(xy 68.163733 -433.564239) (xy 68.183255 -433.549987) (xy 68.20622 -433.542448) (xy 68.218304 -433.541932)
			(xy 69.158104 -433.541932) (xy 69.170216 -433.542313) (xy 69.193249 -433.549818) (xy 69.212825 -433.564087)
			(xy 69.227018 -433.583718) (xy 69.234433 -433.60678) (xy 69.234812 -433.618894) (xy 69.234812 -434.48986)
			(xy 70.138036 -434.48986) (xy 70.138151 -434.474775) (xy 70.13993 -434.444656) (xy 70.141592 -434.429662)
			(xy 70.141592 -433.350162) (xy 70.139927 -433.335168) (xy 70.138146 -433.30505) (xy 70.138036 -433.289964)
			(xy 70.138152 -433.274879) (xy 70.13993 -433.24476) (xy 70.141592 -433.229766) (xy 70.141592 -432.618896)
			(xy 70.142061 -432.606821) (xy 70.149524 -432.583854) (xy 70.16372 -432.564317) (xy 70.183258 -432.550123)
			(xy 70.206225 -432.54266) (xy 70.2183 -432.542188) (xy 71.1581 -432.542188) (xy 71.170174 -432.542664)
			(xy 71.193141 -432.550126) (xy 71.212677 -432.56432) (xy 71.226872 -432.583856) (xy 71.234335 -432.606822)
			(xy 71.234808 -432.618896) (xy 71.234808 -435.16042) (xy 71.234353 -435.172496) (xy 71.226885 -435.195463)
			(xy 71.212686 -435.215) (xy 71.193145 -435.229194) (xy 71.170176 -435.236656) (xy 71.1581 -435.237128)
			(xy 70.2183 -435.237128) (xy 70.206227 -435.236636) (xy 70.183264 -435.229176) (xy 70.163728 -435.214986)
			(xy 70.149533 -435.195454) (xy 70.142067 -435.172492) (xy 70.141592 -435.16042) (xy 70.141592 -434.550058)
			(xy 70.139926 -434.535064) (xy 70.138146 -434.504946) (xy 70.138036 -434.48986) (xy 69.234812 -434.48986)
			(xy 69.234812 -435.489858) (xy 72.138032 -435.489858) (xy 72.138147 -435.474773) (xy 72.139926 -435.444654)
			(xy 72.141588 -435.42966) (xy 72.141588 -434.35016) (xy 72.139922 -434.335166) (xy 72.138142 -434.305048)
			(xy 72.138032 -434.289962) (xy 72.138147 -434.274877) (xy 72.139926 -434.244758) (xy 72.141588 -434.229764)
			(xy 72.141588 -433.618894) (xy 72.142003 -433.606799) (xy 72.149468 -433.583791) (xy 72.163666 -433.564207)
			(xy 72.183213 -433.549958) (xy 72.206203 -433.542435) (xy 72.218296 -433.541932) (xy 73.158096 -433.541932)
			(xy 73.170208 -433.54232) (xy 73.193241 -433.549822) (xy 73.212817 -433.56409) (xy 73.22701 -433.58372)
			(xy 73.234425 -433.606781) (xy 73.234804 -433.618894) (xy 73.234804 -434.48986) (xy 75.138026 -434.48986)
			(xy 75.138124 -434.475286) (xy 75.139774 -434.446185) (xy 75.141328 -434.431694) (xy 75.141328 -433.34813)
			(xy 75.13978 -433.333638) (xy 75.13813 -433.304538) (xy 75.138026 -433.289964) (xy 75.138124 -433.27539)
			(xy 75.139774 -433.246289) (xy 75.141328 -433.231798) (xy 75.141328 -432.618896) (xy 75.141713 -432.606784)
			(xy 75.149217 -432.583752) (xy 75.163486 -432.564176) (xy 75.183116 -432.549983) (xy 75.206177 -432.542567)
			(xy 75.21829 -432.542188) (xy 76.15809 -432.542188) (xy 76.170184 -432.542617) (xy 76.193192 -432.550077)
			(xy 76.212776 -432.564271) (xy 76.227025 -432.583816) (xy 76.234549 -432.606804) (xy 76.235052 -432.618896)
			(xy 76.235052 -435.16042) (xy 76.234601 -435.172525) (xy 76.227103 -435.195544) (xy 76.212848 -435.215112)
			(xy 76.193237 -435.229308) (xy 76.170196 -435.236737) (xy 76.15809 -435.237128) (xy 75.21829 -435.237128)
			(xy 75.206197 -435.2367) (xy 75.183191 -435.229237) (xy 75.163608 -435.215041) (xy 75.149359 -435.195498)
			(xy 75.141833 -435.172512) (xy 75.141328 -435.16042) (xy 75.141328 -434.548026) (xy 75.13978 -434.533534)
			(xy 75.13813 -434.504434) (xy 75.138026 -434.48986) (xy 73.234804 -434.48986) (xy 73.234804 -435.489858)
			(xy 77.138022 -435.489858) (xy 77.13812 -435.475284) (xy 77.13977 -435.446183) (xy 77.141324 -435.431692)
			(xy 77.141324 -434.348128) (xy 77.139776 -434.333636) (xy 77.138126 -434.304536) (xy 77.138022 -434.289962)
			(xy 77.13812 -434.275388) (xy 77.13977 -434.246287) (xy 77.141324 -434.231796) (xy 77.141324 -433.618894)
			(xy 77.141807 -433.606781) (xy 77.149294 -433.58374) (xy 77.163534 -433.564139) (xy 77.183132 -433.549897)
			(xy 77.206173 -433.542408) (xy 77.218286 -433.541932) (xy 78.158086 -433.541932) (xy 78.170207 -433.542372)
			(xy 78.193265 -433.54986) (xy 78.21288 -433.564106) (xy 78.227131 -433.583717) (xy 78.234625 -433.606773)
			(xy 78.235048 -433.618894) (xy 78.235048 -434.48986) (xy 79.138018 -434.48986) (xy 79.138116 -434.475286)
			(xy 79.139766 -434.446185) (xy 79.14132 -434.431694) (xy 79.14132 -433.34813) (xy 79.139772 -433.333638)
			(xy 79.138122 -433.304538) (xy 79.138018 -433.289964) (xy 79.138116 -433.27539) (xy 79.139766 -433.246289)
			(xy 79.14132 -433.231798) (xy 79.14132 -432.618896) (xy 79.141713 -432.606785) (xy 79.149216 -432.583754)
			(xy 79.163483 -432.564179) (xy 79.183111 -432.549985) (xy 79.206169 -432.542568) (xy 79.218282 -432.542188)
			(xy 80.158082 -432.542188) (xy 80.170175 -432.542624) (xy 80.193183 -432.550081) (xy 80.212768 -432.564274)
			(xy 80.227017 -432.583818) (xy 80.234541 -432.606804) (xy 80.235044 -432.618896) (xy 80.235044 -435.16042)
			(xy 80.234601 -435.172526) (xy 80.227102 -435.195546) (xy 80.212845 -435.215115) (xy 80.193232 -435.22931)
			(xy 80.170189 -435.236739) (xy 80.158082 -435.237128) (xy 79.218282 -435.237128) (xy 79.206188 -435.236708)
			(xy 79.183182 -435.229242) (xy 79.163599 -435.215045) (xy 79.14935 -435.195499) (xy 79.141824 -435.172512)
			(xy 79.14132 -435.16042) (xy 79.14132 -434.548026) (xy 79.139772 -434.533534) (xy 79.138122 -434.504434)
			(xy 79.138018 -434.48986) (xy 78.235048 -434.48986) (xy 78.235048 -435.489858) (xy 81.138014 -435.489858)
			(xy 81.138111 -435.475284) (xy 81.139761 -435.446183) (xy 81.141316 -435.431692) (xy 81.141316 -434.348128)
			(xy 81.139768 -434.333636) (xy 81.138118 -434.304536) (xy 81.138014 -434.289962) (xy 81.138112 -434.275388)
			(xy 81.139761 -434.246287) (xy 81.141316 -434.231796) (xy 81.141316 -433.618894) (xy 81.141807 -433.606781)
			(xy 81.149293 -433.583742) (xy 81.163531 -433.564142) (xy 81.183127 -433.5499) (xy 81.206165 -433.542409)
			(xy 81.218278 -433.541932) (xy 82.158078 -433.541932) (xy 82.170199 -433.542379) (xy 82.193256 -433.549864)
			(xy 82.212871 -433.564109) (xy 82.227123 -433.583719) (xy 82.234617 -433.606773) (xy 82.23504 -433.618894)
			(xy 82.23504 -434.48986) (xy 83.13801 -434.48986) (xy 83.138107 -434.475286) (xy 83.139757 -434.446185)
			(xy 83.141312 -434.431694) (xy 83.141312 -433.34813) (xy 83.139764 -433.333638) (xy 83.138114 -433.304538)
			(xy 83.13801 -433.289964) (xy 83.138108 -433.27539) (xy 83.139757 -433.246289) (xy 83.141312 -433.231798)
			(xy 83.141312 -432.618896) (xy 83.141713 -432.606786) (xy 83.149215 -432.583756) (xy 83.16348 -432.564182)
			(xy 83.183106 -432.549988) (xy 83.206162 -432.542569) (xy 83.218274 -432.542188) (xy 84.158074 -432.542188)
			(xy 84.170167 -432.54263) (xy 84.193175 -432.550086) (xy 84.212759 -432.564277) (xy 84.227009 -432.583819)
			(xy 84.234533 -432.606804) (xy 84.235036 -432.618896) (xy 84.235036 -435.16042) (xy 84.234601 -435.172526)
			(xy 84.227101 -435.195548) (xy 84.212843 -435.215118) (xy 84.193227 -435.229313) (xy 84.170182 -435.23674)
			(xy 84.158074 -435.237128) (xy 83.218274 -435.237128) (xy 83.20618 -435.236714) (xy 83.183173 -435.229247)
			(xy 83.163591 -435.215047) (xy 83.149342 -435.195501) (xy 83.141816 -435.172513) (xy 83.141312 -435.16042)
			(xy 83.141312 -434.548026) (xy 83.139764 -434.533534) (xy 83.138114 -434.504434) (xy 83.13801 -434.48986)
			(xy 82.23504 -434.48986) (xy 82.23504 -435.489858) (xy 85.138006 -435.489858) (xy 85.138103 -435.475284)
			(xy 85.139753 -435.446183) (xy 85.141308 -435.431692) (xy 85.141308 -434.348128) (xy 85.13976 -434.333636)
			(xy 85.13811 -434.304536) (xy 85.138006 -434.289962) (xy 85.138104 -434.275388) (xy 85.139753 -434.246287)
			(xy 85.141308 -434.231796) (xy 85.141308 -433.618894) (xy 85.141806 -433.606782) (xy 85.149292 -433.583744)
			(xy 85.163528 -433.564145) (xy 85.183122 -433.549903) (xy 85.206158 -433.54241) (xy 85.21827 -433.541932)
			(xy 86.15807 -433.541932) (xy 86.170191 -433.542385) (xy 86.193247 -433.549869) (xy 86.212863 -433.564112)
			(xy 86.227115 -433.58372) (xy 86.234609 -433.606774) (xy 86.235032 -433.618894) (xy 86.235032 -434.48986)
			(xy 87.138002 -434.48986) (xy 87.1381 -434.475286) (xy 87.139749 -434.446185) (xy 87.141304 -434.431694)
			(xy 87.141304 -433.34813) (xy 87.139756 -433.333638) (xy 87.138106 -433.304538) (xy 87.138002 -433.289964)
			(xy 87.1381 -433.27539) (xy 87.139749 -433.246289) (xy 87.141304 -433.231798) (xy 87.141304 -432.618896)
			(xy 87.141713 -432.606787) (xy 87.149214 -432.583758) (xy 87.163477 -432.564185) (xy 87.183101 -432.549991)
			(xy 87.206155 -432.542571) (xy 87.218266 -432.542188) (xy 88.158066 -432.542188) (xy 88.170159 -432.542637)
			(xy 88.193166 -432.55009) (xy 88.212751 -432.56428) (xy 88.227001 -432.583821) (xy 88.234525 -432.606805)
			(xy 88.235028 -432.618896) (xy 88.235028 -435.16042) (xy 88.234601 -435.172527) (xy 88.2271 -435.19555)
			(xy 88.21284 -435.215121) (xy 88.193222 -435.229316) (xy 88.170174 -435.236741) (xy 88.158066 -435.237128)
			(xy 87.218266 -435.237128) (xy 87.206171 -435.236721) (xy 87.183164 -435.229251) (xy 87.163582 -435.21505)
			(xy 87.149334 -435.195502) (xy 87.141808 -435.172513) (xy 87.141304 -435.16042) (xy 87.141304 -434.548026)
			(xy 87.139756 -434.533534) (xy 87.138106 -434.504434) (xy 87.138002 -434.48986) (xy 86.235032 -434.48986)
			(xy 86.235032 -435.489858) (xy 89.137998 -435.489858) (xy 89.138095 -435.475284) (xy 89.139745 -435.446183)
			(xy 89.1413 -435.431692) (xy 89.1413 -434.348128) (xy 89.139752 -434.333636) (xy 89.138102 -434.304536)
			(xy 89.137998 -434.289962) (xy 89.138096 -434.275388) (xy 89.139745 -434.246287) (xy 89.1413 -434.231796)
			(xy 89.1413 -433.618894) (xy 89.141806 -433.606783) (xy 89.14929 -433.583746) (xy 89.163525 -433.564148)
			(xy 89.183117 -433.549905) (xy 89.206151 -433.542411) (xy 89.218262 -433.541932) (xy 90.158062 -433.541932)
			(xy 90.170182 -433.542392) (xy 90.193239 -433.549873) (xy 90.212854 -433.564115) (xy 90.227107 -433.583722)
			(xy 90.234601 -433.606774) (xy 90.235024 -433.618894) (xy 90.235024 -436.160418) (xy 90.234655 -436.172545)
			(xy 90.227153 -436.195611) (xy 90.212889 -436.215229) (xy 90.193261 -436.229478) (xy 90.17019 -436.236963)
			(xy 90.158062 -436.23738) (xy 89.218262 -436.23738) (xy 89.206147 -436.236921) (xy 89.183106 -436.229425)
			(xy 89.163506 -436.21518) (xy 89.149265 -436.195576) (xy 89.141776 -436.172533) (xy 89.1413 -436.160418)
			(xy 89.1413 -435.548024) (xy 89.139751 -435.533532) (xy 89.138102 -435.504432) (xy 89.137998 -435.489858)
			(xy 86.235032 -435.489858) (xy 86.235032 -436.160418) (xy 86.234655 -436.172545) (xy 86.227154 -436.195609)
			(xy 86.212892 -436.215226) (xy 86.193266 -436.229476) (xy 86.170197 -436.236962) (xy 86.15807 -436.23738)
			(xy 85.21827 -436.23738) (xy 85.206156 -436.236914) (xy 85.183114 -436.229421) (xy 85.163515 -436.215177)
			(xy 85.149274 -436.195575) (xy 85.141784 -436.172532) (xy 85.141308 -436.160418) (xy 85.141308 -435.548024)
			(xy 85.139759 -435.533532) (xy 85.13811 -435.504432) (xy 85.138006 -435.489858) (xy 82.23504 -435.489858)
			(xy 82.23504 -436.160418) (xy 82.234655 -436.172544) (xy 82.227155 -436.195607) (xy 82.212895 -436.215224)
			(xy 82.193271 -436.229473) (xy 82.170204 -436.236961) (xy 82.158078 -436.23738) (xy 81.218278 -436.23738)
			(xy 81.206164 -436.236907) (xy 81.183123 -436.229416) (xy 81.163523 -436.215174) (xy 81.149282 -436.195573)
			(xy 81.141792 -436.172532) (xy 81.141316 -436.160418) (xy 81.141316 -435.548024) (xy 81.139767 -435.533532)
			(xy 81.138118 -435.504432) (xy 81.138014 -435.489858) (xy 78.235048 -435.489858) (xy 78.235048 -436.160418)
			(xy 78.234604 -436.172535) (xy 78.22711 -436.195581) (xy 78.212861 -436.215184) (xy 78.193252 -436.229424)
			(xy 78.170203 -436.236909) (xy 78.158086 -436.23738) (xy 77.218286 -436.23738) (xy 77.206172 -436.236901)
			(xy 77.183132 -436.229412) (xy 77.163532 -436.215171) (xy 77.14929 -436.195572) (xy 77.1418 -436.172531)
			(xy 77.141324 -436.160418) (xy 77.141324 -435.548024) (xy 77.139775 -435.533532) (xy 77.138126 -435.504432)
			(xy 77.138022 -435.489858) (xy 73.234804 -435.489858) (xy 73.234804 -436.160418) (xy 73.234309 -436.172504)
			(xy 73.226853 -436.195498) (xy 73.212672 -436.215074) (xy 73.193147 -436.229325) (xy 73.17018 -436.236865)
			(xy 73.158096 -436.23738) (xy 72.218296 -436.23738) (xy 72.206185 -436.236987) (xy 72.183154 -436.229484)
			(xy 72.163579 -436.215217) (xy 72.149385 -436.195589) (xy 72.141968 -436.172531) (xy 72.141588 -436.160418)
			(xy 72.141588 -435.550056) (xy 72.139922 -435.535062) (xy 72.138142 -435.504944) (xy 72.138032 -435.489858)
			(xy 69.234812 -435.489858) (xy 69.234812 -436.160418) (xy 69.234407 -436.172513) (xy 69.22694 -436.195523)
			(xy 69.212739 -436.215106) (xy 69.193189 -436.229355) (xy 69.170198 -436.236878) (xy 69.158104 -436.23738)
			(xy 68.218304 -436.23738) (xy 68.206193 -436.23698) (xy 68.183163 -436.229479) (xy 68.163588 -436.215214)
			(xy 68.149394 -436.195588) (xy 68.141976 -436.17253) (xy 68.141596 -436.160418) (xy 68.141596 -435.550056)
			(xy 68.13993 -435.535062) (xy 68.13815 -435.504944) (xy 68.13804 -435.489858) (xy 65.23482 -435.489858)
			(xy 65.23482 -436.160418) (xy 65.234407 -436.172513) (xy 65.226941 -436.195521) (xy 65.212742 -436.215104)
			(xy 65.193194 -436.229352) (xy 65.170205 -436.236877) (xy 65.158112 -436.23738) (xy 64.218312 -436.23738)
			(xy 64.206202 -436.236973) (xy 64.183172 -436.229474) (xy 64.163597 -436.215211) (xy 64.149402 -436.195586)
			(xy 64.141985 -436.17253) (xy 64.141604 -436.160418) (xy 64.141604 -435.550056) (xy 64.139938 -435.535062)
			(xy 64.138158 -435.504944) (xy 64.138048 -435.489858) (xy 61.234828 -435.489858) (xy 61.234828 -436.160418)
			(xy 61.234408 -436.172512) (xy 61.226942 -436.195518) (xy 61.212745 -436.215101) (xy 61.193199 -436.22935)
			(xy 61.170212 -436.236876) (xy 61.15812 -436.23738) (xy 60.21832 -436.23738) (xy 60.20621 -436.236966)
			(xy 60.18318 -436.22947) (xy 60.163605 -436.215208) (xy 60.149411 -436.195585) (xy 60.141993 -436.172529)
			(xy 60.141612 -436.160418) (xy 60.141612 -435.550056) (xy 60.139946 -435.535062) (xy 60.138166 -435.504944)
			(xy 60.138056 -435.489858) (xy 7.00913 -435.489858) (xy 7.00913 -438.089802) (xy 58.13806 -438.089802)
			(xy 58.138177 -438.074717) (xy 58.139953 -438.044598) (xy 58.141616 -438.029604) (xy 58.141616 -436.950104)
			(xy 58.139946 -436.935111) (xy 58.138168 -436.904992) (xy 58.13806 -436.889906) (xy 58.138168 -436.87482)
			(xy 58.13995 -436.844702) (xy 58.141616 -436.829708) (xy 58.141616 -436.219092) (xy 58.142006 -436.207006)
			(xy 58.149479 -436.184019) (xy 58.16369 -436.164467) (xy 58.183248 -436.150264) (xy 58.206238 -436.142801)
			(xy 58.218324 -436.142384) (xy 59.158124 -436.142384) (xy 59.170199 -436.142844) (xy 59.193166 -436.150312)
			(xy 59.212701 -436.16451) (xy 59.226895 -436.184049) (xy 59.234359 -436.207017) (xy 59.234832 -436.219092)
			(xy 59.234832 -438.760616) (xy 59.23435 -438.772689) (xy 59.226886 -438.795653) (xy 59.212693 -438.815187)
			(xy 59.19316 -438.829382) (xy 59.170197 -438.836848) (xy 59.158124 -438.837324) (xy 58.218324 -438.837324)
			(xy 58.206244 -438.836867) (xy 58.183265 -438.829408) (xy 58.163716 -438.815213) (xy 58.14951 -438.795671)
			(xy 58.142039 -438.772696) (xy 58.141616 -438.760616) (xy 58.141616 -438.15) (xy 58.139945 -438.135007)
			(xy 58.138168 -438.104888) (xy 58.13806 -438.089802) (xy 7.00913 -438.089802) (xy 7.00913 -439.0898)
			(xy 60.138056 -439.0898) (xy 60.138173 -439.074715) (xy 60.139949 -439.044596) (xy 60.141612 -439.029602)
			(xy 60.141612 -437.950102) (xy 60.139941 -437.935109) (xy 60.138164 -437.90499) (xy 60.138056 -437.889904)
			(xy 60.138173 -437.874819) (xy 60.139949 -437.8447) (xy 60.141612 -437.829706) (xy 60.141612 -437.21909)
			(xy 60.142099 -437.207003) (xy 60.149555 -437.184007) (xy 60.163737 -437.164429) (xy 60.183265 -437.150178)
			(xy 60.206234 -437.142641) (xy 60.21832 -437.142128) (xy 61.15812 -437.142128) (xy 61.170233 -437.1425)
			(xy 61.193265 -437.150008) (xy 61.212841 -437.16428) (xy 61.227034 -437.183913) (xy 61.234449 -437.206976)
			(xy 61.234828 -437.21909) (xy 61.234828 -438.089802) (xy 62.138052 -438.089802) (xy 62.138169 -438.074717)
			(xy 62.139945 -438.044598) (xy 62.141608 -438.029604) (xy 62.141608 -436.950104) (xy 62.139938 -436.935111)
			(xy 62.13816 -436.904992) (xy 62.138052 -436.889906) (xy 62.13816 -436.87482) (xy 62.139942 -436.844702)
			(xy 62.141608 -436.829708) (xy 62.141608 -436.219092) (xy 62.142006 -436.207007) (xy 62.149478 -436.184021)
			(xy 62.163687 -436.16447) (xy 62.183243 -436.150267) (xy 62.206231 -436.142802) (xy 62.218316 -436.142384)
			(xy 63.158116 -436.142384) (xy 63.170191 -436.142851) (xy 63.193157 -436.150317) (xy 63.212693 -436.164513)
			(xy 63.226887 -436.18405) (xy 63.234351 -436.207017) (xy 63.234824 -436.219092) (xy 63.234824 -438.760616)
			(xy 63.23435 -438.77269) (xy 63.226885 -438.795655) (xy 63.21269 -438.81519) (xy 63.193155 -438.829385)
			(xy 63.17019 -438.83685) (xy 63.158116 -438.837324) (xy 62.218316 -438.837324) (xy 62.206244 -438.836822)
			(xy 62.18328 -438.829366) (xy 62.163744 -438.815179) (xy 62.149548 -438.795649) (xy 62.142083 -438.772688)
			(xy 62.141608 -438.760616) (xy 62.141608 -438.15) (xy 62.139937 -438.135007) (xy 62.13816 -438.104888)
			(xy 62.138052 -438.089802) (xy 61.234828 -438.089802) (xy 61.234828 -439.0898) (xy 64.138048 -439.0898)
			(xy 64.138165 -439.074715) (xy 64.139941 -439.044596) (xy 64.141604 -439.029602) (xy 64.141604 -437.950102)
			(xy 64.139933 -437.935109) (xy 64.138156 -437.90499) (xy 64.138048 -437.889904) (xy 64.138165 -437.874819)
			(xy 64.139941 -437.8447) (xy 64.141604 -437.829706) (xy 64.141604 -437.21909) (xy 64.142098 -437.207004)
			(xy 64.149553 -437.184009) (xy 64.163734 -437.164432) (xy 64.18326 -437.150181) (xy 64.206227 -437.142643)
			(xy 64.218312 -437.142128) (xy 65.158112 -437.142128) (xy 65.170224 -437.142506) (xy 65.193257 -437.150012)
			(xy 65.212832 -437.164283) (xy 65.227025 -437.183914) (xy 65.234441 -437.206976) (xy 65.23482 -437.21909)
			(xy 65.23482 -438.089802) (xy 66.138044 -438.089802) (xy 66.138161 -438.074717) (xy 66.139937 -438.044598)
			(xy 66.1416 -438.029604) (xy 66.1416 -436.950104) (xy 66.13993 -436.935111) (xy 66.138152 -436.904992)
			(xy 66.138044 -436.889906) (xy 66.138152 -436.87482) (xy 66.139934 -436.844702) (xy 66.1416 -436.829708)
			(xy 66.1416 -436.219092) (xy 66.142058 -436.207016) (xy 66.149523 -436.184047) (xy 66.163721 -436.16451)
			(xy 66.183262 -436.150316) (xy 66.206232 -436.142855) (xy 66.218308 -436.142384) (xy 67.158108 -436.142384)
			(xy 67.170182 -436.142857) (xy 67.193148 -436.150321) (xy 67.212684 -436.164516) (xy 67.226879 -436.184052)
			(xy 67.234343 -436.207018) (xy 67.234816 -436.219092) (xy 67.234816 -438.760616) (xy 67.234349 -438.772691)
			(xy 67.226883 -438.795657) (xy 67.212687 -438.815193) (xy 67.19315 -438.829387) (xy 67.170183 -438.836851)
			(xy 67.158108 -438.837324) (xy 66.218308 -438.837324) (xy 66.206235 -438.836829) (xy 66.183271 -438.829371)
			(xy 66.163735 -438.815182) (xy 66.14954 -438.79565) (xy 66.142075 -438.772688) (xy 66.1416 -438.760616)
			(xy 66.1416 -438.15) (xy 66.139929 -438.135007) (xy 66.138152 -438.104888) (xy 66.138044 -438.089802)
			(xy 65.23482 -438.089802) (xy 65.23482 -439.0898) (xy 68.13804 -439.0898) (xy 68.138157 -439.074715)
			(xy 68.139933 -439.044596) (xy 68.141596 -439.029602) (xy 68.141596 -437.950102) (xy 68.139925 -437.935109)
			(xy 68.138148 -437.90499) (xy 68.13804 -437.889904) (xy 68.138157 -437.874819) (xy 68.139933 -437.8447)
			(xy 68.141596 -437.829706) (xy 68.141596 -437.21909) (xy 68.142098 -437.207004) (xy 68.149552 -437.184011)
			(xy 68.163731 -437.164435) (xy 68.183255 -437.150183) (xy 68.20622 -437.142644) (xy 68.218304 -437.142128)
			(xy 69.158104 -437.142128) (xy 69.170216 -437.142513) (xy 69.193248 -437.150017) (xy 69.212824 -437.164286)
			(xy 69.227017 -437.183916) (xy 69.234433 -437.206977) (xy 69.234812 -437.21909) (xy 69.234812 -438.089802)
			(xy 70.138036 -438.089802) (xy 70.138153 -438.074717) (xy 70.139929 -438.044598) (xy 70.141592 -438.029604)
			(xy 70.141592 -436.950104) (xy 70.139922 -436.935111) (xy 70.138144 -436.904992) (xy 70.138036 -436.889906)
			(xy 70.138146 -436.87482) (xy 70.139928 -436.844702) (xy 70.141592 -436.829708) (xy 70.141592 -436.219092)
			(xy 70.142058 -436.207017) (xy 70.149522 -436.18405) (xy 70.163718 -436.164513) (xy 70.183257 -436.150319)
			(xy 70.206225 -436.142856) (xy 70.2183 -436.142384) (xy 71.1581 -436.142384) (xy 71.170174 -436.142864)
			(xy 71.19314 -436.150326) (xy 71.212676 -436.164518) (xy 71.226871 -436.184053) (xy 71.234335 -436.207018)
			(xy 71.234808 -436.219092) (xy 71.234808 -438.760616) (xy 71.234349 -438.772691) (xy 71.226882 -438.795659)
			(xy 71.212684 -438.815196) (xy 71.193145 -438.82939) (xy 71.170175 -438.836852) (xy 71.1581 -438.837324)
			(xy 70.2183 -438.837324) (xy 70.206227 -438.836836) (xy 70.183263 -438.829375) (xy 70.163727 -438.815184)
			(xy 70.149532 -438.795652) (xy 70.142067 -438.772689) (xy 70.141592 -438.760616) (xy 70.141592 -438.15)
			(xy 70.139921 -438.135007) (xy 70.138144 -438.104888) (xy 70.138036 -438.089802) (xy 69.234812 -438.089802)
			(xy 69.234812 -439.0898) (xy 72.138032 -439.0898) (xy 72.138151 -439.074715) (xy 72.139927 -439.044596)
			(xy 72.141588 -439.029602) (xy 72.141588 -437.950102) (xy 72.139917 -437.935109) (xy 72.13814 -437.90499)
			(xy 72.138032 -437.889904) (xy 72.138151 -437.874819) (xy 72.139927 -437.8447) (xy 72.141588 -437.829706)
			(xy 72.141588 -437.21909) (xy 72.142 -437.206995) (xy 72.149465 -437.183986) (xy 72.163664 -437.164402)
			(xy 72.183212 -437.150154) (xy 72.206202 -437.142631) (xy 72.218296 -437.142128) (xy 73.158096 -437.142128)
			(xy 73.170207 -437.14252) (xy 73.193239 -437.150022) (xy 73.212815 -437.164288) (xy 73.227009 -437.183917)
			(xy 73.234425 -437.206977) (xy 73.234804 -437.21909) (xy 73.234804 -438.089802) (xy 75.138026 -438.089802)
			(xy 75.138119 -438.075228) (xy 75.139772 -438.046127) (xy 75.141328 -438.031636) (xy 75.141328 -436.948072)
			(xy 75.139784 -436.93358) (xy 75.138131 -436.90448) (xy 75.138026 -436.889906) (xy 75.138119 -436.875332)
			(xy 75.139772 -436.846231) (xy 75.141328 -436.83174) (xy 75.141328 -436.219092) (xy 75.14171 -436.20698)
			(xy 75.149215 -436.183948) (xy 75.163484 -436.164372) (xy 75.183115 -436.150179) (xy 75.206176 -436.142763)
			(xy 75.21829 -436.142384) (xy 76.15809 -436.142384) (xy 76.170183 -436.142817) (xy 76.193191 -436.150276)
			(xy 76.212775 -436.16447) (xy 76.227024 -436.184014) (xy 76.234549 -436.207) (xy 76.235052 -436.219092)
			(xy 76.235052 -438.760616) (xy 76.234598 -438.772721) (xy 76.227101 -438.795739) (xy 76.212847 -438.815308)
			(xy 76.193237 -438.829504) (xy 76.170196 -438.836933) (xy 76.15809 -438.837324) (xy 75.21829 -438.837324)
			(xy 75.206196 -438.8369) (xy 75.183189 -438.829436) (xy 75.163607 -438.81524) (xy 75.149358 -438.795695)
			(xy 75.141832 -438.772708) (xy 75.141328 -438.760616) (xy 75.141328 -438.147968) (xy 75.139783 -438.133476)
			(xy 75.138131 -438.104376) (xy 75.138026 -438.089802) (xy 73.234804 -438.089802) (xy 73.234804 -439.0898)
			(xy 77.138022 -439.0898) (xy 77.138115 -439.075226) (xy 77.139768 -439.046125) (xy 77.141324 -439.031634)
			(xy 77.141324 -437.94807) (xy 77.139779 -437.933578) (xy 77.138127 -437.904478) (xy 77.138022 -437.889904)
			(xy 77.138115 -437.87533) (xy 77.139768 -437.846229) (xy 77.141324 -437.831738) (xy 77.141324 -437.21909)
			(xy 77.141803 -437.206976) (xy 77.149291 -437.183935) (xy 77.163532 -437.164335) (xy 77.183132 -437.150093)
			(xy 77.206172 -437.142604) (xy 77.218286 -437.142128) (xy 78.158086 -437.142128) (xy 78.170207 -437.142572)
			(xy 78.193264 -437.150059) (xy 78.212878 -437.164305) (xy 78.22713 -437.183915) (xy 78.234624 -437.206969)
			(xy 78.235048 -437.21909) (xy 78.235048 -438.089802) (xy 79.138018 -438.089802) (xy 79.138111 -438.075228)
			(xy 79.139764 -438.046127) (xy 79.14132 -438.031636) (xy 79.14132 -436.948072) (xy 79.139776 -436.93358)
			(xy 79.138123 -436.90448) (xy 79.138018 -436.889906) (xy 79.138111 -436.875332) (xy 79.139764 -436.846231)
			(xy 79.14132 -436.83174) (xy 79.14132 -436.219092) (xy 79.14171 -436.206981) (xy 79.149214 -436.18395)
			(xy 79.163481 -436.164375) (xy 79.18311 -436.150181) (xy 79.206169 -436.142764) (xy 79.218282 -436.142384)
			(xy 80.158082 -436.142384) (xy 80.170175 -436.142824) (xy 80.193182 -436.150281) (xy 80.212766 -436.164473)
			(xy 80.227016 -436.184015) (xy 80.234541 -436.207) (xy 80.235044 -436.219092) (xy 80.235044 -438.760616)
			(xy 80.234598 -438.772721) (xy 80.227099 -438.795742) (xy 80.212844 -438.815311) (xy 80.193232 -438.829506)
			(xy 80.170189 -438.836935) (xy 80.158082 -438.837324) (xy 79.218282 -438.837324) (xy 79.206188 -438.836907)
			(xy 79.183181 -438.829441) (xy 79.163598 -438.815243) (xy 79.149349 -438.795697) (xy 79.141824 -438.772709)
			(xy 79.14132 -438.760616) (xy 79.14132 -438.147968) (xy 79.139775 -438.133476) (xy 79.138123 -438.104376)
			(xy 79.138018 -438.089802) (xy 78.235048 -438.089802) (xy 78.235048 -439.0898) (xy 81.138014 -439.0898)
			(xy 81.138106 -439.075226) (xy 81.13976 -439.046125) (xy 81.141316 -439.031634) (xy 81.141316 -437.94807)
			(xy 81.139771 -437.933578) (xy 81.138119 -437.904478) (xy 81.138014 -437.889904) (xy 81.138107 -437.87533)
			(xy 81.13976 -437.846229) (xy 81.141316 -437.831738) (xy 81.141316 -437.21909) (xy 81.141803 -437.206977)
			(xy 81.14929 -437.183937) (xy 81.163529 -437.164338) (xy 81.183127 -437.150096) (xy 81.206165 -437.142605)
			(xy 81.218278 -437.142128) (xy 82.158078 -437.142128) (xy 82.170199 -437.142579) (xy 82.193255 -437.150064)
			(xy 82.21287 -437.164308) (xy 82.227122 -437.183916) (xy 82.234616 -437.20697) (xy 82.23504 -437.21909)
			(xy 82.23504 -438.089802) (xy 83.13801 -438.089802) (xy 83.138103 -438.075228) (xy 83.139756 -438.046127)
			(xy 83.141312 -438.031636) (xy 83.141312 -436.948072) (xy 83.139767 -436.93358) (xy 83.138115 -436.90448)
			(xy 83.13801 -436.889906) (xy 83.138103 -436.875332) (xy 83.139756 -436.846231) (xy 83.141312 -436.83174)
			(xy 83.141312 -436.219092) (xy 83.14171 -436.206981) (xy 83.149213 -436.183952) (xy 83.163479 -436.164378)
			(xy 83.183105 -436.150184) (xy 83.206162 -436.142765) (xy 83.218274 -436.142384) (xy 84.158074 -436.142384)
			(xy 84.170167 -436.14283) (xy 84.193174 -436.150285) (xy 84.212758 -436.164476) (xy 84.227008 -436.184017)
			(xy 84.234533 -436.207001) (xy 84.235036 -436.219092) (xy 84.235036 -438.760616) (xy 84.234598 -438.772722)
			(xy 84.227098 -438.795744) (xy 84.212841 -438.815313) (xy 84.193227 -438.829509) (xy 84.170181 -438.836936)
			(xy 84.158074 -438.837324) (xy 83.218274 -438.837324) (xy 83.206179 -438.836914) (xy 83.183172 -438.829446)
			(xy 83.163589 -438.815246) (xy 83.149341 -438.795698) (xy 83.141816 -438.772709) (xy 83.141312 -438.760616)
			(xy 83.141312 -438.147968) (xy 83.139767 -438.133476) (xy 83.138115 -438.104376) (xy 83.13801 -438.089802)
			(xy 82.23504 -438.089802) (xy 82.23504 -439.0898) (xy 85.138006 -439.0898) (xy 85.138098 -439.075226)
			(xy 85.139752 -439.046125) (xy 85.141308 -439.031634) (xy 85.141308 -437.94807) (xy 85.139763 -437.933578)
			(xy 85.138111 -437.904478) (xy 85.138006 -437.889904) (xy 85.138099 -437.87533) (xy 85.139752 -437.846229)
			(xy 85.141308 -437.831738) (xy 85.141308 -437.21909) (xy 85.141803 -437.206978) (xy 85.149289 -437.18394)
			(xy 85.163526 -437.164341) (xy 85.183122 -437.150098) (xy 85.206158 -437.142606) (xy 85.21827 -437.142128)
			(xy 86.15807 -437.142128) (xy 86.17019 -437.142585) (xy 86.193246 -437.150068) (xy 86.212861 -437.16431)
			(xy 86.227114 -437.183918) (xy 86.234608 -437.20697) (xy 86.235032 -437.21909) (xy 86.235032 -438.089802)
			(xy 87.138002 -438.089802) (xy 87.138095 -438.075228) (xy 87.139748 -438.046127) (xy 87.141304 -438.031636)
			(xy 87.141304 -436.948072) (xy 87.139759 -436.93358) (xy 87.138107 -436.90448) (xy 87.138002 -436.889906)
			(xy 87.138095 -436.875332) (xy 87.139748 -436.846231) (xy 87.141304 -436.83174) (xy 87.141304 -436.219092)
			(xy 87.141709 -436.206982) (xy 87.149212 -436.183954) (xy 87.163476 -436.164381) (xy 87.1831 -436.150186)
			(xy 87.206155 -436.142767) (xy 87.218266 -436.142384) (xy 88.158066 -436.142384) (xy 88.170158 -436.142837)
			(xy 88.193165 -436.15029) (xy 88.212749 -436.164478) (xy 88.227 -436.184018) (xy 88.234525 -436.207001)
			(xy 88.235028 -436.219092) (xy 88.235028 -438.760616) (xy 88.234598 -438.772723) (xy 88.227097 -438.795746)
			(xy 88.212838 -438.815316) (xy 88.193222 -438.829511) (xy 88.170174 -438.836937) (xy 88.158066 -438.837324)
			(xy 87.218266 -438.837324) (xy 87.206171 -438.836921) (xy 87.183163 -438.829451) (xy 87.163581 -438.815249)
			(xy 87.149333 -438.7957) (xy 87.141808 -438.77271) (xy 87.141304 -438.760616) (xy 87.141304 -438.147968)
			(xy 87.139759 -438.133476) (xy 87.138107 -438.104376) (xy 87.138002 -438.089802) (xy 86.235032 -438.089802)
			(xy 86.235032 -439.0898) (xy 89.137998 -439.0898) (xy 89.13809 -439.075226) (xy 89.139744 -439.046125)
			(xy 89.1413 -439.031634) (xy 89.1413 -437.94807) (xy 89.139755 -437.933578) (xy 89.138103 -437.904478)
			(xy 89.137998 -437.889904) (xy 89.138091 -437.87533) (xy 89.139744 -437.846229) (xy 89.1413 -437.831738)
			(xy 89.1413 -437.21909) (xy 89.141803 -437.206979) (xy 89.149288 -437.183942) (xy 89.163524 -437.164343)
			(xy 89.183117 -437.150101) (xy 89.206151 -437.142607) (xy 89.218262 -437.142128) (xy 90.158062 -437.142128)
			(xy 90.170182 -437.142592) (xy 90.193238 -437.150073) (xy 90.212853 -437.164313) (xy 90.227105 -437.183919)
			(xy 90.2346 -437.20697) (xy 90.235024 -437.21909) (xy 90.235024 -439.0898) (xy 127.237998 -439.0898)
			(xy 127.23809 -439.075226) (xy 127.239744 -439.046125) (xy 127.2413 -439.031634) (xy 127.2413 -437.94807)
			(xy 127.239755 -437.933578) (xy 127.238103 -437.904478) (xy 127.237998 -437.889904) (xy 127.238091 -437.87533)
			(xy 127.239744 -437.846229) (xy 127.2413 -437.831738) (xy 127.2413 -437.21909) (xy 127.241803 -437.206979)
			(xy 127.249288 -437.183942) (xy 127.263524 -437.164343) (xy 127.283117 -437.150101) (xy 127.306151 -437.142607)
			(xy 127.318262 -437.142128) (xy 128.258062 -437.142128) (xy 128.270182 -437.142592) (xy 128.293238 -437.150073)
			(xy 128.312853 -437.164313) (xy 128.327105 -437.183919) (xy 128.3346 -437.20697) (xy 128.335024 -437.21909)
			(xy 128.335024 -438.089802) (xy 129.237994 -438.089802) (xy 129.238087 -438.075228) (xy 129.23974 -438.046127)
			(xy 129.241296 -438.031636) (xy 129.241296 -436.948072) (xy 129.239752 -436.93358) (xy 129.238099 -436.90448)
			(xy 129.237994 -436.889906) (xy 129.238087 -436.875332) (xy 129.23974 -436.846231) (xy 129.241296 -436.83174)
			(xy 129.241296 -436.219092) (xy 129.241709 -436.206983) (xy 129.24921 -436.183956) (xy 129.263473 -436.164384)
			(xy 129.283095 -436.150189) (xy 129.306148 -436.142768) (xy 129.318258 -436.142384) (xy 130.258058 -436.142384)
			(xy 130.27015 -436.142844) (xy 130.293156 -436.150294) (xy 130.312741 -436.164481) (xy 130.326991 -436.184019)
			(xy 130.334516 -436.207002) (xy 130.33502 -436.219092) (xy 130.33502 -438.760616) (xy 130.334598 -438.772724)
			(xy 130.327096 -438.795748) (xy 130.312836 -438.815319) (xy 130.293217 -438.829514) (xy 130.270167 -438.836938)
			(xy 130.258058 -438.837324) (xy 129.318258 -438.837324) (xy 129.306163 -438.836928) (xy 129.283155 -438.829455)
			(xy 129.263572 -438.815252) (xy 129.249324 -438.795701) (xy 129.2418 -438.77271) (xy 129.241296 -438.760616)
			(xy 129.241296 -438.147968) (xy 129.239751 -438.133476) (xy 129.238099 -438.104376) (xy 129.237994 -438.089802)
			(xy 128.335024 -438.089802) (xy 128.335024 -439.0898) (xy 131.23799 -439.0898) (xy 131.238082 -439.075226)
			(xy 131.239736 -439.046125) (xy 131.241292 -439.031634) (xy 131.241292 -437.94807) (xy 131.239748 -437.933578)
			(xy 131.238095 -437.904478) (xy 131.23799 -437.889904) (xy 131.238083 -437.87533) (xy 131.239736 -437.846229)
			(xy 131.241292 -437.831738) (xy 131.241292 -437.21909) (xy 131.241803 -437.20698) (xy 131.249287 -437.183944)
			(xy 131.263521 -437.164346) (xy 131.283112 -437.150104) (xy 131.306144 -437.142608) (xy 131.318254 -437.142128)
			(xy 132.258054 -437.142128) (xy 132.270173 -437.142599) (xy 132.293229 -437.150077) (xy 132.312844 -437.164316)
			(xy 132.327097 -437.183921) (xy 132.334592 -437.206971) (xy 132.335016 -437.21909) (xy 132.335016 -438.089802)
			(xy 133.237986 -438.089802) (xy 133.238079 -438.075228) (xy 133.239732 -438.046127) (xy 133.241288 -438.031636)
			(xy 133.241288 -436.948072) (xy 133.239744 -436.93358) (xy 133.238091 -436.90448) (xy 133.237986 -436.889906)
			(xy 133.238079 -436.875332) (xy 133.239732 -436.846231) (xy 133.241288 -436.83174) (xy 133.241288 -436.219092)
			(xy 133.241709 -436.206984) (xy 133.249209 -436.183958) (xy 133.26347 -436.164386) (xy 133.28309 -436.150192)
			(xy 133.306141 -436.142769) (xy 133.31825 -436.142384) (xy 134.25805 -436.142384) (xy 134.270141 -436.142851)
			(xy 134.293148 -436.150299) (xy 134.312732 -436.164484) (xy 134.326983 -436.184021) (xy 134.334508 -436.207002)
			(xy 134.335012 -436.219092) (xy 134.335012 -438.760616) (xy 134.334598 -438.772725) (xy 134.327095 -438.79575)
			(xy 134.312833 -438.815322) (xy 134.293212 -438.829517) (xy 134.27016 -438.836939) (xy 134.25805 -438.837324)
			(xy 133.31825 -438.837324) (xy 133.306159 -438.836849) (xy 133.283154 -438.829402) (xy 133.26357 -438.815219)
			(xy 133.249319 -438.795684) (xy 133.241793 -438.772705) (xy 133.241288 -438.760616) (xy 133.241288 -438.147968)
			(xy 133.239743 -438.133476) (xy 133.238091 -438.104376) (xy 133.237986 -438.089802) (xy 132.335016 -438.089802)
			(xy 132.335016 -439.0898) (xy 135.237982 -439.0898) (xy 135.238075 -439.075226) (xy 135.239728 -439.046125)
			(xy 135.241284 -439.031634) (xy 135.241284 -437.94807) (xy 135.23974 -437.933578) (xy 135.238087 -437.904478)
			(xy 135.237982 -437.889904) (xy 135.238075 -437.87533) (xy 135.239728 -437.846229) (xy 135.241284 -437.831738)
			(xy 135.241284 -437.21909) (xy 135.241652 -437.206962) (xy 135.249153 -437.183895) (xy 135.263416 -437.164276)
			(xy 135.283045 -437.150027) (xy 135.306118 -437.142544) (xy 135.318246 -437.142128) (xy 136.258046 -437.142128)
			(xy 136.270162 -437.142572) (xy 136.293205 -437.150071) (xy 136.312805 -437.164321) (xy 136.327045 -437.183927)
			(xy 136.334533 -437.206974) (xy 136.335008 -437.21909) (xy 136.335008 -438.089802) (xy 137.237978 -438.089802)
			(xy 137.238071 -438.075228) (xy 137.239724 -438.046127) (xy 137.24128 -438.031636) (xy 137.24128 -436.948072)
			(xy 137.239736 -436.93358) (xy 137.238083 -436.90448) (xy 137.237978 -436.889906) (xy 137.238071 -436.875332)
			(xy 137.239724 -436.846231) (xy 137.24128 -436.83174) (xy 137.24128 -436.219092) (xy 137.241709 -436.206985)
			(xy 137.249208 -436.183961) (xy 137.263467 -436.164389) (xy 137.283085 -436.150194) (xy 137.306133 -436.14277)
			(xy 137.318242 -436.142384) (xy 138.258042 -436.142384) (xy 138.270138 -436.142772) (xy 138.293148 -436.150246)
			(xy 138.312731 -436.164451) (xy 138.326978 -436.184004) (xy 138.334501 -436.206997) (xy 138.335004 -436.219092)
			(xy 138.335004 -438.760616) (xy 138.334597 -438.772725) (xy 138.327094 -438.795752) (xy 138.31283 -438.815325)
			(xy 138.293207 -438.829519) (xy 138.270153 -438.83694) (xy 138.258042 -438.837324) (xy 137.318242 -438.837324)
			(xy 137.306151 -438.836856) (xy 137.283146 -438.829407) (xy 137.263562 -438.815222) (xy 137.249311 -438.795686)
			(xy 137.241785 -438.772705) (xy 137.24128 -438.760616) (xy 137.24128 -438.147968) (xy 137.239735 -438.133476)
			(xy 137.238083 -438.104376) (xy 137.237978 -438.089802) (xy 136.335008 -438.089802) (xy 136.335008 -439.0898)
			(xy 139.237974 -439.0898) (xy 139.238067 -439.075226) (xy 139.23972 -439.046125) (xy 139.241276 -439.031634)
			(xy 139.241276 -437.94807) (xy 139.239732 -437.933578) (xy 139.238079 -437.904478) (xy 139.237974 -437.889904)
			(xy 139.238067 -437.87533) (xy 139.23972 -437.846229) (xy 139.241276 -437.831738) (xy 139.241276 -437.21909)
			(xy 139.241652 -437.206963) (xy 139.249152 -437.183897) (xy 139.263413 -437.164279) (xy 139.28304 -437.15003)
			(xy 139.306111 -437.142545) (xy 139.318238 -437.142128) (xy 140.258038 -437.142128) (xy 140.270154 -437.142579)
			(xy 140.293196 -437.150076) (xy 140.312797 -437.164323) (xy 140.327037 -437.183929) (xy 140.334525 -437.206974)
			(xy 140.335 -437.21909) (xy 140.335 -438.089802) (xy 142.237968 -438.089802) (xy 142.238085 -438.074717)
			(xy 142.239861 -438.044598) (xy 142.241524 -438.029604) (xy 142.241524 -436.950104) (xy 142.239854 -436.935111)
			(xy 142.238076 -436.904992) (xy 142.237968 -436.889906) (xy 142.238076 -436.87482) (xy 142.239858 -436.844702)
			(xy 142.241524 -436.829708) (xy 142.241524 -436.219092) (xy 142.241906 -436.207006) (xy 142.24938 -436.184017)
			(xy 142.263593 -436.164464) (xy 142.283153 -436.150262) (xy 142.306145 -436.1428) (xy 142.318232 -436.142384)
			(xy 143.258032 -436.142384) (xy 143.270107 -436.142837) (xy 143.293074 -436.150307) (xy 143.31261 -436.164507)
			(xy 143.326804 -436.184047) (xy 143.334267 -436.207016) (xy 143.33474 -436.219092) (xy 143.33474 -438.760616)
			(xy 143.33425 -438.772688) (xy 143.326787 -438.79565) (xy 143.312596 -438.815184) (xy 143.293065 -438.829379)
			(xy 143.270104 -438.836847) (xy 143.258032 -438.837324) (xy 142.318232 -438.837324) (xy 142.306153 -438.83686)
			(xy 142.283174 -438.829403) (xy 142.263624 -438.81521) (xy 142.249418 -438.795669) (xy 142.241947 -438.772695)
			(xy 142.241524 -438.760616) (xy 142.241524 -438.15) (xy 142.239853 -438.135007) (xy 142.238076 -438.104888)
			(xy 142.237968 -438.089802) (xy 140.335 -438.089802) (xy 140.335 -439.0898) (xy 144.237964 -439.0898)
			(xy 144.23808 -439.074715) (xy 144.239857 -439.044596) (xy 144.24152 -439.029602) (xy 144.24152 -437.950102)
			(xy 144.239849 -437.935109) (xy 144.238072 -437.90499) (xy 144.237964 -437.889904) (xy 144.238081 -437.874819)
			(xy 144.239857 -437.8447) (xy 144.24152 -437.829706) (xy 144.24152 -437.21909) (xy 144.241999 -437.207002)
			(xy 144.249456 -437.184004) (xy 144.26364 -437.164426) (xy 144.28317 -437.150176) (xy 144.306142 -437.14264)
			(xy 144.318228 -437.142128) (xy 145.258028 -437.142128) (xy 145.270141 -437.142493) (xy 145.293174 -437.150003)
			(xy 145.312749 -437.164277) (xy 145.326942 -437.183911) (xy 145.334357 -437.206975) (xy 145.334736 -437.21909)
			(xy 145.334736 -438.089802) (xy 146.23796 -438.089802) (xy 146.238077 -438.074717) (xy 146.239853 -438.044598)
			(xy 146.241516 -438.029604) (xy 146.241516 -436.950104) (xy 146.239846 -436.935111) (xy 146.238068 -436.904992)
			(xy 146.23796 -436.889906) (xy 146.238068 -436.87482) (xy 146.23985 -436.844702) (xy 146.241516 -436.829708)
			(xy 146.241516 -436.219092) (xy 146.241906 -436.207006) (xy 146.249379 -436.184019) (xy 146.26359 -436.164467)
			(xy 146.283148 -436.150264) (xy 146.306138 -436.142801) (xy 146.318224 -436.142384) (xy 147.258024 -436.142384)
			(xy 147.270099 -436.142844) (xy 147.293066 -436.150312) (xy 147.312601 -436.16451) (xy 147.326795 -436.184049)
			(xy 147.334259 -436.207017) (xy 147.334732 -436.219092) (xy 147.334732 -438.760616) (xy 147.33425 -438.772689)
			(xy 147.326786 -438.795653) (xy 147.312593 -438.815187) (xy 147.29306 -438.829382) (xy 147.270097 -438.836848)
			(xy 147.258024 -438.837324) (xy 146.318224 -438.837324) (xy 146.306144 -438.836867) (xy 146.283165 -438.829408)
			(xy 146.263616 -438.815213) (xy 146.24941 -438.795671) (xy 146.241939 -438.772696) (xy 146.241516 -438.760616)
			(xy 146.241516 -438.15) (xy 146.239845 -438.135007) (xy 146.238068 -438.104888) (xy 146.23796 -438.089802)
			(xy 145.334736 -438.089802) (xy 145.334736 -439.0898) (xy 148.237956 -439.0898) (xy 148.238073 -439.074715)
			(xy 148.239849 -439.044596) (xy 148.241512 -439.029602) (xy 148.241512 -437.950102) (xy 148.239841 -437.935109)
			(xy 148.238064 -437.90499) (xy 148.237956 -437.889904) (xy 148.238073 -437.874819) (xy 148.239849 -437.8447)
			(xy 148.241512 -437.829706) (xy 148.241512 -437.21909) (xy 148.241999 -437.207003) (xy 148.249455 -437.184007)
			(xy 148.263637 -437.164429) (xy 148.283165 -437.150178) (xy 148.306134 -437.142641) (xy 148.31822 -437.142128)
			(xy 149.25802 -437.142128) (xy 149.270133 -437.1425) (xy 149.293165 -437.150008) (xy 149.312741 -437.16428)
			(xy 149.326934 -437.183913) (xy 149.334349 -437.206976) (xy 149.334728 -437.21909) (xy 149.334728 -438.089802)
			(xy 150.237952 -438.089802) (xy 150.238069 -438.074717) (xy 150.239845 -438.044598) (xy 150.241508 -438.029604)
			(xy 150.241508 -436.950104) (xy 150.239838 -436.935111) (xy 150.23806 -436.904992) (xy 150.237952 -436.889906)
			(xy 150.23806 -436.87482) (xy 150.239842 -436.844702) (xy 150.241508 -436.829708) (xy 150.241508 -436.219092)
			(xy 150.241906 -436.207007) (xy 150.249378 -436.184021) (xy 150.263587 -436.16447) (xy 150.283143 -436.150267)
			(xy 150.306131 -436.142802) (xy 150.318216 -436.142384) (xy 151.258016 -436.142384) (xy 151.270091 -436.142851)
			(xy 151.293057 -436.150317) (xy 151.312593 -436.164513) (xy 151.326787 -436.18405) (xy 151.334251 -436.207017)
			(xy 151.334724 -436.219092) (xy 151.334724 -438.760616) (xy 151.33425 -438.77269) (xy 151.326785 -438.795655)
			(xy 151.31259 -438.81519) (xy 151.293055 -438.829385) (xy 151.27009 -438.83685) (xy 151.258016 -438.837324)
			(xy 150.318216 -438.837324) (xy 150.306144 -438.836822) (xy 150.28318 -438.829366) (xy 150.263644 -438.815179)
			(xy 150.249448 -438.795649) (xy 150.241983 -438.772688) (xy 150.241508 -438.760616) (xy 150.241508 -438.15)
			(xy 150.239837 -438.135007) (xy 150.23806 -438.104888) (xy 150.237952 -438.089802) (xy 149.334728 -438.089802)
			(xy 149.334728 -439.0898) (xy 152.237948 -439.0898) (xy 152.238065 -439.074715) (xy 152.239841 -439.044596)
			(xy 152.241504 -439.029602) (xy 152.241504 -437.950102) (xy 152.239833 -437.935109) (xy 152.238056 -437.90499)
			(xy 152.237948 -437.889904) (xy 152.238065 -437.874819) (xy 152.239841 -437.8447) (xy 152.241504 -437.829706)
			(xy 152.241504 -437.21909) (xy 152.241998 -437.207004) (xy 152.249453 -437.184009) (xy 152.263634 -437.164432)
			(xy 152.28316 -437.150181) (xy 152.306127 -437.142643) (xy 152.318212 -437.142128) (xy 153.258012 -437.142128)
			(xy 153.270124 -437.142506) (xy 153.293157 -437.150012) (xy 153.312732 -437.164283) (xy 153.326925 -437.183914)
			(xy 153.334341 -437.206976) (xy 153.33472 -437.21909) (xy 153.33472 -438.089802) (xy 154.237944 -438.089802)
			(xy 154.238061 -438.074717) (xy 154.239837 -438.044598) (xy 154.2415 -438.029604) (xy 154.2415 -436.950104)
			(xy 154.23983 -436.935111) (xy 154.238052 -436.904992) (xy 154.237944 -436.889906) (xy 154.238052 -436.87482)
			(xy 154.239834 -436.844702) (xy 154.2415 -436.829708) (xy 154.2415 -436.219092) (xy 154.241958 -436.207016)
			(xy 154.249423 -436.184047) (xy 154.263621 -436.16451) (xy 154.283162 -436.150316) (xy 154.306132 -436.142855)
			(xy 154.318208 -436.142384) (xy 155.258008 -436.142384) (xy 155.270082 -436.142857) (xy 155.293048 -436.150321)
			(xy 155.312584 -436.164516) (xy 155.326779 -436.184052) (xy 155.334243 -436.207018) (xy 155.334716 -436.219092)
			(xy 155.334716 -438.760616) (xy 155.334249 -438.772691) (xy 155.326783 -438.795657) (xy 155.312587 -438.815193)
			(xy 155.29305 -438.829387) (xy 155.270083 -438.836851) (xy 155.258008 -438.837324) (xy 154.318208 -438.837324)
			(xy 154.306135 -438.836829) (xy 154.283171 -438.829371) (xy 154.263635 -438.815182) (xy 154.24944 -438.79565)
			(xy 154.241975 -438.772688) (xy 154.2415 -438.760616) (xy 154.2415 -438.15) (xy 154.239829 -438.135007)
			(xy 154.238052 -438.104888) (xy 154.237944 -438.089802) (xy 153.33472 -438.089802) (xy 153.33472 -439.0898)
			(xy 156.23794 -439.0898) (xy 156.238057 -439.074715) (xy 156.239833 -439.044596) (xy 156.241496 -439.029602)
			(xy 156.241496 -437.950102) (xy 156.239825 -437.935109) (xy 156.238048 -437.90499) (xy 156.23794 -437.889904)
			(xy 156.238057 -437.874819) (xy 156.239833 -437.8447) (xy 156.241496 -437.829706) (xy 156.241496 -437.21909)
			(xy 156.241998 -437.207004) (xy 156.249452 -437.184011) (xy 156.263631 -437.164435) (xy 156.283155 -437.150183)
			(xy 156.30612 -437.142644) (xy 156.318204 -437.142128) (xy 157.258004 -437.142128) (xy 157.270116 -437.142513)
			(xy 157.293148 -437.150017) (xy 157.312724 -437.164286) (xy 157.326917 -437.183916) (xy 157.334333 -437.206977)
			(xy 157.334712 -437.21909) (xy 157.334712 -438.089802) (xy 314.138056 -438.089802) (xy 314.138173 -438.074717)
			(xy 314.139949 -438.044598) (xy 314.141612 -438.029604) (xy 314.141612 -436.950104) (xy 314.139942 -436.935111)
			(xy 314.138164 -436.904992) (xy 314.138056 -436.889906) (xy 314.138164 -436.87482) (xy 314.139946 -436.844702)
			(xy 314.141612 -436.829708) (xy 314.141612 -436.219092) (xy 314.142006 -436.207007) (xy 314.149478 -436.18402)
			(xy 314.163688 -436.164469) (xy 314.183246 -436.150265) (xy 314.206235 -436.142802) (xy 314.21832 -436.142384)
			(xy 315.15812 -436.142384) (xy 315.170195 -436.142847) (xy 315.193161 -436.150314) (xy 315.212697 -436.164511)
			(xy 315.226891 -436.18405) (xy 315.234355 -436.207017) (xy 315.234828 -436.219092) (xy 315.234828 -438.760616)
			(xy 315.23435 -438.772689) (xy 315.226885 -438.795654) (xy 315.212691 -438.815189) (xy 315.193157 -438.829383)
			(xy 315.170193 -438.836849) (xy 315.15812 -438.837324) (xy 314.21832 -438.837324) (xy 314.20624 -438.83687)
			(xy 314.183261 -438.82941) (xy 314.163711 -438.815214) (xy 314.149506 -438.795672) (xy 314.142035 -438.772696)
			(xy 314.141612 -438.760616) (xy 314.141612 -438.15) (xy 314.139941 -438.135007) (xy 314.138164 -438.104888)
			(xy 314.138056 -438.089802) (xy 157.334712 -438.089802) (xy 157.334712 -439.0898) (xy 316.138052 -439.0898)
			(xy 316.138169 -439.074715) (xy 316.139945 -439.044596) (xy 316.141608 -439.029602) (xy 316.141608 -437.950102)
			(xy 316.139937 -437.935109) (xy 316.13816 -437.90499) (xy 316.138052 -437.889904) (xy 316.138169 -437.874819)
			(xy 316.139945 -437.8447) (xy 316.141608 -437.829706) (xy 316.141608 -437.21909) (xy 316.142098 -437.207003)
			(xy 316.149554 -437.184008) (xy 316.163736 -437.164431) (xy 316.183262 -437.150179) (xy 316.206231 -437.142642)
			(xy 316.218316 -437.142128) (xy 317.158116 -437.142128) (xy 317.170229 -437.142503) (xy 317.193261 -437.15001)
			(xy 317.212836 -437.164281) (xy 317.227029 -437.183914) (xy 317.234445 -437.206976) (xy 317.234824 -437.21909)
			(xy 317.234824 -438.089802) (xy 318.138048 -438.089802) (xy 318.138165 -438.074717) (xy 318.139941 -438.044598)
			(xy 318.141604 -438.029604) (xy 318.141604 -436.950104) (xy 318.139934 -436.935111) (xy 318.138156 -436.904992)
			(xy 318.138048 -436.889906) (xy 318.138156 -436.87482) (xy 318.139938 -436.844702) (xy 318.141604 -436.829708)
			(xy 318.141604 -436.219092) (xy 318.142006 -436.207008) (xy 318.149477 -436.184023) (xy 318.163686 -436.164471)
			(xy 318.183241 -436.150268) (xy 318.206228 -436.142803) (xy 318.218312 -436.142384) (xy 319.158112 -436.142384)
			(xy 319.170186 -436.142854) (xy 319.193153 -436.150319) (xy 319.212689 -436.164514) (xy 319.226883 -436.184051)
			(xy 319.234347 -436.207018) (xy 319.23482 -436.219092) (xy 319.23482 -438.760616) (xy 319.234349 -438.77269)
			(xy 319.226884 -438.795656) (xy 319.212689 -438.815191) (xy 319.193152 -438.829386) (xy 319.170186 -438.83685)
			(xy 319.158112 -438.837324) (xy 318.218312 -438.837324) (xy 318.20624 -438.836826) (xy 318.183276 -438.829369)
			(xy 318.16374 -438.81518) (xy 318.149544 -438.79565) (xy 318.142079 -438.772688) (xy 318.141604 -438.760616)
			(xy 318.141604 -438.15) (xy 318.139933 -438.135007) (xy 318.138156 -438.104888) (xy 318.138048 -438.089802)
			(xy 317.234824 -438.089802) (xy 317.234824 -439.0898) (xy 320.138044 -439.0898) (xy 320.138161 -439.074715)
			(xy 320.139937 -439.044596) (xy 320.1416 -439.029602) (xy 320.1416 -437.950102) (xy 320.139929 -437.935109)
			(xy 320.138152 -437.90499) (xy 320.138044 -437.889904) (xy 320.138161 -437.874819) (xy 320.139937 -437.8447)
			(xy 320.1416 -437.829706) (xy 320.1416 -437.21909) (xy 320.142098 -437.207004) (xy 320.149553 -437.18401)
			(xy 320.163733 -437.164434) (xy 320.183257 -437.150182) (xy 320.206224 -437.142643) (xy 320.218308 -437.142128)
			(xy 321.158108 -437.142128) (xy 321.17022 -437.14251) (xy 321.193252 -437.150015) (xy 321.212828 -437.164284)
			(xy 321.227021 -437.183915) (xy 321.234437 -437.206976) (xy 321.234816 -437.21909) (xy 321.234816 -438.089802)
			(xy 322.13804 -438.089802) (xy 322.138157 -438.074717) (xy 322.139933 -438.044598) (xy 322.141596 -438.029604)
			(xy 322.141596 -436.950104) (xy 322.139926 -436.935111) (xy 322.138148 -436.904992) (xy 322.13804 -436.889906)
			(xy 322.13815 -436.87482) (xy 322.139932 -436.844702) (xy 322.141596 -436.829708) (xy 322.141596 -436.219092)
			(xy 322.142058 -436.207017) (xy 322.149523 -436.184049) (xy 322.16372 -436.164511) (xy 322.183259 -436.150317)
			(xy 322.206229 -436.142856) (xy 322.218304 -436.142384) (xy 323.158104 -436.142384) (xy 323.170178 -436.142861)
			(xy 323.193144 -436.150323) (xy 323.21268 -436.164517) (xy 323.226875 -436.184053) (xy 323.234339 -436.207018)
			(xy 323.234812 -436.219092) (xy 323.234812 -438.760616) (xy 323.234349 -438.772691) (xy 323.226883 -438.795658)
			(xy 323.212686 -438.815194) (xy 323.193147 -438.829388) (xy 323.170179 -438.836851) (xy 323.158104 -438.837324)
			(xy 322.218304 -438.837324) (xy 322.206231 -438.836833) (xy 322.183267 -438.829373) (xy 322.163731 -438.815183)
			(xy 322.149536 -438.795651) (xy 322.142071 -438.772689) (xy 322.141596 -438.760616) (xy 322.141596 -438.15)
			(xy 322.139925 -438.135007) (xy 322.138148 -438.104888) (xy 322.13804 -438.089802) (xy 321.234816 -438.089802)
			(xy 321.234816 -439.0898) (xy 324.138036 -439.0898) (xy 324.138153 -439.074715) (xy 324.139929 -439.044596)
			(xy 324.141592 -439.029602) (xy 324.141592 -437.950102) (xy 324.139921 -437.935109) (xy 324.138144 -437.90499)
			(xy 324.138036 -437.889904) (xy 324.138153 -437.874819) (xy 324.139929 -437.8447) (xy 324.141592 -437.829706)
			(xy 324.141592 -437.21909) (xy 324.142098 -437.207005) (xy 324.149552 -437.184012) (xy 324.16373 -437.164436)
			(xy 324.183252 -437.150184) (xy 324.206217 -437.142644) (xy 324.2183 -437.142128) (xy 325.1581 -437.142128)
			(xy 325.170212 -437.142516) (xy 325.193244 -437.150019) (xy 325.212819 -437.164287) (xy 325.227013 -437.183916)
			(xy 325.234429 -437.206977) (xy 325.234808 -437.21909) (xy 325.234808 -438.089802) (xy 326.138032 -438.089802)
			(xy 326.138151 -438.074717) (xy 326.139927 -438.044598) (xy 326.141588 -438.029604) (xy 326.141588 -436.950104)
			(xy 326.139917 -436.935111) (xy 326.13814 -436.904992) (xy 326.138032 -436.889906) (xy 326.138142 -436.87482)
			(xy 326.139924 -436.844702) (xy 326.141588 -436.829708) (xy 326.141588 -436.219092) (xy 326.142057 -436.207017)
			(xy 326.149522 -436.184051) (xy 326.163717 -436.164514) (xy 326.183254 -436.15032) (xy 326.206221 -436.142857)
			(xy 326.218296 -436.142384) (xy 327.158096 -436.142384) (xy 327.17017 -436.142868) (xy 327.193135 -436.150328)
			(xy 327.212672 -436.16452) (xy 327.226867 -436.184054) (xy 327.234331 -436.207019) (xy 327.234804 -436.219092)
			(xy 327.234804 -438.760616) (xy 327.234349 -438.772692) (xy 327.226882 -438.79566) (xy 327.212683 -438.815197)
			(xy 327.193142 -438.829391) (xy 327.170172 -438.836852) (xy 327.158096 -438.837324) (xy 326.218296 -438.837324)
			(xy 326.206223 -438.836839) (xy 326.183258 -438.829378) (xy 326.163723 -438.815186) (xy 326.149528 -438.795652)
			(xy 326.142063 -438.772689) (xy 326.141588 -438.760616) (xy 326.141588 -438.15) (xy 326.139917 -438.135007)
			(xy 326.13814 -438.104888) (xy 326.138032 -438.089802) (xy 325.234808 -438.089802) (xy 325.234808 -439.0898)
			(xy 328.138028 -439.0898) (xy 328.138147 -439.074715) (xy 328.139923 -439.044596) (xy 328.141584 -439.029602)
			(xy 328.141584 -437.950102) (xy 328.139913 -437.935109) (xy 328.138136 -437.90499) (xy 328.138028 -437.889904)
			(xy 328.138147 -437.874819) (xy 328.139923 -437.8447) (xy 328.141584 -437.829706) (xy 328.141584 -437.21909)
			(xy 328.142 -437.206996) (xy 328.149465 -437.183987) (xy 328.163663 -437.164404) (xy 328.18321 -437.150155)
			(xy 328.206199 -437.142631) (xy 328.218292 -437.142128) (xy 329.158092 -437.142128) (xy 329.170203 -437.142523)
			(xy 329.193235 -437.150024) (xy 329.212811 -437.16429) (xy 329.227005 -437.183918) (xy 329.234421 -437.206977)
			(xy 329.2348 -437.21909) (xy 329.2348 -438.089802) (xy 331.138022 -438.089802) (xy 331.138115 -438.075228)
			(xy 331.139768 -438.046127) (xy 331.141324 -438.031636) (xy 331.141324 -436.948072) (xy 331.13978 -436.93358)
			(xy 331.138127 -436.90448) (xy 331.138022 -436.889906) (xy 331.138115 -436.875332) (xy 331.139768 -436.846231)
			(xy 331.141324 -436.83174) (xy 331.141324 -436.219092) (xy 331.14171 -436.20698) (xy 331.149214 -436.183949)
			(xy 331.163483 -436.164374) (xy 331.183112 -436.15018) (xy 331.206173 -436.142764) (xy 331.218286 -436.142384)
			(xy 332.158086 -436.142384) (xy 332.170179 -436.14282) (xy 332.193187 -436.150278) (xy 332.212771 -436.164471)
			(xy 332.22702 -436.184014) (xy 332.234545 -436.207) (xy 332.235048 -436.219092) (xy 332.235048 -438.760616)
			(xy 332.234598 -438.772721) (xy 332.2271 -438.795741) (xy 332.212845 -438.815309) (xy 332.193234 -438.829505)
			(xy 332.170192 -438.836934) (xy 332.158086 -438.837324) (xy 331.218286 -438.837324) (xy 331.206192 -438.836904)
			(xy 331.183185 -438.829439) (xy 331.163602 -438.815242) (xy 331.149353 -438.795696) (xy 331.141828 -438.772709)
			(xy 331.141324 -438.760616) (xy 331.141324 -438.147968) (xy 331.139779 -438.133476) (xy 331.138127 -438.104376)
			(xy 331.138022 -438.089802) (xy 329.2348 -438.089802) (xy 329.2348 -439.0898) (xy 333.138018 -439.0898)
			(xy 333.138111 -439.075226) (xy 333.139764 -439.046125) (xy 333.14132 -439.031634) (xy 333.14132 -437.94807)
			(xy 333.139775 -437.933578) (xy 333.138123 -437.904478) (xy 333.138018 -437.889904) (xy 333.138111 -437.87533)
			(xy 333.139764 -437.846229) (xy 333.14132 -437.831738) (xy 333.14132 -437.21909) (xy 333.141803 -437.206977)
			(xy 333.149291 -437.183936) (xy 333.163531 -437.164336) (xy 333.183129 -437.150095) (xy 333.206169 -437.142604)
			(xy 333.218282 -437.142128) (xy 334.158082 -437.142128) (xy 334.170203 -437.142575) (xy 334.193259 -437.150061)
			(xy 334.212874 -437.164306) (xy 334.227126 -437.183916) (xy 334.23462 -437.206969) (xy 334.235044 -437.21909)
			(xy 334.235044 -438.089802) (xy 335.138014 -438.089802) (xy 335.138106 -438.075228) (xy 335.13976 -438.046127)
			(xy 335.141316 -438.031636) (xy 335.141316 -436.948072) (xy 335.139772 -436.93358) (xy 335.138119 -436.90448)
			(xy 335.138014 -436.889906) (xy 335.138107 -436.875332) (xy 335.13976 -436.846231) (xy 335.141316 -436.83174)
			(xy 335.141316 -436.219092) (xy 335.14171 -436.206981) (xy 335.149213 -436.183951) (xy 335.16348 -436.164376)
			(xy 335.183107 -436.150183) (xy 335.206166 -436.142765) (xy 335.218278 -436.142384) (xy 336.158078 -436.142384)
			(xy 336.170171 -436.142827) (xy 336.193178 -436.150283) (xy 336.212762 -436.164474) (xy 336.227012 -436.184016)
			(xy 336.234537 -436.207001) (xy 336.23504 -436.219092) (xy 336.23504 -438.760616) (xy 336.234598 -438.772722)
			(xy 336.227099 -438.795743) (xy 336.212843 -438.815312) (xy 336.193229 -438.829508) (xy 336.170185 -438.836935)
			(xy 336.158078 -438.837324) (xy 335.218278 -438.837324) (xy 335.206184 -438.836911) (xy 335.183176 -438.829444)
			(xy 335.163594 -438.815245) (xy 335.149345 -438.795698) (xy 335.14182 -438.772709) (xy 335.141316 -438.760616)
			(xy 335.141316 -438.147968) (xy 335.139771 -438.133476) (xy 335.138119 -438.104376) (xy 335.138014 -438.089802)
			(xy 334.235044 -438.089802) (xy 334.235044 -439.0898) (xy 337.13801 -439.0898) (xy 337.138102 -439.075226)
			(xy 337.139756 -439.046125) (xy 337.141312 -439.031634) (xy 337.141312 -437.94807) (xy 337.139767 -437.933578)
			(xy 337.138115 -437.904478) (xy 337.13801 -437.889904) (xy 337.138103 -437.87533) (xy 337.139756 -437.846229)
			(xy 337.141312 -437.831738) (xy 337.141312 -437.21909) (xy 337.141803 -437.206978) (xy 337.14929 -437.183938)
			(xy 337.163528 -437.164339) (xy 337.183124 -437.150097) (xy 337.206162 -437.142606) (xy 337.218274 -437.142128)
			(xy 338.158074 -437.142128) (xy 338.170194 -437.142582) (xy 338.193251 -437.150066) (xy 338.212865 -437.164309)
			(xy 338.227118 -437.183917) (xy 338.234612 -437.20697) (xy 338.235036 -437.21909) (xy 338.235036 -438.089802)
			(xy 339.138006 -438.089802) (xy 339.138099 -438.075228) (xy 339.139752 -438.046127) (xy 339.141308 -438.031636)
			(xy 339.141308 -436.948072) (xy 339.139763 -436.93358) (xy 339.138111 -436.90448) (xy 339.138006 -436.889906)
			(xy 339.138099 -436.875332) (xy 339.139752 -436.846231) (xy 339.141308 -436.83174) (xy 339.141308 -436.219092)
			(xy 339.141709 -436.206982) (xy 339.149212 -436.183953) (xy 339.163477 -436.164379) (xy 339.183102 -436.150185)
			(xy 339.206158 -436.142766) (xy 339.21827 -436.142384) (xy 340.15807 -436.142384) (xy 340.170162 -436.142834)
			(xy 340.193169 -436.150288) (xy 340.212754 -436.164477) (xy 340.227004 -436.184017) (xy 340.234529 -436.207001)
			(xy 340.235032 -436.219092) (xy 340.235032 -438.760616) (xy 340.234598 -438.772723) (xy 340.227098 -438.795745)
			(xy 340.21284 -438.815315) (xy 340.193224 -438.82951) (xy 340.170178 -438.836936) (xy 340.15807 -438.837324)
			(xy 339.21827 -438.837324) (xy 339.206175 -438.836918) (xy 339.183168 -438.829448) (xy 339.163585 -438.815247)
			(xy 339.149337 -438.795699) (xy 339.141812 -438.77271) (xy 339.141308 -438.760616) (xy 339.141308 -438.147968)
			(xy 339.139763 -438.133476) (xy 339.138111 -438.104376) (xy 339.138006 -438.089802) (xy 338.235036 -438.089802)
			(xy 338.235036 -439.0898) (xy 341.138002 -439.0898) (xy 341.138094 -439.075226) (xy 341.139748 -439.046125)
			(xy 341.141304 -439.031634) (xy 341.141304 -437.94807) (xy 341.139759 -437.933578) (xy 341.138107 -437.904478)
			(xy 341.138002 -437.889904) (xy 341.138095 -437.87533) (xy 341.139748 -437.846229) (xy 341.141304 -437.831738)
			(xy 341.141304 -437.21909) (xy 341.141803 -437.206978) (xy 341.149289 -437.183941) (xy 341.163525 -437.164342)
			(xy 341.183119 -437.1501) (xy 341.206154 -437.142607) (xy 341.218266 -437.142128) (xy 342.158066 -437.142128)
			(xy 342.170186 -437.142589) (xy 342.193242 -437.15007) (xy 342.212857 -437.164312) (xy 342.22711 -437.183918)
			(xy 342.234604 -437.20697) (xy 342.235028 -437.21909) (xy 342.235028 -438.089802) (xy 343.137998 -438.089802)
			(xy 343.138091 -438.075228) (xy 343.139744 -438.046127) (xy 343.1413 -438.031636) (xy 343.1413 -436.948072)
			(xy 343.139755 -436.93358) (xy 343.138103 -436.90448) (xy 343.137998 -436.889906) (xy 343.138091 -436.875332)
			(xy 343.139744 -436.846231) (xy 343.1413 -436.83174) (xy 343.1413 -436.219092) (xy 343.141709 -436.206983)
			(xy 343.149211 -436.183955) (xy 343.163474 -436.164382) (xy 343.183097 -436.150188) (xy 343.206151 -436.142767)
			(xy 343.218262 -436.142384) (xy 344.158062 -436.142384) (xy 344.170154 -436.142841) (xy 344.193161 -436.150292)
			(xy 344.212745 -436.16448) (xy 344.226995 -436.184019) (xy 344.234521 -436.207002) (xy 344.235024 -436.219092)
			(xy 344.235024 -438.760616) (xy 344.234598 -438.772723) (xy 344.227097 -438.795747) (xy 344.212837 -438.815318)
			(xy 344.193219 -438.829513) (xy 344.170171 -438.836937) (xy 344.158062 -438.837324) (xy 343.218262 -438.837324)
			(xy 343.206167 -438.836924) (xy 343.183159 -438.829453) (xy 343.163577 -438.81525) (xy 343.149329 -438.795701)
			(xy 343.141804 -438.77271) (xy 343.1413 -438.760616) (xy 343.1413 -438.147968) (xy 343.139755 -438.133476)
			(xy 343.138103 -438.104376) (xy 343.137998 -438.089802) (xy 342.235028 -438.089802) (xy 342.235028 -439.0898)
			(xy 345.137994 -439.0898) (xy 345.138086 -439.075226) (xy 345.13974 -439.046125) (xy 345.141296 -439.031634)
			(xy 345.141296 -437.94807) (xy 345.139752 -437.933578) (xy 345.138099 -437.904478) (xy 345.137994 -437.889904)
			(xy 345.138087 -437.87533) (xy 345.13974 -437.846229) (xy 345.141296 -437.831738) (xy 345.141296 -437.21909)
			(xy 345.141803 -437.206979) (xy 345.149288 -437.183943) (xy 345.163522 -437.164345) (xy 345.183114 -437.150102)
			(xy 345.206147 -437.142608) (xy 345.218258 -437.142128) (xy 346.158058 -437.142128) (xy 346.170178 -437.142595)
			(xy 346.193233 -437.150075) (xy 346.212848 -437.164315) (xy 346.227101 -437.18392) (xy 346.234596 -437.206971)
			(xy 346.23502 -437.21909) (xy 346.23502 -439.0898) (xy 383.237994 -439.0898) (xy 383.238086 -439.075226)
			(xy 383.23974 -439.046125) (xy 383.241296 -439.031634) (xy 383.241296 -437.94807) (xy 383.239752 -437.933578)
			(xy 383.238099 -437.904478) (xy 383.237994 -437.889904) (xy 383.238087 -437.87533) (xy 383.23974 -437.846229)
			(xy 383.241296 -437.831738) (xy 383.241296 -437.21909) (xy 383.241803 -437.206979) (xy 383.249288 -437.183943)
			(xy 383.263522 -437.164345) (xy 383.283114 -437.150102) (xy 383.306147 -437.142608) (xy 383.318258 -437.142128)
			(xy 384.258058 -437.142128) (xy 384.270178 -437.142595) (xy 384.293233 -437.150075) (xy 384.312848 -437.164315)
			(xy 384.327101 -437.18392) (xy 384.334596 -437.206971) (xy 384.33502 -437.21909) (xy 384.33502 -438.089802)
			(xy 385.23799 -438.089802) (xy 385.238083 -438.075228) (xy 385.239736 -438.046127) (xy 385.241292 -438.031636)
			(xy 385.241292 -436.948072) (xy 385.239748 -436.93358) (xy 385.238095 -436.90448) (xy 385.23799 -436.889906)
			(xy 385.238083 -436.875332) (xy 385.239736 -436.846231) (xy 385.241292 -436.83174) (xy 385.241292 -436.219092)
			(xy 385.241709 -436.206983) (xy 385.24921 -436.183957) (xy 385.263472 -436.164385) (xy 385.283092 -436.15019)
			(xy 385.306144 -436.142768) (xy 385.318254 -436.142384) (xy 386.258054 -436.142384) (xy 386.270146 -436.142847)
			(xy 386.293152 -436.150297) (xy 386.312737 -436.164483) (xy 386.326987 -436.18402) (xy 386.334512 -436.207002)
			(xy 386.335016 -436.219092) (xy 386.335016 -438.760616) (xy 386.334598 -438.772724) (xy 386.327096 -438.795749)
			(xy 386.312834 -438.815321) (xy 386.293214 -438.829515) (xy 386.270163 -438.836939) (xy 386.258054 -438.837324)
			(xy 385.318254 -438.837324) (xy 385.306158 -438.836931) (xy 385.28315 -438.829457) (xy 385.263568 -438.815253)
			(xy 385.24932 -438.795702) (xy 385.241796 -438.77271) (xy 385.241292 -438.760616) (xy 385.241292 -438.147968)
			(xy 385.239747 -438.133476) (xy 385.238095 -438.104376) (xy 385.23799 -438.089802) (xy 384.33502 -438.089802)
			(xy 384.33502 -439.0898) (xy 387.237986 -439.0898) (xy 387.238078 -439.075226) (xy 387.239732 -439.046125)
			(xy 387.241288 -439.031634) (xy 387.241288 -437.94807) (xy 387.239744 -437.933578) (xy 387.238091 -437.904478)
			(xy 387.237986 -437.889904) (xy 387.238079 -437.87533) (xy 387.239732 -437.846229) (xy 387.241288 -437.831738)
			(xy 387.241288 -437.21909) (xy 387.241803 -437.20698) (xy 387.249287 -437.183945) (xy 387.263519 -437.164348)
			(xy 387.283109 -437.150105) (xy 387.30614 -437.142609) (xy 387.31825 -437.142128) (xy 388.25805 -437.142128)
			(xy 388.270166 -437.142569) (xy 388.293209 -437.150069) (xy 388.312809 -437.164319) (xy 388.32705 -437.183927)
			(xy 388.334537 -437.206974) (xy 388.335012 -437.21909) (xy 388.335012 -438.089802) (xy 389.237982 -438.089802)
			(xy 389.238075 -438.075228) (xy 389.239728 -438.046127) (xy 389.241284 -438.031636) (xy 389.241284 -436.948072)
			(xy 389.23974 -436.93358) (xy 389.238087 -436.90448) (xy 389.237982 -436.889906) (xy 389.238075 -436.875332)
			(xy 389.239728 -436.846231) (xy 389.241284 -436.83174) (xy 389.241284 -436.219092) (xy 389.241709 -436.206984)
			(xy 389.249209 -436.183959) (xy 389.263469 -436.164388) (xy 389.283087 -436.150193) (xy 389.306137 -436.142769)
			(xy 389.318246 -436.142384) (xy 390.258046 -436.142384) (xy 390.270142 -436.142769) (xy 390.293152 -436.150244)
			(xy 390.312735 -436.16445) (xy 390.326982 -436.184003) (xy 390.334505 -436.206997) (xy 390.335008 -436.219092)
			(xy 390.335008 -438.760616) (xy 390.334598 -438.772725) (xy 390.327095 -438.795751) (xy 390.312831 -438.815324)
			(xy 390.293209 -438.829518) (xy 390.270156 -438.83694) (xy 390.258046 -438.837324) (xy 389.318246 -438.837324)
			(xy 389.306155 -438.836853) (xy 389.28315 -438.829404) (xy 389.263566 -438.81522) (xy 389.249315 -438.795685)
			(xy 389.241789 -438.772705) (xy 389.241284 -438.760616) (xy 389.241284 -438.147968) (xy 389.239739 -438.133476)
			(xy 389.238087 -438.104376) (xy 389.237982 -438.089802) (xy 388.335012 -438.089802) (xy 388.335012 -439.0898)
			(xy 391.237978 -439.0898) (xy 391.238071 -439.075226) (xy 391.239724 -439.046125) (xy 391.24128 -439.031634)
			(xy 391.24128 -437.94807) (xy 391.239736 -437.933578) (xy 391.238083 -437.904478) (xy 391.237978 -437.889904)
			(xy 391.238071 -437.87533) (xy 391.239724 -437.846229) (xy 391.24128 -437.831738) (xy 391.24128 -437.21909)
			(xy 391.241652 -437.206963) (xy 391.249152 -437.183896) (xy 391.263415 -437.164278) (xy 391.283043 -437.150029)
			(xy 391.306114 -437.142544) (xy 391.318242 -437.142128) (xy 392.258042 -437.142128) (xy 392.270158 -437.142576)
			(xy 392.293201 -437.150073) (xy 392.312801 -437.164322) (xy 392.327041 -437.183928) (xy 392.334529 -437.206974)
			(xy 392.335004 -437.21909) (xy 392.335004 -438.089802) (xy 393.237974 -438.089802) (xy 393.238067 -438.075228)
			(xy 393.23972 -438.046127) (xy 393.241276 -438.031636) (xy 393.241276 -436.948072) (xy 393.239732 -436.93358)
			(xy 393.238079 -436.90448) (xy 393.237974 -436.889906) (xy 393.238067 -436.875332) (xy 393.23972 -436.846231)
			(xy 393.241276 -436.83174) (xy 393.241276 -436.219092) (xy 393.241709 -436.206985) (xy 393.249208 -436.183962)
			(xy 393.263466 -436.164391) (xy 393.283082 -436.150195) (xy 393.30613 -436.142771) (xy 393.318238 -436.142384)
			(xy 394.258038 -436.142384) (xy 394.270134 -436.142776) (xy 394.293143 -436.150248) (xy 394.312726 -436.164453)
			(xy 394.326974 -436.184004) (xy 394.334497 -436.206997) (xy 394.335 -436.219092) (xy 394.335 -438.760616)
			(xy 394.334597 -438.772726) (xy 394.327094 -438.795754) (xy 394.312828 -438.815326) (xy 394.293204 -438.82952)
			(xy 394.270149 -438.836941) (xy 394.258038 -438.837324) (xy 393.318238 -438.837324) (xy 393.306147 -438.83686)
			(xy 393.283141 -438.829409) (xy 393.263558 -438.815223) (xy 393.249307 -438.795686) (xy 393.241781 -438.772706)
			(xy 393.241276 -438.760616) (xy 393.241276 -438.147968) (xy 393.239731 -438.133476) (xy 393.238079 -438.104376)
			(xy 393.237974 -438.089802) (xy 392.335004 -438.089802) (xy 392.335004 -439.0898) (xy 395.23797 -439.0898)
			(xy 395.238063 -439.075226) (xy 395.239716 -439.046125) (xy 395.241272 -439.031634) (xy 395.241272 -437.94807)
			(xy 395.239728 -437.933578) (xy 395.238075 -437.904478) (xy 395.23797 -437.889904) (xy 395.238063 -437.87533)
			(xy 395.239716 -437.846229) (xy 395.241272 -437.831738) (xy 395.241272 -437.21909) (xy 395.241652 -437.206963)
			(xy 395.249151 -437.183898) (xy 395.263412 -437.164281) (xy 395.283038 -437.150031) (xy 395.306107 -437.142545)
			(xy 395.318234 -437.142128) (xy 396.258034 -437.142128) (xy 396.270149 -437.142583) (xy 396.293192 -437.150078)
			(xy 396.312792 -437.164325) (xy 396.327033 -437.18393) (xy 396.334521 -437.206975) (xy 396.334996 -437.21909)
			(xy 396.334996 -438.089802) (xy 398.237964 -438.089802) (xy 398.238081 -438.074717) (xy 398.239857 -438.044598)
			(xy 398.24152 -438.029604) (xy 398.24152 -436.950104) (xy 398.23985 -436.935111) (xy 398.238072 -436.904992)
			(xy 398.237964 -436.889906) (xy 398.238072 -436.87482) (xy 398.239854 -436.844702) (xy 398.24152 -436.829708)
			(xy 398.24152 -436.219092) (xy 398.241906 -436.207006) (xy 398.249379 -436.184018) (xy 398.263591 -436.164466)
			(xy 398.283151 -436.150263) (xy 398.306142 -436.1428) (xy 398.318228 -436.142384) (xy 399.258028 -436.142384)
			(xy 399.270103 -436.14284) (xy 399.29307 -436.150309) (xy 399.312606 -436.164508) (xy 399.3268 -436.184048)
			(xy 399.334263 -436.207017) (xy 399.334736 -436.219092) (xy 399.334736 -438.760616) (xy 399.33425 -438.772689)
			(xy 399.326786 -438.795651) (xy 399.312594 -438.815186) (xy 399.293062 -438.829381) (xy 399.270101 -438.836848)
			(xy 399.258028 -438.837324) (xy 398.318228 -438.837324) (xy 398.306148 -438.836864) (xy 398.283169 -438.829406)
			(xy 398.26362 -438.815211) (xy 398.249414 -438.79567) (xy 398.241943 -438.772695) (xy 398.24152 -438.760616)
			(xy 398.24152 -438.15) (xy 398.239849 -438.135007) (xy 398.238072 -438.104888) (xy 398.237964 -438.089802)
			(xy 396.334996 -438.089802) (xy 396.334996 -439.0898) (xy 400.23796 -439.0898) (xy 400.238077 -439.074715)
			(xy 400.239853 -439.044596) (xy 400.241516 -439.029602) (xy 400.241516 -437.950102) (xy 400.239845 -437.935109)
			(xy 400.238068 -437.90499) (xy 400.23796 -437.889904) (xy 400.238077 -437.874819) (xy 400.239853 -437.8447)
			(xy 400.241516 -437.829706) (xy 400.241516 -437.21909) (xy 400.241999 -437.207002) (xy 400.249455 -437.184006)
			(xy 400.263639 -437.164428) (xy 400.283167 -437.150177) (xy 400.306138 -437.142641) (xy 400.318224 -437.142128)
			(xy 401.258024 -437.142128) (xy 401.270137 -437.142496) (xy 401.29317 -437.150006) (xy 401.312745 -437.164279)
			(xy 401.326938 -437.183912) (xy 401.334353 -437.206975) (xy 401.334732 -437.21909) (xy 401.334732 -438.089802)
			(xy 402.237956 -438.089802) (xy 402.238073 -438.074717) (xy 402.239849 -438.044598) (xy 402.241512 -438.029604)
			(xy 402.241512 -436.950104) (xy 402.239842 -436.935111) (xy 402.238064 -436.904992) (xy 402.237956 -436.889906)
			(xy 402.238064 -436.87482) (xy 402.239846 -436.844702) (xy 402.241512 -436.829708) (xy 402.241512 -436.219092)
			(xy 402.241906 -436.207007) (xy 402.249378 -436.18402) (xy 402.263588 -436.164469) (xy 402.283146 -436.150265)
			(xy 402.306135 -436.142802) (xy 402.31822 -436.142384) (xy 403.25802 -436.142384) (xy 403.270095 -436.142847)
			(xy 403.293061 -436.150314) (xy 403.312597 -436.164511) (xy 403.326791 -436.18405) (xy 403.334255 -436.207017)
			(xy 403.334728 -436.219092) (xy 403.334728 -438.760616) (xy 403.33425 -438.772689) (xy 403.326785 -438.795654)
			(xy 403.312591 -438.815189) (xy 403.293057 -438.829383) (xy 403.270093 -438.836849) (xy 403.25802 -438.837324)
			(xy 402.31822 -438.837324) (xy 402.30614 -438.83687) (xy 402.283161 -438.82941) (xy 402.263611 -438.815214)
			(xy 402.249406 -438.795672) (xy 402.241935 -438.772696) (xy 402.241512 -438.760616) (xy 402.241512 -438.15)
			(xy 402.239841 -438.135007) (xy 402.238064 -438.104888) (xy 402.237956 -438.089802) (xy 401.334732 -438.089802)
			(xy 401.334732 -439.0898) (xy 404.237952 -439.0898) (xy 404.238069 -439.074715) (xy 404.239845 -439.044596)
			(xy 404.241508 -439.029602) (xy 404.241508 -437.950102) (xy 404.239837 -437.935109) (xy 404.23806 -437.90499)
			(xy 404.237952 -437.889904) (xy 404.238069 -437.874819) (xy 404.239845 -437.8447) (xy 404.241508 -437.829706)
			(xy 404.241508 -437.21909) (xy 404.241998 -437.207003) (xy 404.249454 -437.184008) (xy 404.263636 -437.164431)
			(xy 404.283162 -437.150179) (xy 404.306131 -437.142642) (xy 404.318216 -437.142128) (xy 405.258016 -437.142128)
			(xy 405.270129 -437.142503) (xy 405.293161 -437.15001) (xy 405.312736 -437.164281) (xy 405.326929 -437.183914)
			(xy 405.334345 -437.206976) (xy 405.334724 -437.21909) (xy 405.334724 -438.089802) (xy 406.237948 -438.089802)
			(xy 406.238065 -438.074717) (xy 406.239841 -438.044598) (xy 406.241504 -438.029604) (xy 406.241504 -436.950104)
			(xy 406.239834 -436.935111) (xy 406.238056 -436.904992) (xy 406.237948 -436.889906) (xy 406.238056 -436.87482)
			(xy 406.239838 -436.844702) (xy 406.241504 -436.829708) (xy 406.241504 -436.219092) (xy 406.241906 -436.207008)
			(xy 406.249377 -436.184023) (xy 406.263586 -436.164471) (xy 406.283141 -436.150268) (xy 406.306128 -436.142803)
			(xy 406.318212 -436.142384) (xy 407.258012 -436.142384) (xy 407.270086 -436.142854) (xy 407.293053 -436.150319)
			(xy 407.312589 -436.164514) (xy 407.326783 -436.184051) (xy 407.334247 -436.207018) (xy 407.33472 -436.219092)
			(xy 407.33472 -438.760616) (xy 407.334249 -438.77269) (xy 407.326784 -438.795656) (xy 407.312589 -438.815191)
			(xy 407.293052 -438.829386) (xy 407.270086 -438.83685) (xy 407.258012 -438.837324) (xy 406.318212 -438.837324)
			(xy 406.30614 -438.836826) (xy 406.283176 -438.829369) (xy 406.26364 -438.81518) (xy 406.249444 -438.79565)
			(xy 406.241979 -438.772688) (xy 406.241504 -438.760616) (xy 406.241504 -438.15) (xy 406.239833 -438.135007)
			(xy 406.238056 -438.104888) (xy 406.237948 -438.089802) (xy 405.334724 -438.089802) (xy 405.334724 -439.0898)
			(xy 408.237944 -439.0898) (xy 408.238061 -439.074715) (xy 408.239837 -439.044596) (xy 408.2415 -439.029602)
			(xy 408.2415 -437.950102) (xy 408.239829 -437.935109) (xy 408.238052 -437.90499) (xy 408.237944 -437.889904)
			(xy 408.238061 -437.874819) (xy 408.239837 -437.8447) (xy 408.2415 -437.829706) (xy 408.2415 -437.21909)
			(xy 408.241998 -437.207004) (xy 408.249453 -437.18401) (xy 408.263633 -437.164434) (xy 408.283157 -437.150182)
			(xy 408.306124 -437.142643) (xy 408.318208 -437.142128) (xy 409.258008 -437.142128) (xy 409.27012 -437.14251)
			(xy 409.293152 -437.150015) (xy 409.312728 -437.164284) (xy 409.326921 -437.183915) (xy 409.334337 -437.206976)
			(xy 409.334716 -437.21909) (xy 409.334716 -438.089802) (xy 410.23794 -438.089802) (xy 410.238057 -438.074717)
			(xy 410.239833 -438.044598) (xy 410.241496 -438.029604) (xy 410.241496 -436.950104) (xy 410.239826 -436.935111)
			(xy 410.238048 -436.904992) (xy 410.23794 -436.889906) (xy 410.23805 -436.87482) (xy 410.239832 -436.844702)
			(xy 410.241496 -436.829708) (xy 410.241496 -436.219092) (xy 410.241958 -436.207017) (xy 410.249423 -436.184049)
			(xy 410.26362 -436.164511) (xy 410.283159 -436.150317) (xy 410.306129 -436.142856) (xy 410.318204 -436.142384)
			(xy 411.258004 -436.142384) (xy 411.270078 -436.142861) (xy 411.293044 -436.150323) (xy 411.31258 -436.164517)
			(xy 411.326775 -436.184053) (xy 411.334239 -436.207018) (xy 411.334712 -436.219092) (xy 411.334712 -438.760616)
			(xy 411.334249 -438.772691) (xy 411.326783 -438.795658) (xy 411.312586 -438.815194) (xy 411.293047 -438.829388)
			(xy 411.270079 -438.836851) (xy 411.258004 -438.837324) (xy 410.318204 -438.837324) (xy 410.306131 -438.836833)
			(xy 410.283167 -438.829373) (xy 410.263631 -438.815183) (xy 410.249436 -438.795651) (xy 410.241971 -438.772689)
			(xy 410.241496 -438.760616) (xy 410.241496 -438.15) (xy 410.239825 -438.135007) (xy 410.238048 -438.104888)
			(xy 410.23794 -438.089802) (xy 409.334716 -438.089802) (xy 409.334716 -439.0898) (xy 412.237936 -439.0898)
			(xy 412.238053 -439.074715) (xy 412.239829 -439.044596) (xy 412.241492 -439.029602) (xy 412.241492 -437.950102)
			(xy 412.239821 -437.935109) (xy 412.238044 -437.90499) (xy 412.237936 -437.889904) (xy 412.238053 -437.874819)
			(xy 412.239829 -437.8447) (xy 412.241492 -437.829706) (xy 412.241492 -437.21909) (xy 412.241998 -437.207005)
			(xy 412.249452 -437.184012) (xy 412.26363 -437.164436) (xy 412.283152 -437.150184) (xy 412.306117 -437.142644)
			(xy 412.3182 -437.142128) (xy 413.258 -437.142128) (xy 413.270112 -437.142516) (xy 413.293144 -437.150019)
			(xy 413.312719 -437.164287) (xy 413.326913 -437.183916) (xy 413.334329 -437.206977) (xy 413.334708 -437.21909)
			(xy 413.334708 -439.760614) (xy 413.334206 -439.7727) (xy 413.326751 -439.795693) (xy 413.312572 -439.815268)
			(xy 413.293049 -439.82952) (xy 413.270084 -439.83706) (xy 413.258 -439.837576) (xy 412.3182 -439.837576)
			(xy 412.306089 -439.837184) (xy 412.283057 -439.829681) (xy 412.263482 -439.815414) (xy 412.249288 -439.795786)
			(xy 412.241872 -439.772727) (xy 412.241492 -439.760614) (xy 412.241492 -439.149998) (xy 412.239821 -439.135005)
			(xy 412.238044 -439.104886) (xy 412.237936 -439.0898) (xy 409.334716 -439.0898) (xy 409.334716 -439.760614)
			(xy 409.334304 -439.772709) (xy 409.326838 -439.795717) (xy 409.312639 -439.815301) (xy 409.293091 -439.829549)
			(xy 409.270101 -439.837073) (xy 409.258008 -439.837576) (xy 408.318208 -439.837576) (xy 408.306097 -439.837177)
			(xy 408.283066 -439.829677) (xy 408.263491 -439.815412) (xy 408.249296 -439.795785) (xy 408.24188 -439.772726)
			(xy 408.2415 -439.760614) (xy 408.2415 -439.149998) (xy 408.239829 -439.135005) (xy 408.238052 -439.104886)
			(xy 408.237944 -439.0898) (xy 405.334724 -439.0898) (xy 405.334724 -439.760614) (xy 405.334304 -439.772708)
			(xy 405.326839 -439.795715) (xy 405.312642 -439.815298) (xy 405.293096 -439.829547) (xy 405.270109 -439.837072)
			(xy 405.258016 -439.837576) (xy 404.318216 -439.837576) (xy 404.306106 -439.83717) (xy 404.283075 -439.829672)
			(xy 404.263499 -439.815408) (xy 404.249305 -439.795783) (xy 404.241888 -439.772726) (xy 404.241508 -439.760614)
			(xy 404.241508 -439.149998) (xy 404.239837 -439.135005) (xy 404.23806 -439.104886) (xy 404.237952 -439.0898)
			(xy 401.334732 -439.0898) (xy 401.334732 -439.760614) (xy 401.334304 -439.772707) (xy 401.32684 -439.795713)
			(xy 401.312645 -439.815295) (xy 401.293101 -439.829544) (xy 401.270116 -439.837071) (xy 401.258024 -439.837576)
			(xy 400.318224 -439.837576) (xy 400.306114 -439.837163) (xy 400.283083 -439.829667) (xy 400.263508 -439.815406)
			(xy 400.249313 -439.795781) (xy 400.241896 -439.772725) (xy 400.241516 -439.760614) (xy 400.241516 -439.149998)
			(xy 400.239845 -439.135005) (xy 400.238068 -439.104886) (xy 400.23796 -439.0898) (xy 396.334996 -439.0898)
			(xy 396.334996 -439.760614) (xy 396.334501 -439.772726) (xy 396.327014 -439.795764) (xy 396.312777 -439.815363)
			(xy 396.293182 -439.829605) (xy 396.270146 -439.837098) (xy 396.258034 -439.837576) (xy 395.318234 -439.837576)
			(xy 395.306114 -439.837111) (xy 395.283059 -439.82963) (xy 395.263445 -439.81539) (xy 395.249192 -439.795784)
			(xy 395.241696 -439.772733) (xy 395.241272 -439.760614) (xy 395.241272 -439.147966) (xy 395.239727 -439.133474)
			(xy 395.238075 -439.104374) (xy 395.23797 -439.0898) (xy 392.335004 -439.0898) (xy 392.335004 -439.760614)
			(xy 392.334501 -439.772725) (xy 392.327015 -439.795762) (xy 392.31278 -439.81536) (xy 392.293187 -439.829602)
			(xy 392.270153 -439.837097) (xy 392.258042 -439.837576) (xy 391.318242 -439.837576) (xy 391.306123 -439.837105)
			(xy 391.283068 -439.829626) (xy 391.263453 -439.815387) (xy 391.2492 -439.795783) (xy 391.241704 -439.772733)
			(xy 391.24128 -439.760614) (xy 391.24128 -439.147966) (xy 391.239735 -439.133474) (xy 391.238083 -439.104374)
			(xy 391.237978 -439.0898) (xy 388.335012 -439.0898) (xy 388.335012 -439.760614) (xy 388.334501 -439.772724)
			(xy 388.327016 -439.79576) (xy 388.312782 -439.815357) (xy 388.293192 -439.8296) (xy 388.27016 -439.837096)
			(xy 388.25805 -439.837576) (xy 387.31825 -439.837576) (xy 387.306134 -439.837131) (xy 387.283092 -439.829632)
			(xy 387.263492 -439.815382) (xy 387.249252 -439.795776) (xy 387.241763 -439.77273) (xy 387.241288 -439.760614)
			(xy 387.241288 -439.147966) (xy 387.239743 -439.133474) (xy 387.238091 -439.104374) (xy 387.237986 -439.0898)
			(xy 384.33502 -439.0898) (xy 384.33502 -439.760614) (xy 384.334651 -439.772742) (xy 384.32715 -439.795808)
			(xy 384.312886 -439.815426) (xy 384.293258 -439.829675) (xy 384.270186 -439.83716) (xy 384.258058 -439.837576)
			(xy 383.318258 -439.837576) (xy 383.306143 -439.837124) (xy 383.2831 -439.829627) (xy 383.263501 -439.815379)
			(xy 383.24926 -439.795774) (xy 383.241771 -439.77273) (xy 383.241296 -439.760614) (xy 383.241296 -439.147966)
			(xy 383.239751 -439.133474) (xy 383.238099 -439.104374) (xy 383.237994 -439.0898) (xy 346.23502 -439.0898)
			(xy 346.23502 -439.760614) (xy 346.234651 -439.772742) (xy 346.22715 -439.795808) (xy 346.212886 -439.815426)
			(xy 346.193258 -439.829675) (xy 346.170186 -439.83716) (xy 346.158058 -439.837576) (xy 345.218258 -439.837576)
			(xy 345.206143 -439.837124) (xy 345.1831 -439.829627) (xy 345.163501 -439.815379) (xy 345.14926 -439.795774)
			(xy 345.141771 -439.77273) (xy 345.141296 -439.760614) (xy 345.141296 -439.147966) (xy 345.139751 -439.133474)
			(xy 345.138099 -439.104374) (xy 345.137994 -439.0898) (xy 342.235028 -439.0898) (xy 342.235028 -439.760614)
			(xy 342.234651 -439.772741) (xy 342.227151 -439.795806) (xy 342.212889 -439.815424) (xy 342.193263 -439.829673)
			(xy 342.170193 -439.837159) (xy 342.158066 -439.837576) (xy 341.218266 -439.837576) (xy 341.206151 -439.837118)
			(xy 341.183109 -439.829623) (xy 341.163509 -439.815377) (xy 341.149268 -439.795773) (xy 341.141779 -439.772729)
			(xy 341.141304 -439.760614) (xy 341.141304 -439.147966) (xy 341.139759 -439.133474) (xy 341.138107 -439.104374)
			(xy 341.138002 -439.0898) (xy 338.235036 -439.0898) (xy 338.235036 -439.760614) (xy 338.234651 -439.77274)
			(xy 338.227152 -439.795804) (xy 338.212892 -439.815421) (xy 338.193268 -439.82967) (xy 338.1702 -439.837158)
			(xy 338.158074 -439.837576) (xy 337.218274 -439.837576) (xy 337.206159 -439.837111) (xy 337.183118 -439.829618)
			(xy 337.163518 -439.815374) (xy 337.149276 -439.795772) (xy 337.141787 -439.772729) (xy 337.141312 -439.760614)
			(xy 337.141312 -439.147966) (xy 337.139767 -439.133474) (xy 337.138115 -439.104374) (xy 337.13801 -439.0898)
			(xy 334.235044 -439.0898) (xy 334.235044 -439.760614) (xy 334.234651 -439.772739) (xy 334.227153 -439.795802)
			(xy 334.212895 -439.815418) (xy 334.193273 -439.829668) (xy 334.170207 -439.837157) (xy 334.158082 -439.837576)
			(xy 333.218282 -439.837576) (xy 333.206168 -439.837104) (xy 333.183126 -439.829614) (xy 333.163526 -439.815371)
			(xy 333.149285 -439.79577) (xy 333.141795 -439.772728) (xy 333.14132 -439.760614) (xy 333.14132 -439.147966)
			(xy 333.139775 -439.133474) (xy 333.138123 -439.104374) (xy 333.138018 -439.0898) (xy 329.2348 -439.0898)
			(xy 329.2348 -439.760614) (xy 329.234306 -439.7727) (xy 329.22685 -439.795695) (xy 329.212669 -439.815271)
			(xy 329.193144 -439.829523) (xy 329.170177 -439.837061) (xy 329.158092 -439.837576) (xy 328.218292 -439.837576)
			(xy 328.20618 -439.83719) (xy 328.183149 -439.829686) (xy 328.163574 -439.815417) (xy 328.14938 -439.795788)
			(xy 328.141964 -439.772727) (xy 328.141584 -439.760614) (xy 328.141584 -439.149998) (xy 328.139913 -439.135005)
			(xy 328.138136 -439.104886) (xy 328.138028 -439.0898) (xy 325.234808 -439.0898) (xy 325.234808 -439.760614)
			(xy 325.234306 -439.7727) (xy 325.226851 -439.795693) (xy 325.212672 -439.815268) (xy 325.193149 -439.82952)
			(xy 325.170184 -439.83706) (xy 325.1581 -439.837576) (xy 324.2183 -439.837576) (xy 324.206189 -439.837184)
			(xy 324.183157 -439.829681) (xy 324.163582 -439.815414) (xy 324.149388 -439.795786) (xy 324.141972 -439.772727)
			(xy 324.141592 -439.760614) (xy 324.141592 -439.149998) (xy 324.139921 -439.135005) (xy 324.138144 -439.104886)
			(xy 324.138036 -439.0898) (xy 321.234816 -439.0898) (xy 321.234816 -439.760614) (xy 321.234404 -439.772709)
			(xy 321.226938 -439.795717) (xy 321.212739 -439.815301) (xy 321.193191 -439.829549) (xy 321.170201 -439.837073)
			(xy 321.158108 -439.837576) (xy 320.218308 -439.837576) (xy 320.206197 -439.837177) (xy 320.183166 -439.829677)
			(xy 320.163591 -439.815412) (xy 320.149396 -439.795785) (xy 320.14198 -439.772726) (xy 320.1416 -439.760614)
			(xy 320.1416 -439.149998) (xy 320.139929 -439.135005) (xy 320.138152 -439.104886) (xy 320.138044 -439.0898)
			(xy 317.234824 -439.0898) (xy 317.234824 -439.760614) (xy 317.234404 -439.772708) (xy 317.226939 -439.795715)
			(xy 317.212742 -439.815298) (xy 317.193196 -439.829547) (xy 317.170209 -439.837072) (xy 317.158116 -439.837576)
			(xy 316.218316 -439.837576) (xy 316.206206 -439.83717) (xy 316.183175 -439.829672) (xy 316.163599 -439.815408)
			(xy 316.149405 -439.795783) (xy 316.141988 -439.772726) (xy 316.141608 -439.760614) (xy 316.141608 -439.149998)
			(xy 316.139937 -439.135005) (xy 316.13816 -439.104886) (xy 316.138052 -439.0898) (xy 157.334712 -439.0898)
			(xy 157.334712 -439.760614) (xy 157.334304 -439.772709) (xy 157.326838 -439.795718) (xy 157.312637 -439.815302)
			(xy 157.293089 -439.829551) (xy 157.270098 -439.837074) (xy 157.258004 -439.837576) (xy 156.318204 -439.837576)
			(xy 156.306093 -439.83718) (xy 156.283062 -439.829679) (xy 156.263486 -439.815413) (xy 156.249292 -439.795785)
			(xy 156.241876 -439.772727) (xy 156.241496 -439.760614) (xy 156.241496 -439.149998) (xy 156.239825 -439.135005)
			(xy 156.238048 -439.104886) (xy 156.23794 -439.0898) (xy 153.33472 -439.0898) (xy 153.33472 -439.760614)
			(xy 153.334304 -439.772708) (xy 153.326839 -439.795716) (xy 153.31264 -439.815299) (xy 153.293094 -439.829548)
			(xy 153.270105 -439.837073) (xy 153.258012 -439.837576) (xy 152.318212 -439.837576) (xy 152.306101 -439.837173)
			(xy 152.28307 -439.829674) (xy 152.263495 -439.81541) (xy 152.249301 -439.795784) (xy 152.241884 -439.772726)
			(xy 152.241504 -439.760614) (xy 152.241504 -439.149998) (xy 152.239833 -439.135005) (xy 152.238056 -439.104886)
			(xy 152.237948 -439.0898) (xy 149.334728 -439.0898) (xy 149.334728 -439.760614) (xy 149.334304 -439.772708)
			(xy 149.32684 -439.795714) (xy 149.312643 -439.815297) (xy 149.293099 -439.829546) (xy 149.270112 -439.837072)
			(xy 149.25802 -439.837576) (xy 148.31822 -439.837576) (xy 148.30611 -439.837166) (xy 148.283079 -439.829669)
			(xy 148.263504 -439.815407) (xy 148.249309 -439.795782) (xy 148.241892 -439.772726) (xy 148.241512 -439.760614)
			(xy 148.241512 -439.149998) (xy 148.239841 -439.135005) (xy 148.238064 -439.104886) (xy 148.237956 -439.0898)
			(xy 145.334736 -439.0898) (xy 145.334736 -439.760614) (xy 145.334304 -439.772707) (xy 145.326841 -439.795712)
			(xy 145.312646 -439.815294) (xy 145.293104 -439.829543) (xy 145.270119 -439.83707) (xy 145.258028 -439.837576)
			(xy 144.318228 -439.837576) (xy 144.306118 -439.837159) (xy 144.283088 -439.829665) (xy 144.263512 -439.815404)
			(xy 144.249317 -439.795781) (xy 144.2419 -439.772725) (xy 144.24152 -439.760614) (xy 144.24152 -439.149998)
			(xy 144.239849 -439.135005) (xy 144.238072 -439.104886) (xy 144.237964 -439.0898) (xy 140.335 -439.0898)
			(xy 140.335 -439.760614) (xy 140.334501 -439.772726) (xy 140.327015 -439.795763) (xy 140.312778 -439.815361)
			(xy 140.293184 -439.829604) (xy 140.270149 -439.837097) (xy 140.258038 -439.837576) (xy 139.318238 -439.837576)
			(xy 139.306119 -439.837108) (xy 139.283063 -439.829628) (xy 139.263449 -439.815388) (xy 139.249196 -439.795783)
			(xy 139.2417 -439.772733) (xy 139.241276 -439.760614) (xy 139.241276 -439.147966) (xy 139.239731 -439.133474)
			(xy 139.238079 -439.104374) (xy 139.237974 -439.0898) (xy 136.335008 -439.0898) (xy 136.335008 -439.760614)
			(xy 136.334501 -439.772725) (xy 136.327016 -439.795761) (xy 136.312781 -439.815358) (xy 136.293189 -439.829601)
			(xy 136.270157 -439.837096) (xy 136.258046 -439.837576) (xy 135.318246 -439.837576) (xy 135.306127 -439.837101)
			(xy 135.283072 -439.829623) (xy 135.263457 -439.815385) (xy 135.249204 -439.795782) (xy 135.241708 -439.772733)
			(xy 135.241284 -439.760614) (xy 135.241284 -439.147966) (xy 135.239739 -439.133474) (xy 135.238087 -439.104374)
			(xy 135.237982 -439.0898) (xy 132.335016 -439.0898) (xy 132.335016 -439.760614) (xy 132.334651 -439.772742)
			(xy 132.327149 -439.795809) (xy 132.312885 -439.815428) (xy 132.293255 -439.829677) (xy 132.270182 -439.83716)
			(xy 132.258054 -439.837576) (xy 131.318254 -439.837576) (xy 131.306138 -439.837128) (xy 131.283096 -439.82963)
			(xy 131.263496 -439.815381) (xy 131.249256 -439.795775) (xy 131.241767 -439.77273) (xy 131.241292 -439.760614)
			(xy 131.241292 -439.147966) (xy 131.239747 -439.133474) (xy 131.238095 -439.104374) (xy 131.23799 -439.0898)
			(xy 128.335024 -439.0898) (xy 128.335024 -439.760614) (xy 128.334651 -439.772741) (xy 128.32715 -439.795807)
			(xy 128.312888 -439.815425) (xy 128.29326 -439.829674) (xy 128.27019 -439.837159) (xy 128.258062 -439.837576)
			(xy 127.318262 -439.837576) (xy 127.306147 -439.837121) (xy 127.283105 -439.829625) (xy 127.263505 -439.815378)
			(xy 127.249264 -439.795774) (xy 127.241775 -439.772729) (xy 127.2413 -439.760614) (xy 127.2413 -439.147966)
			(xy 127.239755 -439.133474) (xy 127.238103 -439.104374) (xy 127.237998 -439.0898) (xy 90.235024 -439.0898)
			(xy 90.235024 -439.760614) (xy 90.234651 -439.772741) (xy 90.22715 -439.795807) (xy 90.212888 -439.815425)
			(xy 90.19326 -439.829674) (xy 90.17019 -439.837159) (xy 90.158062 -439.837576) (xy 89.218262 -439.837576)
			(xy 89.206147 -439.837121) (xy 89.183105 -439.829625) (xy 89.163505 -439.815378) (xy 89.149264 -439.795774)
			(xy 89.141775 -439.772729) (xy 89.1413 -439.760614) (xy 89.1413 -439.147966) (xy 89.139755 -439.133474)
			(xy 89.138103 -439.104374) (xy 89.137998 -439.0898) (xy 86.235032 -439.0898) (xy 86.235032 -439.760614)
			(xy 86.234651 -439.77274) (xy 86.227152 -439.795805) (xy 86.212891 -439.815422) (xy 86.193265 -439.829672)
			(xy 86.170197 -439.837158) (xy 86.15807 -439.837576) (xy 85.21827 -439.837576) (xy 85.206155 -439.837114)
			(xy 85.183113 -439.82962) (xy 85.163513 -439.815375) (xy 85.149272 -439.795772) (xy 85.141783 -439.772729)
			(xy 85.141308 -439.760614) (xy 85.141308 -439.147966) (xy 85.139763 -439.133474) (xy 85.138111 -439.104374)
			(xy 85.138006 -439.0898) (xy 82.23504 -439.0898) (xy 82.23504 -439.760614) (xy 82.234651 -439.77274)
			(xy 82.227153 -439.795803) (xy 82.212894 -439.815419) (xy 82.19327 -439.829669) (xy 82.170204 -439.837157)
			(xy 82.158078 -439.837576) (xy 81.218278 -439.837576) (xy 81.206164 -439.837107) (xy 81.183122 -439.829616)
			(xy 81.163522 -439.815372) (xy 81.149281 -439.795771) (xy 81.141791 -439.772728) (xy 81.141316 -439.760614)
			(xy 81.141316 -439.147966) (xy 81.139771 -439.133474) (xy 81.138119 -439.104374) (xy 81.138014 -439.0898)
			(xy 78.235048 -439.0898) (xy 78.235048 -439.760614) (xy 78.2346 -439.772731) (xy 78.227107 -439.795777)
			(xy 78.21286 -439.81538) (xy 78.193252 -439.82962) (xy 78.170203 -439.837105) (xy 78.158086 -439.837576)
			(xy 77.218286 -439.837576) (xy 77.206172 -439.837101) (xy 77.183131 -439.829611) (xy 77.16353 -439.81537)
			(xy 77.149289 -439.795769) (xy 77.141799 -439.772728) (xy 77.141324 -439.760614) (xy 77.141324 -439.147966)
			(xy 77.139779 -439.133474) (xy 77.138127 -439.104374) (xy 77.138022 -439.0898) (xy 73.234804 -439.0898)
			(xy 73.234804 -439.760614) (xy 73.234306 -439.7727) (xy 73.22685 -439.795694) (xy 73.21267 -439.81527)
			(xy 73.193146 -439.829521) (xy 73.17018 -439.837061) (xy 73.158096 -439.837576) (xy 72.218296 -439.837576)
			(xy 72.206185 -439.837187) (xy 72.183153 -439.829683) (xy 72.163578 -439.815416) (xy 72.149384 -439.795787)
			(xy 72.141968 -439.772727) (xy 72.141588 -439.760614) (xy 72.141588 -439.149998) (xy 72.139917 -439.135005)
			(xy 72.13814 -439.104886) (xy 72.138032 -439.0898) (xy 69.234812 -439.0898) (xy 69.234812 -439.760614)
			(xy 69.234404 -439.772709) (xy 69.226938 -439.795718) (xy 69.212737 -439.815302) (xy 69.193189 -439.829551)
			(xy 69.170198 -439.837074) (xy 69.158104 -439.837576) (xy 68.218304 -439.837576) (xy 68.206193 -439.83718)
			(xy 68.183162 -439.829679) (xy 68.163586 -439.815413) (xy 68.149392 -439.795785) (xy 68.141976 -439.772727)
			(xy 68.141596 -439.760614) (xy 68.141596 -439.149998) (xy 68.139925 -439.135005) (xy 68.138148 -439.104886)
			(xy 68.13804 -439.0898) (xy 65.23482 -439.0898) (xy 65.23482 -439.760614) (xy 65.234404 -439.772708)
			(xy 65.226939 -439.795716) (xy 65.21274 -439.815299) (xy 65.193194 -439.829548) (xy 65.170205 -439.837073)
			(xy 65.158112 -439.837576) (xy 64.218312 -439.837576) (xy 64.206201 -439.837173) (xy 64.18317 -439.829674)
			(xy 64.163595 -439.81541) (xy 64.149401 -439.795784) (xy 64.141984 -439.772726) (xy 64.141604 -439.760614)
			(xy 64.141604 -439.149998) (xy 64.139933 -439.135005) (xy 64.138156 -439.104886) (xy 64.138048 -439.0898)
			(xy 61.234828 -439.0898) (xy 61.234828 -439.760614) (xy 61.234404 -439.772708) (xy 61.22694 -439.795714)
			(xy 61.212743 -439.815297) (xy 61.193199 -439.829546) (xy 61.170212 -439.837072) (xy 61.15812 -439.837576)
			(xy 60.21832 -439.837576) (xy 60.20621 -439.837166) (xy 60.183179 -439.829669) (xy 60.163604 -439.815407)
			(xy 60.149409 -439.795782) (xy 60.141992 -439.772726) (xy 60.141612 -439.760614) (xy 60.141612 -439.149998)
			(xy 60.139941 -439.135005) (xy 60.138164 -439.104886) (xy 60.138056 -439.0898) (xy 7.00913 -439.0898)
			(xy 7.00913 -439.989976) (xy 7.009638 -440.045746) (xy 7.017973 -440.156973) (xy 7.034597 -440.267266)
			(xy 7.059417 -440.376009) (xy 7.092293 -440.482593) (xy 7.133043 -440.586422) (xy 7.181438 -440.686915)
			(xy 7.237207 -440.783511) (xy 7.300039 -440.87567) (xy 7.369583 -440.962874) (xy 7.445449 -441.044639)
			(xy 7.527212 -441.120505) (xy 7.614417 -441.190048) (xy 7.706575 -441.252881) (xy 7.803171 -441.30865)
			(xy 7.903664 -441.357045) (xy 8.007493 -441.397795) (xy 8.114077 -441.430672) (xy 8.22282 -441.455492)
			(xy 8.333113 -441.472116) (xy 8.44434 -441.480451) (xy 8.50011 -441.480956) (xy 194.495928 -441.480956)
		)
		(stroke
			(width 0)
			(type solid)
		)
		(fill yes)
		(layer "In1.Cu")
		(net "GND")
	)
	(gr_line
		(start 52.809902 -62.77102)
		(end 53.709824 -64.733424)
		(stroke
			(width 0.1016)
			(type default)
		)
		(layer "In1.Cu")
	)
	(gr_line
		(start 53.003196 -65.057528)
		(end 52.103528 -63.095124)
		(stroke
			(width 0.1016)
			(type default)
		)
		(layer "In1.Cu")
	)
	(gr_line
		(start 53.48478 -66.474594)
		(end 54.384702 -68.436998)
		(stroke
			(width 0.1016)
			(type default)
		)
		(layer "In1.Cu")
	)
	(gr_line
		(start 53.678074 -68.761102)
		(end 52.778406 -66.798698)
		(stroke
			(width 0.1016)
			(type default)
		)
		(layer "In1.Cu")
	)
	(gr_line
		(start 53.709824 -64.733424)
		(end 53.003196 -65.057528)
		(stroke
			(width 0.1016)
			(type default)
		)
		(layer "In1.Cu")
	)
	(gr_line
		(start 53.724556 -69.228208)
		(end 54.624478 -71.190612)
		(stroke
			(width 0.1016)
			(type default)
		)
		(layer "In1.Cu")
	)
	(gr_line
		(start 53.91785 -71.514716)
		(end 53.018182 -69.552312)
		(stroke
			(width 0.1016)
			(type default)
		)
		(layer "In1.Cu")
	)
	(gr_line
		(start 54.384702 -68.436998)
		(end 53.678074 -68.761102)
		(stroke
			(width 0.1016)
			(type default)
		)
		(layer "In1.Cu")
	)
	(gr_line
		(start 54.623462 -62.189614)
		(end 55.523638 -64.151764)
		(stroke
			(width 0.1016)
			(type default)
		)
		(layer "In1.Cu")
	)
	(gr_line
		(start 54.624478 -71.190612)
		(end 53.91785 -71.514716)
		(stroke
			(width 0.1016)
			(type default)
		)
		(layer "In1.Cu")
	)
	(gr_line
		(start 54.81701 -64.476122)
		(end 53.917088 -62.513718)
		(stroke
			(width 0.1016)
			(type default)
		)
		(layer "In1.Cu")
	)
	(gr_line
		(start 55.157878 -65.660778)
		(end 56.0578 -67.623182)
		(stroke
			(width 0.1016)
			(type default)
		)
		(layer "In1.Cu")
	)
	(gr_line
		(start 55.351172 -67.947286)
		(end 54.451504 -65.984882)
		(stroke
			(width 0.1016)
			(type default)
		)
		(layer "In1.Cu")
	)
	(gr_line
		(start 55.523638 -64.151764)
		(end 54.81701 -64.476122)
		(stroke
			(width 0.1016)
			(type default)
		)
		(layer "In1.Cu")
	)
	(gr_line
		(start 56.0578 -67.623182)
		(end 55.351172 -67.947286)
		(stroke
			(width 0.1016)
			(type default)
		)
		(layer "In1.Cu")
	)
	(gr_line
		(start 56.449976 -61.61405)
		(end 57.349898 -63.576454)
		(stroke
			(width 0.1016)
			(type default)
		)
		(layer "In1.Cu")
	)
	(gr_line
		(start 56.64327 -63.900558)
		(end 55.743602 -61.938154)
		(stroke
			(width 0.1016)
			(type default)
		)
		(layer "In1.Cu")
	)
	(gr_line
		(start 57.002934 -65.094104)
		(end 57.902856 -67.056508)
		(stroke
			(width 0.1016)
			(type default)
		)
		(layer "In1.Cu")
	)
	(gr_line
		(start 57.196228 -67.380612)
		(end 56.29656 -65.418208)
		(stroke
			(width 0.1016)
			(type default)
		)
		(layer "In1.Cu")
	)
	(gr_line
		(start 57.349898 -63.576454)
		(end 56.64327 -63.900558)
		(stroke
			(width 0.1016)
			(type default)
		)
		(layer "In1.Cu")
	)
	(gr_line
		(start 57.902856 -67.056508)
		(end 57.196228 -67.380612)
		(stroke
			(width 0.1016)
			(type default)
		)
		(layer "In1.Cu")
	)
	(gr_line
		(start 58.346086 -61.124084)
		(end 59.246008 -63.086488)
		(stroke
			(width 0.1016)
			(type default)
		)
		(layer "In1.Cu")
	)
	(gr_line
		(start 58.53938 -63.410592)
		(end 57.639712 -61.448188)
		(stroke
			(width 0.1016)
			(type default)
		)
		(layer "In1.Cu")
	)
	(gr_line
		(start 58.86958 -64.560704)
		(end 59.769502 -66.523108)
		(stroke
			(width 0.1016)
			(type default)
		)
		(layer "In1.Cu")
	)
	(gr_line
		(start 59.062874 -66.847212)
		(end 58.163206 -64.884808)
		(stroke
			(width 0.1016)
			(type default)
		)
		(layer "In1.Cu")
	)
	(gr_line
		(start 59.246008 -63.086488)
		(end 58.53938 -63.410592)
		(stroke
			(width 0.1016)
			(type default)
		)
		(layer "In1.Cu")
	)
	(gr_line
		(start 59.769502 -66.523108)
		(end 59.062874 -66.847212)
		(stroke
			(width 0.1016)
			(type default)
		)
		(layer "In1.Cu")
	)
	(gr_line
		(start 60.143898 -60.391802)
		(end 61.044074 -62.353952)
		(stroke
			(width 0.1016)
			(type default)
		)
		(layer "In1.Cu")
	)
	(gr_line
		(start 60.337446 -62.67831)
		(end 59.437524 -60.715906)
		(stroke
			(width 0.1016)
			(type default)
		)
		(layer "In1.Cu")
	)
	(gr_line
		(start 60.677806 -63.83528)
		(end 61.577982 -65.79743)
		(stroke
			(width 0.1016)
			(type default)
		)
		(layer "In1.Cu")
	)
	(gr_line
		(start 60.871354 -66.121788)
		(end 59.971432 -64.159384)
		(stroke
			(width 0.1016)
			(type default)
		)
		(layer "In1.Cu")
	)
	(gr_line
		(start 61.044074 -62.353952)
		(end 60.337446 -62.67831)
		(stroke
			(width 0.1016)
			(type default)
		)
		(layer "In1.Cu")
	)
	(gr_line
		(start 61.577982 -65.79743)
		(end 60.871354 -66.121788)
		(stroke
			(width 0.1016)
			(type default)
		)
		(layer "In1.Cu")
	)
	(gr_line
		(start 61.948822 -59.786774)
		(end 62.848744 -61.749178)
		(stroke
			(width 0.1016)
			(type default)
		)
		(layer "In1.Cu")
	)
	(gr_line
		(start 62.142116 -62.073282)
		(end 61.242448 -60.110878)
		(stroke
			(width 0.1016)
			(type default)
		)
		(layer "In1.Cu")
	)
	(gr_line
		(start 62.38621 -63.048642)
		(end 63.286132 -65.011046)
		(stroke
			(width 0.1016)
			(type default)
		)
		(layer "In1.Cu")
	)
	(gr_line
		(start 62.579504 -65.33515)
		(end 61.679836 -63.372746)
		(stroke
			(width 0.1016)
			(type default)
		)
		(layer "In1.Cu")
	)
	(gr_line
		(start 62.848744 -61.749178)
		(end 62.142116 -62.073282)
		(stroke
			(width 0.1016)
			(type default)
		)
		(layer "In1.Cu")
	)
	(gr_line
		(start 63.286132 -65.011046)
		(end 62.579504 -65.33515)
		(stroke
			(width 0.1016)
			(type default)
		)
		(layer "In1.Cu")
	)
	(gr_line
		(start 63.797688 -59.073288)
		(end 64.69761 -61.035692)
		(stroke
			(width 0.1016)
			(type default)
		)
		(layer "In1.Cu")
	)
	(gr_line
		(start 63.990982 -61.359796)
		(end 63.091314 -59.397392)
		(stroke
			(width 0.1016)
			(type default)
		)
		(layer "In1.Cu")
	)
	(gr_line
		(start 64.191134 -62.32271)
		(end 65.091056 -64.285114)
		(stroke
			(width 0.1016)
			(type default)
		)
		(layer "In1.Cu")
	)
	(gr_line
		(start 64.384428 -64.609218)
		(end 63.48476 -62.646814)
		(stroke
			(width 0.1016)
			(type default)
		)
		(layer "In1.Cu")
	)
	(gr_line
		(start 64.69761 -61.035692)
		(end 63.990982 -61.359796)
		(stroke
			(width 0.1016)
			(type default)
		)
		(layer "In1.Cu")
	)
	(gr_line
		(start 65.091056 -64.285114)
		(end 64.384428 -64.609218)
		(stroke
			(width 0.1016)
			(type default)
		)
		(layer "In1.Cu")
	)
	(gr_line
		(start 65.909698 -61.430916)
		(end 66.80962 -63.39332)
		(stroke
			(width 0.1016)
			(type default)
		)
		(layer "In1.Cu")
	)
	(gr_line
		(start 66.102992 -63.717424)
		(end 65.203324 -61.75502)
		(stroke
			(width 0.1016)
			(type default)
		)
		(layer "In1.Cu")
	)
	(gr_line
		(start 66.80962 -63.39332)
		(end 66.102992 -63.717424)
		(stroke
			(width 0.1016)
			(type default)
		)
		(layer "In1.Cu")
	)
	(gr_line
		(start 184.879488 -406.620726)
		(end 185.209688 -406.950926)
		(stroke
			(width 0.635)
			(type default)
		)
		(layer "In1.Cu")
	)
	(gr_line
		(start 184.879488 -400.685254)
		(end 184.879488 -406.620726)
		(stroke
			(width 0.635)
			(type default)
		)
		(layer "In1.Cu")
	)
	(gr_line
		(start 185.006488 -413.197548)
		(end 185.006488 -412.123128)
		(stroke
			(width 0.635)
			(type default)
		)
		(layer "In1.Cu")
	)
	(gr_line
		(start 185.006488 -408.491182)
		(end 185.006488 -413.19958)
		(stroke
			(width 0.635)
			(type default)
		)
		(layer "In1.Cu")
	)
	(gr_line
		(start 185.209688 -408.287982)
		(end 185.006488 -408.491182)
		(stroke
			(width 0.635)
			(type default)
		)
		(layer "In1.Cu")
	)
	(gr_line
		(start 185.209688 -406.950926)
		(end 185.209688 -408.287982)
		(stroke
			(width 0.635)
			(type default)
		)
		(layer "In1.Cu")
	)
	(gr_line
		(start 188.73343 -400.685254)
		(end 184.879488 -400.685254)
		(stroke
			(width 0.635)
			(type default)
		)
		(layer "In1.Cu")
	)
	(gr_line
		(start 188.93536 -403.657054)
		(end 188.93536 -400.890232)
		(stroke
			(width 0.635)
			(type default)
		)
		(layer "In1.Cu")
	)
	(gr_line
		(start 188.93536 -400.890232)
		(end 188.73343 -400.685254)
		(stroke
			(width 0.635)
			(type default)
		)
		(layer "In1.Cu")
	)
	(gr_line
		(start 189.11316 -403.834854)
		(end 188.93536 -403.657054)
		(stroke
			(width 0.635)
			(type default)
		)
		(layer "In1.Cu")
	)
	(gr_line
		(start 189.46876 -403.834854)
		(end 189.11316 -403.834854)
		(stroke
			(width 0.635)
			(type default)
		)
		(layer "In1.Cu")
	)
	(gr_line
		(start 189.680088 -404.477982)
		(end 189.680088 -404.046182)
		(stroke
			(width 0.635)
			(type default)
		)
		(layer "In1.Cu")
	)
	(gr_line
		(start 189.680088 -404.046182)
		(end 189.46876 -403.834854)
		(stroke
			(width 0.635)
			(type default)
		)
		(layer "In1.Cu")
	)
	(gr_line
		(start 190.870332 -405.66848)
		(end 189.680088 -404.477982)
		(stroke
			(width 0.635)
			(type default)
		)
		(layer "In1.Cu")
	)
	(gr_line
		(start 192.73774 -420.9288)
		(end 185.006488 -413.197548)
		(stroke
			(width 0.635)
			(type default)
		)
		(layer "In1.Cu")
	)
	(gr_line
		(start 196.969888 -405.66848)
		(end 190.870332 -405.66848)
		(stroke
			(width 0.635)
			(type default)
		)
		(layer "In1.Cu")
	)
	(gr_line
		(start 197.416928 -420.9288)
		(end 192.73774 -420.9288)
		(stroke
			(width 0.635)
			(type default)
		)
		(layer "In1.Cu")
	)
	(gr_line
		(start 198.15048 -404.487888)
		(end 196.969888 -405.66848)
		(stroke
			(width 0.635)
			(type default)
		)
		(layer "In1.Cu")
	)
	(gr_line
		(start 198.15048 -400.893788)
		(end 198.15048 -404.487888)
		(stroke
			(width 0.635)
			(type default)
		)
		(layer "In1.Cu")
	)
	(gr_line
		(start 198.341488 -400.70278)
		(end 198.15048 -400.893788)
		(stroke
			(width 0.635)
			(type default)
		)
		(layer "In1.Cu")
	)
	(gr_line
		(start 201.995532 -400.70278)
		(end 198.341488 -400.70278)
		(stroke
			(width 0.635)
			(type default)
		)
		(layer "In1.Cu")
	)
	(gr_line
		(start 202.19416 -404.462488)
		(end 202.19416 -400.901408)
		(stroke
			(width 0.635)
			(type default)
		)
		(layer "In1.Cu")
	)
	(gr_line
		(start 202.19416 -400.901408)
		(end 201.995532 -400.70278)
		(stroke
			(width 0.635)
			(type default)
		)
		(layer "In1.Cu")
	)
	(gr_line
		(start 202.380088 -407.607008)
		(end 202.380088 -404.648416)
		(stroke
			(width 0.635)
			(type default)
		)
		(layer "In1.Cu")
	)
	(gr_line
		(start 202.380088 -404.648416)
		(end 202.19416 -404.462488)
		(stroke
			(width 0.635)
			(type default)
		)
		(layer "In1.Cu")
	)
	(gr_line
		(start 204.16012 -409.38704)
		(end 202.380088 -407.607008)
		(stroke
			(width 0.635)
			(type default)
		)
		(layer "In1.Cu")
	)
	(gr_line
		(start 206.17434 -435.523132)
		(end 207.503268 -436.85206)
		(stroke
			(width 0.635)
			(type default)
		)
		(layer "In1.Cu")
	)
	(gr_line
		(start 206.17434 -429.686212)
		(end 197.416928 -420.9288)
		(stroke
			(width 0.635)
			(type default)
		)
		(layer "In1.Cu")
	)
	(gr_line
		(start 206.17434 -429.686212)
		(end 206.17434 -435.523132)
		(stroke
			(width 0.635)
			(type default)
		)
		(layer "In1.Cu")
	)
	(gr_line
		(start 206.545688 -409.38704)
		(end 204.16012 -409.38704)
		(stroke
			(width 0.635)
			(type default)
		)
		(layer "In1.Cu")
	)
	(gr_line
		(start 207.503268 -436.85206)
		(end 228.909372 -436.85206)
		(stroke
			(width 0.635)
			(type default)
		)
		(layer "In1.Cu")
	)
	(gr_line
		(start 208.628488 -407.30424)
		(end 206.545688 -409.38704)
		(stroke
			(width 0.635)
			(type default)
		)
		(layer "In1.Cu")
	)
	(gr_line
		(start 208.628488 -404.642828)
		(end 208.628488 -407.30424)
		(stroke
			(width 0.635)
			(type default)
		)
		(layer "In1.Cu")
	)
	(gr_line
		(start 208.81848 -404.452836)
		(end 208.628488 -404.642828)
		(stroke
			(width 0.635)
			(type default)
		)
		(layer "In1.Cu")
	)
	(gr_line
		(start 208.81848 -400.893788)
		(end 208.81848 -404.452836)
		(stroke
			(width 0.635)
			(type default)
		)
		(layer "In1.Cu")
	)
	(gr_line
		(start 209.009488 -400.70278)
		(end 208.81848 -400.893788)
		(stroke
			(width 0.635)
			(type default)
		)
		(layer "In1.Cu")
	)
	(gr_line
		(start 212.668612 -400.70278)
		(end 209.009488 -400.70278)
		(stroke
			(width 0.635)
			(type default)
		)
		(layer "In1.Cu")
	)
	(gr_line
		(start 212.85962 -404.485348)
		(end 212.85962 -400.893788)
		(stroke
			(width 0.635)
			(type default)
		)
		(layer "In1.Cu")
	)
	(gr_line
		(start 212.85962 -400.893788)
		(end 212.668612 -400.70278)
		(stroke
			(width 0.635)
			(type default)
		)
		(layer "In1.Cu")
	)
	(gr_line
		(start 213.03742 -407.525728)
		(end 213.03742 -404.663148)
		(stroke
			(width 0.635)
			(type default)
		)
		(layer "In1.Cu")
	)
	(gr_line
		(start 213.03742 -404.663148)
		(end 212.85962 -404.485348)
		(stroke
			(width 0.635)
			(type default)
		)
		(layer "In1.Cu")
	)
	(gr_line
		(start 214.794592 -409.2829)
		(end 213.03742 -407.525728)
		(stroke
			(width 0.635)
			(type default)
		)
		(layer "In1.Cu")
	)
	(gr_line
		(start 217.272616 -409.2829)
		(end 214.794592 -409.2829)
		(stroke
			(width 0.635)
			(type default)
		)
		(layer "In1.Cu")
	)
	(gr_line
		(start 219.296488 -407.259028)
		(end 217.272616 -409.2829)
		(stroke
			(width 0.635)
			(type default)
		)
		(layer "In1.Cu")
	)
	(gr_line
		(start 219.296488 -404.673308)
		(end 219.296488 -407.259028)
		(stroke
			(width 0.635)
			(type default)
		)
		(layer "In1.Cu")
	)
	(gr_line
		(start 219.47886 -404.490936)
		(end 219.296488 -404.673308)
		(stroke
			(width 0.635)
			(type default)
		)
		(layer "In1.Cu")
	)
	(gr_line
		(start 219.47886 -400.906488)
		(end 219.47886 -404.490936)
		(stroke
			(width 0.635)
			(type default)
		)
		(layer "In1.Cu")
	)
	(gr_line
		(start 219.682568 -400.70278)
		(end 219.47886 -400.906488)
		(stroke
			(width 0.635)
			(type default)
		)
		(layer "In1.Cu")
	)
	(gr_line
		(start 223.323912 -400.70278)
		(end 219.682568 -400.70278)
		(stroke
			(width 0.635)
			(type default)
		)
		(layer "In1.Cu")
	)
	(gr_line
		(start 223.53524 -404.47976)
		(end 223.53524 -400.914108)
		(stroke
			(width 0.635)
			(type default)
		)
		(layer "In1.Cu")
	)
	(gr_line
		(start 223.53524 -400.914108)
		(end 223.323912 -400.70278)
		(stroke
			(width 0.635)
			(type default)
		)
		(layer "In1.Cu")
	)
	(gr_line
		(start 223.716088 -407.403808)
		(end 223.716088 -404.660608)
		(stroke
			(width 0.635)
			(type default)
		)
		(layer "In1.Cu")
	)
	(gr_line
		(start 223.716088 -404.660608)
		(end 223.53524 -404.47976)
		(stroke
			(width 0.635)
			(type default)
		)
		(layer "In1.Cu")
	)
	(gr_line
		(start 225.70694 -409.39466)
		(end 223.716088 -407.403808)
		(stroke
			(width 0.635)
			(type default)
		)
		(layer "In1.Cu")
	)
	(gr_line
		(start 227.935028 -409.39466)
		(end 225.70694 -409.39466)
		(stroke
			(width 0.635)
			(type default)
		)
		(layer "In1.Cu")
	)
	(gr_line
		(start 228.909372 -436.85206)
		(end 230.69804 -435.063392)
		(stroke
			(width 0.635)
			(type default)
		)
		(layer "In1.Cu")
	)
	(gr_line
		(start 229.939088 -407.3906)
		(end 227.935028 -409.39466)
		(stroke
			(width 0.635)
			(type default)
		)
		(layer "In1.Cu")
	)
	(gr_line
		(start 229.939088 -404.678388)
		(end 229.939088 -407.3906)
		(stroke
			(width 0.635)
			(type default)
		)
		(layer "In1.Cu")
	)
	(gr_line
		(start 230.14432 -404.473156)
		(end 229.939088 -404.678388)
		(stroke
			(width 0.635)
			(type default)
		)
		(layer "In1.Cu")
	)
	(gr_line
		(start 230.14432 -400.901408)
		(end 230.14432 -404.473156)
		(stroke
			(width 0.635)
			(type default)
		)
		(layer "In1.Cu")
	)
	(gr_line
		(start 230.345488 -400.70024)
		(end 230.14432 -400.901408)
		(stroke
			(width 0.635)
			(type default)
		)
		(layer "In1.Cu")
	)
	(gr_line
		(start 230.69804 -423.45102)
		(end 230.69804 -435.063392)
		(stroke
			(width 0.635)
			(type default)
		)
		(layer "In1.Cu")
	)
	(gr_line
		(start 233.18978 -420.95928)
		(end 230.69804 -423.45102)
		(stroke
			(width 0.635)
			(type default)
		)
		(layer "In1.Cu")
	)
	(gr_line
		(start 233.996992 -400.70024)
		(end 230.345488 -400.70024)
		(stroke
			(width 0.635)
			(type default)
		)
		(layer "In1.Cu")
	)
	(gr_line
		(start 234.19816 -404.477728)
		(end 234.19816 -400.901408)
		(stroke
			(width 0.635)
			(type default)
		)
		(layer "In1.Cu")
	)
	(gr_line
		(start 234.19816 -400.901408)
		(end 233.996992 -400.70024)
		(stroke
			(width 0.635)
			(type default)
		)
		(layer "In1.Cu")
	)
	(gr_line
		(start 235.520992 -405.80056)
		(end 234.19816 -404.477728)
		(stroke
			(width 0.635)
			(type default)
		)
		(layer "In1.Cu")
	)
	(gr_line
		(start 237.746032 -405.80056)
		(end 235.520992 -405.80056)
		(stroke
			(width 0.635)
			(type default)
		)
		(layer "In1.Cu")
	)
	(gr_line
		(start 239.10036 -406.737312)
		(end 238.682784 -406.737312)
		(stroke
			(width 0.635)
			(type default)
		)
		(layer "In1.Cu")
	)
	(gr_line
		(start 239.3315 -406.506172)
		(end 239.10036 -406.737312)
		(stroke
			(width 0.635)
			(type default)
		)
		(layer "In1.Cu")
	)
	(gr_arc
		(start 239.3315 -406.506172)
		(mid 239.359619 -406.647264)
		(end 239.439704 -406.766776)
		(stroke
			(width 0.635)
			(type default)
		)
		(layer "In1.Cu")
	)
	(gr_line
		(start 239.3315 -397.839946)
		(end 239.3315 -406.506172)
		(stroke
			(width 0.635)
			(type default)
		)
		(layer "In1.Cu")
	)
	(gr_line
		(start 239.387634 -397.701516)
		(end 239.3315 -397.839946)
		(stroke
			(width 0.635)
			(type default)
		)
		(layer "In1.Cu")
	)
	(gr_line
		(start 239.439704 -406.766776)
		(end 239.663224 -406.990296)
		(stroke
			(width 0.635)
			(type default)
		)
		(layer "In1.Cu")
	)
	(gr_line
		(start 239.441482 -397.649446)
		(end 239.387634 -397.701516)
		(stroke
			(width 0.635)
			(type default)
		)
		(layer "In1.Cu")
	)
	(gr_arc
		(start 239.663224 -406.990296)
		(mid 239.782747 -407.070378)
		(end 239.923828 -407.0985)
		(stroke
			(width 0.635)
			(type default)
		)
		(layer "In1.Cu")
	)
	(gr_line
		(start 239.699292 -407.75382)
		(end 237.746032 -405.80056)
		(stroke
			(width 0.635)
			(type default)
		)
		(layer "In1.Cu")
	)
	(gr_line
		(start 239.699292 -407.75382)
		(end 240.057432 -407.39568)
		(stroke
			(width 0.635)
			(type default)
		)
		(layer "In1.Cu")
	)
	(gr_line
		(start 239.917224 -397.173704)
		(end 239.441482 -397.649446)
		(stroke
			(width 0.635)
			(type default)
		)
		(layer "In1.Cu")
	)
	(gr_line
		(start 239.923828 -407.0985)
		(end 273.791172 -407.0985)
		(stroke
			(width 0.635)
			(type default)
		)
		(layer "In1.Cu")
	)
	(gr_line
		(start 240.057432 -407.39568)
		(end 273.646392 -407.39568)
		(stroke
			(width 0.635)
			(type default)
		)
		(layer "In1.Cu")
	)
	(gr_arc
		(start 240.177828 -397.0655)
		(mid 240.036774 -397.093687)
		(end 239.917224 -397.173704)
		(stroke
			(width 0.635)
			(type default)
		)
		(layer "In1.Cu")
	)
	(gr_line
		(start 270.481552 -420.95928)
		(end 233.18978 -420.95928)
		(stroke
			(width 0.635)
			(type default)
		)
		(layer "In1.Cu")
	)
	(gr_line
		(start 273.646392 -407.39568)
		(end 274.051776 -406.990296)
		(stroke
			(width 0.635)
			(type default)
		)
		(layer "In1.Cu")
	)
	(gr_arc
		(start 273.791172 -407.0985)
		(mid 273.932264 -407.070381)
		(end 274.051776 -406.990296)
		(stroke
			(width 0.635)
			(type default)
		)
		(layer "In1.Cu")
	)
	(gr_line
		(start 274.051776 -407.33472)
		(end 274.470876 -407.75382)
		(stroke
			(width 0.635)
			(type default)
		)
		(layer "In1.Cu")
	)
	(gr_line
		(start 274.051776 -406.990296)
		(end 274.051776 -407.33472)
		(stroke
			(width 0.635)
			(type default)
		)
		(layer "In1.Cu")
	)
	(gr_line
		(start 274.051776 -406.990296)
		(end 274.529296 -406.512776)
		(stroke
			(width 0.635)
			(type default)
		)
		(layer "In1.Cu")
	)
	(gr_line
		(start 274.117054 -397.0655)
		(end 240.177828 -397.0655)
		(stroke
			(width 0.635)
			(type default)
		)
		(layer "In1.Cu")
	)
	(gr_line
		(start 274.255484 -397.121634)
		(end 274.117054 -397.0655)
		(stroke
			(width 0.635)
			(type default)
		)
		(layer "In1.Cu")
	)
	(gr_line
		(start 274.307554 -397.175482)
		(end 274.255484 -397.121634)
		(stroke
			(width 0.635)
			(type default)
		)
		(layer "In1.Cu")
	)
	(gr_arc
		(start 274.529296 -406.512776)
		(mid 274.609378 -406.393253)
		(end 274.6375 -406.252172)
		(stroke
			(width 0.635)
			(type default)
		)
		(layer "In1.Cu")
	)
	(gr_line
		(start 274.529296 -397.397224)
		(end 274.307554 -397.175482)
		(stroke
			(width 0.635)
			(type default)
		)
		(layer "In1.Cu")
	)
	(gr_line
		(start 274.6375 -406.252172)
		(end 274.6375 -397.657828)
		(stroke
			(width 0.635)
			(type default)
		)
		(layer "In1.Cu")
	)
	(gr_arc
		(start 274.6375 -397.657828)
		(mid 274.609313 -397.516774)
		(end 274.529296 -397.397224)
		(stroke
			(width 0.635)
			(type default)
		)
		(layer "In1.Cu")
	)
	(gr_line
		(start 275.0693 -405.960072)
		(end 275.351748 -406.24252)
		(stroke
			(width 0.635)
			(type default)
		)
		(layer "In1.Cu")
	)
	(gr_line
		(start 275.0693 -397.505428)
		(end 275.0693 -405.960072)
		(stroke
			(width 0.635)
			(type default)
		)
		(layer "In1.Cu")
	)
	(gr_line
		(start 275.351748 -406.24252)
		(end 278.143208 -406.24252)
		(stroke
			(width 0.635)
			(type default)
		)
		(layer "In1.Cu")
	)
	(gr_line
		(start 275.509228 -397.0655)
		(end 275.0693 -397.505428)
		(stroke
			(width 0.635)
			(type default)
		)
		(layer "In1.Cu")
	)
	(gr_line
		(start 275.680932 -415.7599)
		(end 270.481552 -420.95928)
		(stroke
			(width 0.635)
			(type default)
		)
		(layer "In1.Cu")
	)
	(gr_line
		(start 278.143208 -406.24252)
		(end 278.145748 -406.23998)
		(stroke
			(width 0.635)
			(type default)
		)
		(layer "In1.Cu")
	)
	(gr_line
		(start 278.145748 -406.23998)
		(end 281.037792 -406.23998)
		(stroke
			(width 0.635)
			(type default)
		)
		(layer "In1.Cu")
	)
	(gr_line
		(start 279.927812 -415.7599)
		(end 275.680932 -415.7599)
		(stroke
			(width 0.635)
			(type default)
		)
		(layer "In1.Cu")
	)
	(gr_line
		(start 279.927812 -415.7599)
		(end 280.51506 -415.172652)
		(stroke
			(width 0.635)
			(type default)
		)
		(layer "In1.Cu")
	)
	(gr_line
		(start 280.100532 -407.75382)
		(end 239.699292 -407.75382)
		(stroke
			(width 0.635)
			(type default)
		)
		(layer "In1.Cu")
	)
	(gr_line
		(start 280.51506 -415.172652)
		(end 280.51506 -408.168348)
		(stroke
			(width 0.635)
			(type default)
		)
		(layer "In1.Cu")
	)
	(gr_line
		(start 280.51506 -408.168348)
		(end 280.100532 -407.75382)
		(stroke
			(width 0.635)
			(type default)
		)
		(layer "In1.Cu")
	)
	(gr_line
		(start 280.83764 -397.0655)
		(end 275.509228 -397.0655)
		(stroke
			(width 0.635)
			(type default)
		)
		(layer "In1.Cu")
	)
	(gr_line
		(start 281.037792 -406.23998)
		(end 281.369008 -405.908764)
		(stroke
			(width 0.635)
			(type default)
		)
		(layer "In1.Cu")
	)
	(gr_line
		(start 281.369008 -405.908764)
		(end 281.369008 -397.596868)
		(stroke
			(width 0.635)
			(type default)
		)
		(layer "In1.Cu")
	)
	(gr_line
		(start 281.369008 -397.596868)
		(end 280.83764 -397.0655)
		(stroke
			(width 0.635)
			(type default)
		)
		(layer "In1.Cu")
	)
	(gr_line
		(start 393.758674 -91.044014)
		(end 394.99667 -89.275666)
		(stroke
			(width 0.1016)
			(type default)
		)
		(layer "In1.Cu")
	)
	(gr_line
		(start 394.395198 -91.489784)
		(end 393.758674 -91.044014)
		(stroke
			(width 0.1016)
			(type default)
		)
		(layer "In1.Cu")
	)
	(gr_line
		(start 394.742162 -87.999824)
		(end 395.980158 -86.231476)
		(stroke
			(width 0.1016)
			(type default)
		)
		(layer "In1.Cu")
	)
	(gr_line
		(start 395.378686 -88.445594)
		(end 394.742162 -87.999824)
		(stroke
			(width 0.1016)
			(type default)
		)
		(layer "In1.Cu")
	)
	(gr_line
		(start 395.409674 -91.946984)
		(end 396.64767 -90.178636)
		(stroke
			(width 0.1016)
			(type default)
		)
		(layer "In1.Cu")
	)
	(gr_line
		(start 395.633702 -89.721182)
		(end 394.395198 -91.489784)
		(stroke
			(width 0.1016)
			(type default)
		)
		(layer "In1.Cu")
	)
	(gr_line
		(start 396.046198 -92.392754)
		(end 395.409674 -91.946984)
		(stroke
			(width 0.1016)
			(type default)
		)
		(layer "In1.Cu")
	)
	(gr_line
		(start 396.61719 -86.676992)
		(end 395.378686 -88.445594)
		(stroke
			(width 0.1016)
			(type default)
		)
		(layer "In1.Cu")
	)
	(gr_line
		(start 396.94485 -88.132666)
		(end 398.182846 -86.364318)
		(stroke
			(width 0.1016)
			(type default)
		)
		(layer "In1.Cu")
	)
	(gr_line
		(start 397.094456 -92.801694)
		(end 398.332452 -91.033346)
		(stroke
			(width 0.1016)
			(type default)
		)
		(layer "In1.Cu")
	)
	(gr_line
		(start 397.284702 -90.624152)
		(end 396.046198 -92.392754)
		(stroke
			(width 0.1016)
			(type default)
		)
		(layer "In1.Cu")
	)
	(gr_line
		(start 397.581374 -88.578436)
		(end 396.94485 -88.132666)
		(stroke
			(width 0.1016)
			(type default)
		)
		(layer "In1.Cu")
	)
	(gr_line
		(start 397.73098 -93.247464)
		(end 397.094456 -92.801694)
		(stroke
			(width 0.1016)
			(type default)
		)
		(layer "In1.Cu")
	)
	(gr_line
		(start 397.953484 -95.59036)
		(end 399.054066 -93.733112)
		(stroke
			(width 0.1016)
			(type default)
		)
		(layer "In1.Cu")
	)
	(gr_line
		(start 398.622012 -95.9866)
		(end 397.953484 -95.59036)
		(stroke
			(width 0.1016)
			(type default)
		)
		(layer "In1.Cu")
	)
	(gr_line
		(start 398.78127 -88.770968)
		(end 400.019266 -87.00262)
		(stroke
			(width 0.1016)
			(type default)
		)
		(layer "In1.Cu")
	)
	(gr_line
		(start 398.819878 -86.809834)
		(end 397.581374 -88.578436)
		(stroke
			(width 0.1016)
			(type default)
		)
		(layer "In1.Cu")
	)
	(gr_line
		(start 398.969484 -91.478862)
		(end 397.73098 -93.247464)
		(stroke
			(width 0.1016)
			(type default)
		)
		(layer "In1.Cu")
	)
	(gr_line
		(start 399.417794 -89.216738)
		(end 398.78127 -88.770968)
		(stroke
			(width 0.1016)
			(type default)
		)
		(layer "In1.Cu")
	)
	(gr_line
		(start 399.71599 -96.354646)
		(end 400.816572 -94.497398)
		(stroke
			(width 0.1016)
			(type default)
		)
		(layer "In1.Cu")
	)
	(gr_line
		(start 399.722848 -94.129352)
		(end 398.622012 -95.9866)
		(stroke
			(width 0.1016)
			(type default)
		)
		(layer "In1.Cu")
	)
	(gr_line
		(start 400.384518 -96.750886)
		(end 399.71599 -96.354646)
		(stroke
			(width 0.1016)
			(type default)
		)
		(layer "In1.Cu")
	)
	(gr_line
		(start 400.603466 -92.998544)
		(end 401.704048 -91.141296)
		(stroke
			(width 0.1016)
			(type default)
		)
		(layer "In1.Cu")
	)
	(gr_line
		(start 400.656298 -87.448136)
		(end 399.417794 -89.216738)
		(stroke
			(width 0.1016)
			(type default)
		)
		(layer "In1.Cu")
	)
	(gr_line
		(start 401.271994 -93.394784)
		(end 400.603466 -92.998544)
		(stroke
			(width 0.1016)
			(type default)
		)
		(layer "In1.Cu")
	)
	(gr_line
		(start 401.473924 -97.203768)
		(end 402.574506 -95.34652)
		(stroke
			(width 0.1016)
			(type default)
		)
		(layer "In1.Cu")
	)
	(gr_line
		(start 401.485354 -94.893638)
		(end 400.384518 -96.750886)
		(stroke
			(width 0.1016)
			(type default)
		)
		(layer "In1.Cu")
	)
	(gr_line
		(start 402.108162 -94.262702)
		(end 403.208744 -92.405454)
		(stroke
			(width 0.1016)
			(type default)
		)
		(layer "In1.Cu")
	)
	(gr_line
		(start 402.142452 -97.600008)
		(end 401.473924 -97.203768)
		(stroke
			(width 0.1016)
			(type default)
		)
		(layer "In1.Cu")
	)
	(gr_line
		(start 402.37283 -91.537536)
		(end 401.271994 -93.394784)
		(stroke
			(width 0.1016)
			(type default)
		)
		(layer "In1.Cu")
	)
	(gr_line
		(start 402.77669 -94.658942)
		(end 402.108162 -94.262702)
		(stroke
			(width 0.1016)
			(type default)
		)
		(layer "In1.Cu")
	)
	(gr_line
		(start 403.243288 -95.74276)
		(end 402.142452 -97.600008)
		(stroke
			(width 0.1016)
			(type default)
		)
		(layer "In1.Cu")
	)
	(gr_line
		(start 403.246336 -97.953068)
		(end 404.346918 -96.09582)
		(stroke
			(width 0.1016)
			(type default)
		)
		(layer "In1.Cu")
	)
	(gr_line
		(start 403.81682 -95.120206)
		(end 404.917402 -93.262958)
		(stroke
			(width 0.1016)
			(type default)
		)
		(layer "In1.Cu")
	)
	(gr_line
		(start 403.877526 -92.801694)
		(end 402.77669 -94.658942)
		(stroke
			(width 0.1016)
			(type default)
		)
		(layer "In1.Cu")
	)
	(gr_line
		(start 403.914864 -98.349308)
		(end 403.246336 -97.953068)
		(stroke
			(width 0.1016)
			(type default)
		)
		(layer "In1.Cu")
	)
	(gr_line
		(start 404.485348 -95.516446)
		(end 403.81682 -95.120206)
		(stroke
			(width 0.1016)
			(type default)
		)
		(layer "In1.Cu")
	)
	(gr_line
		(start 405.0157 -96.49206)
		(end 403.914864 -98.349308)
		(stroke
			(width 0.1016)
			(type default)
		)
		(layer "In1.Cu")
	)
	(gr_line
		(start 405.092916 -98.577654)
		(end 406.193498 -96.720406)
		(stroke
			(width 0.1016)
			(type default)
		)
		(layer "In1.Cu")
	)
	(gr_line
		(start 405.586184 -93.659198)
		(end 404.485348 -95.516446)
		(stroke
			(width 0.1016)
			(type default)
		)
		(layer "In1.Cu")
	)
	(gr_line
		(start 405.613362 -95.829882)
		(end 406.713944 -93.972634)
		(stroke
			(width 0.1016)
			(type default)
		)
		(layer "In1.Cu")
	)
	(gr_line
		(start 405.761444 -98.973894)
		(end 405.092916 -98.577654)
		(stroke
			(width 0.1016)
			(type default)
		)
		(layer "In1.Cu")
	)
	(gr_line
		(start 406.28189 -96.226122)
		(end 405.613362 -95.829882)
		(stroke
			(width 0.1016)
			(type default)
		)
		(layer "In1.Cu")
	)
	(gr_line
		(start 406.86228 -97.116646)
		(end 405.761444 -98.973894)
		(stroke
			(width 0.1016)
			(type default)
		)
		(layer "In1.Cu")
	)
	(gr_line
		(start 407.31186 -96.731836)
		(end 408.412442 -94.874588)
		(stroke
			(width 0.1016)
			(type default)
		)
		(layer "In1.Cu")
	)
	(gr_line
		(start 407.382726 -94.368874)
		(end 406.28189 -96.226122)
		(stroke
			(width 0.1016)
			(type default)
		)
		(layer "In1.Cu")
	)
	(gr_line
		(start 407.980388 -97.128076)
		(end 407.31186 -96.731836)
		(stroke
			(width 0.1016)
			(type default)
		)
		(layer "In1.Cu")
	)
	(gr_line
		(start 409.081224 -95.270828)
		(end 407.980388 -97.128076)
		(stroke
			(width 0.1016)
			(type default)
		)
		(layer "In1.Cu")
	)
	(gr_poly
		(pts
			(xy 84.52485 -276.350476) (xy 84.563204 -276.328378) (xy 84.385404 -276.02053) (xy 84.34705 -276.042628)
			(xy 84.238592 -276.159468) (xy 84.369402 -276.386036)
		)
		(stroke
			(width 0)
			(type solid)
		)
		(fill yes)
		(layer "In2.Cu")
		(net "M_B_CPU1_SA_DQ<7>")
	)
	(gr_poly
		(pts
			(xy 84.55533 -244.940582) (xy 84.50834 -244.788182) (xy 84.24672 -244.788182) (xy 84.19973 -244.940582)
			(xy 84.19973 -244.985032) (xy 84.55533 -244.985032)
		)
		(stroke
			(width 0)
			(type solid)
		)
		(fill yes)
		(layer "In2.Cu")
		(net "M_B_CPU1_SB_CS_N<1>")
	)
	(gr_poly
		(pts
			(xy 84.55533 -244.532658) (xy 84.55533 -244.488208) (xy 84.19973 -244.488208) (xy 84.19973 -244.532658)
			(xy 84.24672 -244.685058) (xy 84.50834 -244.685058)
		)
		(stroke
			(width 0)
			(type solid)
		)
		(fill yes)
		(layer "In2.Cu")
		(net "M_B_CPU1_SB_CB<6>")
	)
	(gr_poly
		(pts
			(xy 84.55533 -240.057178) (xy 84.50834 -239.904778) (xy 84.24672 -239.904778) (xy 84.19973 -240.057178)
			(xy 84.19973 -240.101628) (xy 84.55533 -240.101628)
		)
		(stroke
			(width 0)
			(type solid)
		)
		(fill yes)
		(layer "In2.Cu")
		(net "M_B_CPU1_SB_CB<1>")
	)
	(gr_poly
		(pts
			(xy 84.55533 -235.174282) (xy 84.50834 -235.021882) (xy 84.24672 -235.021882) (xy 84.19973 -235.174282)
			(xy 84.19973 -235.218478) (xy 84.55533 -235.218478)
		)
		(stroke
			(width 0)
			(type solid)
		)
		(fill yes)
		(layer "In2.Cu")
		(net "M_A_CPU1_SB_DQ<7>")
	)
	(gr_poly
		(pts
			(xy 84.55533 -234.76585) (xy 84.55533 -234.721654) (xy 84.19973 -234.721654) (xy 84.19973 -234.76585)
			(xy 84.24672 -234.91825) (xy 84.50834 -234.91825)
		)
		(stroke
			(width 0)
			(type solid)
		)
		(fill yes)
		(layer "In2.Cu")
		(net "M_B_CPU1_SB_DQ<8>")
	)
	(gr_poly
		(pts
			(xy 84.563966 -246.568722) (xy 84.516976 -246.416322) (xy 84.255356 -246.416322) (xy 84.208366 -246.568722)
			(xy 84.208366 -246.613172) (xy 84.563966 -246.613172)
		)
		(stroke
			(width 0)
			(type solid)
		)
		(fill yes)
		(layer "In2.Cu")
		(net "M_B_CPU1_SB_PAR")
	)
	(gr_poly
		(pts
			(xy 84.563966 -246.16029) (xy 84.563966 -246.11584) (xy 84.208366 -246.11584) (xy 84.208366 -246.16029)
			(xy 84.255356 -246.31269) (xy 84.516976 -246.31269)
		)
		(stroke
			(width 0)
			(type solid)
		)
		(fill yes)
		(layer "In2.Cu")
		(net "M_B_CPU1_SB_CS_N<0>")
	)
	(gr_poly
		(pts
			(xy 84.563966 -238.430054) (xy 84.516976 -238.277654) (xy 84.255356 -238.277654) (xy 84.208366 -238.430054)
			(xy 84.208366 -238.47425) (xy 84.563966 -238.47425)
		)
		(stroke
			(width 0)
			(type solid)
		)
		(fill yes)
		(layer "In2.Cu")
		(net "M_A_CPU1_SB_DQ<3>")
	)
	(gr_poly
		(pts
			(xy 84.569554 -275.450046) (xy 84.5312 -275.427948) (xy 84.375752 -275.392388) (xy 84.244942 -275.618956)
			(xy 84.3534 -275.735796) (xy 84.391754 -275.757894)
		)
		(stroke
			(width 0)
			(type solid)
		)
		(fill yes)
		(layer "In2.Cu")
		(net "M_B_CPU1_SA_DQ<7>")
	)
	(gr_poly
		(pts
			(xy 84.572348 -243.31295) (xy 84.525358 -243.16055) (xy 84.263738 -243.16055) (xy 84.216748 -243.31295)
			(xy 84.216748 -243.3574) (xy 84.572348 -243.3574)
		)
		(stroke
			(width 0)
			(type solid)
		)
		(fill yes)
		(layer "In2.Cu")
		(net "M_B_CPU1_SB_CB<5>")
	)
	(gr_poly
		(pts
			(xy 84.572348 -238.021622) (xy 84.572348 -237.977172) (xy 84.216748 -237.977172) (xy 84.216748 -238.021622)
			(xy 84.263738 -238.174022) (xy 84.525358 -238.174022)
		)
		(stroke
			(width 0)
			(type solid)
		)
		(fill yes)
		(layer "In2.Cu")
		(net "M_A_CPU1_SB_DQS_DP<0>")
	)
	(gr_poly
		(pts
			(xy 84.673694 -265.92403) (xy 84.673694 -265.87958) (xy 84.318094 -265.87958) (xy 84.318094 -265.92403)
			(xy 84.365084 -266.07643) (xy 84.626704 -266.07643)
		)
		(stroke
			(width 0)
			(type solid)
		)
		(fill yes)
		(layer "In2.Cu")
		(net "M_B_CPU1_SA_DQS_DP<2>")
	)
	(gr_poly
		(pts
			(xy 84.673694 -264.70483) (xy 84.626704 -264.55243) (xy 84.365084 -264.55243) (xy 84.318094 -264.70483)
			(xy 84.318094 -264.749026) (xy 84.673694 -264.749026)
		)
		(stroke
			(width 0)
			(type solid)
		)
		(fill yes)
		(layer "In2.Cu")
		(net "M_B_CPU1_SA_DQS_DP<7>")
	)
	(gr_poly
		(pts
			(xy 84.673694 -264.29589) (xy 84.673694 -264.251694) (xy 84.318094 -264.251694) (xy 84.318094 -264.29589)
			(xy 84.365084 -264.44829) (xy 84.626704 -264.44829)
		)
		(stroke
			(width 0)
			(type solid)
		)
		(fill yes)
		(layer "In2.Cu")
		(net "M_B_CPU1_SA_DQ<20>")
	)
	(gr_poly
		(pts
			(xy 84.673694 -262.668258) (xy 84.673694 -262.623808) (xy 84.318094 -262.623808) (xy 84.318094 -262.668258)
			(xy 84.365084 -262.820658) (xy 84.626704 -262.820658)
		)
		(stroke
			(width 0)
			(type solid)
		)
		(fill yes)
		(layer "In2.Cu")
		(net "M_B_CPU1_SA_CB<0>")
	)
	(gr_poly
		(pts
			(xy 84.673694 -261.449058) (xy 84.626704 -261.296658) (xy 84.365084 -261.296658) (xy 84.318094 -261.449058)
			(xy 84.318094 -261.493508) (xy 84.673694 -261.493508)
		)
		(stroke
			(width 0)
			(type solid)
		)
		(fill yes)
		(layer "In2.Cu")
		(net "M_B_CPU1_SA_CB<3>")
	)
	(gr_poly
		(pts
			(xy 84.673694 -261.040626) (xy 84.673694 -260.996176) (xy 84.318094 -260.996176) (xy 84.318094 -261.040626)
			(xy 84.365084 -261.193026) (xy 84.626704 -261.193026)
		)
		(stroke
			(width 0)
			(type solid)
		)
		(fill yes)
		(layer "In2.Cu")
		(net "M_B_CPU1_SA_DQS_DP<4>")
	)
	(gr_poly
		(pts
			(xy 84.673694 -259.821426) (xy 84.626704 -259.669026) (xy 84.365084 -259.669026) (xy 84.318094 -259.821426)
			(xy 84.318094 -259.865622) (xy 84.673694 -259.865622)
		)
		(stroke
			(width 0)
			(type solid)
		)
		(fill yes)
		(layer "In2.Cu")
		(net "M_B_CPU1_SA_DQS_DP<9>")
	)
	(gr_poly
		(pts
			(xy 84.673694 -259.412486) (xy 84.673694 -259.36829) (xy 84.318094 -259.36829) (xy 84.318094 -259.412486)
			(xy 84.365084 -259.564886) (xy 84.626704 -259.564886)
		)
		(stroke
			(width 0)
			(type solid)
		)
		(fill yes)
		(layer "In2.Cu")
		(net "M_B_CPU1_SA_CB<4>")
	)
	(gr_poly
		(pts
			(xy 85.02523 -243.718842) (xy 85.02523 -243.674392) (xy 84.66963 -243.674392) (xy 84.66963 -243.718842)
			(xy 84.71662 -243.871242) (xy 84.97824 -243.871242)
		)
		(stroke
			(width 0)
			(type solid)
		)
		(fill yes)
		(layer "In2.Cu")
		(net "M_B_CPU1_SB_CB<7>")
	)
	(gr_poly
		(pts
			(xy 85.02523 -242.499134) (xy 84.97824 -242.346734) (xy 84.71662 -242.346734) (xy 84.66963 -242.499134)
			(xy 84.66963 -242.54333) (xy 85.02523 -242.54333)
		)
		(stroke
			(width 0)
			(type solid)
		)
		(fill yes)
		(layer "In2.Cu")
		(net "M_B_CPU1_SB_DQS_DP<4>")
	)
	(gr_poly
		(pts
			(xy 85.02523 -237.61573) (xy 84.97824 -237.46333) (xy 84.71662 -237.46333) (xy 84.66963 -237.61573)
			(xy 84.66963 -237.66018) (xy 85.02523 -237.66018)
		)
		(stroke
			(width 0)
			(type solid)
		)
		(fill yes)
		(layer "In2.Cu")
		(net "M_A_CPU1_SB_DQS_DN<0>")
	)
	(gr_poly
		(pts
			(xy 85.02523 -237.207806) (xy 85.02523 -237.163356) (xy 84.66963 -237.163356) (xy 84.66963 -237.207806)
			(xy 84.71662 -237.360206) (xy 84.97824 -237.360206)
		)
		(stroke
			(width 0)
			(type solid)
		)
		(fill yes)
		(layer "In2.Cu")
		(net "M_A_CPU1_SB_DQS_DN<5>")
	)
	(gr_poly
		(pts
			(xy 85.02523 -232.732326) (xy 84.97824 -232.579926) (xy 84.71662 -232.579926) (xy 84.66963 -232.732326)
			(xy 84.66963 -232.776776) (xy 85.02523 -232.776776)
		)
		(stroke
			(width 0)
			(type solid)
		)
		(fill yes)
		(layer "In2.Cu")
		(net "M_B_CPU1_SB_DQS_DN<1>")
	)
	(gr_poly
		(pts
			(xy 85.02523 -232.324402) (xy 85.02523 -232.279952) (xy 84.66963 -232.279952) (xy 84.66963 -232.324402)
			(xy 84.71662 -232.476802) (xy 84.97824 -232.476802)
		)
		(stroke
			(width 0)
			(type solid)
		)
		(fill yes)
		(layer "In2.Cu")
		(net "M_B_CPU1_SB_DQS_DN<6>")
	)
	(gr_poly
		(pts
			(xy 85.02523 -225.813366) (xy 85.02523 -225.768916) (xy 84.66963 -225.768916) (xy 84.66963 -225.813366)
			(xy 84.71662 -225.965766) (xy 84.97824 -225.965766)
		)
		(stroke
			(width 0)
			(type solid)
		)
		(fill yes)
		(layer "In2.Cu")
		(net "M_B_CPU1_SB_DQ<17>")
	)
	(gr_poly
		(pts
			(xy 85.027516 -242.090702) (xy 85.027516 -242.046506) (xy 84.671916 -242.046506) (xy 84.671916 -242.090702)
			(xy 84.718906 -242.243102) (xy 84.980526 -242.243102)
		)
		(stroke
			(width 0)
			(type solid)
		)
		(fill yes)
		(layer "In2.Cu")
		(net "M_B_CPU1_SB_DQS_DP<9>")
	)
	(gr_poly
		(pts
			(xy 85.033104 -274.647152) (xy 84.99475 -274.625054) (xy 84.839302 -274.589494) (xy 84.708492 -274.816062)
			(xy 84.81695 -274.932902) (xy 84.855304 -274.955)
		)
		(stroke
			(width 0)
			(type solid)
		)
		(fill yes)
		(layer "In2.Cu")
		(net "M_B_CPU1_SA_DQ<7>")
	)
	(gr_poly
		(pts
			(xy 85.033866 -247.382538) (xy 84.986876 -247.230138) (xy 84.725256 -247.230138) (xy 84.678266 -247.382538)
			(xy 84.678266 -247.426988) (xy 85.033866 -247.426988)
		)
		(stroke
			(width 0)
			(type solid)
		)
		(fill yes)
		(layer "In2.Cu")
		(net "M_B_CPU1_SB_CA<5>")
	)
	(gr_poly
		(pts
			(xy 85.033866 -246.974106) (xy 85.033866 -246.929656) (xy 84.678266 -246.929656) (xy 84.678266 -246.974106)
			(xy 84.725256 -247.126506) (xy 84.986876 -247.126506)
		)
		(stroke
			(width 0)
			(type solid)
		)
		(fill yes)
		(layer "In2.Cu")
		(net "M_B_CPU1_SB_CA<6>")
	)
	(gr_poly
		(pts
			(xy 85.033866 -245.754906) (xy 84.986876 -245.602506) (xy 84.725256 -245.602506) (xy 84.678266 -245.754906)
			(xy 84.678266 -245.799356) (xy 85.033866 -245.799356)
		)
		(stroke
			(width 0)
			(type solid)
		)
		(fill yes)
		(layer "In2.Cu")
		(net "M_B_CPU1_SB_CS_N<2>")
	)
	(gr_poly
		(pts
			(xy 85.033866 -240.871502) (xy 84.986876 -240.719102) (xy 84.725256 -240.719102) (xy 84.678266 -240.871502)
			(xy 84.678266 -240.915952) (xy 85.033866 -240.915952)
		)
		(stroke
			(width 0)
			(type solid)
		)
		(fill yes)
		(layer "In2.Cu")
		(net "M_B_CPU1_SB_CB<0>")
	)
	(gr_poly
		(pts
			(xy 85.033866 -238.83493) (xy 85.033866 -238.790734) (xy 84.678266 -238.790734) (xy 84.678266 -238.83493)
			(xy 84.725256 -238.98733) (xy 84.986876 -238.98733)
		)
		(stroke
			(width 0)
			(type solid)
		)
		(fill yes)
		(layer "In2.Cu")
		(net "M_A_CPU1_SB_DQ<1>")
	)
	(gr_poly
		(pts
			(xy 85.033866 -235.988098) (xy 84.986876 -235.835698) (xy 84.725256 -235.835698) (xy 84.678266 -235.988098)
			(xy 84.678266 -236.032548) (xy 85.033866 -236.032548)
		)
		(stroke
			(width 0)
			(type solid)
		)
		(fill yes)
		(layer "In2.Cu")
		(net "M_A_CPU1_SB_DQ<6>")
	)
	(gr_poly
		(pts
			(xy 85.033866 -233.952034) (xy 85.033866 -233.907584) (xy 84.678266 -233.907584) (xy 84.678266 -233.952034)
			(xy 84.725256 -234.104434) (xy 84.986876 -234.104434)
		)
		(stroke
			(width 0)
			(type solid)
		)
		(fill yes)
		(layer "In2.Cu")
		(net "M_B_CPU1_SB_DQ<9>")
	)
	(gr_poly
		(pts
			(xy 85.042248 -245.346474) (xy 85.042248 -245.302278) (xy 84.686648 -245.302278) (xy 84.686648 -245.346474)
			(xy 84.733638 -245.498874) (xy 84.995258 -245.498874)
		)
		(stroke
			(width 0)
			(type solid)
		)
		(fill yes)
		(layer "In2.Cu")
		(net "M_B_CPU1_SB_CS_N<3>")
	)
	(gr_poly
		(pts
			(xy 85.042248 -244.126766) (xy 84.995258 -243.974366) (xy 84.733638 -243.974366) (xy 84.686648 -244.126766)
			(xy 84.686648 -244.171216) (xy 85.042248 -244.171216)
		)
		(stroke
			(width 0)
			(type solid)
		)
		(fill yes)
		(layer "In2.Cu")
		(net "M_B_CPU1_SB_CB<4>")
	)
	(gr_poly
		(pts
			(xy 85.042248 -240.46307) (xy 85.042248 -240.418874) (xy 84.686648 -240.418874) (xy 84.686648 -240.46307)
			(xy 84.733638 -240.61547) (xy 84.995258 -240.61547)
		)
		(stroke
			(width 0)
			(type solid)
		)
		(fill yes)
		(layer "In2.Cu")
		(net "M_B_CPU1_SB_CB<3>")
	)
	(gr_poly
		(pts
			(xy 85.042248 -239.243362) (xy 84.995258 -239.090962) (xy 84.733638 -239.090962) (xy 84.686648 -239.243362)
			(xy 84.686648 -239.287812) (xy 85.042248 -239.287812)
		)
		(stroke
			(width 0)
			(type solid)
		)
		(fill yes)
		(layer "In2.Cu")
		(net "M_A_CPU1_SB_DQ<2>")
	)
	(gr_poly
		(pts
			(xy 85.042248 -235.579666) (xy 85.042248 -235.53547) (xy 84.686648 -235.53547) (xy 84.686648 -235.579666)
			(xy 84.733638 -235.732066) (xy 84.995258 -235.732066)
		)
		(stroke
			(width 0)
			(type solid)
		)
		(fill yes)
		(layer "In2.Cu")
		(net "M_A_CPU1_SB_DQ<5>")
	)
	(gr_poly
		(pts
			(xy 85.042248 -234.360466) (xy 84.995258 -234.208066) (xy 84.733638 -234.208066) (xy 84.686648 -234.360466)
			(xy 84.686648 -234.404662) (xy 85.042248 -234.404662)
		)
		(stroke
			(width 0)
			(type solid)
		)
		(fill yes)
		(layer "In2.Cu")
		(net "M_B_CPU1_SB_DQ<10>")
	)
	(gr_poly
		(pts
			(xy 85.114384 -276.560788) (xy 85.222842 -276.443948) (xy 85.092032 -276.21738) (xy 84.936584 -276.25294)
			(xy 84.89823 -276.275038) (xy 85.07603 -276.582886)
		)
		(stroke
			(width 0)
			(type solid)
		)
		(fill yes)
		(layer "In2.Cu")
		(net "M_B_CPU1_SA_DQ<5>")
	)
	(gr_poly
		(pts
			(xy 85.143594 -267.146278) (xy 85.096604 -266.993878) (xy 84.834984 -266.993878) (xy 84.787994 -267.146278)
			(xy 84.787994 -267.190474) (xy 85.143594 -267.190474)
		)
		(stroke
			(width 0)
			(type solid)
		)
		(fill yes)
		(layer "In2.Cu")
		(net "M_B_CPU1_SA_DQ<18>")
	)
	(gr_poly
		(pts
			(xy 85.143594 -266.737846) (xy 85.143594 -266.693396) (xy 84.787994 -266.693396) (xy 84.787994 -266.737846)
			(xy 84.834984 -266.890246) (xy 85.096604 -266.890246)
		)
		(stroke
			(width 0)
			(type solid)
		)
		(fill yes)
		(layer "In2.Cu")
		(net "M_B_CPU1_SA_DQ<17>")
	)
	(gr_poly
		(pts
			(xy 85.143594 -265.518646) (xy 85.096604 -265.366246) (xy 84.834984 -265.366246) (xy 84.787994 -265.518646)
			(xy 84.787994 -265.562842) (xy 85.143594 -265.562842)
		)
		(stroke
			(width 0)
			(type solid)
		)
		(fill yes)
		(layer "In2.Cu")
		(net "M_B_CPU1_SA_DQS_DN<2>")
	)
	(gr_poly
		(pts
			(xy 85.143594 -265.109706) (xy 85.143594 -265.06551) (xy 84.787994 -265.06551) (xy 84.787994 -265.109706)
			(xy 84.834984 -265.262106) (xy 85.096604 -265.262106)
		)
		(stroke
			(width 0)
			(type solid)
		)
		(fill yes)
		(layer "In2.Cu")
		(net "M_B_CPU1_SA_DQS_DN<7>")
	)
	(gr_poly
		(pts
			(xy 85.143594 -263.891014) (xy 85.096604 -263.738614) (xy 84.834984 -263.738614) (xy 84.787994 -263.891014)
			(xy 84.787994 -263.93521) (xy 85.143594 -263.93521)
		)
		(stroke
			(width 0)
			(type solid)
		)
		(fill yes)
		(layer "In2.Cu")
		(net "M_B_CPU1_SA_DQ<22>")
	)
	(gr_poly
		(pts
			(xy 85.143594 -263.482074) (xy 85.143594 -263.437878) (xy 84.787994 -263.437878) (xy 84.787994 -263.482074)
			(xy 84.834984 -263.634474) (xy 85.096604 -263.634474)
		)
		(stroke
			(width 0)
			(type solid)
		)
		(fill yes)
		(layer "In2.Cu")
		(net "M_B_CPU1_SA_DQ<21>")
	)
	(gr_poly
		(pts
			(xy 85.143594 -262.262874) (xy 85.096604 -262.110474) (xy 84.834984 -262.110474) (xy 84.787994 -262.262874)
			(xy 84.787994 -262.307324) (xy 85.143594 -262.307324)
		)
		(stroke
			(width 0)
			(type solid)
		)
		(fill yes)
		(layer "In2.Cu")
		(net "M_B_CPU1_SA_CB<2>")
	)
	(gr_poly
		(pts
			(xy 85.143594 -261.854442) (xy 85.143594 -261.809992) (xy 84.787994 -261.809992) (xy 84.787994 -261.854442)
			(xy 84.834984 -262.006842) (xy 85.096604 -262.006842)
		)
		(stroke
			(width 0)
			(type solid)
		)
		(fill yes)
		(layer "In2.Cu")
		(net "M_B_CPU1_SA_CB<1>")
	)
	(gr_poly
		(pts
			(xy 85.143594 -260.635242) (xy 85.096604 -260.482842) (xy 84.834984 -260.482842) (xy 84.787994 -260.635242)
			(xy 84.787994 -260.679438) (xy 85.143594 -260.679438)
		)
		(stroke
			(width 0)
			(type solid)
		)
		(fill yes)
		(layer "In2.Cu")
		(net "M_B_CPU1_SA_DQS_DN<4>")
	)
	(gr_poly
		(pts
			(xy 85.143594 -260.226302) (xy 85.143594 -260.182106) (xy 84.787994 -260.182106) (xy 84.787994 -260.226302)
			(xy 84.834984 -260.378702) (xy 85.096604 -260.378702)
		)
		(stroke
			(width 0)
			(type solid)
		)
		(fill yes)
		(layer "In2.Cu")
		(net "M_B_CPU1_SA_DQS_DN<9>")
	)
	(gr_poly
		(pts
			(xy 85.143594 -259.00761) (xy 85.096604 -258.85521) (xy 84.834984 -258.85521) (xy 84.787994 -259.00761)
			(xy 84.787994 -259.051806) (xy 85.143594 -259.051806)
		)
		(stroke
			(width 0)
			(type solid)
		)
		(fill yes)
		(layer "In2.Cu")
		(net "M_B_CPU1_SA_CB<6>")
	)
	(gr_poly
		(pts
			(xy 85.143594 -258.59867) (xy 85.143594 -258.554474) (xy 84.787994 -258.554474) (xy 84.787994 -258.59867)
			(xy 84.834984 -258.75107) (xy 85.096604 -258.75107)
		)
		(stroke
			(width 0)
			(type solid)
		)
		(fill yes)
		(layer "In2.Cu")
		(net "M_B_CPU1_SA_CB<5>")
	)
	(gr_poly
		(pts
			(xy 85.143594 -257.37947) (xy 85.096604 -257.22707) (xy 84.834984 -257.22707) (xy 84.787994 -257.37947)
			(xy 84.787994 -257.42392) (xy 85.143594 -257.42392)
		)
		(stroke
			(width 0)
			(type solid)
		)
		(fill yes)
		(layer "In2.Cu")
		(net "M_B_CPU1_SA_CS_N<0>")
	)
	(gr_poly
		(pts
			(xy 85.143594 -256.971038) (xy 85.143594 -256.926588) (xy 84.787994 -256.926588) (xy 84.787994 -256.971038)
			(xy 84.834984 -257.123438) (xy 85.096604 -257.123438)
		)
		(stroke
			(width 0)
			(type solid)
		)
		(fill yes)
		(layer "In2.Cu")
		(net "M_B_CPU1_SA_CS_N<2>")
	)
	(gr_poly
		(pts
			(xy 85.143594 -255.751838) (xy 85.096604 -255.599438) (xy 84.834984 -255.599438) (xy 84.787994 -255.751838)
			(xy 84.787994 -255.796288) (xy 85.143594 -255.796288)
		)
		(stroke
			(width 0)
			(type solid)
		)
		(fill yes)
		(layer "In2.Cu")
		(net "M_B_CPU1_SA_CA<0>")
	)
	(gr_poly
		(pts
			(xy 85.143594 -255.343406) (xy 85.143594 -255.298956) (xy 84.787994 -255.298956) (xy 84.787994 -255.343406)
			(xy 84.834984 -255.495806) (xy 85.096604 -255.495806)
		)
		(stroke
			(width 0)
			(type solid)
		)
		(fill yes)
		(layer "In2.Cu")
		(net "M_B_CPU1_SA_CA<1>")
	)
	(gr_poly
		(pts
			(xy 85.143594 -254.124206) (xy 85.096604 -253.971806) (xy 84.834984 -253.971806) (xy 84.787994 -254.124206)
			(xy 84.787994 -254.168402) (xy 85.143594 -254.168402)
		)
		(stroke
			(width 0)
			(type solid)
		)
		(fill yes)
		(layer "In2.Cu")
		(net "M_B_CPU1_SA_CA<4>")
	)
	(gr_poly
		(pts
			(xy 85.143848 -253.715266) (xy 85.143848 -253.67107) (xy 84.788248 -253.67107) (xy 84.788248 -253.715266)
			(xy 84.835238 -253.867666) (xy 85.096858 -253.867666)
		)
		(stroke
			(width 0)
			(type solid)
		)
		(fill yes)
		(layer "In2.Cu")
		(net "M_B_CPU1_SA_CA<5>")
	)
	(gr_poly
		(pts
			(xy 85.216238 -275.356574) (xy 85.10778 -275.239734) (xy 85.069426 -275.217636) (xy 84.891626 -275.525484)
			(xy 84.92998 -275.547582) (xy 85.085428 -275.583142)
		)
		(stroke
			(width 0)
			(type solid)
		)
		(fill yes)
		(layer "In2.Cu")
		(net "M_B_CPU1_SA_DQ<5>")
	)
	(gr_poly
		(pts
			(xy 85.217508 -276.982428) (xy 85.10905 -276.865588) (xy 85.070696 -276.84349) (xy 84.892896 -277.151338)
			(xy 84.93125 -277.173436) (xy 85.086698 -277.208996)
		)
		(stroke
			(width 0)
			(type solid)
		)
		(fill yes)
		(layer "In2.Cu")
		(net "M_B_CPU1_SA_DQ<5>")
	)
	(gr_poly
		(pts
			(xy 85.354922 -227.286566) (xy 85.393276 -227.264468) (xy 85.215476 -226.95662) (xy 85.177122 -226.978718)
			(xy 85.068664 -227.095558) (xy 85.199474 -227.322126)
		)
		(stroke
			(width 0)
			(type solid)
		)
		(fill yes)
		(layer "In2.Cu")
		(net "M_B_CPU1_SB_DQ<16>")
	)
	(gr_poly
		(pts
			(xy 85.36051 -224.040954) (xy 85.398864 -224.018856) (xy 85.221064 -223.711008) (xy 85.18271 -223.733106)
			(xy 85.074252 -223.849946) (xy 85.205062 -224.076514)
		)
		(stroke
			(width 0)
			(type solid)
		)
		(fill yes)
		(layer "In2.Cu")
		(net "M_B_CPU1_SB_DQS_DP<2>")
	)
	(gr_poly
		(pts
			(xy 85.46465 -276.350476) (xy 85.503004 -276.328378) (xy 85.325204 -276.02053) (xy 85.28685 -276.042628)
			(xy 85.178392 -276.159468) (xy 85.309202 -276.386036)
		)
		(stroke
			(width 0)
			(type solid)
		)
		(fill yes)
		(layer "In2.Cu")
		(net "M_B_CPU1_SA_DQ<6>")
	)
	(gr_poly
		(pts
			(xy 85.469222 -223.418654) (xy 85.57768 -223.301814) (xy 85.44687 -223.075246) (xy 85.291422 -223.110806)
			(xy 85.253068 -223.132904) (xy 85.430868 -223.440752)
		)
		(stroke
			(width 0)
			(type solid)
		)
		(fill yes)
		(layer "In2.Cu")
		(net "M_B_CPU1_SB_DQS_DN<2>")
	)
	(gr_poly
		(pts
			(xy 85.476334 -226.686364) (xy 85.584792 -226.569524) (xy 85.453982 -226.342956) (xy 85.298534 -226.378516)
			(xy 85.26018 -226.400614) (xy 85.43798 -226.708462)
		)
		(stroke
			(width 0)
			(type solid)
		)
		(fill yes)
		(layer "In2.Cu")
		(net "M_B_CPU1_SB_DQ<18>")
	)
	(gr_poly
		(pts
			(xy 85.49513 -244.940582) (xy 85.44814 -244.788182) (xy 85.18652 -244.788182) (xy 85.13953 -244.940582)
			(xy 85.13953 -244.985032) (xy 85.49513 -244.985032)
		)
		(stroke
			(width 0)
			(type solid)
		)
		(fill yes)
		(layer "In2.Cu")
		(net "M_B_CPU1_SB_CS_N<1>")
	)
	(gr_poly
		(pts
			(xy 85.49513 -244.532658) (xy 85.49513 -244.488208) (xy 85.13953 -244.488208) (xy 85.13953 -244.532658)
			(xy 85.18652 -244.685058) (xy 85.44814 -244.685058)
		)
		(stroke
			(width 0)
			(type solid)
		)
		(fill yes)
		(layer "In2.Cu")
		(net "M_B_CPU1_SB_CB<6>")
	)
	(gr_poly
		(pts
			(xy 85.49513 -240.057178) (xy 85.44814 -239.904778) (xy 85.18652 -239.904778) (xy 85.13953 -240.057178)
			(xy 85.13953 -240.101628) (xy 85.49513 -240.101628)
		)
		(stroke
			(width 0)
			(type solid)
		)
		(fill yes)
		(layer "In2.Cu")
		(net "M_B_CPU1_SB_CB<1>")
	)
	(gr_poly
		(pts
			(xy 85.49513 -239.649254) (xy 85.49513 -239.604804) (xy 85.13953 -239.604804) (xy 85.13953 -239.649254)
			(xy 85.18652 -239.801654) (xy 85.44814 -239.801654)
		)
		(stroke
			(width 0)
			(type solid)
		)
		(fill yes)
		(layer "In2.Cu")
		(net "M_A_CPU1_SB_DQ<0>")
	)
	(gr_poly
		(pts
			(xy 85.49513 -235.174282) (xy 85.44814 -235.021882) (xy 85.18652 -235.021882) (xy 85.13953 -235.174282)
			(xy 85.13953 -235.218478) (xy 85.49513 -235.218478)
		)
		(stroke
			(width 0)
			(type solid)
		)
		(fill yes)
		(layer "In2.Cu")
		(net "M_A_CPU1_SB_DQ<7>")
	)
	(gr_poly
		(pts
			(xy 85.49513 -234.76585) (xy 85.49513 -234.721654) (xy 85.13953 -234.721654) (xy 85.13953 -234.76585)
			(xy 85.18652 -234.91825) (xy 85.44814 -234.91825)
		)
		(stroke
			(width 0)
			(type solid)
		)
		(fill yes)
		(layer "In2.Cu")
		(net "M_B_CPU1_SB_DQ<8>")
	)
	(gr_poly
		(pts
			(xy 85.497416 -242.904518) (xy 85.497416 -242.860322) (xy 85.141816 -242.860322) (xy 85.141816 -242.904518)
			(xy 85.188806 -243.056918) (xy 85.450426 -243.056918)
		)
		(stroke
			(width 0)
			(type solid)
		)
		(fill yes)
		(layer "In2.Cu")
		(net "M_B_CPU1_SB_DQS_DN<4>")
	)
	(gr_poly
		(pts
			(xy 85.50021 -273.838416) (xy 85.461856 -273.816318) (xy 85.306408 -273.780758) (xy 85.175598 -274.007326)
			(xy 85.284056 -274.124166) (xy 85.32241 -274.146264)
		)
		(stroke
			(width 0)
			(type solid)
		)
		(fill yes)
		(layer "In2.Cu")
		(net "M_B_CPU1_SA_DQ<7>")
	)
	(gr_poly
		(pts
			(xy 85.503512 -241.685318) (xy 85.456522 -241.532918) (xy 85.194902 -241.532918) (xy 85.147912 -241.685318)
			(xy 85.147912 -241.729768) (xy 85.503512 -241.729768)
		)
		(stroke
			(width 0)
			(type solid)
		)
		(fill yes)
		(layer "In2.Cu")
		(net "M_B_CPU1_SB_DQS_DN<9>")
	)
	(gr_poly
		(pts
			(xy 85.503766 -247.787922) (xy 85.503766 -247.743472) (xy 85.148166 -247.743472) (xy 85.148166 -247.787922)
			(xy 85.195156 -247.940322) (xy 85.456776 -247.940322)
		)
		(stroke
			(width 0)
			(type solid)
		)
		(fill yes)
		(layer "In2.Cu")
		(net "M_B_CPU1_SB_CA<4>")
	)
	(gr_poly
		(pts
			(xy 85.503766 -246.568722) (xy 85.456776 -246.416322) (xy 85.195156 -246.416322) (xy 85.148166 -246.568722)
			(xy 85.148166 -246.613172) (xy 85.503766 -246.613172)
		)
		(stroke
			(width 0)
			(type solid)
		)
		(fill yes)
		(layer "In2.Cu")
		(net "M_B_CPU1_SB_PAR")
	)
	(gr_poly
		(pts
			(xy 85.503766 -246.16029) (xy 85.503766 -246.11584) (xy 85.148166 -246.11584) (xy 85.148166 -246.16029)
			(xy 85.195156 -246.31269) (xy 85.456776 -246.31269)
		)
		(stroke
			(width 0)
			(type solid)
		)
		(fill yes)
		(layer "In2.Cu")
		(net "M_B_CPU1_SB_CS_N<0>")
	)
	(gr_poly
		(pts
			(xy 85.503766 -241.276886) (xy 85.503766 -241.232436) (xy 85.148166 -241.232436) (xy 85.148166 -241.276886)
			(xy 85.195156 -241.429286) (xy 85.456776 -241.429286)
		)
		(stroke
			(width 0)
			(type solid)
		)
		(fill yes)
		(layer "In2.Cu")
		(net "M_B_CPU1_SB_CB<2>")
	)
	(gr_poly
		(pts
			(xy 85.503766 -238.430054) (xy 85.456776 -238.277654) (xy 85.195156 -238.277654) (xy 85.148166 -238.430054)
			(xy 85.148166 -238.47425) (xy 85.503766 -238.47425)
		)
		(stroke
			(width 0)
			(type solid)
		)
		(fill yes)
		(layer "In2.Cu")
		(net "M_A_CPU1_SB_DQ<3>")
	)
	(gr_poly
		(pts
			(xy 85.503766 -236.393482) (xy 85.503766 -236.349286) (xy 85.148166 -236.349286) (xy 85.148166 -236.393482)
			(xy 85.195156 -236.545882) (xy 85.456776 -236.545882)
		)
		(stroke
			(width 0)
			(type solid)
		)
		(fill yes)
		(layer "In2.Cu")
		(net "M_A_CPU1_SB_DQ<4>")
	)
	(gr_poly
		(pts
			(xy 85.503766 -231.510078) (xy 85.503766 -231.465882) (xy 85.148166 -231.465882) (xy 85.148166 -231.510078)
			(xy 85.195156 -231.662478) (xy 85.456776 -231.662478)
		)
		(stroke
			(width 0)
			(type solid)
		)
		(fill yes)
		(layer "In2.Cu")
		(net "M_B_CPU1_SB_DQ<12>")
	)
	(gr_poly
		(pts
			(xy 85.508338 -277.079964) (xy 85.469984 -277.057866) (xy 85.314536 -277.022306) (xy 85.183726 -277.248874)
			(xy 85.292184 -277.365714) (xy 85.330538 -277.387812)
		)
		(stroke
			(width 0)
			(type solid)
		)
		(fill yes)
		(layer "In2.Cu")
		(net "M_B_CPU1_SA_DQ<6>")
	)
	(gr_poly
		(pts
			(xy 85.509354 -275.450046) (xy 85.471 -275.427948) (xy 85.315552 -275.392388) (xy 85.184742 -275.618956)
			(xy 85.2932 -275.735796) (xy 85.331554 -275.757894)
		)
		(stroke
			(width 0)
			(type solid)
		)
		(fill yes)
		(layer "In2.Cu")
		(net "M_B_CPU1_SA_DQ<6>")
	)
	(gr_poly
		(pts
			(xy 85.512148 -243.31295) (xy 85.465158 -243.16055) (xy 85.203538 -243.16055) (xy 85.156548 -243.31295)
			(xy 85.156548 -243.3574) (xy 85.512148 -243.3574)
		)
		(stroke
			(width 0)
			(type solid)
		)
		(fill yes)
		(layer "In2.Cu")
		(net "M_B_CPU1_SB_CB<5>")
	)
	(gr_poly
		(pts
			(xy 85.512148 -238.021622) (xy 85.512148 -237.977172) (xy 85.156548 -237.977172) (xy 85.156548 -238.021622)
			(xy 85.203538 -238.174022) (xy 85.465158 -238.174022)
		)
		(stroke
			(width 0)
			(type solid)
		)
		(fill yes)
		(layer "In2.Cu")
		(net "M_A_CPU1_SB_DQS_DP<0>")
	)
	(gr_poly
		(pts
			(xy 85.512148 -236.801914) (xy 85.465158 -236.649514) (xy 85.203538 -236.649514) (xy 85.156548 -236.801914)
			(xy 85.156548 -236.846364) (xy 85.512148 -236.846364)
		)
		(stroke
			(width 0)
			(type solid)
		)
		(fill yes)
		(layer "In2.Cu")
		(net "M_A_CPU1_SB_DQS_DP<5>")
	)
	(gr_poly
		(pts
			(xy 85.512148 -233.546142) (xy 85.465158 -233.393742) (xy 85.203538 -233.393742) (xy 85.156548 -233.546142)
			(xy 85.156548 -233.590592) (xy 85.512148 -233.590592)
		)
		(stroke
			(width 0)
			(type solid)
		)
		(fill yes)
		(layer "In2.Cu")
		(net "M_B_CPU1_SB_DQ<11>")
	)
	(gr_poly
		(pts
			(xy 85.512148 -233.138218) (xy 85.512148 -233.093768) (xy 85.156548 -233.093768) (xy 85.156548 -233.138218)
			(xy 85.203538 -233.290618) (xy 85.465158 -233.290618)
		)
		(stroke
			(width 0)
			(type solid)
		)
		(fill yes)
		(layer "In2.Cu")
		(net "M_B_CPU1_SB_DQS_DP<1>")
	)
	(gr_poly
		(pts
			(xy 85.512148 -231.91851) (xy 85.465158 -231.76611) (xy 85.203538 -231.76611) (xy 85.156548 -231.91851)
			(xy 85.156548 -231.96296) (xy 85.512148 -231.96296)
		)
		(stroke
			(width 0)
			(type solid)
		)
		(fill yes)
		(layer "In2.Cu")
		(net "M_B_CPU1_SB_DQS_DP<6>")
	)
	(gr_poly
		(pts
			(xy 85.512148 -225.407474) (xy 85.465158 -225.255074) (xy 85.203538 -225.255074) (xy 85.156548 -225.407474)
			(xy 85.156548 -225.45167) (xy 85.512148 -225.45167)
		)
		(stroke
			(width 0)
			(type solid)
		)
		(fill yes)
		(layer "In2.Cu")
		(net "M_B_CPU1_SB_DQ<19>")
	)
	(gr_poly
		(pts
			(xy 85.613494 -267.551662) (xy 85.613494 -267.507212) (xy 85.257894 -267.507212) (xy 85.257894 -267.551662)
			(xy 85.304884 -267.704062) (xy 85.566504 -267.704062)
		)
		(stroke
			(width 0)
			(type solid)
		)
		(fill yes)
		(layer "In2.Cu")
		(net "M_B_CPU1_SA_DQ<16>")
	)
	(gr_poly
		(pts
			(xy 85.613494 -266.332462) (xy 85.566504 -266.180062) (xy 85.304884 -266.180062) (xy 85.257894 -266.332462)
			(xy 85.257894 -266.376658) (xy 85.613494 -266.376658)
		)
		(stroke
			(width 0)
			(type solid)
		)
		(fill yes)
		(layer "In2.Cu")
		(net "M_B_CPU1_SA_DQ<19>")
	)
	(gr_poly
		(pts
			(xy 85.613494 -265.923014) (xy 85.613494 -265.878818) (xy 85.257894 -265.878818) (xy 85.257894 -265.923014)
			(xy 85.304884 -266.075414) (xy 85.566504 -266.075414)
		)
		(stroke
			(width 0)
			(type solid)
		)
		(fill yes)
		(layer "In2.Cu")
		(net "M_B_CPU1_SA_DQS_DP<2>")
	)
	(gr_poly
		(pts
			(xy 85.613494 -264.70483) (xy 85.566504 -264.55243) (xy 85.304884 -264.55243) (xy 85.257894 -264.70483)
			(xy 85.257894 -264.749026) (xy 85.613494 -264.749026)
		)
		(stroke
			(width 0)
			(type solid)
		)
		(fill yes)
		(layer "In2.Cu")
		(net "M_B_CPU1_SA_DQS_DP<7>")
	)
	(gr_poly
		(pts
			(xy 85.613494 -264.29589) (xy 85.613494 -264.251694) (xy 85.257894 -264.251694) (xy 85.257894 -264.29589)
			(xy 85.304884 -264.44829) (xy 85.566504 -264.44829)
		)
		(stroke
			(width 0)
			(type solid)
		)
		(fill yes)
		(layer "In2.Cu")
		(net "M_B_CPU1_SA_DQ<20>")
	)
	(gr_poly
		(pts
			(xy 85.613494 -263.07669) (xy 85.566504 -262.92429) (xy 85.304884 -262.92429) (xy 85.257894 -263.07669)
			(xy 85.257894 -263.12114) (xy 85.613494 -263.12114)
		)
		(stroke
			(width 0)
			(type solid)
		)
		(fill yes)
		(layer "In2.Cu")
		(net "M_B_CPU1_SA_DQ<23>")
	)
	(gr_poly
		(pts
			(xy 85.613494 -262.668258) (xy 85.613494 -262.623808) (xy 85.257894 -262.623808) (xy 85.257894 -262.668258)
			(xy 85.304884 -262.820658) (xy 85.566504 -262.820658)
		)
		(stroke
			(width 0)
			(type solid)
		)
		(fill yes)
		(layer "In2.Cu")
		(net "M_B_CPU1_SA_CB<0>")
	)
	(gr_poly
		(pts
			(xy 85.613494 -261.449058) (xy 85.566504 -261.296658) (xy 85.304884 -261.296658) (xy 85.257894 -261.449058)
			(xy 85.257894 -261.493508) (xy 85.613494 -261.493508)
		)
		(stroke
			(width 0)
			(type solid)
		)
		(fill yes)
		(layer "In2.Cu")
		(net "M_B_CPU1_SA_CB<3>")
	)
	(gr_poly
		(pts
			(xy 85.613494 -261.040626) (xy 85.613494 -260.996176) (xy 85.257894 -260.996176) (xy 85.257894 -261.040626)
			(xy 85.304884 -261.193026) (xy 85.566504 -261.193026)
		)
		(stroke
			(width 0)
			(type solid)
		)
		(fill yes)
		(layer "In2.Cu")
		(net "M_B_CPU1_SA_DQS_DP<4>")
	)
	(gr_poly
		(pts
			(xy 85.613494 -259.821426) (xy 85.566504 -259.669026) (xy 85.304884 -259.669026) (xy 85.257894 -259.821426)
			(xy 85.257894 -259.865622) (xy 85.613494 -259.865622)
		)
		(stroke
			(width 0)
			(type solid)
		)
		(fill yes)
		(layer "In2.Cu")
		(net "M_B_CPU1_SA_DQS_DP<9>")
	)
	(gr_poly
		(pts
			(xy 85.613494 -259.412486) (xy 85.613494 -259.36829) (xy 85.257894 -259.36829) (xy 85.257894 -259.412486)
			(xy 85.304884 -259.564886) (xy 85.566504 -259.564886)
		)
		(stroke
			(width 0)
			(type solid)
		)
		(fill yes)
		(layer "In2.Cu")
		(net "M_B_CPU1_SA_CB<4>")
	)
	(gr_poly
		(pts
			(xy 85.613494 -258.193286) (xy 85.566504 -258.040886) (xy 85.304884 -258.040886) (xy 85.257894 -258.193286)
			(xy 85.257894 -258.237736) (xy 85.613494 -258.237736)
		)
		(stroke
			(width 0)
			(type solid)
		)
		(fill yes)
		(layer "In2.Cu")
		(net "M_B_CPU1_SA_CB<7>")
	)
	(gr_poly
		(pts
			(xy 85.613494 -257.784854) (xy 85.613494 -257.740404) (xy 85.257894 -257.740404) (xy 85.257894 -257.784854)
			(xy 85.304884 -257.937254) (xy 85.566504 -257.937254)
		)
		(stroke
			(width 0)
			(type solid)
		)
		(fill yes)
		(layer "In2.Cu")
		(net "M_B_CPU1_ALERT_N")
	)
	(gr_poly
		(pts
			(xy 85.613494 -256.565654) (xy 85.566504 -256.413254) (xy 85.304884 -256.413254) (xy 85.257894 -256.565654)
			(xy 85.257894 -256.610104) (xy 85.613494 -256.610104)
		)
		(stroke
			(width 0)
			(type solid)
		)
		(fill yes)
		(layer "In2.Cu")
		(net "M_B_CPU1_SA_CS_N<3>")
	)
	(gr_poly
		(pts
			(xy 85.613494 -256.157222) (xy 85.613494 -256.112772) (xy 85.257894 -256.112772) (xy 85.257894 -256.157222)
			(xy 85.304884 -256.309622) (xy 85.566504 -256.309622)
		)
		(stroke
			(width 0)
			(type solid)
		)
		(fill yes)
		(layer "In2.Cu")
		(net "M_B_CPU1_SA_CS_N<1>")
	)
	(gr_poly
		(pts
			(xy 85.613494 -254.938022) (xy 85.566504 -254.785622) (xy 85.304884 -254.785622) (xy 85.257894 -254.938022)
			(xy 85.257894 -254.982218) (xy 85.613494 -254.982218)
		)
		(stroke
			(width 0)
			(type solid)
		)
		(fill yes)
		(layer "In2.Cu")
		(net "M_B_CPU1_SA_CA<2>")
	)
	(gr_poly
		(pts
			(xy 85.613494 -254.529082) (xy 85.613494 -254.484886) (xy 85.257894 -254.484886) (xy 85.257894 -254.529082)
			(xy 85.304884 -254.681482) (xy 85.566504 -254.681482)
		)
		(stroke
			(width 0)
			(type solid)
		)
		(fill yes)
		(layer "In2.Cu")
		(net "M_B_CPU1_SA_CA<3>")
	)
	(gr_poly
		(pts
			(xy 85.692742 -274.531582) (xy 85.584284 -274.414742) (xy 85.54593 -274.392644) (xy 85.36813 -274.700492)
			(xy 85.406484 -274.72259) (xy 85.561932 -274.75815)
		)
		(stroke
			(width 0)
			(type solid)
		)
		(fill yes)
		(layer "In2.Cu")
		(net "M_B_CPU1_SA_DQ<5>")
	)
	(gr_poly
		(pts
			(xy 85.823044 -226.469956) (xy 85.861398 -226.447858) (xy 85.683598 -226.14001) (xy 85.645244 -226.162108)
			(xy 85.536786 -226.278948) (xy 85.667596 -226.505516)
		)
		(stroke
			(width 0)
			(type solid)
		)
		(fill yes)
		(layer "In2.Cu")
		(net "M_B_CPU1_SB_DQ<17>")
	)
	(gr_poly
		(pts
			(xy 85.823044 -224.84207) (xy 85.861398 -224.819972) (xy 85.683598 -224.512124) (xy 85.645244 -224.534222)
			(xy 85.536786 -224.651062) (xy 85.667596 -224.87763)
		)
		(stroke
			(width 0)
			(type solid)
		)
		(fill yes)
		(layer "In2.Cu")
		(net "M_B_CPU1_SB_DQS_DP<2>")
	)
	(gr_poly
		(pts
			(xy 85.828632 -228.106986) (xy 85.866986 -228.084888) (xy 85.689186 -227.77704) (xy 85.650832 -227.799138)
			(xy 85.542374 -227.915978) (xy 85.673184 -228.142546)
		)
		(stroke
			(width 0)
			(type solid)
		)
		(fill yes)
		(layer "In2.Cu")
		(net "M_B_CPU1_SB_DQ<16>")
	)
	(gr_poly
		(pts
			(xy 85.828632 -223.223582) (xy 85.866986 -223.201484) (xy 85.689186 -222.893636) (xy 85.650832 -222.915734)
			(xy 85.542374 -223.032574) (xy 85.673184 -223.259142)
		)
		(stroke
			(width 0)
			(type solid)
		)
		(fill yes)
		(layer "In2.Cu")
		(net "M_B_CPU1_SB_DQS_DN<7>")
	)
	(gr_poly
		(pts
			(xy 85.939122 -225.860356) (xy 86.04758 -225.743516) (xy 85.91677 -225.516948) (xy 85.761322 -225.552508)
			(xy 85.722968 -225.574606) (xy 85.900768 -225.882454)
		)
		(stroke
			(width 0)
			(type solid)
		)
		(fill yes)
		(layer "In2.Cu")
		(net "M_B_CPU1_SB_DQ<19>")
	)
	(gr_poly
		(pts
			(xy 85.944456 -227.497386) (xy 86.052914 -227.380546) (xy 85.922104 -227.153978) (xy 85.766656 -227.189538)
			(xy 85.728302 -227.211636) (xy 85.906102 -227.519484)
		)
		(stroke
			(width 0)
			(type solid)
		)
		(fill yes)
		(layer "In2.Cu")
		(net "M_B_CPU1_SB_DQ<18>")
	)
	(gr_poly
		(pts
			(xy 85.944456 -224.241868) (xy 86.052914 -224.125028) (xy 85.922104 -223.89846) (xy 85.766656 -223.93402)
			(xy 85.728302 -223.956118) (xy 85.906102 -224.263966)
		)
		(stroke
			(width 0)
			(type solid)
		)
		(fill yes)
		(layer "In2.Cu")
		(net "M_B_CPU1_SB_DQS_DN<2>")
	)
	(gr_poly
		(pts
			(xy 85.96757 -242.090702) (xy 85.96757 -242.046506) (xy 85.61197 -242.046506) (xy 85.61197 -242.090702)
			(xy 85.65896 -242.243102) (xy 85.92058 -242.243102)
		)
		(stroke
			(width 0)
			(type solid)
		)
		(fill yes)
		(layer "In2.Cu")
		(net "M_B_CPU1_SB_DQS_DP<9>")
	)
	(gr_poly
		(pts
			(xy 85.96757 -237.61573) (xy 85.92058 -237.46333) (xy 85.65896 -237.46333) (xy 85.61197 -237.61573)
			(xy 85.61197 -237.66018) (xy 85.96757 -237.66018)
		)
		(stroke
			(width 0)
			(type solid)
		)
		(fill yes)
		(layer "In2.Cu")
		(net "M_A_CPU1_SB_DQS_DN<0>")
	)
	(gr_poly
		(pts
			(xy 85.96757 -237.207806) (xy 85.96757 -237.163356) (xy 85.61197 -237.163356) (xy 85.61197 -237.207806)
			(xy 85.65896 -237.360206) (xy 85.92058 -237.360206)
		)
		(stroke
			(width 0)
			(type solid)
		)
		(fill yes)
		(layer "In2.Cu")
		(net "M_A_CPU1_SB_DQS_DN<5>")
	)
	(gr_poly
		(pts
			(xy 85.96757 -233.952034) (xy 85.96757 -233.907838) (xy 85.61197 -233.907838) (xy 85.61197 -233.952034)
			(xy 85.65896 -234.104434) (xy 85.92058 -234.104434)
		)
		(stroke
			(width 0)
			(type solid)
		)
		(fill yes)
		(layer "In2.Cu")
		(net "M_B_CPU1_SB_DQ<9>")
	)
	(gr_poly
		(pts
			(xy 85.96757 -232.732326) (xy 85.92058 -232.579926) (xy 85.65896 -232.579926) (xy 85.61197 -232.732326)
			(xy 85.61197 -232.776776) (xy 85.96757 -232.776776)
		)
		(stroke
			(width 0)
			(type solid)
		)
		(fill yes)
		(layer "In2.Cu")
		(net "M_B_CPU1_SB_DQS_DN<1>")
	)
	(gr_poly
		(pts
			(xy 85.96757 -232.324402) (xy 85.96757 -232.279952) (xy 85.61197 -232.279952) (xy 85.61197 -232.324402)
			(xy 85.65896 -232.476802) (xy 85.92058 -232.476802)
		)
		(stroke
			(width 0)
			(type solid)
		)
		(fill yes)
		(layer "In2.Cu")
		(net "M_B_CPU1_SB_DQS_DN<6>")
	)
	(gr_poly
		(pts
			(xy 85.972904 -274.647152) (xy 85.93455 -274.625054) (xy 85.779102 -274.589494) (xy 85.648292 -274.816062)
			(xy 85.75675 -274.932902) (xy 85.795104 -274.955)
		)
		(stroke
			(width 0)
			(type solid)
		)
		(fill yes)
		(layer "In2.Cu")
		(net "M_B_CPU1_SA_DQ<6>")
	)
	(gr_poly
		(pts
			(xy 85.973412 -235.988098) (xy 85.926422 -235.835698) (xy 85.664802 -235.835698) (xy 85.617812 -235.988098)
			(xy 85.617812 -236.032548) (xy 85.973412 -236.032548)
		)
		(stroke
			(width 0)
			(type solid)
		)
		(fill yes)
		(layer "In2.Cu")
		(net "M_A_CPU1_SB_DQ<6>")
	)
	(gr_poly
		(pts
			(xy 85.973666 -247.382538) (xy 85.926676 -247.230138) (xy 85.665056 -247.230138) (xy 85.618066 -247.382538)
			(xy 85.618066 -247.426988) (xy 85.973666 -247.426988)
		)
		(stroke
			(width 0)
			(type solid)
		)
		(fill yes)
		(layer "In2.Cu")
		(net "M_B_CPU1_SB_CA<5>")
	)
	(gr_poly
		(pts
			(xy 85.973666 -246.974106) (xy 85.973666 -246.929656) (xy 85.618066 -246.929656) (xy 85.618066 -246.974106)
			(xy 85.665056 -247.126506) (xy 85.926676 -247.126506)
		)
		(stroke
			(width 0)
			(type solid)
		)
		(fill yes)
		(layer "In2.Cu")
		(net "M_B_CPU1_SB_CA<6>")
	)
	(gr_poly
		(pts
			(xy 85.973666 -245.754906) (xy 85.926676 -245.602506) (xy 85.665056 -245.602506) (xy 85.618066 -245.754906)
			(xy 85.618066 -245.799356) (xy 85.973666 -245.799356)
		)
		(stroke
			(width 0)
			(type solid)
		)
		(fill yes)
		(layer "In2.Cu")
		(net "M_B_CPU1_SB_CS_N<2>")
	)
	(gr_poly
		(pts
			(xy 85.973666 -243.718334) (xy 85.973666 -243.674138) (xy 85.618066 -243.674138) (xy 85.618066 -243.718334)
			(xy 85.665056 -243.870734) (xy 85.926676 -243.870734)
		)
		(stroke
			(width 0)
			(type solid)
		)
		(fill yes)
		(layer "In2.Cu")
		(net "M_B_CPU1_SB_CB<7>")
	)
	(gr_poly
		(pts
			(xy 85.973666 -240.871502) (xy 85.926676 -240.719102) (xy 85.665056 -240.719102) (xy 85.618066 -240.871502)
			(xy 85.618066 -240.915952) (xy 85.973666 -240.915952)
		)
		(stroke
			(width 0)
			(type solid)
		)
		(fill yes)
		(layer "In2.Cu")
		(net "M_B_CPU1_SB_CB<0>")
	)
	(gr_poly
		(pts
			(xy 85.973666 -238.83493) (xy 85.973666 -238.790734) (xy 85.618066 -238.790734) (xy 85.618066 -238.83493)
			(xy 85.665056 -238.98733) (xy 85.926676 -238.98733)
		)
		(stroke
			(width 0)
			(type solid)
		)
		(fill yes)
		(layer "In2.Cu")
		(net "M_A_CPU1_SB_DQ<1>")
	)
	(gr_poly
		(pts
			(xy 85.973666 -231.104694) (xy 85.926676 -230.952294) (xy 85.665056 -230.952294) (xy 85.618066 -231.104694)
			(xy 85.618066 -231.149144) (xy 85.973666 -231.149144)
		)
		(stroke
			(width 0)
			(type solid)
		)
		(fill yes)
		(layer "In2.Cu")
		(net "M_B_CPU1_SB_DQ<14>")
	)
	(gr_poly
		(pts
			(xy 85.97773 -273.012408) (xy 85.939376 -272.99031) (xy 85.783928 -272.95475) (xy 85.653118 -273.181318)
			(xy 85.761576 -273.298158) (xy 85.79993 -273.320256)
		)
		(stroke
			(width 0)
			(type solid)
		)
		(fill yes)
		(layer "In2.Cu")
		(net "M_B_CPU1_SA_DQ<7>")
	)
	(gr_poly
		(pts
			(xy 85.982048 -245.346474) (xy 85.982048 -245.302278) (xy 85.626448 -245.302278) (xy 85.626448 -245.346474)
			(xy 85.673438 -245.498874) (xy 85.935058 -245.498874)
		)
		(stroke
			(width 0)
			(type solid)
		)
		(fill yes)
		(layer "In2.Cu")
		(net "M_B_CPU1_SB_CS_N<3>")
	)
	(gr_poly
		(pts
			(xy 85.982048 -244.126766) (xy 85.935058 -243.974366) (xy 85.673438 -243.974366) (xy 85.626448 -244.126766)
			(xy 85.626448 -244.171216) (xy 85.982048 -244.171216)
		)
		(stroke
			(width 0)
			(type solid)
		)
		(fill yes)
		(layer "In2.Cu")
		(net "M_B_CPU1_SB_CB<4>")
	)
	(gr_poly
		(pts
			(xy 85.982048 -240.46307) (xy 85.982048 -240.418874) (xy 85.626448 -240.418874) (xy 85.626448 -240.46307)
			(xy 85.673438 -240.61547) (xy 85.935058 -240.61547)
		)
		(stroke
			(width 0)
			(type solid)
		)
		(fill yes)
		(layer "In2.Cu")
		(net "M_B_CPU1_SB_CB<3>")
	)
	(gr_poly
		(pts
			(xy 85.982048 -239.243362) (xy 85.935058 -239.090962) (xy 85.673438 -239.090962) (xy 85.626448 -239.243362)
			(xy 85.626448 -239.287812) (xy 85.982048 -239.287812)
		)
		(stroke
			(width 0)
			(type solid)
		)
		(fill yes)
		(layer "In2.Cu")
		(net "M_A_CPU1_SB_DQ<2>")
	)
	(gr_poly
		(pts
			(xy 85.982048 -235.579666) (xy 85.982048 -235.53547) (xy 85.626448 -235.53547) (xy 85.626448 -235.579666)
			(xy 85.673438 -235.732066) (xy 85.935058 -235.732066)
		)
		(stroke
			(width 0)
			(type solid)
		)
		(fill yes)
		(layer "In2.Cu")
		(net "M_A_CPU1_SB_DQ<5>")
	)
	(gr_poly
		(pts
			(xy 85.982048 -234.360466) (xy 85.935058 -234.208066) (xy 85.673438 -234.208066) (xy 85.626448 -234.360466)
			(xy 85.626448 -234.404662) (xy 85.982048 -234.404662)
		)
		(stroke
			(width 0)
			(type solid)
		)
		(fill yes)
		(layer "In2.Cu")
		(net "M_B_CPU1_SB_DQ<10>")
	)
	(gr_poly
		(pts
			(xy 85.982048 -230.696262) (xy 85.982048 -230.652066) (xy 85.626448 -230.652066) (xy 85.626448 -230.696262)
			(xy 85.673438 -230.848662) (xy 85.935058 -230.848662)
		)
		(stroke
			(width 0)
			(type solid)
		)
		(fill yes)
		(layer "In2.Cu")
		(net "M_B_CPU1_SB_DQ<13>")
	)
	(gr_poly
		(pts
			(xy 85.983064 -242.499134) (xy 85.936074 -242.346734) (xy 85.674454 -242.346734) (xy 85.627464 -242.499134)
			(xy 85.627464 -242.54333) (xy 85.983064 -242.54333)
		)
		(stroke
			(width 0)
			(type solid)
		)
		(fill yes)
		(layer "In2.Cu")
		(net "M_B_CPU1_SB_DQS_DP<4>")
	)
	(gr_poly
		(pts
			(xy 86.054184 -276.560788) (xy 86.162642 -276.443948) (xy 86.031832 -276.21738) (xy 85.876384 -276.25294)
			(xy 85.83803 -276.275038) (xy 86.01583 -276.582886)
		)
		(stroke
			(width 0)
			(type solid)
		)
		(fill yes)
		(layer "In2.Cu")
		(net "M_B_CPU1_SA_DQ<4>")
	)
	(gr_poly
		(pts
			(xy 86.083394 -267.146278) (xy 86.036404 -266.993878) (xy 85.774784 -266.993878) (xy 85.727794 -267.146278)
			(xy 85.727794 -267.190474) (xy 86.083394 -267.190474)
		)
		(stroke
			(width 0)
			(type solid)
		)
		(fill yes)
		(layer "In2.Cu")
		(net "M_B_CPU1_SA_DQ<18>")
	)
	(gr_poly
		(pts
			(xy 86.083394 -266.737846) (xy 86.083394 -266.693396) (xy 85.727794 -266.693396) (xy 85.727794 -266.737846)
			(xy 85.774784 -266.890246) (xy 86.036404 -266.890246)
		)
		(stroke
			(width 0)
			(type solid)
		)
		(fill yes)
		(layer "In2.Cu")
		(net "M_B_CPU1_SA_DQ<17>")
	)
	(gr_poly
		(pts
			(xy 86.083394 -265.518646) (xy 86.036404 -265.366246) (xy 85.774784 -265.366246) (xy 85.727794 -265.518646)
			(xy 85.727794 -265.562842) (xy 86.083394 -265.562842)
		)
		(stroke
			(width 0)
			(type solid)
		)
		(fill yes)
		(layer "In2.Cu")
		(net "M_B_CPU1_SA_DQS_DN<2>")
	)
	(gr_poly
		(pts
			(xy 86.083394 -265.109706) (xy 86.083394 -265.06551) (xy 85.727794 -265.06551) (xy 85.727794 -265.109706)
			(xy 85.774784 -265.262106) (xy 86.036404 -265.262106)
		)
		(stroke
			(width 0)
			(type solid)
		)
		(fill yes)
		(layer "In2.Cu")
		(net "M_B_CPU1_SA_DQS_DN<7>")
	)
	(gr_poly
		(pts
			(xy 86.083394 -263.891014) (xy 86.036404 -263.738614) (xy 85.774784 -263.738614) (xy 85.727794 -263.891014)
			(xy 85.727794 -263.93521) (xy 86.083394 -263.93521)
		)
		(stroke
			(width 0)
			(type solid)
		)
		(fill yes)
		(layer "In2.Cu")
		(net "M_B_CPU1_SA_DQ<22>")
	)
	(gr_poly
		(pts
			(xy 86.083394 -263.482074) (xy 86.083394 -263.437878) (xy 85.727794 -263.437878) (xy 85.727794 -263.482074)
			(xy 85.774784 -263.634474) (xy 86.036404 -263.634474)
		)
		(stroke
			(width 0)
			(type solid)
		)
		(fill yes)
		(layer "In2.Cu")
		(net "M_B_CPU1_SA_DQ<21>")
	)
	(gr_poly
		(pts
			(xy 86.083394 -262.262874) (xy 86.036404 -262.110474) (xy 85.774784 -262.110474) (xy 85.727794 -262.262874)
			(xy 85.727794 -262.307324) (xy 86.083394 -262.307324)
		)
		(stroke
			(width 0)
			(type solid)
		)
		(fill yes)
		(layer "In2.Cu")
		(net "M_B_CPU1_SA_CB<2>")
	)
	(gr_poly
		(pts
			(xy 86.083394 -261.854442) (xy 86.083394 -261.810246) (xy 85.727794 -261.810246) (xy 85.727794 -261.854442)
			(xy 85.774784 -262.006842) (xy 86.036404 -262.006842)
		)
		(stroke
			(width 0)
			(type solid)
		)
		(fill yes)
		(layer "In2.Cu")
		(net "M_B_CPU1_SA_CB<1>")
	)
	(gr_poly
		(pts
			(xy 86.083394 -260.635242) (xy 86.036404 -260.482842) (xy 85.774784 -260.482842) (xy 85.727794 -260.635242)
			(xy 85.727794 -260.679438) (xy 86.083394 -260.679438)
		)
		(stroke
			(width 0)
			(type solid)
		)
		(fill yes)
		(layer "In2.Cu")
		(net "M_B_CPU1_SA_DQS_DN<4>")
	)
	(gr_poly
		(pts
			(xy 86.083394 -260.226302) (xy 86.083394 -260.182106) (xy 85.727794 -260.182106) (xy 85.727794 -260.226302)
			(xy 85.774784 -260.378702) (xy 86.036404 -260.378702)
		)
		(stroke
			(width 0)
			(type solid)
		)
		(fill yes)
		(layer "In2.Cu")
		(net "M_B_CPU1_SA_DQS_DN<9>")
	)
	(gr_poly
		(pts
			(xy 86.083394 -259.00761) (xy 86.036404 -258.85521) (xy 85.774784 -258.85521) (xy 85.727794 -259.00761)
			(xy 85.727794 -259.051806) (xy 86.083394 -259.051806)
		)
		(stroke
			(width 0)
			(type solid)
		)
		(fill yes)
		(layer "In2.Cu")
		(net "M_B_CPU1_SA_CB<6>")
	)
	(gr_poly
		(pts
			(xy 86.083394 -258.59867) (xy 86.083394 -258.554474) (xy 85.727794 -258.554474) (xy 85.727794 -258.59867)
			(xy 85.774784 -258.75107) (xy 86.036404 -258.75107)
		)
		(stroke
			(width 0)
			(type solid)
		)
		(fill yes)
		(layer "In2.Cu")
		(net "M_B_CPU1_SA_CB<5>")
	)
	(gr_poly
		(pts
			(xy 86.083394 -257.37947) (xy 86.036404 -257.22707) (xy 85.774784 -257.22707) (xy 85.727794 -257.37947)
			(xy 85.727794 -257.42392) (xy 86.083394 -257.42392)
		)
		(stroke
			(width 0)
			(type solid)
		)
		(fill yes)
		(layer "In2.Cu")
		(net "M_B_CPU1_SA_CS_N<0>")
	)
	(gr_poly
		(pts
			(xy 86.083394 -256.971038) (xy 86.083394 -256.926588) (xy 85.727794 -256.926588) (xy 85.727794 -256.971038)
			(xy 85.774784 -257.123438) (xy 86.036404 -257.123438)
		)
		(stroke
			(width 0)
			(type solid)
		)
		(fill yes)
		(layer "In2.Cu")
		(net "M_B_CPU1_SA_CS_N<2>")
	)
	(gr_poly
		(pts
			(xy 86.083394 -255.751838) (xy 86.036404 -255.599438) (xy 85.774784 -255.599438) (xy 85.727794 -255.751838)
			(xy 85.727794 -255.796288) (xy 86.083394 -255.796288)
		)
		(stroke
			(width 0)
			(type solid)
		)
		(fill yes)
		(layer "In2.Cu")
		(net "M_B_CPU1_SA_CA<0>")
	)
	(gr_poly
		(pts
			(xy 86.083394 -255.343406) (xy 86.083394 -255.298956) (xy 85.727794 -255.298956) (xy 85.727794 -255.343406)
			(xy 85.774784 -255.495806) (xy 86.036404 -255.495806)
		)
		(stroke
			(width 0)
			(type solid)
		)
		(fill yes)
		(layer "In2.Cu")
		(net "M_B_CPU1_SA_CA<1>")
	)
	(gr_poly
		(pts
			(xy 86.083394 -254.124206) (xy 86.036404 -253.971806) (xy 85.774784 -253.971806) (xy 85.727794 -254.124206)
			(xy 85.727794 -254.168402) (xy 86.083394 -254.168402)
		)
		(stroke
			(width 0)
			(type solid)
		)
		(fill yes)
		(layer "In2.Cu")
		(net "M_B_CPU1_SA_CA<4>")
	)
	(gr_poly
		(pts
			(xy 86.091776 -253.715774) (xy 86.091776 -253.671324) (xy 85.736176 -253.671324) (xy 85.736176 -253.715774)
			(xy 85.783166 -253.868174) (xy 86.044786 -253.868174)
		)
		(stroke
			(width 0)
			(type solid)
		)
		(fill yes)
		(layer "In2.Cu")
		(net "M_B_CPU1_SA_CA<5>")
	)
	(gr_poly
		(pts
			(xy 86.156038 -275.356574) (xy 86.04758 -275.239734) (xy 86.009226 -275.217636) (xy 85.831426 -275.525484)
			(xy 85.86978 -275.547582) (xy 86.025228 -275.583142)
		)
		(stroke
			(width 0)
			(type solid)
		)
		(fill yes)
		(layer "In2.Cu")
		(net "M_B_CPU1_SA_DQ<4>")
	)
	(gr_poly
		(pts
			(xy 86.157308 -276.982428) (xy 86.04885 -276.865588) (xy 86.010496 -276.84349) (xy 85.832696 -277.151338)
			(xy 85.87105 -277.173436) (xy 86.026498 -277.208996)
		)
		(stroke
			(width 0)
			(type solid)
		)
		(fill yes)
		(layer "In2.Cu")
		(net "M_B_CPU1_SA_DQ<4>")
	)
	(gr_poly
		(pts
			(xy 86.162896 -273.717766) (xy 86.054438 -273.600926) (xy 86.016084 -273.578828) (xy 85.838284 -273.886676)
			(xy 85.876638 -273.908774) (xy 86.032086 -273.944334)
		)
		(stroke
			(width 0)
			(type solid)
		)
		(fill yes)
		(layer "In2.Cu")
		(net "M_B_CPU1_SA_DQ<5>")
	)
	(gr_poly
		(pts
			(xy 86.294722 -227.28682) (xy 86.333076 -227.264722) (xy 86.155276 -226.956874) (xy 86.116922 -226.978972)
			(xy 86.008464 -227.095812) (xy 86.139274 -227.32238)
		)
		(stroke
			(width 0)
			(type solid)
		)
		(fill yes)
		(layer "In2.Cu")
		(net "M_B_CPU1_SB_DQ<17>")
	)
	(gr_poly
		(pts
			(xy 86.296754 -228.917754) (xy 86.335108 -228.895656) (xy 86.157308 -228.587808) (xy 86.118954 -228.609906)
			(xy 86.010496 -228.726746) (xy 86.141306 -228.953314)
		)
		(stroke
			(width 0)
			(type solid)
		)
		(fill yes)
		(layer "In2.Cu")
		(net "M_B_CPU1_SB_DQ<16>")
	)
	(gr_poly
		(pts
			(xy 86.299294 -224.038414) (xy 86.337648 -224.016316) (xy 86.159848 -223.708468) (xy 86.121494 -223.730566)
			(xy 86.013036 -223.847406) (xy 86.143846 -224.073974)
		)
		(stroke
			(width 0)
			(type solid)
		)
		(fill yes)
		(layer "In2.Cu")
		(net "M_B_CPU1_SB_DQS_DN<7>")
	)
	(gr_poly
		(pts
			(xy 86.301326 -225.67011) (xy 86.33968 -225.648012) (xy 86.16188 -225.340164) (xy 86.123526 -225.362262)
			(xy 86.015068 -225.479102) (xy 86.145878 -225.70567)
		)
		(stroke
			(width 0)
			(type solid)
		)
		(fill yes)
		(layer "In2.Cu")
		(net "M_B_CPU1_SB_DQS_DP<2>")
	)
	(gr_poly
		(pts
			(xy 86.40445 -277.978362) (xy 86.442804 -277.956264) (xy 86.265004 -277.648416) (xy 86.22665 -277.670514)
			(xy 86.118192 -277.787354) (xy 86.249002 -278.013922)
		)
		(stroke
			(width 0)
			(type solid)
		)
		(fill yes)
		(layer "In2.Cu")
		(net "M_B_CPU1_SA_DQS_DP<5>")
	)
	(gr_poly
		(pts
			(xy 86.40445 -276.350476) (xy 86.442804 -276.328378) (xy 86.265004 -276.02053) (xy 86.22665 -276.042628)
			(xy 86.118192 -276.159468) (xy 86.249002 -276.386036)
		)
		(stroke
			(width 0)
			(type solid)
		)
		(fill yes)
		(layer "In2.Cu")
		(net "M_B_CPU1_SA_DQS_DP<5>")
	)
	(gr_poly
		(pts
			(xy 86.408006 -228.300026) (xy 86.516464 -228.183186) (xy 86.385654 -227.956618) (xy 86.230206 -227.992178)
			(xy 86.191852 -228.014276) (xy 86.369652 -228.322124)
		)
		(stroke
			(width 0)
			(type solid)
		)
		(fill yes)
		(layer "In2.Cu")
		(net "M_B_CPU1_SB_DQ<18>")
	)
	(gr_poly
		(pts
			(xy 86.408006 -223.416622) (xy 86.516464 -223.299782) (xy 86.385654 -223.073214) (xy 86.230206 -223.108774)
			(xy 86.191852 -223.130872) (xy 86.369652 -223.43872)
		)
		(stroke
			(width 0)
			(type solid)
		)
		(fill yes)
		(layer "In2.Cu")
		(net "M_B_CPU1_SB_DQS_DP<7>")
	)
	(gr_poly
		(pts
			(xy 86.410038 -226.676204) (xy 86.518496 -226.559364) (xy 86.387686 -226.332796) (xy 86.232238 -226.368356)
			(xy 86.193884 -226.390454) (xy 86.371684 -226.698302)
		)
		(stroke
			(width 0)
			(type solid)
		)
		(fill yes)
		(layer "In2.Cu")
		(net "M_B_CPU1_SB_DQ<19>")
	)
	(gr_poly
		(pts
			(xy 86.410038 -225.048318) (xy 86.518496 -224.931478) (xy 86.387686 -224.70491) (xy 86.232238 -224.74047)
			(xy 86.193884 -224.762568) (xy 86.371684 -225.070416)
		)
		(stroke
			(width 0)
			(type solid)
		)
		(fill yes)
		(layer "In2.Cu")
		(net "M_B_CPU1_SB_DQS_DN<2>")
	)
	(gr_poly
		(pts
			(xy 86.432898 -242.905026) (xy 86.432898 -242.860576) (xy 86.077298 -242.860576) (xy 86.077298 -242.905026)
			(xy 86.124288 -243.057426) (xy 86.385908 -243.057426)
		)
		(stroke
			(width 0)
			(type solid)
		)
		(fill yes)
		(layer "In2.Cu")
		(net "M_B_CPU1_SB_DQS_DN<4>")
	)
	(gr_poly
		(pts
			(xy 86.43493 -249.416062) (xy 86.43493 -249.371612) (xy 86.07933 -249.371612) (xy 86.07933 -249.416062)
			(xy 86.12632 -249.568462) (xy 86.38794 -249.568462)
		)
		(stroke
			(width 0)
			(type solid)
		)
		(fill yes)
		(layer "In2.Cu")
		(net "M_B_CPU1_SB_CA<0>")
	)
	(gr_poly
		(pts
			(xy 86.43493 -244.532658) (xy 86.43493 -244.488208) (xy 86.07933 -244.488208) (xy 86.07933 -244.532658)
			(xy 86.12632 -244.685058) (xy 86.38794 -244.685058)
		)
		(stroke
			(width 0)
			(type solid)
		)
		(fill yes)
		(layer "In2.Cu")
		(net "M_B_CPU1_SB_CB<6>")
	)
	(gr_poly
		(pts
			(xy 86.43493 -240.057178) (xy 86.38794 -239.904778) (xy 86.12632 -239.904778) (xy 86.07933 -240.057178)
			(xy 86.07933 -240.101628) (xy 86.43493 -240.101628)
		)
		(stroke
			(width 0)
			(type solid)
		)
		(fill yes)
		(layer "In2.Cu")
		(net "M_B_CPU1_SB_CB<1>")
	)
	(gr_poly
		(pts
			(xy 86.43493 -239.649254) (xy 86.43493 -239.604804) (xy 86.07933 -239.604804) (xy 86.07933 -239.649254)
			(xy 86.12632 -239.801654) (xy 86.38794 -239.801654)
		)
		(stroke
			(width 0)
			(type solid)
		)
		(fill yes)
		(layer "In2.Cu")
		(net "M_A_CPU1_SB_DQ<0>")
	)
	(gr_poly
		(pts
			(xy 86.43493 -235.174282) (xy 86.38794 -235.021882) (xy 86.12632 -235.021882) (xy 86.07933 -235.174282)
			(xy 86.07933 -235.218478) (xy 86.43493 -235.218478)
		)
		(stroke
			(width 0)
			(type solid)
		)
		(fill yes)
		(layer "In2.Cu")
		(net "M_A_CPU1_SB_DQ<7>")
	)
	(gr_poly
		(pts
			(xy 86.43493 -234.76585) (xy 86.43493 -234.721654) (xy 86.07933 -234.721654) (xy 86.07933 -234.76585)
			(xy 86.12632 -234.91825) (xy 86.38794 -234.91825)
		)
		(stroke
			(width 0)
			(type solid)
		)
		(fill yes)
		(layer "In2.Cu")
		(net "M_B_CPU1_SB_DQ<8>")
	)
	(gr_poly
		(pts
			(xy 86.43493 -230.290878) (xy 86.38794 -230.138478) (xy 86.12632 -230.138478) (xy 86.07933 -230.290878)
			(xy 86.07933 -230.335074) (xy 86.43493 -230.335074)
		)
		(stroke
			(width 0)
			(type solid)
		)
		(fill yes)
		(layer "In2.Cu")
		(net "M_B_CPU1_SB_DQ<15>")
	)
	(gr_poly
		(pts
			(xy 86.443058 -273.833336) (xy 86.404704 -273.811238) (xy 86.249256 -273.775678) (xy 86.118446 -274.002246)
			(xy 86.226904 -274.119086) (xy 86.265258 -274.141184)
		)
		(stroke
			(width 0)
			(type solid)
		)
		(fill yes)
		(layer "In2.Cu")
		(net "M_B_CPU1_SA_DQ<6>")
	)
	(gr_poly
		(pts
			(xy 86.443312 -236.393482) (xy 86.443312 -236.349032) (xy 86.087712 -236.349032) (xy 86.087712 -236.393482)
			(xy 86.134702 -236.545882) (xy 86.396322 -236.545882)
		)
		(stroke
			(width 0)
			(type solid)
		)
		(fill yes)
		(layer "In2.Cu")
		(net "M_A_CPU1_SB_DQ<4>")
	)
	(gr_poly
		(pts
			(xy 86.443566 -248.196354) (xy 86.396576 -248.043954) (xy 86.134956 -248.043954) (xy 86.087966 -248.196354)
			(xy 86.087966 -248.240804) (xy 86.443566 -248.240804)
		)
		(stroke
			(width 0)
			(type solid)
		)
		(fill yes)
		(layer "In2.Cu")
		(net "M_B_CPU1_SB_CA<3>")
	)
	(gr_poly
		(pts
			(xy 86.443566 -247.787922) (xy 86.443566 -247.743472) (xy 86.087966 -247.743472) (xy 86.087966 -247.787922)
			(xy 86.134956 -247.940322) (xy 86.396576 -247.940322)
		)
		(stroke
			(width 0)
			(type solid)
		)
		(fill yes)
		(layer "In2.Cu")
		(net "M_B_CPU1_SB_CA<4>")
	)
	(gr_poly
		(pts
			(xy 86.443566 -246.568722) (xy 86.396576 -246.416322) (xy 86.134956 -246.416322) (xy 86.087966 -246.568722)
			(xy 86.087966 -246.613172) (xy 86.443566 -246.613172)
		)
		(stroke
			(width 0)
			(type solid)
		)
		(fill yes)
		(layer "In2.Cu")
		(net "M_B_CPU1_SB_PAR")
	)
	(gr_poly
		(pts
			(xy 86.443566 -246.16029) (xy 86.443566 -246.11584) (xy 86.087966 -246.11584) (xy 86.087966 -246.16029)
			(xy 86.134956 -246.31269) (xy 86.396576 -246.31269)
		)
		(stroke
			(width 0)
			(type solid)
		)
		(fill yes)
		(layer "In2.Cu")
		(net "M_B_CPU1_SB_CS_N<0>")
	)
	(gr_poly
		(pts
			(xy 86.443566 -243.313458) (xy 86.396576 -243.161058) (xy 86.134956 -243.161058) (xy 86.087966 -243.313458)
			(xy 86.087966 -243.357654) (xy 86.443566 -243.357654)
		)
		(stroke
			(width 0)
			(type solid)
		)
		(fill yes)
		(layer "In2.Cu")
		(net "M_B_CPU1_SB_CB<5>")
	)
	(gr_poly
		(pts
			(xy 86.443566 -241.685318) (xy 86.396576 -241.532918) (xy 86.134956 -241.532918) (xy 86.087966 -241.685318)
			(xy 86.087966 -241.729768) (xy 86.443566 -241.729768)
		)
		(stroke
			(width 0)
			(type solid)
		)
		(fill yes)
		(layer "In2.Cu")
		(net "M_B_CPU1_SB_DQS_DN<9>")
	)
	(gr_poly
		(pts
			(xy 86.443566 -241.276886) (xy 86.443566 -241.232436) (xy 86.087966 -241.232436) (xy 86.087966 -241.276886)
			(xy 86.134956 -241.429286) (xy 86.396576 -241.429286)
		)
		(stroke
			(width 0)
			(type solid)
		)
		(fill yes)
		(layer "In2.Cu")
		(net "M_B_CPU1_SB_CB<2>")
	)
	(gr_poly
		(pts
			(xy 86.443566 -238.430054) (xy 86.396576 -238.277654) (xy 86.134956 -238.277654) (xy 86.087966 -238.430054)
			(xy 86.087966 -238.47425) (xy 86.443566 -238.47425)
		)
		(stroke
			(width 0)
			(type solid)
		)
		(fill yes)
		(layer "In2.Cu")
		(net "M_A_CPU1_SB_DQ<3>")
	)
	(gr_poly
		(pts
			(xy 86.443566 -238.021114) (xy 86.443566 -237.976918) (xy 86.087966 -237.976918) (xy 86.087966 -238.021114)
			(xy 86.134956 -238.173514) (xy 86.396576 -238.173514)
		)
		(stroke
			(width 0)
			(type solid)
		)
		(fill yes)
		(layer "In2.Cu")
		(net "M_A_CPU1_SB_DQS_DP<0>")
	)
	(gr_poly
		(pts
			(xy 86.443566 -236.802422) (xy 86.396576 -236.650022) (xy 86.134956 -236.650022) (xy 86.087966 -236.802422)
			(xy 86.087966 -236.846618) (xy 86.443566 -236.846618)
		)
		(stroke
			(width 0)
			(type solid)
		)
		(fill yes)
		(layer "In2.Cu")
		(net "M_A_CPU1_SB_DQS_DP<5>")
	)
	(gr_poly
		(pts
			(xy 86.443566 -233.54665) (xy 86.396576 -233.39425) (xy 86.134956 -233.39425) (xy 86.087966 -233.54665)
			(xy 86.087966 -233.590846) (xy 86.443566 -233.590846)
		)
		(stroke
			(width 0)
			(type solid)
		)
		(fill yes)
		(layer "In2.Cu")
		(net "M_B_CPU1_SB_DQ<11>")
	)
	(gr_poly
		(pts
			(xy 86.443566 -233.13771) (xy 86.443566 -233.093514) (xy 86.087966 -233.093514) (xy 86.087966 -233.13771)
			(xy 86.134956 -233.29011) (xy 86.396576 -233.29011)
		)
		(stroke
			(width 0)
			(type solid)
		)
		(fill yes)
		(layer "In2.Cu")
		(net "M_B_CPU1_SB_DQS_DP<1>")
	)
	(gr_poly
		(pts
			(xy 86.443566 -231.919018) (xy 86.396576 -231.766618) (xy 86.134956 -231.766618) (xy 86.087966 -231.919018)
			(xy 86.087966 -231.963214) (xy 86.443566 -231.963214)
		)
		(stroke
			(width 0)
			(type solid)
		)
		(fill yes)
		(layer "In2.Cu")
		(net "M_B_CPU1_SB_DQS_DP<6>")
	)
	(gr_poly
		(pts
			(xy 86.443566 -231.510078) (xy 86.443566 -231.465882) (xy 86.087966 -231.465882) (xy 86.087966 -231.510078)
			(xy 86.134956 -231.662478) (xy 86.396576 -231.662478)
		)
		(stroke
			(width 0)
			(type solid)
		)
		(fill yes)
		(layer "In2.Cu")
		(net "M_B_CPU1_SB_DQ<12>")
	)
	(gr_poly
		(pts
			(xy 86.447376 -268.94282) (xy 86.409022 -268.920722) (xy 86.253574 -268.885162) (xy 86.122764 -269.11173)
			(xy 86.231222 -269.22857) (xy 86.269576 -269.250668)
		)
		(stroke
			(width 0)
			(type solid)
		)
		(fill yes)
		(layer "In2.Cu")
		(net "M_A_CPU1_SA_DQ<14>")
	)
	(gr_poly
		(pts
			(xy 86.448138 -277.079964) (xy 86.409784 -277.057866) (xy 86.254336 -277.022306) (xy 86.123526 -277.248874)
			(xy 86.231984 -277.365714) (xy 86.270338 -277.387812)
		)
		(stroke
			(width 0)
			(type solid)
		)
		(fill yes)
		(layer "In2.Cu")
		(net "M_B_CPU1_SA_DQS_DP<5>")
	)
	(gr_poly
		(pts
			(xy 86.449154 -275.450046) (xy 86.4108 -275.427948) (xy 86.255352 -275.392388) (xy 86.124542 -275.618956)
			(xy 86.233 -275.735796) (xy 86.271354 -275.757894)
		)
		(stroke
			(width 0)
			(type solid)
		)
		(fill yes)
		(layer "In2.Cu")
		(net "M_B_CPU1_SA_DQS_DP<5>")
	)
	(gr_poly
		(pts
			(xy 86.449408 -280.33345) (xy 86.411054 -280.311352) (xy 86.255606 -280.275792) (xy 86.124796 -280.50236)
			(xy 86.233254 -280.6192) (xy 86.271608 -280.641298)
		)
		(stroke
			(width 0)
			(type solid)
		)
		(fill yes)
		(layer "In2.Cu")
		(net "M_B_CPU1_SA_DQ<3>")
	)
	(gr_poly
		(pts
			(xy 86.452202 -244.94109) (xy 86.405212 -244.78869) (xy 86.143592 -244.78869) (xy 86.096602 -244.94109)
			(xy 86.096602 -244.985286) (xy 86.452202 -244.985286)
		)
		(stroke
			(width 0)
			(type solid)
		)
		(fill yes)
		(layer "In2.Cu")
		(net "M_B_CPU1_SB_CS_N<1>")
	)
	(gr_poly
		(pts
			(xy 86.539832 -279.343866) (xy 86.492842 -279.191466) (xy 86.231222 -279.191466) (xy 86.184232 -279.343866)
			(xy 86.184232 -279.388062) (xy 86.539832 -279.388062)
		)
		(stroke
			(width 0)
			(type solid)
		)
		(fill yes)
		(layer "In2.Cu")
		(net "M_B_CPU1_SA_DQS_DN<0>")
	)
	(gr_poly
		(pts
			(xy 86.553294 -267.960094) (xy 86.506304 -267.807694) (xy 86.244684 -267.807694) (xy 86.197694 -267.960094)
			(xy 86.197694 -268.004544) (xy 86.553294 -268.004544)
		)
		(stroke
			(width 0)
			(type solid)
		)
		(fill yes)
		(layer "In2.Cu")
		(net "M_A_CPU1_SA_DQ<13>")
	)
	(gr_poly
		(pts
			(xy 86.553294 -267.551662) (xy 86.553294 -267.507212) (xy 86.197694 -267.507212) (xy 86.197694 -267.551662)
			(xy 86.244684 -267.704062) (xy 86.506304 -267.704062)
		)
		(stroke
			(width 0)
			(type solid)
		)
		(fill yes)
		(layer "In2.Cu")
		(net "M_B_CPU1_SA_DQ<16>")
	)
	(gr_poly
		(pts
			(xy 86.553294 -266.332462) (xy 86.506304 -266.180062) (xy 86.244684 -266.180062) (xy 86.197694 -266.332462)
			(xy 86.197694 -266.376658) (xy 86.553294 -266.376658)
		)
		(stroke
			(width 0)
			(type solid)
		)
		(fill yes)
		(layer "In2.Cu")
		(net "M_B_CPU1_SA_DQ<19>")
	)
	(gr_poly
		(pts
			(xy 86.553294 -265.92403) (xy 86.553294 -265.87958) (xy 86.197694 -265.87958) (xy 86.197694 -265.92403)
			(xy 86.244684 -266.07643) (xy 86.506304 -266.07643)
		)
		(stroke
			(width 0)
			(type solid)
		)
		(fill yes)
		(layer "In2.Cu")
		(net "M_B_CPU1_SA_DQS_DP<2>")
	)
	(gr_poly
		(pts
			(xy 86.553294 -264.70483) (xy 86.506304 -264.55243) (xy 86.244684 -264.55243) (xy 86.197694 -264.70483)
			(xy 86.197694 -264.749026) (xy 86.553294 -264.749026)
		)
		(stroke
			(width 0)
			(type solid)
		)
		(fill yes)
		(layer "In2.Cu")
		(net "M_B_CPU1_SA_DQS_DP<7>")
	)
	(gr_poly
		(pts
			(xy 86.553294 -264.29589) (xy 86.553294 -264.251694) (xy 86.197694 -264.251694) (xy 86.197694 -264.29589)
			(xy 86.244684 -264.44829) (xy 86.506304 -264.44829)
		)
		(stroke
			(width 0)
			(type solid)
		)
		(fill yes)
		(layer "In2.Cu")
		(net "M_B_CPU1_SA_DQ<20>")
	)
	(gr_poly
		(pts
			(xy 86.553294 -263.07669) (xy 86.506304 -262.92429) (xy 86.244684 -262.92429) (xy 86.197694 -263.07669)
			(xy 86.197694 -263.12114) (xy 86.553294 -263.12114)
		)
		(stroke
			(width 0)
			(type solid)
		)
		(fill yes)
		(layer "In2.Cu")
		(net "M_B_CPU1_SA_DQ<23>")
	)
	(gr_poly
		(pts
			(xy 86.553294 -262.668258) (xy 86.553294 -262.623808) (xy 86.197694 -262.623808) (xy 86.197694 -262.668258)
			(xy 86.244684 -262.820658) (xy 86.506304 -262.820658)
		)
		(stroke
			(width 0)
			(type solid)
		)
		(fill yes)
		(layer "In2.Cu")
		(net "M_B_CPU1_SA_CB<0>")
	)
	(gr_poly
		(pts
			(xy 86.553294 -261.449058) (xy 86.506304 -261.296658) (xy 86.244684 -261.296658) (xy 86.197694 -261.449058)
			(xy 86.197694 -261.493508) (xy 86.553294 -261.493508)
		)
		(stroke
			(width 0)
			(type solid)
		)
		(fill yes)
		(layer "In2.Cu")
		(net "M_B_CPU1_SA_CB<3>")
	)
	(gr_poly
		(pts
			(xy 86.553294 -261.040626) (xy 86.553294 -260.996176) (xy 86.197694 -260.996176) (xy 86.197694 -261.040626)
			(xy 86.244684 -261.193026) (xy 86.506304 -261.193026)
		)
		(stroke
			(width 0)
			(type solid)
		)
		(fill yes)
		(layer "In2.Cu")
		(net "M_B_CPU1_SA_DQS_DP<4>")
	)
	(gr_poly
		(pts
			(xy 86.553294 -259.821426) (xy 86.506304 -259.669026) (xy 86.244684 -259.669026) (xy 86.197694 -259.821426)
			(xy 86.197694 -259.865622) (xy 86.553294 -259.865622)
		)
		(stroke
			(width 0)
			(type solid)
		)
		(fill yes)
		(layer "In2.Cu")
		(net "M_B_CPU1_SA_DQS_DP<9>")
	)
	(gr_poly
		(pts
			(xy 86.553294 -259.412486) (xy 86.553294 -259.36829) (xy 86.197694 -259.36829) (xy 86.197694 -259.412486)
			(xy 86.244684 -259.564886) (xy 86.506304 -259.564886)
		)
		(stroke
			(width 0)
			(type solid)
		)
		(fill yes)
		(layer "In2.Cu")
		(net "M_B_CPU1_SA_CB<4>")
	)
	(gr_poly
		(pts
			(xy 86.553294 -258.193286) (xy 86.506304 -258.040886) (xy 86.244684 -258.040886) (xy 86.197694 -258.193286)
			(xy 86.197694 -258.237736) (xy 86.553294 -258.237736)
		)
		(stroke
			(width 0)
			(type solid)
		)
		(fill yes)
		(layer "In2.Cu")
		(net "M_B_CPU1_SA_CB<7>")
	)
	(gr_poly
		(pts
			(xy 86.553294 -257.784854) (xy 86.553294 -257.740404) (xy 86.197694 -257.740404) (xy 86.197694 -257.784854)
			(xy 86.244684 -257.937254) (xy 86.506304 -257.937254)
		)
		(stroke
			(width 0)
			(type solid)
		)
		(fill yes)
		(layer "In2.Cu")
		(net "M_B_CPU1_ALERT_N")
	)
	(gr_poly
		(pts
			(xy 86.553294 -256.565654) (xy 86.506304 -256.413254) (xy 86.244684 -256.413254) (xy 86.197694 -256.565654)
			(xy 86.197694 -256.610104) (xy 86.553294 -256.610104)
		)
		(stroke
			(width 0)
			(type solid)
		)
		(fill yes)
		(layer "In2.Cu")
		(net "M_B_CPU1_SA_CS_N<3>")
	)
	(gr_poly
		(pts
			(xy 86.553294 -256.157222) (xy 86.553294 -256.112772) (xy 86.197694 -256.112772) (xy 86.197694 -256.157222)
			(xy 86.244684 -256.309622) (xy 86.506304 -256.309622)
		)
		(stroke
			(width 0)
			(type solid)
		)
		(fill yes)
		(layer "In2.Cu")
		(net "M_B_CPU1_SA_CS_N<1>")
	)
	(gr_poly
		(pts
			(xy 86.553294 -254.938022) (xy 86.506304 -254.785622) (xy 86.244684 -254.785622) (xy 86.197694 -254.938022)
			(xy 86.197694 -254.982218) (xy 86.553294 -254.982218)
		)
		(stroke
			(width 0)
			(type solid)
		)
		(fill yes)
		(layer "In2.Cu")
		(net "M_B_CPU1_SA_CA<2>")
	)
	(gr_poly
		(pts
			(xy 86.553294 -254.529082) (xy 86.553294 -254.484886) (xy 86.197694 -254.484886) (xy 86.197694 -254.529082)
			(xy 86.244684 -254.681482) (xy 86.506304 -254.681482)
		)
		(stroke
			(width 0)
			(type solid)
		)
		(fill yes)
		(layer "In2.Cu")
		(net "M_B_CPU1_SA_CA<3>")
	)
	(gr_poly
		(pts
			(xy 86.553548 -272.843498) (xy 86.506558 -272.691098) (xy 86.244938 -272.691098) (xy 86.197948 -272.843498)
			(xy 86.197948 -272.887948) (xy 86.553548 -272.887948)
		)
		(stroke
			(width 0)
			(type solid)
		)
		(fill yes)
		(layer "In2.Cu")
		(net "M_B_CPU1_SA_DQ<7>")
	)
	(gr_poly
		(pts
			(xy 86.632542 -274.531582) (xy 86.524084 -274.414742) (xy 86.48573 -274.392644) (xy 86.30793 -274.700492)
			(xy 86.346284 -274.72259) (xy 86.501732 -274.75815)
		)
		(stroke
			(width 0)
			(type solid)
		)
		(fill yes)
		(layer "In2.Cu")
		(net "M_B_CPU1_SA_DQ<4>")
	)
	(gr_poly
		(pts
			(xy 86.76894 -226.480116) (xy 86.807294 -226.458018) (xy 86.629494 -226.15017) (xy 86.59114 -226.172268)
			(xy 86.482682 -226.289108) (xy 86.613492 -226.515676)
		)
		(stroke
			(width 0)
			(type solid)
		)
		(fill yes)
		(layer "In2.Cu")
		(net "M_B_CPU1_SB_DQS_DP<2>")
	)
	(gr_poly
		(pts
			(xy 86.769194 -224.85223) (xy 86.807548 -224.830132) (xy 86.629748 -224.522284) (xy 86.591394 -224.544382)
			(xy 86.482936 -224.661222) (xy 86.613746 -224.88779)
		)
		(stroke
			(width 0)
			(type solid)
		)
		(fill yes)
		(layer "In2.Cu")
		(net "M_B_CPU1_SB_DQS_DN<7>")
	)
	(gr_poly
		(pts
			(xy 86.771226 -223.228408) (xy 86.80958 -223.20631) (xy 86.63178 -222.898462) (xy 86.593426 -222.92056)
			(xy 86.484968 -223.0374) (xy 86.615778 -223.263968)
		)
		(stroke
			(width 0)
			(type solid)
		)
		(fill yes)
		(layer "In2.Cu")
		(net "M_B_CPU1_SB_DQ<20>")
	)
	(gr_poly
		(pts
			(xy 86.877906 -225.858324) (xy 86.986364 -225.741484) (xy 86.855554 -225.514916) (xy 86.700106 -225.550476)
			(xy 86.661752 -225.572574) (xy 86.839552 -225.880422)
		)
		(stroke
			(width 0)
			(type solid)
		)
		(fill yes)
		(layer "In2.Cu")
		(net "M_B_CPU1_SB_DQS_DN<2>")
	)
	(gr_poly
		(pts
			(xy 86.879938 -224.234502) (xy 86.988396 -224.117662) (xy 86.857586 -223.891094) (xy 86.702138 -223.926654)
			(xy 86.663784 -223.948752) (xy 86.841584 -224.2566)
		)
		(stroke
			(width 0)
			(type solid)
		)
		(fill yes)
		(layer "In2.Cu")
		(net "M_B_CPU1_SB_DQS_DP<7>")
	)
	(gr_poly
		(pts
			(xy 86.884256 -227.497132) (xy 86.992714 -227.380292) (xy 86.861904 -227.153724) (xy 86.706456 -227.189284)
			(xy 86.668102 -227.211382) (xy 86.845902 -227.51923)
		)
		(stroke
			(width 0)
			(type solid)
		)
		(fill yes)
		(layer "In2.Cu")
		(net "M_B_CPU1_SB_DQ<19>")
	)
	(gr_poly
		(pts
			(xy 86.903814 -229.61727) (xy 86.943946 -229.598474) (xy 86.793578 -229.276402) (xy 86.753446 -229.294944)
			(xy 86.635082 -229.402132) (xy 86.745826 -229.639114)
		)
		(stroke
			(width 0)
			(type solid)
		)
		(fill yes)
		(layer "In2.Cu")
		(net "M_B_CPU1_SB_DQ<16>")
	)
	(gr_poly
		(pts
			(xy 86.905084 -245.346474) (xy 86.905084 -245.302278) (xy 86.549484 -245.302278) (xy 86.549484 -245.346474)
			(xy 86.596474 -245.498874) (xy 86.858094 -245.498874)
		)
		(stroke
			(width 0)
			(type solid)
		)
		(fill yes)
		(layer "In2.Cu")
		(net "M_B_CPU1_SB_CS_N<3>")
	)
	(gr_poly
		(pts
			(xy 86.90737 -242.090702) (xy 86.90737 -242.046252) (xy 86.55177 -242.046252) (xy 86.55177 -242.090702)
			(xy 86.59876 -242.243102) (xy 86.86038 -242.243102)
		)
		(stroke
			(width 0)
			(type solid)
		)
		(fill yes)
		(layer "In2.Cu")
		(net "M_B_CPU1_SB_DQS_DP<9>")
	)
	(gr_poly
		(pts
			(xy 86.90737 -237.616238) (xy 86.86038 -237.463838) (xy 86.59876 -237.463838) (xy 86.55177 -237.616238)
			(xy 86.55177 -237.660434) (xy 86.90737 -237.660434)
		)
		(stroke
			(width 0)
			(type solid)
		)
		(fill yes)
		(layer "In2.Cu")
		(net "M_A_CPU1_SB_DQS_DN<0>")
	)
	(gr_poly
		(pts
			(xy 86.90737 -237.207298) (xy 86.90737 -237.163102) (xy 86.55177 -237.163102) (xy 86.55177 -237.207298)
			(xy 86.59876 -237.359698) (xy 86.86038 -237.359698)
		)
		(stroke
			(width 0)
			(type solid)
		)
		(fill yes)
		(layer "In2.Cu")
		(net "M_A_CPU1_SB_DQS_DN<5>")
	)
	(gr_poly
		(pts
			(xy 86.912958 -281.158696) (xy 86.874604 -281.136598) (xy 86.719156 -281.101038) (xy 86.588346 -281.327606)
			(xy 86.696804 -281.444446) (xy 86.735158 -281.466544)
		)
		(stroke
			(width 0)
			(type solid)
		)
		(fill yes)
		(layer "In2.Cu")
		(net "M_B_CPU1_SA_DQ<0>")
	)
	(gr_poly
		(pts
			(xy 86.913212 -235.988098) (xy 86.866222 -235.835698) (xy 86.604602 -235.835698) (xy 86.557612 -235.988098)
			(xy 86.557612 -236.032548) (xy 86.913212 -236.032548)
		)
		(stroke
			(width 0)
			(type solid)
		)
		(fill yes)
		(layer "In2.Cu")
		(net "M_A_CPU1_SB_DQ<6>")
	)
	(gr_poly
		(pts
			(xy 86.913466 -248.601738) (xy 86.913466 -248.557542) (xy 86.557866 -248.557542) (xy 86.557866 -248.601738)
			(xy 86.604856 -248.754138) (xy 86.866476 -248.754138)
		)
		(stroke
			(width 0)
			(type solid)
		)
		(fill yes)
		(layer "In2.Cu")
		(net "M_B_CPU1_SB_CA<2>")
	)
	(gr_poly
		(pts
			(xy 86.913466 -247.382538) (xy 86.866476 -247.230138) (xy 86.604856 -247.230138) (xy 86.557866 -247.382538)
			(xy 86.557866 -247.426988) (xy 86.913466 -247.426988)
		)
		(stroke
			(width 0)
			(type solid)
		)
		(fill yes)
		(layer "In2.Cu")
		(net "M_B_CPU1_SB_CA<5>")
	)
	(gr_poly
		(pts
			(xy 86.913466 -246.974106) (xy 86.913466 -246.929656) (xy 86.557866 -246.929656) (xy 86.557866 -246.974106)
			(xy 86.604856 -247.126506) (xy 86.866476 -247.126506)
		)
		(stroke
			(width 0)
			(type solid)
		)
		(fill yes)
		(layer "In2.Cu")
		(net "M_B_CPU1_SB_CA<6>")
	)
	(gr_poly
		(pts
			(xy 86.913466 -245.754906) (xy 86.866476 -245.602506) (xy 86.604856 -245.602506) (xy 86.557866 -245.754906)
			(xy 86.557866 -245.799356) (xy 86.913466 -245.799356)
		)
		(stroke
			(width 0)
			(type solid)
		)
		(fill yes)
		(layer "In2.Cu")
		(net "M_B_CPU1_SB_CS_N<2>")
	)
	(gr_poly
		(pts
			(xy 86.913466 -243.718334) (xy 86.913466 -243.674138) (xy 86.557866 -243.674138) (xy 86.557866 -243.718334)
			(xy 86.604856 -243.870734) (xy 86.866476 -243.870734)
		)
		(stroke
			(width 0)
			(type solid)
		)
		(fill yes)
		(layer "In2.Cu")
		(net "M_B_CPU1_SB_CB<7>")
	)
	(gr_poly
		(pts
			(xy 86.913466 -240.871502) (xy 86.866476 -240.719102) (xy 86.604856 -240.719102) (xy 86.557866 -240.871502)
			(xy 86.557866 -240.915952) (xy 86.913466 -240.915952)
		)
		(stroke
			(width 0)
			(type solid)
		)
		(fill yes)
		(layer "In2.Cu")
		(net "M_B_CPU1_SB_CB<0>")
	)
	(gr_poly
		(pts
			(xy 86.913466 -238.83493) (xy 86.913466 -238.790734) (xy 86.557866 -238.790734) (xy 86.557866 -238.83493)
			(xy 86.604856 -238.98733) (xy 86.866476 -238.98733)
		)
		(stroke
			(width 0)
			(type solid)
		)
		(fill yes)
		(layer "In2.Cu")
		(net "M_A_CPU1_SB_DQ<1>")
	)
	(gr_poly
		(pts
			(xy 86.913466 -233.952034) (xy 86.913466 -233.907584) (xy 86.557866 -233.907584) (xy 86.557866 -233.952034)
			(xy 86.604856 -234.104434) (xy 86.866476 -234.104434)
		)
		(stroke
			(width 0)
			(type solid)
		)
		(fill yes)
		(layer "In2.Cu")
		(net "M_B_CPU1_SB_DQ<9>")
	)
	(gr_poly
		(pts
			(xy 86.913466 -232.732834) (xy 86.866476 -232.580434) (xy 86.604856 -232.580434) (xy 86.557866 -232.732834)
			(xy 86.557866 -232.77703) (xy 86.913466 -232.77703)
		)
		(stroke
			(width 0)
			(type solid)
		)
		(fill yes)
		(layer "In2.Cu")
		(net "M_B_CPU1_SB_DQS_DN<1>")
	)
	(gr_poly
		(pts
			(xy 86.913466 -232.323894) (xy 86.913466 -232.279698) (xy 86.557866 -232.279698) (xy 86.557866 -232.323894)
			(xy 86.604856 -232.476294) (xy 86.866476 -232.476294)
		)
		(stroke
			(width 0)
			(type solid)
		)
		(fill yes)
		(layer "In2.Cu")
		(net "M_B_CPU1_SB_DQS_DN<6>")
	)
	(gr_poly
		(pts
			(xy 86.913466 -231.104694) (xy 86.866476 -230.952294) (xy 86.604856 -230.952294) (xy 86.557866 -231.104694)
			(xy 86.557866 -231.149144) (xy 86.913466 -231.149144)
		)
		(stroke
			(width 0)
			(type solid)
		)
		(fill yes)
		(layer "In2.Cu")
		(net "M_B_CPU1_SB_DQ<14>")
	)
	(gr_poly
		(pts
			(xy 86.916514 -274.640802) (xy 86.87816 -274.618704) (xy 86.722712 -274.583144) (xy 86.591902 -274.809712)
			(xy 86.70036 -274.926552) (xy 86.738714 -274.94865)
		)
		(stroke
			(width 0)
			(type solid)
		)
		(fill yes)
		(layer "In2.Cu")
		(net "M_B_CPU1_SA_DQS_DP<5>")
	)
	(gr_poly
		(pts
			(xy 86.921594 -242.499134) (xy 86.874604 -242.346734) (xy 86.612984 -242.346734) (xy 86.565994 -242.499134)
			(xy 86.565994 -242.54333) (xy 86.921594 -242.54333)
		)
		(stroke
			(width 0)
			(type solid)
		)
		(fill yes)
		(layer "In2.Cu")
		(net "M_B_CPU1_SB_DQS_DP<4>")
	)
	(gr_poly
		(pts
			(xy 86.921848 -249.01017) (xy 86.874858 -248.85777) (xy 86.613238 -248.85777) (xy 86.566248 -249.01017)
			(xy 86.566248 -249.05462) (xy 86.921848 -249.05462)
		)
		(stroke
			(width 0)
			(type solid)
		)
		(fill yes)
		(layer "In2.Cu")
		(net "M_B_CPU1_SB_CA<1>")
	)
	(gr_poly
		(pts
			(xy 86.921848 -244.126766) (xy 86.874858 -243.974366) (xy 86.613238 -243.974366) (xy 86.566248 -244.126766)
			(xy 86.566248 -244.171216) (xy 86.921848 -244.171216)
		)
		(stroke
			(width 0)
			(type solid)
		)
		(fill yes)
		(layer "In2.Cu")
		(net "M_B_CPU1_SB_CB<4>")
	)
	(gr_poly
		(pts
			(xy 86.921848 -240.46307) (xy 86.921848 -240.418874) (xy 86.566248 -240.418874) (xy 86.566248 -240.46307)
			(xy 86.613238 -240.61547) (xy 86.874858 -240.61547)
		)
		(stroke
			(width 0)
			(type solid)
		)
		(fill yes)
		(layer "In2.Cu")
		(net "M_B_CPU1_SB_CB<3>")
	)
	(gr_poly
		(pts
			(xy 86.921848 -239.243362) (xy 86.874858 -239.090962) (xy 86.613238 -239.090962) (xy 86.566248 -239.243362)
			(xy 86.566248 -239.287812) (xy 86.921848 -239.287812)
		)
		(stroke
			(width 0)
			(type solid)
		)
		(fill yes)
		(layer "In2.Cu")
		(net "M_A_CPU1_SB_DQ<2>")
	)
	(gr_poly
		(pts
			(xy 86.921848 -235.579666) (xy 86.921848 -235.53547) (xy 86.566248 -235.53547) (xy 86.566248 -235.579666)
			(xy 86.613238 -235.732066) (xy 86.874858 -235.732066)
		)
		(stroke
			(width 0)
			(type solid)
		)
		(fill yes)
		(layer "In2.Cu")
		(net "M_A_CPU1_SB_DQ<5>")
	)
	(gr_poly
		(pts
			(xy 86.921848 -234.360466) (xy 86.874858 -234.208066) (xy 86.613238 -234.208066) (xy 86.566248 -234.360466)
			(xy 86.566248 -234.404662) (xy 86.921848 -234.404662)
		)
		(stroke
			(width 0)
			(type solid)
		)
		(fill yes)
		(layer "In2.Cu")
		(net "M_B_CPU1_SB_DQ<10>")
	)
	(gr_poly
		(pts
			(xy 86.921848 -230.696262) (xy 86.921848 -230.652066) (xy 86.566248 -230.652066) (xy 86.566248 -230.696262)
			(xy 86.613238 -230.848662) (xy 86.874858 -230.848662)
		)
		(stroke
			(width 0)
			(type solid)
		)
		(fill yes)
		(layer "In2.Cu")
		(net "M_B_CPU1_SB_DQ<13>")
	)
	(gr_poly
		(pts
			(xy 86.993984 -278.188674) (xy 87.102442 -278.071834) (xy 86.971632 -277.845266) (xy 86.816184 -277.880826)
			(xy 86.77783 -277.902924) (xy 86.95563 -278.210772)
		)
		(stroke
			(width 0)
			(type solid)
		)
		(fill yes)
		(layer "In2.Cu")
		(net "M_B_CPU1_SA_DQS_DN<5>")
	)
	(gr_poly
		(pts
			(xy 86.993984 -276.560788) (xy 87.102442 -276.443948) (xy 86.971632 -276.21738) (xy 86.816184 -276.25294)
			(xy 86.77783 -276.275038) (xy 86.95563 -276.582886)
		)
		(stroke
			(width 0)
			(type solid)
		)
		(fill yes)
		(layer "In2.Cu")
		(net "M_B_CPU1_SA_DQS_DN<5>")
	)
	(gr_poly
		(pts
			(xy 87.014812 -272.029174) (xy 86.967822 -271.876774) (xy 86.706202 -271.876774) (xy 86.659212 -272.029174)
			(xy 86.659212 -272.073624) (xy 87.014812 -272.073624)
		)
		(stroke
			(width 0)
			(type solid)
		)
		(fill yes)
		(layer "In2.Cu")
		(net "M_A_CPU1_SA_DQ<8>")
	)
	(gr_poly
		(pts
			(xy 87.017352 -273.248882) (xy 87.017352 -273.204432) (xy 86.661752 -273.204432) (xy 86.661752 -273.248882)
			(xy 86.708742 -273.401282) (xy 86.970362 -273.401282)
		)
		(stroke
			(width 0)
			(type solid)
		)
		(fill yes)
		(layer "In2.Cu")
		(net "M_B_CPU1_SA_DQ<5>")
	)
	(gr_poly
		(pts
			(xy 87.023194 -280.168604) (xy 86.976204 -280.016204) (xy 86.714584 -280.016204) (xy 86.667594 -280.168604)
			(xy 86.667594 -280.2128) (xy 87.023194 -280.2128)
		)
		(stroke
			(width 0)
			(type solid)
		)
		(fill yes)
		(layer "In2.Cu")
		(net "M_B_CPU1_SA_DQ<3>")
	)
	(gr_poly
		(pts
			(xy 87.023194 -270.40205) (xy 86.976204 -270.24965) (xy 86.714584 -270.24965) (xy 86.667594 -270.40205)
			(xy 86.667594 -270.446246) (xy 87.023194 -270.446246)
		)
		(stroke
			(width 0)
			(type solid)
		)
		(fill yes)
		(layer "In2.Cu")
		(net "M_A_CPU1_SA_DQS_DN<1>")
	)
	(gr_poly
		(pts
			(xy 87.023194 -268.77391) (xy 86.976204 -268.62151) (xy 86.714584 -268.62151) (xy 86.667594 -268.77391)
			(xy 86.667594 -268.81836) (xy 87.023194 -268.81836)
		)
		(stroke
			(width 0)
			(type solid)
		)
		(fill yes)
		(layer "In2.Cu")
		(net "M_A_CPU1_SA_DQ<14>")
	)
	(gr_poly
		(pts
			(xy 87.023194 -268.365478) (xy 87.023194 -268.321028) (xy 86.667594 -268.321028) (xy 86.667594 -268.365478)
			(xy 86.714584 -268.517878) (xy 86.976204 -268.517878)
		)
		(stroke
			(width 0)
			(type solid)
		)
		(fill yes)
		(layer "In2.Cu")
		(net "M_A_CPU1_SA_DQ<15>")
	)
	(gr_poly
		(pts
			(xy 87.023194 -267.146278) (xy 86.976204 -266.993878) (xy 86.714584 -266.993878) (xy 86.667594 -267.146278)
			(xy 86.667594 -267.190474) (xy 87.023194 -267.190474)
		)
		(stroke
			(width 0)
			(type solid)
		)
		(fill yes)
		(layer "In2.Cu")
		(net "M_B_CPU1_SA_DQ<18>")
	)
	(gr_poly
		(pts
			(xy 87.023194 -266.737846) (xy 87.023194 -266.693396) (xy 86.667594 -266.693396) (xy 86.667594 -266.737846)
			(xy 86.714584 -266.890246) (xy 86.976204 -266.890246)
		)
		(stroke
			(width 0)
			(type solid)
		)
		(fill yes)
		(layer "In2.Cu")
		(net "M_B_CPU1_SA_DQ<17>")
	)
	(gr_poly
		(pts
			(xy 87.023194 -265.518646) (xy 86.976204 -265.366246) (xy 86.714584 -265.366246) (xy 86.667594 -265.518646)
			(xy 86.667594 -265.562842) (xy 87.023194 -265.562842)
		)
		(stroke
			(width 0)
			(type solid)
		)
		(fill yes)
		(layer "In2.Cu")
		(net "M_B_CPU1_SA_DQS_DN<2>")
	)
	(gr_poly
		(pts
			(xy 87.023194 -265.109706) (xy 87.023194 -265.06551) (xy 86.667594 -265.06551) (xy 86.667594 -265.109706)
			(xy 86.714584 -265.262106) (xy 86.976204 -265.262106)
		)
		(stroke
			(width 0)
			(type solid)
		)
		(fill yes)
		(layer "In2.Cu")
		(net "M_B_CPU1_SA_DQS_DN<7>")
	)
	(gr_poly
		(pts
			(xy 87.023194 -263.891014) (xy 86.976204 -263.738614) (xy 86.714584 -263.738614) (xy 86.667594 -263.891014)
			(xy 86.667594 -263.93521) (xy 87.023194 -263.93521)
		)
		(stroke
			(width 0)
			(type solid)
		)
		(fill yes)
		(layer "In2.Cu")
		(net "M_B_CPU1_SA_DQ<22>")
	)
	(gr_poly
		(pts
			(xy 87.023194 -263.482074) (xy 87.023194 -263.437878) (xy 86.667594 -263.437878) (xy 86.667594 -263.482074)
			(xy 86.714584 -263.634474) (xy 86.976204 -263.634474)
		)
		(stroke
			(width 0)
			(type solid)
		)
		(fill yes)
		(layer "In2.Cu")
		(net "M_B_CPU1_SA_DQ<21>")
	)
	(gr_poly
		(pts
			(xy 87.023194 -262.262874) (xy 86.976204 -262.110474) (xy 86.714584 -262.110474) (xy 86.667594 -262.262874)
			(xy 86.667594 -262.307324) (xy 87.023194 -262.307324)
		)
		(stroke
			(width 0)
			(type solid)
		)
		(fill yes)
		(layer "In2.Cu")
		(net "M_B_CPU1_SA_CB<2>")
	)
	(gr_poly
		(pts
			(xy 87.023194 -261.854442) (xy 87.023194 -261.810246) (xy 86.667594 -261.810246) (xy 86.667594 -261.854442)
			(xy 86.714584 -262.006842) (xy 86.976204 -262.006842)
		)
		(stroke
			(width 0)
			(type solid)
		)
		(fill yes)
		(layer "In2.Cu")
		(net "M_B_CPU1_SA_CB<1>")
	)
	(gr_poly
		(pts
			(xy 87.023194 -260.635242) (xy 86.976204 -260.482842) (xy 86.714584 -260.482842) (xy 86.667594 -260.635242)
			(xy 86.667594 -260.679438) (xy 87.023194 -260.679438)
		)
		(stroke
			(width 0)
			(type solid)
		)
		(fill yes)
		(layer "In2.Cu")
		(net "M_B_CPU1_SA_DQS_DN<4>")
	)
	(gr_poly
		(pts
			(xy 87.023194 -260.226302) (xy 87.023194 -260.182106) (xy 86.667594 -260.182106) (xy 86.667594 -260.226302)
			(xy 86.714584 -260.378702) (xy 86.976204 -260.378702)
		)
		(stroke
			(width 0)
			(type solid)
		)
		(fill yes)
		(layer "In2.Cu")
		(net "M_B_CPU1_SA_DQS_DN<9>")
	)
	(gr_poly
		(pts
			(xy 87.023194 -259.00761) (xy 86.976204 -258.85521) (xy 86.714584 -258.85521) (xy 86.667594 -259.00761)
			(xy 86.667594 -259.051806) (xy 87.023194 -259.051806)
		)
		(stroke
			(width 0)
			(type solid)
		)
		(fill yes)
		(layer "In2.Cu")
		(net "M_B_CPU1_SA_CB<6>")
	)
	(gr_poly
		(pts
			(xy 87.023194 -258.59867) (xy 87.023194 -258.554474) (xy 86.667594 -258.554474) (xy 86.667594 -258.59867)
			(xy 86.714584 -258.75107) (xy 86.976204 -258.75107)
		)
		(stroke
			(width 0)
			(type solid)
		)
		(fill yes)
		(layer "In2.Cu")
		(net "M_B_CPU1_SA_CB<5>")
	)
	(gr_poly
		(pts
			(xy 87.023194 -257.37947) (xy 86.976204 -257.22707) (xy 86.714584 -257.22707) (xy 86.667594 -257.37947)
			(xy 86.667594 -257.42392) (xy 87.023194 -257.42392)
		)
		(stroke
			(width 0)
			(type solid)
		)
		(fill yes)
		(layer "In2.Cu")
		(net "M_B_CPU1_SA_CS_N<0>")
	)
	(gr_poly
		(pts
			(xy 87.023194 -256.971038) (xy 87.023194 -256.926588) (xy 86.667594 -256.926588) (xy 86.667594 -256.971038)
			(xy 86.714584 -257.123438) (xy 86.976204 -257.123438)
		)
		(stroke
			(width 0)
			(type solid)
		)
		(fill yes)
		(layer "In2.Cu")
		(net "M_B_CPU1_SA_CS_N<2>")
	)
	(gr_poly
		(pts
			(xy 87.023194 -255.751838) (xy 86.976204 -255.599438) (xy 86.714584 -255.599438) (xy 86.667594 -255.751838)
			(xy 86.667594 -255.796288) (xy 87.023194 -255.796288)
		)
		(stroke
			(width 0)
			(type solid)
		)
		(fill yes)
		(layer "In2.Cu")
		(net "M_B_CPU1_SA_CA<0>")
	)
	(gr_poly
		(pts
			(xy 87.023194 -255.343406) (xy 87.023194 -255.298956) (xy 86.667594 -255.298956) (xy 86.667594 -255.343406)
			(xy 86.714584 -255.495806) (xy 86.976204 -255.495806)
		)
		(stroke
			(width 0)
			(type solid)
		)
		(fill yes)
		(layer "In2.Cu")
		(net "M_B_CPU1_SA_CA<1>")
	)
	(gr_poly
		(pts
			(xy 87.023194 -254.124206) (xy 86.976204 -253.971806) (xy 86.714584 -253.971806) (xy 86.667594 -254.124206)
			(xy 86.667594 -254.168402) (xy 87.023194 -254.168402)
		)
		(stroke
			(width 0)
			(type solid)
		)
		(fill yes)
		(layer "In2.Cu")
		(net "M_B_CPU1_SA_CA<4>")
	)
	(gr_poly
		(pts
			(xy 87.02929 -273.657314) (xy 86.9823 -273.504914) (xy 86.72068 -273.504914) (xy 86.67369 -273.657314)
			(xy 86.67369 -273.701764) (xy 87.02929 -273.701764)
		)
		(stroke
			(width 0)
			(type solid)
		)
		(fill yes)
		(layer "In2.Cu")
		(net "M_B_CPU1_SA_DQ<6>")
	)
	(gr_poly
		(pts
			(xy 87.031322 -279.760426) (xy 87.031322 -279.715976) (xy 86.675722 -279.715976) (xy 86.675722 -279.760426)
			(xy 86.722712 -279.912826) (xy 86.984332 -279.912826)
		)
		(stroke
			(width 0)
			(type solid)
		)
		(fill yes)
		(layer "In2.Cu")
		(net "M_B_CPU1_SA_DQS_DP<0>")
	)
	(gr_poly
		(pts
			(xy 87.031576 -253.715774) (xy 87.031576 -253.671324) (xy 86.675976 -253.671324) (xy 86.675976 -253.715774)
			(xy 86.722966 -253.868174) (xy 86.984586 -253.868174)
		)
		(stroke
			(width 0)
			(type solid)
		)
		(fill yes)
		(layer "In2.Cu")
		(net "M_B_CPU1_SA_CA<5>")
	)
	(gr_poly
		(pts
			(xy 87.095838 -275.356574) (xy 86.98738 -275.239734) (xy 86.949026 -275.217636) (xy 86.771226 -275.525484)
			(xy 86.80958 -275.547582) (xy 86.965028 -275.583142)
		)
		(stroke
			(width 0)
			(type solid)
		)
		(fill yes)
		(layer "In2.Cu")
		(net "M_B_CPU1_SA_DQS_DN<5>")
	)
	(gr_poly
		(pts
			(xy 87.102696 -281.856434) (xy 86.994238 -281.739594) (xy 86.955884 -281.717496) (xy 86.778084 -282.025344)
			(xy 86.816438 -282.047442) (xy 86.971886 -282.083002)
		)
		(stroke
			(width 0)
			(type solid)
		)
		(fill yes)
		(layer "In2.Cu")
		(net "M_B_CPU1_SA_DQ<2>")
	)
	(gr_poly
		(pts
			(xy 87.236808 -227.289614) (xy 87.275162 -227.267516) (xy 87.097362 -226.959668) (xy 87.059008 -226.981766)
			(xy 86.95055 -227.098606) (xy 87.08136 -227.325174)
		)
		(stroke
			(width 0)
			(type solid)
		)
		(fill yes)
		(layer "In2.Cu")
		(net "M_B_CPU1_SB_DQS_DP<2>")
	)
	(gr_poly
		(pts
			(xy 87.239094 -224.038414) (xy 87.277448 -224.016316) (xy 87.099648 -223.708468) (xy 87.061294 -223.730566)
			(xy 86.952836 -223.847406) (xy 87.083646 -224.073974)
		)
		(stroke
			(width 0)
			(type solid)
		)
		(fill yes)
		(layer "In2.Cu")
		(net "M_B_CPU1_SB_DQ<20>")
	)
	(gr_poly
		(pts
			(xy 87.239094 -222.410528) (xy 87.277448 -222.38843) (xy 87.099648 -222.080582) (xy 87.061294 -222.10268)
			(xy 86.952836 -222.21952) (xy 87.083646 -222.446088)
		)
		(stroke
			(width 0)
			(type solid)
		)
		(fill yes)
		(layer "In2.Cu")
		(net "M_B_CPU1_SB_DQ<21>")
	)
	(gr_poly
		(pts
			(xy 87.347806 -223.416622) (xy 87.456264 -223.299782) (xy 87.325454 -223.073214) (xy 87.170006 -223.108774)
			(xy 87.131652 -223.130872) (xy 87.309452 -223.43872)
		)
		(stroke
			(width 0)
			(type solid)
		)
		(fill yes)
		(layer "In2.Cu")
		(net "M_B_CPU1_SB_DQ<22>")
	)
	(gr_poly
		(pts
			(xy 87.348822 -276.357588) (xy 87.387176 -276.33549) (xy 87.209376 -276.027642) (xy 87.171022 -276.04974)
			(xy 87.062564 -276.16658) (xy 87.193374 -276.393148)
		)
		(stroke
			(width 0)
			(type solid)
		)
		(fill yes)
		(layer "In2.Cu")
		(net "M_B_CPU1_SA_DQS_DN<0>")
	)
	(gr_poly
		(pts
			(xy 87.355934 -226.686364) (xy 87.464392 -226.569524) (xy 87.333582 -226.342956) (xy 87.178134 -226.378516)
			(xy 87.13978 -226.400614) (xy 87.31758 -226.708462)
		)
		(stroke
			(width 0)
			(type solid)
		)
		(fill yes)
		(layer "In2.Cu")
		(net "M_B_CPU1_SB_DQS_DN<2>")
	)
	(gr_poly
		(pts
			(xy 87.37473 -249.416062) (xy 87.37473 -249.371612) (xy 87.01913 -249.371612) (xy 87.01913 -249.416062)
			(xy 87.06612 -249.568462) (xy 87.32774 -249.568462)
		)
		(stroke
			(width 0)
			(type solid)
		)
		(fill yes)
		(layer "In2.Cu")
		(net "M_B_CPU1_SB_CA<0>")
	)
	(gr_poly
		(pts
			(xy 87.37473 -244.532658) (xy 87.37473 -244.488208) (xy 87.01913 -244.488208) (xy 87.01913 -244.532658)
			(xy 87.06612 -244.685058) (xy 87.32774 -244.685058)
		)
		(stroke
			(width 0)
			(type solid)
		)
		(fill yes)
		(layer "In2.Cu")
		(net "M_B_CPU1_SB_CB<6>")
	)
	(gr_poly
		(pts
			(xy 87.37473 -240.057178) (xy 87.32774 -239.904778) (xy 87.06612 -239.904778) (xy 87.01913 -240.057178)
			(xy 87.01913 -240.101628) (xy 87.37473 -240.101628)
		)
		(stroke
			(width 0)
			(type solid)
		)
		(fill yes)
		(layer "In2.Cu")
		(net "M_B_CPU1_SB_CB<1>")
	)
	(gr_poly
		(pts
			(xy 87.37473 -239.649254) (xy 87.37473 -239.604804) (xy 87.01913 -239.604804) (xy 87.01913 -239.649254)
			(xy 87.06612 -239.801654) (xy 87.32774 -239.801654)
		)
		(stroke
			(width 0)
			(type solid)
		)
		(fill yes)
		(layer "In2.Cu")
		(net "M_A_CPU1_SB_DQ<0>")
	)
	(gr_poly
		(pts
			(xy 87.37473 -235.174282) (xy 87.32774 -235.021882) (xy 87.06612 -235.021882) (xy 87.01913 -235.174282)
			(xy 87.01913 -235.218478) (xy 87.37473 -235.218478)
		)
		(stroke
			(width 0)
			(type solid)
		)
		(fill yes)
		(layer "In2.Cu")
		(net "M_A_CPU1_SB_DQ<7>")
	)
	(gr_poly
		(pts
			(xy 87.37473 -234.76585) (xy 87.37473 -234.721654) (xy 87.01913 -234.721654) (xy 87.01913 -234.76585)
			(xy 87.06612 -234.91825) (xy 87.32774 -234.91825)
		)
		(stroke
			(width 0)
			(type solid)
		)
		(fill yes)
		(layer "In2.Cu")
		(net "M_B_CPU1_SB_DQ<8>")
	)
	(gr_poly
		(pts
			(xy 87.37473 -230.290878) (xy 87.32774 -230.138478) (xy 87.06612 -230.138478) (xy 87.01913 -230.290878)
			(xy 87.01913 -230.335074) (xy 87.37473 -230.335074)
		)
		(stroke
			(width 0)
			(type solid)
		)
		(fill yes)
		(layer "In2.Cu")
		(net "M_B_CPU1_SB_DQ<15>")
	)
	(gr_poly
		(pts
			(xy 87.380826 -278.719534) (xy 87.342472 -278.697436) (xy 87.187024 -278.661876) (xy 87.056214 -278.888444)
			(xy 87.164672 -279.005284) (xy 87.203026 -279.027382)
		)
		(stroke
			(width 0)
			(type solid)
		)
		(fill yes)
		(layer "In2.Cu")
		(net "M_B_CPU1_SA_DQS_DN<0>")
	)
	(gr_poly
		(pts
			(xy 87.383112 -242.905026) (xy 87.383112 -242.860576) (xy 87.027512 -242.860576) (xy 87.027512 -242.905026)
			(xy 87.074502 -243.057426) (xy 87.336122 -243.057426)
		)
		(stroke
			(width 0)
			(type solid)
		)
		(fill yes)
		(layer "In2.Cu")
		(net "M_B_CPU1_SB_DQS_DN<4>")
	)
	(gr_poly
		(pts
			(xy 87.383112 -238.020606) (xy 87.383112 -237.97641) (xy 87.027512 -237.97641) (xy 87.027512 -238.020606)
			(xy 87.074502 -238.173006) (xy 87.336122 -238.173006)
		)
		(stroke
			(width 0)
			(type solid)
		)
		(fill yes)
		(layer "In2.Cu")
		(net "M_A_CPU1_SB_DQS_DP<0>")
	)
	(gr_poly
		(pts
			(xy 87.383112 -236.393482) (xy 87.383112 -236.349032) (xy 87.027512 -236.349032) (xy 87.027512 -236.393482)
			(xy 87.074502 -236.545882) (xy 87.336122 -236.545882)
		)
		(stroke
			(width 0)
			(type solid)
		)
		(fill yes)
		(layer "In2.Cu")
		(net "M_A_CPU1_SB_DQ<4>")
	)
	(gr_poly
		(pts
			(xy 87.383366 -248.196354) (xy 87.336376 -248.043954) (xy 87.074756 -248.043954) (xy 87.027766 -248.196354)
			(xy 87.027766 -248.240804) (xy 87.383366 -248.240804)
		)
		(stroke
			(width 0)
			(type solid)
		)
		(fill yes)
		(layer "In2.Cu")
		(net "M_B_CPU1_SB_CA<3>")
	)
	(gr_poly
		(pts
			(xy 87.383366 -247.787922) (xy 87.383366 -247.743472) (xy 87.027766 -247.743472) (xy 87.027766 -247.787922)
			(xy 87.074756 -247.940322) (xy 87.336376 -247.940322)
		)
		(stroke
			(width 0)
			(type solid)
		)
		(fill yes)
		(layer "In2.Cu")
		(net "M_B_CPU1_SB_CA<4>")
	)
	(gr_poly
		(pts
			(xy 87.383366 -246.568722) (xy 87.336376 -246.416322) (xy 87.074756 -246.416322) (xy 87.027766 -246.568722)
			(xy 87.027766 -246.613172) (xy 87.383366 -246.613172)
		)
		(stroke
			(width 0)
			(type solid)
		)
		(fill yes)
		(layer "In2.Cu")
		(net "M_B_CPU1_SB_PAR")
	)
	(gr_poly
		(pts
			(xy 87.383366 -246.16029) (xy 87.383366 -246.11584) (xy 87.027766 -246.11584) (xy 87.027766 -246.16029)
			(xy 87.074756 -246.31269) (xy 87.336376 -246.31269)
		)
		(stroke
			(width 0)
			(type solid)
		)
		(fill yes)
		(layer "In2.Cu")
		(net "M_B_CPU1_SB_CS_N<0>")
	)
	(gr_poly
		(pts
			(xy 87.383366 -243.313458) (xy 87.336376 -243.161058) (xy 87.074756 -243.161058) (xy 87.027766 -243.313458)
			(xy 87.027766 -243.357654) (xy 87.383366 -243.357654)
		)
		(stroke
			(width 0)
			(type solid)
		)
		(fill yes)
		(layer "In2.Cu")
		(net "M_B_CPU1_SB_CB<5>")
	)
	(gr_poly
		(pts
			(xy 87.383366 -241.276886) (xy 87.383366 -241.232436) (xy 87.027766 -241.232436) (xy 87.027766 -241.276886)
			(xy 87.074756 -241.429286) (xy 87.336376 -241.429286)
		)
		(stroke
			(width 0)
			(type solid)
		)
		(fill yes)
		(layer "In2.Cu")
		(net "M_B_CPU1_SB_CB<2>")
	)
	(gr_poly
		(pts
			(xy 87.383366 -238.430054) (xy 87.336376 -238.277654) (xy 87.074756 -238.277654) (xy 87.027766 -238.430054)
			(xy 87.027766 -238.47425) (xy 87.383366 -238.47425)
		)
		(stroke
			(width 0)
			(type solid)
		)
		(fill yes)
		(layer "In2.Cu")
		(net "M_A_CPU1_SB_DQ<3>")
	)
	(gr_poly
		(pts
			(xy 87.383366 -233.54665) (xy 87.336376 -233.39425) (xy 87.074756 -233.39425) (xy 87.027766 -233.54665)
			(xy 87.027766 -233.590846) (xy 87.383366 -233.590846)
		)
		(stroke
			(width 0)
			(type solid)
		)
		(fill yes)
		(layer "In2.Cu")
		(net "M_B_CPU1_SB_DQ<11>")
	)
	(gr_poly
		(pts
			(xy 87.383366 -233.13771) (xy 87.383366 -233.093514) (xy 87.027766 -233.093514) (xy 87.027766 -233.13771)
			(xy 87.074756 -233.29011) (xy 87.336376 -233.29011)
		)
		(stroke
			(width 0)
			(type solid)
		)
		(fill yes)
		(layer "In2.Cu")
		(net "M_B_CPU1_SB_DQS_DP<1>")
	)
	(gr_poly
		(pts
			(xy 87.383366 -231.919018) (xy 87.336376 -231.766618) (xy 87.074756 -231.766618) (xy 87.027766 -231.919018)
			(xy 87.027766 -231.963214) (xy 87.383366 -231.963214)
		)
		(stroke
			(width 0)
			(type solid)
		)
		(fill yes)
		(layer "In2.Cu")
		(net "M_B_CPU1_SB_DQS_DP<6>")
	)
	(gr_poly
		(pts
			(xy 87.383366 -231.510078) (xy 87.383366 -231.465882) (xy 87.027766 -231.465882) (xy 87.027766 -231.510078)
			(xy 87.074756 -231.662478) (xy 87.336376 -231.662478)
		)
		(stroke
			(width 0)
			(type solid)
		)
		(fill yes)
		(layer "In2.Cu")
		(net "M_B_CPU1_SB_DQ<12>")
	)
	(gr_poly
		(pts
			(xy 87.383366 -224.999042) (xy 87.383366 -224.954592) (xy 87.027766 -224.954592) (xy 87.027766 -224.999042)
			(xy 87.074756 -225.151442) (xy 87.336376 -225.151442)
		)
		(stroke
			(width 0)
			(type solid)
		)
		(fill yes)
		(layer "In2.Cu")
		(net "M_B_CPU1_SB_DQS_DN<7>")
	)
	(gr_poly
		(pts
			(xy 87.388954 -275.450046) (xy 87.3506 -275.427948) (xy 87.195152 -275.392388) (xy 87.064342 -275.618956)
			(xy 87.1728 -275.735796) (xy 87.211154 -275.757894)
		)
		(stroke
			(width 0)
			(type solid)
		)
		(fill yes)
		(layer "In2.Cu")
		(net "M_B_CPU1_SA_DQS_DN<0>")
	)
	(gr_poly
		(pts
			(xy 87.391748 -241.685318) (xy 87.344758 -241.532918) (xy 87.083138 -241.532918) (xy 87.036148 -241.685318)
			(xy 87.036148 -241.729514) (xy 87.391748 -241.729514)
		)
		(stroke
			(width 0)
			(type solid)
		)
		(fill yes)
		(layer "In2.Cu")
		(net "M_B_CPU1_SB_DQS_DN<9>")
	)
	(gr_poly
		(pts
			(xy 87.391748 -236.801914) (xy 87.344758 -236.649514) (xy 87.083138 -236.649514) (xy 87.036148 -236.801914)
			(xy 87.036148 -236.846364) (xy 87.391748 -236.846364)
		)
		(stroke
			(width 0)
			(type solid)
		)
		(fill yes)
		(layer "In2.Cu")
		(net "M_A_CPU1_SB_DQS_DP<5>")
	)
	(gr_poly
		(pts
			(xy 87.392002 -244.94109) (xy 87.345012 -244.78869) (xy 87.083392 -244.78869) (xy 87.036402 -244.94109)
			(xy 87.036402 -244.985286) (xy 87.392002 -244.985286)
		)
		(stroke
			(width 0)
			(type solid)
		)
		(fill yes)
		(layer "In2.Cu")
		(net "M_B_CPU1_SB_CS_N<1>")
	)
	(gr_poly
		(pts
			(xy 87.484712 -280.98242) (xy 87.437722 -280.83002) (xy 87.176102 -280.83002) (xy 87.129112 -280.98242)
			(xy 87.129112 -281.026616) (xy 87.484712 -281.026616)
		)
		(stroke
			(width 0)
			(type solid)
		)
		(fill yes)
		(layer "In2.Cu")
		(net "M_B_CPU1_SA_DQ<0>")
	)
	(gr_poly
		(pts
			(xy 87.48776 -272.435066) (xy 87.48776 -272.390616) (xy 87.13216 -272.390616) (xy 87.13216 -272.435066)
			(xy 87.17915 -272.587466) (xy 87.44077 -272.587466)
		)
		(stroke
			(width 0)
			(type solid)
		)
		(fill yes)
		(layer "In2.Cu")
		(net "M_A_CPU1_SA_DQ<10>")
	)
	(gr_poly
		(pts
			(xy 87.493094 -280.573734) (xy 87.493094 -280.529538) (xy 87.137494 -280.529538) (xy 87.137494 -280.573734)
			(xy 87.184484 -280.726134) (xy 87.446104 -280.726134)
		)
		(stroke
			(width 0)
			(type solid)
		)
		(fill yes)
		(layer "In2.Cu")
		(net "M_B_CPU1_SA_DQ<1>")
	)
	(gr_poly
		(pts
			(xy 87.493094 -274.062698) (xy 87.493094 -274.018248) (xy 87.137494 -274.018248) (xy 87.137494 -274.062698)
			(xy 87.184484 -274.215098) (xy 87.446104 -274.215098)
		)
		(stroke
			(width 0)
			(type solid)
		)
		(fill yes)
		(layer "In2.Cu")
		(net "M_B_CPU1_SA_DQ<4>")
	)
	(gr_poly
		(pts
			(xy 87.493094 -271.215866) (xy 87.446104 -271.063466) (xy 87.184484 -271.063466) (xy 87.137494 -271.215866)
			(xy 87.137494 -271.260062) (xy 87.493094 -271.260062)
		)
		(stroke
			(width 0)
			(type solid)
		)
		(fill yes)
		(layer "In2.Cu")
		(net "M_A_CPU1_SA_DQ<11>")
	)
	(gr_poly
		(pts
			(xy 87.493094 -270.806926) (xy 87.493094 -270.76273) (xy 87.137494 -270.76273) (xy 87.137494 -270.806926)
			(xy 87.184484 -270.959326) (xy 87.446104 -270.959326)
		)
		(stroke
			(width 0)
			(type solid)
		)
		(fill yes)
		(layer "In2.Cu")
		(net "M_A_CPU1_SA_DQS_DP<1>")
	)
	(gr_poly
		(pts
			(xy 87.493094 -269.587726) (xy 87.446104 -269.435326) (xy 87.184484 -269.435326) (xy 87.137494 -269.587726)
			(xy 87.137494 -269.632176) (xy 87.493094 -269.632176)
		)
		(stroke
			(width 0)
			(type solid)
		)
		(fill yes)
		(layer "In2.Cu")
		(net "M_A_CPU1_SA_DQS_DP<6>")
	)
	(gr_poly
		(pts
			(xy 87.493094 -269.179294) (xy 87.493094 -269.134844) (xy 87.137494 -269.134844) (xy 87.137494 -269.179294)
			(xy 87.184484 -269.331694) (xy 87.446104 -269.331694)
		)
		(stroke
			(width 0)
			(type solid)
		)
		(fill yes)
		(layer "In2.Cu")
		(net "M_A_CPU1_SA_DQ<12>")
	)
	(gr_poly
		(pts
			(xy 87.493094 -267.960094) (xy 87.446104 -267.807694) (xy 87.184484 -267.807694) (xy 87.137494 -267.960094)
			(xy 87.137494 -268.004544) (xy 87.493094 -268.004544)
		)
		(stroke
			(width 0)
			(type solid)
		)
		(fill yes)
		(layer "In2.Cu")
		(net "M_A_CPU1_SA_DQ<13>")
	)
	(gr_poly
		(pts
			(xy 87.493094 -267.551662) (xy 87.493094 -267.507212) (xy 87.137494 -267.507212) (xy 87.137494 -267.551662)
			(xy 87.184484 -267.704062) (xy 87.446104 -267.704062)
		)
		(stroke
			(width 0)
			(type solid)
		)
		(fill yes)
		(layer "In2.Cu")
		(net "M_B_CPU1_SA_DQ<16>")
	)
	(gr_poly
		(pts
			(xy 87.493094 -266.332462) (xy 87.446104 -266.180062) (xy 87.184484 -266.180062) (xy 87.137494 -266.332462)
			(xy 87.137494 -266.376658) (xy 87.493094 -266.376658)
		)
		(stroke
			(width 0)
			(type solid)
		)
		(fill yes)
		(layer "In2.Cu")
		(net "M_B_CPU1_SA_DQ<19>")
	)
	(gr_poly
		(pts
			(xy 87.493094 -265.923014) (xy 87.493094 -265.878818) (xy 87.137494 -265.878818) (xy 87.137494 -265.923014)
			(xy 87.184484 -266.075414) (xy 87.446104 -266.075414)
		)
		(stroke
			(width 0)
			(type solid)
		)
		(fill yes)
		(layer "In2.Cu")
		(net "M_B_CPU1_SA_DQS_DP<2>")
	)
	(gr_poly
		(pts
			(xy 87.493094 -264.70483) (xy 87.446104 -264.55243) (xy 87.184484 -264.55243) (xy 87.137494 -264.70483)
			(xy 87.137494 -264.749026) (xy 87.493094 -264.749026)
		)
		(stroke
			(width 0)
			(type solid)
		)
		(fill yes)
		(layer "In2.Cu")
		(net "M_B_CPU1_SA_DQS_DP<7>")
	)
	(gr_poly
		(pts
			(xy 87.493094 -264.29589) (xy 87.493094 -264.251694) (xy 87.137494 -264.251694) (xy 87.137494 -264.29589)
			(xy 87.184484 -264.44829) (xy 87.446104 -264.44829)
		)
		(stroke
			(width 0)
			(type solid)
		)
		(fill yes)
		(layer "In2.Cu")
		(net "M_B_CPU1_SA_DQ<20>")
	)
	(gr_poly
		(pts
			(xy 87.493094 -263.07669) (xy 87.446104 -262.92429) (xy 87.184484 -262.92429) (xy 87.137494 -263.07669)
			(xy 87.137494 -263.12114) (xy 87.493094 -263.12114)
		)
		(stroke
			(width 0)
			(type solid)
		)
		(fill yes)
		(layer "In2.Cu")
		(net "M_B_CPU1_SA_DQ<23>")
	)
	(gr_poly
		(pts
			(xy 87.493094 -262.668258) (xy 87.493094 -262.623808) (xy 87.137494 -262.623808) (xy 87.137494 -262.668258)
			(xy 87.184484 -262.820658) (xy 87.446104 -262.820658)
		)
		(stroke
			(width 0)
			(type solid)
		)
		(fill yes)
		(layer "In2.Cu")
		(net "M_B_CPU1_SA_CB<0>")
	)
	(gr_poly
		(pts
			(xy 87.493094 -261.449058) (xy 87.446104 -261.296658) (xy 87.184484 -261.296658) (xy 87.137494 -261.449058)
			(xy 87.137494 -261.493508) (xy 87.493094 -261.493508)
		)
		(stroke
			(width 0)
			(type solid)
		)
		(fill yes)
		(layer "In2.Cu")
		(net "M_B_CPU1_SA_CB<3>")
	)
	(gr_poly
		(pts
			(xy 87.493094 -261.040118) (xy 87.493094 -260.995668) (xy 87.137494 -260.995668) (xy 87.137494 -261.040118)
			(xy 87.184484 -261.192518) (xy 87.446104 -261.192518)
		)
		(stroke
			(width 0)
			(type solid)
		)
		(fill yes)
		(layer "In2.Cu")
		(net "M_B_CPU1_SA_DQS_DP<4>")
	)
	(gr_poly
		(pts
			(xy 87.493094 -259.821426) (xy 87.446104 -259.669026) (xy 87.184484 -259.669026) (xy 87.137494 -259.821426)
			(xy 87.137494 -259.865622) (xy 87.493094 -259.865622)
		)
		(stroke
			(width 0)
			(type solid)
		)
		(fill yes)
		(layer "In2.Cu")
		(net "M_B_CPU1_SA_DQS_DP<9>")
	)
	(gr_poly
		(pts
			(xy 87.493094 -259.412486) (xy 87.493094 -259.36829) (xy 87.137494 -259.36829) (xy 87.137494 -259.412486)
			(xy 87.184484 -259.564886) (xy 87.446104 -259.564886)
		)
		(stroke
			(width 0)
			(type solid)
		)
		(fill yes)
		(layer "In2.Cu")
		(net "M_B_CPU1_SA_CB<4>")
	)
	(gr_poly
		(pts
			(xy 87.493094 -258.193286) (xy 87.446104 -258.040886) (xy 87.184484 -258.040886) (xy 87.137494 -258.193286)
			(xy 87.137494 -258.237736) (xy 87.493094 -258.237736)
		)
		(stroke
			(width 0)
			(type solid)
		)
		(fill yes)
		(layer "In2.Cu")
		(net "M_B_CPU1_SA_CB<7>")
	)
	(gr_poly
		(pts
			(xy 87.493094 -257.784854) (xy 87.493094 -257.740404) (xy 87.137494 -257.740404) (xy 87.137494 -257.784854)
			(xy 87.184484 -257.937254) (xy 87.446104 -257.937254)
		)
		(stroke
			(width 0)
			(type solid)
		)
		(fill yes)
		(layer "In2.Cu")
		(net "M_B_CPU1_ALERT_N")
	)
	(gr_poly
		(pts
			(xy 87.493094 -256.565654) (xy 87.446104 -256.413254) (xy 87.184484 -256.413254) (xy 87.137494 -256.565654)
			(xy 87.137494 -256.610104) (xy 87.493094 -256.610104)
		)
		(stroke
			(width 0)
			(type solid)
		)
		(fill yes)
		(layer "In2.Cu")
		(net "M_B_CPU1_SA_CS_N<3>")
	)
	(gr_poly
		(pts
			(xy 87.493094 -256.157222) (xy 87.493094 -256.112772) (xy 87.137494 -256.112772) (xy 87.137494 -256.157222)
			(xy 87.184484 -256.309622) (xy 87.446104 -256.309622)
		)
		(stroke
			(width 0)
			(type solid)
		)
		(fill yes)
		(layer "In2.Cu")
		(net "M_B_CPU1_SA_CS_N<1>")
	)
	(gr_poly
		(pts
			(xy 87.493094 -254.938022) (xy 87.446104 -254.785622) (xy 87.184484 -254.785622) (xy 87.137494 -254.938022)
			(xy 87.137494 -254.982218) (xy 87.493094 -254.982218)
		)
		(stroke
			(width 0)
			(type solid)
		)
		(fill yes)
		(layer "In2.Cu")
		(net "M_B_CPU1_SA_CA<2>")
	)
	(gr_poly
		(pts
			(xy 87.493094 -254.529082) (xy 87.493094 -254.484886) (xy 87.137494 -254.484886) (xy 87.137494 -254.529082)
			(xy 87.184484 -254.681482) (xy 87.446104 -254.681482)
		)
		(stroke
			(width 0)
			(type solid)
		)
		(fill yes)
		(layer "In2.Cu")
		(net "M_B_CPU1_SA_CA<3>")
	)
	(gr_poly
		(pts
			(xy 87.501476 -274.47113) (xy 87.454486 -274.31873) (xy 87.192866 -274.31873) (xy 87.145876 -274.47113)
			(xy 87.145876 -274.515326) (xy 87.501476 -274.515326)
		)
		(stroke
			(width 0)
			(type solid)
		)
		(fill yes)
		(layer "In2.Cu")
		(net "M_B_CPU1_SA_DQS_DP<5>")
	)
	(gr_poly
		(pts
			(xy 87.50173 -272.843498) (xy 87.45474 -272.691098) (xy 87.19312 -272.691098) (xy 87.14613 -272.843498)
			(xy 87.14613 -272.887694) (xy 87.50173 -272.887694)
		)
		(stroke
			(width 0)
			(type solid)
		)
		(fill yes)
		(layer "In2.Cu")
		(net "M_B_CPU1_SA_DQ<7>")
	)
	(gr_poly
		(pts
			(xy 87.572088 -279.414986) (xy 87.46363 -279.298146) (xy 87.425276 -279.276048) (xy 87.247476 -279.583896)
			(xy 87.28583 -279.605994) (xy 87.441278 -279.641554)
		)
		(stroke
			(width 0)
			(type solid)
		)
		(fill yes)
		(layer "In2.Cu")
		(net "M_B_CPU1_SA_DQS_DP<0>")
	)
	(gr_poly
		(pts
			(xy 87.71001 -223.226376) (xy 87.748364 -223.204278) (xy 87.570564 -222.89643) (xy 87.53221 -222.918528)
			(xy 87.423752 -223.035368) (xy 87.554562 -223.261936)
		)
		(stroke
			(width 0)
			(type solid)
		)
		(fill yes)
		(layer "In2.Cu")
		(net "M_B_CPU1_SB_DQ<21>")
	)
	(gr_poly
		(pts
			(xy 87.821516 -277.176738) (xy 87.85987 -277.15464) (xy 87.68207 -276.846792) (xy 87.643716 -276.86889)
			(xy 87.535258 -276.98573) (xy 87.666068 -277.212298)
		)
		(stroke
			(width 0)
			(type solid)
		)
		(fill yes)
		(layer "In2.Cu")
		(net "M_B_CPU1_SA_DQS_DN<0>")
	)
	(gr_poly
		(pts
			(xy 87.826088 -222.616776) (xy 87.934546 -222.499936) (xy 87.803736 -222.273368) (xy 87.648288 -222.308928)
			(xy 87.609934 -222.331026) (xy 87.787734 -222.638874)
		)
		(stroke
			(width 0)
			(type solid)
		)
		(fill yes)
		(layer "In2.Cu")
		(net "M_B_CPU1_SB_DQ<23>")
	)
	(gr_poly
		(pts
			(xy 87.844884 -245.346474) (xy 87.844884 -245.302278) (xy 87.489284 -245.302278) (xy 87.489284 -245.346474)
			(xy 87.536274 -245.498874) (xy 87.797894 -245.498874)
		)
		(stroke
			(width 0)
			(type solid)
		)
		(fill yes)
		(layer "In2.Cu")
		(net "M_B_CPU1_SB_CS_N<3>")
	)
	(gr_poly
		(pts
			(xy 87.84717 -237.207806) (xy 87.84717 -237.163356) (xy 87.49157 -237.163356) (xy 87.49157 -237.207806)
			(xy 87.53856 -237.360206) (xy 87.80018 -237.360206)
		)
		(stroke
			(width 0)
			(type solid)
		)
		(fill yes)
		(layer "In2.Cu")
		(net "M_A_CPU1_SB_DQS_DN<5>")
	)
	(gr_poly
		(pts
			(xy 87.848948 -277.908258) (xy 87.810594 -277.88616) (xy 87.655146 -277.8506) (xy 87.524336 -278.077168)
			(xy 87.632794 -278.194008) (xy 87.671148 -278.216106)
		)
		(stroke
			(width 0)
			(type solid)
		)
		(fill yes)
		(layer "In2.Cu")
		(net "M_B_CPU1_SA_DQS_DN<0>")
	)
	(gr_poly
		(pts
			(xy 87.853012 -235.988098) (xy 87.806022 -235.835698) (xy 87.544402 -235.835698) (xy 87.497412 -235.988098)
			(xy 87.497412 -236.032548) (xy 87.853012 -236.032548)
		)
		(stroke
			(width 0)
			(type solid)
		)
		(fill yes)
		(layer "In2.Cu")
		(net "M_A_CPU1_SB_DQ<6>")
	)
	(gr_poly
		(pts
			(xy 87.853266 -248.601738) (xy 87.853266 -248.557542) (xy 87.497666 -248.557542) (xy 87.497666 -248.601738)
			(xy 87.544656 -248.754138) (xy 87.806276 -248.754138)
		)
		(stroke
			(width 0)
			(type solid)
		)
		(fill yes)
		(layer "In2.Cu")
		(net "M_B_CPU1_SB_CA<2>")
	)
	(gr_poly
		(pts
			(xy 87.853266 -245.754906) (xy 87.806276 -245.602506) (xy 87.544656 -245.602506) (xy 87.497666 -245.754906)
			(xy 87.497666 -245.799356) (xy 87.853266 -245.799356)
		)
		(stroke
			(width 0)
			(type solid)
		)
		(fill yes)
		(layer "In2.Cu")
		(net "M_B_CPU1_SB_CS_N<2>")
	)
	(gr_poly
		(pts
			(xy 87.853266 -243.718334) (xy 87.853266 -243.674138) (xy 87.497666 -243.674138) (xy 87.497666 -243.718334)
			(xy 87.544656 -243.870734) (xy 87.806276 -243.870734)
		)
		(stroke
			(width 0)
			(type solid)
		)
		(fill yes)
		(layer "In2.Cu")
		(net "M_B_CPU1_SB_CB<7>")
	)
	(gr_poly
		(pts
			(xy 87.853266 -242.499134) (xy 87.806276 -242.346734) (xy 87.544656 -242.346734) (xy 87.497666 -242.499134)
			(xy 87.497666 -242.54333) (xy 87.853266 -242.54333)
		)
		(stroke
			(width 0)
			(type solid)
		)
		(fill yes)
		(layer "In2.Cu")
		(net "M_B_CPU1_SB_DQS_DP<4>")
	)
	(gr_poly
		(pts
			(xy 87.853266 -240.871502) (xy 87.806276 -240.719102) (xy 87.544656 -240.719102) (xy 87.497666 -240.871502)
			(xy 87.497666 -240.915952) (xy 87.853266 -240.915952)
		)
		(stroke
			(width 0)
			(type solid)
		)
		(fill yes)
		(layer "In2.Cu")
		(net "M_B_CPU1_SB_CB<0>")
	)
	(gr_poly
		(pts
			(xy 87.853266 -238.83493) (xy 87.853266 -238.790734) (xy 87.497666 -238.790734) (xy 87.497666 -238.83493)
			(xy 87.544656 -238.98733) (xy 87.806276 -238.98733)
		)
		(stroke
			(width 0)
			(type solid)
		)
		(fill yes)
		(layer "In2.Cu")
		(net "M_A_CPU1_SB_DQ<1>")
	)
	(gr_poly
		(pts
			(xy 87.853266 -233.952034) (xy 87.853266 -233.907584) (xy 87.497666 -233.907584) (xy 87.497666 -233.952034)
			(xy 87.544656 -234.104434) (xy 87.806276 -234.104434)
		)
		(stroke
			(width 0)
			(type solid)
		)
		(fill yes)
		(layer "In2.Cu")
		(net "M_B_CPU1_SB_DQ<9>")
	)
	(gr_poly
		(pts
			(xy 87.853266 -232.323894) (xy 87.853266 -232.279698) (xy 87.497666 -232.279698) (xy 87.497666 -232.323894)
			(xy 87.544656 -232.476294) (xy 87.806276 -232.476294)
		)
		(stroke
			(width 0)
			(type solid)
		)
		(fill yes)
		(layer "In2.Cu")
		(net "M_B_CPU1_SB_DQS_DN<6>")
	)
	(gr_poly
		(pts
			(xy 87.853266 -231.104694) (xy 87.806276 -230.952294) (xy 87.544656 -230.952294) (xy 87.497666 -231.104694)
			(xy 87.497666 -231.149144) (xy 87.853266 -231.149144)
		)
		(stroke
			(width 0)
			(type solid)
		)
		(fill yes)
		(layer "In2.Cu")
		(net "M_B_CPU1_SB_DQ<14>")
	)
	(gr_poly
		(pts
			(xy 87.853266 -229.477062) (xy 87.806276 -229.324662) (xy 87.544656 -229.324662) (xy 87.497666 -229.477062)
			(xy 87.497666 -229.521512) (xy 87.853266 -229.521512)
		)
		(stroke
			(width 0)
			(type solid)
		)
		(fill yes)
		(layer "In2.Cu")
		(net "M_B_CPU1_SB_DQ<16>")
	)
	(gr_poly
		(pts
			(xy 87.853266 -224.593658) (xy 87.806276 -224.441258) (xy 87.544656 -224.441258) (xy 87.497666 -224.593658)
			(xy 87.497666 -224.638108) (xy 87.853266 -224.638108)
		)
		(stroke
			(width 0)
			(type solid)
		)
		(fill yes)
		(layer "In2.Cu")
		(net "M_B_CPU1_SB_DQS_DP<7>")
	)
	(gr_poly
		(pts
			(xy 87.853266 -224.185226) (xy 87.853266 -224.140776) (xy 87.497666 -224.140776) (xy 87.497666 -224.185226)
			(xy 87.544656 -224.337626) (xy 87.806276 -224.337626)
		)
		(stroke
			(width 0)
			(type solid)
		)
		(fill yes)
		(layer "In2.Cu")
		(net "M_B_CPU1_SB_DQ<20>")
	)
	(gr_poly
		(pts
			(xy 87.857076 -279.523444) (xy 87.818722 -279.501346) (xy 87.663274 -279.465786) (xy 87.532464 -279.692354)
			(xy 87.640922 -279.809194) (xy 87.679276 -279.831292)
		)
		(stroke
			(width 0)
			(type solid)
		)
		(fill yes)
		(layer "In2.Cu")
		(net "M_B_CPU1_SA_DQ<3>")
	)
	(gr_poly
		(pts
			(xy 87.859362 -247.382538) (xy 87.812372 -247.230138) (xy 87.550752 -247.230138) (xy 87.503762 -247.382538)
			(xy 87.503762 -247.426988) (xy 87.859362 -247.426988)
		)
		(stroke
			(width 0)
			(type solid)
		)
		(fill yes)
		(layer "In2.Cu")
		(net "M_B_CPU1_SB_CA<5>")
	)
	(gr_poly
		(pts
			(xy 87.861648 -249.01017) (xy 87.814658 -248.85777) (xy 87.553038 -248.85777) (xy 87.506048 -249.01017)
			(xy 87.506048 -249.05462) (xy 87.861648 -249.05462)
		)
		(stroke
			(width 0)
			(type solid)
		)
		(fill yes)
		(layer "In2.Cu")
		(net "M_B_CPU1_SB_CA<1>")
	)
	(gr_poly
		(pts
			(xy 87.861648 -244.126766) (xy 87.814658 -243.974366) (xy 87.553038 -243.974366) (xy 87.506048 -244.126766)
			(xy 87.506048 -244.171216) (xy 87.861648 -244.171216)
		)
		(stroke
			(width 0)
			(type solid)
		)
		(fill yes)
		(layer "In2.Cu")
		(net "M_B_CPU1_SB_CB<4>")
	)
	(gr_poly
		(pts
			(xy 87.861648 -240.46307) (xy 87.861648 -240.418874) (xy 87.506048 -240.418874) (xy 87.506048 -240.46307)
			(xy 87.553038 -240.61547) (xy 87.814658 -240.61547)
		)
		(stroke
			(width 0)
			(type solid)
		)
		(fill yes)
		(layer "In2.Cu")
		(net "M_B_CPU1_SB_CB<3>")
	)
	(gr_poly
		(pts
			(xy 87.861648 -239.243362) (xy 87.814658 -239.090962) (xy 87.553038 -239.090962) (xy 87.506048 -239.243362)
			(xy 87.506048 -239.287812) (xy 87.861648 -239.287812)
		)
		(stroke
			(width 0)
			(type solid)
		)
		(fill yes)
		(layer "In2.Cu")
		(net "M_A_CPU1_SB_DQ<2>")
	)
	(gr_poly
		(pts
			(xy 87.861648 -235.579666) (xy 87.861648 -235.53547) (xy 87.506048 -235.53547) (xy 87.506048 -235.579666)
			(xy 87.553038 -235.732066) (xy 87.814658 -235.732066)
		)
		(stroke
			(width 0)
			(type solid)
		)
		(fill yes)
		(layer "In2.Cu")
		(net "M_A_CPU1_SB_DQ<5>")
	)
	(gr_poly
		(pts
			(xy 87.861648 -234.360466) (xy 87.814658 -234.208066) (xy 87.553038 -234.208066) (xy 87.506048 -234.360466)
			(xy 87.506048 -234.404662) (xy 87.861648 -234.404662)
		)
		(stroke
			(width 0)
			(type solid)
		)
		(fill yes)
		(layer "In2.Cu")
		(net "M_B_CPU1_SB_DQ<10>")
	)
	(gr_poly
		(pts
			(xy 87.861648 -230.696262) (xy 87.861648 -230.652066) (xy 87.506048 -230.652066) (xy 87.506048 -230.696262)
			(xy 87.553038 -230.848662) (xy 87.814658 -230.848662)
		)
		(stroke
			(width 0)
			(type solid)
		)
		(fill yes)
		(layer "In2.Cu")
		(net "M_B_CPU1_SB_DQ<13>")
	)
	(gr_poly
		(pts
			(xy 87.935054 -276.563582) (xy 88.043512 -276.446742) (xy 87.912702 -276.220174) (xy 87.757254 -276.255734)
			(xy 87.7189 -276.277832) (xy 87.8967 -276.58568)
		)
		(stroke
			(width 0)
			(type solid)
		)
		(fill yes)
		(layer "In2.Cu")
		(net "M_B_CPU1_SA_DQS_DP<0>")
	)
	(gr_poly
		(pts
			(xy 87.954612 -273.248882) (xy 87.954612 -273.204686) (xy 87.599012 -273.204686) (xy 87.599012 -273.248882)
			(xy 87.646002 -273.401282) (xy 87.907622 -273.401282)
		)
		(stroke
			(width 0)
			(type solid)
		)
		(fill yes)
		(layer "In2.Cu")
		(net "M_B_CPU1_SA_DQ<5>")
	)
	(gr_poly
		(pts
			(xy 87.956898 -274.876514) (xy 87.956898 -274.832318) (xy 87.601298 -274.832318) (xy 87.601298 -274.876514)
			(xy 87.648288 -275.028914) (xy 87.909908 -275.028914)
		)
		(stroke
			(width 0)
			(type solid)
		)
		(fill yes)
		(layer "In2.Cu")
		(net "M_B_CPU1_SA_DQS_DN<5>")
	)
	(gr_poly
		(pts
			(xy 87.962994 -271.620742) (xy 87.962994 -271.576546) (xy 87.607394 -271.576546) (xy 87.607394 -271.620742)
			(xy 87.654384 -271.773142) (xy 87.916004 -271.773142)
		)
		(stroke
			(width 0)
			(type solid)
		)
		(fill yes)
		(layer "In2.Cu")
		(net "M_A_CPU1_SA_DQ<9>")
	)
	(gr_poly
		(pts
			(xy 87.962994 -268.77391) (xy 87.916004 -268.62151) (xy 87.654384 -268.62151) (xy 87.607394 -268.77391)
			(xy 87.607394 -268.81836) (xy 87.962994 -268.81836)
		)
		(stroke
			(width 0)
			(type solid)
		)
		(fill yes)
		(layer "In2.Cu")
		(net "M_A_CPU1_SA_DQ<14>")
	)
	(gr_poly
		(pts
			(xy 87.962994 -268.365478) (xy 87.962994 -268.321028) (xy 87.607394 -268.321028) (xy 87.607394 -268.365478)
			(xy 87.654384 -268.517878) (xy 87.916004 -268.517878)
		)
		(stroke
			(width 0)
			(type solid)
		)
		(fill yes)
		(layer "In2.Cu")
		(net "M_A_CPU1_SA_DQ<15>")
	)
	(gr_poly
		(pts
			(xy 87.962994 -267.146278) (xy 87.916004 -266.993878) (xy 87.654384 -266.993878) (xy 87.607394 -267.146278)
			(xy 87.607394 -267.190474) (xy 87.962994 -267.190474)
		)
		(stroke
			(width 0)
			(type solid)
		)
		(fill yes)
		(layer "In2.Cu")
		(net "M_B_CPU1_SA_DQ<18>")
	)
	(gr_poly
		(pts
			(xy 87.962994 -265.109706) (xy 87.962994 -265.06551) (xy 87.607394 -265.06551) (xy 87.607394 -265.109706)
			(xy 87.654384 -265.262106) (xy 87.916004 -265.262106)
		)
		(stroke
			(width 0)
			(type solid)
		)
		(fill yes)
		(layer "In2.Cu")
		(net "M_B_CPU1_SA_DQS_DN<7>")
	)
	(gr_poly
		(pts
			(xy 87.962994 -263.891014) (xy 87.916004 -263.738614) (xy 87.654384 -263.738614) (xy 87.607394 -263.891014)
			(xy 87.607394 -263.93521) (xy 87.962994 -263.93521)
		)
		(stroke
			(width 0)
			(type solid)
		)
		(fill yes)
		(layer "In2.Cu")
		(net "M_B_CPU1_SA_DQ<22>")
	)
	(gr_poly
		(pts
			(xy 87.962994 -263.482074) (xy 87.962994 -263.437878) (xy 87.607394 -263.437878) (xy 87.607394 -263.482074)
			(xy 87.654384 -263.634474) (xy 87.916004 -263.634474)
		)
		(stroke
			(width 0)
			(type solid)
		)
		(fill yes)
		(layer "In2.Cu")
		(net "M_B_CPU1_SA_DQ<21>")
	)
	(gr_poly
		(pts
			(xy 87.962994 -262.262874) (xy 87.916004 -262.110474) (xy 87.654384 -262.110474) (xy 87.607394 -262.262874)
			(xy 87.607394 -262.307324) (xy 87.962994 -262.307324)
		)
		(stroke
			(width 0)
			(type solid)
		)
		(fill yes)
		(layer "In2.Cu")
		(net "M_B_CPU1_SA_CB<2>")
	)
	(gr_poly
		(pts
			(xy 87.962994 -260.226302) (xy 87.962994 -260.182106) (xy 87.607394 -260.182106) (xy 87.607394 -260.226302)
			(xy 87.654384 -260.378702) (xy 87.916004 -260.378702)
		)
		(stroke
			(width 0)
			(type solid)
		)
		(fill yes)
		(layer "In2.Cu")
		(net "M_B_CPU1_SA_DQS_DN<9>")
	)
	(gr_poly
		(pts
			(xy 87.962994 -259.00761) (xy 87.916004 -258.85521) (xy 87.654384 -258.85521) (xy 87.607394 -259.00761)
			(xy 87.607394 -259.051806) (xy 87.962994 -259.051806)
		)
		(stroke
			(width 0)
			(type solid)
		)
		(fill yes)
		(layer "In2.Cu")
		(net "M_B_CPU1_SA_CB<6>")
	)
	(gr_poly
		(pts
			(xy 87.962994 -258.59867) (xy 87.962994 -258.554474) (xy 87.607394 -258.554474) (xy 87.607394 -258.59867)
			(xy 87.654384 -258.75107) (xy 87.916004 -258.75107)
		)
		(stroke
			(width 0)
			(type solid)
		)
		(fill yes)
		(layer "In2.Cu")
		(net "M_B_CPU1_SA_CB<5>")
	)
	(gr_poly
		(pts
			(xy 87.962994 -257.37947) (xy 87.916004 -257.22707) (xy 87.654384 -257.22707) (xy 87.607394 -257.37947)
			(xy 87.607394 -257.42392) (xy 87.962994 -257.42392)
		)
		(stroke
			(width 0)
			(type solid)
		)
		(fill yes)
		(layer "In2.Cu")
		(net "M_B_CPU1_SA_CS_N<0>")
	)
	(gr_poly
		(pts
			(xy 87.962994 -256.971038) (xy 87.962994 -256.926588) (xy 87.607394 -256.926588) (xy 87.607394 -256.971038)
			(xy 87.654384 -257.123438) (xy 87.916004 -257.123438)
		)
		(stroke
			(width 0)
			(type solid)
		)
		(fill yes)
		(layer "In2.Cu")
		(net "M_B_CPU1_SA_CS_N<2>")
	)
	(gr_poly
		(pts
			(xy 87.962994 -255.751838) (xy 87.916004 -255.599438) (xy 87.654384 -255.599438) (xy 87.607394 -255.751838)
			(xy 87.607394 -255.796288) (xy 87.962994 -255.796288)
		)
		(stroke
			(width 0)
			(type solid)
		)
		(fill yes)
		(layer "In2.Cu")
		(net "M_B_CPU1_SA_CA<0>")
	)
	(gr_poly
		(pts
			(xy 87.962994 -255.343406) (xy 87.962994 -255.298956) (xy 87.607394 -255.298956) (xy 87.607394 -255.343406)
			(xy 87.654384 -255.495806) (xy 87.916004 -255.495806)
		)
		(stroke
			(width 0)
			(type solid)
		)
		(fill yes)
		(layer "In2.Cu")
		(net "M_B_CPU1_SA_CA<1>")
	)
	(gr_poly
		(pts
			(xy 87.962994 -254.124206) (xy 87.916004 -253.971806) (xy 87.654384 -253.971806) (xy 87.607394 -254.124206)
			(xy 87.607394 -254.168402) (xy 87.962994 -254.168402)
		)
		(stroke
			(width 0)
			(type solid)
		)
		(fill yes)
		(layer "In2.Cu")
		(net "M_B_CPU1_SA_CA<4>")
	)
	(gr_poly
		(pts
			(xy 87.963502 -272.029682) (xy 87.916512 -271.877282) (xy 87.654892 -271.877282) (xy 87.607902 -272.029682)
			(xy 87.607902 -272.073878) (xy 87.963502 -272.073878)
		)
		(stroke
			(width 0)
			(type solid)
		)
		(fill yes)
		(layer "In2.Cu")
		(net "M_A_CPU1_SA_DQ<8>")
	)
	(gr_poly
		(pts
			(xy 87.96909 -281.38755) (xy 87.96909 -281.343354) (xy 87.61349 -281.343354) (xy 87.61349 -281.38755)
			(xy 87.66048 -281.53995) (xy 87.9221 -281.53995)
		)
		(stroke
			(width 0)
			(type solid)
		)
		(fill yes)
		(layer "In2.Cu")
		(net "M_B_CPU1_SA_DQ<2>")
	)
	(gr_poly
		(pts
			(xy 87.971376 -253.715774) (xy 87.971376 -253.671324) (xy 87.615776 -253.671324) (xy 87.615776 -253.715774)
			(xy 87.662766 -253.868174) (xy 87.924386 -253.868174)
		)
		(stroke
			(width 0)
			(type solid)
		)
		(fill yes)
		(layer "In2.Cu")
		(net "M_B_CPU1_SA_CA<5>")
	)
	(gr_poly
		(pts
			(xy 87.97163 -273.657314) (xy 87.92464 -273.504914) (xy 87.66302 -273.504914) (xy 87.61603 -273.657314)
			(xy 87.61603 -273.70151) (xy 87.97163 -273.70151)
		)
		(stroke
			(width 0)
			(type solid)
		)
		(fill yes)
		(layer "In2.Cu")
		(net "M_B_CPU1_SA_DQ<6>")
	)
	(gr_poly
		(pts
			(xy 88.035892 -280.239978) (xy 87.927434 -280.123138) (xy 87.88908 -280.10104) (xy 87.71128 -280.408888)
			(xy 87.749634 -280.430986) (xy 87.905082 -280.466546)
		)
		(stroke
			(width 0)
			(type solid)
		)
		(fill yes)
		(layer "In2.Cu")
		(net "M_B_CPU1_SA_DQ<1>")
	)
	(gr_poly
		(pts
			(xy 88.043004 -278.598884) (xy 87.934546 -278.482044) (xy 87.896192 -278.459946) (xy 87.718392 -278.767794)
			(xy 87.756746 -278.789892) (xy 87.912194 -278.825452)
		)
		(stroke
			(width 0)
			(type solid)
		)
		(fill yes)
		(layer "In2.Cu")
		(net "M_B_CPU1_SA_DQS_DP<0>")
	)
	(gr_poly
		(pts
			(xy 88.289638 -225.048318) (xy 88.398096 -224.931478) (xy 88.267286 -224.70491) (xy 88.111838 -224.74047)
			(xy 88.073484 -224.762568) (xy 88.251284 -225.070416)
		)
		(stroke
			(width 0)
			(type solid)
		)
		(fill yes)
		(layer "In2.Cu")
		(net "M_B_CPU1_SB_DQS_DP<7>")
	)
	(gr_poly
		(pts
			(xy 88.31453 -249.416062) (xy 88.31453 -249.371612) (xy 87.95893 -249.371612) (xy 87.95893 -249.416062)
			(xy 88.00592 -249.568462) (xy 88.26754 -249.568462)
		)
		(stroke
			(width 0)
			(type solid)
		)
		(fill yes)
		(layer "In2.Cu")
		(net "M_B_CPU1_SB_CA<0>")
	)
	(gr_poly
		(pts
			(xy 88.31453 -244.940582) (xy 88.26754 -244.788182) (xy 88.00592 -244.788182) (xy 87.95893 -244.940582)
			(xy 87.95893 -244.985032) (xy 88.31453 -244.985032)
		)
		(stroke
			(width 0)
			(type solid)
		)
		(fill yes)
		(layer "In2.Cu")
		(net "M_B_CPU1_SB_CS_N<1>")
	)
	(gr_poly
		(pts
			(xy 88.31453 -244.532658) (xy 88.31453 -244.488208) (xy 87.95893 -244.488208) (xy 87.95893 -244.532658)
			(xy 88.00592 -244.685058) (xy 88.26754 -244.685058)
		)
		(stroke
			(width 0)
			(type solid)
		)
		(fill yes)
		(layer "In2.Cu")
		(net "M_B_CPU1_SB_CB<6>")
	)
	(gr_poly
		(pts
			(xy 88.31453 -240.057178) (xy 88.26754 -239.904778) (xy 88.00592 -239.904778) (xy 87.95893 -240.057178)
			(xy 87.95893 -240.101628) (xy 88.31453 -240.101628)
		)
		(stroke
			(width 0)
			(type solid)
		)
		(fill yes)
		(layer "In2.Cu")
		(net "M_B_CPU1_SB_CB<1>")
	)
	(gr_poly
		(pts
			(xy 88.31453 -239.649254) (xy 88.31453 -239.604804) (xy 87.95893 -239.604804) (xy 87.95893 -239.649254)
			(xy 88.00592 -239.801654) (xy 88.26754 -239.801654)
		)
		(stroke
			(width 0)
			(type solid)
		)
		(fill yes)
		(layer "In2.Cu")
		(net "M_A_CPU1_SB_DQ<0>")
	)
	(gr_poly
		(pts
			(xy 88.31453 -235.174282) (xy 88.26754 -235.021882) (xy 88.00592 -235.021882) (xy 87.95893 -235.174282)
			(xy 87.95893 -235.218478) (xy 88.31453 -235.218478)
		)
		(stroke
			(width 0)
			(type solid)
		)
		(fill yes)
		(layer "In2.Cu")
		(net "M_A_CPU1_SB_DQ<7>")
	)
	(gr_poly
		(pts
			(xy 88.31453 -234.76585) (xy 88.31453 -234.721654) (xy 87.95893 -234.721654) (xy 87.95893 -234.76585)
			(xy 88.00592 -234.91825) (xy 88.26754 -234.91825)
		)
		(stroke
			(width 0)
			(type solid)
		)
		(fill yes)
		(layer "In2.Cu")
		(net "M_B_CPU1_SB_DQ<8>")
	)
	(gr_poly
		(pts
			(xy 88.314784 -242.905026) (xy 88.314784 -242.860576) (xy 87.959184 -242.860576) (xy 87.959184 -242.905026)
			(xy 88.006174 -243.057426) (xy 88.267794 -243.057426)
		)
		(stroke
			(width 0)
			(type solid)
		)
		(fill yes)
		(layer "In2.Cu")
		(net "M_B_CPU1_SB_DQS_DN<4>")
	)
	(gr_poly
		(pts
			(xy 88.314784 -223.37141) (xy 88.314784 -223.327214) (xy 87.959184 -223.327214) (xy 87.959184 -223.37141)
			(xy 88.006174 -223.52381) (xy 88.267794 -223.52381)
		)
		(stroke
			(width 0)
			(type solid)
		)
		(fill yes)
		(layer "In2.Cu")
		(net "M_B_CPU1_SB_DQ<21>")
	)
	(gr_poly
		(pts
			(xy 88.31707 -248.196354) (xy 88.27008 -248.043954) (xy 88.00846 -248.043954) (xy 87.96147 -248.196354)
			(xy 87.96147 -248.240804) (xy 88.31707 -248.240804)
		)
		(stroke
			(width 0)
			(type solid)
		)
		(fill yes)
		(layer "In2.Cu")
		(net "M_B_CPU1_SB_CA<3>")
	)
	(gr_poly
		(pts
			(xy 88.31707 -246.568722) (xy 88.27008 -246.416322) (xy 88.00846 -246.416322) (xy 87.96147 -246.568722)
			(xy 87.96147 -246.613172) (xy 88.31707 -246.613172)
		)
		(stroke
			(width 0)
			(type solid)
		)
		(fill yes)
		(layer "In2.Cu")
		(net "M_B_CPU1_SB_PAR")
	)
	(gr_poly
		(pts
			(xy 88.31707 -223.779842) (xy 88.27008 -223.627442) (xy 88.00846 -223.627442) (xy 87.96147 -223.779842)
			(xy 87.96147 -223.824292) (xy 88.31707 -223.824292)
		)
		(stroke
			(width 0)
			(type solid)
		)
		(fill yes)
		(layer "In2.Cu")
		(net "M_B_CPU1_SB_DQ<22>")
	)
	(gr_poly
		(pts
			(xy 88.322912 -230.290878) (xy 88.275922 -230.138478) (xy 88.014302 -230.138478) (xy 87.967312 -230.290878)
			(xy 87.967312 -230.335328) (xy 88.322912 -230.335328)
		)
		(stroke
			(width 0)
			(type solid)
		)
		(fill yes)
		(layer "In2.Cu")
		(net "M_B_CPU1_SB_DQ<15>")
	)
	(gr_poly
		(pts
			(xy 88.323166 -236.801914) (xy 88.276176 -236.649514) (xy 88.014556 -236.649514) (xy 87.967566 -236.801914)
			(xy 87.967566 -236.846364) (xy 88.323166 -236.846364)
		)
		(stroke
			(width 0)
			(type solid)
		)
		(fill yes)
		(layer "In2.Cu")
		(net "M_A_CPU1_SB_DQS_DP<5>")
	)
	(gr_poly
		(pts
			(xy 88.326976 -278.709628) (xy 88.288622 -278.68753) (xy 88.133174 -278.65197) (xy 88.002364 -278.878538)
			(xy 88.110822 -278.995378) (xy 88.149176 -279.017476)
		)
		(stroke
			(width 0)
			(type solid)
		)
		(fill yes)
		(layer "In2.Cu")
		(net "M_B_CPU1_SA_DQ<3>")
	)
	(gr_poly
		(pts
			(xy 88.329008 -280.33345) (xy 88.290654 -280.311352) (xy 88.135206 -280.275792) (xy 88.004396 -280.50236)
			(xy 88.112854 -280.6192) (xy 88.151208 -280.641298)
		)
		(stroke
			(width 0)
			(type solid)
		)
		(fill yes)
		(layer "In2.Cu")
		(net "M_B_CPU1_SA_DQ<0>")
	)
	(gr_poly
		(pts
			(xy 88.396064 -225.479102) (xy 88.287606 -225.362262) (xy 88.249252 -225.340164) (xy 88.071452 -225.648012)
			(xy 88.109806 -225.67011) (xy 88.265254 -225.70567)
		)
		(stroke
			(width 0)
			(type solid)
		)
		(fill yes)
		(layer "In2.Cu")
		(net "M_B_CPU1_SB_DQS_DP<7>")
	)
	(gr_poly
		(pts
			(xy 88.398096 -277.365968) (xy 88.506554 -277.249128) (xy 88.375744 -277.02256) (xy 88.220296 -277.05812)
			(xy 88.181942 -277.080218) (xy 88.359742 -277.388066)
		)
		(stroke
			(width 0)
			(type solid)
		)
		(fill yes)
		(layer "In2.Cu")
		(net "M_B_CPU1_SA_DQS_DP<0>")
	)
	(gr_poly
		(pts
			(xy 88.432894 -274.47113) (xy 88.385904 -274.31873) (xy 88.124284 -274.31873) (xy 88.077294 -274.47113)
			(xy 88.077294 -274.51558) (xy 88.432894 -274.51558)
		)
		(stroke
			(width 0)
			(type solid)
		)
		(fill yes)
		(layer "In2.Cu")
		(net "M_B_CPU1_SA_DQS_DP<5>")
	)
	(gr_poly
		(pts
			(xy 88.432894 -274.062698) (xy 88.432894 -274.018248) (xy 88.077294 -274.018248) (xy 88.077294 -274.062698)
			(xy 88.124284 -274.215098) (xy 88.385904 -274.215098)
		)
		(stroke
			(width 0)
			(type solid)
		)
		(fill yes)
		(layer "In2.Cu")
		(net "M_B_CPU1_SA_DQ<4>")
	)
	(gr_poly
		(pts
			(xy 88.432894 -269.587726) (xy 88.385904 -269.435326) (xy 88.124284 -269.435326) (xy 88.077294 -269.587726)
			(xy 88.077294 -269.632176) (xy 88.432894 -269.632176)
		)
		(stroke
			(width 0)
			(type solid)
		)
		(fill yes)
		(layer "In2.Cu")
		(net "M_A_CPU1_SA_DQS_DP<6>")
	)
	(gr_poly
		(pts
			(xy 88.432894 -267.960094) (xy 88.385904 -267.807694) (xy 88.124284 -267.807694) (xy 88.077294 -267.960094)
			(xy 88.077294 -268.004544) (xy 88.432894 -268.004544)
		)
		(stroke
			(width 0)
			(type solid)
		)
		(fill yes)
		(layer "In2.Cu")
		(net "M_A_CPU1_SA_DQ<13>")
	)
	(gr_poly
		(pts
			(xy 88.432894 -267.551662) (xy 88.432894 -267.507212) (xy 88.077294 -267.507212) (xy 88.077294 -267.551662)
			(xy 88.124284 -267.704062) (xy 88.385904 -267.704062)
		)
		(stroke
			(width 0)
			(type solid)
		)
		(fill yes)
		(layer "In2.Cu")
		(net "M_B_CPU1_SA_DQ<16>")
	)
	(gr_poly
		(pts
			(xy 88.432894 -264.70483) (xy 88.385904 -264.55243) (xy 88.124284 -264.55243) (xy 88.077294 -264.70483)
			(xy 88.077294 -264.749026) (xy 88.432894 -264.749026)
		)
		(stroke
			(width 0)
			(type solid)
		)
		(fill yes)
		(layer "In2.Cu")
		(net "M_B_CPU1_SA_DQS_DP<7>")
	)
	(gr_poly
		(pts
			(xy 88.432894 -264.29589) (xy 88.432894 -264.251694) (xy 88.077294 -264.251694) (xy 88.077294 -264.29589)
			(xy 88.124284 -264.44829) (xy 88.385904 -264.44829)
		)
		(stroke
			(width 0)
			(type solid)
		)
		(fill yes)
		(layer "In2.Cu")
		(net "M_B_CPU1_SA_DQ<20>")
	)
	(gr_poly
		(pts
			(xy 88.432894 -263.07669) (xy 88.385904 -262.92429) (xy 88.124284 -262.92429) (xy 88.077294 -263.07669)
			(xy 88.077294 -263.12114) (xy 88.432894 -263.12114)
		)
		(stroke
			(width 0)
			(type solid)
		)
		(fill yes)
		(layer "In2.Cu")
		(net "M_B_CPU1_SA_DQ<23>")
	)
	(gr_poly
		(pts
			(xy 88.432894 -262.668258) (xy 88.432894 -262.623808) (xy 88.077294 -262.623808) (xy 88.077294 -262.668258)
			(xy 88.124284 -262.820658) (xy 88.385904 -262.820658)
		)
		(stroke
			(width 0)
			(type solid)
		)
		(fill yes)
		(layer "In2.Cu")
		(net "M_B_CPU1_SA_CB<0>")
	)
	(gr_poly
		(pts
			(xy 88.432894 -259.821426) (xy 88.385904 -259.669026) (xy 88.124284 -259.669026) (xy 88.077294 -259.821426)
			(xy 88.077294 -259.865622) (xy 88.432894 -259.865622)
		)
		(stroke
			(width 0)
			(type solid)
		)
		(fill yes)
		(layer "In2.Cu")
		(net "M_B_CPU1_SA_DQS_DP<9>")
	)
	(gr_poly
		(pts
			(xy 88.432894 -258.193286) (xy 88.385904 -258.040886) (xy 88.124284 -258.040886) (xy 88.077294 -258.193286)
			(xy 88.077294 -258.237736) (xy 88.432894 -258.237736)
		)
		(stroke
			(width 0)
			(type solid)
		)
		(fill yes)
		(layer "In2.Cu")
		(net "M_B_CPU1_SA_CB<7>")
	)
	(gr_poly
		(pts
			(xy 88.432894 -257.784854) (xy 88.432894 -257.740404) (xy 88.077294 -257.740404) (xy 88.077294 -257.784854)
			(xy 88.124284 -257.937254) (xy 88.385904 -257.937254)
		)
		(stroke
			(width 0)
			(type solid)
		)
		(fill yes)
		(layer "In2.Cu")
		(net "M_B_CPU1_ALERT_N")
	)
	(gr_poly
		(pts
			(xy 88.432894 -256.565654) (xy 88.385904 -256.413254) (xy 88.124284 -256.413254) (xy 88.077294 -256.565654)
			(xy 88.077294 -256.610104) (xy 88.432894 -256.610104)
		)
		(stroke
			(width 0)
			(type solid)
		)
		(fill yes)
		(layer "In2.Cu")
		(net "M_B_CPU1_SA_CS_N<3>")
	)
	(gr_poly
		(pts
			(xy 88.432894 -254.529082) (xy 88.432894 -254.484886) (xy 88.077294 -254.484886) (xy 88.077294 -254.529082)
			(xy 88.124284 -254.681482) (xy 88.385904 -254.681482)
		)
		(stroke
			(width 0)
			(type solid)
		)
		(fill yes)
		(layer "In2.Cu")
		(net "M_B_CPU1_SA_CA<3>")
	)
	(gr_poly
		(pts
			(xy 88.44153 -272.843498) (xy 88.39454 -272.691098) (xy 88.13292 -272.691098) (xy 88.08593 -272.843498)
			(xy 88.08593 -272.887694) (xy 88.44153 -272.887694)
		)
		(stroke
			(width 0)
			(type solid)
		)
		(fill yes)
		(layer "In2.Cu")
		(net "M_B_CPU1_SA_DQ<7>")
	)
	(gr_poly
		(pts
			(xy 88.44153 -272.435066) (xy 88.44153 -272.39087) (xy 88.08593 -272.39087) (xy 88.08593 -272.435066)
			(xy 88.13292 -272.587466) (xy 88.39454 -272.587466)
		)
		(stroke
			(width 0)
			(type solid)
		)
		(fill yes)
		(layer "In2.Cu")
		(net "M_A_CPU1_SA_DQ<10>")
	)
	(gr_poly
		(pts
			(xy 88.507824 -281.049984) (xy 88.399366 -280.933144) (xy 88.361012 -280.911046) (xy 88.183212 -281.218894)
			(xy 88.221566 -281.240992) (xy 88.377014 -281.276552)
		)
		(stroke
			(width 0)
			(type solid)
		)
		(fill yes)
		(layer "In2.Cu")
		(net "M_B_CPU1_SA_DQ<2>")
	)
	(gr_poly
		(pts
			(xy 88.507824 -279.422098) (xy 88.399366 -279.305258) (xy 88.361012 -279.28316) (xy 88.183212 -279.591008)
			(xy 88.221566 -279.613106) (xy 88.377014 -279.648666)
		)
		(stroke
			(width 0)
			(type solid)
		)
		(fill yes)
		(layer "In2.Cu")
		(net "M_B_CPU1_SA_DQ<1>")
	)
	(gr_poly
		(pts
			(xy 88.514682 -277.782528) (xy 88.406224 -277.665688) (xy 88.36787 -277.64359) (xy 88.19007 -277.951438)
			(xy 88.228424 -277.973536) (xy 88.383872 -278.009096)
		)
		(stroke
			(width 0)
			(type solid)
		)
		(fill yes)
		(layer "In2.Cu")
		(net "M_B_CPU1_SA_DQS_DP<0>")
	)
	(gr_poly
		(pts
			(xy 88.648794 -224.85223) (xy 88.687148 -224.830132) (xy 88.509348 -224.522284) (xy 88.470994 -224.544382)
			(xy 88.362536 -224.661222) (xy 88.493346 -224.88779)
		)
		(stroke
			(width 0)
			(type solid)
		)
		(fill yes)
		(layer "In2.Cu")
		(net "M_B_CPU1_SB_DQ<20>")
	)
	(gr_poly
		(pts
			(xy 88.688164 -238.59617) (xy 88.64981 -238.574072) (xy 88.494362 -238.538512) (xy 88.363552 -238.76508)
			(xy 88.47201 -238.88192) (xy 88.510364 -238.904018)
		)
		(stroke
			(width 0)
			(type solid)
		)
		(fill yes)
		(layer "In2.Cu")
		(net "M_A_CPU1_SB_DQ<2>")
	)
	(gr_poly
		(pts
			(xy 88.68918 -225.572574) (xy 88.650826 -225.550476) (xy 88.495378 -225.514916) (xy 88.364568 -225.741484)
			(xy 88.473026 -225.858324) (xy 88.51138 -225.880422)
		)
		(stroke
			(width 0)
			(type solid)
		)
		(fill yes)
		(layer "In2.Cu")
		(net "M_B_CPU1_SB_DQ<20>")
	)
	(gr_poly
		(pts
			(xy 88.761316 -277.175468) (xy 88.79967 -277.15337) (xy 88.62187 -276.845522) (xy 88.583516 -276.86762)
			(xy 88.475058 -276.98446) (xy 88.605868 -277.211028)
		)
		(stroke
			(width 0)
			(type solid)
		)
		(fill yes)
		(layer "In2.Cu")
		(net "M_B_CPU1_SA_DQ<3>")
	)
	(gr_poly
		(pts
			(xy 88.763856 -224.241614) (xy 88.872314 -224.124774) (xy 88.741504 -223.898206) (xy 88.586056 -223.933766)
			(xy 88.547702 -223.955864) (xy 88.725502 -224.263712)
		)
		(stroke
			(width 0)
			(type solid)
		)
		(fill yes)
		(layer "In2.Cu")
		(net "M_B_CPU1_SB_DQ<22>")
	)
	(gr_poly
		(pts
			(xy 88.78697 -247.382538) (xy 88.73998 -247.230138) (xy 88.47836 -247.230138) (xy 88.43137 -247.382538)
			(xy 88.43137 -247.426988) (xy 88.78697 -247.426988)
		)
		(stroke
			(width 0)
			(type solid)
		)
		(fill yes)
		(layer "In2.Cu")
		(net "M_B_CPU1_SB_CA<5>")
	)
	(gr_poly
		(pts
			(xy 88.78697 -243.718334) (xy 88.78697 -243.674138) (xy 88.43137 -243.674138) (xy 88.43137 -243.718334)
			(xy 88.47836 -243.870734) (xy 88.73998 -243.870734)
		)
		(stroke
			(width 0)
			(type solid)
		)
		(fill yes)
		(layer "In2.Cu")
		(net "M_B_CPU1_SB_CB<7>")
	)
	(gr_poly
		(pts
			(xy 88.790272 -231.105202) (xy 88.743282 -230.952802) (xy 88.481662 -230.952802) (xy 88.434672 -231.105202)
			(xy 88.434672 -231.149398) (xy 88.790272 -231.149398)
		)
		(stroke
			(width 0)
			(type solid)
		)
		(fill yes)
		(layer "In2.Cu")
		(net "M_B_CPU1_SB_DQ<14>")
	)
	(gr_poly
		(pts
			(xy 88.791288 -277.904194) (xy 88.752934 -277.882096) (xy 88.597486 -277.846536) (xy 88.466676 -278.073104)
			(xy 88.575134 -278.189944) (xy 88.613488 -278.212042)
		)
		(stroke
			(width 0)
			(type solid)
		)
		(fill yes)
		(layer "In2.Cu")
		(net "M_B_CPU1_SA_DQ<3>")
	)
	(gr_poly
		(pts
			(xy 88.792812 -235.988606) (xy 88.745822 -235.836206) (xy 88.484202 -235.836206) (xy 88.437212 -235.988606)
			(xy 88.437212 -236.032802) (xy 88.792812 -236.032802)
		)
		(stroke
			(width 0)
			(type solid)
		)
		(fill yes)
		(layer "In2.Cu")
		(net "M_A_CPU1_SB_DQ<6>")
	)
	(gr_poly
		(pts
			(xy 88.796876 -279.523444) (xy 88.758522 -279.501346) (xy 88.603074 -279.465786) (xy 88.472264 -279.692354)
			(xy 88.580722 -279.809194) (xy 88.619076 -279.831292)
		)
		(stroke
			(width 0)
			(type solid)
		)
		(fill yes)
		(layer "In2.Cu")
		(net "M_B_CPU1_SA_DQ<0>")
	)
	(gr_poly
		(pts
			(xy 88.796876 -266.501118) (xy 88.758522 -266.47902) (xy 88.603074 -266.44346) (xy 88.472264 -266.670028)
			(xy 88.580722 -266.786868) (xy 88.619076 -266.808966)
		)
		(stroke
			(width 0)
			(type solid)
		)
		(fill yes)
		(layer "In2.Cu")
		(net "M_B_CPU1_SA_DQ<18>")
	)
	(gr_poly
		(pts
			(xy 88.801448 -249.01017) (xy 88.754458 -248.85777) (xy 88.492838 -248.85777) (xy 88.445848 -249.01017)
			(xy 88.445848 -249.05462) (xy 88.801448 -249.05462)
		)
		(stroke
			(width 0)
			(type solid)
		)
		(fill yes)
		(layer "In2.Cu")
		(net "M_B_CPU1_SB_CA<1>")
	)
	(gr_poly
		(pts
			(xy 88.801448 -242.499134) (xy 88.754458 -242.346734) (xy 88.492838 -242.346734) (xy 88.445848 -242.499134)
			(xy 88.445848 -242.54333) (xy 88.801448 -242.54333)
		)
		(stroke
			(width 0)
			(type solid)
		)
		(fill yes)
		(layer "In2.Cu")
		(net "M_B_CPU1_SB_DQS_DP<4>")
	)
	(gr_poly
		(pts
			(xy 88.801448 -235.579666) (xy 88.801448 -235.53547) (xy 88.445848 -235.53547) (xy 88.445848 -235.579666)
			(xy 88.492838 -235.732066) (xy 88.754458 -235.732066)
		)
		(stroke
			(width 0)
			(type solid)
		)
		(fill yes)
		(layer "In2.Cu")
		(net "M_A_CPU1_SB_DQ<5>")
	)
	(gr_poly
		(pts
			(xy 88.801448 -232.324402) (xy 88.801448 -232.279952) (xy 88.445848 -232.279952) (xy 88.445848 -232.324402)
			(xy 88.492838 -232.476802) (xy 88.754458 -232.476802)
		)
		(stroke
			(width 0)
			(type solid)
		)
		(fill yes)
		(layer "In2.Cu")
		(net "M_B_CPU1_SB_DQS_DN<6>")
	)
	(gr_poly
		(pts
			(xy 88.801448 -222.965518) (xy 88.754458 -222.813118) (xy 88.492838 -222.813118) (xy 88.445848 -222.965518)
			(xy 88.445848 -223.009968) (xy 88.801448 -223.009968)
		)
		(stroke
			(width 0)
			(type solid)
		)
		(fill yes)
		(layer "In2.Cu")
		(net "M_B_CPU1_SB_DQ<23>")
	)
	(gr_poly
		(pts
			(xy 88.872314 -239.304068) (xy 88.763856 -239.187228) (xy 88.725502 -239.16513) (xy 88.547702 -239.472978)
			(xy 88.586056 -239.495076) (xy 88.741504 -239.530636)
		)
		(stroke
			(width 0)
			(type solid)
		)
		(fill yes)
		(layer "In2.Cu")
		(net "M_A_CPU1_SB_DQ<0>")
	)
	(gr_poly
		(pts
			(xy 88.894412 -273.248882) (xy 88.894412 -273.204686) (xy 88.538812 -273.204686) (xy 88.538812 -273.248882)
			(xy 88.585802 -273.401282) (xy 88.847422 -273.401282)
		)
		(stroke
			(width 0)
			(type solid)
		)
		(fill yes)
		(layer "In2.Cu")
		(net "M_B_CPU1_SA_DQ<5>")
	)
	(gr_poly
		(pts
			(xy 88.896952 -272.029174) (xy 88.849962 -271.876774) (xy 88.588342 -271.876774) (xy 88.541352 -272.029174)
			(xy 88.541352 -272.073624) (xy 88.896952 -272.073624)
		)
		(stroke
			(width 0)
			(type solid)
		)
		(fill yes)
		(layer "In2.Cu")
		(net "M_A_CPU1_SA_DQ<8>")
	)
	(gr_poly
		(pts
			(xy 88.902794 -274.876514) (xy 88.902794 -274.832064) (xy 88.547194 -274.832064) (xy 88.547194 -274.876514)
			(xy 88.594184 -275.028914) (xy 88.855804 -275.028914)
		)
		(stroke
			(width 0)
			(type solid)
		)
		(fill yes)
		(layer "In2.Cu")
		(net "M_B_CPU1_SA_DQS_DN<5>")
	)
	(gr_poly
		(pts
			(xy 88.902794 -263.891014) (xy 88.855804 -263.738614) (xy 88.594184 -263.738614) (xy 88.547194 -263.891014)
			(xy 88.547194 -263.93521) (xy 88.902794 -263.93521)
		)
		(stroke
			(width 0)
			(type solid)
		)
		(fill yes)
		(layer "In2.Cu")
		(net "M_B_CPU1_SA_DQ<22>")
	)
	(gr_poly
		(pts
			(xy 88.902794 -263.482074) (xy 88.902794 -263.437878) (xy 88.547194 -263.437878) (xy 88.547194 -263.482074)
			(xy 88.594184 -263.634474) (xy 88.855804 -263.634474)
		)
		(stroke
			(width 0)
			(type solid)
		)
		(fill yes)
		(layer "In2.Cu")
		(net "M_B_CPU1_SA_DQ<21>")
	)
	(gr_poly
		(pts
			(xy 88.902794 -259.00761) (xy 88.855804 -258.85521) (xy 88.594184 -258.85521) (xy 88.547194 -259.00761)
			(xy 88.547194 -259.05206) (xy 88.902794 -259.05206)
		)
		(stroke
			(width 0)
			(type solid)
		)
		(fill yes)
		(layer "In2.Cu")
		(net "M_B_CPU1_SA_CB<6>")
	)
	(gr_poly
		(pts
			(xy 88.902794 -258.59867) (xy 88.902794 -258.554474) (xy 88.547194 -258.554474) (xy 88.547194 -258.59867)
			(xy 88.594184 -258.75107) (xy 88.855804 -258.75107)
		)
		(stroke
			(width 0)
			(type solid)
		)
		(fill yes)
		(layer "In2.Cu")
		(net "M_B_CPU1_SA_CB<5>")
	)
	(gr_poly
		(pts
			(xy 88.902794 -256.971038) (xy 88.902794 -256.926588) (xy 88.547194 -256.926588) (xy 88.547194 -256.971038)
			(xy 88.594184 -257.123438) (xy 88.855804 -257.123438)
		)
		(stroke
			(width 0)
			(type solid)
		)
		(fill yes)
		(layer "In2.Cu")
		(net "M_B_CPU1_SA_CS_N<2>")
	)
	(gr_poly
		(pts
			(xy 88.90889 -255.343406) (xy 88.90889 -255.29921) (xy 88.55329 -255.29921) (xy 88.55329 -255.343406)
			(xy 88.60028 -255.495806) (xy 88.8619 -255.495806)
		)
		(stroke
			(width 0)
			(type solid)
		)
		(fill yes)
		(layer "In2.Cu")
		(net "M_B_CPU1_SA_CA<1>")
	)
	(gr_poly
		(pts
			(xy 88.911176 -253.715774) (xy 88.911176 -253.671324) (xy 88.555576 -253.671324) (xy 88.555576 -253.715774)
			(xy 88.602566 -253.868174) (xy 88.864186 -253.868174)
		)
		(stroke
			(width 0)
			(type solid)
		)
		(fill yes)
		(layer "In2.Cu")
		(net "M_B_CPU1_SA_CA<5>")
	)
	(gr_poly
		(pts
			(xy 88.91143 -273.657314) (xy 88.86444 -273.504914) (xy 88.60282 -273.504914) (xy 88.55583 -273.657314)
			(xy 88.55583 -273.70151) (xy 88.91143 -273.70151)
		)
		(stroke
			(width 0)
			(type solid)
		)
		(fill yes)
		(layer "In2.Cu")
		(net "M_B_CPU1_SA_DQ<6>")
	)
	(gr_poly
		(pts
			(xy 88.975692 -280.239978) (xy 88.867234 -280.123138) (xy 88.82888 -280.10104) (xy 88.65108 -280.408888)
			(xy 88.689434 -280.430986) (xy 88.844882 -280.466546)
		)
		(stroke
			(width 0)
			(type solid)
		)
		(fill yes)
		(layer "In2.Cu")
		(net "M_B_CPU1_SA_DQ<2>")
	)
	(gr_poly
		(pts
			(xy 88.975692 -267.217652) (xy 88.867234 -267.100812) (xy 88.82888 -267.078714) (xy 88.65108 -267.386562)
			(xy 88.689434 -267.40866) (xy 88.844882 -267.44422)
		)
		(stroke
			(width 0)
			(type solid)
		)
		(fill yes)
		(layer "In2.Cu")
		(net "M_B_CPU1_SA_DQ<16>")
	)
	(gr_poly
		(pts
			(xy 88.97747 -278.608536) (xy 88.869012 -278.491696) (xy 88.830658 -278.469598) (xy 88.652858 -278.777446)
			(xy 88.691212 -278.799544) (xy 88.84666 -278.835104)
		)
		(stroke
			(width 0)
			(type solid)
		)
		(fill yes)
		(layer "In2.Cu")
		(net "M_B_CPU1_SA_DQ<1>")
	)
	(gr_poly
		(pts
			(xy 89.112344 -224.028254) (xy 89.150698 -224.006156) (xy 88.972898 -223.698308) (xy 88.934544 -223.720406)
			(xy 88.826086 -223.837246) (xy 88.956896 -224.063814)
		)
		(stroke
			(width 0)
			(type solid)
		)
		(fill yes)
		(layer "In2.Cu")
		(net "M_B_CPU1_SB_DQ<21>")
	)
	(gr_poly
		(pts
			(xy 89.228422 -223.418654) (xy 89.33688 -223.301814) (xy 89.20607 -223.075246) (xy 89.050622 -223.110806)
			(xy 89.012268 -223.132904) (xy 89.190068 -223.440752)
		)
		(stroke
			(width 0)
			(type solid)
		)
		(fill yes)
		(layer "In2.Cu")
		(net "M_B_CPU1_SB_DQ<23>")
	)
	(gr_poly
		(pts
			(xy 89.229438 -225.048318) (xy 89.337896 -224.931478) (xy 89.207086 -224.70491) (xy 89.051638 -224.74047)
			(xy 89.013284 -224.762568) (xy 89.191084 -225.070416)
		)
		(stroke
			(width 0)
			(type solid)
		)
		(fill yes)
		(layer "In2.Cu")
		(net "M_B_CPU1_SB_DQ<22>")
	)
	(gr_poly
		(pts
			(xy 89.25433 -249.416062) (xy 89.25433 -249.371612) (xy 88.89873 -249.371612) (xy 88.89873 -249.416062)
			(xy 88.94572 -249.568462) (xy 89.20734 -249.568462)
		)
		(stroke
			(width 0)
			(type solid)
		)
		(fill yes)
		(layer "In2.Cu")
		(net "M_B_CPU1_SB_CA<0>")
	)
	(gr_poly
		(pts
			(xy 89.25433 -246.568722) (xy 89.20734 -246.416322) (xy 88.94572 -246.416322) (xy 88.89873 -246.568722)
			(xy 88.89873 -246.612918) (xy 89.25433 -246.612918)
		)
		(stroke
			(width 0)
			(type solid)
		)
		(fill yes)
		(layer "In2.Cu")
		(net "M_B_CPU1_SB_PAR")
	)
	(gr_poly
		(pts
			(xy 89.25433 -242.905026) (xy 89.25433 -242.860576) (xy 88.89873 -242.860576) (xy 88.89873 -242.905026)
			(xy 88.94572 -243.057426) (xy 89.20734 -243.057426)
		)
		(stroke
			(width 0)
			(type solid)
		)
		(fill yes)
		(layer "In2.Cu")
		(net "M_B_CPU1_SB_DQS_DN<4>")
	)
	(gr_poly
		(pts
			(xy 89.25687 -236.801914) (xy 89.20988 -236.649514) (xy 88.94826 -236.649514) (xy 88.90127 -236.801914)
			(xy 88.90127 -236.846364) (xy 89.25687 -236.846364)
		)
		(stroke
			(width 0)
			(type solid)
		)
		(fill yes)
		(layer "In2.Cu")
		(net "M_A_CPU1_SB_DQS_DP<5>")
	)
	(gr_poly
		(pts
			(xy 89.262458 -248.196354) (xy 89.215468 -248.043954) (xy 88.953848 -248.043954) (xy 88.906858 -248.196354)
			(xy 88.906858 -248.240804) (xy 89.262458 -248.240804)
		)
		(stroke
			(width 0)
			(type solid)
		)
		(fill yes)
		(layer "In2.Cu")
		(net "M_B_CPU1_SB_CA<3>")
	)
	(gr_poly
		(pts
			(xy 89.266776 -278.709628) (xy 89.228422 -278.68753) (xy 89.072974 -278.65197) (xy 88.942164 -278.878538)
			(xy 89.050622 -278.995378) (xy 89.088976 -279.017476)
		)
		(stroke
			(width 0)
			(type solid)
		)
		(fill yes)
		(layer "In2.Cu")
		(net "M_B_CPU1_SA_DQ<0>")
	)
	(gr_poly
		(pts
			(xy 89.297764 -247.6373) (xy 89.301574 -247.593104) (xy 88.947498 -247.562116) (xy 88.943434 -247.606312)
			(xy 88.976962 -247.762268) (xy 89.23782 -247.784874)
		)
		(stroke
			(width 0)
			(type solid)
		)
		(fill yes)
		(layer "In2.Cu")
		(net "M_B_CPU1_SB_CA<5>")
	)
	(gr_poly
		(pts
			(xy 89.335864 -225.479102) (xy 89.227406 -225.362262) (xy 89.189052 -225.340164) (xy 89.011252 -225.648012)
			(xy 89.049606 -225.67011) (xy 89.205054 -225.70567)
		)
		(stroke
			(width 0)
			(type solid)
		)
		(fill yes)
		(layer "In2.Cu")
		(net "M_B_CPU1_SB_DQ<22>")
	)
	(gr_poly
		(pts
			(xy 89.33815 -277.365714) (xy 89.446608 -277.248874) (xy 89.315798 -277.022306) (xy 89.16035 -277.057866)
			(xy 89.121996 -277.079964) (xy 89.299796 -277.387812)
		)
		(stroke
			(width 0)
			(type solid)
		)
		(fill yes)
		(layer "In2.Cu")
		(net "M_B_CPU1_SA_DQ<1>")
	)
	(gr_poly
		(pts
			(xy 89.366852 -272.435066) (xy 89.366852 -272.390616) (xy 89.011252 -272.390616) (xy 89.011252 -272.435066)
			(xy 89.058242 -272.587466) (xy 89.319862 -272.587466)
		)
		(stroke
			(width 0)
			(type solid)
		)
		(fill yes)
		(layer "In2.Cu")
		(net "M_A_CPU1_SA_DQ<10>")
	)
	(gr_poly
		(pts
			(xy 89.372694 -269.587726) (xy 89.325704 -269.435326) (xy 89.064084 -269.435326) (xy 89.017094 -269.587726)
			(xy 89.017094 -269.632176) (xy 89.372694 -269.632176)
		)
		(stroke
			(width 0)
			(type solid)
		)
		(fill yes)
		(layer "In2.Cu")
		(net "M_A_CPU1_SA_DQS_DP<6>")
	)
	(gr_poly
		(pts
			(xy 89.372694 -263.07669) (xy 89.325704 -262.92429) (xy 89.064084 -262.92429) (xy 89.017094 -263.07669)
			(xy 89.017094 -263.12114) (xy 89.372694 -263.12114)
		)
		(stroke
			(width 0)
			(type solid)
		)
		(fill yes)
		(layer "In2.Cu")
		(net "M_B_CPU1_SA_DQ<23>")
	)
	(gr_poly
		(pts
			(xy 89.372694 -258.193286) (xy 89.325704 -258.040886) (xy 89.064084 -258.040886) (xy 89.017094 -258.193286)
			(xy 89.017094 -258.237736) (xy 89.372694 -258.237736)
		)
		(stroke
			(width 0)
			(type solid)
		)
		(fill yes)
		(layer "In2.Cu")
		(net "M_B_CPU1_SA_CB<7>")
	)
	(gr_poly
		(pts
			(xy 89.372694 -257.784854) (xy 89.372694 -257.740404) (xy 89.017094 -257.740404) (xy 89.017094 -257.784854)
			(xy 89.064084 -257.937254) (xy 89.325704 -257.937254)
		)
		(stroke
			(width 0)
			(type solid)
		)
		(fill yes)
		(layer "In2.Cu")
		(net "M_B_CPU1_ALERT_N")
	)
	(gr_poly
		(pts
			(xy 89.372694 -256.565654) (xy 89.325704 -256.413254) (xy 89.064084 -256.413254) (xy 89.017094 -256.565654)
			(xy 89.017094 -256.610104) (xy 89.372694 -256.610104)
		)
		(stroke
			(width 0)
			(type solid)
		)
		(fill yes)
		(layer "In2.Cu")
		(net "M_B_CPU1_SA_CS_N<3>")
	)
	(gr_poly
		(pts
			(xy 89.372694 -254.529082) (xy 89.372694 -254.484886) (xy 89.017094 -254.484886) (xy 89.017094 -254.529082)
			(xy 89.064084 -254.681482) (xy 89.325704 -254.681482)
		)
		(stroke
			(width 0)
			(type solid)
		)
		(fill yes)
		(layer "In2.Cu")
		(net "M_B_CPU1_SA_CA<3>")
	)
	(gr_poly
		(pts
			(xy 89.447624 -279.422098) (xy 89.339166 -279.305258) (xy 89.300812 -279.28316) (xy 89.123012 -279.591008)
			(xy 89.161366 -279.613106) (xy 89.316814 -279.648666)
		)
		(stroke
			(width 0)
			(type solid)
		)
		(fill yes)
		(layer "In2.Cu")
		(net "M_B_CPU1_SA_DQ<2>")
	)
	(gr_poly
		(pts
			(xy 89.45245 -277.786338) (xy 89.343992 -277.669498) (xy 89.305638 -277.6474) (xy 89.127838 -277.955248)
			(xy 89.166192 -277.977346) (xy 89.32164 -278.012906)
		)
		(stroke
			(width 0)
			(type solid)
		)
		(fill yes)
		(layer "In2.Cu")
		(net "M_B_CPU1_SA_DQ<1>")
	)
	(gr_poly
		(pts
			(xy 89.58961 -224.85477) (xy 89.627964 -224.832672) (xy 89.450164 -224.524824) (xy 89.41181 -224.546922)
			(xy 89.303352 -224.663762) (xy 89.434162 -224.89033)
		)
		(stroke
			(width 0)
			(type solid)
		)
		(fill yes)
		(layer "In2.Cu")
		(net "M_B_CPU1_SB_DQ<21>")
	)
	(gr_poly
		(pts
			(xy 89.698322 -270.660368) (xy 89.736676 -270.63827) (xy 89.558876 -270.330422) (xy 89.520522 -270.35252)
			(xy 89.412064 -270.46936) (xy 89.542874 -270.695928)
		)
		(stroke
			(width 0)
			(type solid)
		)
		(fill yes)
		(layer "In2.Cu")
		(net "M_A_CPU1_SA_DQS_DN<6>")
	)
	(gr_poly
		(pts
			(xy 89.699338 -224.234502) (xy 89.807796 -224.117662) (xy 89.676986 -223.891094) (xy 89.521538 -223.926654)
			(xy 89.483184 -223.948752) (xy 89.660984 -224.2566)
		)
		(stroke
			(width 0)
			(type solid)
		)
		(fill yes)
		(layer "In2.Cu")
		(net "M_B_CPU1_SB_DQ<23>")
	)
	(gr_poly
		(pts
			(xy 89.728548 -231.105202) (xy 89.681558 -230.952802) (xy 89.419938 -230.952802) (xy 89.372948 -231.105202)
			(xy 89.372948 -231.149398) (xy 89.728548 -231.149398)
		)
		(stroke
			(width 0)
			(type solid)
		)
		(fill yes)
		(layer "In2.Cu")
		(net "M_B_CPU1_SB_DQ<14>")
	)
	(gr_poly
		(pts
			(xy 89.738708 -277.891748) (xy 89.700354 -277.86965) (xy 89.544906 -277.83409) (xy 89.414096 -278.060658)
			(xy 89.522554 -278.177498) (xy 89.560908 -278.199596)
		)
		(stroke
			(width 0)
			(type solid)
		)
		(fill yes)
		(layer "In2.Cu")
		(net "M_B_CPU1_SA_DQ<0>")
	)
	(gr_poly
		(pts
			(xy 89.741248 -249.01017) (xy 89.694258 -248.85777) (xy 89.432638 -248.85777) (xy 89.385648 -249.01017)
			(xy 89.385648 -249.05462) (xy 89.741248 -249.05462)
		)
		(stroke
			(width 0)
			(type solid)
		)
		(fill yes)
		(layer "In2.Cu")
		(net "M_B_CPU1_SB_CA<1>")
	)
	(gr_poly
		(pts
			(xy 89.842594 -274.876514) (xy 89.842594 -274.832064) (xy 89.486994 -274.832064) (xy 89.486994 -274.876514)
			(xy 89.533984 -275.028914) (xy 89.795604 -275.028914)
		)
		(stroke
			(width 0)
			(type solid)
		)
		(fill yes)
		(layer "In2.Cu")
		(net "M_B_CPU1_SA_DQS_DN<5>")
	)
	(gr_poly
		(pts
			(xy 89.842594 -256.971038) (xy 89.842594 -256.926588) (xy 89.486994 -256.926588) (xy 89.486994 -256.971038)
			(xy 89.533984 -257.123438) (xy 89.795604 -257.123438)
		)
		(stroke
			(width 0)
			(type solid)
		)
		(fill yes)
		(layer "In2.Cu")
		(net "M_B_CPU1_SA_CS_N<2>")
	)
	(gr_poly
		(pts
			(xy 89.84869 -255.343406) (xy 89.84869 -255.298956) (xy 89.49309 -255.298956) (xy 89.49309 -255.343406)
			(xy 89.54008 -255.495806) (xy 89.8017 -255.495806)
		)
		(stroke
			(width 0)
			(type solid)
		)
		(fill yes)
		(layer "In2.Cu")
		(net "M_B_CPU1_SA_CA<1>")
	)
	(gr_poly
		(pts
			(xy 89.917524 -278.608282) (xy 89.809066 -278.491442) (xy 89.770712 -278.469344) (xy 89.592912 -278.777192)
			(xy 89.631266 -278.79929) (xy 89.786714 -278.83485)
		)
		(stroke
			(width 0)
			(type solid)
		)
		(fill yes)
		(layer "In2.Cu")
		(net "M_B_CPU1_SA_DQ<2>")
	)
	(gr_poly
		(pts
			(xy 90.167968 -225.045778) (xy 90.276426 -224.928938) (xy 90.145616 -224.70237) (xy 89.990168 -224.73793)
			(xy 89.951814 -224.760028) (xy 90.129614 -225.067876)
		)
		(stroke
			(width 0)
			(type solid)
		)
		(fill yes)
		(layer "In2.Cu")
		(net "M_B_CPU1_SB_DQ<23>")
	)
	(gr_poly
		(pts
			(xy 90.19667 -249.416062) (xy 90.19667 -249.371612) (xy 89.84107 -249.371612) (xy 89.84107 -249.416062)
			(xy 89.88806 -249.568462) (xy 90.14968 -249.568462)
		)
		(stroke
			(width 0)
			(type solid)
		)
		(fill yes)
		(layer "In2.Cu")
		(net "M_B_CPU1_SB_CA<0>")
	)
	(gr_poly
		(pts
			(xy 90.285316 -277.377652) (xy 90.393774 -277.260812) (xy 90.262964 -277.034244) (xy 90.107516 -277.069804)
			(xy 90.069162 -277.091902) (xy 90.246962 -277.39975)
		)
		(stroke
			(width 0)
			(type solid)
		)
		(fill yes)
		(layer "In2.Cu")
		(net "M_B_CPU1_SA_DQ<2>")
	)
	(gr_poly
		(pts
			(xy 90.312494 -270.806926) (xy 90.312494 -270.76273) (xy 89.956894 -270.76273) (xy 89.956894 -270.806926)
			(xy 90.003884 -270.959326) (xy 90.265504 -270.959326)
		)
		(stroke
			(width 0)
			(type solid)
		)
		(fill yes)
		(layer "In2.Cu")
		(net "M_A_CPU1_SA_DQS_DN<6>")
	)
	(gr_poly
		(pts
			(xy 90.392504 -277.786084) (xy 90.284046 -277.669244) (xy 90.245692 -277.647146) (xy 90.067892 -277.954994)
			(xy 90.106246 -277.977092) (xy 90.261694 -278.012652)
		)
		(stroke
			(width 0)
			(type solid)
		)
		(fill yes)
		(layer "In2.Cu")
		(net "M_B_CPU1_SA_DQ<2>")
	)
	(gr_poly
		(pts
			(xy 129.170176 -256.01041) (xy 129.20853 -255.988312) (xy 129.03073 -255.680464) (xy 128.992376 -255.702562)
			(xy 128.883918 -255.819402) (xy 129.014728 -256.04597)
		)
		(stroke
			(width 0)
			(type solid)
		)
		(fill yes)
		(layer "In2.Cu")
		(net "M_F_CPU1_SB_CA<0>")
	)
	(gr_poly
		(pts
			(xy 129.211324 -255.102868) (xy 129.17297 -255.08077) (xy 129.017522 -255.04521) (xy 128.886712 -255.271778)
			(xy 128.99517 -255.388618) (xy 129.033524 -255.410716)
		)
		(stroke
			(width 0)
			(type solid)
		)
		(fill yes)
		(layer "In2.Cu")
		(net "M_F_CPU1_SB_CA<0>")
	)
	(gr_poly
		(pts
			(xy 129.635504 -256.817114) (xy 129.673858 -256.795016) (xy 129.496058 -256.487168) (xy 129.457704 -256.509266)
			(xy 129.349246 -256.626106) (xy 129.480056 -256.852674)
		)
		(stroke
			(width 0)
			(type solid)
		)
		(fill yes)
		(layer "In2.Cu")
		(net "M_F_CPU1_SB_CA<0>")
	)
	(gr_poly
		(pts
			(xy 129.678176 -254.292862) (xy 129.639822 -254.270764) (xy 129.484374 -254.235204) (xy 129.353564 -254.461772)
			(xy 129.462022 -254.578612) (xy 129.500376 -254.60071)
		)
		(stroke
			(width 0)
			(type solid)
		)
		(fill yes)
		(layer "In2.Cu")
		(net "M_F_CPU1_SB_CA<0>")
	)
	(gr_poly
		(pts
			(xy 129.75082 -256.206498) (xy 129.859278 -256.089658) (xy 129.728468 -255.86309) (xy 129.57302 -255.89865)
			(xy 129.534666 -255.920748) (xy 129.712466 -256.228596)
		)
		(stroke
			(width 0)
			(type solid)
		)
		(fill yes)
		(layer "In2.Cu")
		(net "M_F_CPU1_SB_CA<1>")
	)
	(gr_poly
		(pts
			(xy 129.861564 -255.001522) (xy 129.753106 -254.884682) (xy 129.714752 -254.862584) (xy 129.536952 -255.170432)
			(xy 129.575306 -255.19253) (xy 129.730754 -255.22809)
		)
		(stroke
			(width 0)
			(type solid)
		)
		(fill yes)
		(layer "In2.Cu")
		(net "M_F_CPU1_SB_CA<1>")
	)
	(gr_poly
		(pts
			(xy 130.335274 -254.181356) (xy 130.226816 -254.064516) (xy 130.188462 -254.042418) (xy 130.010662 -254.350266)
			(xy 130.049016 -254.372364) (xy 130.204464 -254.407924)
		)
		(stroke
			(width 0)
			(type solid)
		)
		(fill yes)
		(layer "In2.Cu")
		(net "M_F_CPU1_SB_CA<1>")
	)
	(gr_poly
		(pts
			(xy 130.715512 -256.157222) (xy 130.715512 -256.113026) (xy 130.359912 -256.113026) (xy 130.359912 -256.157222)
			(xy 130.406902 -256.309622) (xy 130.668522 -256.309622)
		)
		(stroke
			(width 0)
			(type solid)
		)
		(fill yes)
		(layer "In2.Cu")
		(net "M_F_CPU1_CLK_DP<1>")
	)
	(gr_poly
		(pts
			(xy 131.20243 -255.751838) (xy 131.15544 -255.599438) (xy 130.89382 -255.599438) (xy 130.84683 -255.751838)
			(xy 130.84683 -255.796034) (xy 131.20243 -255.796034)
		)
		(stroke
			(width 0)
			(type solid)
		)
		(fill yes)
		(layer "In2.Cu")
		(net "M_F_CPU1_CLK_DN<1>")
	)
	(gr_poly
		(pts
			(xy 131.655312 -256.157222) (xy 131.655312 -256.113026) (xy 131.299712 -256.113026) (xy 131.299712 -256.157222)
			(xy 131.346702 -256.309622) (xy 131.608322 -256.309622)
		)
		(stroke
			(width 0)
			(type solid)
		)
		(fill yes)
		(layer "In2.Cu")
		(net "M_F_CPU1_CLK_DP<1>")
	)
	(gr_poly
		(pts
			(xy 132.498846 -254.290322) (xy 132.460492 -254.268224) (xy 132.305044 -254.232664) (xy 132.174234 -254.459232)
			(xy 132.282692 -254.576072) (xy 132.321046 -254.59817)
		)
		(stroke
			(width 0)
			(type solid)
		)
		(fill yes)
		(layer "In2.Cu")
		(net "M_F_CPU1_CLK_DN<0>")
	)
	(gr_poly
		(pts
			(xy 132.603494 -256.565654) (xy 132.556504 -256.413254) (xy 132.294884 -256.413254) (xy 132.247894 -256.565654)
			(xy 132.247894 -256.610104) (xy 132.603494 -256.610104)
		)
		(stroke
			(width 0)
			(type solid)
		)
		(fill yes)
		(layer "In2.Cu")
		(net "M_F_CPU1_SA_PAR")
	)
	(gr_poly
		(pts
			(xy 132.603494 -256.157222) (xy 132.603494 -256.112772) (xy 132.247894 -256.112772) (xy 132.247894 -256.157222)
			(xy 132.294884 -256.309622) (xy 132.556504 -256.309622)
		)
		(stroke
			(width 0)
			(type solid)
		)
		(fill yes)
		(layer "In2.Cu")
		(net "M_F_CPU1_CLK_DP<1>")
	)
	(gr_poly
		(pts
			(xy 132.677916 -255.007364) (xy 132.569458 -254.890524) (xy 132.531104 -254.868426) (xy 132.353304 -255.176274)
			(xy 132.391658 -255.198372) (xy 132.547106 -255.233932)
		)
		(stroke
			(width 0)
			(type solid)
		)
		(fill yes)
		(layer "In2.Cu")
		(net "M_F_CPU1_CLK_DP<0>")
	)
	(gr_poly
		(pts
			(xy 132.968492 -255.1049) (xy 132.930138 -255.082802) (xy 132.77469 -255.047242) (xy 132.64388 -255.27381)
			(xy 132.752338 -255.39065) (xy 132.790692 -255.412748)
		)
		(stroke
			(width 0)
			(type solid)
		)
		(fill yes)
		(layer "In2.Cu")
		(net "M_F_CPU1_CLK_DN<1>")
	)
	(gr_poly
		(pts
			(xy 133.07949 -256.971038) (xy 133.07949 -256.926842) (xy 132.72389 -256.926842) (xy 132.72389 -256.971038)
			(xy 132.77088 -257.123438) (xy 133.0325 -257.123438)
		)
		(stroke
			(width 0)
			(type solid)
		)
		(fill yes)
		(layer "In2.Cu")
		(net "M_F_CPU1_SA_CA<6>")
	)
	(gr_poly
		(pts
			(xy 133.148324 -255.819402) (xy 133.039866 -255.702562) (xy 133.001512 -255.680464) (xy 132.823712 -255.988312)
			(xy 132.862066 -256.01041) (xy 133.017514 -256.04597)
		)
		(stroke
			(width 0)
			(type solid)
		)
		(fill yes)
		(layer "In2.Cu")
		(net "M_F_CPU1_CLK_DP<1>")
	)
	(gr_poly
		(pts
			(xy 133.15442 -254.18034) (xy 133.045962 -254.0635) (xy 133.007608 -254.041402) (xy 132.829808 -254.34925)
			(xy 132.868162 -254.371348) (xy 133.02361 -254.406908)
		)
		(stroke
			(width 0)
			(type solid)
		)
		(fill yes)
		(layer "In2.Cu")
		(net "M_F_CPU1_CLK_DP<0>")
	)
	(gr_poly
		(pts
			(xy 133.394704 -279.605994) (xy 133.433058 -279.583896) (xy 133.255258 -279.276048) (xy 133.216904 -279.298146)
			(xy 133.108446 -279.414986) (xy 133.239256 -279.641554)
		)
		(stroke
			(width 0)
			(type solid)
		)
		(fill yes)
		(layer "In2.Cu")
		(net "M_F_CPU1_SA_DQ<0>")
	)
	(gr_poly
		(pts
			(xy 133.433058 -254.299974) (xy 133.394704 -254.277876) (xy 133.239256 -254.242316) (xy 133.108446 -254.468884)
			(xy 133.216904 -254.585724) (xy 133.255258 -254.607822)
		)
		(stroke
			(width 0)
			(type solid)
		)
		(fill yes)
		(layer "In2.Cu")
		(net "M_F_CPU1_CLK_DN<1>")
	)
	(gr_poly
		(pts
			(xy 133.437376 -255.920748) (xy 133.399022 -255.89865) (xy 133.243574 -255.86309) (xy 133.112764 -256.089658)
			(xy 133.221222 -256.206498) (xy 133.259576 -256.228596)
		)
		(stroke
			(width 0)
			(type solid)
		)
		(fill yes)
		(layer "In2.Cu")
		(net "M_F_CPU1_SA_PAR")
	)
	(gr_poly
		(pts
			(xy 133.617208 -256.635758) (xy 133.50875 -256.518918) (xy 133.470396 -256.49682) (xy 133.292596 -256.804668)
			(xy 133.33095 -256.826766) (xy 133.486398 -256.862326)
		)
		(stroke
			(width 0)
			(type solid)
		)
		(fill yes)
		(layer "In2.Cu")
		(net "M_F_CPU1_SA_CA<6>")
	)
	(gr_poly
		(pts
			(xy 133.617462 -255.007364) (xy 133.509004 -254.890524) (xy 133.47065 -254.868426) (xy 133.29285 -255.176274)
			(xy 133.331204 -255.198372) (xy 133.486652 -255.233932)
		)
		(stroke
			(width 0)
			(type solid)
		)
		(fill yes)
		(layer "In2.Cu")
		(net "M_F_CPU1_CLK_DP<1>")
	)
	(gr_poly
		(pts
			(xy 133.87197 -280.430986) (xy 133.910324 -280.408888) (xy 133.732524 -280.10104) (xy 133.69417 -280.123138)
			(xy 133.585712 -280.239978) (xy 133.716522 -280.466546)
		)
		(stroke
			(width 0)
			(type solid)
		)
		(fill yes)
		(layer "In2.Cu")
		(net "M_F_CPU1_SA_DQ<0>")
	)
	(gr_poly
		(pts
			(xy 133.908292 -255.1049) (xy 133.869938 -255.082802) (xy 133.71449 -255.047242) (xy 133.58368 -255.27381)
			(xy 133.692138 -255.39065) (xy 133.730492 -255.412748)
		)
		(stroke
			(width 0)
			(type solid)
		)
		(fill yes)
		(layer "In2.Cu")
		(net "M_F_CPU1_SA_PAR")
	)
	(gr_poly
		(pts
			(xy 133.984238 -279.816306) (xy 134.092696 -279.699466) (xy 133.961886 -279.472898) (xy 133.806438 -279.508458)
			(xy 133.768084 -279.530556) (xy 133.945884 -279.838404)
		)
		(stroke
			(width 0)
			(type solid)
		)
		(fill yes)
		(layer "In2.Cu")
		(net "M_F_CPU1_SA_DQ<2>")
	)
	(gr_poly
		(pts
			(xy 134.02183 -254.123698) (xy 133.97484 -253.971298) (xy 133.71322 -253.971298) (xy 133.66623 -254.123698)
			(xy 133.66623 -254.168148) (xy 134.02183 -254.168148)
		)
		(stroke
			(width 0)
			(type solid)
		)
		(fill yes)
		(layer "In2.Cu")
		(net "M_F_CPU1_CLK_DN<1>")
	)
	(gr_poly
		(pts
			(xy 134.094474 -255.809242) (xy 133.986016 -255.692402) (xy 133.947662 -255.670304) (xy 133.769862 -255.978152)
			(xy 133.808216 -256.00025) (xy 133.963664 -256.03581)
		)
		(stroke
			(width 0)
			(type solid)
		)
		(fill yes)
		(layer "In2.Cu")
		(net "M_F_CPU1_SA_CA<6>")
	)
	(gr_poly
		(pts
			(xy 134.373112 -244.53215) (xy 134.373112 -244.487954) (xy 134.017512 -244.487954) (xy 134.017512 -244.53215)
			(xy 134.064502 -244.68455) (xy 134.326122 -244.68455)
		)
		(stroke
			(width 0)
			(type solid)
		)
		(fill yes)
		(layer "In2.Cu")
		(net "M_F_CPU1_SB_CS_N<2>")
	)
	(gr_poly
		(pts
			(xy 134.474712 -280.574242) (xy 134.474712 -280.529792) (xy 134.119112 -280.529792) (xy 134.119112 -280.574242)
			(xy 134.166102 -280.726642) (xy 134.427722 -280.726642)
		)
		(stroke
			(width 0)
			(type solid)
		)
		(fill yes)
		(layer "In2.Cu")
		(net "M_F_CPU1_SA_DQ<0>")
	)
	(gr_poly
		(pts
			(xy 134.474712 -254.937514) (xy 134.427722 -254.785114) (xy 134.166102 -254.785114) (xy 134.119112 -254.937514)
			(xy 134.119112 -254.981964) (xy 134.474712 -254.981964)
		)
		(stroke
			(width 0)
			(type solid)
		)
		(fill yes)
		(layer "In2.Cu")
		(net "M_F_CPU1_SA_PAR")
	)
	(gr_poly
		(pts
			(xy 134.474712 -254.52959) (xy 134.474712 -254.48514) (xy 134.119112 -254.48514) (xy 134.119112 -254.52959)
			(xy 134.166102 -254.68199) (xy 134.427722 -254.68199)
		)
		(stroke
			(width 0)
			(type solid)
		)
		(fill yes)
		(layer "In2.Cu")
		(net "M_F_CPU1_CLK_DP<1>")
	)
	(gr_poly
		(pts
			(xy 134.48284 -258.28879) (xy 134.43585 -258.13639) (xy 134.17423 -258.13639) (xy 134.12724 -258.28879)
			(xy 134.12724 -258.33324) (xy 134.48284 -258.33324)
		)
		(stroke
			(width 0)
			(type solid)
		)
		(fill yes)
		(layer "In2.Cu")
		(net "M_F_CPU1_SA_CA<0>")
	)
	(gr_poly
		(pts
			(xy 134.698994 -247.64111) (xy 134.737348 -247.619012) (xy 134.559548 -247.311164) (xy 134.521194 -247.333262)
			(xy 134.412736 -247.450102) (xy 134.543546 -247.67667)
		)
		(stroke
			(width 0)
			(type solid)
		)
		(fill yes)
		(layer "In2.Cu")
		(net "M_F_CPU1_SB_CA<2>")
	)
	(gr_poly
		(pts
			(xy 134.809738 -247.023382) (xy 134.918196 -246.906542) (xy 134.787386 -246.679974) (xy 134.631938 -246.715534)
			(xy 134.593584 -246.737632) (xy 134.771384 -247.04548)
		)
		(stroke
			(width 0)
			(type solid)
		)
		(fill yes)
		(layer "In2.Cu")
		(net "M_F_CPU1_SB_CA<3>")
	)
	(gr_poly
		(pts
			(xy 134.814056 -242.14709) (xy 134.922514 -242.03025) (xy 134.791704 -241.803682) (xy 134.636256 -241.839242)
			(xy 134.597902 -241.86134) (xy 134.775702 -242.169188)
		)
		(stroke
			(width 0)
			(type solid)
		)
		(fill yes)
		(layer "In2.Cu")
		(net "M_F_CPU1_SB_CB<6>")
	)
	(gr_poly
		(pts
			(xy 134.84352 -240.46307) (xy 134.84352 -240.41862) (xy 134.48792 -240.41862) (xy 134.48792 -240.46307)
			(xy 134.53491 -240.61547) (xy 134.79653 -240.61547)
		)
		(stroke
			(width 0)
			(type solid)
		)
		(fill yes)
		(layer "In2.Cu")
		(net "M_F_CPU1_SB_DQS_DP<9>")
	)
	(gr_poly
		(pts
			(xy 134.851648 -243.718842) (xy 134.851648 -243.674392) (xy 134.496048 -243.674392) (xy 134.496048 -243.718842)
			(xy 134.543038 -243.871242) (xy 134.804658 -243.871242)
		)
		(stroke
			(width 0)
			(type solid)
		)
		(fill yes)
		(layer "In2.Cu")
		(net "M_F_CPU1_SB_CS_N<3>")
	)
	(gr_poly
		(pts
			(xy 134.944612 -257.37947) (xy 134.897622 -257.22707) (xy 134.636002 -257.22707) (xy 134.589012 -257.37947)
			(xy 134.589012 -257.423666) (xy 134.944612 -257.423666)
		)
		(stroke
			(width 0)
			(type solid)
		)
		(fill yes)
		(layer "In2.Cu")
		(net "M_F_CPU1_SA_CA<2>")
	)
	(gr_poly
		(pts
			(xy 134.952994 -280.168604) (xy 134.906004 -280.016204) (xy 134.644384 -280.016204) (xy 134.597394 -280.168604)
			(xy 134.597394 -280.2128) (xy 134.952994 -280.2128)
		)
		(stroke
			(width 0)
			(type solid)
		)
		(fill yes)
		(layer "In2.Cu")
		(net "M_F_CPU1_SA_DQ<2>")
	)
	(gr_poly
		(pts
			(xy 134.953248 -276.913086) (xy 134.906258 -276.760686) (xy 134.644638 -276.760686) (xy 134.597648 -276.913086)
			(xy 134.597648 -276.957282) (xy 134.953248 -276.957282)
		)
		(stroke
			(width 0)
			(type solid)
		)
		(fill yes)
		(layer "In2.Cu")
		(net "M_F_CPU1_SA_DQ<4>")
	)
	(gr_poly
		(pts
			(xy 134.953248 -258.503674) (xy 134.953248 -258.459224) (xy 134.597648 -258.459224) (xy 134.597648 -258.503674)
			(xy 134.644638 -258.656074) (xy 134.906258 -258.656074)
		)
		(stroke
			(width 0)
			(type solid)
		)
		(fill yes)
		(layer "In2.Cu")
		(net "M_F_CPU1_SA_CA<0>")
	)
	(gr_poly
		(pts
			(xy 134.95909 -260.226302) (xy 134.95909 -260.182106) (xy 134.60349 -260.182106) (xy 134.60349 -260.226302)
			(xy 134.65048 -260.378702) (xy 134.9121 -260.378702)
		)
		(stroke
			(width 0)
			(type solid)
		)
		(fill yes)
		(layer "In2.Cu")
		(net "M_F_CPU1_ALERT_N")
	)
	(gr_poly
		(pts
			(xy 134.95909 -259.00761) (xy 134.9121 -258.85521) (xy 134.65048 -258.85521) (xy 134.60349 -259.00761)
			(xy 134.60349 -259.051806) (xy 134.95909 -259.051806)
		)
		(stroke
			(width 0)
			(type solid)
		)
		(fill yes)
		(layer "In2.Cu")
		(net "M_F_CPU1_SA_CS_N<3>")
	)
	(gr_poly
		(pts
			(xy 134.95909 -255.343406) (xy 134.95909 -255.298956) (xy 134.60349 -255.298956) (xy 134.60349 -255.343406)
			(xy 134.65048 -255.495806) (xy 134.9121 -255.495806)
		)
		(stroke
			(width 0)
			(type solid)
		)
		(fill yes)
		(layer "In2.Cu")
		(net "M_F_CPU1_SA_CA<6>")
	)
	(gr_poly
		(pts
			(xy 134.95909 -254.124206) (xy 134.9121 -253.971806) (xy 134.65048 -253.971806) (xy 134.60349 -254.124206)
			(xy 134.60349 -254.168402) (xy 134.95909 -254.168402)
		)
		(stroke
			(width 0)
			(type solid)
		)
		(fill yes)
		(layer "In2.Cu")
		(net "M_F_CPU1_CLK_DN<1>")
	)
	(gr_poly
		(pts
			(xy 134.96163 -269.993618) (xy 134.96163 -269.949168) (xy 134.60603 -269.949168) (xy 134.60603 -269.993618)
			(xy 134.65302 -270.146018) (xy 134.91464 -270.146018)
		)
		(stroke
			(width 0)
			(type solid)
		)
		(fill yes)
		(layer "In2.Cu")
		(net "M_F_CPU1_SA_DQ<16>")
	)
	(gr_poly
		(pts
			(xy 135.168894 -246.827294) (xy 135.207248 -246.805196) (xy 135.029448 -246.497348) (xy 134.991094 -246.519446)
			(xy 134.882636 -246.636286) (xy 135.013446 -246.862854)
		)
		(stroke
			(width 0)
			(type solid)
		)
		(fill yes)
		(layer "In2.Cu")
		(net "M_F_CPU1_SB_CA<4>")
	)
	(gr_poly
		(pts
			(xy 135.20928 -237.78083) (xy 135.170926 -237.758732) (xy 135.015478 -237.723172) (xy 134.884668 -237.94974)
			(xy 134.993126 -238.06658) (xy 135.03148 -238.088678)
		)
		(stroke
			(width 0)
			(type solid)
		)
		(fill yes)
		(layer "In2.Cu")
		(net "M_F_CPU1_SB_CB<3>")
	)
	(gr_poly
		(pts
			(xy 135.279638 -279.615646) (xy 135.317992 -279.593548) (xy 135.140192 -279.2857) (xy 135.101838 -279.307798)
			(xy 134.99338 -279.424638) (xy 135.12419 -279.651206)
		)
		(stroke
			(width 0)
			(type solid)
		)
		(fill yes)
		(layer "In2.Cu")
		(net "M_F_CPU1_SA_DQ<3>")
	)
	(gr_poly
		(pts
			(xy 135.30707 -244.532658) (xy 135.30707 -244.488208) (xy 134.95147 -244.488208) (xy 134.95147 -244.532658)
			(xy 134.99846 -244.685058) (xy 135.26008 -244.685058)
		)
		(stroke
			(width 0)
			(type solid)
		)
		(fill yes)
		(layer "In2.Cu")
		(net "M_F_CPU1_SB_CS_N<2>")
	)
	(gr_poly
		(pts
			(xy 135.30707 -243.31295) (xy 135.26008 -243.16055) (xy 134.99846 -243.16055) (xy 134.95147 -243.31295)
			(xy 134.95147 -243.3574) (xy 135.30707 -243.3574)
		)
		(stroke
			(width 0)
			(type solid)
		)
		(fill yes)
		(layer "In2.Cu")
		(net "M_F_CPU1_SB_CS_N<1>")
	)
	(gr_poly
		(pts
			(xy 135.30707 -242.905026) (xy 135.30707 -242.860576) (xy 134.95147 -242.860576) (xy 134.95147 -242.905026)
			(xy 134.99846 -243.057426) (xy 135.26008 -243.057426)
		)
		(stroke
			(width 0)
			(type solid)
		)
		(fill yes)
		(layer "In2.Cu")
		(net "M_F_CPU1_SB_CB<4>")
	)
	(gr_poly
		(pts
			(xy 135.30707 -236.801914) (xy 135.26008 -236.649514) (xy 134.99846 -236.649514) (xy 134.95147 -236.801914)
			(xy 134.95147 -236.846364) (xy 135.30707 -236.846364)
		)
		(stroke
			(width 0)
			(type solid)
		)
		(fill yes)
		(layer "In2.Cu")
		(net "M_E_CPU1_SB_DQ<2>")
	)
	(gr_poly
		(pts
			(xy 135.313166 -247.787922) (xy 135.313166 -247.743472) (xy 134.957566 -247.743472) (xy 134.957566 -247.787922)
			(xy 135.004556 -247.940322) (xy 135.266176 -247.940322)
		)
		(stroke
			(width 0)
			(type solid)
		)
		(fill yes)
		(layer "In2.Cu")
		(net "M_F_CPU1_SB_CA<2>")
	)
	(gr_poly
		(pts
			(xy 135.316468 -241.276886) (xy 135.316468 -241.232436) (xy 134.960868 -241.232436) (xy 134.960868 -241.276886)
			(xy 135.007858 -241.429286) (xy 135.269478 -241.429286)
		)
		(stroke
			(width 0)
			(type solid)
		)
		(fill yes)
		(layer "In2.Cu")
		(net "M_F_CPU1_SB_CB<5>")
	)
	(gr_poly
		(pts
			(xy 135.31723 -236.393482) (xy 135.31723 -236.349032) (xy 134.96163 -236.349032) (xy 134.96163 -236.393482)
			(xy 135.00862 -236.545882) (xy 135.27024 -236.545882)
		)
		(stroke
			(width 0)
			(type solid)
		)
		(fill yes)
		(layer "In2.Cu")
		(net "M_E_CPU1_SB_DQ<1>")
	)
	(gr_poly
		(pts
			(xy 135.319008 -260.800088) (xy 135.280654 -260.77799) (xy 135.125206 -260.74243) (xy 134.994396 -260.968998)
			(xy 135.102854 -261.085838) (xy 135.141208 -261.107936)
		)
		(stroke
			(width 0)
			(type solid)
		)
		(fill yes)
		(layer "In2.Cu")
		(net "M_F_CPU1_SA_CB<7>")
	)
	(gr_poly
		(pts
			(xy 135.388096 -238.497364) (xy 135.279638 -238.380524) (xy 135.241284 -238.358426) (xy 135.063484 -238.666274)
			(xy 135.101838 -238.688372) (xy 135.257286 -238.723932)
		)
		(stroke
			(width 0)
			(type solid)
		)
		(fill yes)
		(layer "In2.Cu")
		(net "M_F_CPU1_SB_CB<1>")
	)
	(gr_poly
		(pts
			(xy 135.414512 -274.47113) (xy 135.367522 -274.31873) (xy 135.105902 -274.31873) (xy 135.058912 -274.47113)
			(xy 135.058912 -274.515326) (xy 135.414512 -274.515326)
		)
		(stroke
			(width 0)
			(type solid)
		)
		(fill yes)
		(layer "In2.Cu")
		(net "M_E_CPU1_SA_DQ<10>")
	)
	(gr_poly
		(pts
			(xy 135.414512 -274.062698) (xy 135.414512 -274.018502) (xy 135.058912 -274.018502) (xy 135.058912 -274.062698)
			(xy 135.105902 -274.215098) (xy 135.367522 -274.215098)
		)
		(stroke
			(width 0)
			(type solid)
		)
		(fill yes)
		(layer "In2.Cu")
		(net "M_E_CPU1_SA_DQ<9>")
	)
	(gr_poly
		(pts
			(xy 135.414512 -269.587726) (xy 135.367522 -269.435326) (xy 135.105902 -269.435326) (xy 135.058912 -269.587726)
			(xy 135.058912 -269.631922) (xy 135.414512 -269.631922)
		)
		(stroke
			(width 0)
			(type solid)
		)
		(fill yes)
		(layer "In2.Cu")
		(net "M_F_CPU1_SA_DQ<18>")
	)
	(gr_poly
		(pts
			(xy 135.422894 -263.077706) (xy 135.375904 -262.925306) (xy 135.114284 -262.925306) (xy 135.067294 -263.077706)
			(xy 135.067294 -263.121902) (xy 135.422894 -263.121902)
		)
		(stroke
			(width 0)
			(type solid)
		)
		(fill yes)
		(layer "In2.Cu")
		(net "M_F_CPU1_SA_DQS_DN<4>")
	)
	(gr_poly
		(pts
			(xy 135.422894 -259.412486) (xy 135.422894 -259.36829) (xy 135.067294 -259.36829) (xy 135.067294 -259.412486)
			(xy 135.114284 -259.564886) (xy 135.375904 -259.564886)
		)
		(stroke
			(width 0)
			(type solid)
		)
		(fill yes)
		(layer "In2.Cu")
		(net "M_F_CPU1_SA_CS_N<2>")
	)
	(gr_poly
		(pts
			(xy 135.422894 -254.938022) (xy 135.375904 -254.785622) (xy 135.114284 -254.785622) (xy 135.067294 -254.938022)
			(xy 135.067294 -254.982218) (xy 135.422894 -254.982218)
		)
		(stroke
			(width 0)
			(type solid)
		)
		(fill yes)
		(layer "In2.Cu")
		(net "M_F_CPU1_SA_PAR")
	)
	(gr_poly
		(pts
			(xy 135.422894 -254.529082) (xy 135.422894 -254.484886) (xy 135.067294 -254.484886) (xy 135.067294 -254.529082)
			(xy 135.114284 -254.681482) (xy 135.375904 -254.681482)
		)
		(stroke
			(width 0)
			(type solid)
		)
		(fill yes)
		(layer "In2.Cu")
		(net "M_F_CPU1_CLK_DP<1>")
	)
	(gr_poly
		(pts
			(xy 135.425688 -269.179294) (xy 135.425688 -269.134844) (xy 135.070088 -269.134844) (xy 135.070088 -269.179294)
			(xy 135.117078 -269.331694) (xy 135.378698 -269.331694)
		)
		(stroke
			(width 0)
			(type solid)
		)
		(fill yes)
		(layer "In2.Cu")
		(net "M_F_CPU1_SA_DQ<17>")
	)
	(gr_poly
		(pts
			(xy 135.431276 -280.574242) (xy 135.431276 -280.529792) (xy 135.075676 -280.529792) (xy 135.075676 -280.574242)
			(xy 135.122666 -280.726642) (xy 135.384286 -280.726642)
		)
		(stroke
			(width 0)
			(type solid)
		)
		(fill yes)
		(layer "In2.Cu")
		(net "M_F_CPU1_SA_DQ<0>")
	)
	(gr_poly
		(pts
			(xy 135.436356 -258.27609) (xy 135.428736 -258.232656) (xy 135.356092 -258.09067) (xy 135.098282 -258.136136)
			(xy 135.07847 -258.294378) (xy 135.086344 -258.338066)
		)
		(stroke
			(width 0)
			(type solid)
		)
		(fill yes)
		(layer "In2.Cu")
		(net "M_F_CPU1_SA_CA<0>")
	)
	(gr_poly
		(pts
			(xy 135.497824 -261.516622) (xy 135.389366 -261.399782) (xy 135.351012 -261.377684) (xy 135.173212 -261.685532)
			(xy 135.211566 -261.70763) (xy 135.367014 -261.74319)
		)
		(stroke
			(width 0)
			(type solid)
		)
		(fill yes)
		(layer "In2.Cu")
		(net "M_F_CPU1_SA_CB<5>")
	)
	(gr_poly
		(pts
			(xy 135.638794 -246.013478) (xy 135.677148 -245.99138) (xy 135.499348 -245.683532) (xy 135.460994 -245.70563)
			(xy 135.352536 -245.82247) (xy 135.483346 -246.049038)
		)
		(stroke
			(width 0)
			(type solid)
		)
		(fill yes)
		(layer "In2.Cu")
		(net "M_F_CPU1_SB_CA<6>")
	)
	(gr_poly
		(pts
			(xy 135.743188 -278.789638) (xy 135.781542 -278.76754) (xy 135.603742 -278.459692) (xy 135.565388 -278.48179)
			(xy 135.45693 -278.59863) (xy 135.58774 -278.825198)
		)
		(stroke
			(width 0)
			(type solid)
		)
		(fill yes)
		(layer "In2.Cu")
		(net "M_F_CPU1_SA_DQS_DP<0>")
	)
	(gr_poly
		(pts
			(xy 135.783066 -247.382538) (xy 135.736076 -247.230138) (xy 135.474456 -247.230138) (xy 135.427466 -247.382538)
			(xy 135.427466 -247.426988) (xy 135.783066 -247.426988)
		)
		(stroke
			(width 0)
			(type solid)
		)
		(fill yes)
		(layer "In2.Cu")
		(net "M_F_CPU1_SB_CA<3>")
	)
	(gr_poly
		(pts
			(xy 135.783066 -246.974106) (xy 135.783066 -246.929656) (xy 135.427466 -246.929656) (xy 135.427466 -246.974106)
			(xy 135.474456 -247.126506) (xy 135.736076 -247.126506)
		)
		(stroke
			(width 0)
			(type solid)
		)
		(fill yes)
		(layer "In2.Cu")
		(net "M_F_CPU1_SB_CA<4>")
	)
	(gr_poly
		(pts
			(xy 135.783066 -243.718334) (xy 135.783066 -243.674138) (xy 135.427466 -243.674138) (xy 135.427466 -243.718334)
			(xy 135.474456 -243.870734) (xy 135.736076 -243.870734)
		)
		(stroke
			(width 0)
			(type solid)
		)
		(fill yes)
		(layer "In2.Cu")
		(net "M_F_CPU1_SB_CS_N<3>")
	)
	(gr_poly
		(pts
			(xy 135.783066 -242.499134) (xy 135.736076 -242.346734) (xy 135.474456 -242.346734) (xy 135.427466 -242.499134)
			(xy 135.427466 -242.543584) (xy 135.783066 -242.543584)
		)
		(stroke
			(width 0)
			(type solid)
		)
		(fill yes)
		(layer "In2.Cu")
		(net "M_F_CPU1_SB_CB<6>")
	)
	(gr_poly
		(pts
			(xy 135.783066 -240.46307) (xy 135.783066 -240.41862) (xy 135.427466 -240.41862) (xy 135.427466 -240.46307)
			(xy 135.474456 -240.61547) (xy 135.736076 -240.61547)
		)
		(stroke
			(width 0)
			(type solid)
		)
		(fill yes)
		(layer "In2.Cu")
		(net "M_F_CPU1_SB_DQS_DP<9>")
	)
	(gr_poly
		(pts
			(xy 135.783066 -237.61573) (xy 135.736076 -237.46333) (xy 135.474456 -237.46333) (xy 135.427466 -237.61573)
			(xy 135.427466 -237.66018) (xy 135.783066 -237.66018)
		)
		(stroke
			(width 0)
			(type solid)
		)
		(fill yes)
		(layer "In2.Cu")
		(net "M_F_CPU1_SB_CB<3>")
	)
	(gr_poly
		(pts
			(xy 135.783066 -232.732834) (xy 135.736076 -232.580434) (xy 135.474456 -232.580434) (xy 135.427466 -232.732834)
			(xy 135.427466 -232.77703) (xy 135.783066 -232.77703)
		)
		(stroke
			(width 0)
			(type solid)
		)
		(fill yes)
		(layer "In2.Cu")
		(net "M_E_CPU1_SB_DQ<7>")
	)
	(gr_poly
		(pts
			(xy 135.783066 -232.323894) (xy 135.783066 -232.279698) (xy 135.427466 -232.279698) (xy 135.427466 -232.323894)
			(xy 135.474456 -232.476294) (xy 135.736076 -232.476294)
		)
		(stroke
			(width 0)
			(type solid)
		)
		(fill yes)
		(layer "In2.Cu")
		(net "M_F_CPU1_SB_DQ<8>")
	)
	(gr_poly
		(pts
			(xy 135.783066 -230.696262) (xy 135.783066 -230.651812) (xy 135.427466 -230.651812) (xy 135.427466 -230.696262)
			(xy 135.474456 -230.848662) (xy 135.736076 -230.848662)
		)
		(stroke
			(width 0)
			(type solid)
		)
		(fill yes)
		(layer "In2.Cu")
		(net "M_F_CPU1_SB_DQS_DP<1>")
	)
	(gr_poly
		(pts
			(xy 135.791448 -237.207806) (xy 135.791448 -237.163356) (xy 135.435848 -237.163356) (xy 135.435848 -237.207806)
			(xy 135.482838 -237.360206) (xy 135.744458 -237.360206)
		)
		(stroke
			(width 0)
			(type solid)
		)
		(fill yes)
		(layer "In2.Cu")
		(net "M_E_CPU1_SB_DQ<0>")
	)
	(gr_poly
		(pts
			(xy 135.85825 -278.17953) (xy 135.966708 -278.06269) (xy 135.835898 -277.836122) (xy 135.68045 -277.871682)
			(xy 135.642096 -277.89378) (xy 135.819896 -278.201628)
		)
		(stroke
			(width 0)
			(type solid)
		)
		(fill yes)
		(layer "In2.Cu")
		(net "M_F_CPU1_SA_DQS_DN<0>")
	)
	(gr_poly
		(pts
			(xy 135.886698 -280.16835) (xy 135.839708 -280.01595) (xy 135.578088 -280.01595) (xy 135.531098 -280.16835)
			(xy 135.531098 -280.212546) (xy 135.886698 -280.212546)
		)
		(stroke
			(width 0)
			(type solid)
		)
		(fill yes)
		(layer "In2.Cu")
		(net "M_F_CPU1_SA_DQ<2>")
	)
	(gr_poly
		(pts
			(xy 135.886698 -279.759918) (xy 135.886698 -279.715722) (xy 135.531098 -279.715722) (xy 135.531098 -279.759918)
			(xy 135.578088 -279.912318) (xy 135.839708 -279.912318)
		)
		(stroke
			(width 0)
			(type solid)
		)
		(fill yes)
		(layer "In2.Cu")
		(net "M_F_CPU1_SA_DQ<3>")
	)
	(gr_poly
		(pts
			(xy 135.892794 -260.635242) (xy 135.845804 -260.482842) (xy 135.584184 -260.482842) (xy 135.537194 -260.635242)
			(xy 135.537194 -260.679438) (xy 135.892794 -260.679438)
		)
		(stroke
			(width 0)
			(type solid)
		)
		(fill yes)
		(layer "In2.Cu")
		(net "M_F_CPU1_SA_CB<7>")
	)
	(gr_poly
		(pts
			(xy 135.892794 -260.226302) (xy 135.892794 -260.182106) (xy 135.537194 -260.182106) (xy 135.537194 -260.226302)
			(xy 135.584184 -260.378702) (xy 135.845804 -260.378702)
		)
		(stroke
			(width 0)
			(type solid)
		)
		(fill yes)
		(layer "In2.Cu")
		(net "M_F_CPU1_ALERT_N")
	)
	(gr_poly
		(pts
			(xy 135.892794 -257.37947) (xy 135.845804 -257.22707) (xy 135.584184 -257.22707) (xy 135.537194 -257.37947)
			(xy 135.537194 -257.42392) (xy 135.892794 -257.42392)
		)
		(stroke
			(width 0)
			(type solid)
		)
		(fill yes)
		(layer "In2.Cu")
		(net "M_F_CPU1_SA_CA<2>")
	)
	(gr_poly
		(pts
			(xy 135.892794 -255.751838) (xy 135.845804 -255.599438) (xy 135.584184 -255.599438) (xy 135.537194 -255.751838)
			(xy 135.537194 -255.796288) (xy 135.892794 -255.796288)
		)
		(stroke
			(width 0)
			(type solid)
		)
		(fill yes)
		(layer "In2.Cu")
		(net "M_F_CPU1_SA_CA<5>")
	)
	(gr_poly
		(pts
			(xy 135.892794 -255.343406) (xy 135.892794 -255.298956) (xy 135.537194 -255.298956) (xy 135.537194 -255.343406)
			(xy 135.584184 -255.495806) (xy 135.845804 -255.495806)
		)
		(stroke
			(width 0)
			(type solid)
		)
		(fill yes)
		(layer "In2.Cu")
		(net "M_F_CPU1_SA_CA<6>")
	)
	(gr_poly
		(pts
			(xy 135.892794 -254.124206) (xy 135.845804 -253.971806) (xy 135.584184 -253.971806) (xy 135.537194 -254.124206)
			(xy 135.537194 -254.168402) (xy 135.892794 -254.168402)
		)
		(stroke
			(width 0)
			(type solid)
		)
		(fill yes)
		(layer "In2.Cu")
		(net "M_F_CPU1_CLK_DN<1>")
	)
	(gr_poly
		(pts
			(xy 135.893048 -276.913086) (xy 135.846058 -276.760686) (xy 135.584438 -276.760686) (xy 135.537448 -276.913086)
			(xy 135.537448 -276.957282) (xy 135.893048 -276.957282)
		)
		(stroke
			(width 0)
			(type solid)
		)
		(fill yes)
		(layer "In2.Cu")
		(net "M_F_CPU1_SA_DQ<4>")
	)
	(gr_poly
		(pts
			(xy 135.89889 -273.248882) (xy 135.89889 -273.204432) (xy 135.54329 -273.204432) (xy 135.54329 -273.248882)
			(xy 135.59028 -273.401282) (xy 135.8519 -273.401282)
		)
		(stroke
			(width 0)
			(type solid)
		)
		(fill yes)
		(layer "In2.Cu")
		(net "M_E_CPU1_SA_DQS_DP<1>")
	)
	(gr_poly
		(pts
			(xy 135.89889 -268.365478) (xy 135.89889 -268.321028) (xy 135.54329 -268.321028) (xy 135.54329 -268.365478)
			(xy 135.59028 -268.517878) (xy 135.8519 -268.517878)
		)
		(stroke
			(width 0)
			(type solid)
		)
		(fill yes)
		(layer "In2.Cu")
		(net "M_F_CPU1_SA_DQS_DP<2>")
	)
	(gr_poly
		(pts
			(xy 135.90143 -275.284946) (xy 135.85444 -275.132546) (xy 135.59282 -275.132546) (xy 135.54583 -275.284946)
			(xy 135.54583 -275.329396) (xy 135.90143 -275.329396)
		)
		(stroke
			(width 0)
			(type solid)
		)
		(fill yes)
		(layer "In2.Cu")
		(net "M_F_CPU1_SA_DQ<7>")
	)
	(gr_poly
		(pts
			(xy 135.90143 -274.876768) (xy 135.90143 -274.832572) (xy 135.54583 -274.832572) (xy 135.54583 -274.876768)
			(xy 135.59282 -275.029168) (xy 135.85444 -275.029168)
		)
		(stroke
			(width 0)
			(type solid)
		)
		(fill yes)
		(layer "In2.Cu")
		(net "M_E_CPU1_SA_DQ<8>")
	)
	(gr_poly
		(pts
			(xy 135.90143 -270.401542) (xy 135.85444 -270.249142) (xy 135.59282 -270.249142) (xy 135.54583 -270.401542)
			(xy 135.54583 -270.445992) (xy 135.90143 -270.445992)
		)
		(stroke
			(width 0)
			(type solid)
		)
		(fill yes)
		(layer "In2.Cu")
		(net "M_E_CPU1_SA_DQ<15>")
	)
	(gr_poly
		(pts
			(xy 135.90143 -269.993618) (xy 135.90143 -269.949168) (xy 135.54583 -269.949168) (xy 135.54583 -269.993618)
			(xy 135.59282 -270.146018) (xy 135.85444 -270.146018)
		)
		(stroke
			(width 0)
			(type solid)
		)
		(fill yes)
		(layer "In2.Cu")
		(net "M_F_CPU1_SA_DQ<16>")
	)
	(gr_poly
		(pts
			(xy 135.90143 -265.518392) (xy 135.85444 -265.365992) (xy 135.59282 -265.365992) (xy 135.54583 -265.518392)
			(xy 135.54583 -265.562588) (xy 135.90143 -265.562588)
		)
		(stroke
			(width 0)
			(type solid)
		)
		(fill yes)
		(layer "In2.Cu")
		(net "M_F_CPU1_SA_DQ<23>")
	)
	(gr_poly
		(pts
			(xy 135.90143 -265.110214) (xy 135.90143 -265.065764) (xy 135.54583 -265.065764) (xy 135.54583 -265.110214)
			(xy 135.59282 -265.262614) (xy 135.85444 -265.262614)
		)
		(stroke
			(width 0)
			(type solid)
		)
		(fill yes)
		(layer "In2.Cu")
		(net "M_F_CPU1_SA_CB<0>")
	)
	(gr_poly
		(pts
			(xy 136.106154 -245.195598) (xy 136.144508 -245.1735) (xy 135.966708 -244.865652) (xy 135.928354 -244.88775)
			(xy 135.819896 -245.00459) (xy 135.950706 -245.231158)
		)
		(stroke
			(width 0)
			(type solid)
		)
		(fill yes)
		(layer "In2.Cu")
		(net "M_F_CPU1_SB_CS_N<2>")
	)
	(gr_poly
		(pts
			(xy 136.108694 -241.94389) (xy 136.147048 -241.921792) (xy 135.969248 -241.613944) (xy 135.930894 -241.636042)
			(xy 135.822436 -241.752882) (xy 135.953246 -241.97945)
		)
		(stroke
			(width 0)
			(type solid)
		)
		(fill yes)
		(layer "In2.Cu")
		(net "M_F_CPU1_SB_CB<5>")
	)
	(gr_poly
		(pts
			(xy 136.14908 -228.014276) (xy 136.110726 -227.992178) (xy 135.955278 -227.956618) (xy 135.824468 -228.183186)
			(xy 135.932926 -228.300026) (xy 135.97128 -228.322124)
		)
		(stroke
			(width 0)
			(type solid)
		)
		(fill yes)
		(layer "In2.Cu")
		(net "M_F_CPU1_SB_DQ<14>")
	)
	(gr_poly
		(pts
			(xy 136.219438 -241.326162) (xy 136.327896 -241.209322) (xy 136.197086 -240.982754) (xy 136.041638 -241.018314)
			(xy 136.003284 -241.040412) (xy 136.181084 -241.34826)
		)
		(stroke
			(width 0)
			(type solid)
		)
		(fill yes)
		(layer "In2.Cu")
		(net "M_F_CPU1_SB_CB<7>")
	)
	(gr_poly
		(pts
			(xy 136.221978 -244.585744) (xy 136.330436 -244.468904) (xy 136.199626 -244.242336) (xy 136.044178 -244.277896)
			(xy 136.005824 -244.299994) (xy 136.183624 -244.607842)
		)
		(stroke
			(width 0)
			(type solid)
		)
		(fill yes)
		(layer "In2.Cu")
		(net "M_F_CPU1_SB_CS_N<0>")
	)
	(gr_poly
		(pts
			(xy 136.24433 -236.801914) (xy 136.19734 -236.649514) (xy 135.93572 -236.649514) (xy 135.88873 -236.801914)
			(xy 135.88873 -236.84611) (xy 136.24433 -236.84611)
		)
		(stroke
			(width 0)
			(type solid)
		)
		(fill yes)
		(layer "In2.Cu")
		(net "M_E_CPU1_SB_DQ<2>")
	)
	(gr_poly
		(pts
			(xy 136.24433 -236.39399) (xy 136.24433 -236.34954) (xy 135.88873 -236.34954) (xy 135.88873 -236.39399)
			(xy 135.93572 -236.54639) (xy 136.19734 -236.54639)
		)
		(stroke
			(width 0)
			(type solid)
		)
		(fill yes)
		(layer "In2.Cu")
		(net "M_E_CPU1_SB_DQ<1>")
	)
	(gr_poly
		(pts
			(xy 136.24687 -240.057686) (xy 136.19988 -239.905286) (xy 135.93826 -239.905286) (xy 135.89127 -240.057686)
			(xy 135.89127 -240.101882) (xy 136.24687 -240.101882)
		)
		(stroke
			(width 0)
			(type solid)
		)
		(fill yes)
		(layer "In2.Cu")
		(net "M_F_CPU1_SB_DQS_DN<9>")
	)
	(gr_poly
		(pts
			(xy 136.24687 -235.174282) (xy 136.19988 -235.021882) (xy 135.93826 -235.021882) (xy 135.89127 -235.174282)
			(xy 135.89127 -235.218732) (xy 136.24687 -235.218732)
		)
		(stroke
			(width 0)
			(type solid)
		)
		(fill yes)
		(layer "In2.Cu")
		(net "M_E_CPU1_SB_DQS_DN<0>")
	)
	(gr_poly
		(pts
			(xy 136.252966 -246.568722) (xy 136.205976 -246.416322) (xy 135.944356 -246.416322) (xy 135.897366 -246.568722)
			(xy 135.897366 -246.613172) (xy 136.252966 -246.613172)
		)
		(stroke
			(width 0)
			(type solid)
		)
		(fill yes)
		(layer "In2.Cu")
		(net "M_F_CPU1_SB_CA<5>")
	)
	(gr_poly
		(pts
			(xy 136.252966 -246.16029) (xy 136.252966 -246.11584) (xy 135.897366 -246.11584) (xy 135.897366 -246.16029)
			(xy 135.944356 -246.31269) (xy 136.205976 -246.31269)
		)
		(stroke
			(width 0)
			(type solid)
		)
		(fill yes)
		(layer "In2.Cu")
		(net "M_F_CPU1_SB_CA<6>")
	)
	(gr_poly
		(pts
			(xy 136.252966 -243.313458) (xy 136.205976 -243.161058) (xy 135.944356 -243.161058) (xy 135.897366 -243.313458)
			(xy 135.897366 -243.357654) (xy 136.252966 -243.357654)
		)
		(stroke
			(width 0)
			(type solid)
		)
		(fill yes)
		(layer "In2.Cu")
		(net "M_F_CPU1_SB_CS_N<1>")
	)
	(gr_poly
		(pts
			(xy 136.252966 -242.904518) (xy 136.252966 -242.860322) (xy 135.897366 -242.860322) (xy 135.897366 -242.904518)
			(xy 135.944356 -243.056918) (xy 136.205976 -243.056918)
		)
		(stroke
			(width 0)
			(type solid)
		)
		(fill yes)
		(layer "In2.Cu")
		(net "M_F_CPU1_SB_CB<4>")
	)
	(gr_poly
		(pts
			(xy 136.252966 -238.430054) (xy 136.205976 -238.277654) (xy 135.944356 -238.277654) (xy 135.897366 -238.430054)
			(xy 135.897366 -238.47425) (xy 136.252966 -238.47425)
		)
		(stroke
			(width 0)
			(type solid)
		)
		(fill yes)
		(layer "In2.Cu")
		(net "M_F_CPU1_SB_CB<2>")
	)
	(gr_poly
		(pts
			(xy 136.252966 -238.021114) (xy 136.252966 -237.976918) (xy 135.897366 -237.976918) (xy 135.897366 -238.021114)
			(xy 135.944356 -238.173514) (xy 136.205976 -238.173514)
		)
		(stroke
			(width 0)
			(type solid)
		)
		(fill yes)
		(layer "In2.Cu")
		(net "M_F_CPU1_SB_CB<1>")
	)
	(gr_poly
		(pts
			(xy 136.252966 -233.54665) (xy 136.205976 -233.39425) (xy 135.944356 -233.39425) (xy 135.897366 -233.54665)
			(xy 135.897366 -233.590846) (xy 136.252966 -233.590846)
		)
		(stroke
			(width 0)
			(type solid)
		)
		(fill yes)
		(layer "In2.Cu")
		(net "M_E_CPU1_SB_DQ<6>")
	)
	(gr_poly
		(pts
			(xy 136.252966 -233.13771) (xy 136.252966 -233.093514) (xy 135.897366 -233.093514) (xy 135.897366 -233.13771)
			(xy 135.944356 -233.29011) (xy 136.205976 -233.29011)
		)
		(stroke
			(width 0)
			(type solid)
		)
		(fill yes)
		(layer "In2.Cu")
		(net "M_E_CPU1_SB_DQ<5>")
	)
	(gr_poly
		(pts
			(xy 136.252966 -231.919018) (xy 136.205976 -231.766618) (xy 135.944356 -231.766618) (xy 135.897366 -231.919018)
			(xy 135.897366 -231.963214) (xy 136.252966 -231.963214)
		)
		(stroke
			(width 0)
			(type solid)
		)
		(fill yes)
		(layer "In2.Cu")
		(net "M_F_CPU1_SB_DQ<10>")
	)
	(gr_poly
		(pts
			(xy 136.252966 -231.510078) (xy 136.252966 -231.465882) (xy 135.897366 -231.465882) (xy 135.897366 -231.510078)
			(xy 135.944356 -231.662478) (xy 136.205976 -231.662478)
		)
		(stroke
			(width 0)
			(type solid)
		)
		(fill yes)
		(layer "In2.Cu")
		(net "M_F_CPU1_SB_DQ<9>")
	)
	(gr_poly
		(pts
			(xy 136.252966 -230.290878) (xy 136.205976 -230.138478) (xy 135.944356 -230.138478) (xy 135.897366 -230.290878)
			(xy 135.897366 -230.335328) (xy 136.252966 -230.335328)
		)
		(stroke
			(width 0)
			(type solid)
		)
		(fill yes)
		(layer "In2.Cu")
		(net "M_F_CPU1_SB_DQS_DN<1>")
	)
	(gr_poly
		(pts
			(xy 136.354058 -259.820918) (xy 136.307068 -259.668518) (xy 136.045448 -259.668518) (xy 135.998458 -259.820918)
			(xy 135.998458 -259.865368) (xy 136.354058 -259.865368)
		)
		(stroke
			(width 0)
			(type solid)
		)
		(fill yes)
		(layer "In2.Cu")
		(net "M_F_CPU1_SA_CS_N<0>")
	)
	(gr_poly
		(pts
			(xy 136.354058 -259.412994) (xy 136.354058 -259.368544) (xy 135.998458 -259.368544) (xy 135.998458 -259.412994)
			(xy 136.045448 -259.565394) (xy 136.307068 -259.565394)
		)
		(stroke
			(width 0)
			(type solid)
		)
		(fill yes)
		(layer "In2.Cu")
		(net "M_F_CPU1_SA_CS_N<2>")
	)
	(gr_poly
		(pts
			(xy 136.354312 -274.47113) (xy 136.307322 -274.31873) (xy 136.045702 -274.31873) (xy 135.998712 -274.47113)
			(xy 135.998712 -274.515326) (xy 136.354312 -274.515326)
		)
		(stroke
			(width 0)
			(type solid)
		)
		(fill yes)
		(layer "In2.Cu")
		(net "M_E_CPU1_SA_DQ<10>")
	)
	(gr_poly
		(pts
			(xy 136.354312 -270.807434) (xy 136.354312 -270.762984) (xy 135.998712 -270.762984) (xy 135.998712 -270.807434)
			(xy 136.045702 -270.959834) (xy 136.307322 -270.959834)
		)
		(stroke
			(width 0)
			(type solid)
		)
		(fill yes)
		(layer "In2.Cu")
		(net "M_E_CPU1_SA_DQ<13>")
	)
	(gr_poly
		(pts
			(xy 136.354312 -269.587726) (xy 136.307322 -269.435326) (xy 136.045702 -269.435326) (xy 135.998712 -269.587726)
			(xy 135.998712 -269.631922) (xy 136.354312 -269.631922)
		)
		(stroke
			(width 0)
			(type solid)
		)
		(fill yes)
		(layer "In2.Cu")
		(net "M_F_CPU1_SA_DQ<18>")
	)
	(gr_poly
		(pts
			(xy 136.354312 -265.924284) (xy 136.354312 -265.879834) (xy 135.998712 -265.879834) (xy 135.998712 -265.924284)
			(xy 136.045702 -266.076684) (xy 136.307322 -266.076684)
		)
		(stroke
			(width 0)
			(type solid)
		)
		(fill yes)
		(layer "In2.Cu")
		(net "M_F_CPU1_SA_DQ<21>")
	)
	(gr_poly
		(pts
			(xy 136.354312 -264.704322) (xy 136.307322 -264.551922) (xy 136.045702 -264.551922) (xy 135.998712 -264.704322)
			(xy 135.998712 -264.748772) (xy 136.354312 -264.748772)
		)
		(stroke
			(width 0)
			(type solid)
		)
		(fill yes)
		(layer "In2.Cu")
		(net "M_F_CPU1_SA_CB<2>")
	)
	(gr_poly
		(pts
			(xy 136.356852 -275.690584) (xy 136.356852 -275.646388) (xy 136.001252 -275.646388) (xy 136.001252 -275.690584)
			(xy 136.048242 -275.842984) (xy 136.309862 -275.842984)
		)
		(stroke
			(width 0)
			(type solid)
		)
		(fill yes)
		(layer "In2.Cu")
		(net "M_F_CPU1_SA_DQ<5>")
	)
	(gr_poly
		(pts
			(xy 136.362694 -274.062698) (xy 136.362694 -274.018248) (xy 136.007094 -274.018248) (xy 136.007094 -274.062698)
			(xy 136.054084 -274.215098) (xy 136.315704 -274.215098)
		)
		(stroke
			(width 0)
			(type solid)
		)
		(fill yes)
		(layer "In2.Cu")
		(net "M_E_CPU1_SA_DQ<9>")
	)
	(gr_poly
		(pts
			(xy 136.362694 -272.843498) (xy 136.315704 -272.691098) (xy 136.054084 -272.691098) (xy 136.007094 -272.843498)
			(xy 136.007094 -272.887948) (xy 136.362694 -272.887948)
		)
		(stroke
			(width 0)
			(type solid)
		)
		(fill yes)
		(layer "In2.Cu")
		(net "M_E_CPU1_SA_DQS_DN<1>")
	)
	(gr_poly
		(pts
			(xy 136.362694 -271.215866) (xy 136.315704 -271.063466) (xy 136.054084 -271.063466) (xy 136.007094 -271.215866)
			(xy 136.007094 -271.260062) (xy 136.362694 -271.260062)
		)
		(stroke
			(width 0)
			(type solid)
		)
		(fill yes)
		(layer "In2.Cu")
		(net "M_E_CPU1_SA_DQ<14>")
	)
	(gr_poly
		(pts
			(xy 136.362694 -269.179294) (xy 136.362694 -269.134844) (xy 136.007094 -269.134844) (xy 136.007094 -269.179294)
			(xy 136.054084 -269.331694) (xy 136.315704 -269.331694)
		)
		(stroke
			(width 0)
			(type solid)
		)
		(fill yes)
		(layer "In2.Cu")
		(net "M_F_CPU1_SA_DQ<17>")
	)
	(gr_poly
		(pts
			(xy 136.362694 -267.960094) (xy 136.315704 -267.807694) (xy 136.054084 -267.807694) (xy 136.007094 -267.960094)
			(xy 136.007094 -268.004544) (xy 136.362694 -268.004544)
		)
		(stroke
			(width 0)
			(type solid)
		)
		(fill yes)
		(layer "In2.Cu")
		(net "M_F_CPU1_SA_DQS_DN<2>")
	)
	(gr_poly
		(pts
			(xy 136.362694 -264.29589) (xy 136.362694 -264.251694) (xy 136.007094 -264.251694) (xy 136.007094 -264.29589)
			(xy 136.054084 -264.44829) (xy 136.315704 -264.44829)
		)
		(stroke
			(width 0)
			(type solid)
		)
		(fill yes)
		(layer "In2.Cu")
		(net "M_F_CPU1_SA_CB<1>")
	)
	(gr_poly
		(pts
			(xy 136.362694 -263.077706) (xy 136.315704 -262.925306) (xy 136.054084 -262.925306) (xy 136.007094 -263.077706)
			(xy 136.007094 -263.121902) (xy 136.362694 -263.121902)
		)
		(stroke
			(width 0)
			(type solid)
		)
		(fill yes)
		(layer "In2.Cu")
		(net "M_F_CPU1_SA_DQS_DN<4>")
	)
	(gr_poly
		(pts
			(xy 136.362694 -261.449058) (xy 136.315704 -261.296658) (xy 136.054084 -261.296658) (xy 136.007094 -261.449058)
			(xy 136.007094 -261.493508) (xy 136.362694 -261.493508)
		)
		(stroke
			(width 0)
			(type solid)
		)
		(fill yes)
		(layer "In2.Cu")
		(net "M_F_CPU1_SA_CB<6>")
	)
	(gr_poly
		(pts
			(xy 136.362694 -261.040626) (xy 136.362694 -260.996176) (xy 136.007094 -260.996176) (xy 136.007094 -261.040626)
			(xy 136.054084 -261.193026) (xy 136.315704 -261.193026)
		)
		(stroke
			(width 0)
			(type solid)
		)
		(fill yes)
		(layer "In2.Cu")
		(net "M_F_CPU1_SA_CB<5>")
	)
	(gr_poly
		(pts
			(xy 136.362694 -254.938022) (xy 136.315704 -254.785622) (xy 136.054084 -254.785622) (xy 136.007094 -254.938022)
			(xy 136.007094 -254.982218) (xy 136.362694 -254.982218)
		)
		(stroke
			(width 0)
			(type solid)
		)
		(fill yes)
		(layer "In2.Cu")
		(net "M_F_CPU1_SA_PAR")
	)
	(gr_poly
		(pts
			(xy 136.362694 -254.529082) (xy 136.362694 -254.484886) (xy 136.007094 -254.484886) (xy 136.007094 -254.529082)
			(xy 136.054084 -254.681482) (xy 136.315704 -254.681482)
		)
		(stroke
			(width 0)
			(type solid)
		)
		(fill yes)
		(layer "In2.Cu")
		(net "M_F_CPU1_CLK_DP<1>")
	)
	(gr_poly
		(pts
			(xy 136.362948 -278.945594) (xy 136.362948 -278.901398) (xy 136.007348 -278.901398) (xy 136.007348 -278.945594)
			(xy 136.054338 -279.097994) (xy 136.315958 -279.097994)
		)
		(stroke
			(width 0)
			(type solid)
		)
		(fill yes)
		(layer "In2.Cu")
		(net "M_F_CPU1_SA_DQS_DP<0>")
	)
	(gr_poly
		(pts
			(xy 136.362948 -256.157222) (xy 136.362948 -256.112772) (xy 136.007348 -256.112772) (xy 136.007348 -256.157222)
			(xy 136.054338 -256.309622) (xy 136.315958 -256.309622)
		)
		(stroke
			(width 0)
			(type solid)
		)
		(fill yes)
		(layer "In2.Cu")
		(net "M_F_CPU1_SA_CA<4>")
	)
	(gr_poly
		(pts
			(xy 136.36879 -279.354534) (xy 136.3218 -279.202134) (xy 136.06018 -279.202134) (xy 136.01319 -279.354534)
			(xy 136.01319 -279.39873) (xy 136.36879 -279.39873)
		)
		(stroke
			(width 0)
			(type solid)
		)
		(fill yes)
		(layer "In2.Cu")
		(net "M_F_CPU1_SA_DQ<1>")
	)
	(gr_poly
		(pts
			(xy 136.578594 -244.385592) (xy 136.616948 -244.363494) (xy 136.439148 -244.055646) (xy 136.400794 -244.077744)
			(xy 136.292336 -244.194584) (xy 136.423146 -244.421152)
		)
		(stroke
			(width 0)
			(type solid)
		)
		(fill yes)
		(layer "In2.Cu")
		(net "M_F_CPU1_SB_CS_N<3>")
	)
	(gr_poly
		(pts
			(xy 136.578594 -241.130074) (xy 136.616948 -241.107976) (xy 136.439148 -240.800128) (xy 136.400794 -240.822226)
			(xy 136.292336 -240.939066) (xy 136.423146 -241.165634)
		)
		(stroke
			(width 0)
			(type solid)
		)
		(fill yes)
		(layer "In2.Cu")
		(net "M_F_CPU1_SB_DQS_DP<9>")
	)
	(gr_poly
		(pts
			(xy 136.616948 -228.832156) (xy 136.578594 -228.810058) (xy 136.423146 -228.774498) (xy 136.292336 -229.001066)
			(xy 136.400794 -229.117906) (xy 136.439148 -229.140004)
		)
		(stroke
			(width 0)
			(type solid)
		)
		(fill yes)
		(layer "In2.Cu")
		(net "M_F_CPU1_SB_DQS_DP<6>")
	)
	(gr_poly
		(pts
			(xy 136.688322 -240.510314) (xy 136.79678 -240.393474) (xy 136.66597 -240.166906) (xy 136.510522 -240.202466)
			(xy 136.472168 -240.224564) (xy 136.649968 -240.532412)
		)
		(stroke
			(width 0)
			(type solid)
		)
		(fill yes)
		(layer "In2.Cu")
		(net "M_F_CPU1_SB_DQS_DN<9>")
	)
	(gr_poly
		(pts
			(xy 136.689338 -243.767864) (xy 136.797796 -243.651024) (xy 136.666986 -243.424456) (xy 136.511538 -243.460016)
			(xy 136.473184 -243.482114) (xy 136.650984 -243.789962)
		)
		(stroke
			(width 0)
			(type solid)
		)
		(fill yes)
		(layer "In2.Cu")
		(net "M_F_CPU1_SB_CS_N<1>")
	)
	(gr_poly
		(pts
			(xy 136.722866 -246.974106) (xy 136.722866 -246.929656) (xy 136.367266 -246.929656) (xy 136.367266 -246.974106)
			(xy 136.414256 -247.126506) (xy 136.675876 -247.126506)
		)
		(stroke
			(width 0)
			(type solid)
		)
		(fill yes)
		(layer "In2.Cu")
		(net "M_F_CPU1_SB_CA<4>")
	)
	(gr_poly
		(pts
			(xy 136.722866 -245.754906) (xy 136.675876 -245.602506) (xy 136.414256 -245.602506) (xy 136.367266 -245.754906)
			(xy 136.367266 -245.799356) (xy 136.722866 -245.799356)
		)
		(stroke
			(width 0)
			(type solid)
		)
		(fill yes)
		(layer "In2.Cu")
		(net "M_F_CPU1_SB_PAR")
	)
	(gr_poly
		(pts
			(xy 136.722866 -245.346474) (xy 136.722866 -245.302024) (xy 136.367266 -245.302024) (xy 136.367266 -245.346474)
			(xy 136.414256 -245.498874) (xy 136.675876 -245.498874)
		)
		(stroke
			(width 0)
			(type solid)
		)
		(fill yes)
		(layer "In2.Cu")
		(net "M_F_CPU1_SB_CS_N<2>")
	)
	(gr_poly
		(pts
			(xy 136.722866 -242.499134) (xy 136.675876 -242.346734) (xy 136.414256 -242.346734) (xy 136.367266 -242.499134)
			(xy 136.367266 -242.543584) (xy 136.722866 -242.543584)
		)
		(stroke
			(width 0)
			(type solid)
		)
		(fill yes)
		(layer "In2.Cu")
		(net "M_F_CPU1_SB_CB<6>")
	)
	(gr_poly
		(pts
			(xy 136.722866 -242.090702) (xy 136.722866 -242.046252) (xy 136.367266 -242.046252) (xy 136.367266 -242.090702)
			(xy 136.414256 -242.243102) (xy 136.675876 -242.243102)
		)
		(stroke
			(width 0)
			(type solid)
		)
		(fill yes)
		(layer "In2.Cu")
		(net "M_F_CPU1_SB_CB<5>")
	)
	(gr_poly
		(pts
			(xy 136.722866 -238.83493) (xy 136.722866 -238.790734) (xy 136.367266 -238.790734) (xy 136.367266 -238.83493)
			(xy 136.414256 -238.98733) (xy 136.675876 -238.98733)
		)
		(stroke
			(width 0)
			(type solid)
		)
		(fill yes)
		(layer "In2.Cu")
		(net "M_F_CPU1_SB_CB<0>")
	)
	(gr_poly
		(pts
			(xy 136.722866 -237.61573) (xy 136.675876 -237.46333) (xy 136.414256 -237.46333) (xy 136.367266 -237.61573)
			(xy 136.367266 -237.66018) (xy 136.722866 -237.66018)
		)
		(stroke
			(width 0)
			(type solid)
		)
		(fill yes)
		(layer "In2.Cu")
		(net "M_F_CPU1_SB_CB<3>")
	)
	(gr_poly
		(pts
			(xy 136.722866 -233.952034) (xy 136.722866 -233.907584) (xy 136.367266 -233.907584) (xy 136.367266 -233.952034)
			(xy 136.414256 -234.104434) (xy 136.675876 -234.104434)
		)
		(stroke
			(width 0)
			(type solid)
		)
		(fill yes)
		(layer "In2.Cu")
		(net "M_E_CPU1_SB_DQ<4>")
	)
	(gr_poly
		(pts
			(xy 136.722866 -232.732834) (xy 136.675876 -232.580434) (xy 136.414256 -232.580434) (xy 136.367266 -232.732834)
			(xy 136.367266 -232.77703) (xy 136.722866 -232.77703)
		)
		(stroke
			(width 0)
			(type solid)
		)
		(fill yes)
		(layer "In2.Cu")
		(net "M_E_CPU1_SB_DQ<7>")
	)
	(gr_poly
		(pts
			(xy 136.722866 -232.323894) (xy 136.722866 -232.279698) (xy 136.367266 -232.279698) (xy 136.367266 -232.323894)
			(xy 136.414256 -232.476294) (xy 136.675876 -232.476294)
		)
		(stroke
			(width 0)
			(type solid)
		)
		(fill yes)
		(layer "In2.Cu")
		(net "M_F_CPU1_SB_DQ<8>")
	)
	(gr_poly
		(pts
			(xy 136.722866 -231.104694) (xy 136.675876 -230.952294) (xy 136.414256 -230.952294) (xy 136.367266 -231.104694)
			(xy 136.367266 -231.149144) (xy 136.722866 -231.149144)
		)
		(stroke
			(width 0)
			(type solid)
		)
		(fill yes)
		(layer "In2.Cu")
		(net "M_F_CPU1_SB_DQ<11>")
	)
	(gr_poly
		(pts
			(xy 136.722866 -230.696262) (xy 136.722866 -230.651812) (xy 136.367266 -230.651812) (xy 136.367266 -230.696262)
			(xy 136.414256 -230.848662) (xy 136.675876 -230.848662)
		)
		(stroke
			(width 0)
			(type solid)
		)
		(fill yes)
		(layer "In2.Cu")
		(net "M_F_CPU1_SB_DQS_DP<1>")
	)
	(gr_poly
		(pts
			(xy 136.722866 -227.84943) (xy 136.675876 -227.69703) (xy 136.414256 -227.69703) (xy 136.367266 -227.84943)
			(xy 136.367266 -227.893626) (xy 136.722866 -227.893626)
		)
		(stroke
			(width 0)
			(type solid)
		)
		(fill yes)
		(layer "In2.Cu")
		(net "M_F_CPU1_SB_DQ<14>")
	)
	(gr_poly
		(pts
			(xy 136.722866 -227.44049) (xy 136.722866 -227.396294) (xy 136.367266 -227.396294) (xy 136.367266 -227.44049)
			(xy 136.414256 -227.59289) (xy 136.675876 -227.59289)
		)
		(stroke
			(width 0)
			(type solid)
		)
		(fill yes)
		(layer "In2.Cu")
		(net "M_F_CPU1_SB_DQ<13>")
	)
	(gr_poly
		(pts
			(xy 136.731248 -239.243362) (xy 136.684258 -239.090962) (xy 136.422638 -239.090962) (xy 136.375648 -239.243362)
			(xy 136.375648 -239.287812) (xy 136.731248 -239.287812)
		)
		(stroke
			(width 0)
			(type solid)
		)
		(fill yes)
		(layer "In2.Cu")
		(net "M_F_CPU1_SB_DQS_DP<4>")
	)
	(gr_poly
		(pts
			(xy 136.731248 -237.207806) (xy 136.731248 -237.163356) (xy 136.375648 -237.163356) (xy 136.375648 -237.207806)
			(xy 136.422638 -237.360206) (xy 136.684258 -237.360206)
		)
		(stroke
			(width 0)
			(type solid)
		)
		(fill yes)
		(layer "In2.Cu")
		(net "M_E_CPU1_SB_DQ<0>")
	)
	(gr_poly
		(pts
			(xy 136.731248 -235.988098) (xy 136.684258 -235.835698) (xy 136.422638 -235.835698) (xy 136.375648 -235.988098)
			(xy 136.375648 -236.032294) (xy 136.731248 -236.032294)
		)
		(stroke
			(width 0)
			(type solid)
		)
		(fill yes)
		(layer "In2.Cu")
		(net "M_E_CPU1_SB_DQ<3>")
	)
	(gr_poly
		(pts
			(xy 136.731248 -235.579666) (xy 136.731248 -235.53547) (xy 136.375648 -235.53547) (xy 136.375648 -235.579666)
			(xy 136.422638 -235.732066) (xy 136.684258 -235.732066)
		)
		(stroke
			(width 0)
			(type solid)
		)
		(fill yes)
		(layer "In2.Cu")
		(net "M_E_CPU1_SB_DQS_DP<0>")
	)
	(gr_poly
		(pts
			(xy 136.731248 -234.360466) (xy 136.684258 -234.208066) (xy 136.422638 -234.208066) (xy 136.375648 -234.360466)
			(xy 136.375648 -234.404662) (xy 136.731248 -234.404662)
		)
		(stroke
			(width 0)
			(type solid)
		)
		(fill yes)
		(layer "In2.Cu")
		(net "M_E_CPU1_SB_DQS_DP<5>")
	)
	(gr_poly
		(pts
			(xy 136.797796 -229.544626) (xy 136.689338 -229.427786) (xy 136.650984 -229.405688) (xy 136.473184 -229.713536)
			(xy 136.511538 -229.735634) (xy 136.666986 -229.771194)
		)
		(stroke
			(width 0)
			(type solid)
		)
		(fill yes)
		(layer "In2.Cu")
		(net "M_F_CPU1_SB_DQS_DN<6>")
	)
	(gr_poly
		(pts
			(xy 136.824212 -279.759918) (xy 136.824212 -279.715722) (xy 136.468612 -279.715722) (xy 136.468612 -279.759918)
			(xy 136.515602 -279.912318) (xy 136.777222 -279.912318)
		)
		(stroke
			(width 0)
			(type solid)
		)
		(fill yes)
		(layer "In2.Cu")
		(net "M_F_CPU1_SA_DQ<3>")
	)
	(gr_poly
		(pts
			(xy 136.824212 -278.540718) (xy 136.777222 -278.388318) (xy 136.515602 -278.388318) (xy 136.468612 -278.540718)
			(xy 136.468612 -278.584914) (xy 136.824212 -278.584914)
		)
		(stroke
			(width 0)
			(type solid)
		)
		(fill yes)
		(layer "In2.Cu")
		(net "M_F_CPU1_SA_DQS_DN<0>")
	)
	(gr_poly
		(pts
			(xy 136.824212 -258.599178) (xy 136.824212 -258.554728) (xy 136.468612 -258.554728) (xy 136.468612 -258.599178)
			(xy 136.515602 -258.751578) (xy 136.777222 -258.751578)
		)
		(stroke
			(width 0)
			(type solid)
		)
		(fill yes)
		(layer "In2.Cu")
		(net "M_F_CPU1_SA_CS_N<1>")
	)
	(gr_poly
		(pts
			(xy 136.824212 -257.37947) (xy 136.777222 -257.22707) (xy 136.515602 -257.22707) (xy 136.468612 -257.37947)
			(xy 136.468612 -257.423666) (xy 136.824212 -257.423666)
		)
		(stroke
			(width 0)
			(type solid)
		)
		(fill yes)
		(layer "In2.Cu")
		(net "M_F_CPU1_SA_CA<2>")
	)
	(gr_poly
		(pts
			(xy 136.832594 -280.168604) (xy 136.785604 -280.016204) (xy 136.523984 -280.016204) (xy 136.476994 -280.168604)
			(xy 136.476994 -280.2128) (xy 136.832594 -280.2128)
		)
		(stroke
			(width 0)
			(type solid)
		)
		(fill yes)
		(layer "In2.Cu")
		(net "M_F_CPU1_SA_DQ<2>")
	)
	(gr_poly
		(pts
			(xy 136.832594 -278.132032) (xy 136.832594 -278.087836) (xy 136.476994 -278.087836) (xy 136.476994 -278.132032)
			(xy 136.523984 -278.284432) (xy 136.785604 -278.284432)
		)
		(stroke
			(width 0)
			(type solid)
		)
		(fill yes)
		(layer "In2.Cu")
		(net "M_F_CPU1_SA_DQS_DN<5>")
	)
	(gr_poly
		(pts
			(xy 136.832594 -273.657314) (xy 136.785604 -273.504914) (xy 136.523984 -273.504914) (xy 136.476994 -273.657314)
			(xy 136.476994 -273.701764) (xy 136.832594 -273.701764)
		)
		(stroke
			(width 0)
			(type solid)
		)
		(fill yes)
		(layer "In2.Cu")
		(net "M_E_CPU1_SA_DQ<11>")
	)
	(gr_poly
		(pts
			(xy 136.832594 -273.248882) (xy 136.832594 -273.204432) (xy 136.476994 -273.204432) (xy 136.476994 -273.248882)
			(xy 136.523984 -273.401282) (xy 136.785604 -273.401282)
		)
		(stroke
			(width 0)
			(type solid)
		)
		(fill yes)
		(layer "In2.Cu")
		(net "M_E_CPU1_SA_DQS_DP<1>")
	)
	(gr_poly
		(pts
			(xy 136.832594 -268.77391) (xy 136.785604 -268.62151) (xy 136.523984 -268.62151) (xy 136.476994 -268.77391)
			(xy 136.476994 -268.81836) (xy 136.832594 -268.81836)
		)
		(stroke
			(width 0)
			(type solid)
		)
		(fill yes)
		(layer "In2.Cu")
		(net "M_F_CPU1_SA_DQ<19>")
	)
	(gr_poly
		(pts
			(xy 136.832594 -268.365478) (xy 136.832594 -268.321028) (xy 136.476994 -268.321028) (xy 136.476994 -268.365478)
			(xy 136.523984 -268.517878) (xy 136.785604 -268.517878)
		)
		(stroke
			(width 0)
			(type solid)
		)
		(fill yes)
		(layer "In2.Cu")
		(net "M_F_CPU1_SA_DQS_DP<2>")
	)
	(gr_poly
		(pts
			(xy 136.832594 -267.146278) (xy 136.785604 -266.993878) (xy 136.523984 -266.993878) (xy 136.476994 -267.146278)
			(xy 136.476994 -267.190474) (xy 136.832594 -267.190474)
		)
		(stroke
			(width 0)
			(type solid)
		)
		(fill yes)
		(layer "In2.Cu")
		(net "M_F_CPU1_SA_DQS_DP<7>")
	)
	(gr_poly
		(pts
			(xy 136.832594 -266.737846) (xy 136.832594 -266.693396) (xy 136.476994 -266.693396) (xy 136.476994 -266.737846)
			(xy 136.523984 -266.890246) (xy 136.785604 -266.890246)
		)
		(stroke
			(width 0)
			(type solid)
		)
		(fill yes)
		(layer "In2.Cu")
		(net "M_F_CPU1_SA_DQ<20>")
	)
	(gr_poly
		(pts
			(xy 136.832594 -263.891014) (xy 136.785604 -263.738614) (xy 136.523984 -263.738614) (xy 136.476994 -263.891014)
			(xy 136.476994 -263.93521) (xy 136.832594 -263.93521)
		)
		(stroke
			(width 0)
			(type solid)
		)
		(fill yes)
		(layer "In2.Cu")
		(net "M_F_CPU1_SA_CB<3>")
	)
	(gr_poly
		(pts
			(xy 136.832594 -263.482074) (xy 136.832594 -263.437878) (xy 136.476994 -263.437878) (xy 136.476994 -263.482074)
			(xy 136.523984 -263.634474) (xy 136.785604 -263.634474)
		)
		(stroke
			(width 0)
			(type solid)
		)
		(fill yes)
		(layer "In2.Cu")
		(net "M_F_CPU1_SA_DQS_DP<4>")
	)
	(gr_poly
		(pts
			(xy 136.832594 -262.262874) (xy 136.785604 -262.110474) (xy 136.523984 -262.110474) (xy 136.476994 -262.262874)
			(xy 136.476994 -262.307324) (xy 136.832594 -262.307324)
		)
		(stroke
			(width 0)
			(type solid)
		)
		(fill yes)
		(layer "In2.Cu")
		(net "M_F_CPU1_SA_DQS_DP<9>")
	)
	(gr_poly
		(pts
			(xy 136.832594 -261.854442) (xy 136.832594 -261.809992) (xy 136.476994 -261.809992) (xy 136.476994 -261.854442)
			(xy 136.523984 -262.006842) (xy 136.785604 -262.006842)
		)
		(stroke
			(width 0)
			(type solid)
		)
		(fill yes)
		(layer "In2.Cu")
		(net "M_F_CPU1_SA_CB<4>")
	)
	(gr_poly
		(pts
			(xy 136.832594 -260.635242) (xy 136.785604 -260.482842) (xy 136.523984 -260.482842) (xy 136.476994 -260.635242)
			(xy 136.476994 -260.679438) (xy 136.832594 -260.679438)
		)
		(stroke
			(width 0)
			(type solid)
		)
		(fill yes)
		(layer "In2.Cu")
		(net "M_F_CPU1_SA_CB<7>")
	)
	(gr_poly
		(pts
			(xy 136.832594 -256.971038) (xy 136.832594 -256.926588) (xy 136.476994 -256.926588) (xy 136.476994 -256.971038)
			(xy 136.523984 -257.123438) (xy 136.785604 -257.123438)
		)
		(stroke
			(width 0)
			(type solid)
		)
		(fill yes)
		(layer "In2.Cu")
		(net "M_F_CPU1_SA_CA<3>")
	)
	(gr_poly
		(pts
			(xy 136.832594 -255.343406) (xy 136.832594 -255.298956) (xy 136.476994 -255.298956) (xy 136.476994 -255.343406)
			(xy 136.523984 -255.495806) (xy 136.785604 -255.495806)
		)
		(stroke
			(width 0)
			(type solid)
		)
		(fill yes)
		(layer "In2.Cu")
		(net "M_F_CPU1_SA_CA<6>")
	)
	(gr_poly
		(pts
			(xy 136.832594 -254.124206) (xy 136.785604 -253.971806) (xy 136.523984 -253.971806) (xy 136.476994 -254.124206)
			(xy 136.476994 -254.168402) (xy 136.832594 -254.168402)
		)
		(stroke
			(width 0)
			(type solid)
		)
		(fill yes)
		(layer "In2.Cu")
		(net "M_F_CPU1_CLK_DN<1>")
	)
	(gr_poly
		(pts
			(xy 136.832848 -271.620742) (xy 136.832848 -271.576546) (xy 136.477248 -271.576546) (xy 136.477248 -271.620742)
			(xy 136.524238 -271.773142) (xy 136.785858 -271.773142)
		)
		(stroke
			(width 0)
			(type solid)
		)
		(fill yes)
		(layer "In2.Cu")
		(net "M_E_CPU1_SA_DQ<12>")
	)
	(gr_poly
		(pts
			(xy 136.837928 -275.284946) (xy 136.790938 -275.132546) (xy 136.529318 -275.132546) (xy 136.482328 -275.284946)
			(xy 136.482328 -275.329396) (xy 136.837928 -275.329396)
		)
		(stroke
			(width 0)
			(type solid)
		)
		(fill yes)
		(layer "In2.Cu")
		(net "M_F_CPU1_SA_DQ<7>")
	)
	(gr_poly
		(pts
			(xy 136.837928 -255.751838) (xy 136.790938 -255.599438) (xy 136.529318 -255.599438) (xy 136.482328 -255.751838)
			(xy 136.482328 -255.796034) (xy 136.837928 -255.796034)
		)
		(stroke
			(width 0)
			(type solid)
		)
		(fill yes)
		(layer "In2.Cu")
		(net "M_F_CPU1_SA_CA<5>")
	)
	(gr_poly
		(pts
			(xy 136.840976 -260.22681) (xy 136.840976 -260.18236) (xy 136.485376 -260.18236) (xy 136.485376 -260.22681)
			(xy 136.532366 -260.37921) (xy 136.793986 -260.37921)
		)
		(stroke
			(width 0)
			(type solid)
		)
		(fill yes)
		(layer "In2.Cu")
		(net "M_F_CPU1_ALERT_N")
	)
	(gr_poly
		(pts
			(xy 136.840976 -259.007102) (xy 136.793986 -258.854702) (xy 136.532366 -258.854702) (xy 136.485376 -259.007102)
			(xy 136.485376 -259.051552) (xy 136.840976 -259.051552)
		)
		(stroke
			(width 0)
			(type solid)
		)
		(fill yes)
		(layer "In2.Cu")
		(net "M_F_CPU1_SA_CS_N<3>")
	)
	(gr_poly
		(pts
			(xy 136.84123 -274.876768) (xy 136.84123 -274.832572) (xy 136.48563 -274.832572) (xy 136.48563 -274.876768)
			(xy 136.53262 -275.029168) (xy 136.79424 -275.029168)
		)
		(stroke
			(width 0)
			(type solid)
		)
		(fill yes)
		(layer "In2.Cu")
		(net "M_E_CPU1_SA_DQ<8>")
	)
	(gr_poly
		(pts
			(xy 136.84123 -272.029174) (xy 136.79424 -271.876774) (xy 136.53262 -271.876774) (xy 136.48563 -272.029174)
			(xy 136.48563 -272.073624) (xy 136.84123 -272.073624)
		)
		(stroke
			(width 0)
			(type solid)
		)
		(fill yes)
		(layer "In2.Cu")
		(net "M_E_CPU1_SA_DQS_DP<6>")
	)
	(gr_poly
		(pts
			(xy 136.84123 -270.401542) (xy 136.79424 -270.249142) (xy 136.53262 -270.249142) (xy 136.48563 -270.401542)
			(xy 136.48563 -270.445992) (xy 136.84123 -270.445992)
		)
		(stroke
			(width 0)
			(type solid)
		)
		(fill yes)
		(layer "In2.Cu")
		(net "M_E_CPU1_SA_DQ<15>")
	)
	(gr_poly
		(pts
			(xy 136.84123 -269.993618) (xy 136.84123 -269.949168) (xy 136.48563 -269.949168) (xy 136.48563 -269.993618)
			(xy 136.53262 -270.146018) (xy 136.79424 -270.146018)
		)
		(stroke
			(width 0)
			(type solid)
		)
		(fill yes)
		(layer "In2.Cu")
		(net "M_F_CPU1_SA_DQ<16>")
	)
	(gr_poly
		(pts
			(xy 136.84123 -265.518392) (xy 136.79424 -265.365992) (xy 136.53262 -265.365992) (xy 136.48563 -265.518392)
			(xy 136.48563 -265.562588) (xy 136.84123 -265.562588)
		)
		(stroke
			(width 0)
			(type solid)
		)
		(fill yes)
		(layer "In2.Cu")
		(net "M_F_CPU1_SA_DQ<23>")
	)
	(gr_poly
		(pts
			(xy 136.84123 -265.110214) (xy 136.84123 -265.065764) (xy 136.48563 -265.065764) (xy 136.48563 -265.110214)
			(xy 136.53262 -265.262614) (xy 136.79424 -265.262614)
		)
		(stroke
			(width 0)
			(type solid)
		)
		(fill yes)
		(layer "In2.Cu")
		(net "M_F_CPU1_SA_CB<0>")
	)
	(gr_poly
		(pts
			(xy 137.048494 -243.571776) (xy 137.086848 -243.549678) (xy 136.909048 -243.24183) (xy 136.870694 -243.263928)
			(xy 136.762236 -243.380768) (xy 136.893046 -243.607336)
		)
		(stroke
			(width 0)
			(type solid)
		)
		(fill yes)
		(layer "In2.Cu")
		(net "M_F_CPU1_SB_CB<4>")
	)
	(gr_poly
		(pts
			(xy 137.049256 -240.318036) (xy 137.08761 -240.295938) (xy 136.90981 -239.98809) (xy 136.871456 -240.010188)
			(xy 136.762998 -240.127028) (xy 136.893808 -240.353596)
		)
		(stroke
			(width 0)
			(type solid)
		)
		(fill yes)
		(layer "In2.Cu")
		(net "M_F_CPU1_SB_DQS_DN<4>")
	)
	(gr_poly
		(pts
			(xy 137.086848 -229.645972) (xy 137.048494 -229.623874) (xy 136.893046 -229.588314) (xy 136.762236 -229.814882)
			(xy 136.870694 -229.931722) (xy 136.909048 -229.95382)
		)
		(stroke
			(width 0)
			(type solid)
		)
		(fill yes)
		(layer "In2.Cu")
		(net "M_F_CPU1_SB_DQS_DN<1>")
	)
	(gr_poly
		(pts
			(xy 137.157206 -242.949984) (xy 137.265664 -242.833144) (xy 137.134854 -242.606576) (xy 136.979406 -242.642136)
			(xy 136.941052 -242.664234) (xy 137.118852 -242.972082)
		)
		(stroke
			(width 0)
			(type solid)
		)
		(fill yes)
		(layer "In2.Cu")
		(net "M_F_CPU1_SB_CB<6>")
	)
	(gr_poly
		(pts
			(xy 137.157968 -239.695736) (xy 137.266426 -239.578896) (xy 137.135616 -239.352328) (xy 136.980168 -239.387888)
			(xy 136.941814 -239.409986) (xy 137.119614 -239.717834)
		)
		(stroke
			(width 0)
			(type solid)
		)
		(fill yes)
		(layer "In2.Cu")
		(net "M_F_CPU1_SB_DQS_DP<4>")
	)
	(gr_poly
		(pts
			(xy 137.158222 -276.357588) (xy 137.196576 -276.33549) (xy 137.018776 -276.027642) (xy 136.980422 -276.04974)
			(xy 136.871964 -276.16658) (xy 137.002774 -276.393148)
		)
		(stroke
			(width 0)
			(type solid)
		)
		(fill yes)
		(layer "In2.Cu")
		(net "M_F_CPU1_SA_DQ<5>")
	)
	(gr_poly
		(pts
			(xy 137.18413 -236.801914) (xy 137.13714 -236.649514) (xy 136.87552 -236.649514) (xy 136.82853 -236.801914)
			(xy 136.82853 -236.84611) (xy 137.18413 -236.84611)
		)
		(stroke
			(width 0)
			(type solid)
		)
		(fill yes)
		(layer "In2.Cu")
		(net "M_E_CPU1_SB_DQ<2>")
	)
	(gr_poly
		(pts
			(xy 137.18413 -236.39399) (xy 137.18413 -236.34954) (xy 136.82853 -236.34954) (xy 136.82853 -236.39399)
			(xy 136.87552 -236.54639) (xy 137.13714 -236.54639)
		)
		(stroke
			(width 0)
			(type solid)
		)
		(fill yes)
		(layer "In2.Cu")
		(net "M_E_CPU1_SB_DQ<1>")
	)
	(gr_poly
		(pts
			(xy 137.18413 -235.174282) (xy 137.13714 -235.021882) (xy 136.87552 -235.021882) (xy 136.82853 -235.174282)
			(xy 136.82853 -235.218478) (xy 137.18413 -235.218478)
		)
		(stroke
			(width 0)
			(type solid)
		)
		(fill yes)
		(layer "In2.Cu")
		(net "M_E_CPU1_SB_DQS_DN<0>")
	)
	(gr_poly
		(pts
			(xy 137.192766 -246.16029) (xy 137.192766 -246.11584) (xy 136.837166 -246.11584) (xy 136.837166 -246.16029)
			(xy 136.884156 -246.31269) (xy 137.145776 -246.31269)
		)
		(stroke
			(width 0)
			(type solid)
		)
		(fill yes)
		(layer "In2.Cu")
		(net "M_F_CPU1_SB_CA<6>")
	)
	(gr_poly
		(pts
			(xy 137.192766 -244.94109) (xy 137.145776 -244.78869) (xy 136.884156 -244.78869) (xy 136.837166 -244.94109)
			(xy 136.837166 -244.985286) (xy 137.192766 -244.985286)
		)
		(stroke
			(width 0)
			(type solid)
		)
		(fill yes)
		(layer "In2.Cu")
		(net "M_F_CPU1_SB_CS_N<0>")
	)
	(gr_poly
		(pts
			(xy 137.192766 -244.53215) (xy 137.192766 -244.487954) (xy 136.837166 -244.487954) (xy 136.837166 -244.53215)
			(xy 136.884156 -244.68455) (xy 137.145776 -244.68455)
		)
		(stroke
			(width 0)
			(type solid)
		)
		(fill yes)
		(layer "In2.Cu")
		(net "M_F_CPU1_SB_CS_N<3>")
	)
	(gr_poly
		(pts
			(xy 137.192766 -241.685318) (xy 137.145776 -241.532918) (xy 136.884156 -241.532918) (xy 136.837166 -241.685318)
			(xy 136.837166 -241.729768) (xy 137.192766 -241.729768)
		)
		(stroke
			(width 0)
			(type solid)
		)
		(fill yes)
		(layer "In2.Cu")
		(net "M_F_CPU1_SB_CB<7>")
	)
	(gr_poly
		(pts
			(xy 137.192766 -241.276886) (xy 137.192766 -241.232436) (xy 136.837166 -241.232436) (xy 136.837166 -241.276886)
			(xy 136.884156 -241.429286) (xy 137.145776 -241.429286)
		)
		(stroke
			(width 0)
			(type solid)
		)
		(fill yes)
		(layer "In2.Cu")
		(net "M_F_CPU1_SB_DQS_DP<9>")
	)
	(gr_poly
		(pts
			(xy 137.192766 -238.430054) (xy 137.145776 -238.277654) (xy 136.884156 -238.277654) (xy 136.837166 -238.430054)
			(xy 136.837166 -238.47425) (xy 137.192766 -238.47425)
		)
		(stroke
			(width 0)
			(type solid)
		)
		(fill yes)
		(layer "In2.Cu")
		(net "M_F_CPU1_SB_CB<2>")
	)
	(gr_poly
		(pts
			(xy 137.192766 -238.021114) (xy 137.192766 -237.976918) (xy 136.837166 -237.976918) (xy 136.837166 -238.021114)
			(xy 136.884156 -238.173514) (xy 137.145776 -238.173514)
		)
		(stroke
			(width 0)
			(type solid)
		)
		(fill yes)
		(layer "In2.Cu")
		(net "M_F_CPU1_SB_CB<1>")
	)
	(gr_poly
		(pts
			(xy 137.192766 -234.765342) (xy 137.192766 -234.720892) (xy 136.837166 -234.720892) (xy 136.837166 -234.765342)
			(xy 136.884156 -234.917742) (xy 137.145776 -234.917742)
		)
		(stroke
			(width 0)
			(type solid)
		)
		(fill yes)
		(layer "In2.Cu")
		(net "M_E_CPU1_SB_DQS_DN<5>")
	)
	(gr_poly
		(pts
			(xy 137.192766 -233.54665) (xy 137.145776 -233.39425) (xy 136.884156 -233.39425) (xy 136.837166 -233.54665)
			(xy 136.837166 -233.590846) (xy 137.192766 -233.590846)
		)
		(stroke
			(width 0)
			(type solid)
		)
		(fill yes)
		(layer "In2.Cu")
		(net "M_E_CPU1_SB_DQ<6>")
	)
	(gr_poly
		(pts
			(xy 137.192766 -233.13771) (xy 137.192766 -233.093514) (xy 136.837166 -233.093514) (xy 136.837166 -233.13771)
			(xy 136.884156 -233.29011) (xy 137.145776 -233.29011)
		)
		(stroke
			(width 0)
			(type solid)
		)
		(fill yes)
		(layer "In2.Cu")
		(net "M_E_CPU1_SB_DQ<5>")
	)
	(gr_poly
		(pts
			(xy 137.192766 -231.919018) (xy 137.145776 -231.766618) (xy 136.884156 -231.766618) (xy 136.837166 -231.919018)
			(xy 136.837166 -231.963214) (xy 137.192766 -231.963214)
		)
		(stroke
			(width 0)
			(type solid)
		)
		(fill yes)
		(layer "In2.Cu")
		(net "M_F_CPU1_SB_DQ<10>")
	)
	(gr_poly
		(pts
			(xy 137.192766 -231.510078) (xy 137.192766 -231.465882) (xy 136.837166 -231.465882) (xy 136.837166 -231.510078)
			(xy 136.884156 -231.662478) (xy 137.145776 -231.662478)
		)
		(stroke
			(width 0)
			(type solid)
		)
		(fill yes)
		(layer "In2.Cu")
		(net "M_F_CPU1_SB_DQ<9>")
	)
	(gr_poly
		(pts
			(xy 137.192766 -228.663246) (xy 137.145776 -228.510846) (xy 136.884156 -228.510846) (xy 136.837166 -228.663246)
			(xy 136.837166 -228.707696) (xy 137.192766 -228.707696)
		)
		(stroke
			(width 0)
			(type solid)
		)
		(fill yes)
		(layer "In2.Cu")
		(net "M_F_CPU1_SB_DQS_DP<6>")
	)
	(gr_poly
		(pts
			(xy 137.192766 -228.254814) (xy 137.192766 -228.210364) (xy 136.837166 -228.210364) (xy 136.837166 -228.254814)
			(xy 136.884156 -228.407214) (xy 137.145776 -228.407214)
		)
		(stroke
			(width 0)
			(type solid)
		)
		(fill yes)
		(layer "In2.Cu")
		(net "M_F_CPU1_SB_DQ<12>")
	)
	(gr_poly
		(pts
			(xy 137.192766 -227.035614) (xy 137.145776 -226.883214) (xy 136.884156 -226.883214) (xy 136.837166 -227.035614)
			(xy 136.837166 -227.07981) (xy 137.192766 -227.07981)
		)
		(stroke
			(width 0)
			(type solid)
		)
		(fill yes)
		(layer "In2.Cu")
		(net "M_F_CPU1_SB_DQ<15>")
	)
	(gr_poly
		(pts
			(xy 137.267696 -230.358442) (xy 137.159238 -230.241602) (xy 137.120884 -230.219504) (xy 136.943084 -230.527352)
			(xy 136.981438 -230.54945) (xy 137.136886 -230.58501)
		)
		(stroke
			(width 0)
			(type solid)
		)
		(fill yes)
		(layer "In2.Cu")
		(net "M_F_CPU1_SB_DQS_DP<1>")
	)
	(gr_poly
		(pts
			(xy 137.268966 -275.73986) (xy 137.377424 -275.62302) (xy 137.246614 -275.396452) (xy 137.091166 -275.432012)
			(xy 137.052812 -275.45411) (xy 137.230612 -275.761958)
		)
		(stroke
			(width 0)
			(type solid)
		)
		(fill yes)
		(layer "In2.Cu")
		(net "M_F_CPU1_SA_DQ<7>")
	)
	(gr_poly
		(pts
			(xy 137.293858 -259.820918) (xy 137.246868 -259.668518) (xy 136.985248 -259.668518) (xy 136.938258 -259.820918)
			(xy 136.938258 -259.865368) (xy 137.293858 -259.865368)
		)
		(stroke
			(width 0)
			(type solid)
		)
		(fill yes)
		(layer "In2.Cu")
		(net "M_F_CPU1_SA_CS_N<0>")
	)
	(gr_poly
		(pts
			(xy 137.293858 -259.412994) (xy 137.293858 -259.368544) (xy 136.938258 -259.368544) (xy 136.938258 -259.412994)
			(xy 136.985248 -259.565394) (xy 137.246868 -259.565394)
		)
		(stroke
			(width 0)
			(type solid)
		)
		(fill yes)
		(layer "In2.Cu")
		(net "M_F_CPU1_SA_CS_N<2>")
	)
	(gr_poly
		(pts
			(xy 137.294112 -274.47113) (xy 137.247122 -274.31873) (xy 136.985502 -274.31873) (xy 136.938512 -274.47113)
			(xy 136.938512 -274.515326) (xy 137.294112 -274.515326)
		)
		(stroke
			(width 0)
			(type solid)
		)
		(fill yes)
		(layer "In2.Cu")
		(net "M_E_CPU1_SA_DQ<10>")
	)
	(gr_poly
		(pts
			(xy 137.294112 -272.435066) (xy 137.294112 -272.39087) (xy 136.938512 -272.39087) (xy 136.938512 -272.435066)
			(xy 136.985502 -272.587466) (xy 137.247122 -272.587466)
		)
		(stroke
			(width 0)
			(type solid)
		)
		(fill yes)
		(layer "In2.Cu")
		(net "M_E_CPU1_SA_DQS_DN<6>")
	)
	(gr_poly
		(pts
			(xy 137.294112 -271.215358) (xy 137.247122 -271.062958) (xy 136.985502 -271.062958) (xy 136.938512 -271.215358)
			(xy 136.938512 -271.259808) (xy 137.294112 -271.259808)
		)
		(stroke
			(width 0)
			(type solid)
		)
		(fill yes)
		(layer "In2.Cu")
		(net "M_E_CPU1_SA_DQ<14>")
	)
	(gr_poly
		(pts
			(xy 137.294112 -270.807434) (xy 137.294112 -270.762984) (xy 136.938512 -270.762984) (xy 136.938512 -270.807434)
			(xy 136.985502 -270.959834) (xy 137.247122 -270.959834)
		)
		(stroke
			(width 0)
			(type solid)
		)
		(fill yes)
		(layer "In2.Cu")
		(net "M_E_CPU1_SA_DQ<13>")
	)
	(gr_poly
		(pts
			(xy 137.294112 -269.587726) (xy 137.247122 -269.435326) (xy 136.985502 -269.435326) (xy 136.938512 -269.587726)
			(xy 136.938512 -269.631922) (xy 137.294112 -269.631922)
		)
		(stroke
			(width 0)
			(type solid)
		)
		(fill yes)
		(layer "In2.Cu")
		(net "M_F_CPU1_SA_DQ<18>")
	)
	(gr_poly
		(pts
			(xy 137.294112 -265.924284) (xy 137.294112 -265.879834) (xy 136.938512 -265.879834) (xy 136.938512 -265.924284)
			(xy 136.985502 -266.076684) (xy 137.247122 -266.076684)
		)
		(stroke
			(width 0)
			(type solid)
		)
		(fill yes)
		(layer "In2.Cu")
		(net "M_F_CPU1_SA_DQ<21>")
	)
	(gr_poly
		(pts
			(xy 137.294112 -264.704322) (xy 137.247122 -264.551922) (xy 136.985502 -264.551922) (xy 136.938512 -264.704322)
			(xy 136.938512 -264.748772) (xy 137.294112 -264.748772)
		)
		(stroke
			(width 0)
			(type solid)
		)
		(fill yes)
		(layer "In2.Cu")
		(net "M_F_CPU1_SA_CB<2>")
	)
	(gr_poly
		(pts
			(xy 137.294112 -256.157222) (xy 137.294112 -256.113026) (xy 136.938512 -256.113026) (xy 136.938512 -256.157222)
			(xy 136.985502 -256.309622) (xy 137.247122 -256.309622)
		)
		(stroke
			(width 0)
			(type solid)
		)
		(fill yes)
		(layer "In2.Cu")
		(net "M_F_CPU1_SA_CA<4>")
	)
	(gr_poly
		(pts
			(xy 137.294112 -254.937514) (xy 137.247122 -254.785114) (xy 136.985502 -254.785114) (xy 136.938512 -254.937514)
			(xy 136.938512 -254.981964) (xy 137.294112 -254.981964)
		)
		(stroke
			(width 0)
			(type solid)
		)
		(fill yes)
		(layer "In2.Cu")
		(net "M_F_CPU1_SA_PAR")
	)
	(gr_poly
		(pts
			(xy 137.30224 -278.945594) (xy 137.30224 -278.901398) (xy 136.94664 -278.901398) (xy 136.94664 -278.945594)
			(xy 136.99363 -279.097994) (xy 137.25525 -279.097994)
		)
		(stroke
			(width 0)
			(type solid)
		)
		(fill yes)
		(layer "In2.Cu")
		(net "M_F_CPU1_SA_DQS_DP<0>")
	)
	(gr_poly
		(pts
			(xy 137.302494 -277.726902) (xy 137.255504 -277.574502) (xy 136.993884 -277.574502) (xy 136.946894 -277.726902)
			(xy 136.946894 -277.771098) (xy 137.302494 -277.771098)
		)
		(stroke
			(width 0)
			(type solid)
		)
		(fill yes)
		(layer "In2.Cu")
		(net "M_F_CPU1_SA_DQS_DP<5>")
	)
	(gr_poly
		(pts
			(xy 137.302494 -277.317962) (xy 137.302494 -277.273766) (xy 136.946894 -277.273766) (xy 136.946894 -277.317962)
			(xy 136.993884 -277.470362) (xy 137.255504 -277.470362)
		)
		(stroke
			(width 0)
			(type solid)
		)
		(fill yes)
		(layer "In2.Cu")
		(net "M_F_CPU1_SA_DQ<4>")
	)
	(gr_poly
		(pts
			(xy 137.302494 -274.062698) (xy 137.302494 -274.018248) (xy 136.946894 -274.018248) (xy 136.946894 -274.062698)
			(xy 136.993884 -274.215098) (xy 137.255504 -274.215098)
		)
		(stroke
			(width 0)
			(type solid)
		)
		(fill yes)
		(layer "In2.Cu")
		(net "M_E_CPU1_SA_DQ<9>")
	)
	(gr_poly
		(pts
			(xy 137.302494 -272.843498) (xy 137.255504 -272.691098) (xy 136.993884 -272.691098) (xy 136.946894 -272.843498)
			(xy 136.946894 -272.887948) (xy 137.302494 -272.887948)
		)
		(stroke
			(width 0)
			(type solid)
		)
		(fill yes)
		(layer "In2.Cu")
		(net "M_E_CPU1_SA_DQS_DN<1>")
	)
	(gr_poly
		(pts
			(xy 137.302494 -269.179294) (xy 137.302494 -269.134844) (xy 136.946894 -269.134844) (xy 136.946894 -269.179294)
			(xy 136.993884 -269.331694) (xy 137.255504 -269.331694)
		)
		(stroke
			(width 0)
			(type solid)
		)
		(fill yes)
		(layer "In2.Cu")
		(net "M_F_CPU1_SA_DQ<17>")
	)
	(gr_poly
		(pts
			(xy 137.302494 -267.960094) (xy 137.255504 -267.807694) (xy 136.993884 -267.807694) (xy 136.946894 -267.960094)
			(xy 136.946894 -268.004544) (xy 137.302494 -268.004544)
		)
		(stroke
			(width 0)
			(type solid)
		)
		(fill yes)
		(layer "In2.Cu")
		(net "M_F_CPU1_SA_DQS_DN<2>")
	)
	(gr_poly
		(pts
			(xy 137.302494 -267.551662) (xy 137.302494 -267.507212) (xy 136.946894 -267.507212) (xy 136.946894 -267.551662)
			(xy 136.993884 -267.704062) (xy 137.255504 -267.704062)
		)
		(stroke
			(width 0)
			(type solid)
		)
		(fill yes)
		(layer "In2.Cu")
		(net "M_F_CPU1_SA_DQS_DN<7>")
	)
	(gr_poly
		(pts
			(xy 137.302494 -266.332462) (xy 137.255504 -266.180062) (xy 136.993884 -266.180062) (xy 136.946894 -266.332462)
			(xy 136.946894 -266.376658) (xy 137.302494 -266.376658)
		)
		(stroke
			(width 0)
			(type solid)
		)
		(fill yes)
		(layer "In2.Cu")
		(net "M_F_CPU1_SA_DQ<22>")
	)
	(gr_poly
		(pts
			(xy 137.302494 -264.29589) (xy 137.302494 -264.251694) (xy 136.946894 -264.251694) (xy 136.946894 -264.29589)
			(xy 136.993884 -264.44829) (xy 137.255504 -264.44829)
		)
		(stroke
			(width 0)
			(type solid)
		)
		(fill yes)
		(layer "In2.Cu")
		(net "M_F_CPU1_SA_CB<1>")
	)
	(gr_poly
		(pts
			(xy 137.302494 -263.077706) (xy 137.255504 -262.925306) (xy 136.993884 -262.925306) (xy 136.946894 -263.077706)
			(xy 136.946894 -263.121902) (xy 137.302494 -263.121902)
		)
		(stroke
			(width 0)
			(type solid)
		)
		(fill yes)
		(layer "In2.Cu")
		(net "M_F_CPU1_SA_DQS_DN<4>")
	)
	(gr_poly
		(pts
			(xy 137.302494 -262.668258) (xy 137.302494 -262.623808) (xy 136.946894 -262.623808) (xy 136.946894 -262.668258)
			(xy 136.993884 -262.820658) (xy 137.255504 -262.820658)
		)
		(stroke
			(width 0)
			(type solid)
		)
		(fill yes)
		(layer "In2.Cu")
		(net "M_F_CPU1_SA_DQS_DN<9>")
	)
	(gr_poly
		(pts
			(xy 137.302494 -261.449058) (xy 137.255504 -261.296658) (xy 136.993884 -261.296658) (xy 136.946894 -261.449058)
			(xy 136.946894 -261.493508) (xy 137.302494 -261.493508)
		)
		(stroke
			(width 0)
			(type solid)
		)
		(fill yes)
		(layer "In2.Cu")
		(net "M_F_CPU1_SA_CB<6>")
	)
	(gr_poly
		(pts
			(xy 137.302494 -261.040626) (xy 137.302494 -260.996176) (xy 136.946894 -260.996176) (xy 136.946894 -261.040626)
			(xy 136.993884 -261.193026) (xy 137.255504 -261.193026)
		)
		(stroke
			(width 0)
			(type solid)
		)
		(fill yes)
		(layer "In2.Cu")
		(net "M_F_CPU1_SA_CB<5>")
	)
	(gr_poly
		(pts
			(xy 137.302494 -254.529082) (xy 137.302494 -254.484886) (xy 136.946894 -254.484886) (xy 136.946894 -254.529082)
			(xy 136.993884 -254.681482) (xy 137.255504 -254.681482)
		)
		(stroke
			(width 0)
			(type solid)
		)
		(fill yes)
		(layer "In2.Cu")
		(net "M_F_CPU1_CLK_DP<1>")
	)
	(gr_poly
		(pts
			(xy 137.31113 -279.354534) (xy 137.26414 -279.202134) (xy 137.00252 -279.202134) (xy 136.95553 -279.354534)
			(xy 136.95553 -279.39873) (xy 137.31113 -279.39873)
		)
		(stroke
			(width 0)
			(type solid)
		)
		(fill yes)
		(layer "In2.Cu")
		(net "M_F_CPU1_SA_DQ<1>")
	)
	(gr_poly
		(pts
			(xy 137.31113 -258.193286) (xy 137.26414 -258.040886) (xy 137.00252 -258.040886) (xy 136.95553 -258.193286)
			(xy 136.95553 -258.237482) (xy 137.31113 -258.237482)
		)
		(stroke
			(width 0)
			(type solid)
		)
		(fill yes)
		(layer "In2.Cu")
		(net "M_F_CPU1_SA_CA<0>")
	)
	(gr_poly
		(pts
			(xy 137.31113 -257.784854) (xy 137.31113 -257.740658) (xy 136.95553 -257.740658) (xy 136.95553 -257.784854)
			(xy 137.00252 -257.937254) (xy 137.26414 -257.937254)
		)
		(stroke
			(width 0)
			(type solid)
		)
		(fill yes)
		(layer "In2.Cu")
		(net "M_F_CPU1_SA_CA<1>")
	)
	(gr_poly
		(pts
			(xy 137.51941 -239.504728) (xy 137.557764 -239.48263) (xy 137.379964 -239.174782) (xy 137.34161 -239.19688)
			(xy 137.233152 -239.31372) (xy 137.363962 -239.540288)
		)
		(stroke
			(width 0)
			(type solid)
		)
		(fill yes)
		(layer "In2.Cu")
		(net "M_F_CPU1_SB_CB<0>")
	)
	(gr_poly
		(pts
			(xy 137.520426 -242.76177) (xy 137.55878 -242.739672) (xy 137.38098 -242.431824) (xy 137.342626 -242.453922)
			(xy 137.234168 -242.570762) (xy 137.364978 -242.79733)
		)
		(stroke
			(width 0)
			(type solid)
		)
		(fill yes)
		(layer "In2.Cu")
		(net "M_F_CPU1_SB_CB<5>")
	)
	(gr_poly
		(pts
			(xy 137.556748 -230.459788) (xy 137.518394 -230.43769) (xy 137.362946 -230.40213) (xy 137.232136 -230.628698)
			(xy 137.340594 -230.745538) (xy 137.378948 -230.767636)
		)
		(stroke
			(width 0)
			(type solid)
		)
		(fill yes)
		(layer "In2.Cu")
		(net "M_F_CPU1_SB_DQ<11>")
	)
	(gr_poly
		(pts
			(xy 137.629138 -238.88446) (xy 137.737596 -238.76762) (xy 137.606786 -238.541052) (xy 137.451338 -238.576612)
			(xy 137.412984 -238.59871) (xy 137.590784 -238.906558)
		)
		(stroke
			(width 0)
			(type solid)
		)
		(fill yes)
		(layer "In2.Cu")
		(net "M_F_CPU1_SB_CB<2>")
	)
	(gr_poly
		(pts
			(xy 137.631678 -242.144042) (xy 137.740136 -242.027202) (xy 137.609326 -241.800634) (xy 137.453878 -241.836194)
			(xy 137.415524 -241.858292) (xy 137.593324 -242.16614)
		)
		(stroke
			(width 0)
			(type solid)
		)
		(fill yes)
		(layer "In2.Cu")
		(net "M_F_CPU1_SB_CB<7>")
	)
	(gr_poly
		(pts
			(xy 137.662666 -245.754906) (xy 137.615676 -245.602506) (xy 137.354056 -245.602506) (xy 137.307066 -245.754906)
			(xy 137.307066 -245.799356) (xy 137.662666 -245.799356)
		)
		(stroke
			(width 0)
			(type solid)
		)
		(fill yes)
		(layer "In2.Cu")
		(net "M_F_CPU1_SB_PAR")
	)
	(gr_poly
		(pts
			(xy 137.662666 -245.346474) (xy 137.662666 -245.302024) (xy 137.307066 -245.302024) (xy 137.307066 -245.346474)
			(xy 137.354056 -245.498874) (xy 137.615676 -245.498874)
		)
		(stroke
			(width 0)
			(type solid)
		)
		(fill yes)
		(layer "In2.Cu")
		(net "M_F_CPU1_SB_CS_N<2>")
	)
	(gr_poly
		(pts
			(xy 137.662666 -244.127274) (xy 137.615676 -243.974874) (xy 137.354056 -243.974874) (xy 137.307066 -244.127274)
			(xy 137.307066 -244.17147) (xy 137.662666 -244.17147)
		)
		(stroke
			(width 0)
			(type solid)
		)
		(fill yes)
		(layer "In2.Cu")
		(net "M_F_CPU1_SB_CS_N<1>")
	)
	(gr_poly
		(pts
			(xy 137.662666 -243.718334) (xy 137.662666 -243.674138) (xy 137.307066 -243.674138) (xy 137.307066 -243.718334)
			(xy 137.354056 -243.870734) (xy 137.615676 -243.870734)
		)
		(stroke
			(width 0)
			(type solid)
		)
		(fill yes)
		(layer "In2.Cu")
		(net "M_F_CPU1_SB_CB<4>")
	)
	(gr_poly
		(pts
			(xy 137.662666 -240.871502) (xy 137.615676 -240.719102) (xy 137.354056 -240.719102) (xy 137.307066 -240.871502)
			(xy 137.307066 -240.915952) (xy 137.662666 -240.915952)
		)
		(stroke
			(width 0)
			(type solid)
		)
		(fill yes)
		(layer "In2.Cu")
		(net "M_F_CPU1_SB_DQS_DN<9>")
	)
	(gr_poly
		(pts
			(xy 137.662666 -237.61573) (xy 137.615676 -237.46333) (xy 137.354056 -237.46333) (xy 137.307066 -237.61573)
			(xy 137.307066 -237.66018) (xy 137.662666 -237.66018)
		)
		(stroke
			(width 0)
			(type solid)
		)
		(fill yes)
		(layer "In2.Cu")
		(net "M_F_CPU1_SB_CB<3>")
	)
	(gr_poly
		(pts
			(xy 137.662666 -233.952034) (xy 137.662666 -233.907584) (xy 137.307066 -233.907584) (xy 137.307066 -233.952034)
			(xy 137.354056 -234.104434) (xy 137.615676 -234.104434)
		)
		(stroke
			(width 0)
			(type solid)
		)
		(fill yes)
		(layer "In2.Cu")
		(net "M_E_CPU1_SB_DQ<4>")
	)
	(gr_poly
		(pts
			(xy 137.662666 -232.732834) (xy 137.615676 -232.580434) (xy 137.354056 -232.580434) (xy 137.307066 -232.732834)
			(xy 137.307066 -232.77703) (xy 137.662666 -232.77703)
		)
		(stroke
			(width 0)
			(type solid)
		)
		(fill yes)
		(layer "In2.Cu")
		(net "M_E_CPU1_SB_DQ<7>")
	)
	(gr_poly
		(pts
			(xy 137.662666 -232.323894) (xy 137.662666 -232.279698) (xy 137.307066 -232.279698) (xy 137.307066 -232.323894)
			(xy 137.354056 -232.476294) (xy 137.615676 -232.476294)
		)
		(stroke
			(width 0)
			(type solid)
		)
		(fill yes)
		(layer "In2.Cu")
		(net "M_F_CPU1_SB_DQ<8>")
	)
	(gr_poly
		(pts
			(xy 137.662666 -229.477062) (xy 137.615676 -229.324662) (xy 137.354056 -229.324662) (xy 137.307066 -229.477062)
			(xy 137.307066 -229.521512) (xy 137.662666 -229.521512)
		)
		(stroke
			(width 0)
			(type solid)
		)
		(fill yes)
		(layer "In2.Cu")
		(net "M_F_CPU1_SB_DQS_DN<1>")
	)
	(gr_poly
		(pts
			(xy 137.662666 -229.06863) (xy 137.662666 -229.02418) (xy 137.307066 -229.02418) (xy 137.307066 -229.06863)
			(xy 137.354056 -229.22103) (xy 137.615676 -229.22103)
		)
		(stroke
			(width 0)
			(type solid)
		)
		(fill yes)
		(layer "In2.Cu")
		(net "M_F_CPU1_SB_DQS_DN<6>")
	)
	(gr_poly
		(pts
			(xy 137.662666 -227.84943) (xy 137.615676 -227.69703) (xy 137.354056 -227.69703) (xy 137.307066 -227.84943)
			(xy 137.307066 -227.893626) (xy 137.662666 -227.893626)
		)
		(stroke
			(width 0)
			(type solid)
		)
		(fill yes)
		(layer "In2.Cu")
		(net "M_F_CPU1_SB_DQ<14>")
	)
	(gr_poly
		(pts
			(xy 137.662666 -227.44049) (xy 137.662666 -227.396294) (xy 137.307066 -227.396294) (xy 137.307066 -227.44049)
			(xy 137.354056 -227.59289) (xy 137.615676 -227.59289)
		)
		(stroke
			(width 0)
			(type solid)
		)
		(fill yes)
		(layer "In2.Cu")
		(net "M_F_CPU1_SB_DQ<13>")
	)
	(gr_poly
		(pts
			(xy 137.671048 -240.46307) (xy 137.671048 -240.418874) (xy 137.315448 -240.418874) (xy 137.315448 -240.46307)
			(xy 137.362438 -240.61547) (xy 137.624058 -240.61547)
		)
		(stroke
			(width 0)
			(type solid)
		)
		(fill yes)
		(layer "In2.Cu")
		(net "M_F_CPU1_SB_DQS_DN<4>")
	)
	(gr_poly
		(pts
			(xy 137.671048 -237.207806) (xy 137.671048 -237.163356) (xy 137.315448 -237.163356) (xy 137.315448 -237.207806)
			(xy 137.362438 -237.360206) (xy 137.624058 -237.360206)
		)
		(stroke
			(width 0)
			(type solid)
		)
		(fill yes)
		(layer "In2.Cu")
		(net "M_E_CPU1_SB_DQ<0>")
	)
	(gr_poly
		(pts
			(xy 137.671048 -235.988098) (xy 137.624058 -235.835698) (xy 137.362438 -235.835698) (xy 137.315448 -235.988098)
			(xy 137.315448 -236.032294) (xy 137.671048 -236.032294)
		)
		(stroke
			(width 0)
			(type solid)
		)
		(fill yes)
		(layer "In2.Cu")
		(net "M_E_CPU1_SB_DQ<3>")
	)
	(gr_poly
		(pts
			(xy 137.671048 -235.579666) (xy 137.671048 -235.53547) (xy 137.315448 -235.53547) (xy 137.315448 -235.579666)
			(xy 137.362438 -235.732066) (xy 137.624058 -235.732066)
		)
		(stroke
			(width 0)
			(type solid)
		)
		(fill yes)
		(layer "In2.Cu")
		(net "M_E_CPU1_SB_DQS_DP<0>")
	)
	(gr_poly
		(pts
			(xy 137.735564 -231.176322) (xy 137.627106 -231.059482) (xy 137.588752 -231.037384) (xy 137.410952 -231.345232)
			(xy 137.449306 -231.36733) (xy 137.604754 -231.40289)
		)
		(stroke
			(width 0)
			(type solid)
		)
		(fill yes)
		(layer "In2.Cu")
		(net "M_F_CPU1_SB_DQ<9>")
	)
	(gr_poly
		(pts
			(xy 137.764012 -279.759918) (xy 137.764012 -279.715722) (xy 137.408412 -279.715722) (xy 137.408412 -279.759918)
			(xy 137.455402 -279.912318) (xy 137.717022 -279.912318)
		)
		(stroke
			(width 0)
			(type solid)
		)
		(fill yes)
		(layer "In2.Cu")
		(net "M_F_CPU1_SA_DQ<3>")
	)
	(gr_poly
		(pts
			(xy 137.764012 -278.540718) (xy 137.717022 -278.388318) (xy 137.455402 -278.388318) (xy 137.408412 -278.540718)
			(xy 137.408412 -278.584914) (xy 137.764012 -278.584914)
		)
		(stroke
			(width 0)
			(type solid)
		)
		(fill yes)
		(layer "In2.Cu")
		(net "M_F_CPU1_SA_DQS_DN<0>")
	)
	(gr_poly
		(pts
			(xy 137.764012 -258.599178) (xy 137.764012 -258.554728) (xy 137.408412 -258.554728) (xy 137.408412 -258.599178)
			(xy 137.455402 -258.751578) (xy 137.717022 -258.751578)
		)
		(stroke
			(width 0)
			(type solid)
		)
		(fill yes)
		(layer "In2.Cu")
		(net "M_F_CPU1_SA_CS_N<1>")
	)
	(gr_poly
		(pts
			(xy 137.764012 -257.37947) (xy 137.717022 -257.22707) (xy 137.455402 -257.22707) (xy 137.408412 -257.37947)
			(xy 137.408412 -257.423666) (xy 137.764012 -257.423666)
		)
		(stroke
			(width 0)
			(type solid)
		)
		(fill yes)
		(layer "In2.Cu")
		(net "M_F_CPU1_SA_CA<2>")
	)
	(gr_poly
		(pts
			(xy 137.772394 -278.132032) (xy 137.772394 -278.087836) (xy 137.416794 -278.087836) (xy 137.416794 -278.132032)
			(xy 137.463784 -278.284432) (xy 137.725404 -278.284432)
		)
		(stroke
			(width 0)
			(type solid)
		)
		(fill yes)
		(layer "In2.Cu")
		(net "M_F_CPU1_SA_DQS_DN<5>")
	)
	(gr_poly
		(pts
			(xy 137.772394 -276.913086) (xy 137.725404 -276.760686) (xy 137.463784 -276.760686) (xy 137.416794 -276.913086)
			(xy 137.416794 -276.957282) (xy 137.772394 -276.957282)
		)
		(stroke
			(width 0)
			(type solid)
		)
		(fill yes)
		(layer "In2.Cu")
		(net "M_F_CPU1_SA_DQ<6>")
	)
	(gr_poly
		(pts
			(xy 137.772394 -276.504146) (xy 137.772394 -276.45995) (xy 137.416794 -276.45995) (xy 137.416794 -276.504146)
			(xy 137.463784 -276.656546) (xy 137.725404 -276.656546)
		)
		(stroke
			(width 0)
			(type solid)
		)
		(fill yes)
		(layer "In2.Cu")
		(net "M_F_CPU1_SA_DQ<5>")
	)
	(gr_poly
		(pts
			(xy 137.772394 -273.657314) (xy 137.725404 -273.504914) (xy 137.463784 -273.504914) (xy 137.416794 -273.657314)
			(xy 137.416794 -273.701764) (xy 137.772394 -273.701764)
		)
		(stroke
			(width 0)
			(type solid)
		)
		(fill yes)
		(layer "In2.Cu")
		(net "M_E_CPU1_SA_DQ<11>")
	)
	(gr_poly
		(pts
			(xy 137.772394 -273.248882) (xy 137.772394 -273.204432) (xy 137.416794 -273.204432) (xy 137.416794 -273.248882)
			(xy 137.463784 -273.401282) (xy 137.725404 -273.401282)
		)
		(stroke
			(width 0)
			(type solid)
		)
		(fill yes)
		(layer "In2.Cu")
		(net "M_E_CPU1_SA_DQS_DP<1>")
	)
	(gr_poly
		(pts
			(xy 137.772394 -268.77391) (xy 137.725404 -268.62151) (xy 137.463784 -268.62151) (xy 137.416794 -268.77391)
			(xy 137.416794 -268.81836) (xy 137.772394 -268.81836)
		)
		(stroke
			(width 0)
			(type solid)
		)
		(fill yes)
		(layer "In2.Cu")
		(net "M_F_CPU1_SA_DQ<19>")
	)
	(gr_poly
		(pts
			(xy 137.772394 -268.365478) (xy 137.772394 -268.321028) (xy 137.416794 -268.321028) (xy 137.416794 -268.365478)
			(xy 137.463784 -268.517878) (xy 137.725404 -268.517878)
		)
		(stroke
			(width 0)
			(type solid)
		)
		(fill yes)
		(layer "In2.Cu")
		(net "M_F_CPU1_SA_DQS_DP<2>")
	)
	(gr_poly
		(pts
			(xy 137.772394 -267.146278) (xy 137.725404 -266.993878) (xy 137.463784 -266.993878) (xy 137.416794 -267.146278)
			(xy 137.416794 -267.190474) (xy 137.772394 -267.190474)
		)
		(stroke
			(width 0)
			(type solid)
		)
		(fill yes)
		(layer "In2.Cu")
		(net "M_F_CPU1_SA_DQS_DP<7>")
	)
	(gr_poly
		(pts
			(xy 137.772394 -266.737846) (xy 137.772394 -266.693396) (xy 137.416794 -266.693396) (xy 137.416794 -266.737846)
			(xy 137.463784 -266.890246) (xy 137.725404 -266.890246)
		)
		(stroke
			(width 0)
			(type solid)
		)
		(fill yes)
		(layer "In2.Cu")
		(net "M_F_CPU1_SA_DQ<20>")
	)
	(gr_poly
		(pts
			(xy 137.772394 -263.891014) (xy 137.725404 -263.738614) (xy 137.463784 -263.738614) (xy 137.416794 -263.891014)
			(xy 137.416794 -263.93521) (xy 137.772394 -263.93521)
		)
		(stroke
			(width 0)
			(type solid)
		)
		(fill yes)
		(layer "In2.Cu")
		(net "M_F_CPU1_SA_CB<3>")
	)
	(gr_poly
		(pts
			(xy 137.772394 -263.482074) (xy 137.772394 -263.437878) (xy 137.416794 -263.437878) (xy 137.416794 -263.482074)
			(xy 137.463784 -263.634474) (xy 137.725404 -263.634474)
		)
		(stroke
			(width 0)
			(type solid)
		)
		(fill yes)
		(layer "In2.Cu")
		(net "M_F_CPU1_SA_DQS_DP<4>")
	)
	(gr_poly
		(pts
			(xy 137.772394 -262.262874) (xy 137.725404 -262.110474) (xy 137.463784 -262.110474) (xy 137.416794 -262.262874)
			(xy 137.416794 -262.307324) (xy 137.772394 -262.307324)
		)
		(stroke
			(width 0)
			(type solid)
		)
		(fill yes)
		(layer "In2.Cu")
		(net "M_F_CPU1_SA_DQS_DP<9>")
	)
	(gr_poly
		(pts
			(xy 137.772394 -261.854442) (xy 137.772394 -261.809992) (xy 137.416794 -261.809992) (xy 137.416794 -261.854442)
			(xy 137.463784 -262.006842) (xy 137.725404 -262.006842)
		)
		(stroke
			(width 0)
			(type solid)
		)
		(fill yes)
		(layer "In2.Cu")
		(net "M_F_CPU1_SA_CB<4>")
	)
	(gr_poly
		(pts
			(xy 137.772394 -260.635242) (xy 137.725404 -260.482842) (xy 137.463784 -260.482842) (xy 137.416794 -260.635242)
			(xy 137.416794 -260.679438) (xy 137.772394 -260.679438)
		)
		(stroke
			(width 0)
			(type solid)
		)
		(fill yes)
		(layer "In2.Cu")
		(net "M_F_CPU1_SA_CB<7>")
	)
	(gr_poly
		(pts
			(xy 137.772394 -256.971038) (xy 137.772394 -256.926588) (xy 137.416794 -256.926588) (xy 137.416794 -256.971038)
			(xy 137.463784 -257.123438) (xy 137.725404 -257.123438)
		)
		(stroke
			(width 0)
			(type solid)
		)
		(fill yes)
		(layer "In2.Cu")
		(net "M_F_CPU1_SA_CA<3>")
	)
	(gr_poly
		(pts
			(xy 137.772394 -254.124206) (xy 137.725404 -253.971806) (xy 137.463784 -253.971806) (xy 137.416794 -254.124206)
			(xy 137.416794 -254.168402) (xy 137.772394 -254.168402)
		)
		(stroke
			(width 0)
			(type solid)
		)
		(fill yes)
		(layer "In2.Cu")
		(net "M_F_CPU1_CLK_DN<1>")
	)
	(gr_poly
		(pts
			(xy 137.780776 -260.22681) (xy 137.780776 -260.18236) (xy 137.425176 -260.18236) (xy 137.425176 -260.22681)
			(xy 137.472166 -260.37921) (xy 137.733786 -260.37921)
		)
		(stroke
			(width 0)
			(type solid)
		)
		(fill yes)
		(layer "In2.Cu")
		(net "M_F_CPU1_ALERT_N")
	)
	(gr_poly
		(pts
			(xy 137.780776 -259.007102) (xy 137.733786 -258.854702) (xy 137.472166 -258.854702) (xy 137.425176 -259.007102)
			(xy 137.425176 -259.051552) (xy 137.780776 -259.051552)
		)
		(stroke
			(width 0)
			(type solid)
		)
		(fill yes)
		(layer "In2.Cu")
		(net "M_F_CPU1_SA_CS_N<3>")
	)
	(gr_poly
		(pts
			(xy 137.78103 -274.876768) (xy 137.78103 -274.832572) (xy 137.42543 -274.832572) (xy 137.42543 -274.876768)
			(xy 137.47242 -275.029168) (xy 137.73404 -275.029168)
		)
		(stroke
			(width 0)
			(type solid)
		)
		(fill yes)
		(layer "In2.Cu")
		(net "M_E_CPU1_SA_DQ<8>")
	)
	(gr_poly
		(pts
			(xy 137.78103 -272.029174) (xy 137.73404 -271.876774) (xy 137.47242 -271.876774) (xy 137.42543 -272.029174)
			(xy 137.42543 -272.073624) (xy 137.78103 -272.073624)
		)
		(stroke
			(width 0)
			(type solid)
		)
		(fill yes)
		(layer "In2.Cu")
		(net "M_E_CPU1_SA_DQS_DP<6>")
	)
	(gr_poly
		(pts
			(xy 137.78103 -271.62125) (xy 137.78103 -271.5768) (xy 137.42543 -271.5768) (xy 137.42543 -271.62125)
			(xy 137.47242 -271.77365) (xy 137.73404 -271.77365)
		)
		(stroke
			(width 0)
			(type solid)
		)
		(fill yes)
		(layer "In2.Cu")
		(net "M_E_CPU1_SA_DQ<12>")
	)
	(gr_poly
		(pts
			(xy 137.78103 -270.401542) (xy 137.73404 -270.249142) (xy 137.47242 -270.249142) (xy 137.42543 -270.401542)
			(xy 137.42543 -270.445992) (xy 137.78103 -270.445992)
		)
		(stroke
			(width 0)
			(type solid)
		)
		(fill yes)
		(layer "In2.Cu")
		(net "M_E_CPU1_SA_DQ<15>")
	)
	(gr_poly
		(pts
			(xy 137.78103 -269.993618) (xy 137.78103 -269.949168) (xy 137.42543 -269.949168) (xy 137.42543 -269.993618)
			(xy 137.47242 -270.146018) (xy 137.73404 -270.146018)
		)
		(stroke
			(width 0)
			(type solid)
		)
		(fill yes)
		(layer "In2.Cu")
		(net "M_F_CPU1_SA_DQ<16>")
	)
	(gr_poly
		(pts
			(xy 137.78103 -265.518392) (xy 137.73404 -265.365992) (xy 137.47242 -265.365992) (xy 137.42543 -265.518392)
			(xy 137.42543 -265.562588) (xy 137.78103 -265.562588)
		)
		(stroke
			(width 0)
			(type solid)
		)
		(fill yes)
		(layer "In2.Cu")
		(net "M_F_CPU1_SA_DQ<23>")
	)
	(gr_poly
		(pts
			(xy 137.78103 -265.110214) (xy 137.78103 -265.065764) (xy 137.42543 -265.065764) (xy 137.42543 -265.110214)
			(xy 137.47242 -265.262614) (xy 137.73404 -265.262614)
		)
		(stroke
			(width 0)
			(type solid)
		)
		(fill yes)
		(layer "In2.Cu")
		(net "M_F_CPU1_SA_CB<0>")
	)
	(gr_poly
		(pts
			(xy 137.78103 -255.75133) (xy 137.73404 -255.59893) (xy 137.47242 -255.59893) (xy 137.42543 -255.75133)
			(xy 137.42543 -255.79578) (xy 137.78103 -255.79578)
		)
		(stroke
			(width 0)
			(type solid)
		)
		(fill yes)
		(layer "In2.Cu")
		(net "M_F_CPU1_SA_CA<5>")
	)
	(gr_poly
		(pts
			(xy 137.78103 -255.343406) (xy 137.78103 -255.298956) (xy 137.42543 -255.298956) (xy 137.42543 -255.343406)
			(xy 137.47242 -255.495806) (xy 137.73404 -255.495806)
		)
		(stroke
			(width 0)
			(type solid)
		)
		(fill yes)
		(layer "In2.Cu")
		(net "M_F_CPU1_SA_CA<6>")
	)
	(gr_poly
		(pts
			(xy 137.988294 -238.688372) (xy 138.026648 -238.666274) (xy 137.848848 -238.358426) (xy 137.810494 -238.380524)
			(xy 137.702036 -238.497364) (xy 137.832846 -238.723932)
		)
		(stroke
			(width 0)
			(type solid)
		)
		(fill yes)
		(layer "In2.Cu")
		(net "M_F_CPU1_SB_CB<1>")
	)
	(gr_poly
		(pts
			(xy 138.027664 -219.876624) (xy 137.98931 -219.854526) (xy 137.833862 -219.818966) (xy 137.703052 -220.045534)
			(xy 137.81151 -220.162374) (xy 137.849864 -220.184472)
		)
		(stroke
			(width 0)
			(type solid)
		)
		(fill yes)
		(layer "In2.Cu")
		(net "M_F_CPU1_SB_DQ<21>")
	)
	(gr_poly
		(pts
			(xy 138.02868 -231.269794) (xy 137.990326 -231.247696) (xy 137.834878 -231.212136) (xy 137.704068 -231.438704)
			(xy 137.812526 -231.555544) (xy 137.85088 -231.577642)
		)
		(stroke
			(width 0)
			(type solid)
		)
		(fill yes)
		(layer "In2.Cu")
		(net "M_F_CPU1_SB_DQ<10>")
	)
	(gr_poly
		(pts
			(xy 138.097006 -238.06658) (xy 138.205464 -237.94974) (xy 138.074654 -237.723172) (xy 137.919206 -237.758732)
			(xy 137.880852 -237.78083) (xy 138.058652 -238.088678)
		)
		(stroke
			(width 0)
			(type solid)
		)
		(fill yes)
		(layer "In2.Cu")
		(net "M_F_CPU1_SB_CB<3>")
	)
	(gr_poly
		(pts
			(xy 138.104372 -241.335814) (xy 138.21283 -241.218974) (xy 138.08202 -240.992406) (xy 137.926572 -241.027966)
			(xy 137.888218 -241.050064) (xy 138.066018 -241.357912)
		)
		(stroke
			(width 0)
			(type solid)
		)
		(fill yes)
		(layer "In2.Cu")
		(net "M_F_CPU1_SB_DQS_DN<9>")
	)
	(gr_poly
		(pts
			(xy 138.12393 -240.057178) (xy 138.07694 -239.904778) (xy 137.81532 -239.904778) (xy 137.76833 -240.057178)
			(xy 137.76833 -240.101628) (xy 138.12393 -240.101628)
		)
		(stroke
			(width 0)
			(type solid)
		)
		(fill yes)
		(layer "In2.Cu")
		(net "M_F_CPU1_SB_DQS_DP<4>")
	)
	(gr_poly
		(pts
			(xy 138.12393 -239.649254) (xy 138.12393 -239.604804) (xy 137.76833 -239.604804) (xy 137.76833 -239.649254)
			(xy 137.81532 -239.801654) (xy 138.07694 -239.801654)
		)
		(stroke
			(width 0)
			(type solid)
		)
		(fill yes)
		(layer "In2.Cu")
		(net "M_F_CPU1_SB_CB<0>")
	)
	(gr_poly
		(pts
			(xy 138.12393 -235.174282) (xy 138.07694 -235.021882) (xy 137.81532 -235.021882) (xy 137.76833 -235.174282)
			(xy 137.76833 -235.218478) (xy 138.12393 -235.218478)
		)
		(stroke
			(width 0)
			(type solid)
		)
		(fill yes)
		(layer "In2.Cu")
		(net "M_E_CPU1_SB_DQS_DN<0>")
	)
	(gr_poly
		(pts
			(xy 138.132566 -244.94109) (xy 138.085576 -244.78869) (xy 137.823956 -244.78869) (xy 137.776966 -244.94109)
			(xy 137.776966 -244.985286) (xy 138.132566 -244.985286)
		)
		(stroke
			(width 0)
			(type solid)
		)
		(fill yes)
		(layer "In2.Cu")
		(net "M_F_CPU1_SB_CS_N<0>")
	)
	(gr_poly
		(pts
			(xy 138.132566 -244.53215) (xy 138.132566 -244.487954) (xy 137.776966 -244.487954) (xy 137.776966 -244.53215)
			(xy 137.823956 -244.68455) (xy 138.085576 -244.68455)
		)
		(stroke
			(width 0)
			(type solid)
		)
		(fill yes)
		(layer "In2.Cu")
		(net "M_F_CPU1_SB_CS_N<3>")
	)
	(gr_poly
		(pts
			(xy 138.132566 -243.313458) (xy 138.085576 -243.161058) (xy 137.823956 -243.161058) (xy 137.776966 -243.313458)
			(xy 137.776966 -243.357654) (xy 138.132566 -243.357654)
		)
		(stroke
			(width 0)
			(type solid)
		)
		(fill yes)
		(layer "In2.Cu")
		(net "M_F_CPU1_SB_CB<6>")
	)
	(gr_poly
		(pts
			(xy 138.132566 -242.904518) (xy 138.132566 -242.860322) (xy 137.776966 -242.860322) (xy 137.776966 -242.904518)
			(xy 137.823956 -243.056918) (xy 138.085576 -243.056918)
		)
		(stroke
			(width 0)
			(type solid)
		)
		(fill yes)
		(layer "In2.Cu")
		(net "M_F_CPU1_SB_CB<5>")
	)
	(gr_poly
		(pts
			(xy 138.132566 -233.54665) (xy 138.085576 -233.39425) (xy 137.823956 -233.39425) (xy 137.776966 -233.54665)
			(xy 137.776966 -233.590846) (xy 138.132566 -233.590846)
		)
		(stroke
			(width 0)
			(type solid)
		)
		(fill yes)
		(layer "In2.Cu")
		(net "M_E_CPU1_SB_DQ<6>")
	)
	(gr_poly
		(pts
			(xy 138.132566 -233.13771) (xy 138.132566 -233.093514) (xy 137.776966 -233.093514) (xy 137.776966 -233.13771)
			(xy 137.823956 -233.29011) (xy 138.085576 -233.29011)
		)
		(stroke
			(width 0)
			(type solid)
		)
		(fill yes)
		(layer "In2.Cu")
		(net "M_E_CPU1_SB_DQ<5>")
	)
	(gr_poly
		(pts
			(xy 138.132566 -230.290878) (xy 138.085576 -230.138478) (xy 137.823956 -230.138478) (xy 137.776966 -230.290878)
			(xy 137.776966 -230.335328) (xy 138.132566 -230.335328)
		)
		(stroke
			(width 0)
			(type solid)
		)
		(fill yes)
		(layer "In2.Cu")
		(net "M_F_CPU1_SB_DQ<11>")
	)
	(gr_poly
		(pts
			(xy 138.132566 -229.882446) (xy 138.132566 -229.837996) (xy 137.776966 -229.837996) (xy 137.776966 -229.882446)
			(xy 137.823956 -230.034846) (xy 138.085576 -230.034846)
		)
		(stroke
			(width 0)
			(type solid)
		)
		(fill yes)
		(layer "In2.Cu")
		(net "M_F_CPU1_SB_DQS_DP<1>")
	)
	(gr_poly
		(pts
			(xy 138.132566 -228.663246) (xy 138.085576 -228.510846) (xy 137.823956 -228.510846) (xy 137.776966 -228.663246)
			(xy 137.776966 -228.707696) (xy 138.132566 -228.707696)
		)
		(stroke
			(width 0)
			(type solid)
		)
		(fill yes)
		(layer "In2.Cu")
		(net "M_F_CPU1_SB_DQS_DP<6>")
	)
	(gr_poly
		(pts
			(xy 138.132566 -228.254814) (xy 138.132566 -228.210364) (xy 137.776966 -228.210364) (xy 137.776966 -228.254814)
			(xy 137.823956 -228.407214) (xy 138.085576 -228.407214)
		)
		(stroke
			(width 0)
			(type solid)
		)
		(fill yes)
		(layer "In2.Cu")
		(net "M_F_CPU1_SB_DQ<12>")
	)
	(gr_poly
		(pts
			(xy 138.132566 -227.035614) (xy 138.085576 -226.883214) (xy 137.823956 -226.883214) (xy 137.776966 -227.035614)
			(xy 137.776966 -227.07981) (xy 138.132566 -227.07981)
		)
		(stroke
			(width 0)
			(type solid)
		)
		(fill yes)
		(layer "In2.Cu")
		(net "M_F_CPU1_SB_DQ<15>")
	)
	(gr_poly
		(pts
			(xy 138.132566 -224.999042) (xy 138.132566 -224.954592) (xy 137.776966 -224.954592) (xy 137.776966 -224.999042)
			(xy 137.823956 -225.151442) (xy 138.085576 -225.151442)
		)
		(stroke
			(width 0)
			(type solid)
		)
		(fill yes)
		(layer "In2.Cu")
		(net "M_F_CPU1_SB_DQ<16>")
	)
	(gr_poly
		(pts
			(xy 138.132566 -223.37141) (xy 138.132566 -223.32696) (xy 137.776966 -223.32696) (xy 137.776966 -223.37141)
			(xy 137.823956 -223.52381) (xy 138.085576 -223.52381)
		)
		(stroke
			(width 0)
			(type solid)
		)
		(fill yes)
		(layer "In2.Cu")
		(net "M_F_CPU1_SB_DQS_DP<2>")
	)
	(gr_poly
		(pts
			(xy 138.205464 -220.595698) (xy 138.097006 -220.478858) (xy 138.058652 -220.45676) (xy 137.880852 -220.764608)
			(xy 137.919206 -220.786706) (xy 138.074654 -220.822266)
		)
		(stroke
			(width 0)
			(type solid)
		)
		(fill yes)
		(layer "In2.Cu")
		(net "M_F_CPU1_SB_DQ<23>")
	)
	(gr_poly
		(pts
			(xy 138.207496 -231.986328) (xy 138.099038 -231.869488) (xy 138.060684 -231.84739) (xy 137.882884 -232.155238)
			(xy 137.921238 -232.177336) (xy 138.076686 -232.212896)
		)
		(stroke
			(width 0)
			(type solid)
		)
		(fill yes)
		(layer "In2.Cu")
		(net "M_F_CPU1_SB_DQ<8>")
	)
	(gr_poly
		(pts
			(xy 138.233658 -259.820918) (xy 138.186668 -259.668518) (xy 137.925048 -259.668518) (xy 137.878058 -259.820918)
			(xy 137.878058 -259.865368) (xy 138.233658 -259.865368)
		)
		(stroke
			(width 0)
			(type solid)
		)
		(fill yes)
		(layer "In2.Cu")
		(net "M_F_CPU1_SA_CS_N<0>")
	)
	(gr_poly
		(pts
			(xy 138.233658 -259.412994) (xy 138.233658 -259.368544) (xy 137.878058 -259.368544) (xy 137.878058 -259.412994)
			(xy 137.925048 -259.565394) (xy 138.186668 -259.565394)
		)
		(stroke
			(width 0)
			(type solid)
		)
		(fill yes)
		(layer "In2.Cu")
		(net "M_F_CPU1_SA_CS_N<2>")
	)
	(gr_poly
		(pts
			(xy 138.233912 -274.47113) (xy 138.186922 -274.31873) (xy 137.925302 -274.31873) (xy 137.878312 -274.47113)
			(xy 137.878312 -274.515326) (xy 138.233912 -274.515326)
		)
		(stroke
			(width 0)
			(type solid)
		)
		(fill yes)
		(layer "In2.Cu")
		(net "M_E_CPU1_SA_DQ<10>")
	)
	(gr_poly
		(pts
			(xy 138.233912 -272.435066) (xy 138.233912 -272.39087) (xy 137.878312 -272.39087) (xy 137.878312 -272.435066)
			(xy 137.925302 -272.587466) (xy 138.186922 -272.587466)
		)
		(stroke
			(width 0)
			(type solid)
		)
		(fill yes)
		(layer "In2.Cu")
		(net "M_E_CPU1_SA_DQS_DN<6>")
	)
	(gr_poly
		(pts
			(xy 138.233912 -271.215358) (xy 138.186922 -271.062958) (xy 137.925302 -271.062958) (xy 137.878312 -271.215358)
			(xy 137.878312 -271.259808) (xy 138.233912 -271.259808)
		)
		(stroke
			(width 0)
			(type solid)
		)
		(fill yes)
		(layer "In2.Cu")
		(net "M_E_CPU1_SA_DQ<14>")
	)
	(gr_poly
		(pts
			(xy 138.233912 -270.807434) (xy 138.233912 -270.762984) (xy 137.878312 -270.762984) (xy 137.878312 -270.807434)
			(xy 137.925302 -270.959834) (xy 138.186922 -270.959834)
		)
		(stroke
			(width 0)
			(type solid)
		)
		(fill yes)
		(layer "In2.Cu")
		(net "M_E_CPU1_SA_DQ<13>")
	)
	(gr_poly
		(pts
			(xy 138.233912 -269.587726) (xy 138.186922 -269.435326) (xy 137.925302 -269.435326) (xy 137.878312 -269.587726)
			(xy 137.878312 -269.631922) (xy 138.233912 -269.631922)
		)
		(stroke
			(width 0)
			(type solid)
		)
		(fill yes)
		(layer "In2.Cu")
		(net "M_F_CPU1_SA_DQ<18>")
	)
	(gr_poly
		(pts
			(xy 138.233912 -265.924284) (xy 138.233912 -265.879834) (xy 137.878312 -265.879834) (xy 137.878312 -265.924284)
			(xy 137.925302 -266.076684) (xy 138.186922 -266.076684)
		)
		(stroke
			(width 0)
			(type solid)
		)
		(fill yes)
		(layer "In2.Cu")
		(net "M_F_CPU1_SA_DQ<21>")
	)
	(gr_poly
		(pts
			(xy 138.233912 -264.704322) (xy 138.186922 -264.551922) (xy 137.925302 -264.551922) (xy 137.878312 -264.704322)
			(xy 137.878312 -264.748772) (xy 138.233912 -264.748772)
		)
		(stroke
			(width 0)
			(type solid)
		)
		(fill yes)
		(layer "In2.Cu")
		(net "M_F_CPU1_SA_CB<2>")
	)
	(gr_poly
		(pts
			(xy 138.233912 -256.157222) (xy 138.233912 -256.113026) (xy 137.878312 -256.113026) (xy 137.878312 -256.157222)
			(xy 137.925302 -256.309622) (xy 138.186922 -256.309622)
		)
		(stroke
			(width 0)
			(type solid)
		)
		(fill yes)
		(layer "In2.Cu")
		(net "M_F_CPU1_SA_CA<4>")
	)
	(gr_poly
		(pts
			(xy 138.24204 -278.945594) (xy 138.24204 -278.901398) (xy 137.88644 -278.901398) (xy 137.88644 -278.945594)
			(xy 137.93343 -279.097994) (xy 138.19505 -279.097994)
		)
		(stroke
			(width 0)
			(type solid)
		)
		(fill yes)
		(layer "In2.Cu")
		(net "M_F_CPU1_SA_DQS_DP<0>")
	)
	(gr_poly
		(pts
			(xy 138.24204 -254.52959) (xy 138.24204 -254.48514) (xy 137.88644 -254.48514) (xy 137.88644 -254.52959)
			(xy 137.93343 -254.68199) (xy 138.19505 -254.68199)
		)
		(stroke
			(width 0)
			(type solid)
		)
		(fill yes)
		(layer "In2.Cu")
		(net "M_F_CPU1_CLK_DP<1>")
	)
	(gr_poly
		(pts
			(xy 138.242294 -277.726902) (xy 138.195304 -277.574502) (xy 137.933684 -277.574502) (xy 137.886694 -277.726902)
			(xy 137.886694 -277.771098) (xy 138.242294 -277.771098)
		)
		(stroke
			(width 0)
			(type solid)
		)
		(fill yes)
		(layer "In2.Cu")
		(net "M_F_CPU1_SA_DQS_DP<5>")
	)
	(gr_poly
		(pts
			(xy 138.242294 -277.317962) (xy 138.242294 -277.273766) (xy 137.886694 -277.273766) (xy 137.886694 -277.317962)
			(xy 137.933684 -277.470362) (xy 138.195304 -277.470362)
		)
		(stroke
			(width 0)
			(type solid)
		)
		(fill yes)
		(layer "In2.Cu")
		(net "M_F_CPU1_SA_DQ<4>")
	)
	(gr_poly
		(pts
			(xy 138.242294 -276.09927) (xy 138.195304 -275.94687) (xy 137.933684 -275.94687) (xy 137.886694 -276.09927)
			(xy 137.886694 -276.143466) (xy 138.242294 -276.143466)
		)
		(stroke
			(width 0)
			(type solid)
		)
		(fill yes)
		(layer "In2.Cu")
		(net "M_F_CPU1_SA_DQ<7>")
	)
	(gr_poly
		(pts
			(xy 138.242294 -274.062698) (xy 138.242294 -274.018248) (xy 137.886694 -274.018248) (xy 137.886694 -274.062698)
			(xy 137.933684 -274.215098) (xy 138.195304 -274.215098)
		)
		(stroke
			(width 0)
			(type solid)
		)
		(fill yes)
		(layer "In2.Cu")
		(net "M_E_CPU1_SA_DQ<9>")
	)
	(gr_poly
		(pts
			(xy 138.242294 -272.843498) (xy 138.195304 -272.691098) (xy 137.933684 -272.691098) (xy 137.886694 -272.843498)
			(xy 137.886694 -272.887948) (xy 138.242294 -272.887948)
		)
		(stroke
			(width 0)
			(type solid)
		)
		(fill yes)
		(layer "In2.Cu")
		(net "M_E_CPU1_SA_DQS_DN<1>")
	)
	(gr_poly
		(pts
			(xy 138.242294 -269.179294) (xy 138.242294 -269.134844) (xy 137.886694 -269.134844) (xy 137.886694 -269.179294)
			(xy 137.933684 -269.331694) (xy 138.195304 -269.331694)
		)
		(stroke
			(width 0)
			(type solid)
		)
		(fill yes)
		(layer "In2.Cu")
		(net "M_F_CPU1_SA_DQ<17>")
	)
	(gr_poly
		(pts
			(xy 138.242294 -267.960094) (xy 138.195304 -267.807694) (xy 137.933684 -267.807694) (xy 137.886694 -267.960094)
			(xy 137.886694 -268.004544) (xy 138.242294 -268.004544)
		)
		(stroke
			(width 0)
			(type solid)
		)
		(fill yes)
		(layer "In2.Cu")
		(net "M_F_CPU1_SA_DQS_DN<2>")
	)
	(gr_poly
		(pts
			(xy 138.242294 -267.551662) (xy 138.242294 -267.507212) (xy 137.886694 -267.507212) (xy 137.886694 -267.551662)
			(xy 137.933684 -267.704062) (xy 138.195304 -267.704062)
		)
		(stroke
			(width 0)
			(type solid)
		)
		(fill yes)
		(layer "In2.Cu")
		(net "M_F_CPU1_SA_DQS_DN<7>")
	)
	(gr_poly
		(pts
			(xy 138.242294 -266.332462) (xy 138.195304 -266.180062) (xy 137.933684 -266.180062) (xy 137.886694 -266.332462)
			(xy 137.886694 -266.376658) (xy 138.242294 -266.376658)
		)
		(stroke
			(width 0)
			(type solid)
		)
		(fill yes)
		(layer "In2.Cu")
		(net "M_F_CPU1_SA_DQ<22>")
	)
	(gr_poly
		(pts
			(xy 138.242294 -264.29589) (xy 138.242294 -264.251694) (xy 137.886694 -264.251694) (xy 137.886694 -264.29589)
			(xy 137.933684 -264.44829) (xy 138.195304 -264.44829)
		)
		(stroke
			(width 0)
			(type solid)
		)
		(fill yes)
		(layer "In2.Cu")
		(net "M_F_CPU1_SA_CB<1>")
	)
	(gr_poly
		(pts
			(xy 138.242294 -261.449058) (xy 138.195304 -261.296658) (xy 137.933684 -261.296658) (xy 137.886694 -261.449058)
			(xy 137.886694 -261.493508) (xy 138.242294 -261.493508)
		)
		(stroke
			(width 0)
			(type solid)
		)
		(fill yes)
		(layer "In2.Cu")
		(net "M_F_CPU1_SA_CB<6>")
	)
	(gr_poly
		(pts
			(xy 138.242294 -261.040626) (xy 138.242294 -260.996176) (xy 137.886694 -260.996176) (xy 137.886694 -261.040626)
			(xy 137.933684 -261.193026) (xy 138.195304 -261.193026)
		)
		(stroke
			(width 0)
			(type solid)
		)
		(fill yes)
		(layer "In2.Cu")
		(net "M_F_CPU1_SA_CB<5>")
	)
	(gr_poly
		(pts
			(xy 138.242548 -263.077198) (xy 138.195558 -262.924798) (xy 137.933938 -262.924798) (xy 137.886948 -263.077198)
			(xy 137.886948 -263.121648) (xy 138.242548 -263.121648)
		)
		(stroke
			(width 0)
			(type solid)
		)
		(fill yes)
		(layer "In2.Cu")
		(net "M_F_CPU1_SA_DQS_DN<4>")
	)
	(gr_poly
		(pts
			(xy 138.24839 -262.668258) (xy 138.24839 -262.624062) (xy 137.89279 -262.624062) (xy 137.89279 -262.668258)
			(xy 137.93978 -262.820658) (xy 138.2014 -262.820658)
		)
		(stroke
			(width 0)
			(type solid)
		)
		(fill yes)
		(layer "In2.Cu")
		(net "M_F_CPU1_SA_DQS_DN<9>")
	)
	(gr_poly
		(pts
			(xy 138.25093 -258.193286) (xy 138.20394 -258.040886) (xy 137.94232 -258.040886) (xy 137.89533 -258.193286)
			(xy 137.89533 -258.237482) (xy 138.25093 -258.237482)
		)
		(stroke
			(width 0)
			(type solid)
		)
		(fill yes)
		(layer "In2.Cu")
		(net "M_F_CPU1_SA_CA<0>")
	)
	(gr_poly
		(pts
			(xy 138.25093 -257.784854) (xy 138.25093 -257.740658) (xy 137.89533 -257.740658) (xy 137.89533 -257.784854)
			(xy 137.94232 -257.937254) (xy 138.20394 -257.937254)
		)
		(stroke
			(width 0)
			(type solid)
		)
		(fill yes)
		(layer "In2.Cu")
		(net "M_F_CPU1_SA_CA<1>")
	)
	(gr_poly
		(pts
			(xy 138.491976 -219.07246) (xy 138.453622 -219.050362) (xy 138.298174 -219.014802) (xy 138.167364 -219.24137)
			(xy 138.275822 -219.35821) (xy 138.314176 -219.380308)
		)
		(stroke
			(width 0)
			(type solid)
		)
		(fill yes)
		(layer "In2.Cu")
		(net "M_F_CPU1_SB_DQ<21>")
	)
	(gr_poly
		(pts
			(xy 138.602466 -244.127274) (xy 138.555476 -243.974874) (xy 138.293856 -243.974874) (xy 138.246866 -244.127274)
			(xy 138.246866 -244.17147) (xy 138.602466 -244.17147)
		)
		(stroke
			(width 0)
			(type solid)
		)
		(fill yes)
		(layer "In2.Cu")
		(net "M_F_CPU1_SB_CS_N<1>")
	)
	(gr_poly
		(pts
			(xy 138.602466 -243.718334) (xy 138.602466 -243.674138) (xy 138.246866 -243.674138) (xy 138.246866 -243.718334)
			(xy 138.293856 -243.870734) (xy 138.555476 -243.870734)
		)
		(stroke
			(width 0)
			(type solid)
		)
		(fill yes)
		(layer "In2.Cu")
		(net "M_F_CPU1_SB_CB<4>")
	)
	(gr_poly
		(pts
			(xy 138.602466 -238.83493) (xy 138.602466 -238.790734) (xy 138.246866 -238.790734) (xy 138.246866 -238.83493)
			(xy 138.293856 -238.98733) (xy 138.555476 -238.98733)
		)
		(stroke
			(width 0)
			(type solid)
		)
		(fill yes)
		(layer "In2.Cu")
		(net "M_F_CPU1_SB_CB<1>")
	)
	(gr_poly
		(pts
			(xy 138.602466 -231.104694) (xy 138.555476 -230.952294) (xy 138.293856 -230.952294) (xy 138.246866 -231.104694)
			(xy 138.246866 -231.149144) (xy 138.602466 -231.149144)
		)
		(stroke
			(width 0)
			(type solid)
		)
		(fill yes)
		(layer "In2.Cu")
		(net "M_F_CPU1_SB_DQ<10>")
	)
	(gr_poly
		(pts
			(xy 138.602466 -230.696262) (xy 138.602466 -230.651812) (xy 138.246866 -230.651812) (xy 138.246866 -230.696262)
			(xy 138.293856 -230.848662) (xy 138.555476 -230.848662)
		)
		(stroke
			(width 0)
			(type solid)
		)
		(fill yes)
		(layer "In2.Cu")
		(net "M_F_CPU1_SB_DQ<9>")
	)
	(gr_poly
		(pts
			(xy 138.602466 -229.477062) (xy 138.555476 -229.324662) (xy 138.293856 -229.324662) (xy 138.246866 -229.477062)
			(xy 138.246866 -229.521512) (xy 138.602466 -229.521512)
		)
		(stroke
			(width 0)
			(type solid)
		)
		(fill yes)
		(layer "In2.Cu")
		(net "M_F_CPU1_SB_DQS_DN<1>")
	)
	(gr_poly
		(pts
			(xy 138.602466 -229.06863) (xy 138.602466 -229.02418) (xy 138.246866 -229.02418) (xy 138.246866 -229.06863)
			(xy 138.293856 -229.22103) (xy 138.555476 -229.22103)
		)
		(stroke
			(width 0)
			(type solid)
		)
		(fill yes)
		(layer "In2.Cu")
		(net "M_F_CPU1_SB_DQS_DN<6>")
	)
	(gr_poly
		(pts
			(xy 138.602466 -227.84943) (xy 138.555476 -227.69703) (xy 138.293856 -227.69703) (xy 138.246866 -227.84943)
			(xy 138.246866 -227.893626) (xy 138.602466 -227.893626)
		)
		(stroke
			(width 0)
			(type solid)
		)
		(fill yes)
		(layer "In2.Cu")
		(net "M_F_CPU1_SB_DQ<14>")
	)
	(gr_poly
		(pts
			(xy 138.602466 -227.44049) (xy 138.602466 -227.396294) (xy 138.246866 -227.396294) (xy 138.246866 -227.44049)
			(xy 138.293856 -227.59289) (xy 138.555476 -227.59289)
		)
		(stroke
			(width 0)
			(type solid)
		)
		(fill yes)
		(layer "In2.Cu")
		(net "M_F_CPU1_SB_DQ<13>")
	)
	(gr_poly
		(pts
			(xy 138.602466 -222.966026) (xy 138.555476 -222.813626) (xy 138.293856 -222.813626) (xy 138.246866 -222.966026)
			(xy 138.246866 -223.010222) (xy 138.602466 -223.010222)
		)
		(stroke
			(width 0)
			(type solid)
		)
		(fill yes)
		(layer "In2.Cu")
		(net "M_F_CPU1_SB_DQS_DN<2>")
	)
	(gr_poly
		(pts
			(xy 138.610848 -240.46307) (xy 138.610848 -240.418874) (xy 138.255248 -240.418874) (xy 138.255248 -240.46307)
			(xy 138.302238 -240.61547) (xy 138.563858 -240.61547)
		)
		(stroke
			(width 0)
			(type solid)
		)
		(fill yes)
		(layer "In2.Cu")
		(net "M_F_CPU1_SB_DQS_DN<4>")
	)
	(gr_poly
		(pts
			(xy 138.610848 -239.243362) (xy 138.563858 -239.090962) (xy 138.302238 -239.090962) (xy 138.255248 -239.243362)
			(xy 138.255248 -239.287812) (xy 138.610848 -239.287812)
		)
		(stroke
			(width 0)
			(type solid)
		)
		(fill yes)
		(layer "In2.Cu")
		(net "M_F_CPU1_SB_CB<2>")
	)
	(gr_poly
		(pts
			(xy 138.610848 -235.988098) (xy 138.563858 -235.835698) (xy 138.302238 -235.835698) (xy 138.255248 -235.988098)
			(xy 138.255248 -236.032294) (xy 138.610848 -236.032294)
		)
		(stroke
			(width 0)
			(type solid)
		)
		(fill yes)
		(layer "In2.Cu")
		(net "M_E_CPU1_SB_DQ<3>")
	)
	(gr_poly
		(pts
			(xy 138.610848 -235.579666) (xy 138.610848 -235.53547) (xy 138.255248 -235.53547) (xy 138.255248 -235.579666)
			(xy 138.302238 -235.732066) (xy 138.563858 -235.732066)
		)
		(stroke
			(width 0)
			(type solid)
		)
		(fill yes)
		(layer "In2.Cu")
		(net "M_E_CPU1_SB_DQS_DP<0>")
	)
	(gr_poly
		(pts
			(xy 138.676126 -219.780358) (xy 138.567668 -219.663518) (xy 138.529314 -219.64142) (xy 138.351514 -219.949268)
			(xy 138.389868 -219.971366) (xy 138.545316 -220.006926)
		)
		(stroke
			(width 0)
			(type solid)
		)
		(fill yes)
		(layer "In2.Cu")
		(net "M_F_CPU1_SB_DQ<23>")
	)
	(gr_poly
		(pts
			(xy 138.703812 -278.540718) (xy 138.656822 -278.388318) (xy 138.395202 -278.388318) (xy 138.348212 -278.540718)
			(xy 138.348212 -278.585168) (xy 138.703812 -278.585168)
		)
		(stroke
			(width 0)
			(type solid)
		)
		(fill yes)
		(layer "In2.Cu")
		(net "M_F_CPU1_SA_DQS_DN<0>")
	)
	(gr_poly
		(pts
			(xy 138.703812 -263.482582) (xy 138.703812 -263.438132) (xy 138.348212 -263.438132) (xy 138.348212 -263.482582)
			(xy 138.395202 -263.634982) (xy 138.656822 -263.634982)
		)
		(stroke
			(width 0)
			(type solid)
		)
		(fill yes)
		(layer "In2.Cu")
		(net "M_F_CPU1_SA_DQS_DP<4>")
	)
	(gr_poly
		(pts
			(xy 138.703812 -262.262874) (xy 138.656822 -262.110474) (xy 138.395202 -262.110474) (xy 138.348212 -262.262874)
			(xy 138.348212 -262.30707) (xy 138.703812 -262.30707)
		)
		(stroke
			(width 0)
			(type solid)
		)
		(fill yes)
		(layer "In2.Cu")
		(net "M_F_CPU1_SA_DQS_DP<9>")
	)
	(gr_poly
		(pts
			(xy 138.703812 -258.599178) (xy 138.703812 -258.554728) (xy 138.348212 -258.554728) (xy 138.348212 -258.599178)
			(xy 138.395202 -258.751578) (xy 138.656822 -258.751578)
		)
		(stroke
			(width 0)
			(type solid)
		)
		(fill yes)
		(layer "In2.Cu")
		(net "M_F_CPU1_SA_CS_N<1>")
	)
	(gr_poly
		(pts
			(xy 138.703812 -257.37947) (xy 138.656822 -257.22707) (xy 138.395202 -257.22707) (xy 138.348212 -257.37947)
			(xy 138.348212 -257.423666) (xy 138.703812 -257.423666)
		)
		(stroke
			(width 0)
			(type solid)
		)
		(fill yes)
		(layer "In2.Cu")
		(net "M_F_CPU1_SA_CA<2>")
	)
	(gr_poly
		(pts
			(xy 138.71194 -273.248374) (xy 138.71194 -273.204178) (xy 138.35634 -273.204178) (xy 138.35634 -273.248374)
			(xy 138.40333 -273.400774) (xy 138.66495 -273.400774)
		)
		(stroke
			(width 0)
			(type solid)
		)
		(fill yes)
		(layer "In2.Cu")
		(net "M_E_CPU1_SA_DQS_DP<1>")
	)
	(gr_poly
		(pts
			(xy 138.712194 -278.132032) (xy 138.712194 -278.087836) (xy 138.356594 -278.087836) (xy 138.356594 -278.132032)
			(xy 138.403584 -278.284432) (xy 138.665204 -278.284432)
		)
		(stroke
			(width 0)
			(type solid)
		)
		(fill yes)
		(layer "In2.Cu")
		(net "M_F_CPU1_SA_DQS_DN<5>")
	)
	(gr_poly
		(pts
			(xy 138.712194 -276.913086) (xy 138.665204 -276.760686) (xy 138.403584 -276.760686) (xy 138.356594 -276.913086)
			(xy 138.356594 -276.957282) (xy 138.712194 -276.957282)
		)
		(stroke
			(width 0)
			(type solid)
		)
		(fill yes)
		(layer "In2.Cu")
		(net "M_F_CPU1_SA_DQ<6>")
	)
	(gr_poly
		(pts
			(xy 138.712194 -276.504146) (xy 138.712194 -276.45995) (xy 138.356594 -276.45995) (xy 138.356594 -276.504146)
			(xy 138.403584 -276.656546) (xy 138.665204 -276.656546)
		)
		(stroke
			(width 0)
			(type solid)
		)
		(fill yes)
		(layer "In2.Cu")
		(net "M_F_CPU1_SA_DQ<5>")
	)
	(gr_poly
		(pts
			(xy 138.712194 -273.657314) (xy 138.665204 -273.504914) (xy 138.403584 -273.504914) (xy 138.356594 -273.657314)
			(xy 138.356594 -273.701764) (xy 138.712194 -273.701764)
		)
		(stroke
			(width 0)
			(type solid)
		)
		(fill yes)
		(layer "In2.Cu")
		(net "M_E_CPU1_SA_DQ<11>")
	)
	(gr_poly
		(pts
			(xy 138.712194 -268.77391) (xy 138.665204 -268.62151) (xy 138.403584 -268.62151) (xy 138.356594 -268.77391)
			(xy 138.356594 -268.81836) (xy 138.712194 -268.81836)
		)
		(stroke
			(width 0)
			(type solid)
		)
		(fill yes)
		(layer "In2.Cu")
		(net "M_F_CPU1_SA_DQ<19>")
	)
	(gr_poly
		(pts
			(xy 138.712194 -268.365478) (xy 138.712194 -268.321028) (xy 138.356594 -268.321028) (xy 138.356594 -268.365478)
			(xy 138.403584 -268.517878) (xy 138.665204 -268.517878)
		)
		(stroke
			(width 0)
			(type solid)
		)
		(fill yes)
		(layer "In2.Cu")
		(net "M_F_CPU1_SA_DQS_DP<2>")
	)
	(gr_poly
		(pts
			(xy 138.712194 -267.146278) (xy 138.665204 -266.993878) (xy 138.403584 -266.993878) (xy 138.356594 -267.146278)
			(xy 138.356594 -267.190474) (xy 138.712194 -267.190474)
		)
		(stroke
			(width 0)
			(type solid)
		)
		(fill yes)
		(layer "In2.Cu")
		(net "M_F_CPU1_SA_DQS_DP<7>")
	)
	(gr_poly
		(pts
			(xy 138.712194 -266.737846) (xy 138.712194 -266.693396) (xy 138.356594 -266.693396) (xy 138.356594 -266.737846)
			(xy 138.403584 -266.890246) (xy 138.665204 -266.890246)
		)
		(stroke
			(width 0)
			(type solid)
		)
		(fill yes)
		(layer "In2.Cu")
		(net "M_F_CPU1_SA_DQ<20>")
	)
	(gr_poly
		(pts
			(xy 138.712194 -263.891014) (xy 138.665204 -263.738614) (xy 138.403584 -263.738614) (xy 138.356594 -263.891014)
			(xy 138.356594 -263.93521) (xy 138.712194 -263.93521)
		)
		(stroke
			(width 0)
			(type solid)
		)
		(fill yes)
		(layer "In2.Cu")
		(net "M_F_CPU1_SA_CB<3>")
	)
	(gr_poly
		(pts
			(xy 138.712194 -261.854442) (xy 138.712194 -261.809992) (xy 138.356594 -261.809992) (xy 138.356594 -261.854442)
			(xy 138.403584 -262.006842) (xy 138.665204 -262.006842)
		)
		(stroke
			(width 0)
			(type solid)
		)
		(fill yes)
		(layer "In2.Cu")
		(net "M_F_CPU1_SA_CB<4>")
	)
	(gr_poly
		(pts
			(xy 138.712194 -260.635242) (xy 138.665204 -260.482842) (xy 138.403584 -260.482842) (xy 138.356594 -260.635242)
			(xy 138.356594 -260.679438) (xy 138.712194 -260.679438)
		)
		(stroke
			(width 0)
			(type solid)
		)
		(fill yes)
		(layer "In2.Cu")
		(net "M_F_CPU1_SA_CB<7>")
	)
	(gr_poly
		(pts
			(xy 138.712194 -256.971038) (xy 138.712194 -256.926588) (xy 138.356594 -256.926588) (xy 138.356594 -256.971038)
			(xy 138.403584 -257.123438) (xy 138.665204 -257.123438)
		)
		(stroke
			(width 0)
			(type solid)
		)
		(fill yes)
		(layer "In2.Cu")
		(net "M_F_CPU1_SA_CA<3>")
	)
	(gr_poly
		(pts
			(xy 138.712448 -254.124206) (xy 138.665458 -253.971806) (xy 138.403838 -253.971806) (xy 138.356848 -254.124206)
			(xy 138.356848 -254.168402) (xy 138.712448 -254.168402)
		)
		(stroke
			(width 0)
			(type solid)
		)
		(fill yes)
		(layer "In2.Cu")
		(net "M_F_CPU1_CLK_DN<1>")
	)
	(gr_poly
		(pts
			(xy 138.720576 -260.22681) (xy 138.720576 -260.18236) (xy 138.364976 -260.18236) (xy 138.364976 -260.22681)
			(xy 138.411966 -260.37921) (xy 138.673586 -260.37921)
		)
		(stroke
			(width 0)
			(type solid)
		)
		(fill yes)
		(layer "In2.Cu")
		(net "M_F_CPU1_ALERT_N")
	)
	(gr_poly
		(pts
			(xy 138.720576 -259.007102) (xy 138.673586 -258.854702) (xy 138.411966 -258.854702) (xy 138.364976 -259.007102)
			(xy 138.364976 -259.051552) (xy 138.720576 -259.051552)
		)
		(stroke
			(width 0)
			(type solid)
		)
		(fill yes)
		(layer "In2.Cu")
		(net "M_F_CPU1_SA_CS_N<3>")
	)
	(gr_poly
		(pts
			(xy 138.72083 -274.876768) (xy 138.72083 -274.832572) (xy 138.36523 -274.832572) (xy 138.36523 -274.876768)
			(xy 138.41222 -275.029168) (xy 138.67384 -275.029168)
		)
		(stroke
			(width 0)
			(type solid)
		)
		(fill yes)
		(layer "In2.Cu")
		(net "M_E_CPU1_SA_DQ<8>")
	)
	(gr_poly
		(pts
			(xy 138.72083 -272.029174) (xy 138.67384 -271.876774) (xy 138.41222 -271.876774) (xy 138.36523 -272.029174)
			(xy 138.36523 -272.073624) (xy 138.72083 -272.073624)
		)
		(stroke
			(width 0)
			(type solid)
		)
		(fill yes)
		(layer "In2.Cu")
		(net "M_E_CPU1_SA_DQS_DP<6>")
	)
	(gr_poly
		(pts
			(xy 138.72083 -271.62125) (xy 138.72083 -271.5768) (xy 138.36523 -271.5768) (xy 138.36523 -271.62125)
			(xy 138.41222 -271.77365) (xy 138.67384 -271.77365)
		)
		(stroke
			(width 0)
			(type solid)
		)
		(fill yes)
		(layer "In2.Cu")
		(net "M_E_CPU1_SA_DQ<12>")
	)
	(gr_poly
		(pts
			(xy 138.72083 -270.401542) (xy 138.67384 -270.249142) (xy 138.41222 -270.249142) (xy 138.36523 -270.401542)
			(xy 138.36523 -270.445992) (xy 138.72083 -270.445992)
		)
		(stroke
			(width 0)
			(type solid)
		)
		(fill yes)
		(layer "In2.Cu")
		(net "M_E_CPU1_SA_DQ<15>")
	)
	(gr_poly
		(pts
			(xy 138.72083 -269.993618) (xy 138.72083 -269.949168) (xy 138.36523 -269.949168) (xy 138.36523 -269.993618)
			(xy 138.41222 -270.146018) (xy 138.67384 -270.146018)
		)
		(stroke
			(width 0)
			(type solid)
		)
		(fill yes)
		(layer "In2.Cu")
		(net "M_F_CPU1_SA_DQ<16>")
	)
	(gr_poly
		(pts
			(xy 138.72083 -265.518392) (xy 138.67384 -265.365992) (xy 138.41222 -265.365992) (xy 138.36523 -265.518392)
			(xy 138.36523 -265.562588) (xy 138.72083 -265.562588)
		)
		(stroke
			(width 0)
			(type solid)
		)
		(fill yes)
		(layer "In2.Cu")
		(net "M_F_CPU1_SA_DQ<23>")
	)
	(gr_poly
		(pts
			(xy 138.72083 -265.110214) (xy 138.72083 -265.065764) (xy 138.36523 -265.065764) (xy 138.36523 -265.110214)
			(xy 138.41222 -265.262614) (xy 138.67384 -265.262614)
		)
		(stroke
			(width 0)
			(type solid)
		)
		(fill yes)
		(layer "In2.Cu")
		(net "M_F_CPU1_SA_CB<0>")
	)
	(gr_poly
		(pts
			(xy 138.966448 -226.390454) (xy 138.928094 -226.368356) (xy 138.772646 -226.332796) (xy 138.641836 -226.559364)
			(xy 138.750294 -226.676204) (xy 138.788648 -226.698302)
		)
		(stroke
			(width 0)
			(type solid)
		)
		(fill yes)
		(layer "In2.Cu")
		(net "M_F_CPU1_SB_DQ<15>")
	)
	(gr_poly
		(pts
			(xy 139.06373 -240.057178) (xy 139.01674 -239.904778) (xy 138.75512 -239.904778) (xy 138.70813 -240.057178)
			(xy 138.70813 -240.101628) (xy 139.06373 -240.101628)
		)
		(stroke
			(width 0)
			(type solid)
		)
		(fill yes)
		(layer "In2.Cu")
		(net "M_F_CPU1_SB_DQS_DP<4>")
	)
	(gr_poly
		(pts
			(xy 139.06373 -239.649254) (xy 139.06373 -239.604804) (xy 138.70813 -239.604804) (xy 138.70813 -239.649254)
			(xy 138.75512 -239.801654) (xy 139.01674 -239.801654)
		)
		(stroke
			(width 0)
			(type solid)
		)
		(fill yes)
		(layer "In2.Cu")
		(net "M_F_CPU1_SB_CB<0>")
	)
	(gr_poly
		(pts
			(xy 139.072112 -229.882446) (xy 139.072112 -229.83825) (xy 138.716512 -229.83825) (xy 138.716512 -229.882446)
			(xy 138.763502 -230.034846) (xy 139.025122 -230.034846)
		)
		(stroke
			(width 0)
			(type solid)
		)
		(fill yes)
		(layer "In2.Cu")
		(net "M_F_CPU1_SB_DQS_DP<1>")
	)
	(gr_poly
		(pts
			(xy 139.072366 -231.510078) (xy 139.072366 -231.465882) (xy 138.716766 -231.465882) (xy 138.716766 -231.510078)
			(xy 138.763756 -231.662478) (xy 139.025376 -231.662478)
		)
		(stroke
			(width 0)
			(type solid)
		)
		(fill yes)
		(layer "In2.Cu")
		(net "M_F_CPU1_SB_DQ<8>")
	)
	(gr_poly
		(pts
			(xy 139.072366 -230.290878) (xy 139.025376 -230.138478) (xy 138.763756 -230.138478) (xy 138.716766 -230.290878)
			(xy 138.716766 -230.335328) (xy 139.072366 -230.335328)
		)
		(stroke
			(width 0)
			(type solid)
		)
		(fill yes)
		(layer "In2.Cu")
		(net "M_F_CPU1_SB_DQ<11>")
	)
	(gr_poly
		(pts
			(xy 139.072366 -228.663246) (xy 139.025376 -228.510846) (xy 138.763756 -228.510846) (xy 138.716766 -228.663246)
			(xy 138.716766 -228.707696) (xy 139.072366 -228.707696)
		)
		(stroke
			(width 0)
			(type solid)
		)
		(fill yes)
		(layer "In2.Cu")
		(net "M_F_CPU1_SB_DQS_DP<6>")
	)
	(gr_poly
		(pts
			(xy 139.072366 -228.254814) (xy 139.072366 -228.210364) (xy 138.716766 -228.210364) (xy 138.716766 -228.254814)
			(xy 138.763756 -228.407214) (xy 139.025376 -228.407214)
		)
		(stroke
			(width 0)
			(type solid)
		)
		(fill yes)
		(layer "In2.Cu")
		(net "M_F_CPU1_SB_DQ<12>")
	)
	(gr_poly
		(pts
			(xy 139.072366 -224.999042) (xy 139.072366 -224.954592) (xy 138.716766 -224.954592) (xy 138.716766 -224.999042)
			(xy 138.763756 -225.151442) (xy 139.025376 -225.151442)
		)
		(stroke
			(width 0)
			(type solid)
		)
		(fill yes)
		(layer "In2.Cu")
		(net "M_F_CPU1_SB_DQ<16>")
	)
	(gr_poly
		(pts
			(xy 139.080748 -223.37141) (xy 139.080748 -223.327214) (xy 138.725148 -223.327214) (xy 138.725148 -223.37141)
			(xy 138.772138 -223.52381) (xy 139.033758 -223.52381)
		)
		(stroke
			(width 0)
			(type solid)
		)
		(fill yes)
		(layer "In2.Cu")
		(net "M_F_CPU1_SB_DQS_DP<2>")
	)
	(gr_poly
		(pts
			(xy 139.080748 -218.896438) (xy 139.033758 -218.744038) (xy 138.772138 -218.744038) (xy 138.725148 -218.896438)
			(xy 138.725148 -218.940634) (xy 139.080748 -218.940634)
		)
		(stroke
			(width 0)
			(type solid)
		)
		(fill yes)
		(layer "In2.Cu")
		(net "M_F_CPU1_SB_DQ<21>")
	)
	(gr_poly
		(pts
			(xy 139.147296 -227.102924) (xy 139.038838 -226.986084) (xy 139.000484 -226.963986) (xy 138.822684 -227.271834)
			(xy 138.861038 -227.293932) (xy 139.016486 -227.329492)
		)
		(stroke
			(width 0)
			(type solid)
		)
		(fill yes)
		(layer "In2.Cu")
		(net "M_F_CPU1_SB_DQ<13>")
	)
	(gr_poly
		(pts
			(xy 139.173458 -259.820918) (xy 139.126468 -259.668518) (xy 138.864848 -259.668518) (xy 138.817858 -259.820918)
			(xy 138.817858 -259.865368) (xy 139.173458 -259.865368)
		)
		(stroke
			(width 0)
			(type solid)
		)
		(fill yes)
		(layer "In2.Cu")
		(net "M_F_CPU1_SA_CS_N<0>")
	)
	(gr_poly
		(pts
			(xy 139.173458 -259.412994) (xy 139.173458 -259.368544) (xy 138.817858 -259.368544) (xy 138.817858 -259.412994)
			(xy 138.864848 -259.565394) (xy 139.126468 -259.565394)
		)
		(stroke
			(width 0)
			(type solid)
		)
		(fill yes)
		(layer "In2.Cu")
		(net "M_F_CPU1_SA_CS_N<2>")
	)
	(gr_poly
		(pts
			(xy 139.173712 -269.587726) (xy 139.126722 -269.435326) (xy 138.865102 -269.435326) (xy 138.818112 -269.587726)
			(xy 138.818112 -269.631922) (xy 139.173712 -269.631922)
		)
		(stroke
			(width 0)
			(type solid)
		)
		(fill yes)
		(layer "In2.Cu")
		(net "M_F_CPU1_SA_DQ<18>")
	)
	(gr_poly
		(pts
			(xy 139.173712 -265.924284) (xy 139.173712 -265.879834) (xy 138.818112 -265.879834) (xy 138.818112 -265.924284)
			(xy 138.865102 -266.076684) (xy 139.126722 -266.076684)
		)
		(stroke
			(width 0)
			(type solid)
		)
		(fill yes)
		(layer "In2.Cu")
		(net "M_F_CPU1_SA_DQ<21>")
	)
	(gr_poly
		(pts
			(xy 139.173712 -264.704322) (xy 139.126722 -264.551922) (xy 138.865102 -264.551922) (xy 138.818112 -264.704322)
			(xy 138.818112 -264.748772) (xy 139.173712 -264.748772)
		)
		(stroke
			(width 0)
			(type solid)
		)
		(fill yes)
		(layer "In2.Cu")
		(net "M_F_CPU1_SA_CB<2>")
	)
	(gr_poly
		(pts
			(xy 139.18184 -263.077198) (xy 139.13485 -262.924798) (xy 138.87323 -262.924798) (xy 138.82624 -263.077198)
			(xy 138.82624 -263.121648) (xy 139.18184 -263.121648)
		)
		(stroke
			(width 0)
			(type solid)
		)
		(fill yes)
		(layer "In2.Cu")
		(net "M_F_CPU1_SA_DQS_DN<4>")
	)
	(gr_poly
		(pts
			(xy 139.182094 -272.843498) (xy 139.135104 -272.691098) (xy 138.873484 -272.691098) (xy 138.826494 -272.843498)
			(xy 138.826494 -272.887948) (xy 139.182094 -272.887948)
		)
		(stroke
			(width 0)
			(type solid)
		)
		(fill yes)
		(layer "In2.Cu")
		(net "M_E_CPU1_SA_DQS_DN<1>")
	)
	(gr_poly
		(pts
			(xy 139.182094 -269.179294) (xy 139.182094 -269.134844) (xy 138.826494 -269.134844) (xy 138.826494 -269.179294)
			(xy 138.873484 -269.331694) (xy 139.135104 -269.331694)
		)
		(stroke
			(width 0)
			(type solid)
		)
		(fill yes)
		(layer "In2.Cu")
		(net "M_F_CPU1_SA_DQ<17>")
	)
	(gr_poly
		(pts
			(xy 139.182094 -267.960094) (xy 139.135104 -267.807694) (xy 138.873484 -267.807694) (xy 138.826494 -267.960094)
			(xy 138.826494 -268.004544) (xy 139.182094 -268.004544)
		)
		(stroke
			(width 0)
			(type solid)
		)
		(fill yes)
		(layer "In2.Cu")
		(net "M_F_CPU1_SA_DQS_DN<2>")
	)
	(gr_poly
		(pts
			(xy 139.182094 -267.551662) (xy 139.182094 -267.507212) (xy 138.826494 -267.507212) (xy 138.826494 -267.551662)
			(xy 138.873484 -267.704062) (xy 139.135104 -267.704062)
		)
		(stroke
			(width 0)
			(type solid)
		)
		(fill yes)
		(layer "In2.Cu")
		(net "M_F_CPU1_SA_DQS_DN<7>")
	)
	(gr_poly
		(pts
			(xy 139.182094 -266.332462) (xy 139.135104 -266.180062) (xy 138.873484 -266.180062) (xy 138.826494 -266.332462)
			(xy 138.826494 -266.376658) (xy 139.182094 -266.376658)
		)
		(stroke
			(width 0)
			(type solid)
		)
		(fill yes)
		(layer "In2.Cu")
		(net "M_F_CPU1_SA_DQ<22>")
	)
	(gr_poly
		(pts
			(xy 139.182094 -264.29589) (xy 139.182094 -264.251694) (xy 138.826494 -264.251694) (xy 138.826494 -264.29589)
			(xy 138.873484 -264.44829) (xy 139.135104 -264.44829)
		)
		(stroke
			(width 0)
			(type solid)
		)
		(fill yes)
		(layer "In2.Cu")
		(net "M_F_CPU1_SA_CB<1>")
	)
	(gr_poly
		(pts
			(xy 139.182094 -261.449058) (xy 139.135104 -261.296658) (xy 138.873484 -261.296658) (xy 138.826494 -261.449058)
			(xy 138.826494 -261.493508) (xy 139.182094 -261.493508)
		)
		(stroke
			(width 0)
			(type solid)
		)
		(fill yes)
		(layer "In2.Cu")
		(net "M_F_CPU1_SA_CB<6>")
	)
	(gr_poly
		(pts
			(xy 139.182094 -261.040626) (xy 139.182094 -260.996176) (xy 138.826494 -260.996176) (xy 138.826494 -261.040626)
			(xy 138.873484 -261.193026) (xy 139.135104 -261.193026)
		)
		(stroke
			(width 0)
			(type solid)
		)
		(fill yes)
		(layer "In2.Cu")
		(net "M_F_CPU1_SA_CB<5>")
	)
	(gr_poly
		(pts
			(xy 139.19073 -262.668258) (xy 139.19073 -262.624062) (xy 138.83513 -262.624062) (xy 138.83513 -262.668258)
			(xy 138.88212 -262.820658) (xy 139.14374 -262.820658)
		)
		(stroke
			(width 0)
			(type solid)
		)
		(fill yes)
		(layer "In2.Cu")
		(net "M_F_CPU1_SA_DQS_DN<9>")
	)
	(gr_poly
		(pts
			(xy 139.19073 -258.193286) (xy 139.14374 -258.040886) (xy 138.88212 -258.040886) (xy 138.83513 -258.193286)
			(xy 138.83513 -258.237482) (xy 139.19073 -258.237482)
		)
		(stroke
			(width 0)
			(type solid)
		)
		(fill yes)
		(layer "In2.Cu")
		(net "M_F_CPU1_SA_CA<0>")
	)
	(gr_poly
		(pts
			(xy 139.19073 -257.784854) (xy 139.19073 -257.740658) (xy 138.83513 -257.740658) (xy 138.83513 -257.784854)
			(xy 138.88212 -257.937254) (xy 139.14374 -257.937254)
		)
		(stroke
			(width 0)
			(type solid)
		)
		(fill yes)
		(layer "In2.Cu")
		(net "M_F_CPU1_SA_CA<1>")
	)
	(gr_poly
		(pts
			(xy 139.43838 -225.572574) (xy 139.400026 -225.550476) (xy 139.244578 -225.514916) (xy 139.113768 -225.741484)
			(xy 139.222226 -225.858324) (xy 139.26058 -225.880422)
		)
		(stroke
			(width 0)
			(type solid)
		)
		(fill yes)
		(layer "In2.Cu")
		(net "M_F_CPU1_SB_DQ<15>")
	)
	(gr_poly
		(pts
			(xy 139.43838 -220.68917) (xy 139.400026 -220.667072) (xy 139.244578 -220.631512) (xy 139.113768 -220.85808)
			(xy 139.222226 -220.97492) (xy 139.26058 -220.997018)
		)
		(stroke
			(width 0)
			(type solid)
		)
		(fill yes)
		(layer "In2.Cu")
		(net "M_F_CPU1_SB_DQ<22>")
	)
	(gr_poly
		(pts
			(xy 139.53363 -222.965518) (xy 139.48664 -222.813118) (xy 139.22502 -222.813118) (xy 139.17803 -222.965518)
			(xy 139.17803 -223.009968) (xy 139.53363 -223.009968)
		)
		(stroke
			(width 0)
			(type solid)
		)
		(fill yes)
		(layer "In2.Cu")
		(net "M_F_CPU1_SB_DQS_DN<2>")
	)
	(gr_poly
		(pts
			(xy 139.53363 -219.301822) (xy 139.53363 -219.257626) (xy 139.17803 -219.257626) (xy 139.17803 -219.301822)
			(xy 139.22502 -219.454222) (xy 139.48664 -219.454222)
		)
		(stroke
			(width 0)
			(type solid)
		)
		(fill yes)
		(layer "In2.Cu")
		(net "M_F_CPU1_SB_DQ<23>")
	)
	(gr_poly
		(pts
			(xy 139.542266 -230.696262) (xy 139.542266 -230.651812) (xy 139.186666 -230.651812) (xy 139.186666 -230.696262)
			(xy 139.233656 -230.848662) (xy 139.495276 -230.848662)
		)
		(stroke
			(width 0)
			(type solid)
		)
		(fill yes)
		(layer "In2.Cu")
		(net "M_F_CPU1_SB_DQ<9>")
	)
	(gr_poly
		(pts
			(xy 139.542266 -229.06863) (xy 139.542266 -229.02418) (xy 139.186666 -229.02418) (xy 139.186666 -229.06863)
			(xy 139.233656 -229.22103) (xy 139.495276 -229.22103)
		)
		(stroke
			(width 0)
			(type solid)
		)
		(fill yes)
		(layer "In2.Cu")
		(net "M_F_CPU1_SB_DQS_DN<6>")
	)
	(gr_poly
		(pts
			(xy 139.542266 -224.593658) (xy 139.495276 -224.441258) (xy 139.233656 -224.441258) (xy 139.186666 -224.593658)
			(xy 139.186666 -224.638108) (xy 139.542266 -224.638108)
		)
		(stroke
			(width 0)
			(type solid)
		)
		(fill yes)
		(layer "In2.Cu")
		(net "M_F_CPU1_SB_DQ<18>")
	)
	(gr_poly
		(pts
			(xy 139.542266 -224.185226) (xy 139.542266 -224.140776) (xy 139.186666 -224.140776) (xy 139.186666 -224.185226)
			(xy 139.233656 -224.337626) (xy 139.495276 -224.337626)
		)
		(stroke
			(width 0)
			(type solid)
		)
		(fill yes)
		(layer "In2.Cu")
		(net "M_F_CPU1_SB_DQ<17>")
	)
	(gr_poly
		(pts
			(xy 139.617196 -226.289108) (xy 139.508738 -226.172268) (xy 139.470384 -226.15017) (xy 139.292584 -226.458018)
			(xy 139.330938 -226.480116) (xy 139.486386 -226.515676)
		)
		(stroke
			(width 0)
			(type solid)
		)
		(fill yes)
		(layer "In2.Cu")
		(net "M_F_CPU1_SB_DQ<13>")
	)
	(gr_poly
		(pts
			(xy 139.617196 -221.405704) (xy 139.508738 -221.288864) (xy 139.470384 -221.266766) (xy 139.292584 -221.574614)
			(xy 139.330938 -221.596712) (xy 139.486386 -221.632272)
		)
		(stroke
			(width 0)
			(type solid)
		)
		(fill yes)
		(layer "In2.Cu")
		(net "M_F_CPU1_SB_DQ<20>")
	)
	(gr_poly
		(pts
			(xy 139.643612 -263.482582) (xy 139.643612 -263.438132) (xy 139.288012 -263.438132) (xy 139.288012 -263.482582)
			(xy 139.335002 -263.634982) (xy 139.596622 -263.634982)
		)
		(stroke
			(width 0)
			(type solid)
		)
		(fill yes)
		(layer "In2.Cu")
		(net "M_F_CPU1_SA_DQS_DP<4>")
	)
	(gr_poly
		(pts
			(xy 139.643612 -262.262874) (xy 139.596622 -262.110474) (xy 139.335002 -262.110474) (xy 139.288012 -262.262874)
			(xy 139.288012 -262.30707) (xy 139.643612 -262.30707)
		)
		(stroke
			(width 0)
			(type solid)
		)
		(fill yes)
		(layer "In2.Cu")
		(net "M_F_CPU1_SA_DQS_DP<9>")
	)
	(gr_poly
		(pts
			(xy 139.643612 -258.599178) (xy 139.643612 -258.554728) (xy 139.288012 -258.554728) (xy 139.288012 -258.599178)
			(xy 139.335002 -258.751578) (xy 139.596622 -258.751578)
		)
		(stroke
			(width 0)
			(type solid)
		)
		(fill yes)
		(layer "In2.Cu")
		(net "M_F_CPU1_SA_CS_N<1>")
	)
	(gr_poly
		(pts
			(xy 139.651994 -268.77391) (xy 139.605004 -268.62151) (xy 139.343384 -268.62151) (xy 139.296394 -268.77391)
			(xy 139.296394 -268.81836) (xy 139.651994 -268.81836)
		)
		(stroke
			(width 0)
			(type solid)
		)
		(fill yes)
		(layer "In2.Cu")
		(net "M_F_CPU1_SA_DQ<19>")
	)
	(gr_poly
		(pts
			(xy 139.651994 -268.365478) (xy 139.651994 -268.321028) (xy 139.296394 -268.321028) (xy 139.296394 -268.365478)
			(xy 139.343384 -268.517878) (xy 139.605004 -268.517878)
		)
		(stroke
			(width 0)
			(type solid)
		)
		(fill yes)
		(layer "In2.Cu")
		(net "M_F_CPU1_SA_DQS_DP<2>")
	)
	(gr_poly
		(pts
			(xy 139.651994 -267.146278) (xy 139.605004 -266.993878) (xy 139.343384 -266.993878) (xy 139.296394 -267.146278)
			(xy 139.296394 -267.190474) (xy 139.651994 -267.190474)
		)
		(stroke
			(width 0)
			(type solid)
		)
		(fill yes)
		(layer "In2.Cu")
		(net "M_F_CPU1_SA_DQS_DP<7>")
	)
	(gr_poly
		(pts
			(xy 139.651994 -266.737846) (xy 139.651994 -266.693396) (xy 139.296394 -266.693396) (xy 139.296394 -266.737846)
			(xy 139.343384 -266.890246) (xy 139.605004 -266.890246)
		)
		(stroke
			(width 0)
			(type solid)
		)
		(fill yes)
		(layer "In2.Cu")
		(net "M_F_CPU1_SA_DQ<20>")
	)
	(gr_poly
		(pts
			(xy 139.651994 -263.891014) (xy 139.605004 -263.738614) (xy 139.343384 -263.738614) (xy 139.296394 -263.891014)
			(xy 139.296394 -263.93521) (xy 139.651994 -263.93521)
		)
		(stroke
			(width 0)
			(type solid)
		)
		(fill yes)
		(layer "In2.Cu")
		(net "M_F_CPU1_SA_CB<3>")
	)
	(gr_poly
		(pts
			(xy 139.651994 -261.854442) (xy 139.651994 -261.809992) (xy 139.296394 -261.809992) (xy 139.296394 -261.854442)
			(xy 139.343384 -262.006842) (xy 139.605004 -262.006842)
		)
		(stroke
			(width 0)
			(type solid)
		)
		(fill yes)
		(layer "In2.Cu")
		(net "M_F_CPU1_SA_CB<4>")
	)
	(gr_poly
		(pts
			(xy 139.660376 -260.22681) (xy 139.660376 -260.18236) (xy 139.304776 -260.18236) (xy 139.304776 -260.22681)
			(xy 139.351766 -260.37921) (xy 139.613386 -260.37921)
		)
		(stroke
			(width 0)
			(type solid)
		)
		(fill yes)
		(layer "In2.Cu")
		(net "M_F_CPU1_ALERT_N")
	)
	(gr_poly
		(pts
			(xy 139.66063 -265.518392) (xy 139.61364 -265.365992) (xy 139.35202 -265.365992) (xy 139.30503 -265.518392)
			(xy 139.30503 -265.562588) (xy 139.66063 -265.562588)
		)
		(stroke
			(width 0)
			(type solid)
		)
		(fill yes)
		(layer "In2.Cu")
		(net "M_F_CPU1_SA_DQ<23>")
	)
	(gr_poly
		(pts
			(xy 139.66063 -265.110214) (xy 139.66063 -265.065764) (xy 139.30503 -265.065764) (xy 139.30503 -265.110214)
			(xy 139.35202 -265.262614) (xy 139.61364 -265.262614)
		)
		(stroke
			(width 0)
			(type solid)
		)
		(fill yes)
		(layer "In2.Cu")
		(net "M_F_CPU1_SA_CB<0>")
	)
	(gr_poly
		(pts
			(xy 139.906248 -221.50705) (xy 139.867894 -221.484952) (xy 139.712446 -221.449392) (xy 139.581636 -221.67596)
			(xy 139.690094 -221.7928) (xy 139.728448 -221.814898)
		)
		(stroke
			(width 0)
			(type solid)
		)
		(fill yes)
		(layer "In2.Cu")
		(net "M_F_CPU1_SB_DQS_DP<7>")
	)
	(gr_poly
		(pts
			(xy 140.012166 -225.407474) (xy 139.965176 -225.255074) (xy 139.703556 -225.255074) (xy 139.656566 -225.407474)
			(xy 139.656566 -225.451924) (xy 140.012166 -225.451924)
		)
		(stroke
			(width 0)
			(type solid)
		)
		(fill yes)
		(layer "In2.Cu")
		(net "M_F_CPU1_SB_DQ<15>")
	)
	(gr_poly
		(pts
			(xy 140.012166 -224.999042) (xy 140.012166 -224.954592) (xy 139.656566 -224.954592) (xy 139.656566 -224.999042)
			(xy 139.703556 -225.151442) (xy 139.965176 -225.151442)
		)
		(stroke
			(width 0)
			(type solid)
		)
		(fill yes)
		(layer "In2.Cu")
		(net "M_F_CPU1_SB_DQ<16>")
	)
	(gr_poly
		(pts
			(xy 140.012166 -223.779842) (xy 139.965176 -223.627442) (xy 139.703556 -223.627442) (xy 139.656566 -223.779842)
			(xy 139.656566 -223.824292) (xy 140.012166 -223.824292)
		)
		(stroke
			(width 0)
			(type solid)
		)
		(fill yes)
		(layer "In2.Cu")
		(net "M_F_CPU1_SB_DQ<19>")
	)
	(gr_poly
		(pts
			(xy 140.012166 -220.52407) (xy 139.965176 -220.37167) (xy 139.703556 -220.37167) (xy 139.656566 -220.52407)
			(xy 139.656566 -220.56852) (xy 140.012166 -220.56852)
		)
		(stroke
			(width 0)
			(type solid)
		)
		(fill yes)
		(layer "In2.Cu")
		(net "M_F_CPU1_SB_DQ<22>")
	)
	(gr_poly
		(pts
			(xy 140.091414 -222.212408) (xy 139.982956 -222.095568) (xy 139.944602 -222.07347) (xy 139.766802 -222.381318)
			(xy 139.805156 -222.403416) (xy 139.960604 -222.438976)
		)
		(stroke
			(width 0)
			(type solid)
		)
		(fill yes)
		(layer "In2.Cu")
		(net "M_F_CPU1_SB_DQS_DN<7>")
	)
	(gr_poly
		(pts
			(xy 140.326364 -223.35744) (xy 140.290804 -223.201992) (xy 140.268706 -223.163638) (xy 139.960858 -223.341438)
			(xy 139.982956 -223.379792) (xy 140.099796 -223.48825)
		)
		(stroke
			(width 0)
			(type solid)
		)
		(fill yes)
		(layer "In2.Cu")
		(net "M_F_CPU1_SB_DQS_DP<2>")
	)
	(gr_poly
		(pts
			(xy 140.371576 -222.327978) (xy 140.333222 -222.30588) (xy 140.177774 -222.27032) (xy 140.046964 -222.496888)
			(xy 140.155422 -222.613728) (xy 140.193776 -222.635826)
		)
		(stroke
			(width 0)
			(type solid)
		)
		(fill yes)
		(layer "In2.Cu")
		(net "M_F_CPU1_SB_DQS_DN<2>")
	)
	(gr_poly
		(pts
			(xy 140.482066 -224.185226) (xy 140.482066 -224.140776) (xy 140.126466 -224.140776) (xy 140.126466 -224.185226)
			(xy 140.173456 -224.337626) (xy 140.435076 -224.337626)
		)
		(stroke
			(width 0)
			(type solid)
		)
		(fill yes)
		(layer "In2.Cu")
		(net "M_F_CPU1_SB_DQ<17>")
	)
	(gr_poly
		(pts
			(xy 140.482066 -221.338394) (xy 140.435076 -221.185994) (xy 140.173456 -221.185994) (xy 140.126466 -221.338394)
			(xy 140.126466 -221.38259) (xy 140.482066 -221.38259)
		)
		(stroke
			(width 0)
			(type solid)
		)
		(fill yes)
		(layer "In2.Cu")
		(net "M_F_CPU1_SB_DQS_DP<7>")
	)
	(gr_poly
		(pts
			(xy 140.482066 -220.929454) (xy 140.482066 -220.885258) (xy 140.126466 -220.885258) (xy 140.126466 -220.929454)
			(xy 140.173456 -221.081854) (xy 140.435076 -221.081854)
		)
		(stroke
			(width 0)
			(type solid)
		)
		(fill yes)
		(layer "In2.Cu")
		(net "M_F_CPU1_SB_DQ<20>")
	)
	(gr_poly
		(pts
			(xy 140.951966 -221.74327) (xy 140.951966 -221.699074) (xy 140.596366 -221.699074) (xy 140.596366 -221.74327)
			(xy 140.643356 -221.89567) (xy 140.904976 -221.89567)
		)
		(stroke
			(width 0)
			(type solid)
		)
		(fill yes)
		(layer "In2.Cu")
		(net "M_F_CPU1_SB_DQS_DN<7>")
	)
	(gr_poly
		(pts
			(xy 141.024864 -220.595698) (xy 140.916406 -220.478858) (xy 140.878052 -220.45676) (xy 140.700252 -220.764608)
			(xy 140.738606 -220.786706) (xy 140.894054 -220.822266)
		)
		(stroke
			(width 0)
			(type solid)
		)
		(fill yes)
		(layer "In2.Cu")
		(net "M_F_CPU1_SB_DQ<20>")
	)
	(gr_poly
		(pts
			(xy 141.026896 -223.847406) (xy 140.918438 -223.730566) (xy 140.880084 -223.708468) (xy 140.702284 -224.016316)
			(xy 140.740638 -224.038414) (xy 140.896086 -224.073974)
		)
		(stroke
			(width 0)
			(type solid)
		)
		(fill yes)
		(layer "In2.Cu")
		(net "M_F_CPU1_SB_DQ<17>")
	)
	(gr_poly
		(pts
			(xy 332.464918 -276.350476) (xy 332.503272 -276.328378) (xy 332.325472 -276.02053) (xy 332.287118 -276.042628)
			(xy 332.17866 -276.159468) (xy 332.30947 -276.386036)
		)
		(stroke
			(width 0)
			(type solid)
		)
		(fill yes)
		(layer "In2.Cu")
		(net "M_B_CPU0_SA_DQ<7>")
	)
	(gr_poly
		(pts
			(xy 332.495398 -244.940582) (xy 332.448408 -244.788182) (xy 332.186788 -244.788182) (xy 332.139798 -244.940582)
			(xy 332.139798 -244.985032) (xy 332.495398 -244.985032)
		)
		(stroke
			(width 0)
			(type solid)
		)
		(fill yes)
		(layer "In2.Cu")
		(net "M_B_CPU0_SB_CS_N<1>")
	)
	(gr_poly
		(pts
			(xy 332.495398 -244.532658) (xy 332.495398 -244.488208) (xy 332.139798 -244.488208) (xy 332.139798 -244.532658)
			(xy 332.186788 -244.685058) (xy 332.448408 -244.685058)
		)
		(stroke
			(width 0)
			(type solid)
		)
		(fill yes)
		(layer "In2.Cu")
		(net "M_B_CPU0_SB_CB<6>")
	)
	(gr_poly
		(pts
			(xy 332.495398 -240.057178) (xy 332.448408 -239.904778) (xy 332.186788 -239.904778) (xy 332.139798 -240.057178)
			(xy 332.139798 -240.101628) (xy 332.495398 -240.101628)
		)
		(stroke
			(width 0)
			(type solid)
		)
		(fill yes)
		(layer "In2.Cu")
		(net "M_B_CPU0_SB_CB<1>")
	)
	(gr_poly
		(pts
			(xy 332.495398 -235.174282) (xy 332.448408 -235.021882) (xy 332.186788 -235.021882) (xy 332.139798 -235.174282)
			(xy 332.139798 -235.218478) (xy 332.495398 -235.218478)
		)
		(stroke
			(width 0)
			(type solid)
		)
		(fill yes)
		(layer "In2.Cu")
		(net "M_A_CPU0_SB_DQ<7>")
	)
	(gr_poly
		(pts
			(xy 332.495398 -234.76585) (xy 332.495398 -234.721654) (xy 332.139798 -234.721654) (xy 332.139798 -234.76585)
			(xy 332.186788 -234.91825) (xy 332.448408 -234.91825)
		)
		(stroke
			(width 0)
			(type solid)
		)
		(fill yes)
		(layer "In2.Cu")
		(net "M_B_CPU0_SB_DQ<8>")
	)
	(gr_poly
		(pts
			(xy 332.504034 -246.568722) (xy 332.457044 -246.416322) (xy 332.195424 -246.416322) (xy 332.148434 -246.568722)
			(xy 332.148434 -246.613172) (xy 332.504034 -246.613172)
		)
		(stroke
			(width 0)
			(type solid)
		)
		(fill yes)
		(layer "In2.Cu")
		(net "M_B_CPU0_SB_PAR")
	)
	(gr_poly
		(pts
			(xy 332.504034 -246.16029) (xy 332.504034 -246.11584) (xy 332.148434 -246.11584) (xy 332.148434 -246.16029)
			(xy 332.195424 -246.31269) (xy 332.457044 -246.31269)
		)
		(stroke
			(width 0)
			(type solid)
		)
		(fill yes)
		(layer "In2.Cu")
		(net "M_B_CPU0_SB_CS_N<0>")
	)
	(gr_poly
		(pts
			(xy 332.504034 -238.430054) (xy 332.457044 -238.277654) (xy 332.195424 -238.277654) (xy 332.148434 -238.430054)
			(xy 332.148434 -238.47425) (xy 332.504034 -238.47425)
		)
		(stroke
			(width 0)
			(type solid)
		)
		(fill yes)
		(layer "In2.Cu")
		(net "M_A_CPU0_SB_DQ<3>")
	)
	(gr_poly
		(pts
			(xy 332.509622 -275.450046) (xy 332.471268 -275.427948) (xy 332.31582 -275.392388) (xy 332.18501 -275.618956)
			(xy 332.293468 -275.735796) (xy 332.331822 -275.757894)
		)
		(stroke
			(width 0)
			(type solid)
		)
		(fill yes)
		(layer "In2.Cu")
		(net "M_B_CPU0_SA_DQ<7>")
	)
	(gr_poly
		(pts
			(xy 332.512416 -243.31295) (xy 332.465426 -243.16055) (xy 332.203806 -243.16055) (xy 332.156816 -243.31295)
			(xy 332.156816 -243.3574) (xy 332.512416 -243.3574)
		)
		(stroke
			(width 0)
			(type solid)
		)
		(fill yes)
		(layer "In2.Cu")
		(net "M_B_CPU0_SB_CB<5>")
	)
	(gr_poly
		(pts
			(xy 332.512416 -238.021622) (xy 332.512416 -237.977172) (xy 332.156816 -237.977172) (xy 332.156816 -238.021622)
			(xy 332.203806 -238.174022) (xy 332.465426 -238.174022)
		)
		(stroke
			(width 0)
			(type solid)
		)
		(fill yes)
		(layer "In2.Cu")
		(net "M_A_CPU0_SB_DQS_DP<0>")
	)
	(gr_poly
		(pts
			(xy 332.613762 -265.92403) (xy 332.613762 -265.87958) (xy 332.258162 -265.87958) (xy 332.258162 -265.92403)
			(xy 332.305152 -266.07643) (xy 332.566772 -266.07643)
		)
		(stroke
			(width 0)
			(type solid)
		)
		(fill yes)
		(layer "In2.Cu")
		(net "M_B_CPU0_SA_DQS_DP<2>")
	)
	(gr_poly
		(pts
			(xy 332.613762 -264.70483) (xy 332.566772 -264.55243) (xy 332.305152 -264.55243) (xy 332.258162 -264.70483)
			(xy 332.258162 -264.749026) (xy 332.613762 -264.749026)
		)
		(stroke
			(width 0)
			(type solid)
		)
		(fill yes)
		(layer "In2.Cu")
		(net "M_B_CPU0_SA_DQS_DP<7>")
	)
	(gr_poly
		(pts
			(xy 332.613762 -264.29589) (xy 332.613762 -264.251694) (xy 332.258162 -264.251694) (xy 332.258162 -264.29589)
			(xy 332.305152 -264.44829) (xy 332.566772 -264.44829)
		)
		(stroke
			(width 0)
			(type solid)
		)
		(fill yes)
		(layer "In2.Cu")
		(net "M_B_CPU0_SA_DQ<20>")
	)
	(gr_poly
		(pts
			(xy 332.613762 -262.668258) (xy 332.613762 -262.623808) (xy 332.258162 -262.623808) (xy 332.258162 -262.668258)
			(xy 332.305152 -262.820658) (xy 332.566772 -262.820658)
		)
		(stroke
			(width 0)
			(type solid)
		)
		(fill yes)
		(layer "In2.Cu")
		(net "M_B_CPU0_SA_CB<0>")
	)
	(gr_poly
		(pts
			(xy 332.613762 -261.449058) (xy 332.566772 -261.296658) (xy 332.305152 -261.296658) (xy 332.258162 -261.449058)
			(xy 332.258162 -261.493508) (xy 332.613762 -261.493508)
		)
		(stroke
			(width 0)
			(type solid)
		)
		(fill yes)
		(layer "In2.Cu")
		(net "M_B_CPU0_SA_CB<3>")
	)
	(gr_poly
		(pts
			(xy 332.613762 -261.040626) (xy 332.613762 -260.996176) (xy 332.258162 -260.996176) (xy 332.258162 -261.040626)
			(xy 332.305152 -261.193026) (xy 332.566772 -261.193026)
		)
		(stroke
			(width 0)
			(type solid)
		)
		(fill yes)
		(layer "In2.Cu")
		(net "M_B_CPU0_SA_DQS_DP<4>")
	)
	(gr_poly
		(pts
			(xy 332.613762 -259.821426) (xy 332.566772 -259.669026) (xy 332.305152 -259.669026) (xy 332.258162 -259.821426)
			(xy 332.258162 -259.865622) (xy 332.613762 -259.865622)
		)
		(stroke
			(width 0)
			(type solid)
		)
		(fill yes)
		(layer "In2.Cu")
		(net "M_B_CPU0_SA_DQS_DP<9>")
	)
	(gr_poly
		(pts
			(xy 332.613762 -259.412486) (xy 332.613762 -259.36829) (xy 332.258162 -259.36829) (xy 332.258162 -259.412486)
			(xy 332.305152 -259.564886) (xy 332.566772 -259.564886)
		)
		(stroke
			(width 0)
			(type solid)
		)
		(fill yes)
		(layer "In2.Cu")
		(net "M_B_CPU0_SA_CB<4>")
	)
	(gr_poly
		(pts
			(xy 332.965298 -243.718842) (xy 332.965298 -243.674392) (xy 332.609698 -243.674392) (xy 332.609698 -243.718842)
			(xy 332.656688 -243.871242) (xy 332.918308 -243.871242)
		)
		(stroke
			(width 0)
			(type solid)
		)
		(fill yes)
		(layer "In2.Cu")
		(net "M_B_CPU0_SB_CB<7>")
	)
	(gr_poly
		(pts
			(xy 332.965298 -242.499134) (xy 332.918308 -242.346734) (xy 332.656688 -242.346734) (xy 332.609698 -242.499134)
			(xy 332.609698 -242.54333) (xy 332.965298 -242.54333)
		)
		(stroke
			(width 0)
			(type solid)
		)
		(fill yes)
		(layer "In2.Cu")
		(net "M_B_CPU0_SB_DQS_DP<4>")
	)
	(gr_poly
		(pts
			(xy 332.965298 -237.61573) (xy 332.918308 -237.46333) (xy 332.656688 -237.46333) (xy 332.609698 -237.61573)
			(xy 332.609698 -237.66018) (xy 332.965298 -237.66018)
		)
		(stroke
			(width 0)
			(type solid)
		)
		(fill yes)
		(layer "In2.Cu")
		(net "M_A_CPU0_SB_DQS_DN<0>")
	)
	(gr_poly
		(pts
			(xy 332.965298 -237.207806) (xy 332.965298 -237.163356) (xy 332.609698 -237.163356) (xy 332.609698 -237.207806)
			(xy 332.656688 -237.360206) (xy 332.918308 -237.360206)
		)
		(stroke
			(width 0)
			(type solid)
		)
		(fill yes)
		(layer "In2.Cu")
		(net "M_A_CPU0_SB_DQS_DN<5>")
	)
	(gr_poly
		(pts
			(xy 332.965298 -232.732326) (xy 332.918308 -232.579926) (xy 332.656688 -232.579926) (xy 332.609698 -232.732326)
			(xy 332.609698 -232.776776) (xy 332.965298 -232.776776)
		)
		(stroke
			(width 0)
			(type solid)
		)
		(fill yes)
		(layer "In2.Cu")
		(net "M_B_CPU0_SB_DQS_DN<1>")
	)
	(gr_poly
		(pts
			(xy 332.965298 -232.324402) (xy 332.965298 -232.279952) (xy 332.609698 -232.279952) (xy 332.609698 -232.324402)
			(xy 332.656688 -232.476802) (xy 332.918308 -232.476802)
		)
		(stroke
			(width 0)
			(type solid)
		)
		(fill yes)
		(layer "In2.Cu")
		(net "M_B_CPU0_SB_DQS_DN<6>")
	)
	(gr_poly
		(pts
			(xy 332.965298 -225.813366) (xy 332.965298 -225.768916) (xy 332.609698 -225.768916) (xy 332.609698 -225.813366)
			(xy 332.656688 -225.965766) (xy 332.918308 -225.965766)
		)
		(stroke
			(width 0)
			(type solid)
		)
		(fill yes)
		(layer "In2.Cu")
		(net "M_B_CPU0_SB_DQ<17>")
	)
	(gr_poly
		(pts
			(xy 332.967584 -242.090702) (xy 332.967584 -242.046506) (xy 332.611984 -242.046506) (xy 332.611984 -242.090702)
			(xy 332.658974 -242.243102) (xy 332.920594 -242.243102)
		)
		(stroke
			(width 0)
			(type solid)
		)
		(fill yes)
		(layer "In2.Cu")
		(net "M_B_CPU0_SB_DQS_DP<9>")
	)
	(gr_poly
		(pts
			(xy 332.973172 -274.647152) (xy 332.934818 -274.625054) (xy 332.77937 -274.589494) (xy 332.64856 -274.816062)
			(xy 332.757018 -274.932902) (xy 332.795372 -274.955)
		)
		(stroke
			(width 0)
			(type solid)
		)
		(fill yes)
		(layer "In2.Cu")
		(net "M_B_CPU0_SA_DQ<7>")
	)
	(gr_poly
		(pts
			(xy 332.973934 -247.382538) (xy 332.926944 -247.230138) (xy 332.665324 -247.230138) (xy 332.618334 -247.382538)
			(xy 332.618334 -247.426988) (xy 332.973934 -247.426988)
		)
		(stroke
			(width 0)
			(type solid)
		)
		(fill yes)
		(layer "In2.Cu")
		(net "M_B_CPU0_SB_CA<5>")
	)
	(gr_poly
		(pts
			(xy 332.973934 -246.974106) (xy 332.973934 -246.929656) (xy 332.618334 -246.929656) (xy 332.618334 -246.974106)
			(xy 332.665324 -247.126506) (xy 332.926944 -247.126506)
		)
		(stroke
			(width 0)
			(type solid)
		)
		(fill yes)
		(layer "In2.Cu")
		(net "M_B_CPU0_SB_CA<6>")
	)
	(gr_poly
		(pts
			(xy 332.973934 -245.754906) (xy 332.926944 -245.602506) (xy 332.665324 -245.602506) (xy 332.618334 -245.754906)
			(xy 332.618334 -245.799356) (xy 332.973934 -245.799356)
		)
		(stroke
			(width 0)
			(type solid)
		)
		(fill yes)
		(layer "In2.Cu")
		(net "M_B_CPU0_SB_CS_N<2>")
	)
	(gr_poly
		(pts
			(xy 332.973934 -240.871502) (xy 332.926944 -240.719102) (xy 332.665324 -240.719102) (xy 332.618334 -240.871502)
			(xy 332.618334 -240.915952) (xy 332.973934 -240.915952)
		)
		(stroke
			(width 0)
			(type solid)
		)
		(fill yes)
		(layer "In2.Cu")
		(net "M_B_CPU0_SB_CB<0>")
	)
	(gr_poly
		(pts
			(xy 332.973934 -238.83493) (xy 332.973934 -238.790734) (xy 332.618334 -238.790734) (xy 332.618334 -238.83493)
			(xy 332.665324 -238.98733) (xy 332.926944 -238.98733)
		)
		(stroke
			(width 0)
			(type solid)
		)
		(fill yes)
		(layer "In2.Cu")
		(net "M_A_CPU0_SB_DQ<1>")
	)
	(gr_poly
		(pts
			(xy 332.973934 -235.988098) (xy 332.926944 -235.835698) (xy 332.665324 -235.835698) (xy 332.618334 -235.988098)
			(xy 332.618334 -236.032548) (xy 332.973934 -236.032548)
		)
		(stroke
			(width 0)
			(type solid)
		)
		(fill yes)
		(layer "In2.Cu")
		(net "M_A_CPU0_SB_DQ<6>")
	)
	(gr_poly
		(pts
			(xy 332.973934 -233.952034) (xy 332.973934 -233.907584) (xy 332.618334 -233.907584) (xy 332.618334 -233.952034)
			(xy 332.665324 -234.104434) (xy 332.926944 -234.104434)
		)
		(stroke
			(width 0)
			(type solid)
		)
		(fill yes)
		(layer "In2.Cu")
		(net "M_B_CPU0_SB_DQ<9>")
	)
	(gr_poly
		(pts
			(xy 332.982316 -245.346474) (xy 332.982316 -245.302278) (xy 332.626716 -245.302278) (xy 332.626716 -245.346474)
			(xy 332.673706 -245.498874) (xy 332.935326 -245.498874)
		)
		(stroke
			(width 0)
			(type solid)
		)
		(fill yes)
		(layer "In2.Cu")
		(net "M_B_CPU0_SB_CS_N<3>")
	)
	(gr_poly
		(pts
			(xy 332.982316 -244.126766) (xy 332.935326 -243.974366) (xy 332.673706 -243.974366) (xy 332.626716 -244.126766)
			(xy 332.626716 -244.171216) (xy 332.982316 -244.171216)
		)
		(stroke
			(width 0)
			(type solid)
		)
		(fill yes)
		(layer "In2.Cu")
		(net "M_B_CPU0_SB_CB<4>")
	)
	(gr_poly
		(pts
			(xy 332.982316 -240.46307) (xy 332.982316 -240.418874) (xy 332.626716 -240.418874) (xy 332.626716 -240.46307)
			(xy 332.673706 -240.61547) (xy 332.935326 -240.61547)
		)
		(stroke
			(width 0)
			(type solid)
		)
		(fill yes)
		(layer "In2.Cu")
		(net "M_B_CPU0_SB_CB<3>")
	)
	(gr_poly
		(pts
			(xy 332.982316 -239.243362) (xy 332.935326 -239.090962) (xy 332.673706 -239.090962) (xy 332.626716 -239.243362)
			(xy 332.626716 -239.287812) (xy 332.982316 -239.287812)
		)
		(stroke
			(width 0)
			(type solid)
		)
		(fill yes)
		(layer "In2.Cu")
		(net "M_A_CPU0_SB_DQ<2>")
	)
	(gr_poly
		(pts
			(xy 332.982316 -235.579666) (xy 332.982316 -235.53547) (xy 332.626716 -235.53547) (xy 332.626716 -235.579666)
			(xy 332.673706 -235.732066) (xy 332.935326 -235.732066)
		)
		(stroke
			(width 0)
			(type solid)
		)
		(fill yes)
		(layer "In2.Cu")
		(net "M_A_CPU0_SB_DQ<5>")
	)
	(gr_poly
		(pts
			(xy 332.982316 -234.360466) (xy 332.935326 -234.208066) (xy 332.673706 -234.208066) (xy 332.626716 -234.360466)
			(xy 332.626716 -234.404662) (xy 332.982316 -234.404662)
		)
		(stroke
			(width 0)
			(type solid)
		)
		(fill yes)
		(layer "In2.Cu")
		(net "M_B_CPU0_SB_DQ<10>")
	)
	(gr_poly
		(pts
			(xy 333.054452 -276.560788) (xy 333.16291 -276.443948) (xy 333.0321 -276.21738) (xy 332.876652 -276.25294)
			(xy 332.838298 -276.275038) (xy 333.016098 -276.582886)
		)
		(stroke
			(width 0)
			(type solid)
		)
		(fill yes)
		(layer "In2.Cu")
		(net "M_B_CPU0_SA_DQ<5>")
	)
	(gr_poly
		(pts
			(xy 333.083662 -267.146278) (xy 333.036672 -266.993878) (xy 332.775052 -266.993878) (xy 332.728062 -267.146278)
			(xy 332.728062 -267.190474) (xy 333.083662 -267.190474)
		)
		(stroke
			(width 0)
			(type solid)
		)
		(fill yes)
		(layer "In2.Cu")
		(net "M_B_CPU0_SA_DQ<18>")
	)
	(gr_poly
		(pts
			(xy 333.083662 -266.737846) (xy 333.083662 -266.693396) (xy 332.728062 -266.693396) (xy 332.728062 -266.737846)
			(xy 332.775052 -266.890246) (xy 333.036672 -266.890246)
		)
		(stroke
			(width 0)
			(type solid)
		)
		(fill yes)
		(layer "In2.Cu")
		(net "M_B_CPU0_SA_DQ<17>")
	)
	(gr_poly
		(pts
			(xy 333.083662 -265.518646) (xy 333.036672 -265.366246) (xy 332.775052 -265.366246) (xy 332.728062 -265.518646)
			(xy 332.728062 -265.562842) (xy 333.083662 -265.562842)
		)
		(stroke
			(width 0)
			(type solid)
		)
		(fill yes)
		(layer "In2.Cu")
		(net "M_B_CPU0_SA_DQS_DN<2>")
	)
	(gr_poly
		(pts
			(xy 333.083662 -265.109706) (xy 333.083662 -265.06551) (xy 332.728062 -265.06551) (xy 332.728062 -265.109706)
			(xy 332.775052 -265.262106) (xy 333.036672 -265.262106)
		)
		(stroke
			(width 0)
			(type solid)
		)
		(fill yes)
		(layer "In2.Cu")
		(net "M_B_CPU0_SA_DQS_DN<7>")
	)
	(gr_poly
		(pts
			(xy 333.083662 -263.891014) (xy 333.036672 -263.738614) (xy 332.775052 -263.738614) (xy 332.728062 -263.891014)
			(xy 332.728062 -263.93521) (xy 333.083662 -263.93521)
		)
		(stroke
			(width 0)
			(type solid)
		)
		(fill yes)
		(layer "In2.Cu")
		(net "M_B_CPU0_SA_DQ<22>")
	)
	(gr_poly
		(pts
			(xy 333.083662 -263.482074) (xy 333.083662 -263.437878) (xy 332.728062 -263.437878) (xy 332.728062 -263.482074)
			(xy 332.775052 -263.634474) (xy 333.036672 -263.634474)
		)
		(stroke
			(width 0)
			(type solid)
		)
		(fill yes)
		(layer "In2.Cu")
		(net "M_B_CPU0_SA_DQ<21>")
	)
	(gr_poly
		(pts
			(xy 333.083662 -262.262874) (xy 333.036672 -262.110474) (xy 332.775052 -262.110474) (xy 332.728062 -262.262874)
			(xy 332.728062 -262.307324) (xy 333.083662 -262.307324)
		)
		(stroke
			(width 0)
			(type solid)
		)
		(fill yes)
		(layer "In2.Cu")
		(net "M_B_CPU0_SA_CB<2>")
	)
	(gr_poly
		(pts
			(xy 333.083662 -261.854442) (xy 333.083662 -261.809992) (xy 332.728062 -261.809992) (xy 332.728062 -261.854442)
			(xy 332.775052 -262.006842) (xy 333.036672 -262.006842)
		)
		(stroke
			(width 0)
			(type solid)
		)
		(fill yes)
		(layer "In2.Cu")
		(net "M_B_CPU0_SA_CB<1>")
	)
	(gr_poly
		(pts
			(xy 333.083662 -260.635242) (xy 333.036672 -260.482842) (xy 332.775052 -260.482842) (xy 332.728062 -260.635242)
			(xy 332.728062 -260.679438) (xy 333.083662 -260.679438)
		)
		(stroke
			(width 0)
			(type solid)
		)
		(fill yes)
		(layer "In2.Cu")
		(net "M_B_CPU0_SA_DQS_DN<4>")
	)
	(gr_poly
		(pts
			(xy 333.083662 -260.226302) (xy 333.083662 -260.182106) (xy 332.728062 -260.182106) (xy 332.728062 -260.226302)
			(xy 332.775052 -260.378702) (xy 333.036672 -260.378702)
		)
		(stroke
			(width 0)
			(type solid)
		)
		(fill yes)
		(layer "In2.Cu")
		(net "M_B_CPU0_SA_DQS_DN<9>")
	)
	(gr_poly
		(pts
			(xy 333.083662 -259.00761) (xy 333.036672 -258.85521) (xy 332.775052 -258.85521) (xy 332.728062 -259.00761)
			(xy 332.728062 -259.051806) (xy 333.083662 -259.051806)
		)
		(stroke
			(width 0)
			(type solid)
		)
		(fill yes)
		(layer "In2.Cu")
		(net "M_B_CPU0_SA_CB<6>")
	)
	(gr_poly
		(pts
			(xy 333.083662 -258.59867) (xy 333.083662 -258.554474) (xy 332.728062 -258.554474) (xy 332.728062 -258.59867)
			(xy 332.775052 -258.75107) (xy 333.036672 -258.75107)
		)
		(stroke
			(width 0)
			(type solid)
		)
		(fill yes)
		(layer "In2.Cu")
		(net "M_B_CPU0_SA_CB<5>")
	)
	(gr_poly
		(pts
			(xy 333.083662 -257.37947) (xy 333.036672 -257.22707) (xy 332.775052 -257.22707) (xy 332.728062 -257.37947)
			(xy 332.728062 -257.42392) (xy 333.083662 -257.42392)
		)
		(stroke
			(width 0)
			(type solid)
		)
		(fill yes)
		(layer "In2.Cu")
		(net "M_B_CPU0_SA_CS_N<0>")
	)
	(gr_poly
		(pts
			(xy 333.083662 -256.971038) (xy 333.083662 -256.926588) (xy 332.728062 -256.926588) (xy 332.728062 -256.971038)
			(xy 332.775052 -257.123438) (xy 333.036672 -257.123438)
		)
		(stroke
			(width 0)
			(type solid)
		)
		(fill yes)
		(layer "In2.Cu")
		(net "M_B_CPU0_SA_CS_N<2>")
	)
	(gr_poly
		(pts
			(xy 333.083662 -255.751838) (xy 333.036672 -255.599438) (xy 332.775052 -255.599438) (xy 332.728062 -255.751838)
			(xy 332.728062 -255.796288) (xy 333.083662 -255.796288)
		)
		(stroke
			(width 0)
			(type solid)
		)
		(fill yes)
		(layer "In2.Cu")
		(net "M_B_CPU0_SA_CA<0>")
	)
	(gr_poly
		(pts
			(xy 333.083662 -255.343406) (xy 333.083662 -255.298956) (xy 332.728062 -255.298956) (xy 332.728062 -255.343406)
			(xy 332.775052 -255.495806) (xy 333.036672 -255.495806)
		)
		(stroke
			(width 0)
			(type solid)
		)
		(fill yes)
		(layer "In2.Cu")
		(net "M_B_CPU0_SA_CA<1>")
	)
	(gr_poly
		(pts
			(xy 333.083662 -254.124206) (xy 333.036672 -253.971806) (xy 332.775052 -253.971806) (xy 332.728062 -254.124206)
			(xy 332.728062 -254.168402) (xy 333.083662 -254.168402)
		)
		(stroke
			(width 0)
			(type solid)
		)
		(fill yes)
		(layer "In2.Cu")
		(net "M_B_CPU0_SA_CA<4>")
	)
	(gr_poly
		(pts
			(xy 333.083916 -253.715266) (xy 333.083916 -253.67107) (xy 332.728316 -253.67107) (xy 332.728316 -253.715266)
			(xy 332.775306 -253.867666) (xy 333.036926 -253.867666)
		)
		(stroke
			(width 0)
			(type solid)
		)
		(fill yes)
		(layer "In2.Cu")
		(net "M_B_CPU0_SA_CA<5>")
	)
	(gr_poly
		(pts
			(xy 333.156306 -275.356574) (xy 333.047848 -275.239734) (xy 333.009494 -275.217636) (xy 332.831694 -275.525484)
			(xy 332.870048 -275.547582) (xy 333.025496 -275.583142)
		)
		(stroke
			(width 0)
			(type solid)
		)
		(fill yes)
		(layer "In2.Cu")
		(net "M_B_CPU0_SA_DQ<5>")
	)
	(gr_poly
		(pts
			(xy 333.157576 -276.982428) (xy 333.049118 -276.865588) (xy 333.010764 -276.84349) (xy 332.832964 -277.151338)
			(xy 332.871318 -277.173436) (xy 333.026766 -277.208996)
		)
		(stroke
			(width 0)
			(type solid)
		)
		(fill yes)
		(layer "In2.Cu")
		(net "M_B_CPU0_SA_DQ<5>")
	)
	(gr_poly
		(pts
			(xy 333.29499 -227.286566) (xy 333.333344 -227.264468) (xy 333.155544 -226.95662) (xy 333.11719 -226.978718)
			(xy 333.008732 -227.095558) (xy 333.139542 -227.322126)
		)
		(stroke
			(width 0)
			(type solid)
		)
		(fill yes)
		(layer "In2.Cu")
		(net "M_B_CPU0_SB_DQ<16>")
	)
	(gr_poly
		(pts
			(xy 333.300578 -224.040954) (xy 333.338932 -224.018856) (xy 333.161132 -223.711008) (xy 333.122778 -223.733106)
			(xy 333.01432 -223.849946) (xy 333.14513 -224.076514)
		)
		(stroke
			(width 0)
			(type solid)
		)
		(fill yes)
		(layer "In2.Cu")
		(net "M_B_CPU0_SB_DQS_DP<2>")
	)
	(gr_poly
		(pts
			(xy 333.404718 -276.350476) (xy 333.443072 -276.328378) (xy 333.265272 -276.02053) (xy 333.226918 -276.042628)
			(xy 333.11846 -276.159468) (xy 333.24927 -276.386036)
		)
		(stroke
			(width 0)
			(type solid)
		)
		(fill yes)
		(layer "In2.Cu")
		(net "M_B_CPU0_SA_DQ<6>")
	)
	(gr_poly
		(pts
			(xy 333.40929 -223.418654) (xy 333.517748 -223.301814) (xy 333.386938 -223.075246) (xy 333.23149 -223.110806)
			(xy 333.193136 -223.132904) (xy 333.370936 -223.440752)
		)
		(stroke
			(width 0)
			(type solid)
		)
		(fill yes)
		(layer "In2.Cu")
		(net "M_B_CPU0_SB_DQS_DN<2>")
	)
	(gr_poly
		(pts
			(xy 333.416402 -226.686364) (xy 333.52486 -226.569524) (xy 333.39405 -226.342956) (xy 333.238602 -226.378516)
			(xy 333.200248 -226.400614) (xy 333.378048 -226.708462)
		)
		(stroke
			(width 0)
			(type solid)
		)
		(fill yes)
		(layer "In2.Cu")
		(net "M_B_CPU0_SB_DQ<18>")
	)
	(gr_poly
		(pts
			(xy 333.435198 -244.940582) (xy 333.388208 -244.788182) (xy 333.126588 -244.788182) (xy 333.079598 -244.940582)
			(xy 333.079598 -244.985032) (xy 333.435198 -244.985032)
		)
		(stroke
			(width 0)
			(type solid)
		)
		(fill yes)
		(layer "In2.Cu")
		(net "M_B_CPU0_SB_CS_N<1>")
	)
	(gr_poly
		(pts
			(xy 333.435198 -244.532658) (xy 333.435198 -244.488208) (xy 333.079598 -244.488208) (xy 333.079598 -244.532658)
			(xy 333.126588 -244.685058) (xy 333.388208 -244.685058)
		)
		(stroke
			(width 0)
			(type solid)
		)
		(fill yes)
		(layer "In2.Cu")
		(net "M_B_CPU0_SB_CB<6>")
	)
	(gr_poly
		(pts
			(xy 333.435198 -240.057178) (xy 333.388208 -239.904778) (xy 333.126588 -239.904778) (xy 333.079598 -240.057178)
			(xy 333.079598 -240.101628) (xy 333.435198 -240.101628)
		)
		(stroke
			(width 0)
			(type solid)
		)
		(fill yes)
		(layer "In2.Cu")
		(net "M_B_CPU0_SB_CB<1>")
	)
	(gr_poly
		(pts
			(xy 333.435198 -239.649254) (xy 333.435198 -239.604804) (xy 333.079598 -239.604804) (xy 333.079598 -239.649254)
			(xy 333.126588 -239.801654) (xy 333.388208 -239.801654)
		)
		(stroke
			(width 0)
			(type solid)
		)
		(fill yes)
		(layer "In2.Cu")
		(net "M_A_CPU0_SB_DQ<0>")
	)
	(gr_poly
		(pts
			(xy 333.435198 -235.174282) (xy 333.388208 -235.021882) (xy 333.126588 -235.021882) (xy 333.079598 -235.174282)
			(xy 333.079598 -235.218478) (xy 333.435198 -235.218478)
		)
		(stroke
			(width 0)
			(type solid)
		)
		(fill yes)
		(layer "In2.Cu")
		(net "M_A_CPU0_SB_DQ<7>")
	)
	(gr_poly
		(pts
			(xy 333.435198 -234.76585) (xy 333.435198 -234.721654) (xy 333.079598 -234.721654) (xy 333.079598 -234.76585)
			(xy 333.126588 -234.91825) (xy 333.388208 -234.91825)
		)
		(stroke
			(width 0)
			(type solid)
		)
		(fill yes)
		(layer "In2.Cu")
		(net "M_B_CPU0_SB_DQ<8>")
	)
	(gr_poly
		(pts
			(xy 333.437484 -242.904518) (xy 333.437484 -242.860322) (xy 333.081884 -242.860322) (xy 333.081884 -242.904518)
			(xy 333.128874 -243.056918) (xy 333.390494 -243.056918)
		)
		(stroke
			(width 0)
			(type solid)
		)
		(fill yes)
		(layer "In2.Cu")
		(net "M_B_CPU0_SB_DQS_DN<4>")
	)
	(gr_poly
		(pts
			(xy 333.440278 -273.838416) (xy 333.401924 -273.816318) (xy 333.246476 -273.780758) (xy 333.115666 -274.007326)
			(xy 333.224124 -274.124166) (xy 333.262478 -274.146264)
		)
		(stroke
			(width 0)
			(type solid)
		)
		(fill yes)
		(layer "In2.Cu")
		(net "M_B_CPU0_SA_DQ<7>")
	)
	(gr_poly
		(pts
			(xy 333.44358 -241.685318) (xy 333.39659 -241.532918) (xy 333.13497 -241.532918) (xy 333.08798 -241.685318)
			(xy 333.08798 -241.729768) (xy 333.44358 -241.729768)
		)
		(stroke
			(width 0)
			(type solid)
		)
		(fill yes)
		(layer "In2.Cu")
		(net "M_B_CPU0_SB_DQS_DN<9>")
	)
	(gr_poly
		(pts
			(xy 333.443834 -247.787922) (xy 333.443834 -247.743472) (xy 333.088234 -247.743472) (xy 333.088234 -247.787922)
			(xy 333.135224 -247.940322) (xy 333.396844 -247.940322)
		)
		(stroke
			(width 0)
			(type solid)
		)
		(fill yes)
		(layer "In2.Cu")
		(net "M_B_CPU0_SB_CA<4>")
	)
	(gr_poly
		(pts
			(xy 333.443834 -246.568722) (xy 333.396844 -246.416322) (xy 333.135224 -246.416322) (xy 333.088234 -246.568722)
			(xy 333.088234 -246.613172) (xy 333.443834 -246.613172)
		)
		(stroke
			(width 0)
			(type solid)
		)
		(fill yes)
		(layer "In2.Cu")
		(net "M_B_CPU0_SB_PAR")
	)
	(gr_poly
		(pts
			(xy 333.443834 -246.16029) (xy 333.443834 -246.11584) (xy 333.088234 -246.11584) (xy 333.088234 -246.16029)
			(xy 333.135224 -246.31269) (xy 333.396844 -246.31269)
		)
		(stroke
			(width 0)
			(type solid)
		)
		(fill yes)
		(layer "In2.Cu")
		(net "M_B_CPU0_SB_CS_N<0>")
	)
	(gr_poly
		(pts
			(xy 333.443834 -241.276886) (xy 333.443834 -241.232436) (xy 333.088234 -241.232436) (xy 333.088234 -241.276886)
			(xy 333.135224 -241.429286) (xy 333.396844 -241.429286)
		)
		(stroke
			(width 0)
			(type solid)
		)
		(fill yes)
		(layer "In2.Cu")
		(net "M_B_CPU0_SB_CB<2>")
	)
	(gr_poly
		(pts
			(xy 333.443834 -238.430054) (xy 333.396844 -238.277654) (xy 333.135224 -238.277654) (xy 333.088234 -238.430054)
			(xy 333.088234 -238.47425) (xy 333.443834 -238.47425)
		)
		(stroke
			(width 0)
			(type solid)
		)
		(fill yes)
		(layer "In2.Cu")
		(net "M_A_CPU0_SB_DQ<3>")
	)
	(gr_poly
		(pts
			(xy 333.443834 -236.393482) (xy 333.443834 -236.349286) (xy 333.088234 -236.349286) (xy 333.088234 -236.393482)
			(xy 333.135224 -236.545882) (xy 333.396844 -236.545882)
		)
		(stroke
			(width 0)
			(type solid)
		)
		(fill yes)
		(layer "In2.Cu")
		(net "M_A_CPU0_SB_DQ<4>")
	)
	(gr_poly
		(pts
			(xy 333.443834 -231.510078) (xy 333.443834 -231.465882) (xy 333.088234 -231.465882) (xy 333.088234 -231.510078)
			(xy 333.135224 -231.662478) (xy 333.396844 -231.662478)
		)
		(stroke
			(width 0)
			(type solid)
		)
		(fill yes)
		(layer "In2.Cu")
		(net "M_B_CPU0_SB_DQ<12>")
	)
	(gr_poly
		(pts
			(xy 333.448406 -277.079964) (xy 333.410052 -277.057866) (xy 333.254604 -277.022306) (xy 333.123794 -277.248874)
			(xy 333.232252 -277.365714) (xy 333.270606 -277.387812)
		)
		(stroke
			(width 0)
			(type solid)
		)
		(fill yes)
		(layer "In2.Cu")
		(net "M_B_CPU0_SA_DQ<6>")
	)
	(gr_poly
		(pts
			(xy 333.449422 -275.450046) (xy 333.411068 -275.427948) (xy 333.25562 -275.392388) (xy 333.12481 -275.618956)
			(xy 333.233268 -275.735796) (xy 333.271622 -275.757894)
		)
		(stroke
			(width 0)
			(type solid)
		)
		(fill yes)
		(layer "In2.Cu")
		(net "M_B_CPU0_SA_DQ<6>")
	)
	(gr_poly
		(pts
			(xy 333.452216 -243.31295) (xy 333.405226 -243.16055) (xy 333.143606 -243.16055) (xy 333.096616 -243.31295)
			(xy 333.096616 -243.3574) (xy 333.452216 -243.3574)
		)
		(stroke
			(width 0)
			(type solid)
		)
		(fill yes)
		(layer "In2.Cu")
		(net "M_B_CPU0_SB_CB<5>")
	)
	(gr_poly
		(pts
			(xy 333.452216 -238.021622) (xy 333.452216 -237.977172) (xy 333.096616 -237.977172) (xy 333.096616 -238.021622)
			(xy 333.143606 -238.174022) (xy 333.405226 -238.174022)
		)
		(stroke
			(width 0)
			(type solid)
		)
		(fill yes)
		(layer "In2.Cu")
		(net "M_A_CPU0_SB_DQS_DP<0>")
	)
	(gr_poly
		(pts
			(xy 333.452216 -236.801914) (xy 333.405226 -236.649514) (xy 333.143606 -236.649514) (xy 333.096616 -236.801914)
			(xy 333.096616 -236.846364) (xy 333.452216 -236.846364)
		)
		(stroke
			(width 0)
			(type solid)
		)
		(fill yes)
		(layer "In2.Cu")
		(net "M_A_CPU0_SB_DQS_DP<5>")
	)
	(gr_poly
		(pts
			(xy 333.452216 -233.546142) (xy 333.405226 -233.393742) (xy 333.143606 -233.393742) (xy 333.096616 -233.546142)
			(xy 333.096616 -233.590592) (xy 333.452216 -233.590592)
		)
		(stroke
			(width 0)
			(type solid)
		)
		(fill yes)
		(layer "In2.Cu")
		(net "M_B_CPU0_SB_DQ<11>")
	)
	(gr_poly
		(pts
			(xy 333.452216 -233.138218) (xy 333.452216 -233.093768) (xy 333.096616 -233.093768) (xy 333.096616 -233.138218)
			(xy 333.143606 -233.290618) (xy 333.405226 -233.290618)
		)
		(stroke
			(width 0)
			(type solid)
		)
		(fill yes)
		(layer "In2.Cu")
		(net "M_B_CPU0_SB_DQS_DP<1>")
	)
	(gr_poly
		(pts
			(xy 333.452216 -231.91851) (xy 333.405226 -231.76611) (xy 333.143606 -231.76611) (xy 333.096616 -231.91851)
			(xy 333.096616 -231.96296) (xy 333.452216 -231.96296)
		)
		(stroke
			(width 0)
			(type solid)
		)
		(fill yes)
		(layer "In2.Cu")
		(net "M_B_CPU0_SB_DQS_DP<6>")
	)
	(gr_poly
		(pts
			(xy 333.452216 -225.407474) (xy 333.405226 -225.255074) (xy 333.143606 -225.255074) (xy 333.096616 -225.407474)
			(xy 333.096616 -225.45167) (xy 333.452216 -225.45167)
		)
		(stroke
			(width 0)
			(type solid)
		)
		(fill yes)
		(layer "In2.Cu")
		(net "M_B_CPU0_SB_DQ<19>")
	)
	(gr_poly
		(pts
			(xy 333.553562 -267.551662) (xy 333.553562 -267.507212) (xy 333.197962 -267.507212) (xy 333.197962 -267.551662)
			(xy 333.244952 -267.704062) (xy 333.506572 -267.704062)
		)
		(stroke
			(width 0)
			(type solid)
		)
		(fill yes)
		(layer "In2.Cu")
		(net "M_B_CPU0_SA_DQ<16>")
	)
	(gr_poly
		(pts
			(xy 333.553562 -266.332462) (xy 333.506572 -266.180062) (xy 333.244952 -266.180062) (xy 333.197962 -266.332462)
			(xy 333.197962 -266.376658) (xy 333.553562 -266.376658)
		)
		(stroke
			(width 0)
			(type solid)
		)
		(fill yes)
		(layer "In2.Cu")
		(net "M_B_CPU0_SA_DQ<19>")
	)
	(gr_poly
		(pts
			(xy 333.553562 -265.923014) (xy 333.553562 -265.878818) (xy 333.197962 -265.878818) (xy 333.197962 -265.923014)
			(xy 333.244952 -266.075414) (xy 333.506572 -266.075414)
		)
		(stroke
			(width 0)
			(type solid)
		)
		(fill yes)
		(layer "In2.Cu")
		(net "M_B_CPU0_SA_DQS_DP<2>")
	)
	(gr_poly
		(pts
			(xy 333.553562 -264.70483) (xy 333.506572 -264.55243) (xy 333.244952 -264.55243) (xy 333.197962 -264.70483)
			(xy 333.197962 -264.749026) (xy 333.553562 -264.749026)
		)
		(stroke
			(width 0)
			(type solid)
		)
		(fill yes)
		(layer "In2.Cu")
		(net "M_B_CPU0_SA_DQS_DP<7>")
	)
	(gr_poly
		(pts
			(xy 333.553562 -264.29589) (xy 333.553562 -264.251694) (xy 333.197962 -264.251694) (xy 333.197962 -264.29589)
			(xy 333.244952 -264.44829) (xy 333.506572 -264.44829)
		)
		(stroke
			(width 0)
			(type solid)
		)
		(fill yes)
		(layer "In2.Cu")
		(net "M_B_CPU0_SA_DQ<20>")
	)
	(gr_poly
		(pts
			(xy 333.553562 -263.07669) (xy 333.506572 -262.92429) (xy 333.244952 -262.92429) (xy 333.197962 -263.07669)
			(xy 333.197962 -263.12114) (xy 333.553562 -263.12114)
		)
		(stroke
			(width 0)
			(type solid)
		)
		(fill yes)
		(layer "In2.Cu")
		(net "M_B_CPU0_SA_DQ<23>")
	)
	(gr_poly
		(pts
			(xy 333.553562 -262.668258) (xy 333.553562 -262.623808) (xy 333.197962 -262.623808) (xy 333.197962 -262.668258)
			(xy 333.244952 -262.820658) (xy 333.506572 -262.820658)
		)
		(stroke
			(width 0)
			(type solid)
		)
		(fill yes)
		(layer "In2.Cu")
		(net "M_B_CPU0_SA_CB<0>")
	)
	(gr_poly
		(pts
			(xy 333.553562 -261.449058) (xy 333.506572 -261.296658) (xy 333.244952 -261.296658) (xy 333.197962 -261.449058)
			(xy 333.197962 -261.493508) (xy 333.553562 -261.493508)
		)
		(stroke
			(width 0)
			(type solid)
		)
		(fill yes)
		(layer "In2.Cu")
		(net "M_B_CPU0_SA_CB<3>")
	)
	(gr_poly
		(pts
			(xy 333.553562 -261.040626) (xy 333.553562 -260.996176) (xy 333.197962 -260.996176) (xy 333.197962 -261.040626)
			(xy 333.244952 -261.193026) (xy 333.506572 -261.193026)
		)
		(stroke
			(width 0)
			(type solid)
		)
		(fill yes)
		(layer "In2.Cu")
		(net "M_B_CPU0_SA_DQS_DP<4>")
	)
	(gr_poly
		(pts
			(xy 333.553562 -259.821426) (xy 333.506572 -259.669026) (xy 333.244952 -259.669026) (xy 333.197962 -259.821426)
			(xy 333.197962 -259.865622) (xy 333.553562 -259.865622)
		)
		(stroke
			(width 0)
			(type solid)
		)
		(fill yes)
		(layer "In2.Cu")
		(net "M_B_CPU0_SA_DQS_DP<9>")
	)
	(gr_poly
		(pts
			(xy 333.553562 -259.412486) (xy 333.553562 -259.36829) (xy 333.197962 -259.36829) (xy 333.197962 -259.412486)
			(xy 333.244952 -259.564886) (xy 333.506572 -259.564886)
		)
		(stroke
			(width 0)
			(type solid)
		)
		(fill yes)
		(layer "In2.Cu")
		(net "M_B_CPU0_SA_CB<4>")
	)
	(gr_poly
		(pts
			(xy 333.553562 -258.193286) (xy 333.506572 -258.040886) (xy 333.244952 -258.040886) (xy 333.197962 -258.193286)
			(xy 333.197962 -258.237736) (xy 333.553562 -258.237736)
		)
		(stroke
			(width 0)
			(type solid)
		)
		(fill yes)
		(layer "In2.Cu")
		(net "M_B_CPU0_SA_CB<7>")
	)
	(gr_poly
		(pts
			(xy 333.553562 -257.784854) (xy 333.553562 -257.740404) (xy 333.197962 -257.740404) (xy 333.197962 -257.784854)
			(xy 333.244952 -257.937254) (xy 333.506572 -257.937254)
		)
		(stroke
			(width 0)
			(type solid)
		)
		(fill yes)
		(layer "In2.Cu")
		(net "M_B_CPU0_ALERT_N")
	)
	(gr_poly
		(pts
			(xy 333.553562 -256.565654) (xy 333.506572 -256.413254) (xy 333.244952 -256.413254) (xy 333.197962 -256.565654)
			(xy 333.197962 -256.610104) (xy 333.553562 -256.610104)
		)
		(stroke
			(width 0)
			(type solid)
		)
		(fill yes)
		(layer "In2.Cu")
		(net "M_B_CPU0_SA_CS_N<3>")
	)
	(gr_poly
		(pts
			(xy 333.553562 -256.157222) (xy 333.553562 -256.112772) (xy 333.197962 -256.112772) (xy 333.197962 -256.157222)
			(xy 333.244952 -256.309622) (xy 333.506572 -256.309622)
		)
		(stroke
			(width 0)
			(type solid)
		)
		(fill yes)
		(layer "In2.Cu")
		(net "M_B_CPU0_SA_CS_N<1>")
	)
	(gr_poly
		(pts
			(xy 333.553562 -254.938022) (xy 333.506572 -254.785622) (xy 333.244952 -254.785622) (xy 333.197962 -254.938022)
			(xy 333.197962 -254.982218) (xy 333.553562 -254.982218)
		)
		(stroke
			(width 0)
			(type solid)
		)
		(fill yes)
		(layer "In2.Cu")
		(net "M_B_CPU0_SA_CA<2>")
	)
	(gr_poly
		(pts
			(xy 333.553562 -254.529082) (xy 333.553562 -254.484886) (xy 333.197962 -254.484886) (xy 333.197962 -254.529082)
			(xy 333.244952 -254.681482) (xy 333.506572 -254.681482)
		)
		(stroke
			(width 0)
			(type solid)
		)
		(fill yes)
		(layer "In2.Cu")
		(net "M_B_CPU0_SA_CA<3>")
	)
	(gr_poly
		(pts
			(xy 333.63281 -274.531582) (xy 333.524352 -274.414742) (xy 333.485998 -274.392644) (xy 333.308198 -274.700492)
			(xy 333.346552 -274.72259) (xy 333.502 -274.75815)
		)
		(stroke
			(width 0)
			(type solid)
		)
		(fill yes)
		(layer "In2.Cu")
		(net "M_B_CPU0_SA_DQ<5>")
	)
	(gr_poly
		(pts
			(xy 333.763112 -226.469956) (xy 333.801466 -226.447858) (xy 333.623666 -226.14001) (xy 333.585312 -226.162108)
			(xy 333.476854 -226.278948) (xy 333.607664 -226.505516)
		)
		(stroke
			(width 0)
			(type solid)
		)
		(fill yes)
		(layer "In2.Cu")
		(net "M_B_CPU0_SB_DQ<17>")
	)
	(gr_poly
		(pts
			(xy 333.763112 -224.84207) (xy 333.801466 -224.819972) (xy 333.623666 -224.512124) (xy 333.585312 -224.534222)
			(xy 333.476854 -224.651062) (xy 333.607664 -224.87763)
		)
		(stroke
			(width 0)
			(type solid)
		)
		(fill yes)
		(layer "In2.Cu")
		(net "M_B_CPU0_SB_DQS_DP<2>")
	)
	(gr_poly
		(pts
			(xy 333.7687 -228.106986) (xy 333.807054 -228.084888) (xy 333.629254 -227.77704) (xy 333.5909 -227.799138)
			(xy 333.482442 -227.915978) (xy 333.613252 -228.142546)
		)
		(stroke
			(width 0)
			(type solid)
		)
		(fill yes)
		(layer "In2.Cu")
		(net "M_B_CPU0_SB_DQ<16>")
	)
	(gr_poly
		(pts
			(xy 333.7687 -223.223582) (xy 333.807054 -223.201484) (xy 333.629254 -222.893636) (xy 333.5909 -222.915734)
			(xy 333.482442 -223.032574) (xy 333.613252 -223.259142)
		)
		(stroke
			(width 0)
			(type solid)
		)
		(fill yes)
		(layer "In2.Cu")
		(net "M_B_CPU0_SB_DQS_DN<7>")
	)
	(gr_poly
		(pts
			(xy 333.87919 -225.860356) (xy 333.987648 -225.743516) (xy 333.856838 -225.516948) (xy 333.70139 -225.552508)
			(xy 333.663036 -225.574606) (xy 333.840836 -225.882454)
		)
		(stroke
			(width 0)
			(type solid)
		)
		(fill yes)
		(layer "In2.Cu")
		(net "M_B_CPU0_SB_DQ<19>")
	)
	(gr_poly
		(pts
			(xy 333.884524 -227.497386) (xy 333.992982 -227.380546) (xy 333.862172 -227.153978) (xy 333.706724 -227.189538)
			(xy 333.66837 -227.211636) (xy 333.84617 -227.519484)
		)
		(stroke
			(width 0)
			(type solid)
		)
		(fill yes)
		(layer "In2.Cu")
		(net "M_B_CPU0_SB_DQ<18>")
	)
	(gr_poly
		(pts
			(xy 333.884524 -224.241868) (xy 333.992982 -224.125028) (xy 333.862172 -223.89846) (xy 333.706724 -223.93402)
			(xy 333.66837 -223.956118) (xy 333.84617 -224.263966)
		)
		(stroke
			(width 0)
			(type solid)
		)
		(fill yes)
		(layer "In2.Cu")
		(net "M_B_CPU0_SB_DQS_DN<2>")
	)
	(gr_poly
		(pts
			(xy 333.907638 -242.090702) (xy 333.907638 -242.046506) (xy 333.552038 -242.046506) (xy 333.552038 -242.090702)
			(xy 333.599028 -242.243102) (xy 333.860648 -242.243102)
		)
		(stroke
			(width 0)
			(type solid)
		)
		(fill yes)
		(layer "In2.Cu")
		(net "M_B_CPU0_SB_DQS_DP<9>")
	)
	(gr_poly
		(pts
			(xy 333.907638 -237.61573) (xy 333.860648 -237.46333) (xy 333.599028 -237.46333) (xy 333.552038 -237.61573)
			(xy 333.552038 -237.66018) (xy 333.907638 -237.66018)
		)
		(stroke
			(width 0)
			(type solid)
		)
		(fill yes)
		(layer "In2.Cu")
		(net "M_A_CPU0_SB_DQS_DN<0>")
	)
	(gr_poly
		(pts
			(xy 333.907638 -237.207806) (xy 333.907638 -237.163356) (xy 333.552038 -237.163356) (xy 333.552038 -237.207806)
			(xy 333.599028 -237.360206) (xy 333.860648 -237.360206)
		)
		(stroke
			(width 0)
			(type solid)
		)
		(fill yes)
		(layer "In2.Cu")
		(net "M_A_CPU0_SB_DQS_DN<5>")
	)
	(gr_poly
		(pts
			(xy 333.907638 -233.952034) (xy 333.907638 -233.907838) (xy 333.552038 -233.907838) (xy 333.552038 -233.952034)
			(xy 333.599028 -234.104434) (xy 333.860648 -234.104434)
		)
		(stroke
			(width 0)
			(type solid)
		)
		(fill yes)
		(layer "In2.Cu")
		(net "M_B_CPU0_SB_DQ<9>")
	)
	(gr_poly
		(pts
			(xy 333.907638 -232.732326) (xy 333.860648 -232.579926) (xy 333.599028 -232.579926) (xy 333.552038 -232.732326)
			(xy 333.552038 -232.776776) (xy 333.907638 -232.776776)
		)
		(stroke
			(width 0)
			(type solid)
		)
		(fill yes)
		(layer "In2.Cu")
		(net "M_B_CPU0_SB_DQS_DN<1>")
	)
	(gr_poly
		(pts
			(xy 333.907638 -232.324402) (xy 333.907638 -232.279952) (xy 333.552038 -232.279952) (xy 333.552038 -232.324402)
			(xy 333.599028 -232.476802) (xy 333.860648 -232.476802)
		)
		(stroke
			(width 0)
			(type solid)
		)
		(fill yes)
		(layer "In2.Cu")
		(net "M_B_CPU0_SB_DQS_DN<6>")
	)
	(gr_poly
		(pts
			(xy 333.912972 -274.647152) (xy 333.874618 -274.625054) (xy 333.71917 -274.589494) (xy 333.58836 -274.816062)
			(xy 333.696818 -274.932902) (xy 333.735172 -274.955)
		)
		(stroke
			(width 0)
			(type solid)
		)
		(fill yes)
		(layer "In2.Cu")
		(net "M_B_CPU0_SA_DQ<6>")
	)
	(gr_poly
		(pts
			(xy 333.91348 -235.988098) (xy 333.86649 -235.835698) (xy 333.60487 -235.835698) (xy 333.55788 -235.988098)
			(xy 333.55788 -236.032548) (xy 333.91348 -236.032548)
		)
		(stroke
			(width 0)
			(type solid)
		)
		(fill yes)
		(layer "In2.Cu")
		(net "M_A_CPU0_SB_DQ<6>")
	)
	(gr_poly
		(pts
			(xy 333.913734 -247.382538) (xy 333.866744 -247.230138) (xy 333.605124 -247.230138) (xy 333.558134 -247.382538)
			(xy 333.558134 -247.426988) (xy 333.913734 -247.426988)
		)
		(stroke
			(width 0)
			(type solid)
		)
		(fill yes)
		(layer "In2.Cu")
		(net "M_B_CPU0_SB_CA<5>")
	)
	(gr_poly
		(pts
			(xy 333.913734 -246.974106) (xy 333.913734 -246.929656) (xy 333.558134 -246.929656) (xy 333.558134 -246.974106)
			(xy 333.605124 -247.126506) (xy 333.866744 -247.126506)
		)
		(stroke
			(width 0)
			(type solid)
		)
		(fill yes)
		(layer "In2.Cu")
		(net "M_B_CPU0_SB_CA<6>")
	)
	(gr_poly
		(pts
			(xy 333.913734 -245.754906) (xy 333.866744 -245.602506) (xy 333.605124 -245.602506) (xy 333.558134 -245.754906)
			(xy 333.558134 -245.799356) (xy 333.913734 -245.799356)
		)
		(stroke
			(width 0)
			(type solid)
		)
		(fill yes)
		(layer "In2.Cu")
		(net "M_B_CPU0_SB_CS_N<2>")
	)
	(gr_poly
		(pts
			(xy 333.913734 -243.718334) (xy 333.913734 -243.674138) (xy 333.558134 -243.674138) (xy 333.558134 -243.718334)
			(xy 333.605124 -243.870734) (xy 333.866744 -243.870734)
		)
		(stroke
			(width 0)
			(type solid)
		)
		(fill yes)
		(layer "In2.Cu")
		(net "M_B_CPU0_SB_CB<7>")
	)
	(gr_poly
		(pts
			(xy 333.913734 -240.871502) (xy 333.866744 -240.719102) (xy 333.605124 -240.719102) (xy 333.558134 -240.871502)
			(xy 333.558134 -240.915952) (xy 333.913734 -240.915952)
		)
		(stroke
			(width 0)
			(type solid)
		)
		(fill yes)
		(layer "In2.Cu")
		(net "M_B_CPU0_SB_CB<0>")
	)
	(gr_poly
		(pts
			(xy 333.913734 -238.83493) (xy 333.913734 -238.790734) (xy 333.558134 -238.790734) (xy 333.558134 -238.83493)
			(xy 333.605124 -238.98733) (xy 333.866744 -238.98733)
		)
		(stroke
			(width 0)
			(type solid)
		)
		(fill yes)
		(layer "In2.Cu")
		(net "M_A_CPU0_SB_DQ<1>")
	)
	(gr_poly
		(pts
			(xy 333.913734 -231.104694) (xy 333.866744 -230.952294) (xy 333.605124 -230.952294) (xy 333.558134 -231.104694)
			(xy 333.558134 -231.149144) (xy 333.913734 -231.149144)
		)
		(stroke
			(width 0)
			(type solid)
		)
		(fill yes)
		(layer "In2.Cu")
		(net "M_B_CPU0_SB_DQ<14>")
	)
	(gr_poly
		(pts
			(xy 333.917798 -273.012408) (xy 333.879444 -272.99031) (xy 333.723996 -272.95475) (xy 333.593186 -273.181318)
			(xy 333.701644 -273.298158) (xy 333.739998 -273.320256)
		)
		(stroke
			(width 0)
			(type solid)
		)
		(fill yes)
		(layer "In2.Cu")
		(net "M_B_CPU0_SA_DQ<7>")
	)
	(gr_poly
		(pts
			(xy 333.922116 -245.346474) (xy 333.922116 -245.302278) (xy 333.566516 -245.302278) (xy 333.566516 -245.346474)
			(xy 333.613506 -245.498874) (xy 333.875126 -245.498874)
		)
		(stroke
			(width 0)
			(type solid)
		)
		(fill yes)
		(layer "In2.Cu")
		(net "M_B_CPU0_SB_CS_N<3>")
	)
	(gr_poly
		(pts
			(xy 333.922116 -244.126766) (xy 333.875126 -243.974366) (xy 333.613506 -243.974366) (xy 333.566516 -244.126766)
			(xy 333.566516 -244.171216) (xy 333.922116 -244.171216)
		)
		(stroke
			(width 0)
			(type solid)
		)
		(fill yes)
		(layer "In2.Cu")
		(net "M_B_CPU0_SB_CB<4>")
	)
	(gr_poly
		(pts
			(xy 333.922116 -240.46307) (xy 333.922116 -240.418874) (xy 333.566516 -240.418874) (xy 333.566516 -240.46307)
			(xy 333.613506 -240.61547) (xy 333.875126 -240.61547)
		)
		(stroke
			(width 0)
			(type solid)
		)
		(fill yes)
		(layer "In2.Cu")
		(net "M_B_CPU0_SB_CB<3>")
	)
	(gr_poly
		(pts
			(xy 333.922116 -239.243362) (xy 333.875126 -239.090962) (xy 333.613506 -239.090962) (xy 333.566516 -239.243362)
			(xy 333.566516 -239.287812) (xy 333.922116 -239.287812)
		)
		(stroke
			(width 0)
			(type solid)
		)
		(fill yes)
		(layer "In2.Cu")
		(net "M_A_CPU0_SB_DQ<2>")
	)
	(gr_poly
		(pts
			(xy 333.922116 -235.579666) (xy 333.922116 -235.53547) (xy 333.566516 -235.53547) (xy 333.566516 -235.579666)
			(xy 333.613506 -235.732066) (xy 333.875126 -235.732066)
		)
		(stroke
			(width 0)
			(type solid)
		)
		(fill yes)
		(layer "In2.Cu")
		(net "M_A_CPU0_SB_DQ<5>")
	)
	(gr_poly
		(pts
			(xy 333.922116 -234.360466) (xy 333.875126 -234.208066) (xy 333.613506 -234.208066) (xy 333.566516 -234.360466)
			(xy 333.566516 -234.404662) (xy 333.922116 -234.404662)
		)
		(stroke
			(width 0)
			(type solid)
		)
		(fill yes)
		(layer "In2.Cu")
		(net "M_B_CPU0_SB_DQ<10>")
	)
	(gr_poly
		(pts
			(xy 333.922116 -230.696262) (xy 333.922116 -230.652066) (xy 333.566516 -230.652066) (xy 333.566516 -230.696262)
			(xy 333.613506 -230.848662) (xy 333.875126 -230.848662)
		)
		(stroke
			(width 0)
			(type solid)
		)
		(fill yes)
		(layer "In2.Cu")
		(net "M_B_CPU0_SB_DQ<13>")
	)
	(gr_poly
		(pts
			(xy 333.923132 -242.499134) (xy 333.876142 -242.346734) (xy 333.614522 -242.346734) (xy 333.567532 -242.499134)
			(xy 333.567532 -242.54333) (xy 333.923132 -242.54333)
		)
		(stroke
			(width 0)
			(type solid)
		)
		(fill yes)
		(layer "In2.Cu")
		(net "M_B_CPU0_SB_DQS_DP<4>")
	)
	(gr_poly
		(pts
			(xy 333.994252 -276.560788) (xy 334.10271 -276.443948) (xy 333.9719 -276.21738) (xy 333.816452 -276.25294)
			(xy 333.778098 -276.275038) (xy 333.955898 -276.582886)
		)
		(stroke
			(width 0)
			(type solid)
		)
		(fill yes)
		(layer "In2.Cu")
		(net "M_B_CPU0_SA_DQ<4>")
	)
	(gr_poly
		(pts
			(xy 334.023462 -267.146278) (xy 333.976472 -266.993878) (xy 333.714852 -266.993878) (xy 333.667862 -267.146278)
			(xy 333.667862 -267.190474) (xy 334.023462 -267.190474)
		)
		(stroke
			(width 0)
			(type solid)
		)
		(fill yes)
		(layer "In2.Cu")
		(net "M_B_CPU0_SA_DQ<18>")
	)
	(gr_poly
		(pts
			(xy 334.023462 -266.737846) (xy 334.023462 -266.693396) (xy 333.667862 -266.693396) (xy 333.667862 -266.737846)
			(xy 333.714852 -266.890246) (xy 333.976472 -266.890246)
		)
		(stroke
			(width 0)
			(type solid)
		)
		(fill yes)
		(layer "In2.Cu")
		(net "M_B_CPU0_SA_DQ<17>")
	)
	(gr_poly
		(pts
			(xy 334.023462 -265.518646) (xy 333.976472 -265.366246) (xy 333.714852 -265.366246) (xy 333.667862 -265.518646)
			(xy 333.667862 -265.562842) (xy 334.023462 -265.562842)
		)
		(stroke
			(width 0)
			(type solid)
		)
		(fill yes)
		(layer "In2.Cu")
		(net "M_B_CPU0_SA_DQS_DN<2>")
	)
	(gr_poly
		(pts
			(xy 334.023462 -265.109706) (xy 334.023462 -265.06551) (xy 333.667862 -265.06551) (xy 333.667862 -265.109706)
			(xy 333.714852 -265.262106) (xy 333.976472 -265.262106)
		)
		(stroke
			(width 0)
			(type solid)
		)
		(fill yes)
		(layer "In2.Cu")
		(net "M_B_CPU0_SA_DQS_DN<7>")
	)
	(gr_poly
		(pts
			(xy 334.023462 -263.891014) (xy 333.976472 -263.738614) (xy 333.714852 -263.738614) (xy 333.667862 -263.891014)
			(xy 333.667862 -263.93521) (xy 334.023462 -263.93521)
		)
		(stroke
			(width 0)
			(type solid)
		)
		(fill yes)
		(layer "In2.Cu")
		(net "M_B_CPU0_SA_DQ<22>")
	)
	(gr_poly
		(pts
			(xy 334.023462 -263.482074) (xy 334.023462 -263.437878) (xy 333.667862 -263.437878) (xy 333.667862 -263.482074)
			(xy 333.714852 -263.634474) (xy 333.976472 -263.634474)
		)
		(stroke
			(width 0)
			(type solid)
		)
		(fill yes)
		(layer "In2.Cu")
		(net "M_B_CPU0_SA_DQ<21>")
	)
	(gr_poly
		(pts
			(xy 334.023462 -262.262874) (xy 333.976472 -262.110474) (xy 333.714852 -262.110474) (xy 333.667862 -262.262874)
			(xy 333.667862 -262.307324) (xy 334.023462 -262.307324)
		)
		(stroke
			(width 0)
			(type solid)
		)
		(fill yes)
		(layer "In2.Cu")
		(net "M_B_CPU0_SA_CB<2>")
	)
	(gr_poly
		(pts
			(xy 334.023462 -261.854442) (xy 334.023462 -261.810246) (xy 333.667862 -261.810246) (xy 333.667862 -261.854442)
			(xy 333.714852 -262.006842) (xy 333.976472 -262.006842)
		)
		(stroke
			(width 0)
			(type solid)
		)
		(fill yes)
		(layer "In2.Cu")
		(net "M_B_CPU0_SA_CB<1>")
	)
	(gr_poly
		(pts
			(xy 334.023462 -260.635242) (xy 333.976472 -260.482842) (xy 333.714852 -260.482842) (xy 333.667862 -260.635242)
			(xy 333.667862 -260.679438) (xy 334.023462 -260.679438)
		)
		(stroke
			(width 0)
			(type solid)
		)
		(fill yes)
		(layer "In2.Cu")
		(net "M_B_CPU0_SA_DQS_DN<4>")
	)
	(gr_poly
		(pts
			(xy 334.023462 -260.226302) (xy 334.023462 -260.182106) (xy 333.667862 -260.182106) (xy 333.667862 -260.226302)
			(xy 333.714852 -260.378702) (xy 333.976472 -260.378702)
		)
		(stroke
			(width 0)
			(type solid)
		)
		(fill yes)
		(layer "In2.Cu")
		(net "M_B_CPU0_SA_DQS_DN<9>")
	)
	(gr_poly
		(pts
			(xy 334.023462 -259.00761) (xy 333.976472 -258.85521) (xy 333.714852 -258.85521) (xy 333.667862 -259.00761)
			(xy 333.667862 -259.051806) (xy 334.023462 -259.051806)
		)
		(stroke
			(width 0)
			(type solid)
		)
		(fill yes)
		(layer "In2.Cu")
		(net "M_B_CPU0_SA_CB<6>")
	)
	(gr_poly
		(pts
			(xy 334.023462 -258.59867) (xy 334.023462 -258.554474) (xy 333.667862 -258.554474) (xy 333.667862 -258.59867)
			(xy 333.714852 -258.75107) (xy 333.976472 -258.75107)
		)
		(stroke
			(width 0)
			(type solid)
		)
		(fill yes)
		(layer "In2.Cu")
		(net "M_B_CPU0_SA_CB<5>")
	)
	(gr_poly
		(pts
			(xy 334.023462 -257.37947) (xy 333.976472 -257.22707) (xy 333.714852 -257.22707) (xy 333.667862 -257.37947)
			(xy 333.667862 -257.42392) (xy 334.023462 -257.42392)
		)
		(stroke
			(width 0)
			(type solid)
		)
		(fill yes)
		(layer "In2.Cu")
		(net "M_B_CPU0_SA_CS_N<0>")
	)
	(gr_poly
		(pts
			(xy 334.023462 -256.971038) (xy 334.023462 -256.926588) (xy 333.667862 -256.926588) (xy 333.667862 -256.971038)
			(xy 333.714852 -257.123438) (xy 333.976472 -257.123438)
		)
		(stroke
			(width 0)
			(type solid)
		)
		(fill yes)
		(layer "In2.Cu")
		(net "M_B_CPU0_SA_CS_N<2>")
	)
	(gr_poly
		(pts
			(xy 334.023462 -255.751838) (xy 333.976472 -255.599438) (xy 333.714852 -255.599438) (xy 333.667862 -255.751838)
			(xy 333.667862 -255.796288) (xy 334.023462 -255.796288)
		)
		(stroke
			(width 0)
			(type solid)
		)
		(fill yes)
		(layer "In2.Cu")
		(net "M_B_CPU0_SA_CA<0>")
	)
	(gr_poly
		(pts
			(xy 334.023462 -255.343406) (xy 334.023462 -255.298956) (xy 333.667862 -255.298956) (xy 333.667862 -255.343406)
			(xy 333.714852 -255.495806) (xy 333.976472 -255.495806)
		)
		(stroke
			(width 0)
			(type solid)
		)
		(fill yes)
		(layer "In2.Cu")
		(net "M_B_CPU0_SA_CA<1>")
	)
	(gr_poly
		(pts
			(xy 334.023462 -254.124206) (xy 333.976472 -253.971806) (xy 333.714852 -253.971806) (xy 333.667862 -254.124206)
			(xy 333.667862 -254.168402) (xy 334.023462 -254.168402)
		)
		(stroke
			(width 0)
			(type solid)
		)
		(fill yes)
		(layer "In2.Cu")
		(net "M_B_CPU0_SA_CA<4>")
	)
	(gr_poly
		(pts
			(xy 334.031844 -253.715774) (xy 334.031844 -253.671324) (xy 333.676244 -253.671324) (xy 333.676244 -253.715774)
			(xy 333.723234 -253.868174) (xy 333.984854 -253.868174)
		)
		(stroke
			(width 0)
			(type solid)
		)
		(fill yes)
		(layer "In2.Cu")
		(net "M_B_CPU0_SA_CA<5>")
	)
	(gr_poly
		(pts
			(xy 334.096106 -275.356574) (xy 333.987648 -275.239734) (xy 333.949294 -275.217636) (xy 333.771494 -275.525484)
			(xy 333.809848 -275.547582) (xy 333.965296 -275.583142)
		)
		(stroke
			(width 0)
			(type solid)
		)
		(fill yes)
		(layer "In2.Cu")
		(net "M_B_CPU0_SA_DQ<4>")
	)
	(gr_poly
		(pts
			(xy 334.097376 -276.982428) (xy 333.988918 -276.865588) (xy 333.950564 -276.84349) (xy 333.772764 -277.151338)
			(xy 333.811118 -277.173436) (xy 333.966566 -277.208996)
		)
		(stroke
			(width 0)
			(type solid)
		)
		(fill yes)
		(layer "In2.Cu")
		(net "M_B_CPU0_SA_DQ<4>")
	)
	(gr_poly
		(pts
			(xy 334.102964 -273.717766) (xy 333.994506 -273.600926) (xy 333.956152 -273.578828) (xy 333.778352 -273.886676)
			(xy 333.816706 -273.908774) (xy 333.972154 -273.944334)
		)
		(stroke
			(width 0)
			(type solid)
		)
		(fill yes)
		(layer "In2.Cu")
		(net "M_B_CPU0_SA_DQ<5>")
	)
	(gr_poly
		(pts
			(xy 334.23479 -227.28682) (xy 334.273144 -227.264722) (xy 334.095344 -226.956874) (xy 334.05699 -226.978972)
			(xy 333.948532 -227.095812) (xy 334.079342 -227.32238)
		)
		(stroke
			(width 0)
			(type solid)
		)
		(fill yes)
		(layer "In2.Cu")
		(net "M_B_CPU0_SB_DQ<17>")
	)
	(gr_poly
		(pts
			(xy 334.236822 -228.917754) (xy 334.275176 -228.895656) (xy 334.097376 -228.587808) (xy 334.059022 -228.609906)
			(xy 333.950564 -228.726746) (xy 334.081374 -228.953314)
		)
		(stroke
			(width 0)
			(type solid)
		)
		(fill yes)
		(layer "In2.Cu")
		(net "M_B_CPU0_SB_DQ<16>")
	)
	(gr_poly
		(pts
			(xy 334.239362 -224.038414) (xy 334.277716 -224.016316) (xy 334.099916 -223.708468) (xy 334.061562 -223.730566)
			(xy 333.953104 -223.847406) (xy 334.083914 -224.073974)
		)
		(stroke
			(width 0)
			(type solid)
		)
		(fill yes)
		(layer "In2.Cu")
		(net "M_B_CPU0_SB_DQS_DN<7>")
	)
	(gr_poly
		(pts
			(xy 334.241394 -225.67011) (xy 334.279748 -225.648012) (xy 334.101948 -225.340164) (xy 334.063594 -225.362262)
			(xy 333.955136 -225.479102) (xy 334.085946 -225.70567)
		)
		(stroke
			(width 0)
			(type solid)
		)
		(fill yes)
		(layer "In2.Cu")
		(net "M_B_CPU0_SB_DQS_DP<2>")
	)
	(gr_poly
		(pts
			(xy 334.344518 -277.978362) (xy 334.382872 -277.956264) (xy 334.205072 -277.648416) (xy 334.166718 -277.670514)
			(xy 334.05826 -277.787354) (xy 334.18907 -278.013922)
		)
		(stroke
			(width 0)
			(type solid)
		)
		(fill yes)
		(layer "In2.Cu")
		(net "M_B_CPU0_SA_DQS_DP<5>")
	)
	(gr_poly
		(pts
			(xy 334.344518 -276.350476) (xy 334.382872 -276.328378) (xy 334.205072 -276.02053) (xy 334.166718 -276.042628)
			(xy 334.05826 -276.159468) (xy 334.18907 -276.386036)
		)
		(stroke
			(width 0)
			(type solid)
		)
		(fill yes)
		(layer "In2.Cu")
		(net "M_B_CPU0_SA_DQS_DP<5>")
	)
	(gr_poly
		(pts
			(xy 334.348074 -228.300026) (xy 334.456532 -228.183186) (xy 334.325722 -227.956618) (xy 334.170274 -227.992178)
			(xy 334.13192 -228.014276) (xy 334.30972 -228.322124)
		)
		(stroke
			(width 0)
			(type solid)
		)
		(fill yes)
		(layer "In2.Cu")
		(net "M_B_CPU0_SB_DQ<18>")
	)
	(gr_poly
		(pts
			(xy 334.348074 -223.416622) (xy 334.456532 -223.299782) (xy 334.325722 -223.073214) (xy 334.170274 -223.108774)
			(xy 334.13192 -223.130872) (xy 334.30972 -223.43872)
		)
		(stroke
			(width 0)
			(type solid)
		)
		(fill yes)
		(layer "In2.Cu")
		(net "M_B_CPU0_SB_DQS_DP<7>")
	)
	(gr_poly
		(pts
			(xy 334.350106 -226.676204) (xy 334.458564 -226.559364) (xy 334.327754 -226.332796) (xy 334.172306 -226.368356)
			(xy 334.133952 -226.390454) (xy 334.311752 -226.698302)
		)
		(stroke
			(width 0)
			(type solid)
		)
		(fill yes)
		(layer "In2.Cu")
		(net "M_B_CPU0_SB_DQ<19>")
	)
	(gr_poly
		(pts
			(xy 334.350106 -225.048318) (xy 334.458564 -224.931478) (xy 334.327754 -224.70491) (xy 334.172306 -224.74047)
			(xy 334.133952 -224.762568) (xy 334.311752 -225.070416)
		)
		(stroke
			(width 0)
			(type solid)
		)
		(fill yes)
		(layer "In2.Cu")
		(net "M_B_CPU0_SB_DQS_DN<2>")
	)
	(gr_poly
		(pts
			(xy 334.372966 -242.905026) (xy 334.372966 -242.860576) (xy 334.017366 -242.860576) (xy 334.017366 -242.905026)
			(xy 334.064356 -243.057426) (xy 334.325976 -243.057426)
		)
		(stroke
			(width 0)
			(type solid)
		)
		(fill yes)
		(layer "In2.Cu")
		(net "M_B_CPU0_SB_DQS_DN<4>")
	)
	(gr_poly
		(pts
			(xy 334.374998 -249.416062) (xy 334.374998 -249.371612) (xy 334.019398 -249.371612) (xy 334.019398 -249.416062)
			(xy 334.066388 -249.568462) (xy 334.328008 -249.568462)
		)
		(stroke
			(width 0)
			(type solid)
		)
		(fill yes)
		(layer "In2.Cu")
		(net "M_B_CPU0_SB_CA<0>")
	)
	(gr_poly
		(pts
			(xy 334.374998 -244.532658) (xy 334.374998 -244.488208) (xy 334.019398 -244.488208) (xy 334.019398 -244.532658)
			(xy 334.066388 -244.685058) (xy 334.328008 -244.685058)
		)
		(stroke
			(width 0)
			(type solid)
		)
		(fill yes)
		(layer "In2.Cu")
		(net "M_B_CPU0_SB_CB<6>")
	)
	(gr_poly
		(pts
			(xy 334.374998 -240.057178) (xy 334.328008 -239.904778) (xy 334.066388 -239.904778) (xy 334.019398 -240.057178)
			(xy 334.019398 -240.101628) (xy 334.374998 -240.101628)
		)
		(stroke
			(width 0)
			(type solid)
		)
		(fill yes)
		(layer "In2.Cu")
		(net "M_B_CPU0_SB_CB<1>")
	)
	(gr_poly
		(pts
			(xy 334.374998 -239.649254) (xy 334.374998 -239.604804) (xy 334.019398 -239.604804) (xy 334.019398 -239.649254)
			(xy 334.066388 -239.801654) (xy 334.328008 -239.801654)
		)
		(stroke
			(width 0)
			(type solid)
		)
		(fill yes)
		(layer "In2.Cu")
		(net "M_A_CPU0_SB_DQ<0>")
	)
	(gr_poly
		(pts
			(xy 334.374998 -235.174282) (xy 334.328008 -235.021882) (xy 334.066388 -235.021882) (xy 334.019398 -235.174282)
			(xy 334.019398 -235.218478) (xy 334.374998 -235.218478)
		)
		(stroke
			(width 0)
			(type solid)
		)
		(fill yes)
		(layer "In2.Cu")
		(net "M_A_CPU0_SB_DQ<7>")
	)
	(gr_poly
		(pts
			(xy 334.374998 -234.76585) (xy 334.374998 -234.721654) (xy 334.019398 -234.721654) (xy 334.019398 -234.76585)
			(xy 334.066388 -234.91825) (xy 334.328008 -234.91825)
		)
		(stroke
			(width 0)
			(type solid)
		)
		(fill yes)
		(layer "In2.Cu")
		(net "M_B_CPU0_SB_DQ<8>")
	)
	(gr_poly
		(pts
			(xy 334.374998 -230.290878) (xy 334.328008 -230.138478) (xy 334.066388 -230.138478) (xy 334.019398 -230.290878)
			(xy 334.019398 -230.335074) (xy 334.374998 -230.335074)
		)
		(stroke
			(width 0)
			(type solid)
		)
		(fill yes)
		(layer "In2.Cu")
		(net "M_B_CPU0_SB_DQ<15>")
	)
	(gr_poly
		(pts
			(xy 334.383126 -273.833336) (xy 334.344772 -273.811238) (xy 334.189324 -273.775678) (xy 334.058514 -274.002246)
			(xy 334.166972 -274.119086) (xy 334.205326 -274.141184)
		)
		(stroke
			(width 0)
			(type solid)
		)
		(fill yes)
		(layer "In2.Cu")
		(net "M_B_CPU0_SA_DQ<6>")
	)
	(gr_poly
		(pts
			(xy 334.38338 -236.393482) (xy 334.38338 -236.349032) (xy 334.02778 -236.349032) (xy 334.02778 -236.393482)
			(xy 334.07477 -236.545882) (xy 334.33639 -236.545882)
		)
		(stroke
			(width 0)
			(type solid)
		)
		(fill yes)
		(layer "In2.Cu")
		(net "M_A_CPU0_SB_DQ<4>")
	)
	(gr_poly
		(pts
			(xy 334.383634 -248.196354) (xy 334.336644 -248.043954) (xy 334.075024 -248.043954) (xy 334.028034 -248.196354)
			(xy 334.028034 -248.240804) (xy 334.383634 -248.240804)
		)
		(stroke
			(width 0)
			(type solid)
		)
		(fill yes)
		(layer "In2.Cu")
		(net "M_B_CPU0_SB_CA<3>")
	)
	(gr_poly
		(pts
			(xy 334.383634 -247.787922) (xy 334.383634 -247.743472) (xy 334.028034 -247.743472) (xy 334.028034 -247.787922)
			(xy 334.075024 -247.940322) (xy 334.336644 -247.940322)
		)
		(stroke
			(width 0)
			(type solid)
		)
		(fill yes)
		(layer "In2.Cu")
		(net "M_B_CPU0_SB_CA<4>")
	)
	(gr_poly
		(pts
			(xy 334.383634 -246.568722) (xy 334.336644 -246.416322) (xy 334.075024 -246.416322) (xy 334.028034 -246.568722)
			(xy 334.028034 -246.613172) (xy 334.383634 -246.613172)
		)
		(stroke
			(width 0)
			(type solid)
		)
		(fill yes)
		(layer "In2.Cu")
		(net "M_B_CPU0_SB_PAR")
	)
	(gr_poly
		(pts
			(xy 334.383634 -246.16029) (xy 334.383634 -246.11584) (xy 334.028034 -246.11584) (xy 334.028034 -246.16029)
			(xy 334.075024 -246.31269) (xy 334.336644 -246.31269)
		)
		(stroke
			(width 0)
			(type solid)
		)
		(fill yes)
		(layer "In2.Cu")
		(net "M_B_CPU0_SB_CS_N<0>")
	)
	(gr_poly
		(pts
			(xy 334.383634 -243.313458) (xy 334.336644 -243.161058) (xy 334.075024 -243.161058) (xy 334.028034 -243.313458)
			(xy 334.028034 -243.357654) (xy 334.383634 -243.357654)
		)
		(stroke
			(width 0)
			(type solid)
		)
		(fill yes)
		(layer "In2.Cu")
		(net "M_B_CPU0_SB_CB<5>")
	)
	(gr_poly
		(pts
			(xy 334.383634 -241.685318) (xy 334.336644 -241.532918) (xy 334.075024 -241.532918) (xy 334.028034 -241.685318)
			(xy 334.028034 -241.729768) (xy 334.383634 -241.729768)
		)
		(stroke
			(width 0)
			(type solid)
		)
		(fill yes)
		(layer "In2.Cu")
		(net "M_B_CPU0_SB_DQS_DN<9>")
	)
	(gr_poly
		(pts
			(xy 334.383634 -241.276886) (xy 334.383634 -241.232436) (xy 334.028034 -241.232436) (xy 334.028034 -241.276886)
			(xy 334.075024 -241.429286) (xy 334.336644 -241.429286)
		)
		(stroke
			(width 0)
			(type solid)
		)
		(fill yes)
		(layer "In2.Cu")
		(net "M_B_CPU0_SB_CB<2>")
	)
	(gr_poly
		(pts
			(xy 334.383634 -238.430054) (xy 334.336644 -238.277654) (xy 334.075024 -238.277654) (xy 334.028034 -238.430054)
			(xy 334.028034 -238.47425) (xy 334.383634 -238.47425)
		)
		(stroke
			(width 0)
			(type solid)
		)
		(fill yes)
		(layer "In2.Cu")
		(net "M_A_CPU0_SB_DQ<3>")
	)
	(gr_poly
		(pts
			(xy 334.383634 -238.021114) (xy 334.383634 -237.976918) (xy 334.028034 -237.976918) (xy 334.028034 -238.021114)
			(xy 334.075024 -238.173514) (xy 334.336644 -238.173514)
		)
		(stroke
			(width 0)
			(type solid)
		)
		(fill yes)
		(layer "In2.Cu")
		(net "M_A_CPU0_SB_DQS_DP<0>")
	)
	(gr_poly
		(pts
			(xy 334.383634 -236.802422) (xy 334.336644 -236.650022) (xy 334.075024 -236.650022) (xy 334.028034 -236.802422)
			(xy 334.028034 -236.846618) (xy 334.383634 -236.846618)
		)
		(stroke
			(width 0)
			(type solid)
		)
		(fill yes)
		(layer "In2.Cu")
		(net "M_A_CPU0_SB_DQS_DP<5>")
	)
	(gr_poly
		(pts
			(xy 334.383634 -233.54665) (xy 334.336644 -233.39425) (xy 334.075024 -233.39425) (xy 334.028034 -233.54665)
			(xy 334.028034 -233.590846) (xy 334.383634 -233.590846)
		)
		(stroke
			(width 0)
			(type solid)
		)
		(fill yes)
		(layer "In2.Cu")
		(net "M_B_CPU0_SB_DQ<11>")
	)
	(gr_poly
		(pts
			(xy 334.383634 -233.13771) (xy 334.383634 -233.093514) (xy 334.028034 -233.093514) (xy 334.028034 -233.13771)
			(xy 334.075024 -233.29011) (xy 334.336644 -233.29011)
		)
		(stroke
			(width 0)
			(type solid)
		)
		(fill yes)
		(layer "In2.Cu")
		(net "M_B_CPU0_SB_DQS_DP<1>")
	)
	(gr_poly
		(pts
			(xy 334.383634 -231.919018) (xy 334.336644 -231.766618) (xy 334.075024 -231.766618) (xy 334.028034 -231.919018)
			(xy 334.028034 -231.963214) (xy 334.383634 -231.963214)
		)
		(stroke
			(width 0)
			(type solid)
		)
		(fill yes)
		(layer "In2.Cu")
		(net "M_B_CPU0_SB_DQS_DP<6>")
	)
	(gr_poly
		(pts
			(xy 334.383634 -231.510078) (xy 334.383634 -231.465882) (xy 334.028034 -231.465882) (xy 334.028034 -231.510078)
			(xy 334.075024 -231.662478) (xy 334.336644 -231.662478)
		)
		(stroke
			(width 0)
			(type solid)
		)
		(fill yes)
		(layer "In2.Cu")
		(net "M_B_CPU0_SB_DQ<12>")
	)
	(gr_poly
		(pts
			(xy 334.387444 -268.94282) (xy 334.34909 -268.920722) (xy 334.193642 -268.885162) (xy 334.062832 -269.11173)
			(xy 334.17129 -269.22857) (xy 334.209644 -269.250668)
		)
		(stroke
			(width 0)
			(type solid)
		)
		(fill yes)
		(layer "In2.Cu")
		(net "M_A_CPU0_SA_DQ<14>")
	)
	(gr_poly
		(pts
			(xy 334.388206 -277.079964) (xy 334.349852 -277.057866) (xy 334.194404 -277.022306) (xy 334.063594 -277.248874)
			(xy 334.172052 -277.365714) (xy 334.210406 -277.387812)
		)
		(stroke
			(width 0)
			(type solid)
		)
		(fill yes)
		(layer "In2.Cu")
		(net "M_B_CPU0_SA_DQS_DP<5>")
	)
	(gr_poly
		(pts
			(xy 334.389222 -275.450046) (xy 334.350868 -275.427948) (xy 334.19542 -275.392388) (xy 334.06461 -275.618956)
			(xy 334.173068 -275.735796) (xy 334.211422 -275.757894)
		)
		(stroke
			(width 0)
			(type solid)
		)
		(fill yes)
		(layer "In2.Cu")
		(net "M_B_CPU0_SA_DQS_DP<5>")
	)
	(gr_poly
		(pts
			(xy 334.389476 -280.33345) (xy 334.351122 -280.311352) (xy 334.195674 -280.275792) (xy 334.064864 -280.50236)
			(xy 334.173322 -280.6192) (xy 334.211676 -280.641298)
		)
		(stroke
			(width 0)
			(type solid)
		)
		(fill yes)
		(layer "In2.Cu")
		(net "M_B_CPU0_SA_DQ<3>")
	)
	(gr_poly
		(pts
			(xy 334.39227 -244.94109) (xy 334.34528 -244.78869) (xy 334.08366 -244.78869) (xy 334.03667 -244.94109)
			(xy 334.03667 -244.985286) (xy 334.39227 -244.985286)
		)
		(stroke
			(width 0)
			(type solid)
		)
		(fill yes)
		(layer "In2.Cu")
		(net "M_B_CPU0_SB_CS_N<1>")
	)
	(gr_poly
		(pts
			(xy 334.4799 -279.343866) (xy 334.43291 -279.191466) (xy 334.17129 -279.191466) (xy 334.1243 -279.343866)
			(xy 334.1243 -279.388062) (xy 334.4799 -279.388062)
		)
		(stroke
			(width 0)
			(type solid)
		)
		(fill yes)
		(layer "In2.Cu")
		(net "M_B_CPU0_SA_DQS_DN<0>")
	)
	(gr_poly
		(pts
			(xy 334.493362 -267.960094) (xy 334.446372 -267.807694) (xy 334.184752 -267.807694) (xy 334.137762 -267.960094)
			(xy 334.137762 -268.004544) (xy 334.493362 -268.004544)
		)
		(stroke
			(width 0)
			(type solid)
		)
		(fill yes)
		(layer "In2.Cu")
		(net "M_A_CPU0_SA_DQ<13>")
	)
	(gr_poly
		(pts
			(xy 334.493362 -267.551662) (xy 334.493362 -267.507212) (xy 334.137762 -267.507212) (xy 334.137762 -267.551662)
			(xy 334.184752 -267.704062) (xy 334.446372 -267.704062)
		)
		(stroke
			(width 0)
			(type solid)
		)
		(fill yes)
		(layer "In2.Cu")
		(net "M_B_CPU0_SA_DQ<16>")
	)
	(gr_poly
		(pts
			(xy 334.493362 -266.332462) (xy 334.446372 -266.180062) (xy 334.184752 -266.180062) (xy 334.137762 -266.332462)
			(xy 334.137762 -266.376658) (xy 334.493362 -266.376658)
		)
		(stroke
			(width 0)
			(type solid)
		)
		(fill yes)
		(layer "In2.Cu")
		(net "M_B_CPU0_SA_DQ<19>")
	)
	(gr_poly
		(pts
			(xy 334.493362 -265.92403) (xy 334.493362 -265.87958) (xy 334.137762 -265.87958) (xy 334.137762 -265.92403)
			(xy 334.184752 -266.07643) (xy 334.446372 -266.07643)
		)
		(stroke
			(width 0)
			(type solid)
		)
		(fill yes)
		(layer "In2.Cu")
		(net "M_B_CPU0_SA_DQS_DP<2>")
	)
	(gr_poly
		(pts
			(xy 334.493362 -264.70483) (xy 334.446372 -264.55243) (xy 334.184752 -264.55243) (xy 334.137762 -264.70483)
			(xy 334.137762 -264.749026) (xy 334.493362 -264.749026)
		)
		(stroke
			(width 0)
			(type solid)
		)
		(fill yes)
		(layer "In2.Cu")
		(net "M_B_CPU0_SA_DQS_DP<7>")
	)
	(gr_poly
		(pts
			(xy 334.493362 -264.29589) (xy 334.493362 -264.251694) (xy 334.137762 -264.251694) (xy 334.137762 -264.29589)
			(xy 334.184752 -264.44829) (xy 334.446372 -264.44829)
		)
		(stroke
			(width 0)
			(type solid)
		)
		(fill yes)
		(layer "In2.Cu")
		(net "M_B_CPU0_SA_DQ<20>")
	)
	(gr_poly
		(pts
			(xy 334.493362 -263.07669) (xy 334.446372 -262.92429) (xy 334.184752 -262.92429) (xy 334.137762 -263.07669)
			(xy 334.137762 -263.12114) (xy 334.493362 -263.12114)
		)
		(stroke
			(width 0)
			(type solid)
		)
		(fill yes)
		(layer "In2.Cu")
		(net "M_B_CPU0_SA_DQ<23>")
	)
	(gr_poly
		(pts
			(xy 334.493362 -262.668258) (xy 334.493362 -262.623808) (xy 334.137762 -262.623808) (xy 334.137762 -262.668258)
			(xy 334.184752 -262.820658) (xy 334.446372 -262.820658)
		)
		(stroke
			(width 0)
			(type solid)
		)
		(fill yes)
		(layer "In2.Cu")
		(net "M_B_CPU0_SA_CB<0>")
	)
	(gr_poly
		(pts
			(xy 334.493362 -261.449058) (xy 334.446372 -261.296658) (xy 334.184752 -261.296658) (xy 334.137762 -261.449058)
			(xy 334.137762 -261.493508) (xy 334.493362 -261.493508)
		)
		(stroke
			(width 0)
			(type solid)
		)
		(fill yes)
		(layer "In2.Cu")
		(net "M_B_CPU0_SA_CB<3>")
	)
	(gr_poly
		(pts
			(xy 334.493362 -261.040626) (xy 334.493362 -260.996176) (xy 334.137762 -260.996176) (xy 334.137762 -261.040626)
			(xy 334.184752 -261.193026) (xy 334.446372 -261.193026)
		)
		(stroke
			(width 0)
			(type solid)
		)
		(fill yes)
		(layer "In2.Cu")
		(net "M_B_CPU0_SA_DQS_DP<4>")
	)
	(gr_poly
		(pts
			(xy 334.493362 -259.821426) (xy 334.446372 -259.669026) (xy 334.184752 -259.669026) (xy 334.137762 -259.821426)
			(xy 334.137762 -259.865622) (xy 334.493362 -259.865622)
		)
		(stroke
			(width 0)
			(type solid)
		)
		(fill yes)
		(layer "In2.Cu")
		(net "M_B_CPU0_SA_DQS_DP<9>")
	)
	(gr_poly
		(pts
			(xy 334.493362 -259.412486) (xy 334.493362 -259.36829) (xy 334.137762 -259.36829) (xy 334.137762 -259.412486)
			(xy 334.184752 -259.564886) (xy 334.446372 -259.564886)
		)
		(stroke
			(width 0)
			(type solid)
		)
		(fill yes)
		(layer "In2.Cu")
		(net "M_B_CPU0_SA_CB<4>")
	)
	(gr_poly
		(pts
			(xy 334.493362 -258.193286) (xy 334.446372 -258.040886) (xy 334.184752 -258.040886) (xy 334.137762 -258.193286)
			(xy 334.137762 -258.237736) (xy 334.493362 -258.237736)
		)
		(stroke
			(width 0)
			(type solid)
		)
		(fill yes)
		(layer "In2.Cu")
		(net "M_B_CPU0_SA_CB<7>")
	)
	(gr_poly
		(pts
			(xy 334.493362 -257.784854) (xy 334.493362 -257.740404) (xy 334.137762 -257.740404) (xy 334.137762 -257.784854)
			(xy 334.184752 -257.937254) (xy 334.446372 -257.937254)
		)
		(stroke
			(width 0)
			(type solid)
		)
		(fill yes)
		(layer "In2.Cu")
		(net "M_B_CPU0_ALERT_N")
	)
	(gr_poly
		(pts
			(xy 334.493362 -256.565654) (xy 334.446372 -256.413254) (xy 334.184752 -256.413254) (xy 334.137762 -256.565654)
			(xy 334.137762 -256.610104) (xy 334.493362 -256.610104)
		)
		(stroke
			(width 0)
			(type solid)
		)
		(fill yes)
		(layer "In2.Cu")
		(net "M_B_CPU0_SA_CS_N<3>")
	)
	(gr_poly
		(pts
			(xy 334.493362 -256.157222) (xy 334.493362 -256.112772) (xy 334.137762 -256.112772) (xy 334.137762 -256.157222)
			(xy 334.184752 -256.309622) (xy 334.446372 -256.309622)
		)
		(stroke
			(width 0)
			(type solid)
		)
		(fill yes)
		(layer "In2.Cu")
		(net "M_B_CPU0_SA_CS_N<1>")
	)
	(gr_poly
		(pts
			(xy 334.493362 -254.938022) (xy 334.446372 -254.785622) (xy 334.184752 -254.785622) (xy 334.137762 -254.938022)
			(xy 334.137762 -254.982218) (xy 334.493362 -254.982218)
		)
		(stroke
			(width 0)
			(type solid)
		)
		(fill yes)
		(layer "In2.Cu")
		(net "M_B_CPU0_SA_CA<2>")
	)
	(gr_poly
		(pts
			(xy 334.493362 -254.529082) (xy 334.493362 -254.484886) (xy 334.137762 -254.484886) (xy 334.137762 -254.529082)
			(xy 334.184752 -254.681482) (xy 334.446372 -254.681482)
		)
		(stroke
			(width 0)
			(type solid)
		)
		(fill yes)
		(layer "In2.Cu")
		(net "M_B_CPU0_SA_CA<3>")
	)
	(gr_poly
		(pts
			(xy 334.493616 -272.843498) (xy 334.446626 -272.691098) (xy 334.185006 -272.691098) (xy 334.138016 -272.843498)
			(xy 334.138016 -272.887948) (xy 334.493616 -272.887948)
		)
		(stroke
			(width 0)
			(type solid)
		)
		(fill yes)
		(layer "In2.Cu")
		(net "M_B_CPU0_SA_DQ<7>")
	)
	(gr_poly
		(pts
			(xy 334.57261 -274.531582) (xy 334.464152 -274.414742) (xy 334.425798 -274.392644) (xy 334.247998 -274.700492)
			(xy 334.286352 -274.72259) (xy 334.4418 -274.75815)
		)
		(stroke
			(width 0)
			(type solid)
		)
		(fill yes)
		(layer "In2.Cu")
		(net "M_B_CPU0_SA_DQ<4>")
	)
	(gr_poly
		(pts
			(xy 334.709008 -226.480116) (xy 334.747362 -226.458018) (xy 334.569562 -226.15017) (xy 334.531208 -226.172268)
			(xy 334.42275 -226.289108) (xy 334.55356 -226.515676)
		)
		(stroke
			(width 0)
			(type solid)
		)
		(fill yes)
		(layer "In2.Cu")
		(net "M_B_CPU0_SB_DQS_DP<2>")
	)
	(gr_poly
		(pts
			(xy 334.709262 -224.85223) (xy 334.747616 -224.830132) (xy 334.569816 -224.522284) (xy 334.531462 -224.544382)
			(xy 334.423004 -224.661222) (xy 334.553814 -224.88779)
		)
		(stroke
			(width 0)
			(type solid)
		)
		(fill yes)
		(layer "In2.Cu")
		(net "M_B_CPU0_SB_DQS_DN<7>")
	)
	(gr_poly
		(pts
			(xy 334.711294 -223.228408) (xy 334.749648 -223.20631) (xy 334.571848 -222.898462) (xy 334.533494 -222.92056)
			(xy 334.425036 -223.0374) (xy 334.555846 -223.263968)
		)
		(stroke
			(width 0)
			(type solid)
		)
		(fill yes)
		(layer "In2.Cu")
		(net "M_B_CPU0_SB_DQ<20>")
	)
	(gr_poly
		(pts
			(xy 334.817974 -225.858324) (xy 334.926432 -225.741484) (xy 334.795622 -225.514916) (xy 334.640174 -225.550476)
			(xy 334.60182 -225.572574) (xy 334.77962 -225.880422)
		)
		(stroke
			(width 0)
			(type solid)
		)
		(fill yes)
		(layer "In2.Cu")
		(net "M_B_CPU0_SB_DQS_DN<2>")
	)
	(gr_poly
		(pts
			(xy 334.820006 -224.234502) (xy 334.928464 -224.117662) (xy 334.797654 -223.891094) (xy 334.642206 -223.926654)
			(xy 334.603852 -223.948752) (xy 334.781652 -224.2566)
		)
		(stroke
			(width 0)
			(type solid)
		)
		(fill yes)
		(layer "In2.Cu")
		(net "M_B_CPU0_SB_DQS_DP<7>")
	)
	(gr_poly
		(pts
			(xy 334.824324 -227.497132) (xy 334.932782 -227.380292) (xy 334.801972 -227.153724) (xy 334.646524 -227.189284)
			(xy 334.60817 -227.211382) (xy 334.78597 -227.51923)
		)
		(stroke
			(width 0)
			(type solid)
		)
		(fill yes)
		(layer "In2.Cu")
		(net "M_B_CPU0_SB_DQ<19>")
	)
	(gr_poly
		(pts
			(xy 334.843882 -229.61727) (xy 334.884014 -229.598474) (xy 334.733646 -229.276402) (xy 334.693514 -229.294944)
			(xy 334.57515 -229.402132) (xy 334.685894 -229.639114)
		)
		(stroke
			(width 0)
			(type solid)
		)
		(fill yes)
		(layer "In2.Cu")
		(net "M_B_CPU0_SB_DQ<16>")
	)
	(gr_poly
		(pts
			(xy 334.845152 -245.346474) (xy 334.845152 -245.302278) (xy 334.489552 -245.302278) (xy 334.489552 -245.346474)
			(xy 334.536542 -245.498874) (xy 334.798162 -245.498874)
		)
		(stroke
			(width 0)
			(type solid)
		)
		(fill yes)
		(layer "In2.Cu")
		(net "M_B_CPU0_SB_CS_N<3>")
	)
	(gr_poly
		(pts
			(xy 334.847438 -242.090702) (xy 334.847438 -242.046252) (xy 334.491838 -242.046252) (xy 334.491838 -242.090702)
			(xy 334.538828 -242.243102) (xy 334.800448 -242.243102)
		)
		(stroke
			(width 0)
			(type solid)
		)
		(fill yes)
		(layer "In2.Cu")
		(net "M_B_CPU0_SB_DQS_DP<9>")
	)
	(gr_poly
		(pts
			(xy 334.847438 -237.616238) (xy 334.800448 -237.463838) (xy 334.538828 -237.463838) (xy 334.491838 -237.616238)
			(xy 334.491838 -237.660434) (xy 334.847438 -237.660434)
		)
		(stroke
			(width 0)
			(type solid)
		)
		(fill yes)
		(layer "In2.Cu")
		(net "M_A_CPU0_SB_DQS_DN<0>")
	)
	(gr_poly
		(pts
			(xy 334.847438 -237.207298) (xy 334.847438 -237.163102) (xy 334.491838 -237.163102) (xy 334.491838 -237.207298)
			(xy 334.538828 -237.359698) (xy 334.800448 -237.359698)
		)
		(stroke
			(width 0)
			(type solid)
		)
		(fill yes)
		(layer "In2.Cu")
		(net "M_A_CPU0_SB_DQS_DN<5>")
	)
	(gr_poly
		(pts
			(xy 334.853026 -281.158696) (xy 334.814672 -281.136598) (xy 334.659224 -281.101038) (xy 334.528414 -281.327606)
			(xy 334.636872 -281.444446) (xy 334.675226 -281.466544)
		)
		(stroke
			(width 0)
			(type solid)
		)
		(fill yes)
		(layer "In2.Cu")
		(net "M_B_CPU0_SA_DQ<0>")
	)
	(gr_poly
		(pts
			(xy 334.85328 -235.988098) (xy 334.80629 -235.835698) (xy 334.54467 -235.835698) (xy 334.49768 -235.988098)
			(xy 334.49768 -236.032548) (xy 334.85328 -236.032548)
		)
		(stroke
			(width 0)
			(type solid)
		)
		(fill yes)
		(layer "In2.Cu")
		(net "M_A_CPU0_SB_DQ<6>")
	)
	(gr_poly
		(pts
			(xy 334.853534 -248.601738) (xy 334.853534 -248.557542) (xy 334.497934 -248.557542) (xy 334.497934 -248.601738)
			(xy 334.544924 -248.754138) (xy 334.806544 -248.754138)
		)
		(stroke
			(width 0)
			(type solid)
		)
		(fill yes)
		(layer "In2.Cu")
		(net "M_B_CPU0_SB_CA<2>")
	)
	(gr_poly
		(pts
			(xy 334.853534 -247.382538) (xy 334.806544 -247.230138) (xy 334.544924 -247.230138) (xy 334.497934 -247.382538)
			(xy 334.497934 -247.426988) (xy 334.853534 -247.426988)
		)
		(stroke
			(width 0)
			(type solid)
		)
		(fill yes)
		(layer "In2.Cu")
		(net "M_B_CPU0_SB_CA<5>")
	)
	(gr_poly
		(pts
			(xy 334.853534 -246.974106) (xy 334.853534 -246.929656) (xy 334.497934 -246.929656) (xy 334.497934 -246.974106)
			(xy 334.544924 -247.126506) (xy 334.806544 -247.126506)
		)
		(stroke
			(width 0)
			(type solid)
		)
		(fill yes)
		(layer "In2.Cu")
		(net "M_B_CPU0_SB_CA<6>")
	)
	(gr_poly
		(pts
			(xy 334.853534 -245.754906) (xy 334.806544 -245.602506) (xy 334.544924 -245.602506) (xy 334.497934 -245.754906)
			(xy 334.497934 -245.799356) (xy 334.853534 -245.799356)
		)
		(stroke
			(width 0)
			(type solid)
		)
		(fill yes)
		(layer "In2.Cu")
		(net "M_B_CPU0_SB_CS_N<2>")
	)
	(gr_poly
		(pts
			(xy 334.853534 -243.718334) (xy 334.853534 -243.674138) (xy 334.497934 -243.674138) (xy 334.497934 -243.718334)
			(xy 334.544924 -243.870734) (xy 334.806544 -243.870734)
		)
		(stroke
			(width 0)
			(type solid)
		)
		(fill yes)
		(layer "In2.Cu")
		(net "M_B_CPU0_SB_CB<7>")
	)
	(gr_poly
		(pts
			(xy 334.853534 -240.871502) (xy 334.806544 -240.719102) (xy 334.544924 -240.719102) (xy 334.497934 -240.871502)
			(xy 334.497934 -240.915952) (xy 334.853534 -240.915952)
		)
		(stroke
			(width 0)
			(type solid)
		)
		(fill yes)
		(layer "In2.Cu")
		(net "M_B_CPU0_SB_CB<0>")
	)
	(gr_poly
		(pts
			(xy 334.853534 -238.83493) (xy 334.853534 -238.790734) (xy 334.497934 -238.790734) (xy 334.497934 -238.83493)
			(xy 334.544924 -238.98733) (xy 334.806544 -238.98733)
		)
		(stroke
			(width 0)
			(type solid)
		)
		(fill yes)
		(layer "In2.Cu")
		(net "M_A_CPU0_SB_DQ<1>")
	)
	(gr_poly
		(pts
			(xy 334.853534 -233.952034) (xy 334.853534 -233.907584) (xy 334.497934 -233.907584) (xy 334.497934 -233.952034)
			(xy 334.544924 -234.104434) (xy 334.806544 -234.104434)
		)
		(stroke
			(width 0)
			(type solid)
		)
		(fill yes)
		(layer "In2.Cu")
		(net "M_B_CPU0_SB_DQ<9>")
	)
	(gr_poly
		(pts
			(xy 334.853534 -232.732834) (xy 334.806544 -232.580434) (xy 334.544924 -232.580434) (xy 334.497934 -232.732834)
			(xy 334.497934 -232.77703) (xy 334.853534 -232.77703)
		)
		(stroke
			(width 0)
			(type solid)
		)
		(fill yes)
		(layer "In2.Cu")
		(net "M_B_CPU0_SB_DQS_DN<1>")
	)
	(gr_poly
		(pts
			(xy 334.853534 -232.323894) (xy 334.853534 -232.279698) (xy 334.497934 -232.279698) (xy 334.497934 -232.323894)
			(xy 334.544924 -232.476294) (xy 334.806544 -232.476294)
		)
		(stroke
			(width 0)
			(type solid)
		)
		(fill yes)
		(layer "In2.Cu")
		(net "M_B_CPU0_SB_DQS_DN<6>")
	)
	(gr_poly
		(pts
			(xy 334.853534 -231.104694) (xy 334.806544 -230.952294) (xy 334.544924 -230.952294) (xy 334.497934 -231.104694)
			(xy 334.497934 -231.149144) (xy 334.853534 -231.149144)
		)
		(stroke
			(width 0)
			(type solid)
		)
		(fill yes)
		(layer "In2.Cu")
		(net "M_B_CPU0_SB_DQ<14>")
	)
	(gr_poly
		(pts
			(xy 334.856582 -274.640802) (xy 334.818228 -274.618704) (xy 334.66278 -274.583144) (xy 334.53197 -274.809712)
			(xy 334.640428 -274.926552) (xy 334.678782 -274.94865)
		)
		(stroke
			(width 0)
			(type solid)
		)
		(fill yes)
		(layer "In2.Cu")
		(net "M_B_CPU0_SA_DQS_DP<5>")
	)
	(gr_poly
		(pts
			(xy 334.861662 -242.499134) (xy 334.814672 -242.346734) (xy 334.553052 -242.346734) (xy 334.506062 -242.499134)
			(xy 334.506062 -242.54333) (xy 334.861662 -242.54333)
		)
		(stroke
			(width 0)
			(type solid)
		)
		(fill yes)
		(layer "In2.Cu")
		(net "M_B_CPU0_SB_DQS_DP<4>")
	)
	(gr_poly
		(pts
			(xy 334.861916 -249.01017) (xy 334.814926 -248.85777) (xy 334.553306 -248.85777) (xy 334.506316 -249.01017)
			(xy 334.506316 -249.05462) (xy 334.861916 -249.05462)
		)
		(stroke
			(width 0)
			(type solid)
		)
		(fill yes)
		(layer "In2.Cu")
		(net "M_B_CPU0_SB_CA<1>")
	)
	(gr_poly
		(pts
			(xy 334.861916 -244.126766) (xy 334.814926 -243.974366) (xy 334.553306 -243.974366) (xy 334.506316 -244.126766)
			(xy 334.506316 -244.171216) (xy 334.861916 -244.171216)
		)
		(stroke
			(width 0)
			(type solid)
		)
		(fill yes)
		(layer "In2.Cu")
		(net "M_B_CPU0_SB_CB<4>")
	)
	(gr_poly
		(pts
			(xy 334.861916 -240.46307) (xy 334.861916 -240.418874) (xy 334.506316 -240.418874) (xy 334.506316 -240.46307)
			(xy 334.553306 -240.61547) (xy 334.814926 -240.61547)
		)
		(stroke
			(width 0)
			(type solid)
		)
		(fill yes)
		(layer "In2.Cu")
		(net "M_B_CPU0_SB_CB<3>")
	)
	(gr_poly
		(pts
			(xy 334.861916 -239.243362) (xy 334.814926 -239.090962) (xy 334.553306 -239.090962) (xy 334.506316 -239.243362)
			(xy 334.506316 -239.287812) (xy 334.861916 -239.287812)
		)
		(stroke
			(width 0)
			(type solid)
		)
		(fill yes)
		(layer "In2.Cu")
		(net "M_A_CPU0_SB_DQ<2>")
	)
	(gr_poly
		(pts
			(xy 334.861916 -235.579666) (xy 334.861916 -235.53547) (xy 334.506316 -235.53547) (xy 334.506316 -235.579666)
			(xy 334.553306 -235.732066) (xy 334.814926 -235.732066)
		)
		(stroke
			(width 0)
			(type solid)
		)
		(fill yes)
		(layer "In2.Cu")
		(net "M_A_CPU0_SB_DQ<5>")
	)
	(gr_poly
		(pts
			(xy 334.861916 -234.360466) (xy 334.814926 -234.208066) (xy 334.553306 -234.208066) (xy 334.506316 -234.360466)
			(xy 334.506316 -234.404662) (xy 334.861916 -234.404662)
		)
		(stroke
			(width 0)
			(type solid)
		)
		(fill yes)
		(layer "In2.Cu")
		(net "M_B_CPU0_SB_DQ<10>")
	)
	(gr_poly
		(pts
			(xy 334.861916 -230.696262) (xy 334.861916 -230.652066) (xy 334.506316 -230.652066) (xy 334.506316 -230.696262)
			(xy 334.553306 -230.848662) (xy 334.814926 -230.848662)
		)
		(stroke
			(width 0)
			(type solid)
		)
		(fill yes)
		(layer "In2.Cu")
		(net "M_B_CPU0_SB_DQ<13>")
	)
	(gr_poly
		(pts
			(xy 334.934052 -278.188674) (xy 335.04251 -278.071834) (xy 334.9117 -277.845266) (xy 334.756252 -277.880826)
			(xy 334.717898 -277.902924) (xy 334.895698 -278.210772)
		)
		(stroke
			(width 0)
			(type solid)
		)
		(fill yes)
		(layer "In2.Cu")
		(net "M_B_CPU0_SA_DQS_DN<5>")
	)
	(gr_poly
		(pts
			(xy 334.934052 -276.560788) (xy 335.04251 -276.443948) (xy 334.9117 -276.21738) (xy 334.756252 -276.25294)
			(xy 334.717898 -276.275038) (xy 334.895698 -276.582886)
		)
		(stroke
			(width 0)
			(type solid)
		)
		(fill yes)
		(layer "In2.Cu")
		(net "M_B_CPU0_SA_DQS_DN<5>")
	)
	(gr_poly
		(pts
			(xy 334.95488 -272.029174) (xy 334.90789 -271.876774) (xy 334.64627 -271.876774) (xy 334.59928 -272.029174)
			(xy 334.59928 -272.073624) (xy 334.95488 -272.073624)
		)
		(stroke
			(width 0)
			(type solid)
		)
		(fill yes)
		(layer "In2.Cu")
		(net "M_A_CPU0_SA_DQ<8>")
	)
	(gr_poly
		(pts
			(xy 334.95742 -273.248882) (xy 334.95742 -273.204432) (xy 334.60182 -273.204432) (xy 334.60182 -273.248882)
			(xy 334.64881 -273.401282) (xy 334.91043 -273.401282)
		)
		(stroke
			(width 0)
			(type solid)
		)
		(fill yes)
		(layer "In2.Cu")
		(net "M_B_CPU0_SA_DQ<5>")
	)
	(gr_poly
		(pts
			(xy 334.963262 -280.168604) (xy 334.916272 -280.016204) (xy 334.654652 -280.016204) (xy 334.607662 -280.168604)
			(xy 334.607662 -280.2128) (xy 334.963262 -280.2128)
		)
		(stroke
			(width 0)
			(type solid)
		)
		(fill yes)
		(layer "In2.Cu")
		(net "M_B_CPU0_SA_DQ<3>")
	)
	(gr_poly
		(pts
			(xy 334.963262 -270.40205) (xy 334.916272 -270.24965) (xy 334.654652 -270.24965) (xy 334.607662 -270.40205)
			(xy 334.607662 -270.446246) (xy 334.963262 -270.446246)
		)
		(stroke
			(width 0)
			(type solid)
		)
		(fill yes)
		(layer "In2.Cu")
		(net "M_A_CPU0_SA_DQS_DN<1>")
	)
	(gr_poly
		(pts
			(xy 334.963262 -268.77391) (xy 334.916272 -268.62151) (xy 334.654652 -268.62151) (xy 334.607662 -268.77391)
			(xy 334.607662 -268.81836) (xy 334.963262 -268.81836)
		)
		(stroke
			(width 0)
			(type solid)
		)
		(fill yes)
		(layer "In2.Cu")
		(net "M_A_CPU0_SA_DQ<14>")
	)
	(gr_poly
		(pts
			(xy 334.963262 -268.365478) (xy 334.963262 -268.321028) (xy 334.607662 -268.321028) (xy 334.607662 -268.365478)
			(xy 334.654652 -268.517878) (xy 334.916272 -268.517878)
		)
		(stroke
			(width 0)
			(type solid)
		)
		(fill yes)
		(layer "In2.Cu")
		(net "M_A_CPU0_SA_DQ<15>")
	)
	(gr_poly
		(pts
			(xy 334.963262 -267.146278) (xy 334.916272 -266.993878) (xy 334.654652 -266.993878) (xy 334.607662 -267.146278)
			(xy 334.607662 -267.190474) (xy 334.963262 -267.190474)
		)
		(stroke
			(width 0)
			(type solid)
		)
		(fill yes)
		(layer "In2.Cu")
		(net "M_B_CPU0_SA_DQ<18>")
	)
	(gr_poly
		(pts
			(xy 334.963262 -266.737846) (xy 334.963262 -266.693396) (xy 334.607662 -266.693396) (xy 334.607662 -266.737846)
			(xy 334.654652 -266.890246) (xy 334.916272 -266.890246)
		)
		(stroke
			(width 0)
			(type solid)
		)
		(fill yes)
		(layer "In2.Cu")
		(net "M_B_CPU0_SA_DQ<17>")
	)
	(gr_poly
		(pts
			(xy 334.963262 -265.518646) (xy 334.916272 -265.366246) (xy 334.654652 -265.366246) (xy 334.607662 -265.518646)
			(xy 334.607662 -265.562842) (xy 334.963262 -265.562842)
		)
		(stroke
			(width 0)
			(type solid)
		)
		(fill yes)
		(layer "In2.Cu")
		(net "M_B_CPU0_SA_DQS_DN<2>")
	)
	(gr_poly
		(pts
			(xy 334.963262 -265.109706) (xy 334.963262 -265.06551) (xy 334.607662 -265.06551) (xy 334.607662 -265.109706)
			(xy 334.654652 -265.262106) (xy 334.916272 -265.262106)
		)
		(stroke
			(width 0)
			(type solid)
		)
		(fill yes)
		(layer "In2.Cu")
		(net "M_B_CPU0_SA_DQS_DN<7>")
	)
	(gr_poly
		(pts
			(xy 334.963262 -263.891014) (xy 334.916272 -263.738614) (xy 334.654652 -263.738614) (xy 334.607662 -263.891014)
			(xy 334.607662 -263.93521) (xy 334.963262 -263.93521)
		)
		(stroke
			(width 0)
			(type solid)
		)
		(fill yes)
		(layer "In2.Cu")
		(net "M_B_CPU0_SA_DQ<22>")
	)
	(gr_poly
		(pts
			(xy 334.963262 -263.482074) (xy 334.963262 -263.437878) (xy 334.607662 -263.437878) (xy 334.607662 -263.482074)
			(xy 334.654652 -263.634474) (xy 334.916272 -263.634474)
		)
		(stroke
			(width 0)
			(type solid)
		)
		(fill yes)
		(layer "In2.Cu")
		(net "M_B_CPU0_SA_DQ<21>")
	)
	(gr_poly
		(pts
			(xy 334.963262 -262.262874) (xy 334.916272 -262.110474) (xy 334.654652 -262.110474) (xy 334.607662 -262.262874)
			(xy 334.607662 -262.307324) (xy 334.963262 -262.307324)
		)
		(stroke
			(width 0)
			(type solid)
		)
		(fill yes)
		(layer "In2.Cu")
		(net "M_B_CPU0_SA_CB<2>")
	)
	(gr_poly
		(pts
			(xy 334.963262 -261.854442) (xy 334.963262 -261.810246) (xy 334.607662 -261.810246) (xy 334.607662 -261.854442)
			(xy 334.654652 -262.006842) (xy 334.916272 -262.006842)
		)
		(stroke
			(width 0)
			(type solid)
		)
		(fill yes)
		(layer "In2.Cu")
		(net "M_B_CPU0_SA_CB<1>")
	)
	(gr_poly
		(pts
			(xy 334.963262 -260.635242) (xy 334.916272 -260.482842) (xy 334.654652 -260.482842) (xy 334.607662 -260.635242)
			(xy 334.607662 -260.679438) (xy 334.963262 -260.679438)
		)
		(stroke
			(width 0)
			(type solid)
		)
		(fill yes)
		(layer "In2.Cu")
		(net "M_B_CPU0_SA_DQS_DN<4>")
	)
	(gr_poly
		(pts
			(xy 334.963262 -260.226302) (xy 334.963262 -260.182106) (xy 334.607662 -260.182106) (xy 334.607662 -260.226302)
			(xy 334.654652 -260.378702) (xy 334.916272 -260.378702)
		)
		(stroke
			(width 0)
			(type solid)
		)
		(fill yes)
		(layer "In2.Cu")
		(net "M_B_CPU0_SA_DQS_DN<9>")
	)
	(gr_poly
		(pts
			(xy 334.963262 -259.00761) (xy 334.916272 -258.85521) (xy 334.654652 -258.85521) (xy 334.607662 -259.00761)
			(xy 334.607662 -259.051806) (xy 334.963262 -259.051806)
		)
		(stroke
			(width 0)
			(type solid)
		)
		(fill yes)
		(layer "In2.Cu")
		(net "M_B_CPU0_SA_CB<6>")
	)
	(gr_poly
		(pts
			(xy 334.963262 -258.59867) (xy 334.963262 -258.554474) (xy 334.607662 -258.554474) (xy 334.607662 -258.59867)
			(xy 334.654652 -258.75107) (xy 334.916272 -258.75107)
		)
		(stroke
			(width 0)
			(type solid)
		)
		(fill yes)
		(layer "In2.Cu")
		(net "M_B_CPU0_SA_CB<5>")
	)
	(gr_poly
		(pts
			(xy 334.963262 -257.37947) (xy 334.916272 -257.22707) (xy 334.654652 -257.22707) (xy 334.607662 -257.37947)
			(xy 334.607662 -257.42392) (xy 334.963262 -257.42392)
		)
		(stroke
			(width 0)
			(type solid)
		)
		(fill yes)
		(layer "In2.Cu")
		(net "M_B_CPU0_SA_CS_N<0>")
	)
	(gr_poly
		(pts
			(xy 334.963262 -256.971038) (xy 334.963262 -256.926588) (xy 334.607662 -256.926588) (xy 334.607662 -256.971038)
			(xy 334.654652 -257.123438) (xy 334.916272 -257.123438)
		)
		(stroke
			(width 0)
			(type solid)
		)
		(fill yes)
		(layer "In2.Cu")
		(net "M_B_CPU0_SA_CS_N<2>")
	)
	(gr_poly
		(pts
			(xy 334.963262 -255.751838) (xy 334.916272 -255.599438) (xy 334.654652 -255.599438) (xy 334.607662 -255.751838)
			(xy 334.607662 -255.796288) (xy 334.963262 -255.796288)
		)
		(stroke
			(width 0)
			(type solid)
		)
		(fill yes)
		(layer "In2.Cu")
		(net "M_B_CPU0_SA_CA<0>")
	)
	(gr_poly
		(pts
			(xy 334.963262 -255.343406) (xy 334.963262 -255.298956) (xy 334.607662 -255.298956) (xy 334.607662 -255.343406)
			(xy 334.654652 -255.495806) (xy 334.916272 -255.495806)
		)
		(stroke
			(width 0)
			(type solid)
		)
		(fill yes)
		(layer "In2.Cu")
		(net "M_B_CPU0_SA_CA<1>")
	)
	(gr_poly
		(pts
			(xy 334.963262 -254.124206) (xy 334.916272 -253.971806) (xy 334.654652 -253.971806) (xy 334.607662 -254.124206)
			(xy 334.607662 -254.168402) (xy 334.963262 -254.168402)
		)
		(stroke
			(width 0)
			(type solid)
		)
		(fill yes)
		(layer "In2.Cu")
		(net "M_B_CPU0_SA_CA<4>")
	)
	(gr_poly
		(pts
			(xy 334.969358 -273.657314) (xy 334.922368 -273.504914) (xy 334.660748 -273.504914) (xy 334.613758 -273.657314)
			(xy 334.613758 -273.701764) (xy 334.969358 -273.701764)
		)
		(stroke
			(width 0)
			(type solid)
		)
		(fill yes)
		(layer "In2.Cu")
		(net "M_B_CPU0_SA_DQ<6>")
	)
	(gr_poly
		(pts
			(xy 334.97139 -279.760426) (xy 334.97139 -279.715976) (xy 334.61579 -279.715976) (xy 334.61579 -279.760426)
			(xy 334.66278 -279.912826) (xy 334.9244 -279.912826)
		)
		(stroke
			(width 0)
			(type solid)
		)
		(fill yes)
		(layer "In2.Cu")
		(net "M_B_CPU0_SA_DQS_DP<0>")
	)
	(gr_poly
		(pts
			(xy 334.971644 -253.715774) (xy 334.971644 -253.671324) (xy 334.616044 -253.671324) (xy 334.616044 -253.715774)
			(xy 334.663034 -253.868174) (xy 334.924654 -253.868174)
		)
		(stroke
			(width 0)
			(type solid)
		)
		(fill yes)
		(layer "In2.Cu")
		(net "M_B_CPU0_SA_CA<5>")
	)
	(gr_poly
		(pts
			(xy 335.035906 -275.356574) (xy 334.927448 -275.239734) (xy 334.889094 -275.217636) (xy 334.711294 -275.525484)
			(xy 334.749648 -275.547582) (xy 334.905096 -275.583142)
		)
		(stroke
			(width 0)
			(type solid)
		)
		(fill yes)
		(layer "In2.Cu")
		(net "M_B_CPU0_SA_DQS_DN<5>")
	)
	(gr_poly
		(pts
			(xy 335.042764 -281.856434) (xy 334.934306 -281.739594) (xy 334.895952 -281.717496) (xy 334.718152 -282.025344)
			(xy 334.756506 -282.047442) (xy 334.911954 -282.083002)
		)
		(stroke
			(width 0)
			(type solid)
		)
		(fill yes)
		(layer "In2.Cu")
		(net "M_B_CPU0_SA_DQ<2>")
	)
	(gr_poly
		(pts
			(xy 335.176876 -227.289614) (xy 335.21523 -227.267516) (xy 335.03743 -226.959668) (xy 334.999076 -226.981766)
			(xy 334.890618 -227.098606) (xy 335.021428 -227.325174)
		)
		(stroke
			(width 0)
			(type solid)
		)
		(fill yes)
		(layer "In2.Cu")
		(net "M_B_CPU0_SB_DQS_DP<2>")
	)
	(gr_poly
		(pts
			(xy 335.179162 -224.038414) (xy 335.217516 -224.016316) (xy 335.039716 -223.708468) (xy 335.001362 -223.730566)
			(xy 334.892904 -223.847406) (xy 335.023714 -224.073974)
		)
		(stroke
			(width 0)
			(type solid)
		)
		(fill yes)
		(layer "In2.Cu")
		(net "M_B_CPU0_SB_DQ<20>")
	)
	(gr_poly
		(pts
			(xy 335.179162 -222.410528) (xy 335.217516 -222.38843) (xy 335.039716 -222.080582) (xy 335.001362 -222.10268)
			(xy 334.892904 -222.21952) (xy 335.023714 -222.446088)
		)
		(stroke
			(width 0)
			(type solid)
		)
		(fill yes)
		(layer "In2.Cu")
		(net "M_B_CPU0_SB_DQ<21>")
	)
	(gr_poly
		(pts
			(xy 335.287874 -223.416622) (xy 335.396332 -223.299782) (xy 335.265522 -223.073214) (xy 335.110074 -223.108774)
			(xy 335.07172 -223.130872) (xy 335.24952 -223.43872)
		)
		(stroke
			(width 0)
			(type solid)
		)
		(fill yes)
		(layer "In2.Cu")
		(net "M_B_CPU0_SB_DQ<22>")
	)
	(gr_poly
		(pts
			(xy 335.28889 -276.357588) (xy 335.327244 -276.33549) (xy 335.149444 -276.027642) (xy 335.11109 -276.04974)
			(xy 335.002632 -276.16658) (xy 335.133442 -276.393148)
		)
		(stroke
			(width 0)
			(type solid)
		)
		(fill yes)
		(layer "In2.Cu")
		(net "M_B_CPU0_SA_DQS_DN<0>")
	)
	(gr_poly
		(pts
			(xy 335.296002 -226.686364) (xy 335.40446 -226.569524) (xy 335.27365 -226.342956) (xy 335.118202 -226.378516)
			(xy 335.079848 -226.400614) (xy 335.257648 -226.708462)
		)
		(stroke
			(width 0)
			(type solid)
		)
		(fill yes)
		(layer "In2.Cu")
		(net "M_B_CPU0_SB_DQS_DN<2>")
	)
	(gr_poly
		(pts
			(xy 335.314798 -249.416062) (xy 335.314798 -249.371612) (xy 334.959198 -249.371612) (xy 334.959198 -249.416062)
			(xy 335.006188 -249.568462) (xy 335.267808 -249.568462)
		)
		(stroke
			(width 0)
			(type solid)
		)
		(fill yes)
		(layer "In2.Cu")
		(net "M_B_CPU0_SB_CA<0>")
	)
	(gr_poly
		(pts
			(xy 335.314798 -244.532658) (xy 335.314798 -244.488208) (xy 334.959198 -244.488208) (xy 334.959198 -244.532658)
			(xy 335.006188 -244.685058) (xy 335.267808 -244.685058)
		)
		(stroke
			(width 0)
			(type solid)
		)
		(fill yes)
		(layer "In2.Cu")
		(net "M_B_CPU0_SB_CB<6>")
	)
	(gr_poly
		(pts
			(xy 335.314798 -240.057178) (xy 335.267808 -239.904778) (xy 335.006188 -239.904778) (xy 334.959198 -240.057178)
			(xy 334.959198 -240.101628) (xy 335.314798 -240.101628)
		)
		(stroke
			(width 0)
			(type solid)
		)
		(fill yes)
		(layer "In2.Cu")
		(net "M_B_CPU0_SB_CB<1>")
	)
	(gr_poly
		(pts
			(xy 335.314798 -239.649254) (xy 335.314798 -239.604804) (xy 334.959198 -239.604804) (xy 334.959198 -239.649254)
			(xy 335.006188 -239.801654) (xy 335.267808 -239.801654)
		)
		(stroke
			(width 0)
			(type solid)
		)
		(fill yes)
		(layer "In2.Cu")
		(net "M_A_CPU0_SB_DQ<0>")
	)
	(gr_poly
		(pts
			(xy 335.314798 -235.174282) (xy 335.267808 -235.021882) (xy 335.006188 -235.021882) (xy 334.959198 -235.174282)
			(xy 334.959198 -235.218478) (xy 335.314798 -235.218478)
		)
		(stroke
			(width 0)
			(type solid)
		)
		(fill yes)
		(layer "In2.Cu")
		(net "M_A_CPU0_SB_DQ<7>")
	)
	(gr_poly
		(pts
			(xy 335.314798 -234.76585) (xy 335.314798 -234.721654) (xy 334.959198 -234.721654) (xy 334.959198 -234.76585)
			(xy 335.006188 -234.91825) (xy 335.267808 -234.91825)
		)
		(stroke
			(width 0)
			(type solid)
		)
		(fill yes)
		(layer "In2.Cu")
		(net "M_B_CPU0_SB_DQ<8>")
	)
	(gr_poly
		(pts
			(xy 335.314798 -230.290878) (xy 335.267808 -230.138478) (xy 335.006188 -230.138478) (xy 334.959198 -230.290878)
			(xy 334.959198 -230.335074) (xy 335.314798 -230.335074)
		)
		(stroke
			(width 0)
			(type solid)
		)
		(fill yes)
		(layer "In2.Cu")
		(net "M_B_CPU0_SB_DQ<15>")
	)
	(gr_poly
		(pts
			(xy 335.320894 -278.719534) (xy 335.28254 -278.697436) (xy 335.127092 -278.661876) (xy 334.996282 -278.888444)
			(xy 335.10474 -279.005284) (xy 335.143094 -279.027382)
		)
		(stroke
			(width 0)
			(type solid)
		)
		(fill yes)
		(layer "In2.Cu")
		(net "M_B_CPU0_SA_DQS_DN<0>")
	)
	(gr_poly
		(pts
			(xy 335.32318 -242.905026) (xy 335.32318 -242.860576) (xy 334.96758 -242.860576) (xy 334.96758 -242.905026)
			(xy 335.01457 -243.057426) (xy 335.27619 -243.057426)
		)
		(stroke
			(width 0)
			(type solid)
		)
		(fill yes)
		(layer "In2.Cu")
		(net "M_B_CPU0_SB_DQS_DN<4>")
	)
	(gr_poly
		(pts
			(xy 335.32318 -238.020606) (xy 335.32318 -237.97641) (xy 334.96758 -237.97641) (xy 334.96758 -238.020606)
			(xy 335.01457 -238.173006) (xy 335.27619 -238.173006)
		)
		(stroke
			(width 0)
			(type solid)
		)
		(fill yes)
		(layer "In2.Cu")
		(net "M_A_CPU0_SB_DQS_DP<0>")
	)
	(gr_poly
		(pts
			(xy 335.32318 -236.393482) (xy 335.32318 -236.349032) (xy 334.96758 -236.349032) (xy 334.96758 -236.393482)
			(xy 335.01457 -236.545882) (xy 335.27619 -236.545882)
		)
		(stroke
			(width 0)
			(type solid)
		)
		(fill yes)
		(layer "In2.Cu")
		(net "M_A_CPU0_SB_DQ<4>")
	)
	(gr_poly
		(pts
			(xy 335.323434 -248.196354) (xy 335.276444 -248.043954) (xy 335.014824 -248.043954) (xy 334.967834 -248.196354)
			(xy 334.967834 -248.240804) (xy 335.323434 -248.240804)
		)
		(stroke
			(width 0)
			(type solid)
		)
		(fill yes)
		(layer "In2.Cu")
		(net "M_B_CPU0_SB_CA<3>")
	)
	(gr_poly
		(pts
			(xy 335.323434 -247.787922) (xy 335.323434 -247.743472) (xy 334.967834 -247.743472) (xy 334.967834 -247.787922)
			(xy 335.014824 -247.940322) (xy 335.276444 -247.940322)
		)
		(stroke
			(width 0)
			(type solid)
		)
		(fill yes)
		(layer "In2.Cu")
		(net "M_B_CPU0_SB_CA<4>")
	)
	(gr_poly
		(pts
			(xy 335.323434 -246.568722) (xy 335.276444 -246.416322) (xy 335.014824 -246.416322) (xy 334.967834 -246.568722)
			(xy 334.967834 -246.613172) (xy 335.323434 -246.613172)
		)
		(stroke
			(width 0)
			(type solid)
		)
		(fill yes)
		(layer "In2.Cu")
		(net "M_B_CPU0_SB_PAR")
	)
	(gr_poly
		(pts
			(xy 335.323434 -246.16029) (xy 335.323434 -246.11584) (xy 334.967834 -246.11584) (xy 334.967834 -246.16029)
			(xy 335.014824 -246.31269) (xy 335.276444 -246.31269)
		)
		(stroke
			(width 0)
			(type solid)
		)
		(fill yes)
		(layer "In2.Cu")
		(net "M_B_CPU0_SB_CS_N<0>")
	)
	(gr_poly
		(pts
			(xy 335.323434 -243.313458) (xy 335.276444 -243.161058) (xy 335.014824 -243.161058) (xy 334.967834 -243.313458)
			(xy 334.967834 -243.357654) (xy 335.323434 -243.357654)
		)
		(stroke
			(width 0)
			(type solid)
		)
		(fill yes)
		(layer "In2.Cu")
		(net "M_B_CPU0_SB_CB<5>")
	)
	(gr_poly
		(pts
			(xy 335.323434 -241.276886) (xy 335.323434 -241.232436) (xy 334.967834 -241.232436) (xy 334.967834 -241.276886)
			(xy 335.014824 -241.429286) (xy 335.276444 -241.429286)
		)
		(stroke
			(width 0)
			(type solid)
		)
		(fill yes)
		(layer "In2.Cu")
		(net "M_B_CPU0_SB_CB<2>")
	)
	(gr_poly
		(pts
			(xy 335.323434 -238.430054) (xy 335.276444 -238.277654) (xy 335.014824 -238.277654) (xy 334.967834 -238.430054)
			(xy 334.967834 -238.47425) (xy 335.323434 -238.47425)
		)
		(stroke
			(width 0)
			(type solid)
		)
		(fill yes)
		(layer "In2.Cu")
		(net "M_A_CPU0_SB_DQ<3>")
	)
	(gr_poly
		(pts
			(xy 335.323434 -233.54665) (xy 335.276444 -233.39425) (xy 335.014824 -233.39425) (xy 334.967834 -233.54665)
			(xy 334.967834 -233.590846) (xy 335.323434 -233.590846)
		)
		(stroke
			(width 0)
			(type solid)
		)
		(fill yes)
		(layer "In2.Cu")
		(net "M_B_CPU0_SB_DQ<11>")
	)
	(gr_poly
		(pts
			(xy 335.323434 -233.13771) (xy 335.323434 -233.093514) (xy 334.967834 -233.093514) (xy 334.967834 -233.13771)
			(xy 335.014824 -233.29011) (xy 335.276444 -233.29011)
		)
		(stroke
			(width 0)
			(type solid)
		)
		(fill yes)
		(layer "In2.Cu")
		(net "M_B_CPU0_SB_DQS_DP<1>")
	)
	(gr_poly
		(pts
			(xy 335.323434 -231.919018) (xy 335.276444 -231.766618) (xy 335.014824 -231.766618) (xy 334.967834 -231.919018)
			(xy 334.967834 -231.963214) (xy 335.323434 -231.963214)
		)
		(stroke
			(width 0)
			(type solid)
		)
		(fill yes)
		(layer "In2.Cu")
		(net "M_B_CPU0_SB_DQS_DP<6>")
	)
	(gr_poly
		(pts
			(xy 335.323434 -231.510078) (xy 335.323434 -231.465882) (xy 334.967834 -231.465882) (xy 334.967834 -231.510078)
			(xy 335.014824 -231.662478) (xy 335.276444 -231.662478)
		)
		(stroke
			(width 0)
			(type solid)
		)
		(fill yes)
		(layer "In2.Cu")
		(net "M_B_CPU0_SB_DQ<12>")
	)
	(gr_poly
		(pts
			(xy 335.323434 -224.999042) (xy 335.323434 -224.954592) (xy 334.967834 -224.954592) (xy 334.967834 -224.999042)
			(xy 335.014824 -225.151442) (xy 335.276444 -225.151442)
		)
		(stroke
			(width 0)
			(type solid)
		)
		(fill yes)
		(layer "In2.Cu")
		(net "M_B_CPU0_SB_DQS_DN<7>")
	)
	(gr_poly
		(pts
			(xy 335.329022 -275.450046) (xy 335.290668 -275.427948) (xy 335.13522 -275.392388) (xy 335.00441 -275.618956)
			(xy 335.112868 -275.735796) (xy 335.151222 -275.757894)
		)
		(stroke
			(width 0)
			(type solid)
		)
		(fill yes)
		(layer "In2.Cu")
		(net "M_B_CPU0_SA_DQS_DN<0>")
	)
	(gr_poly
		(pts
			(xy 335.331816 -241.685318) (xy 335.284826 -241.532918) (xy 335.023206 -241.532918) (xy 334.976216 -241.685318)
			(xy 334.976216 -241.729514) (xy 335.331816 -241.729514)
		)
		(stroke
			(width 0)
			(type solid)
		)
		(fill yes)
		(layer "In2.Cu")
		(net "M_B_CPU0_SB_DQS_DN<9>")
	)
	(gr_poly
		(pts
			(xy 335.331816 -236.801914) (xy 335.284826 -236.649514) (xy 335.023206 -236.649514) (xy 334.976216 -236.801914)
			(xy 334.976216 -236.846364) (xy 335.331816 -236.846364)
		)
		(stroke
			(width 0)
			(type solid)
		)
		(fill yes)
		(layer "In2.Cu")
		(net "M_A_CPU0_SB_DQS_DP<5>")
	)
	(gr_poly
		(pts
			(xy 335.33207 -244.94109) (xy 335.28508 -244.78869) (xy 335.02346 -244.78869) (xy 334.97647 -244.94109)
			(xy 334.97647 -244.985286) (xy 335.33207 -244.985286)
		)
		(stroke
			(width 0)
			(type solid)
		)
		(fill yes)
		(layer "In2.Cu")
		(net "M_B_CPU0_SB_CS_N<1>")
	)
	(gr_poly
		(pts
			(xy 335.42478 -280.98242) (xy 335.37779 -280.83002) (xy 335.11617 -280.83002) (xy 335.06918 -280.98242)
			(xy 335.06918 -281.026616) (xy 335.42478 -281.026616)
		)
		(stroke
			(width 0)
			(type solid)
		)
		(fill yes)
		(layer "In2.Cu")
		(net "M_B_CPU0_SA_DQ<0>")
	)
	(gr_poly
		(pts
			(xy 335.427828 -272.435066) (xy 335.427828 -272.390616) (xy 335.072228 -272.390616) (xy 335.072228 -272.435066)
			(xy 335.119218 -272.587466) (xy 335.380838 -272.587466)
		)
		(stroke
			(width 0)
			(type solid)
		)
		(fill yes)
		(layer "In2.Cu")
		(net "M_A_CPU0_SA_DQ<10>")
	)
	(gr_poly
		(pts
			(xy 335.433162 -280.573734) (xy 335.433162 -280.529538) (xy 335.077562 -280.529538) (xy 335.077562 -280.573734)
			(xy 335.124552 -280.726134) (xy 335.386172 -280.726134)
		)
		(stroke
			(width 0)
			(type solid)
		)
		(fill yes)
		(layer "In2.Cu")
		(net "M_B_CPU0_SA_DQ<1>")
	)
	(gr_poly
		(pts
			(xy 335.433162 -274.062698) (xy 335.433162 -274.018248) (xy 335.077562 -274.018248) (xy 335.077562 -274.062698)
			(xy 335.124552 -274.215098) (xy 335.386172 -274.215098)
		)
		(stroke
			(width 0)
			(type solid)
		)
		(fill yes)
		(layer "In2.Cu")
		(net "M_B_CPU0_SA_DQ<4>")
	)
	(gr_poly
		(pts
			(xy 335.433162 -271.215866) (xy 335.386172 -271.063466) (xy 335.124552 -271.063466) (xy 335.077562 -271.215866)
			(xy 335.077562 -271.260062) (xy 335.433162 -271.260062)
		)
		(stroke
			(width 0)
			(type solid)
		)
		(fill yes)
		(layer "In2.Cu")
		(net "M_A_CPU0_SA_DQ<11>")
	)
	(gr_poly
		(pts
			(xy 335.433162 -270.806926) (xy 335.433162 -270.76273) (xy 335.077562 -270.76273) (xy 335.077562 -270.806926)
			(xy 335.124552 -270.959326) (xy 335.386172 -270.959326)
		)
		(stroke
			(width 0)
			(type solid)
		)
		(fill yes)
		(layer "In2.Cu")
		(net "M_A_CPU0_SA_DQS_DP<1>")
	)
	(gr_poly
		(pts
			(xy 335.433162 -269.587726) (xy 335.386172 -269.435326) (xy 335.124552 -269.435326) (xy 335.077562 -269.587726)
			(xy 335.077562 -269.632176) (xy 335.433162 -269.632176)
		)
		(stroke
			(width 0)
			(type solid)
		)
		(fill yes)
		(layer "In2.Cu")
		(net "M_A_CPU0_SA_DQS_DP<6>")
	)
	(gr_poly
		(pts
			(xy 335.433162 -269.179294) (xy 335.433162 -269.134844) (xy 335.077562 -269.134844) (xy 335.077562 -269.179294)
			(xy 335.124552 -269.331694) (xy 335.386172 -269.331694)
		)
		(stroke
			(width 0)
			(type solid)
		)
		(fill yes)
		(layer "In2.Cu")
		(net "M_A_CPU0_SA_DQ<12>")
	)
	(gr_poly
		(pts
			(xy 335.433162 -267.960094) (xy 335.386172 -267.807694) (xy 335.124552 -267.807694) (xy 335.077562 -267.960094)
			(xy 335.077562 -268.004544) (xy 335.433162 -268.004544)
		)
		(stroke
			(width 0)
			(type solid)
		)
		(fill yes)
		(layer "In2.Cu")
		(net "M_A_CPU0_SA_DQ<13>")
	)
	(gr_poly
		(pts
			(xy 335.433162 -267.551662) (xy 335.433162 -267.507212) (xy 335.077562 -267.507212) (xy 335.077562 -267.551662)
			(xy 335.124552 -267.704062) (xy 335.386172 -267.704062)
		)
		(stroke
			(width 0)
			(type solid)
		)
		(fill yes)
		(layer "In2.Cu")
		(net "M_B_CPU0_SA_DQ<16>")
	)
	(gr_poly
		(pts
			(xy 335.433162 -266.332462) (xy 335.386172 -266.180062) (xy 335.124552 -266.180062) (xy 335.077562 -266.332462)
			(xy 335.077562 -266.376658) (xy 335.433162 -266.376658)
		)
		(stroke
			(width 0)
			(type solid)
		)
		(fill yes)
		(layer "In2.Cu")
		(net "M_B_CPU0_SA_DQ<19>")
	)
	(gr_poly
		(pts
			(xy 335.433162 -265.923014) (xy 335.433162 -265.878818) (xy 335.077562 -265.878818) (xy 335.077562 -265.923014)
			(xy 335.124552 -266.075414) (xy 335.386172 -266.075414)
		)
		(stroke
			(width 0)
			(type solid)
		)
		(fill yes)
		(layer "In2.Cu")
		(net "M_B_CPU0_SA_DQS_DP<2>")
	)
	(gr_poly
		(pts
			(xy 335.433162 -264.70483) (xy 335.386172 -264.55243) (xy 335.124552 -264.55243) (xy 335.077562 -264.70483)
			(xy 335.077562 -264.749026) (xy 335.433162 -264.749026)
		)
		(stroke
			(width 0)
			(type solid)
		)
		(fill yes)
		(layer "In2.Cu")
		(net "M_B_CPU0_SA_DQS_DP<7>")
	)
	(gr_poly
		(pts
			(xy 335.433162 -264.29589) (xy 335.433162 -264.251694) (xy 335.077562 -264.251694) (xy 335.077562 -264.29589)
			(xy 335.124552 -264.44829) (xy 335.386172 -264.44829)
		)
		(stroke
			(width 0)
			(type solid)
		)
		(fill yes)
		(layer "In2.Cu")
		(net "M_B_CPU0_SA_DQ<20>")
	)
	(gr_poly
		(pts
			(xy 335.433162 -263.07669) (xy 335.386172 -262.92429) (xy 335.124552 -262.92429) (xy 335.077562 -263.07669)
			(xy 335.077562 -263.12114) (xy 335.433162 -263.12114)
		)
		(stroke
			(width 0)
			(type solid)
		)
		(fill yes)
		(layer "In2.Cu")
		(net "M_B_CPU0_SA_DQ<23>")
	)
	(gr_poly
		(pts
			(xy 335.433162 -262.668258) (xy 335.433162 -262.623808) (xy 335.077562 -262.623808) (xy 335.077562 -262.668258)
			(xy 335.124552 -262.820658) (xy 335.386172 -262.820658)
		)
		(stroke
			(width 0)
			(type solid)
		)
		(fill yes)
		(layer "In2.Cu")
		(net "M_B_CPU0_SA_CB<0>")
	)
	(gr_poly
		(pts
			(xy 335.433162 -261.449058) (xy 335.386172 -261.296658) (xy 335.124552 -261.296658) (xy 335.077562 -261.449058)
			(xy 335.077562 -261.493508) (xy 335.433162 -261.493508)
		)
		(stroke
			(width 0)
			(type solid)
		)
		(fill yes)
		(layer "In2.Cu")
		(net "M_B_CPU0_SA_CB<3>")
	)
	(gr_poly
		(pts
			(xy 335.433162 -261.040118) (xy 335.433162 -260.995668) (xy 335.077562 -260.995668) (xy 335.077562 -261.040118)
			(xy 335.124552 -261.192518) (xy 335.386172 -261.192518)
		)
		(stroke
			(width 0)
			(type solid)
		)
		(fill yes)
		(layer "In2.Cu")
		(net "M_B_CPU0_SA_DQS_DP<4>")
	)
	(gr_poly
		(pts
			(xy 335.433162 -259.821426) (xy 335.386172 -259.669026) (xy 335.124552 -259.669026) (xy 335.077562 -259.821426)
			(xy 335.077562 -259.865622) (xy 335.433162 -259.865622)
		)
		(stroke
			(width 0)
			(type solid)
		)
		(fill yes)
		(layer "In2.Cu")
		(net "M_B_CPU0_SA_DQS_DP<9>")
	)
	(gr_poly
		(pts
			(xy 335.433162 -259.412486) (xy 335.433162 -259.36829) (xy 335.077562 -259.36829) (xy 335.077562 -259.412486)
			(xy 335.124552 -259.564886) (xy 335.386172 -259.564886)
		)
		(stroke
			(width 0)
			(type solid)
		)
		(fill yes)
		(layer "In2.Cu")
		(net "M_B_CPU0_SA_CB<4>")
	)
	(gr_poly
		(pts
			(xy 335.433162 -258.193286) (xy 335.386172 -258.040886) (xy 335.124552 -258.040886) (xy 335.077562 -258.193286)
			(xy 335.077562 -258.237736) (xy 335.433162 -258.237736)
		)
		(stroke
			(width 0)
			(type solid)
		)
		(fill yes)
		(layer "In2.Cu")
		(net "M_B_CPU0_SA_CB<7>")
	)
	(gr_poly
		(pts
			(xy 335.433162 -257.784854) (xy 335.433162 -257.740404) (xy 335.077562 -257.740404) (xy 335.077562 -257.784854)
			(xy 335.124552 -257.937254) (xy 335.386172 -257.937254)
		)
		(stroke
			(width 0)
			(type solid)
		)
		(fill yes)
		(layer "In2.Cu")
		(net "M_B_CPU0_ALERT_N")
	)
	(gr_poly
		(pts
			(xy 335.433162 -256.565654) (xy 335.386172 -256.413254) (xy 335.124552 -256.413254) (xy 335.077562 -256.565654)
			(xy 335.077562 -256.610104) (xy 335.433162 -256.610104)
		)
		(stroke
			(width 0)
			(type solid)
		)
		(fill yes)
		(layer "In2.Cu")
		(net "M_B_CPU0_SA_CS_N<3>")
	)
	(gr_poly
		(pts
			(xy 335.433162 -256.157222) (xy 335.433162 -256.112772) (xy 335.077562 -256.112772) (xy 335.077562 -256.157222)
			(xy 335.124552 -256.309622) (xy 335.386172 -256.309622)
		)
		(stroke
			(width 0)
			(type solid)
		)
		(fill yes)
		(layer "In2.Cu")
		(net "M_B_CPU0_SA_CS_N<1>")
	)
	(gr_poly
		(pts
			(xy 335.433162 -254.938022) (xy 335.386172 -254.785622) (xy 335.124552 -254.785622) (xy 335.077562 -254.938022)
			(xy 335.077562 -254.982218) (xy 335.433162 -254.982218)
		)
		(stroke
			(width 0)
			(type solid)
		)
		(fill yes)
		(layer "In2.Cu")
		(net "M_B_CPU0_SA_CA<2>")
	)
	(gr_poly
		(pts
			(xy 335.433162 -254.529082) (xy 335.433162 -254.484886) (xy 335.077562 -254.484886) (xy 335.077562 -254.529082)
			(xy 335.124552 -254.681482) (xy 335.386172 -254.681482)
		)
		(stroke
			(width 0)
			(type solid)
		)
		(fill yes)
		(layer "In2.Cu")
		(net "M_B_CPU0_SA_CA<3>")
	)
	(gr_poly
		(pts
			(xy 335.441544 -274.47113) (xy 335.394554 -274.31873) (xy 335.132934 -274.31873) (xy 335.085944 -274.47113)
			(xy 335.085944 -274.515326) (xy 335.441544 -274.515326)
		)
		(stroke
			(width 0)
			(type solid)
		)
		(fill yes)
		(layer "In2.Cu")
		(net "M_B_CPU0_SA_DQS_DP<5>")
	)
	(gr_poly
		(pts
			(xy 335.441798 -272.843498) (xy 335.394808 -272.691098) (xy 335.133188 -272.691098) (xy 335.086198 -272.843498)
			(xy 335.086198 -272.887694) (xy 335.441798 -272.887694)
		)
		(stroke
			(width 0)
			(type solid)
		)
		(fill yes)
		(layer "In2.Cu")
		(net "M_B_CPU0_SA_DQ<7>")
	)
	(gr_poly
		(pts
			(xy 335.512156 -279.414986) (xy 335.403698 -279.298146) (xy 335.365344 -279.276048) (xy 335.187544 -279.583896)
			(xy 335.225898 -279.605994) (xy 335.381346 -279.641554)
		)
		(stroke
			(width 0)
			(type solid)
		)
		(fill yes)
		(layer "In2.Cu")
		(net "M_B_CPU0_SA_DQS_DP<0>")
	)
	(gr_poly
		(pts
			(xy 335.650078 -223.226376) (xy 335.688432 -223.204278) (xy 335.510632 -222.89643) (xy 335.472278 -222.918528)
			(xy 335.36382 -223.035368) (xy 335.49463 -223.261936)
		)
		(stroke
			(width 0)
			(type solid)
		)
		(fill yes)
		(layer "In2.Cu")
		(net "M_B_CPU0_SB_DQ<21>")
	)
	(gr_poly
		(pts
			(xy 335.761584 -277.176738) (xy 335.799938 -277.15464) (xy 335.622138 -276.846792) (xy 335.583784 -276.86889)
			(xy 335.475326 -276.98573) (xy 335.606136 -277.212298)
		)
		(stroke
			(width 0)
			(type solid)
		)
		(fill yes)
		(layer "In2.Cu")
		(net "M_B_CPU0_SA_DQS_DN<0>")
	)
	(gr_poly
		(pts
			(xy 335.766156 -222.616776) (xy 335.874614 -222.499936) (xy 335.743804 -222.273368) (xy 335.588356 -222.308928)
			(xy 335.550002 -222.331026) (xy 335.727802 -222.638874)
		)
		(stroke
			(width 0)
			(type solid)
		)
		(fill yes)
		(layer "In2.Cu")
		(net "M_B_CPU0_SB_DQ<23>")
	)
	(gr_poly
		(pts
			(xy 335.784952 -245.346474) (xy 335.784952 -245.302278) (xy 335.429352 -245.302278) (xy 335.429352 -245.346474)
			(xy 335.476342 -245.498874) (xy 335.737962 -245.498874)
		)
		(stroke
			(width 0)
			(type solid)
		)
		(fill yes)
		(layer "In2.Cu")
		(net "M_B_CPU0_SB_CS_N<3>")
	)
	(gr_poly
		(pts
			(xy 335.787238 -237.207806) (xy 335.787238 -237.163356) (xy 335.431638 -237.163356) (xy 335.431638 -237.207806)
			(xy 335.478628 -237.360206) (xy 335.740248 -237.360206)
		)
		(stroke
			(width 0)
			(type solid)
		)
		(fill yes)
		(layer "In2.Cu")
		(net "M_A_CPU0_SB_DQS_DN<5>")
	)
	(gr_poly
		(pts
			(xy 335.789016 -277.908258) (xy 335.750662 -277.88616) (xy 335.595214 -277.8506) (xy 335.464404 -278.077168)
			(xy 335.572862 -278.194008) (xy 335.611216 -278.216106)
		)
		(stroke
			(width 0)
			(type solid)
		)
		(fill yes)
		(layer "In2.Cu")
		(net "M_B_CPU0_SA_DQS_DN<0>")
	)
	(gr_poly
		(pts
			(xy 335.79308 -235.988098) (xy 335.74609 -235.835698) (xy 335.48447 -235.835698) (xy 335.43748 -235.988098)
			(xy 335.43748 -236.032548) (xy 335.79308 -236.032548)
		)
		(stroke
			(width 0)
			(type solid)
		)
		(fill yes)
		(layer "In2.Cu")
		(net "M_A_CPU0_SB_DQ<6>")
	)
	(gr_poly
		(pts
			(xy 335.793334 -248.601738) (xy 335.793334 -248.557542) (xy 335.437734 -248.557542) (xy 335.437734 -248.601738)
			(xy 335.484724 -248.754138) (xy 335.746344 -248.754138)
		)
		(stroke
			(width 0)
			(type solid)
		)
		(fill yes)
		(layer "In2.Cu")
		(net "M_B_CPU0_SB_CA<2>")
	)
	(gr_poly
		(pts
			(xy 335.793334 -245.754906) (xy 335.746344 -245.602506) (xy 335.484724 -245.602506) (xy 335.437734 -245.754906)
			(xy 335.437734 -245.799356) (xy 335.793334 -245.799356)
		)
		(stroke
			(width 0)
			(type solid)
		)
		(fill yes)
		(layer "In2.Cu")
		(net "M_B_CPU0_SB_CS_N<2>")
	)
	(gr_poly
		(pts
			(xy 335.793334 -243.718334) (xy 335.793334 -243.674138) (xy 335.437734 -243.674138) (xy 335.437734 -243.718334)
			(xy 335.484724 -243.870734) (xy 335.746344 -243.870734)
		)
		(stroke
			(width 0)
			(type solid)
		)
		(fill yes)
		(layer "In2.Cu")
		(net "M_B_CPU0_SB_CB<7>")
	)
	(gr_poly
		(pts
			(xy 335.793334 -242.499134) (xy 335.746344 -242.346734) (xy 335.484724 -242.346734) (xy 335.437734 -242.499134)
			(xy 335.437734 -242.54333) (xy 335.793334 -242.54333)
		)
		(stroke
			(width 0)
			(type solid)
		)
		(fill yes)
		(layer "In2.Cu")
		(net "M_B_CPU0_SB_DQS_DP<4>")
	)
	(gr_poly
		(pts
			(xy 335.793334 -240.871502) (xy 335.746344 -240.719102) (xy 335.484724 -240.719102) (xy 335.437734 -240.871502)
			(xy 335.437734 -240.915952) (xy 335.793334 -240.915952)
		)
		(stroke
			(width 0)
			(type solid)
		)
		(fill yes)
		(layer "In2.Cu")
		(net "M_B_CPU0_SB_CB<0>")
	)
	(gr_poly
		(pts
			(xy 335.793334 -238.83493) (xy 335.793334 -238.790734) (xy 335.437734 -238.790734) (xy 335.437734 -238.83493)
			(xy 335.484724 -238.98733) (xy 335.746344 -238.98733)
		)
		(stroke
			(width 0)
			(type solid)
		)
		(fill yes)
		(layer "In2.Cu")
		(net "M_A_CPU0_SB_DQ<1>")
	)
	(gr_poly
		(pts
			(xy 335.793334 -233.952034) (xy 335.793334 -233.907584) (xy 335.437734 -233.907584) (xy 335.437734 -233.952034)
			(xy 335.484724 -234.104434) (xy 335.746344 -234.104434)
		)
		(stroke
			(width 0)
			(type solid)
		)
		(fill yes)
		(layer "In2.Cu")
		(net "M_B_CPU0_SB_DQ<9>")
	)
	(gr_poly
		(pts
			(xy 335.793334 -232.323894) (xy 335.793334 -232.279698) (xy 335.437734 -232.279698) (xy 335.437734 -232.323894)
			(xy 335.484724 -232.476294) (xy 335.746344 -232.476294)
		)
		(stroke
			(width 0)
			(type solid)
		)
		(fill yes)
		(layer "In2.Cu")
		(net "M_B_CPU0_SB_DQS_DN<6>")
	)
	(gr_poly
		(pts
			(xy 335.793334 -231.104694) (xy 335.746344 -230.952294) (xy 335.484724 -230.952294) (xy 335.437734 -231.104694)
			(xy 335.437734 -231.149144) (xy 335.793334 -231.149144)
		)
		(stroke
			(width 0)
			(type solid)
		)
		(fill yes)
		(layer "In2.Cu")
		(net "M_B_CPU0_SB_DQ<14>")
	)
	(gr_poly
		(pts
			(xy 335.793334 -229.477062) (xy 335.746344 -229.324662) (xy 335.484724 -229.324662) (xy 335.437734 -229.477062)
			(xy 335.437734 -229.521512) (xy 335.793334 -229.521512)
		)
		(stroke
			(width 0)
			(type solid)
		)
		(fill yes)
		(layer "In2.Cu")
		(net "M_B_CPU0_SB_DQ<16>")
	)
	(gr_poly
		(pts
			(xy 335.793334 -224.593658) (xy 335.746344 -224.441258) (xy 335.484724 -224.441258) (xy 335.437734 -224.593658)
			(xy 335.437734 -224.638108) (xy 335.793334 -224.638108)
		)
		(stroke
			(width 0)
			(type solid)
		)
		(fill yes)
		(layer "In2.Cu")
		(net "M_B_CPU0_SB_DQS_DP<7>")
	)
	(gr_poly
		(pts
			(xy 335.793334 -224.185226) (xy 335.793334 -224.140776) (xy 335.437734 -224.140776) (xy 335.437734 -224.185226)
			(xy 335.484724 -224.337626) (xy 335.746344 -224.337626)
		)
		(stroke
			(width 0)
			(type solid)
		)
		(fill yes)
		(layer "In2.Cu")
		(net "M_B_CPU0_SB_DQ<20>")
	)
	(gr_poly
		(pts
			(xy 335.797144 -279.523444) (xy 335.75879 -279.501346) (xy 335.603342 -279.465786) (xy 335.472532 -279.692354)
			(xy 335.58099 -279.809194) (xy 335.619344 -279.831292)
		)
		(stroke
			(width 0)
			(type solid)
		)
		(fill yes)
		(layer "In2.Cu")
		(net "M_B_CPU0_SA_DQ<3>")
	)
	(gr_poly
		(pts
			(xy 335.79943 -247.382538) (xy 335.75244 -247.230138) (xy 335.49082 -247.230138) (xy 335.44383 -247.382538)
			(xy 335.44383 -247.426988) (xy 335.79943 -247.426988)
		)
		(stroke
			(width 0)
			(type solid)
		)
		(fill yes)
		(layer "In2.Cu")
		(net "M_B_CPU0_SB_CA<5>")
	)
	(gr_poly
		(pts
			(xy 335.801716 -249.01017) (xy 335.754726 -248.85777) (xy 335.493106 -248.85777) (xy 335.446116 -249.01017)
			(xy 335.446116 -249.05462) (xy 335.801716 -249.05462)
		)
		(stroke
			(width 0)
			(type solid)
		)
		(fill yes)
		(layer "In2.Cu")
		(net "M_B_CPU0_SB_CA<1>")
	)
	(gr_poly
		(pts
			(xy 335.801716 -244.126766) (xy 335.754726 -243.974366) (xy 335.493106 -243.974366) (xy 335.446116 -244.126766)
			(xy 335.446116 -244.171216) (xy 335.801716 -244.171216)
		)
		(stroke
			(width 0)
			(type solid)
		)
		(fill yes)
		(layer "In2.Cu")
		(net "M_B_CPU0_SB_CB<4>")
	)
	(gr_poly
		(pts
			(xy 335.801716 -240.46307) (xy 335.801716 -240.418874) (xy 335.446116 -240.418874) (xy 335.446116 -240.46307)
			(xy 335.493106 -240.61547) (xy 335.754726 -240.61547)
		)
		(stroke
			(width 0)
			(type solid)
		)
		(fill yes)
		(layer "In2.Cu")
		(net "M_B_CPU0_SB_CB<3>")
	)
	(gr_poly
		(pts
			(xy 335.801716 -239.243362) (xy 335.754726 -239.090962) (xy 335.493106 -239.090962) (xy 335.446116 -239.243362)
			(xy 335.446116 -239.287812) (xy 335.801716 -239.287812)
		)
		(stroke
			(width 0)
			(type solid)
		)
		(fill yes)
		(layer "In2.Cu")
		(net "M_A_CPU0_SB_DQ<2>")
	)
	(gr_poly
		(pts
			(xy 335.801716 -235.579666) (xy 335.801716 -235.53547) (xy 335.446116 -235.53547) (xy 335.446116 -235.579666)
			(xy 335.493106 -235.732066) (xy 335.754726 -235.732066)
		)
		(stroke
			(width 0)
			(type solid)
		)
		(fill yes)
		(layer "In2.Cu")
		(net "M_A_CPU0_SB_DQ<5>")
	)
	(gr_poly
		(pts
			(xy 335.801716 -234.360466) (xy 335.754726 -234.208066) (xy 335.493106 -234.208066) (xy 335.446116 -234.360466)
			(xy 335.446116 -234.404662) (xy 335.801716 -234.404662)
		)
		(stroke
			(width 0)
			(type solid)
		)
		(fill yes)
		(layer "In2.Cu")
		(net "M_B_CPU0_SB_DQ<10>")
	)
	(gr_poly
		(pts
			(xy 335.801716 -230.696262) (xy 335.801716 -230.652066) (xy 335.446116 -230.652066) (xy 335.446116 -230.696262)
			(xy 335.493106 -230.848662) (xy 335.754726 -230.848662)
		)
		(stroke
			(width 0)
			(type solid)
		)
		(fill yes)
		(layer "In2.Cu")
		(net "M_B_CPU0_SB_DQ<13>")
	)
	(gr_poly
		(pts
			(xy 335.875122 -276.563582) (xy 335.98358 -276.446742) (xy 335.85277 -276.220174) (xy 335.697322 -276.255734)
			(xy 335.658968 -276.277832) (xy 335.836768 -276.58568)
		)
		(stroke
			(width 0)
			(type solid)
		)
		(fill yes)
		(layer "In2.Cu")
		(net "M_B_CPU0_SA_DQS_DP<0>")
	)
	(gr_poly
		(pts
			(xy 335.89468 -273.248882) (xy 335.89468 -273.204686) (xy 335.53908 -273.204686) (xy 335.53908 -273.248882)
			(xy 335.58607 -273.401282) (xy 335.84769 -273.401282)
		)
		(stroke
			(width 0)
			(type solid)
		)
		(fill yes)
		(layer "In2.Cu")
		(net "M_B_CPU0_SA_DQ<5>")
	)
	(gr_poly
		(pts
			(xy 335.896966 -274.876514) (xy 335.896966 -274.832318) (xy 335.541366 -274.832318) (xy 335.541366 -274.876514)
			(xy 335.588356 -275.028914) (xy 335.849976 -275.028914)
		)
		(stroke
			(width 0)
			(type solid)
		)
		(fill yes)
		(layer "In2.Cu")
		(net "M_B_CPU0_SA_DQS_DN<5>")
	)
	(gr_poly
		(pts
			(xy 335.903062 -271.620742) (xy 335.903062 -271.576546) (xy 335.547462 -271.576546) (xy 335.547462 -271.620742)
			(xy 335.594452 -271.773142) (xy 335.856072 -271.773142)
		)
		(stroke
			(width 0)
			(type solid)
		)
		(fill yes)
		(layer "In2.Cu")
		(net "M_A_CPU0_SA_DQ<9>")
	)
	(gr_poly
		(pts
			(xy 335.903062 -268.77391) (xy 335.856072 -268.62151) (xy 335.594452 -268.62151) (xy 335.547462 -268.77391)
			(xy 335.547462 -268.81836) (xy 335.903062 -268.81836)
		)
		(stroke
			(width 0)
			(type solid)
		)
		(fill yes)
		(layer "In2.Cu")
		(net "M_A_CPU0_SA_DQ<14>")
	)
	(gr_poly
		(pts
			(xy 335.903062 -268.365478) (xy 335.903062 -268.321028) (xy 335.547462 -268.321028) (xy 335.547462 -268.365478)
			(xy 335.594452 -268.517878) (xy 335.856072 -268.517878)
		)
		(stroke
			(width 0)
			(type solid)
		)
		(fill yes)
		(layer "In2.Cu")
		(net "M_A_CPU0_SA_DQ<15>")
	)
	(gr_poly
		(pts
			(xy 335.903062 -267.146278) (xy 335.856072 -266.993878) (xy 335.594452 -266.993878) (xy 335.547462 -267.146278)
			(xy 335.547462 -267.190474) (xy 335.903062 -267.190474)
		)
		(stroke
			(width 0)
			(type solid)
		)
		(fill yes)
		(layer "In2.Cu")
		(net "M_B_CPU0_SA_DQ<18>")
	)
	(gr_poly
		(pts
			(xy 335.903062 -265.109706) (xy 335.903062 -265.06551) (xy 335.547462 -265.06551) (xy 335.547462 -265.109706)
			(xy 335.594452 -265.262106) (xy 335.856072 -265.262106)
		)
		(stroke
			(width 0)
			(type solid)
		)
		(fill yes)
		(layer "In2.Cu")
		(net "M_B_CPU0_SA_DQS_DN<7>")
	)
	(gr_poly
		(pts
			(xy 335.903062 -263.891014) (xy 335.856072 -263.738614) (xy 335.594452 -263.738614) (xy 335.547462 -263.891014)
			(xy 335.547462 -263.93521) (xy 335.903062 -263.93521)
		)
		(stroke
			(width 0)
			(type solid)
		)
		(fill yes)
		(layer "In2.Cu")
		(net "M_B_CPU0_SA_DQ<22>")
	)
	(gr_poly
		(pts
			(xy 335.903062 -263.482074) (xy 335.903062 -263.437878) (xy 335.547462 -263.437878) (xy 335.547462 -263.482074)
			(xy 335.594452 -263.634474) (xy 335.856072 -263.634474)
		)
		(stroke
			(width 0)
			(type solid)
		)
		(fill yes)
		(layer "In2.Cu")
		(net "M_B_CPU0_SA_DQ<21>")
	)
	(gr_poly
		(pts
			(xy 335.903062 -262.262874) (xy 335.856072 -262.110474) (xy 335.594452 -262.110474) (xy 335.547462 -262.262874)
			(xy 335.547462 -262.307324) (xy 335.903062 -262.307324)
		)
		(stroke
			(width 0)
			(type solid)
		)
		(fill yes)
		(layer "In2.Cu")
		(net "M_B_CPU0_SA_CB<2>")
	)
	(gr_poly
		(pts
			(xy 335.903062 -260.226302) (xy 335.903062 -260.182106) (xy 335.547462 -260.182106) (xy 335.547462 -260.226302)
			(xy 335.594452 -260.378702) (xy 335.856072 -260.378702)
		)
		(stroke
			(width 0)
			(type solid)
		)
		(fill yes)
		(layer "In2.Cu")
		(net "M_B_CPU0_SA_DQS_DN<9>")
	)
	(gr_poly
		(pts
			(xy 335.903062 -259.00761) (xy 335.856072 -258.85521) (xy 335.594452 -258.85521) (xy 335.547462 -259.00761)
			(xy 335.547462 -259.051806) (xy 335.903062 -259.051806)
		)
		(stroke
			(width 0)
			(type solid)
		)
		(fill yes)
		(layer "In2.Cu")
		(net "M_B_CPU0_SA_CB<6>")
	)
	(gr_poly
		(pts
			(xy 335.903062 -258.59867) (xy 335.903062 -258.554474) (xy 335.547462 -258.554474) (xy 335.547462 -258.59867)
			(xy 335.594452 -258.75107) (xy 335.856072 -258.75107)
		)
		(stroke
			(width 0)
			(type solid)
		)
		(fill yes)
		(layer "In2.Cu")
		(net "M_B_CPU0_SA_CB<5>")
	)
	(gr_poly
		(pts
			(xy 335.903062 -257.37947) (xy 335.856072 -257.22707) (xy 335.594452 -257.22707) (xy 335.547462 -257.37947)
			(xy 335.547462 -257.42392) (xy 335.903062 -257.42392)
		)
		(stroke
			(width 0)
			(type solid)
		)
		(fill yes)
		(layer "In2.Cu")
		(net "M_B_CPU0_SA_CS_N<0>")
	)
	(gr_poly
		(pts
			(xy 335.903062 -256.971038) (xy 335.903062 -256.926588) (xy 335.547462 -256.926588) (xy 335.547462 -256.971038)
			(xy 335.594452 -257.123438) (xy 335.856072 -257.123438)
		)
		(stroke
			(width 0)
			(type solid)
		)
		(fill yes)
		(layer "In2.Cu")
		(net "M_B_CPU0_SA_CS_N<2>")
	)
	(gr_poly
		(pts
			(xy 335.903062 -255.751838) (xy 335.856072 -255.599438) (xy 335.594452 -255.599438) (xy 335.547462 -255.751838)
			(xy 335.547462 -255.796288) (xy 335.903062 -255.796288)
		)
		(stroke
			(width 0)
			(type solid)
		)
		(fill yes)
		(layer "In2.Cu")
		(net "M_B_CPU0_SA_CA<0>")
	)
	(gr_poly
		(pts
			(xy 335.903062 -255.343406) (xy 335.903062 -255.298956) (xy 335.547462 -255.298956) (xy 335.547462 -255.343406)
			(xy 335.594452 -255.495806) (xy 335.856072 -255.495806)
		)
		(stroke
			(width 0)
			(type solid)
		)
		(fill yes)
		(layer "In2.Cu")
		(net "M_B_CPU0_SA_CA<1>")
	)
	(gr_poly
		(pts
			(xy 335.903062 -254.124206) (xy 335.856072 -253.971806) (xy 335.594452 -253.971806) (xy 335.547462 -254.124206)
			(xy 335.547462 -254.168402) (xy 335.903062 -254.168402)
		)
		(stroke
			(width 0)
			(type solid)
		)
		(fill yes)
		(layer "In2.Cu")
		(net "M_B_CPU0_SA_CA<4>")
	)
	(gr_poly
		(pts
			(xy 335.90357 -272.029682) (xy 335.85658 -271.877282) (xy 335.59496 -271.877282) (xy 335.54797 -272.029682)
			(xy 335.54797 -272.073878) (xy 335.90357 -272.073878)
		)
		(stroke
			(width 0)
			(type solid)
		)
		(fill yes)
		(layer "In2.Cu")
		(net "M_A_CPU0_SA_DQ<8>")
	)
	(gr_poly
		(pts
			(xy 335.909158 -281.38755) (xy 335.909158 -281.343354) (xy 335.553558 -281.343354) (xy 335.553558 -281.38755)
			(xy 335.600548 -281.53995) (xy 335.862168 -281.53995)
		)
		(stroke
			(width 0)
			(type solid)
		)
		(fill yes)
		(layer "In2.Cu")
		(net "M_B_CPU0_SA_DQ<2>")
	)
	(gr_poly
		(pts
			(xy 335.911444 -253.715774) (xy 335.911444 -253.671324) (xy 335.555844 -253.671324) (xy 335.555844 -253.715774)
			(xy 335.602834 -253.868174) (xy 335.864454 -253.868174)
		)
		(stroke
			(width 0)
			(type solid)
		)
		(fill yes)
		(layer "In2.Cu")
		(net "M_B_CPU0_SA_CA<5>")
	)
	(gr_poly
		(pts
			(xy 335.911698 -273.657314) (xy 335.864708 -273.504914) (xy 335.603088 -273.504914) (xy 335.556098 -273.657314)
			(xy 335.556098 -273.70151) (xy 335.911698 -273.70151)
		)
		(stroke
			(width 0)
			(type solid)
		)
		(fill yes)
		(layer "In2.Cu")
		(net "M_B_CPU0_SA_DQ<6>")
	)
	(gr_poly
		(pts
			(xy 335.97596 -280.239978) (xy 335.867502 -280.123138) (xy 335.829148 -280.10104) (xy 335.651348 -280.408888)
			(xy 335.689702 -280.430986) (xy 335.84515 -280.466546)
		)
		(stroke
			(width 0)
			(type solid)
		)
		(fill yes)
		(layer "In2.Cu")
		(net "M_B_CPU0_SA_DQ<1>")
	)
	(gr_poly
		(pts
			(xy 335.983072 -278.598884) (xy 335.874614 -278.482044) (xy 335.83626 -278.459946) (xy 335.65846 -278.767794)
			(xy 335.696814 -278.789892) (xy 335.852262 -278.825452)
		)
		(stroke
			(width 0)
			(type solid)
		)
		(fill yes)
		(layer "In2.Cu")
		(net "M_B_CPU0_SA_DQS_DP<0>")
	)
	(gr_poly
		(pts
			(xy 336.229706 -225.048318) (xy 336.338164 -224.931478) (xy 336.207354 -224.70491) (xy 336.051906 -224.74047)
			(xy 336.013552 -224.762568) (xy 336.191352 -225.070416)
		)
		(stroke
			(width 0)
			(type solid)
		)
		(fill yes)
		(layer "In2.Cu")
		(net "M_B_CPU0_SB_DQS_DP<7>")
	)
	(gr_poly
		(pts
			(xy 336.254598 -249.416062) (xy 336.254598 -249.371612) (xy 335.898998 -249.371612) (xy 335.898998 -249.416062)
			(xy 335.945988 -249.568462) (xy 336.207608 -249.568462)
		)
		(stroke
			(width 0)
			(type solid)
		)
		(fill yes)
		(layer "In2.Cu")
		(net "M_B_CPU0_SB_CA<0>")
	)
	(gr_poly
		(pts
			(xy 336.254598 -244.940582) (xy 336.207608 -244.788182) (xy 335.945988 -244.788182) (xy 335.898998 -244.940582)
			(xy 335.898998 -244.985032) (xy 336.254598 -244.985032)
		)
		(stroke
			(width 0)
			(type solid)
		)
		(fill yes)
		(layer "In2.Cu")
		(net "M_B_CPU0_SB_CS_N<1>")
	)
	(gr_poly
		(pts
			(xy 336.254598 -244.532658) (xy 336.254598 -244.488208) (xy 335.898998 -244.488208) (xy 335.898998 -244.532658)
			(xy 335.945988 -244.685058) (xy 336.207608 -244.685058)
		)
		(stroke
			(width 0)
			(type solid)
		)
		(fill yes)
		(layer "In2.Cu")
		(net "M_B_CPU0_SB_CB<6>")
	)
	(gr_poly
		(pts
			(xy 336.254598 -240.057178) (xy 336.207608 -239.904778) (xy 335.945988 -239.904778) (xy 335.898998 -240.057178)
			(xy 335.898998 -240.101628) (xy 336.254598 -240.101628)
		)
		(stroke
			(width 0)
			(type solid)
		)
		(fill yes)
		(layer "In2.Cu")
		(net "M_B_CPU0_SB_CB<1>")
	)
	(gr_poly
		(pts
			(xy 336.254598 -239.649254) (xy 336.254598 -239.604804) (xy 335.898998 -239.604804) (xy 335.898998 -239.649254)
			(xy 335.945988 -239.801654) (xy 336.207608 -239.801654)
		)
		(stroke
			(width 0)
			(type solid)
		)
		(fill yes)
		(layer "In2.Cu")
		(net "M_A_CPU0_SB_DQ<0>")
	)
	(gr_poly
		(pts
			(xy 336.254598 -235.174282) (xy 336.207608 -235.021882) (xy 335.945988 -235.021882) (xy 335.898998 -235.174282)
			(xy 335.898998 -235.218478) (xy 336.254598 -235.218478)
		)
		(stroke
			(width 0)
			(type solid)
		)
		(fill yes)
		(layer "In2.Cu")
		(net "M_A_CPU0_SB_DQ<7>")
	)
	(gr_poly
		(pts
			(xy 336.254598 -234.76585) (xy 336.254598 -234.721654) (xy 335.898998 -234.721654) (xy 335.898998 -234.76585)
			(xy 335.945988 -234.91825) (xy 336.207608 -234.91825)
		)
		(stroke
			(width 0)
			(type solid)
		)
		(fill yes)
		(layer "In2.Cu")
		(net "M_B_CPU0_SB_DQ<8>")
	)
	(gr_poly
		(pts
			(xy 336.254852 -242.905026) (xy 336.254852 -242.860576) (xy 335.899252 -242.860576) (xy 335.899252 -242.905026)
			(xy 335.946242 -243.057426) (xy 336.207862 -243.057426)
		)
		(stroke
			(width 0)
			(type solid)
		)
		(fill yes)
		(layer "In2.Cu")
		(net "M_B_CPU0_SB_DQS_DN<4>")
	)
	(gr_poly
		(pts
			(xy 336.254852 -223.37141) (xy 336.254852 -223.327214) (xy 335.899252 -223.327214) (xy 335.899252 -223.37141)
			(xy 335.946242 -223.52381) (xy 336.207862 -223.52381)
		)
		(stroke
			(width 0)
			(type solid)
		)
		(fill yes)
		(layer "In2.Cu")
		(net "M_B_CPU0_SB_DQ<21>")
	)
	(gr_poly
		(pts
			(xy 336.257138 -248.196354) (xy 336.210148 -248.043954) (xy 335.948528 -248.043954) (xy 335.901538 -248.196354)
			(xy 335.901538 -248.240804) (xy 336.257138 -248.240804)
		)
		(stroke
			(width 0)
			(type solid)
		)
		(fill yes)
		(layer "In2.Cu")
		(net "M_B_CPU0_SB_CA<3>")
	)
	(gr_poly
		(pts
			(xy 336.257138 -246.568722) (xy 336.210148 -246.416322) (xy 335.948528 -246.416322) (xy 335.901538 -246.568722)
			(xy 335.901538 -246.613172) (xy 336.257138 -246.613172)
		)
		(stroke
			(width 0)
			(type solid)
		)
		(fill yes)
		(layer "In2.Cu")
		(net "M_B_CPU0_SB_PAR")
	)
	(gr_poly
		(pts
			(xy 336.257138 -223.779842) (xy 336.210148 -223.627442) (xy 335.948528 -223.627442) (xy 335.901538 -223.779842)
			(xy 335.901538 -223.824292) (xy 336.257138 -223.824292)
		)
		(stroke
			(width 0)
			(type solid)
		)
		(fill yes)
		(layer "In2.Cu")
		(net "M_B_CPU0_SB_DQ<22>")
	)
	(gr_poly
		(pts
			(xy 336.26298 -230.290878) (xy 336.21599 -230.138478) (xy 335.95437 -230.138478) (xy 335.90738 -230.290878)
			(xy 335.90738 -230.335328) (xy 336.26298 -230.335328)
		)
		(stroke
			(width 0)
			(type solid)
		)
		(fill yes)
		(layer "In2.Cu")
		(net "M_B_CPU0_SB_DQ<15>")
	)
	(gr_poly
		(pts
			(xy 336.263234 -236.801914) (xy 336.216244 -236.649514) (xy 335.954624 -236.649514) (xy 335.907634 -236.801914)
			(xy 335.907634 -236.846364) (xy 336.263234 -236.846364)
		)
		(stroke
			(width 0)
			(type solid)
		)
		(fill yes)
		(layer "In2.Cu")
		(net "M_A_CPU0_SB_DQS_DP<5>")
	)
	(gr_poly
		(pts
			(xy 336.267044 -278.709628) (xy 336.22869 -278.68753) (xy 336.073242 -278.65197) (xy 335.942432 -278.878538)
			(xy 336.05089 -278.995378) (xy 336.089244 -279.017476)
		)
		(stroke
			(width 0)
			(type solid)
		)
		(fill yes)
		(layer "In2.Cu")
		(net "M_B_CPU0_SA_DQ<3>")
	)
	(gr_poly
		(pts
			(xy 336.269076 -280.33345) (xy 336.230722 -280.311352) (xy 336.075274 -280.275792) (xy 335.944464 -280.50236)
			(xy 336.052922 -280.6192) (xy 336.091276 -280.641298)
		)
		(stroke
			(width 0)
			(type solid)
		)
		(fill yes)
		(layer "In2.Cu")
		(net "M_B_CPU0_SA_DQ<0>")
	)
	(gr_poly
		(pts
			(xy 336.336132 -225.479102) (xy 336.227674 -225.362262) (xy 336.18932 -225.340164) (xy 336.01152 -225.648012)
			(xy 336.049874 -225.67011) (xy 336.205322 -225.70567)
		)
		(stroke
			(width 0)
			(type solid)
		)
		(fill yes)
		(layer "In2.Cu")
		(net "M_B_CPU0_SB_DQS_DP<7>")
	)
	(gr_poly
		(pts
			(xy 336.338164 -277.365968) (xy 336.446622 -277.249128) (xy 336.315812 -277.02256) (xy 336.160364 -277.05812)
			(xy 336.12201 -277.080218) (xy 336.29981 -277.388066)
		)
		(stroke
			(width 0)
			(type solid)
		)
		(fill yes)
		(layer "In2.Cu")
		(net "M_B_CPU0_SA_DQS_DP<0>")
	)
	(gr_poly
		(pts
			(xy 336.372962 -274.47113) (xy 336.325972 -274.31873) (xy 336.064352 -274.31873) (xy 336.017362 -274.47113)
			(xy 336.017362 -274.51558) (xy 336.372962 -274.51558)
		)
		(stroke
			(width 0)
			(type solid)
		)
		(fill yes)
		(layer "In2.Cu")
		(net "M_B_CPU0_SA_DQS_DP<5>")
	)
	(gr_poly
		(pts
			(xy 336.372962 -274.062698) (xy 336.372962 -274.018248) (xy 336.017362 -274.018248) (xy 336.017362 -274.062698)
			(xy 336.064352 -274.215098) (xy 336.325972 -274.215098)
		)
		(stroke
			(width 0)
			(type solid)
		)
		(fill yes)
		(layer "In2.Cu")
		(net "M_B_CPU0_SA_DQ<4>")
	)
	(gr_poly
		(pts
			(xy 336.372962 -269.587726) (xy 336.325972 -269.435326) (xy 336.064352 -269.435326) (xy 336.017362 -269.587726)
			(xy 336.017362 -269.632176) (xy 336.372962 -269.632176)
		)
		(stroke
			(width 0)
			(type solid)
		)
		(fill yes)
		(layer "In2.Cu")
		(net "M_A_CPU0_SA_DQS_DP<6>")
	)
	(gr_poly
		(pts
			(xy 336.372962 -267.960094) (xy 336.325972 -267.807694) (xy 336.064352 -267.807694) (xy 336.017362 -267.960094)
			(xy 336.017362 -268.004544) (xy 336.372962 -268.004544)
		)
		(stroke
			(width 0)
			(type solid)
		)
		(fill yes)
		(layer "In2.Cu")
		(net "M_A_CPU0_SA_DQ<13>")
	)
	(gr_poly
		(pts
			(xy 336.372962 -267.551662) (xy 336.372962 -267.507212) (xy 336.017362 -267.507212) (xy 336.017362 -267.551662)
			(xy 336.064352 -267.704062) (xy 336.325972 -267.704062)
		)
		(stroke
			(width 0)
			(type solid)
		)
		(fill yes)
		(layer "In2.Cu")
		(net "M_B_CPU0_SA_DQ<16>")
	)
	(gr_poly
		(pts
			(xy 336.372962 -264.70483) (xy 336.325972 -264.55243) (xy 336.064352 -264.55243) (xy 336.017362 -264.70483)
			(xy 336.017362 -264.749026) (xy 336.372962 -264.749026)
		)
		(stroke
			(width 0)
			(type solid)
		)
		(fill yes)
		(layer "In2.Cu")
		(net "M_B_CPU0_SA_DQS_DP<7>")
	)
	(gr_poly
		(pts
			(xy 336.372962 -264.29589) (xy 336.372962 -264.251694) (xy 336.017362 -264.251694) (xy 336.017362 -264.29589)
			(xy 336.064352 -264.44829) (xy 336.325972 -264.44829)
		)
		(stroke
			(width 0)
			(type solid)
		)
		(fill yes)
		(layer "In2.Cu")
		(net "M_B_CPU0_SA_DQ<20>")
	)
	(gr_poly
		(pts
			(xy 336.372962 -263.07669) (xy 336.325972 -262.92429) (xy 336.064352 -262.92429) (xy 336.017362 -263.07669)
			(xy 336.017362 -263.12114) (xy 336.372962 -263.12114)
		)
		(stroke
			(width 0)
			(type solid)
		)
		(fill yes)
		(layer "In2.Cu")
		(net "M_B_CPU0_SA_DQ<23>")
	)
	(gr_poly
		(pts
			(xy 336.372962 -262.668258) (xy 336.372962 -262.623808) (xy 336.017362 -262.623808) (xy 336.017362 -262.668258)
			(xy 336.064352 -262.820658) (xy 336.325972 -262.820658)
		)
		(stroke
			(width 0)
			(type solid)
		)
		(fill yes)
		(layer "In2.Cu")
		(net "M_B_CPU0_SA_CB<0>")
	)
	(gr_poly
		(pts
			(xy 336.372962 -259.821426) (xy 336.325972 -259.669026) (xy 336.064352 -259.669026) (xy 336.017362 -259.821426)
			(xy 336.017362 -259.865622) (xy 336.372962 -259.865622)
		)
		(stroke
			(width 0)
			(type solid)
		)
		(fill yes)
		(layer "In2.Cu")
		(net "M_B_CPU0_SA_DQS_DP<9>")
	)
	(gr_poly
		(pts
			(xy 336.372962 -258.193286) (xy 336.325972 -258.040886) (xy 336.064352 -258.040886) (xy 336.017362 -258.193286)
			(xy 336.017362 -258.237736) (xy 336.372962 -258.237736)
		)
		(stroke
			(width 0)
			(type solid)
		)
		(fill yes)
		(layer "In2.Cu")
		(net "M_B_CPU0_SA_CB<7>")
	)
	(gr_poly
		(pts
			(xy 336.372962 -257.784854) (xy 336.372962 -257.740404) (xy 336.017362 -257.740404) (xy 336.017362 -257.784854)
			(xy 336.064352 -257.937254) (xy 336.325972 -257.937254)
		)
		(stroke
			(width 0)
			(type solid)
		)
		(fill yes)
		(layer "In2.Cu")
		(net "M_B_CPU0_ALERT_N")
	)
	(gr_poly
		(pts
			(xy 336.372962 -256.565654) (xy 336.325972 -256.413254) (xy 336.064352 -256.413254) (xy 336.017362 -256.565654)
			(xy 336.017362 -256.610104) (xy 336.372962 -256.610104)
		)
		(stroke
			(width 0)
			(type solid)
		)
		(fill yes)
		(layer "In2.Cu")
		(net "M_B_CPU0_SA_CS_N<3>")
	)
	(gr_poly
		(pts
			(xy 336.372962 -254.529082) (xy 336.372962 -254.484886) (xy 336.017362 -254.484886) (xy 336.017362 -254.529082)
			(xy 336.064352 -254.681482) (xy 336.325972 -254.681482)
		)
		(stroke
			(width 0)
			(type solid)
		)
		(fill yes)
		(layer "In2.Cu")
		(net "M_B_CPU0_SA_CA<3>")
	)
	(gr_poly
		(pts
			(xy 336.381598 -272.843498) (xy 336.334608 -272.691098) (xy 336.072988 -272.691098) (xy 336.025998 -272.843498)
			(xy 336.025998 -272.887694) (xy 336.381598 -272.887694)
		)
		(stroke
			(width 0)
			(type solid)
		)
		(fill yes)
		(layer "In2.Cu")
		(net "M_B_CPU0_SA_DQ<7>")
	)
	(gr_poly
		(pts
			(xy 336.381598 -272.435066) (xy 336.381598 -272.39087) (xy 336.025998 -272.39087) (xy 336.025998 -272.435066)
			(xy 336.072988 -272.587466) (xy 336.334608 -272.587466)
		)
		(stroke
			(width 0)
			(type solid)
		)
		(fill yes)
		(layer "In2.Cu")
		(net "M_A_CPU0_SA_DQ<10>")
	)
	(gr_poly
		(pts
			(xy 336.447892 -281.049984) (xy 336.339434 -280.933144) (xy 336.30108 -280.911046) (xy 336.12328 -281.218894)
			(xy 336.161634 -281.240992) (xy 336.317082 -281.276552)
		)
		(stroke
			(width 0)
			(type solid)
		)
		(fill yes)
		(layer "In2.Cu")
		(net "M_B_CPU0_SA_DQ<2>")
	)
	(gr_poly
		(pts
			(xy 336.447892 -279.422098) (xy 336.339434 -279.305258) (xy 336.30108 -279.28316) (xy 336.12328 -279.591008)
			(xy 336.161634 -279.613106) (xy 336.317082 -279.648666)
		)
		(stroke
			(width 0)
			(type solid)
		)
		(fill yes)
		(layer "In2.Cu")
		(net "M_B_CPU0_SA_DQ<1>")
	)
	(gr_poly
		(pts
			(xy 336.45475 -277.782528) (xy 336.346292 -277.665688) (xy 336.307938 -277.64359) (xy 336.130138 -277.951438)
			(xy 336.168492 -277.973536) (xy 336.32394 -278.009096)
		)
		(stroke
			(width 0)
			(type solid)
		)
		(fill yes)
		(layer "In2.Cu")
		(net "M_B_CPU0_SA_DQS_DP<0>")
	)
	(gr_poly
		(pts
			(xy 336.588862 -224.85223) (xy 336.627216 -224.830132) (xy 336.449416 -224.522284) (xy 336.411062 -224.544382)
			(xy 336.302604 -224.661222) (xy 336.433414 -224.88779)
		)
		(stroke
			(width 0)
			(type solid)
		)
		(fill yes)
		(layer "In2.Cu")
		(net "M_B_CPU0_SB_DQ<20>")
	)
	(gr_poly
		(pts
			(xy 336.628232 -238.59617) (xy 336.589878 -238.574072) (xy 336.43443 -238.538512) (xy 336.30362 -238.76508)
			(xy 336.412078 -238.88192) (xy 336.450432 -238.904018)
		)
		(stroke
			(width 0)
			(type solid)
		)
		(fill yes)
		(layer "In2.Cu")
		(net "M_A_CPU0_SB_DQ<2>")
	)
	(gr_poly
		(pts
			(xy 336.629248 -225.572574) (xy 336.590894 -225.550476) (xy 336.435446 -225.514916) (xy 336.304636 -225.741484)
			(xy 336.413094 -225.858324) (xy 336.451448 -225.880422)
		)
		(stroke
			(width 0)
			(type solid)
		)
		(fill yes)
		(layer "In2.Cu")
		(net "M_B_CPU0_SB_DQ<20>")
	)
	(gr_poly
		(pts
			(xy 336.701384 -277.175468) (xy 336.739738 -277.15337) (xy 336.561938 -276.845522) (xy 336.523584 -276.86762)
			(xy 336.415126 -276.98446) (xy 336.545936 -277.211028)
		)
		(stroke
			(width 0)
			(type solid)
		)
		(fill yes)
		(layer "In2.Cu")
		(net "M_B_CPU0_SA_DQ<3>")
	)
	(gr_poly
		(pts
			(xy 336.703924 -224.241614) (xy 336.812382 -224.124774) (xy 336.681572 -223.898206) (xy 336.526124 -223.933766)
			(xy 336.48777 -223.955864) (xy 336.66557 -224.263712)
		)
		(stroke
			(width 0)
			(type solid)
		)
		(fill yes)
		(layer "In2.Cu")
		(net "M_B_CPU0_SB_DQ<22>")
	)
	(gr_poly
		(pts
			(xy 336.727038 -247.382538) (xy 336.680048 -247.230138) (xy 336.418428 -247.230138) (xy 336.371438 -247.382538)
			(xy 336.371438 -247.426988) (xy 336.727038 -247.426988)
		)
		(stroke
			(width 0)
			(type solid)
		)
		(fill yes)
		(layer "In2.Cu")
		(net "M_B_CPU0_SB_CA<5>")
	)
	(gr_poly
		(pts
			(xy 336.727038 -243.718334) (xy 336.727038 -243.674138) (xy 336.371438 -243.674138) (xy 336.371438 -243.718334)
			(xy 336.418428 -243.870734) (xy 336.680048 -243.870734)
		)
		(stroke
			(width 0)
			(type solid)
		)
		(fill yes)
		(layer "In2.Cu")
		(net "M_B_CPU0_SB_CB<7>")
	)
	(gr_poly
		(pts
			(xy 336.73034 -231.105202) (xy 336.68335 -230.952802) (xy 336.42173 -230.952802) (xy 336.37474 -231.105202)
			(xy 336.37474 -231.149398) (xy 336.73034 -231.149398)
		)
		(stroke
			(width 0)
			(type solid)
		)
		(fill yes)
		(layer "In2.Cu")
		(net "M_B_CPU0_SB_DQ<14>")
	)
	(gr_poly
		(pts
			(xy 336.731356 -277.904194) (xy 336.693002 -277.882096) (xy 336.537554 -277.846536) (xy 336.406744 -278.073104)
			(xy 336.515202 -278.189944) (xy 336.553556 -278.212042)
		)
		(stroke
			(width 0)
			(type solid)
		)
		(fill yes)
		(layer "In2.Cu")
		(net "M_B_CPU0_SA_DQ<3>")
	)
	(gr_poly
		(pts
			(xy 336.73288 -235.988606) (xy 336.68589 -235.836206) (xy 336.42427 -235.836206) (xy 336.37728 -235.988606)
			(xy 336.37728 -236.032802) (xy 336.73288 -236.032802)
		)
		(stroke
			(width 0)
			(type solid)
		)
		(fill yes)
		(layer "In2.Cu")
		(net "M_A_CPU0_SB_DQ<6>")
	)
	(gr_poly
		(pts
			(xy 336.736944 -279.523444) (xy 336.69859 -279.501346) (xy 336.543142 -279.465786) (xy 336.412332 -279.692354)
			(xy 336.52079 -279.809194) (xy 336.559144 -279.831292)
		)
		(stroke
			(width 0)
			(type solid)
		)
		(fill yes)
		(layer "In2.Cu")
		(net "M_B_CPU0_SA_DQ<0>")
	)
	(gr_poly
		(pts
			(xy 336.736944 -266.501118) (xy 336.69859 -266.47902) (xy 336.543142 -266.44346) (xy 336.412332 -266.670028)
			(xy 336.52079 -266.786868) (xy 336.559144 -266.808966)
		)
		(stroke
			(width 0)
			(type solid)
		)
		(fill yes)
		(layer "In2.Cu")
		(net "M_B_CPU0_SA_DQ<18>")
	)
	(gr_poly
		(pts
			(xy 336.741516 -249.01017) (xy 336.694526 -248.85777) (xy 336.432906 -248.85777) (xy 336.385916 -249.01017)
			(xy 336.385916 -249.05462) (xy 336.741516 -249.05462)
		)
		(stroke
			(width 0)
			(type solid)
		)
		(fill yes)
		(layer "In2.Cu")
		(net "M_B_CPU0_SB_CA<1>")
	)
	(gr_poly
		(pts
			(xy 336.741516 -242.499134) (xy 336.694526 -242.346734) (xy 336.432906 -242.346734) (xy 336.385916 -242.499134)
			(xy 336.385916 -242.54333) (xy 336.741516 -242.54333)
		)
		(stroke
			(width 0)
			(type solid)
		)
		(fill yes)
		(layer "In2.Cu")
		(net "M_B_CPU0_SB_DQS_DP<4>")
	)
	(gr_poly
		(pts
			(xy 336.741516 -235.579666) (xy 336.741516 -235.53547) (xy 336.385916 -235.53547) (xy 336.385916 -235.579666)
			(xy 336.432906 -235.732066) (xy 336.694526 -235.732066)
		)
		(stroke
			(width 0)
			(type solid)
		)
		(fill yes)
		(layer "In2.Cu")
		(net "M_A_CPU0_SB_DQ<5>")
	)
	(gr_poly
		(pts
			(xy 336.741516 -232.324402) (xy 336.741516 -232.279952) (xy 336.385916 -232.279952) (xy 336.385916 -232.324402)
			(xy 336.432906 -232.476802) (xy 336.694526 -232.476802)
		)
		(stroke
			(width 0)
			(type solid)
		)
		(fill yes)
		(layer "In2.Cu")
		(net "M_B_CPU0_SB_DQS_DN<6>")
	)
	(gr_poly
		(pts
			(xy 336.741516 -222.965518) (xy 336.694526 -222.813118) (xy 336.432906 -222.813118) (xy 336.385916 -222.965518)
			(xy 336.385916 -223.009968) (xy 336.741516 -223.009968)
		)
		(stroke
			(width 0)
			(type solid)
		)
		(fill yes)
		(layer "In2.Cu")
		(net "M_B_CPU0_SB_DQ<23>")
	)
	(gr_poly
		(pts
			(xy 336.812382 -239.304068) (xy 336.703924 -239.187228) (xy 336.66557 -239.16513) (xy 336.48777 -239.472978)
			(xy 336.526124 -239.495076) (xy 336.681572 -239.530636)
		)
		(stroke
			(width 0)
			(type solid)
		)
		(fill yes)
		(layer "In2.Cu")
		(net "M_A_CPU0_SB_DQ<0>")
	)
	(gr_poly
		(pts
			(xy 336.83448 -273.248882) (xy 336.83448 -273.204686) (xy 336.47888 -273.204686) (xy 336.47888 -273.248882)
			(xy 336.52587 -273.401282) (xy 336.78749 -273.401282)
		)
		(stroke
			(width 0)
			(type solid)
		)
		(fill yes)
		(layer "In2.Cu")
		(net "M_B_CPU0_SA_DQ<5>")
	)
	(gr_poly
		(pts
			(xy 336.83702 -272.029174) (xy 336.79003 -271.876774) (xy 336.52841 -271.876774) (xy 336.48142 -272.029174)
			(xy 336.48142 -272.073624) (xy 336.83702 -272.073624)
		)
		(stroke
			(width 0)
			(type solid)
		)
		(fill yes)
		(layer "In2.Cu")
		(net "M_A_CPU0_SA_DQ<8>")
	)
	(gr_poly
		(pts
			(xy 336.842862 -274.876514) (xy 336.842862 -274.832064) (xy 336.487262 -274.832064) (xy 336.487262 -274.876514)
			(xy 336.534252 -275.028914) (xy 336.795872 -275.028914)
		)
		(stroke
			(width 0)
			(type solid)
		)
		(fill yes)
		(layer "In2.Cu")
		(net "M_B_CPU0_SA_DQS_DN<5>")
	)
	(gr_poly
		(pts
			(xy 336.842862 -263.891014) (xy 336.795872 -263.738614) (xy 336.534252 -263.738614) (xy 336.487262 -263.891014)
			(xy 336.487262 -263.93521) (xy 336.842862 -263.93521)
		)
		(stroke
			(width 0)
			(type solid)
		)
		(fill yes)
		(layer "In2.Cu")
		(net "M_B_CPU0_SA_DQ<22>")
	)
	(gr_poly
		(pts
			(xy 336.842862 -263.482074) (xy 336.842862 -263.437878) (xy 336.487262 -263.437878) (xy 336.487262 -263.482074)
			(xy 336.534252 -263.634474) (xy 336.795872 -263.634474)
		)
		(stroke
			(width 0)
			(type solid)
		)
		(fill yes)
		(layer "In2.Cu")
		(net "M_B_CPU0_SA_DQ<21>")
	)
	(gr_poly
		(pts
			(xy 336.842862 -259.00761) (xy 336.795872 -258.85521) (xy 336.534252 -258.85521) (xy 336.487262 -259.00761)
			(xy 336.487262 -259.05206) (xy 336.842862 -259.05206)
		)
		(stroke
			(width 0)
			(type solid)
		)
		(fill yes)
		(layer "In2.Cu")
		(net "M_B_CPU0_SA_CB<6>")
	)
	(gr_poly
		(pts
			(xy 336.842862 -258.59867) (xy 336.842862 -258.554474) (xy 336.487262 -258.554474) (xy 336.487262 -258.59867)
			(xy 336.534252 -258.75107) (xy 336.795872 -258.75107)
		)
		(stroke
			(width 0)
			(type solid)
		)
		(fill yes)
		(layer "In2.Cu")
		(net "M_B_CPU0_SA_CB<5>")
	)
	(gr_poly
		(pts
			(xy 336.842862 -256.971038) (xy 336.842862 -256.926588) (xy 336.487262 -256.926588) (xy 336.487262 -256.971038)
			(xy 336.534252 -257.123438) (xy 336.795872 -257.123438)
		)
		(stroke
			(width 0)
			(type solid)
		)
		(fill yes)
		(layer "In2.Cu")
		(net "M_B_CPU0_SA_CS_N<2>")
	)
	(gr_poly
		(pts
			(xy 336.848958 -255.343406) (xy 336.848958 -255.29921) (xy 336.493358 -255.29921) (xy 336.493358 -255.343406)
			(xy 336.540348 -255.495806) (xy 336.801968 -255.495806)
		)
		(stroke
			(width 0)
			(type solid)
		)
		(fill yes)
		(layer "In2.Cu")
		(net "M_B_CPU0_SA_CA<1>")
	)
	(gr_poly
		(pts
			(xy 336.851244 -253.715774) (xy 336.851244 -253.671324) (xy 336.495644 -253.671324) (xy 336.495644 -253.715774)
			(xy 336.542634 -253.868174) (xy 336.804254 -253.868174)
		)
		(stroke
			(width 0)
			(type solid)
		)
		(fill yes)
		(layer "In2.Cu")
		(net "M_B_CPU0_SA_CA<5>")
	)
	(gr_poly
		(pts
			(xy 336.851498 -273.657314) (xy 336.804508 -273.504914) (xy 336.542888 -273.504914) (xy 336.495898 -273.657314)
			(xy 336.495898 -273.70151) (xy 336.851498 -273.70151)
		)
		(stroke
			(width 0)
			(type solid)
		)
		(fill yes)
		(layer "In2.Cu")
		(net "M_B_CPU0_SA_DQ<6>")
	)
	(gr_poly
		(pts
			(xy 336.91576 -280.239978) (xy 336.807302 -280.123138) (xy 336.768948 -280.10104) (xy 336.591148 -280.408888)
			(xy 336.629502 -280.430986) (xy 336.78495 -280.466546)
		)
		(stroke
			(width 0)
			(type solid)
		)
		(fill yes)
		(layer "In2.Cu")
		(net "M_B_CPU0_SA_DQ<2>")
	)
	(gr_poly
		(pts
			(xy 336.91576 -267.217652) (xy 336.807302 -267.100812) (xy 336.768948 -267.078714) (xy 336.591148 -267.386562)
			(xy 336.629502 -267.40866) (xy 336.78495 -267.44422)
		)
		(stroke
			(width 0)
			(type solid)
		)
		(fill yes)
		(layer "In2.Cu")
		(net "M_B_CPU0_SA_DQ<16>")
	)
	(gr_poly
		(pts
			(xy 336.917538 -278.608536) (xy 336.80908 -278.491696) (xy 336.770726 -278.469598) (xy 336.592926 -278.777446)
			(xy 336.63128 -278.799544) (xy 336.786728 -278.835104)
		)
		(stroke
			(width 0)
			(type solid)
		)
		(fill yes)
		(layer "In2.Cu")
		(net "M_B_CPU0_SA_DQ<1>")
	)
	(gr_poly
		(pts
			(xy 337.052412 -224.028254) (xy 337.090766 -224.006156) (xy 336.912966 -223.698308) (xy 336.874612 -223.720406)
			(xy 336.766154 -223.837246) (xy 336.896964 -224.063814)
		)
		(stroke
			(width 0)
			(type solid)
		)
		(fill yes)
		(layer "In2.Cu")
		(net "M_B_CPU0_SB_DQ<21>")
	)
	(gr_poly
		(pts
			(xy 337.16849 -223.418654) (xy 337.276948 -223.301814) (xy 337.146138 -223.075246) (xy 336.99069 -223.110806)
			(xy 336.952336 -223.132904) (xy 337.130136 -223.440752)
		)
		(stroke
			(width 0)
			(type solid)
		)
		(fill yes)
		(layer "In2.Cu")
		(net "M_B_CPU0_SB_DQ<23>")
	)
	(gr_poly
		(pts
			(xy 337.169506 -225.048318) (xy 337.277964 -224.931478) (xy 337.147154 -224.70491) (xy 336.991706 -224.74047)
			(xy 336.953352 -224.762568) (xy 337.131152 -225.070416)
		)
		(stroke
			(width 0)
			(type solid)
		)
		(fill yes)
		(layer "In2.Cu")
		(net "M_B_CPU0_SB_DQ<22>")
	)
	(gr_poly
		(pts
			(xy 337.194398 -249.416062) (xy 337.194398 -249.371612) (xy 336.838798 -249.371612) (xy 336.838798 -249.416062)
			(xy 336.885788 -249.568462) (xy 337.147408 -249.568462)
		)
		(stroke
			(width 0)
			(type solid)
		)
		(fill yes)
		(layer "In2.Cu")
		(net "M_B_CPU0_SB_CA<0>")
	)
	(gr_poly
		(pts
			(xy 337.194398 -246.568722) (xy 337.147408 -246.416322) (xy 336.885788 -246.416322) (xy 336.838798 -246.568722)
			(xy 336.838798 -246.612918) (xy 337.194398 -246.612918)
		)
		(stroke
			(width 0)
			(type solid)
		)
		(fill yes)
		(layer "In2.Cu")
		(net "M_B_CPU0_SB_PAR")
	)
	(gr_poly
		(pts
			(xy 337.194398 -242.905026) (xy 337.194398 -242.860576) (xy 336.838798 -242.860576) (xy 336.838798 -242.905026)
			(xy 336.885788 -243.057426) (xy 337.147408 -243.057426)
		)
		(stroke
			(width 0)
			(type solid)
		)
		(fill yes)
		(layer "In2.Cu")
		(net "M_B_CPU0_SB_DQS_DN<4>")
	)
	(gr_poly
		(pts
			(xy 337.196938 -236.801914) (xy 337.149948 -236.649514) (xy 336.888328 -236.649514) (xy 336.841338 -236.801914)
			(xy 336.841338 -236.846364) (xy 337.196938 -236.846364)
		)
		(stroke
			(width 0)
			(type solid)
		)
		(fill yes)
		(layer "In2.Cu")
		(net "M_A_CPU0_SB_DQS_DP<5>")
	)
	(gr_poly
		(pts
			(xy 337.202526 -248.196354) (xy 337.155536 -248.043954) (xy 336.893916 -248.043954) (xy 336.846926 -248.196354)
			(xy 336.846926 -248.240804) (xy 337.202526 -248.240804)
		)
		(stroke
			(width 0)
			(type solid)
		)
		(fill yes)
		(layer "In2.Cu")
		(net "M_B_CPU0_SB_CA<3>")
	)
	(gr_poly
		(pts
			(xy 337.206844 -278.709628) (xy 337.16849 -278.68753) (xy 337.013042 -278.65197) (xy 336.882232 -278.878538)
			(xy 336.99069 -278.995378) (xy 337.029044 -279.017476)
		)
		(stroke
			(width 0)
			(type solid)
		)
		(fill yes)
		(layer "In2.Cu")
		(net "M_B_CPU0_SA_DQ<0>")
	)
	(gr_poly
		(pts
			(xy 337.237832 -247.6373) (xy 337.241642 -247.593104) (xy 336.887566 -247.562116) (xy 336.883502 -247.606312)
			(xy 336.91703 -247.762268) (xy 337.177888 -247.784874)
		)
		(stroke
			(width 0)
			(type solid)
		)
		(fill yes)
		(layer "In2.Cu")
		(net "M_B_CPU0_SB_CA<5>")
	)
	(gr_poly
		(pts
			(xy 337.275932 -225.479102) (xy 337.167474 -225.362262) (xy 337.12912 -225.340164) (xy 336.95132 -225.648012)
			(xy 336.989674 -225.67011) (xy 337.145122 -225.70567)
		)
		(stroke
			(width 0)
			(type solid)
		)
		(fill yes)
		(layer "In2.Cu")
		(net "M_B_CPU0_SB_DQ<22>")
	)
	(gr_poly
		(pts
			(xy 337.278218 -277.365714) (xy 337.386676 -277.248874) (xy 337.255866 -277.022306) (xy 337.100418 -277.057866)
			(xy 337.062064 -277.079964) (xy 337.239864 -277.387812)
		)
		(stroke
			(width 0)
			(type solid)
		)
		(fill yes)
		(layer "In2.Cu")
		(net "M_B_CPU0_SA_DQ<1>")
	)
	(gr_poly
		(pts
			(xy 337.30692 -272.435066) (xy 337.30692 -272.390616) (xy 336.95132 -272.390616) (xy 336.95132 -272.435066)
			(xy 336.99831 -272.587466) (xy 337.25993 -272.587466)
		)
		(stroke
			(width 0)
			(type solid)
		)
		(fill yes)
		(layer "In2.Cu")
		(net "M_A_CPU0_SA_DQ<10>")
	)
	(gr_poly
		(pts
			(xy 337.312762 -269.587726) (xy 337.265772 -269.435326) (xy 337.004152 -269.435326) (xy 336.957162 -269.587726)
			(xy 336.957162 -269.632176) (xy 337.312762 -269.632176)
		)
		(stroke
			(width 0)
			(type solid)
		)
		(fill yes)
		(layer "In2.Cu")
		(net "M_A_CPU0_SA_DQS_DP<6>")
	)
	(gr_poly
		(pts
			(xy 337.312762 -263.07669) (xy 337.265772 -262.92429) (xy 337.004152 -262.92429) (xy 336.957162 -263.07669)
			(xy 336.957162 -263.12114) (xy 337.312762 -263.12114)
		)
		(stroke
			(width 0)
			(type solid)
		)
		(fill yes)
		(layer "In2.Cu")
		(net "M_B_CPU0_SA_DQ<23>")
	)
	(gr_poly
		(pts
			(xy 337.312762 -258.193286) (xy 337.265772 -258.040886) (xy 337.004152 -258.040886) (xy 336.957162 -258.193286)
			(xy 336.957162 -258.237736) (xy 337.312762 -258.237736)
		)
		(stroke
			(width 0)
			(type solid)
		)
		(fill yes)
		(layer "In2.Cu")
		(net "M_B_CPU0_SA_CB<7>")
	)
	(gr_poly
		(pts
			(xy 337.312762 -257.784854) (xy 337.312762 -257.740404) (xy 336.957162 -257.740404) (xy 336.957162 -257.784854)
			(xy 337.004152 -257.937254) (xy 337.265772 -257.937254)
		)
		(stroke
			(width 0)
			(type solid)
		)
		(fill yes)
		(layer "In2.Cu")
		(net "M_B_CPU0_ALERT_N")
	)
	(gr_poly
		(pts
			(xy 337.312762 -256.565654) (xy 337.265772 -256.413254) (xy 337.004152 -256.413254) (xy 336.957162 -256.565654)
			(xy 336.957162 -256.610104) (xy 337.312762 -256.610104)
		)
		(stroke
			(width 0)
			(type solid)
		)
		(fill yes)
		(layer "In2.Cu")
		(net "M_B_CPU0_SA_CS_N<3>")
	)
	(gr_poly
		(pts
			(xy 337.312762 -254.529082) (xy 337.312762 -254.484886) (xy 336.957162 -254.484886) (xy 336.957162 -254.529082)
			(xy 337.004152 -254.681482) (xy 337.265772 -254.681482)
		)
		(stroke
			(width 0)
			(type solid)
		)
		(fill yes)
		(layer "In2.Cu")
		(net "M_B_CPU0_SA_CA<3>")
	)
	(gr_poly
		(pts
			(xy 337.387692 -279.422098) (xy 337.279234 -279.305258) (xy 337.24088 -279.28316) (xy 337.06308 -279.591008)
			(xy 337.101434 -279.613106) (xy 337.256882 -279.648666)
		)
		(stroke
			(width 0)
			(type solid)
		)
		(fill yes)
		(layer "In2.Cu")
		(net "M_B_CPU0_SA_DQ<2>")
	)
	(gr_poly
		(pts
			(xy 337.392518 -277.786338) (xy 337.28406 -277.669498) (xy 337.245706 -277.6474) (xy 337.067906 -277.955248)
			(xy 337.10626 -277.977346) (xy 337.261708 -278.012906)
		)
		(stroke
			(width 0)
			(type solid)
		)
		(fill yes)
		(layer "In2.Cu")
		(net "M_B_CPU0_SA_DQ<1>")
	)
	(gr_poly
		(pts
			(xy 337.529678 -224.85477) (xy 337.568032 -224.832672) (xy 337.390232 -224.524824) (xy 337.351878 -224.546922)
			(xy 337.24342 -224.663762) (xy 337.37423 -224.89033)
		)
		(stroke
			(width 0)
			(type solid)
		)
		(fill yes)
		(layer "In2.Cu")
		(net "M_B_CPU0_SB_DQ<21>")
	)
	(gr_poly
		(pts
			(xy 337.63839 -270.660368) (xy 337.676744 -270.63827) (xy 337.498944 -270.330422) (xy 337.46059 -270.35252)
			(xy 337.352132 -270.46936) (xy 337.482942 -270.695928)
		)
		(stroke
			(width 0)
			(type solid)
		)
		(fill yes)
		(layer "In2.Cu")
		(net "M_A_CPU0_SA_DQS_DN<6>")
	)
	(gr_poly
		(pts
			(xy 337.639406 -224.234502) (xy 337.747864 -224.117662) (xy 337.617054 -223.891094) (xy 337.461606 -223.926654)
			(xy 337.423252 -223.948752) (xy 337.601052 -224.2566)
		)
		(stroke
			(width 0)
			(type solid)
		)
		(fill yes)
		(layer "In2.Cu")
		(net "M_B_CPU0_SB_DQ<23>")
	)
	(gr_poly
		(pts
			(xy 337.668616 -231.105202) (xy 337.621626 -230.952802) (xy 337.360006 -230.952802) (xy 337.313016 -231.105202)
			(xy 337.313016 -231.149398) (xy 337.668616 -231.149398)
		)
		(stroke
			(width 0)
			(type solid)
		)
		(fill yes)
		(layer "In2.Cu")
		(net "M_B_CPU0_SB_DQ<14>")
	)
	(gr_poly
		(pts
			(xy 337.678776 -277.891748) (xy 337.640422 -277.86965) (xy 337.484974 -277.83409) (xy 337.354164 -278.060658)
			(xy 337.462622 -278.177498) (xy 337.500976 -278.199596)
		)
		(stroke
			(width 0)
			(type solid)
		)
		(fill yes)
		(layer "In2.Cu")
		(net "M_B_CPU0_SA_DQ<0>")
	)
	(gr_poly
		(pts
			(xy 337.681316 -249.01017) (xy 337.634326 -248.85777) (xy 337.372706 -248.85777) (xy 337.325716 -249.01017)
			(xy 337.325716 -249.05462) (xy 337.681316 -249.05462)
		)
		(stroke
			(width 0)
			(type solid)
		)
		(fill yes)
		(layer "In2.Cu")
		(net "M_B_CPU0_SB_CA<1>")
	)
	(gr_poly
		(pts
			(xy 337.782662 -274.876514) (xy 337.782662 -274.832064) (xy 337.427062 -274.832064) (xy 337.427062 -274.876514)
			(xy 337.474052 -275.028914) (xy 337.735672 -275.028914)
		)
		(stroke
			(width 0)
			(type solid)
		)
		(fill yes)
		(layer "In2.Cu")
		(net "M_B_CPU0_SA_DQS_DN<5>")
	)
	(gr_poly
		(pts
			(xy 337.782662 -256.971038) (xy 337.782662 -256.926588) (xy 337.427062 -256.926588) (xy 337.427062 -256.971038)
			(xy 337.474052 -257.123438) (xy 337.735672 -257.123438)
		)
		(stroke
			(width 0)
			(type solid)
		)
		(fill yes)
		(layer "In2.Cu")
		(net "M_B_CPU0_SA_CS_N<2>")
	)
	(gr_poly
		(pts
			(xy 337.788758 -255.343406) (xy 337.788758 -255.298956) (xy 337.433158 -255.298956) (xy 337.433158 -255.343406)
			(xy 337.480148 -255.495806) (xy 337.741768 -255.495806)
		)
		(stroke
			(width 0)
			(type solid)
		)
		(fill yes)
		(layer "In2.Cu")
		(net "M_B_CPU0_SA_CA<1>")
	)
	(gr_poly
		(pts
			(xy 337.857592 -278.608282) (xy 337.749134 -278.491442) (xy 337.71078 -278.469344) (xy 337.53298 -278.777192)
			(xy 337.571334 -278.79929) (xy 337.726782 -278.83485)
		)
		(stroke
			(width 0)
			(type solid)
		)
		(fill yes)
		(layer "In2.Cu")
		(net "M_B_CPU0_SA_DQ<2>")
	)
	(gr_poly
		(pts
			(xy 338.108036 -225.045778) (xy 338.216494 -224.928938) (xy 338.085684 -224.70237) (xy 337.930236 -224.73793)
			(xy 337.891882 -224.760028) (xy 338.069682 -225.067876)
		)
		(stroke
			(width 0)
			(type solid)
		)
		(fill yes)
		(layer "In2.Cu")
		(net "M_B_CPU0_SB_DQ<23>")
	)
	(gr_poly
		(pts
			(xy 338.136738 -249.416062) (xy 338.136738 -249.371612) (xy 337.781138 -249.371612) (xy 337.781138 -249.416062)
			(xy 337.828128 -249.568462) (xy 338.089748 -249.568462)
		)
		(stroke
			(width 0)
			(type solid)
		)
		(fill yes)
		(layer "In2.Cu")
		(net "M_B_CPU0_SB_CA<0>")
	)
	(gr_poly
		(pts
			(xy 338.225384 -277.377652) (xy 338.333842 -277.260812) (xy 338.203032 -277.034244) (xy 338.047584 -277.069804)
			(xy 338.00923 -277.091902) (xy 338.18703 -277.39975)
		)
		(stroke
			(width 0)
			(type solid)
		)
		(fill yes)
		(layer "In2.Cu")
		(net "M_B_CPU0_SA_DQ<2>")
	)
	(gr_poly
		(pts
			(xy 338.252562 -270.806926) (xy 338.252562 -270.76273) (xy 337.896962 -270.76273) (xy 337.896962 -270.806926)
			(xy 337.943952 -270.959326) (xy 338.205572 -270.959326)
		)
		(stroke
			(width 0)
			(type solid)
		)
		(fill yes)
		(layer "In2.Cu")
		(net "M_A_CPU0_SA_DQS_DN<6>")
	)
	(gr_poly
		(pts
			(xy 338.332572 -277.786084) (xy 338.224114 -277.669244) (xy 338.18576 -277.647146) (xy 338.00796 -277.954994)
			(xy 338.046314 -277.977092) (xy 338.201762 -278.012652)
		)
		(stroke
			(width 0)
			(type solid)
		)
		(fill yes)
		(layer "In2.Cu")
		(net "M_B_CPU0_SA_DQ<2>")
	)
	(gr_poly
		(pts
			(xy 377.110244 -256.01041) (xy 377.148598 -255.988312) (xy 376.970798 -255.680464) (xy 376.932444 -255.702562)
			(xy 376.823986 -255.819402) (xy 376.954796 -256.04597)
		)
		(stroke
			(width 0)
			(type solid)
		)
		(fill yes)
		(layer "In2.Cu")
		(net "M_F_CPU0_SB_CA<0>")
	)
	(gr_poly
		(pts
			(xy 377.151392 -255.102868) (xy 377.113038 -255.08077) (xy 376.95759 -255.04521) (xy 376.82678 -255.271778)
			(xy 376.935238 -255.388618) (xy 376.973592 -255.410716)
		)
		(stroke
			(width 0)
			(type solid)
		)
		(fill yes)
		(layer "In2.Cu")
		(net "M_F_CPU0_SB_CA<0>")
	)
	(gr_poly
		(pts
			(xy 377.575572 -256.817114) (xy 377.613926 -256.795016) (xy 377.436126 -256.487168) (xy 377.397772 -256.509266)
			(xy 377.289314 -256.626106) (xy 377.420124 -256.852674)
		)
		(stroke
			(width 0)
			(type solid)
		)
		(fill yes)
		(layer "In2.Cu")
		(net "M_F_CPU0_SB_CA<0>")
	)
	(gr_poly
		(pts
			(xy 377.618244 -254.292862) (xy 377.57989 -254.270764) (xy 377.424442 -254.235204) (xy 377.293632 -254.461772)
			(xy 377.40209 -254.578612) (xy 377.440444 -254.60071)
		)
		(stroke
			(width 0)
			(type solid)
		)
		(fill yes)
		(layer "In2.Cu")
		(net "M_F_CPU0_SB_CA<0>")
	)
	(gr_poly
		(pts
			(xy 377.690888 -256.206498) (xy 377.799346 -256.089658) (xy 377.668536 -255.86309) (xy 377.513088 -255.89865)
			(xy 377.474734 -255.920748) (xy 377.652534 -256.228596)
		)
		(stroke
			(width 0)
			(type solid)
		)
		(fill yes)
		(layer "In2.Cu")
		(net "M_F_CPU0_SB_CA<1>")
	)
	(gr_poly
		(pts
			(xy 377.801632 -255.001522) (xy 377.693174 -254.884682) (xy 377.65482 -254.862584) (xy 377.47702 -255.170432)
			(xy 377.515374 -255.19253) (xy 377.670822 -255.22809)
		)
		(stroke
			(width 0)
			(type solid)
		)
		(fill yes)
		(layer "In2.Cu")
		(net "M_F_CPU0_SB_CA<1>")
	)
	(gr_poly
		(pts
			(xy 378.275342 -254.181356) (xy 378.166884 -254.064516) (xy 378.12853 -254.042418) (xy 377.95073 -254.350266)
			(xy 377.989084 -254.372364) (xy 378.144532 -254.407924)
		)
		(stroke
			(width 0)
			(type solid)
		)
		(fill yes)
		(layer "In2.Cu")
		(net "M_F_CPU0_SB_CA<1>")
	)
	(gr_poly
		(pts
			(xy 378.65558 -256.157222) (xy 378.65558 -256.113026) (xy 378.29998 -256.113026) (xy 378.29998 -256.157222)
			(xy 378.34697 -256.309622) (xy 378.60859 -256.309622)
		)
		(stroke
			(width 0)
			(type solid)
		)
		(fill yes)
		(layer "In2.Cu")
		(net "M_F_CPU0_CLK_DP<1>")
	)
	(gr_poly
		(pts
			(xy 379.142498 -255.751838) (xy 379.095508 -255.599438) (xy 378.833888 -255.599438) (xy 378.786898 -255.751838)
			(xy 378.786898 -255.796034) (xy 379.142498 -255.796034)
		)
		(stroke
			(width 0)
			(type solid)
		)
		(fill yes)
		(layer "In2.Cu")
		(net "M_F_CPU0_CLK_DN<1>")
	)
	(gr_poly
		(pts
			(xy 379.59538 -256.157222) (xy 379.59538 -256.113026) (xy 379.23978 -256.113026) (xy 379.23978 -256.157222)
			(xy 379.28677 -256.309622) (xy 379.54839 -256.309622)
		)
		(stroke
			(width 0)
			(type solid)
		)
		(fill yes)
		(layer "In2.Cu")
		(net "M_F_CPU0_CLK_DP<1>")
	)
	(gr_poly
		(pts
			(xy 380.438914 -254.290322) (xy 380.40056 -254.268224) (xy 380.245112 -254.232664) (xy 380.114302 -254.459232)
			(xy 380.22276 -254.576072) (xy 380.261114 -254.59817)
		)
		(stroke
			(width 0)
			(type solid)
		)
		(fill yes)
		(layer "In2.Cu")
		(net "M_F_CPU0_CLK_DN<0>")
	)
	(gr_poly
		(pts
			(xy 380.543562 -256.565654) (xy 380.496572 -256.413254) (xy 380.234952 -256.413254) (xy 380.187962 -256.565654)
			(xy 380.187962 -256.610104) (xy 380.543562 -256.610104)
		)
		(stroke
			(width 0)
			(type solid)
		)
		(fill yes)
		(layer "In2.Cu")
		(net "M_F_CPU0_SA_PAR")
	)
	(gr_poly
		(pts
			(xy 380.543562 -256.157222) (xy 380.543562 -256.112772) (xy 380.187962 -256.112772) (xy 380.187962 -256.157222)
			(xy 380.234952 -256.309622) (xy 380.496572 -256.309622)
		)
		(stroke
			(width 0)
			(type solid)
		)
		(fill yes)
		(layer "In2.Cu")
		(net "M_F_CPU0_CLK_DP<1>")
	)
	(gr_poly
		(pts
			(xy 380.617984 -255.007364) (xy 380.509526 -254.890524) (xy 380.471172 -254.868426) (xy 380.293372 -255.176274)
			(xy 380.331726 -255.198372) (xy 380.487174 -255.233932)
		)
		(stroke
			(width 0)
			(type solid)
		)
		(fill yes)
		(layer "In2.Cu")
		(net "M_F_CPU0_CLK_DP<0>")
	)
	(gr_poly
		(pts
			(xy 380.90856 -255.1049) (xy 380.870206 -255.082802) (xy 380.714758 -255.047242) (xy 380.583948 -255.27381)
			(xy 380.692406 -255.39065) (xy 380.73076 -255.412748)
		)
		(stroke
			(width 0)
			(type solid)
		)
		(fill yes)
		(layer "In2.Cu")
		(net "M_F_CPU0_CLK_DN<1>")
	)
	(gr_poly
		(pts
			(xy 381.019558 -256.971038) (xy 381.019558 -256.926842) (xy 380.663958 -256.926842) (xy 380.663958 -256.971038)
			(xy 380.710948 -257.123438) (xy 380.972568 -257.123438)
		)
		(stroke
			(width 0)
			(type solid)
		)
		(fill yes)
		(layer "In2.Cu")
		(net "M_F_CPU0_SA_CA<6>")
	)
	(gr_poly
		(pts
			(xy 381.088392 -255.819402) (xy 380.979934 -255.702562) (xy 380.94158 -255.680464) (xy 380.76378 -255.988312)
			(xy 380.802134 -256.01041) (xy 380.957582 -256.04597)
		)
		(stroke
			(width 0)
			(type solid)
		)
		(fill yes)
		(layer "In2.Cu")
		(net "M_F_CPU0_CLK_DP<1>")
	)
	(gr_poly
		(pts
			(xy 381.094488 -254.18034) (xy 380.98603 -254.0635) (xy 380.947676 -254.041402) (xy 380.769876 -254.34925)
			(xy 380.80823 -254.371348) (xy 380.963678 -254.406908)
		)
		(stroke
			(width 0)
			(type solid)
		)
		(fill yes)
		(layer "In2.Cu")
		(net "M_F_CPU0_CLK_DP<0>")
	)
	(gr_poly
		(pts
			(xy 381.334772 -279.605994) (xy 381.373126 -279.583896) (xy 381.195326 -279.276048) (xy 381.156972 -279.298146)
			(xy 381.048514 -279.414986) (xy 381.179324 -279.641554)
		)
		(stroke
			(width 0)
			(type solid)
		)
		(fill yes)
		(layer "In2.Cu")
		(net "M_F_CPU0_SA_DQ<0>")
	)
	(gr_poly
		(pts
			(xy 381.373126 -254.299974) (xy 381.334772 -254.277876) (xy 381.179324 -254.242316) (xy 381.048514 -254.468884)
			(xy 381.156972 -254.585724) (xy 381.195326 -254.607822)
		)
		(stroke
			(width 0)
			(type solid)
		)
		(fill yes)
		(layer "In2.Cu")
		(net "M_F_CPU0_CLK_DN<1>")
	)
	(gr_poly
		(pts
			(xy 381.377444 -255.920748) (xy 381.33909 -255.89865) (xy 381.183642 -255.86309) (xy 381.052832 -256.089658)
			(xy 381.16129 -256.206498) (xy 381.199644 -256.228596)
		)
		(stroke
			(width 0)
			(type solid)
		)
		(fill yes)
		(layer "In2.Cu")
		(net "M_F_CPU0_SA_PAR")
	)
	(gr_poly
		(pts
			(xy 381.557276 -256.635758) (xy 381.448818 -256.518918) (xy 381.410464 -256.49682) (xy 381.232664 -256.804668)
			(xy 381.271018 -256.826766) (xy 381.426466 -256.862326)
		)
		(stroke
			(width 0)
			(type solid)
		)
		(fill yes)
		(layer "In2.Cu")
		(net "M_F_CPU0_SA_CA<6>")
	)
	(gr_poly
		(pts
			(xy 381.55753 -255.007364) (xy 381.449072 -254.890524) (xy 381.410718 -254.868426) (xy 381.232918 -255.176274)
			(xy 381.271272 -255.198372) (xy 381.42672 -255.233932)
		)
		(stroke
			(width 0)
			(type solid)
		)
		(fill yes)
		(layer "In2.Cu")
		(net "M_F_CPU0_CLK_DP<1>")
	)
	(gr_poly
		(pts
			(xy 381.812038 -280.430986) (xy 381.850392 -280.408888) (xy 381.672592 -280.10104) (xy 381.634238 -280.123138)
			(xy 381.52578 -280.239978) (xy 381.65659 -280.466546)
		)
		(stroke
			(width 0)
			(type solid)
		)
		(fill yes)
		(layer "In2.Cu")
		(net "M_F_CPU0_SA_DQ<0>")
	)
	(gr_poly
		(pts
			(xy 381.84836 -255.1049) (xy 381.810006 -255.082802) (xy 381.654558 -255.047242) (xy 381.523748 -255.27381)
			(xy 381.632206 -255.39065) (xy 381.67056 -255.412748)
		)
		(stroke
			(width 0)
			(type solid)
		)
		(fill yes)
		(layer "In2.Cu")
		(net "M_F_CPU0_SA_PAR")
	)
	(gr_poly
		(pts
			(xy 381.924306 -279.816306) (xy 382.032764 -279.699466) (xy 381.901954 -279.472898) (xy 381.746506 -279.508458)
			(xy 381.708152 -279.530556) (xy 381.885952 -279.838404)
		)
		(stroke
			(width 0)
			(type solid)
		)
		(fill yes)
		(layer "In2.Cu")
		(net "M_F_CPU0_SA_DQ<2>")
	)
	(gr_poly
		(pts
			(xy 381.961898 -254.123698) (xy 381.914908 -253.971298) (xy 381.653288 -253.971298) (xy 381.606298 -254.123698)
			(xy 381.606298 -254.168148) (xy 381.961898 -254.168148)
		)
		(stroke
			(width 0)
			(type solid)
		)
		(fill yes)
		(layer "In2.Cu")
		(net "M_F_CPU0_CLK_DN<1>")
	)
	(gr_poly
		(pts
			(xy 382.034542 -255.809242) (xy 381.926084 -255.692402) (xy 381.88773 -255.670304) (xy 381.70993 -255.978152)
			(xy 381.748284 -256.00025) (xy 381.903732 -256.03581)
		)
		(stroke
			(width 0)
			(type solid)
		)
		(fill yes)
		(layer "In2.Cu")
		(net "M_F_CPU0_SA_CA<6>")
	)
	(gr_poly
		(pts
			(xy 382.31318 -244.53215) (xy 382.31318 -244.487954) (xy 381.95758 -244.487954) (xy 381.95758 -244.53215)
			(xy 382.00457 -244.68455) (xy 382.26619 -244.68455)
		)
		(stroke
			(width 0)
			(type solid)
		)
		(fill yes)
		(layer "In2.Cu")
		(net "M_F_CPU0_SB_CS_N<2>")
	)
	(gr_poly
		(pts
			(xy 382.41478 -280.574242) (xy 382.41478 -280.529792) (xy 382.05918 -280.529792) (xy 382.05918 -280.574242)
			(xy 382.10617 -280.726642) (xy 382.36779 -280.726642)
		)
		(stroke
			(width 0)
			(type solid)
		)
		(fill yes)
		(layer "In2.Cu")
		(net "M_F_CPU0_SA_DQ<0>")
	)
	(gr_poly
		(pts
			(xy 382.41478 -254.937514) (xy 382.36779 -254.785114) (xy 382.10617 -254.785114) (xy 382.05918 -254.937514)
			(xy 382.05918 -254.981964) (xy 382.41478 -254.981964)
		)
		(stroke
			(width 0)
			(type solid)
		)
		(fill yes)
		(layer "In2.Cu")
		(net "M_F_CPU0_SA_PAR")
	)
	(gr_poly
		(pts
			(xy 382.41478 -254.52959) (xy 382.41478 -254.48514) (xy 382.05918 -254.48514) (xy 382.05918 -254.52959)
			(xy 382.10617 -254.68199) (xy 382.36779 -254.68199)
		)
		(stroke
			(width 0)
			(type solid)
		)
		(fill yes)
		(layer "In2.Cu")
		(net "M_F_CPU0_CLK_DP<1>")
	)
	(gr_poly
		(pts
			(xy 382.422908 -258.28879) (xy 382.375918 -258.13639) (xy 382.114298 -258.13639) (xy 382.067308 -258.28879)
			(xy 382.067308 -258.33324) (xy 382.422908 -258.33324)
		)
		(stroke
			(width 0)
			(type solid)
		)
		(fill yes)
		(layer "In2.Cu")
		(net "M_F_CPU0_SA_CA<0>")
	)
	(gr_poly
		(pts
			(xy 382.639062 -247.64111) (xy 382.677416 -247.619012) (xy 382.499616 -247.311164) (xy 382.461262 -247.333262)
			(xy 382.352804 -247.450102) (xy 382.483614 -247.67667)
		)
		(stroke
			(width 0)
			(type solid)
		)
		(fill yes)
		(layer "In2.Cu")
		(net "M_F_CPU0_SB_CA<2>")
	)
	(gr_poly
		(pts
			(xy 382.749806 -247.023382) (xy 382.858264 -246.906542) (xy 382.727454 -246.679974) (xy 382.572006 -246.715534)
			(xy 382.533652 -246.737632) (xy 382.711452 -247.04548)
		)
		(stroke
			(width 0)
			(type solid)
		)
		(fill yes)
		(layer "In2.Cu")
		(net "M_F_CPU0_SB_CA<3>")
	)
	(gr_poly
		(pts
			(xy 382.754124 -242.14709) (xy 382.862582 -242.03025) (xy 382.731772 -241.803682) (xy 382.576324 -241.839242)
			(xy 382.53797 -241.86134) (xy 382.71577 -242.169188)
		)
		(stroke
			(width 0)
			(type solid)
		)
		(fill yes)
		(layer "In2.Cu")
		(net "M_F_CPU0_SB_CB<6>")
	)
	(gr_poly
		(pts
			(xy 382.783588 -240.46307) (xy 382.783588 -240.41862) (xy 382.427988 -240.41862) (xy 382.427988 -240.46307)
			(xy 382.474978 -240.61547) (xy 382.736598 -240.61547)
		)
		(stroke
			(width 0)
			(type solid)
		)
		(fill yes)
		(layer "In2.Cu")
		(net "M_F_CPU0_SB_DQS_DP<9>")
	)
	(gr_poly
		(pts
			(xy 382.791716 -243.718842) (xy 382.791716 -243.674392) (xy 382.436116 -243.674392) (xy 382.436116 -243.718842)
			(xy 382.483106 -243.871242) (xy 382.744726 -243.871242)
		)
		(stroke
			(width 0)
			(type solid)
		)
		(fill yes)
		(layer "In2.Cu")
		(net "M_F_CPU0_SB_CS_N<3>")
	)
	(gr_poly
		(pts
			(xy 382.88468 -257.37947) (xy 382.83769 -257.22707) (xy 382.57607 -257.22707) (xy 382.52908 -257.37947)
			(xy 382.52908 -257.423666) (xy 382.88468 -257.423666)
		)
		(stroke
			(width 0)
			(type solid)
		)
		(fill yes)
		(layer "In2.Cu")
		(net "M_F_CPU0_SA_CA<2>")
	)
	(gr_poly
		(pts
			(xy 382.893062 -280.168604) (xy 382.846072 -280.016204) (xy 382.584452 -280.016204) (xy 382.537462 -280.168604)
			(xy 382.537462 -280.2128) (xy 382.893062 -280.2128)
		)
		(stroke
			(width 0)
			(type solid)
		)
		(fill yes)
		(layer "In2.Cu")
		(net "M_F_CPU0_SA_DQ<2>")
	)
	(gr_poly
		(pts
			(xy 382.893316 -276.913086) (xy 382.846326 -276.760686) (xy 382.584706 -276.760686) (xy 382.537716 -276.913086)
			(xy 382.537716 -276.957282) (xy 382.893316 -276.957282)
		)
		(stroke
			(width 0)
			(type solid)
		)
		(fill yes)
		(layer "In2.Cu")
		(net "M_F_CPU0_SA_DQ<4>")
	)
	(gr_poly
		(pts
			(xy 382.893316 -258.503674) (xy 382.893316 -258.459224) (xy 382.537716 -258.459224) (xy 382.537716 -258.503674)
			(xy 382.584706 -258.656074) (xy 382.846326 -258.656074)
		)
		(stroke
			(width 0)
			(type solid)
		)
		(fill yes)
		(layer "In2.Cu")
		(net "M_F_CPU0_SA_CA<0>")
	)
	(gr_poly
		(pts
			(xy 382.899158 -260.226302) (xy 382.899158 -260.182106) (xy 382.543558 -260.182106) (xy 382.543558 -260.226302)
			(xy 382.590548 -260.378702) (xy 382.852168 -260.378702)
		)
		(stroke
			(width 0)
			(type solid)
		)
		(fill yes)
		(layer "In2.Cu")
		(net "M_F_CPU0_ALERT_N")
	)
	(gr_poly
		(pts
			(xy 382.899158 -259.00761) (xy 382.852168 -258.85521) (xy 382.590548 -258.85521) (xy 382.543558 -259.00761)
			(xy 382.543558 -259.051806) (xy 382.899158 -259.051806)
		)
		(stroke
			(width 0)
			(type solid)
		)
		(fill yes)
		(layer "In2.Cu")
		(net "M_F_CPU0_SA_CS_N<3>")
	)
	(gr_poly
		(pts
			(xy 382.899158 -255.343406) (xy 382.899158 -255.298956) (xy 382.543558 -255.298956) (xy 382.543558 -255.343406)
			(xy 382.590548 -255.495806) (xy 382.852168 -255.495806)
		)
		(stroke
			(width 0)
			(type solid)
		)
		(fill yes)
		(layer "In2.Cu")
		(net "M_F_CPU0_SA_CA<6>")
	)
	(gr_poly
		(pts
			(xy 382.899158 -254.124206) (xy 382.852168 -253.971806) (xy 382.590548 -253.971806) (xy 382.543558 -254.124206)
			(xy 382.543558 -254.168402) (xy 382.899158 -254.168402)
		)
		(stroke
			(width 0)
			(type solid)
		)
		(fill yes)
		(layer "In2.Cu")
		(net "M_F_CPU0_CLK_DN<1>")
	)
	(gr_poly
		(pts
			(xy 382.901698 -269.993618) (xy 382.901698 -269.949168) (xy 382.546098 -269.949168) (xy 382.546098 -269.993618)
			(xy 382.593088 -270.146018) (xy 382.854708 -270.146018)
		)
		(stroke
			(width 0)
			(type solid)
		)
		(fill yes)
		(layer "In2.Cu")
		(net "M_F_CPU0_SA_DQ<16>")
	)
	(gr_poly
		(pts
			(xy 383.108962 -246.827294) (xy 383.147316 -246.805196) (xy 382.969516 -246.497348) (xy 382.931162 -246.519446)
			(xy 382.822704 -246.636286) (xy 382.953514 -246.862854)
		)
		(stroke
			(width 0)
			(type solid)
		)
		(fill yes)
		(layer "In2.Cu")
		(net "M_F_CPU0_SB_CA<4>")
	)
	(gr_poly
		(pts
			(xy 383.149348 -237.78083) (xy 383.110994 -237.758732) (xy 382.955546 -237.723172) (xy 382.824736 -237.94974)
			(xy 382.933194 -238.06658) (xy 382.971548 -238.088678)
		)
		(stroke
			(width 0)
			(type solid)
		)
		(fill yes)
		(layer "In2.Cu")
		(net "M_F_CPU0_SB_CB<3>")
	)
	(gr_poly
		(pts
			(xy 383.219706 -279.615646) (xy 383.25806 -279.593548) (xy 383.08026 -279.2857) (xy 383.041906 -279.307798)
			(xy 382.933448 -279.424638) (xy 383.064258 -279.651206)
		)
		(stroke
			(width 0)
			(type solid)
		)
		(fill yes)
		(layer "In2.Cu")
		(net "M_F_CPU0_SA_DQ<3>")
	)
	(gr_poly
		(pts
			(xy 383.247138 -244.532658) (xy 383.247138 -244.488208) (xy 382.891538 -244.488208) (xy 382.891538 -244.532658)
			(xy 382.938528 -244.685058) (xy 383.200148 -244.685058)
		)
		(stroke
			(width 0)
			(type solid)
		)
		(fill yes)
		(layer "In2.Cu")
		(net "M_F_CPU0_SB_CS_N<2>")
	)
	(gr_poly
		(pts
			(xy 383.247138 -243.31295) (xy 383.200148 -243.16055) (xy 382.938528 -243.16055) (xy 382.891538 -243.31295)
			(xy 382.891538 -243.3574) (xy 383.247138 -243.3574)
		)
		(stroke
			(width 0)
			(type solid)
		)
		(fill yes)
		(layer "In2.Cu")
		(net "M_F_CPU0_SB_CS_N<1>")
	)
	(gr_poly
		(pts
			(xy 383.247138 -242.905026) (xy 383.247138 -242.860576) (xy 382.891538 -242.860576) (xy 382.891538 -242.905026)
			(xy 382.938528 -243.057426) (xy 383.200148 -243.057426)
		)
		(stroke
			(width 0)
			(type solid)
		)
		(fill yes)
		(layer "In2.Cu")
		(net "M_F_CPU0_SB_CB<4>")
	)
	(gr_poly
		(pts
			(xy 383.247138 -236.801914) (xy 383.200148 -236.649514) (xy 382.938528 -236.649514) (xy 382.891538 -236.801914)
			(xy 382.891538 -236.846364) (xy 383.247138 -236.846364)
		)
		(stroke
			(width 0)
			(type solid)
		)
		(fill yes)
		(layer "In2.Cu")
		(net "M_E_CPU0_SB_DQ<2>")
	)
	(gr_poly
		(pts
			(xy 383.253234 -247.787922) (xy 383.253234 -247.743472) (xy 382.897634 -247.743472) (xy 382.897634 -247.787922)
			(xy 382.944624 -247.940322) (xy 383.206244 -247.940322)
		)
		(stroke
			(width 0)
			(type solid)
		)
		(fill yes)
		(layer "In2.Cu")
		(net "M_F_CPU0_SB_CA<2>")
	)
	(gr_poly
		(pts
			(xy 383.256536 -241.276886) (xy 383.256536 -241.232436) (xy 382.900936 -241.232436) (xy 382.900936 -241.276886)
			(xy 382.947926 -241.429286) (xy 383.209546 -241.429286)
		)
		(stroke
			(width 0)
			(type solid)
		)
		(fill yes)
		(layer "In2.Cu")
		(net "M_F_CPU0_SB_CB<5>")
	)
	(gr_poly
		(pts
			(xy 383.257298 -236.393482) (xy 383.257298 -236.349032) (xy 382.901698 -236.349032) (xy 382.901698 -236.393482)
			(xy 382.948688 -236.545882) (xy 383.210308 -236.545882)
		)
		(stroke
			(width 0)
			(type solid)
		)
		(fill yes)
		(layer "In2.Cu")
		(net "M_E_CPU0_SB_DQ<1>")
	)
	(gr_poly
		(pts
			(xy 383.259076 -260.800088) (xy 383.220722 -260.77799) (xy 383.065274 -260.74243) (xy 382.934464 -260.968998)
			(xy 383.042922 -261.085838) (xy 383.081276 -261.107936)
		)
		(stroke
			(width 0)
			(type solid)
		)
		(fill yes)
		(layer "In2.Cu")
		(net "M_F_CPU0_SA_CB<7>")
	)
	(gr_poly
		(pts
			(xy 383.328164 -238.497364) (xy 383.219706 -238.380524) (xy 383.181352 -238.358426) (xy 383.003552 -238.666274)
			(xy 383.041906 -238.688372) (xy 383.197354 -238.723932)
		)
		(stroke
			(width 0)
			(type solid)
		)
		(fill yes)
		(layer "In2.Cu")
		(net "M_F_CPU0_SB_CB<1>")
	)
	(gr_poly
		(pts
			(xy 383.35458 -274.47113) (xy 383.30759 -274.31873) (xy 383.04597 -274.31873) (xy 382.99898 -274.47113)
			(xy 382.99898 -274.515326) (xy 383.35458 -274.515326)
		)
		(stroke
			(width 0)
			(type solid)
		)
		(fill yes)
		(layer "In2.Cu")
		(net "M_E_CPU0_SA_DQ<10>")
	)
	(gr_poly
		(pts
			(xy 383.35458 -274.062698) (xy 383.35458 -274.018502) (xy 382.99898 -274.018502) (xy 382.99898 -274.062698)
			(xy 383.04597 -274.215098) (xy 383.30759 -274.215098)
		)
		(stroke
			(width 0)
			(type solid)
		)
		(fill yes)
		(layer "In2.Cu")
		(net "M_E_CPU0_SA_DQ<9>")
	)
	(gr_poly
		(pts
			(xy 383.35458 -269.587726) (xy 383.30759 -269.435326) (xy 383.04597 -269.435326) (xy 382.99898 -269.587726)
			(xy 382.99898 -269.631922) (xy 383.35458 -269.631922)
		)
		(stroke
			(width 0)
			(type solid)
		)
		(fill yes)
		(layer "In2.Cu")
		(net "M_F_CPU0_SA_DQ<18>")
	)
	(gr_poly
		(pts
			(xy 383.362962 -263.077706) (xy 383.315972 -262.925306) (xy 383.054352 -262.925306) (xy 383.007362 -263.077706)
			(xy 383.007362 -263.121902) (xy 383.362962 -263.121902)
		)
		(stroke
			(width 0)
			(type solid)
		)
		(fill yes)
		(layer "In2.Cu")
		(net "M_F_CPU0_SA_DQS_DN<4>")
	)
	(gr_poly
		(pts
			(xy 383.362962 -259.412486) (xy 383.362962 -259.36829) (xy 383.007362 -259.36829) (xy 383.007362 -259.412486)
			(xy 383.054352 -259.564886) (xy 383.315972 -259.564886)
		)
		(stroke
			(width 0)
			(type solid)
		)
		(fill yes)
		(layer "In2.Cu")
		(net "M_F_CPU0_SA_CS_N<2>")
	)
	(gr_poly
		(pts
			(xy 383.362962 -254.938022) (xy 383.315972 -254.785622) (xy 383.054352 -254.785622) (xy 383.007362 -254.938022)
			(xy 383.007362 -254.982218) (xy 383.362962 -254.982218)
		)
		(stroke
			(width 0)
			(type solid)
		)
		(fill yes)
		(layer "In2.Cu")
		(net "M_F_CPU0_SA_PAR")
	)
	(gr_poly
		(pts
			(xy 383.362962 -254.529082) (xy 383.362962 -254.484886) (xy 383.007362 -254.484886) (xy 383.007362 -254.529082)
			(xy 383.054352 -254.681482) (xy 383.315972 -254.681482)
		)
		(stroke
			(width 0)
			(type solid)
		)
		(fill yes)
		(layer "In2.Cu")
		(net "M_F_CPU0_CLK_DP<1>")
	)
	(gr_poly
		(pts
			(xy 383.365756 -269.179294) (xy 383.365756 -269.134844) (xy 383.010156 -269.134844) (xy 383.010156 -269.179294)
			(xy 383.057146 -269.331694) (xy 383.318766 -269.331694)
		)
		(stroke
			(width 0)
			(type solid)
		)
		(fill yes)
		(layer "In2.Cu")
		(net "M_F_CPU0_SA_DQ<17>")
	)
	(gr_poly
		(pts
			(xy 383.371344 -280.574242) (xy 383.371344 -280.529792) (xy 383.015744 -280.529792) (xy 383.015744 -280.574242)
			(xy 383.062734 -280.726642) (xy 383.324354 -280.726642)
		)
		(stroke
			(width 0)
			(type solid)
		)
		(fill yes)
		(layer "In2.Cu")
		(net "M_F_CPU0_SA_DQ<0>")
	)
	(gr_poly
		(pts
			(xy 383.376424 -258.27609) (xy 383.368804 -258.232656) (xy 383.29616 -258.09067) (xy 383.03835 -258.136136)
			(xy 383.018538 -258.294378) (xy 383.026412 -258.338066)
		)
		(stroke
			(width 0)
			(type solid)
		)
		(fill yes)
		(layer "In2.Cu")
		(net "M_F_CPU0_SA_CA<0>")
	)
	(gr_poly
		(pts
			(xy 383.437892 -261.516622) (xy 383.329434 -261.399782) (xy 383.29108 -261.377684) (xy 383.11328 -261.685532)
			(xy 383.151634 -261.70763) (xy 383.307082 -261.74319)
		)
		(stroke
			(width 0)
			(type solid)
		)
		(fill yes)
		(layer "In2.Cu")
		(net "M_F_CPU0_SA_CB<5>")
	)
	(gr_poly
		(pts
			(xy 383.578862 -246.013478) (xy 383.617216 -245.99138) (xy 383.439416 -245.683532) (xy 383.401062 -245.70563)
			(xy 383.292604 -245.82247) (xy 383.423414 -246.049038)
		)
		(stroke
			(width 0)
			(type solid)
		)
		(fill yes)
		(layer "In2.Cu")
		(net "M_F_CPU0_SB_CA<6>")
	)
	(gr_poly
		(pts
			(xy 383.683256 -278.789638) (xy 383.72161 -278.76754) (xy 383.54381 -278.459692) (xy 383.505456 -278.48179)
			(xy 383.396998 -278.59863) (xy 383.527808 -278.825198)
		)
		(stroke
			(width 0)
			(type solid)
		)
		(fill yes)
		(layer "In2.Cu")
		(net "M_F_CPU0_SA_DQS_DP<0>")
	)
	(gr_poly
		(pts
			(xy 383.723134 -247.382538) (xy 383.676144 -247.230138) (xy 383.414524 -247.230138) (xy 383.367534 -247.382538)
			(xy 383.367534 -247.426988) (xy 383.723134 -247.426988)
		)
		(stroke
			(width 0)
			(type solid)
		)
		(fill yes)
		(layer "In2.Cu")
		(net "M_F_CPU0_SB_CA<3>")
	)
	(gr_poly
		(pts
			(xy 383.723134 -246.974106) (xy 383.723134 -246.929656) (xy 383.367534 -246.929656) (xy 383.367534 -246.974106)
			(xy 383.414524 -247.126506) (xy 383.676144 -247.126506)
		)
		(stroke
			(width 0)
			(type solid)
		)
		(fill yes)
		(layer "In2.Cu")
		(net "M_F_CPU0_SB_CA<4>")
	)
	(gr_poly
		(pts
			(xy 383.723134 -243.718334) (xy 383.723134 -243.674138) (xy 383.367534 -243.674138) (xy 383.367534 -243.718334)
			(xy 383.414524 -243.870734) (xy 383.676144 -243.870734)
		)
		(stroke
			(width 0)
			(type solid)
		)
		(fill yes)
		(layer "In2.Cu")
		(net "M_F_CPU0_SB_CS_N<3>")
	)
	(gr_poly
		(pts
			(xy 383.723134 -242.499134) (xy 383.676144 -242.346734) (xy 383.414524 -242.346734) (xy 383.367534 -242.499134)
			(xy 383.367534 -242.543584) (xy 383.723134 -242.543584)
		)
		(stroke
			(width 0)
			(type solid)
		)
		(fill yes)
		(layer "In2.Cu")
		(net "M_F_CPU0_SB_CB<6>")
	)
	(gr_poly
		(pts
			(xy 383.723134 -240.46307) (xy 383.723134 -240.41862) (xy 383.367534 -240.41862) (xy 383.367534 -240.46307)
			(xy 383.414524 -240.61547) (xy 383.676144 -240.61547)
		)
		(stroke
			(width 0)
			(type solid)
		)
		(fill yes)
		(layer "In2.Cu")
		(net "M_F_CPU0_SB_DQS_DP<9>")
	)
	(gr_poly
		(pts
			(xy 383.723134 -237.61573) (xy 383.676144 -237.46333) (xy 383.414524 -237.46333) (xy 383.367534 -237.61573)
			(xy 383.367534 -237.66018) (xy 383.723134 -237.66018)
		)
		(stroke
			(width 0)
			(type solid)
		)
		(fill yes)
		(layer "In2.Cu")
		(net "M_F_CPU0_SB_CB<3>")
	)
	(gr_poly
		(pts
			(xy 383.723134 -232.732834) (xy 383.676144 -232.580434) (xy 383.414524 -232.580434) (xy 383.367534 -232.732834)
			(xy 383.367534 -232.77703) (xy 383.723134 -232.77703)
		)
		(stroke
			(width 0)
			(type solid)
		)
		(fill yes)
		(layer "In2.Cu")
		(net "M_E_CPU0_SB_DQ<7>")
	)
	(gr_poly
		(pts
			(xy 383.723134 -232.323894) (xy 383.723134 -232.279698) (xy 383.367534 -232.279698) (xy 383.367534 -232.323894)
			(xy 383.414524 -232.476294) (xy 383.676144 -232.476294)
		)
		(stroke
			(width 0)
			(type solid)
		)
		(fill yes)
		(layer "In2.Cu")
		(net "M_F_CPU0_SB_DQ<8>")
	)
	(gr_poly
		(pts
			(xy 383.723134 -230.696262) (xy 383.723134 -230.651812) (xy 383.367534 -230.651812) (xy 383.367534 -230.696262)
			(xy 383.414524 -230.848662) (xy 383.676144 -230.848662)
		)
		(stroke
			(width 0)
			(type solid)
		)
		(fill yes)
		(layer "In2.Cu")
		(net "M_F_CPU0_SB_DQS_DP<1>")
	)
	(gr_poly
		(pts
			(xy 383.731516 -237.207806) (xy 383.731516 -237.163356) (xy 383.375916 -237.163356) (xy 383.375916 -237.207806)
			(xy 383.422906 -237.360206) (xy 383.684526 -237.360206)
		)
		(stroke
			(width 0)
			(type solid)
		)
		(fill yes)
		(layer "In2.Cu")
		(net "M_E_CPU0_SB_DQ<0>")
	)
	(gr_poly
		(pts
			(xy 383.798318 -278.17953) (xy 383.906776 -278.06269) (xy 383.775966 -277.836122) (xy 383.620518 -277.871682)
			(xy 383.582164 -277.89378) (xy 383.759964 -278.201628)
		)
		(stroke
			(width 0)
			(type solid)
		)
		(fill yes)
		(layer "In2.Cu")
		(net "M_F_CPU0_SA_DQS_DN<0>")
	)
	(gr_poly
		(pts
			(xy 383.826766 -280.16835) (xy 383.779776 -280.01595) (xy 383.518156 -280.01595) (xy 383.471166 -280.16835)
			(xy 383.471166 -280.212546) (xy 383.826766 -280.212546)
		)
		(stroke
			(width 0)
			(type solid)
		)
		(fill yes)
		(layer "In2.Cu")
		(net "M_F_CPU0_SA_DQ<2>")
	)
	(gr_poly
		(pts
			(xy 383.826766 -279.759918) (xy 383.826766 -279.715722) (xy 383.471166 -279.715722) (xy 383.471166 -279.759918)
			(xy 383.518156 -279.912318) (xy 383.779776 -279.912318)
		)
		(stroke
			(width 0)
			(type solid)
		)
		(fill yes)
		(layer "In2.Cu")
		(net "M_F_CPU0_SA_DQ<3>")
	)
	(gr_poly
		(pts
			(xy 383.832862 -260.635242) (xy 383.785872 -260.482842) (xy 383.524252 -260.482842) (xy 383.477262 -260.635242)
			(xy 383.477262 -260.679438) (xy 383.832862 -260.679438)
		)
		(stroke
			(width 0)
			(type solid)
		)
		(fill yes)
		(layer "In2.Cu")
		(net "M_F_CPU0_SA_CB<7>")
	)
	(gr_poly
		(pts
			(xy 383.832862 -260.226302) (xy 383.832862 -260.182106) (xy 383.477262 -260.182106) (xy 383.477262 -260.226302)
			(xy 383.524252 -260.378702) (xy 383.785872 -260.378702)
		)
		(stroke
			(width 0)
			(type solid)
		)
		(fill yes)
		(layer "In2.Cu")
		(net "M_F_CPU0_ALERT_N")
	)
	(gr_poly
		(pts
			(xy 383.832862 -257.37947) (xy 383.785872 -257.22707) (xy 383.524252 -257.22707) (xy 383.477262 -257.37947)
			(xy 383.477262 -257.42392) (xy 383.832862 -257.42392)
		)
		(stroke
			(width 0)
			(type solid)
		)
		(fill yes)
		(layer "In2.Cu")
		(net "M_F_CPU0_SA_CA<2>")
	)
	(gr_poly
		(pts
			(xy 383.832862 -255.751838) (xy 383.785872 -255.599438) (xy 383.524252 -255.599438) (xy 383.477262 -255.751838)
			(xy 383.477262 -255.796288) (xy 383.832862 -255.796288)
		)
		(stroke
			(width 0)
			(type solid)
		)
		(fill yes)
		(layer "In2.Cu")
		(net "M_F_CPU0_SA_CA<5>")
	)
	(gr_poly
		(pts
			(xy 383.832862 -255.343406) (xy 383.832862 -255.298956) (xy 383.477262 -255.298956) (xy 383.477262 -255.343406)
			(xy 383.524252 -255.495806) (xy 383.785872 -255.495806)
		)
		(stroke
			(width 0)
			(type solid)
		)
		(fill yes)
		(layer "In2.Cu")
		(net "M_F_CPU0_SA_CA<6>")
	)
	(gr_poly
		(pts
			(xy 383.832862 -254.124206) (xy 383.785872 -253.971806) (xy 383.524252 -253.971806) (xy 383.477262 -254.124206)
			(xy 383.477262 -254.168402) (xy 383.832862 -254.168402)
		)
		(stroke
			(width 0)
			(type solid)
		)
		(fill yes)
		(layer "In2.Cu")
		(net "M_F_CPU0_CLK_DN<1>")
	)
	(gr_poly
		(pts
			(xy 383.833116 -276.913086) (xy 383.786126 -276.760686) (xy 383.524506 -276.760686) (xy 383.477516 -276.913086)
			(xy 383.477516 -276.957282) (xy 383.833116 -276.957282)
		)
		(stroke
			(width 0)
			(type solid)
		)
		(fill yes)
		(layer "In2.Cu")
		(net "M_F_CPU0_SA_DQ<4>")
	)
	(gr_poly
		(pts
			(xy 383.838958 -268.365478) (xy 383.838958 -268.321028) (xy 383.483358 -268.321028) (xy 383.483358 -268.365478)
			(xy 383.530348 -268.517878) (xy 383.791968 -268.517878)
		)
		(stroke
			(width 0)
			(type solid)
		)
		(fill yes)
		(layer "In2.Cu")
		(net "M_F_CPU0_SA_DQS_DP<2>")
	)
	(gr_poly
		(pts
			(xy 383.841498 -275.284946) (xy 383.794508 -275.132546) (xy 383.532888 -275.132546) (xy 383.485898 -275.284946)
			(xy 383.485898 -275.329396) (xy 383.841498 -275.329396)
		)
		(stroke
			(width 0)
			(type solid)
		)
		(fill yes)
		(layer "In2.Cu")
		(net "M_F_CPU0_SA_DQ<7>")
	)
	(gr_poly
		(pts
			(xy 383.841498 -274.876768) (xy 383.841498 -274.832572) (xy 383.485898 -274.832572) (xy 383.485898 -274.876768)
			(xy 383.532888 -275.029168) (xy 383.794508 -275.029168)
		)
		(stroke
			(width 0)
			(type solid)
		)
		(fill yes)
		(layer "In2.Cu")
		(net "M_E_CPU0_SA_DQ<8>")
	)
	(gr_poly
		(pts
			(xy 383.841498 -270.401542) (xy 383.794508 -270.249142) (xy 383.532888 -270.249142) (xy 383.485898 -270.401542)
			(xy 383.485898 -270.445992) (xy 383.841498 -270.445992)
		)
		(stroke
			(width 0)
			(type solid)
		)
		(fill yes)
		(layer "In2.Cu")
		(net "M_E_CPU0_SA_DQ<15>")
	)
	(gr_poly
		(pts
			(xy 383.841498 -269.993618) (xy 383.841498 -269.949168) (xy 383.485898 -269.949168) (xy 383.485898 -269.993618)
			(xy 383.532888 -270.146018) (xy 383.794508 -270.146018)
		)
		(stroke
			(width 0)
			(type solid)
		)
		(fill yes)
		(layer "In2.Cu")
		(net "M_F_CPU0_SA_DQ<16>")
	)
	(gr_poly
		(pts
			(xy 383.841498 -265.518392) (xy 383.794508 -265.365992) (xy 383.532888 -265.365992) (xy 383.485898 -265.518392)
			(xy 383.485898 -265.562588) (xy 383.841498 -265.562588)
		)
		(stroke
			(width 0)
			(type solid)
		)
		(fill yes)
		(layer "In2.Cu")
		(net "M_F_CPU0_SA_DQ<23>")
	)
	(gr_poly
		(pts
			(xy 383.841498 -265.110214) (xy 383.841498 -265.065764) (xy 383.485898 -265.065764) (xy 383.485898 -265.110214)
			(xy 383.532888 -265.262614) (xy 383.794508 -265.262614)
		)
		(stroke
			(width 0)
			(type solid)
		)
		(fill yes)
		(layer "In2.Cu")
		(net "M_F_CPU0_SA_CB<0>")
	)
	(gr_poly
		(pts
			(xy 384.046222 -245.195598) (xy 384.084576 -245.1735) (xy 383.906776 -244.865652) (xy 383.868422 -244.88775)
			(xy 383.759964 -245.00459) (xy 383.890774 -245.231158)
		)
		(stroke
			(width 0)
			(type solid)
		)
		(fill yes)
		(layer "In2.Cu")
		(net "M_F_CPU0_SB_CS_N<2>")
	)
	(gr_poly
		(pts
			(xy 384.048762 -241.94389) (xy 384.087116 -241.921792) (xy 383.909316 -241.613944) (xy 383.870962 -241.636042)
			(xy 383.762504 -241.752882) (xy 383.893314 -241.97945)
		)
		(stroke
			(width 0)
			(type solid)
		)
		(fill yes)
		(layer "In2.Cu")
		(net "M_F_CPU0_SB_CB<5>")
	)
	(gr_poly
		(pts
			(xy 384.089148 -228.014276) (xy 384.050794 -227.992178) (xy 383.895346 -227.956618) (xy 383.764536 -228.183186)
			(xy 383.872994 -228.300026) (xy 383.911348 -228.322124)
		)
		(stroke
			(width 0)
			(type solid)
		)
		(fill yes)
		(layer "In2.Cu")
		(net "M_F_CPU0_SB_DQ<14>")
	)
	(gr_poly
		(pts
			(xy 384.159506 -241.326162) (xy 384.267964 -241.209322) (xy 384.137154 -240.982754) (xy 383.981706 -241.018314)
			(xy 383.943352 -241.040412) (xy 384.121152 -241.34826)
		)
		(stroke
			(width 0)
			(type solid)
		)
		(fill yes)
		(layer "In2.Cu")
		(net "M_F_CPU0_SB_CB<7>")
	)
	(gr_poly
		(pts
			(xy 384.162046 -244.585744) (xy 384.270504 -244.468904) (xy 384.139694 -244.242336) (xy 383.984246 -244.277896)
			(xy 383.945892 -244.299994) (xy 384.123692 -244.607842)
		)
		(stroke
			(width 0)
			(type solid)
		)
		(fill yes)
		(layer "In2.Cu")
		(net "M_F_CPU0_SB_CS_N<0>")
	)
	(gr_poly
		(pts
			(xy 384.184398 -236.801914) (xy 384.137408 -236.649514) (xy 383.875788 -236.649514) (xy 383.828798 -236.801914)
			(xy 383.828798 -236.84611) (xy 384.184398 -236.84611)
		)
		(stroke
			(width 0)
			(type solid)
		)
		(fill yes)
		(layer "In2.Cu")
		(net "M_E_CPU0_SB_DQ<2>")
	)
	(gr_poly
		(pts
			(xy 384.184398 -236.39399) (xy 384.184398 -236.34954) (xy 383.828798 -236.34954) (xy 383.828798 -236.39399)
			(xy 383.875788 -236.54639) (xy 384.137408 -236.54639)
		)
		(stroke
			(width 0)
			(type solid)
		)
		(fill yes)
		(layer "In2.Cu")
		(net "M_E_CPU0_SB_DQ<1>")
	)
	(gr_poly
		(pts
			(xy 384.186938 -240.057686) (xy 384.139948 -239.905286) (xy 383.878328 -239.905286) (xy 383.831338 -240.057686)
			(xy 383.831338 -240.101882) (xy 384.186938 -240.101882)
		)
		(stroke
			(width 0)
			(type solid)
		)
		(fill yes)
		(layer "In2.Cu")
		(net "M_F_CPU0_SB_DQS_DN<9>")
	)
	(gr_poly
		(pts
			(xy 384.186938 -235.174282) (xy 384.139948 -235.021882) (xy 383.878328 -235.021882) (xy 383.831338 -235.174282)
			(xy 383.831338 -235.218732) (xy 384.186938 -235.218732)
		)
		(stroke
			(width 0)
			(type solid)
		)
		(fill yes)
		(layer "In2.Cu")
		(net "M_E_CPU0_SB_DQS_DN<0>")
	)
	(gr_poly
		(pts
			(xy 384.193034 -246.568722) (xy 384.146044 -246.416322) (xy 383.884424 -246.416322) (xy 383.837434 -246.568722)
			(xy 383.837434 -246.613172) (xy 384.193034 -246.613172)
		)
		(stroke
			(width 0)
			(type solid)
		)
		(fill yes)
		(layer "In2.Cu")
		(net "M_F_CPU0_SB_CA<5>")
	)
	(gr_poly
		(pts
			(xy 384.193034 -246.16029) (xy 384.193034 -246.11584) (xy 383.837434 -246.11584) (xy 383.837434 -246.16029)
			(xy 383.884424 -246.31269) (xy 384.146044 -246.31269)
		)
		(stroke
			(width 0)
			(type solid)
		)
		(fill yes)
		(layer "In2.Cu")
		(net "M_F_CPU0_SB_CA<6>")
	)
	(gr_poly
		(pts
			(xy 384.193034 -243.313458) (xy 384.146044 -243.161058) (xy 383.884424 -243.161058) (xy 383.837434 -243.313458)
			(xy 383.837434 -243.357654) (xy 384.193034 -243.357654)
		)
		(stroke
			(width 0)
			(type solid)
		)
		(fill yes)
		(layer "In2.Cu")
		(net "M_F_CPU0_SB_CS_N<1>")
	)
	(gr_poly
		(pts
			(xy 384.193034 -242.904518) (xy 384.193034 -242.860322) (xy 383.837434 -242.860322) (xy 383.837434 -242.904518)
			(xy 383.884424 -243.056918) (xy 384.146044 -243.056918)
		)
		(stroke
			(width 0)
			(type solid)
		)
		(fill yes)
		(layer "In2.Cu")
		(net "M_F_CPU0_SB_CB<4>")
	)
	(gr_poly
		(pts
			(xy 384.193034 -238.430054) (xy 384.146044 -238.277654) (xy 383.884424 -238.277654) (xy 383.837434 -238.430054)
			(xy 383.837434 -238.47425) (xy 384.193034 -238.47425)
		)
		(stroke
			(width 0)
			(type solid)
		)
		(fill yes)
		(layer "In2.Cu")
		(net "M_F_CPU0_SB_CB<2>")
	)
	(gr_poly
		(pts
			(xy 384.193034 -238.021114) (xy 384.193034 -237.976918) (xy 383.837434 -237.976918) (xy 383.837434 -238.021114)
			(xy 383.884424 -238.173514) (xy 384.146044 -238.173514)
		)
		(stroke
			(width 0)
			(type solid)
		)
		(fill yes)
		(layer "In2.Cu")
		(net "M_F_CPU0_SB_CB<1>")
	)
	(gr_poly
		(pts
			(xy 384.193034 -233.54665) (xy 384.146044 -233.39425) (xy 383.884424 -233.39425) (xy 383.837434 -233.54665)
			(xy 383.837434 -233.590846) (xy 384.193034 -233.590846)
		)
		(stroke
			(width 0)
			(type solid)
		)
		(fill yes)
		(layer "In2.Cu")
		(net "M_E_CPU0_SB_DQ<6>")
	)
	(gr_poly
		(pts
			(xy 384.193034 -233.13771) (xy 384.193034 -233.093514) (xy 383.837434 -233.093514) (xy 383.837434 -233.13771)
			(xy 383.884424 -233.29011) (xy 384.146044 -233.29011)
		)
		(stroke
			(width 0)
			(type solid)
		)
		(fill yes)
		(layer "In2.Cu")
		(net "M_E_CPU0_SB_DQ<5>")
	)
	(gr_poly
		(pts
			(xy 384.193034 -231.919018) (xy 384.146044 -231.766618) (xy 383.884424 -231.766618) (xy 383.837434 -231.919018)
			(xy 383.837434 -231.963214) (xy 384.193034 -231.963214)
		)
		(stroke
			(width 0)
			(type solid)
		)
		(fill yes)
		(layer "In2.Cu")
		(net "M_F_CPU0_SB_DQ<10>")
	)
	(gr_poly
		(pts
			(xy 384.193034 -231.510078) (xy 384.193034 -231.465882) (xy 383.837434 -231.465882) (xy 383.837434 -231.510078)
			(xy 383.884424 -231.662478) (xy 384.146044 -231.662478)
		)
		(stroke
			(width 0)
			(type solid)
		)
		(fill yes)
		(layer "In2.Cu")
		(net "M_F_CPU0_SB_DQ<9>")
	)
	(gr_poly
		(pts
			(xy 384.193034 -230.290878) (xy 384.146044 -230.138478) (xy 383.884424 -230.138478) (xy 383.837434 -230.290878)
			(xy 383.837434 -230.335328) (xy 384.193034 -230.335328)
		)
		(stroke
			(width 0)
			(type solid)
		)
		(fill yes)
		(layer "In2.Cu")
		(net "M_F_CPU0_SB_DQS_DN<1>")
	)
	(gr_poly
		(pts
			(xy 384.294126 -259.820918) (xy 384.247136 -259.668518) (xy 383.985516 -259.668518) (xy 383.938526 -259.820918)
			(xy 383.938526 -259.865368) (xy 384.294126 -259.865368)
		)
		(stroke
			(width 0)
			(type solid)
		)
		(fill yes)
		(layer "In2.Cu")
		(net "M_F_CPU0_SA_CS_N<0>")
	)
	(gr_poly
		(pts
			(xy 384.294126 -259.412994) (xy 384.294126 -259.368544) (xy 383.938526 -259.368544) (xy 383.938526 -259.412994)
			(xy 383.985516 -259.565394) (xy 384.247136 -259.565394)
		)
		(stroke
			(width 0)
			(type solid)
		)
		(fill yes)
		(layer "In2.Cu")
		(net "M_F_CPU0_SA_CS_N<2>")
	)
	(gr_poly
		(pts
			(xy 384.29438 -274.47113) (xy 384.24739 -274.31873) (xy 383.98577 -274.31873) (xy 383.93878 -274.47113)
			(xy 383.93878 -274.515326) (xy 384.29438 -274.515326)
		)
		(stroke
			(width 0)
			(type solid)
		)
		(fill yes)
		(layer "In2.Cu")
		(net "M_E_CPU0_SA_DQ<10>")
	)
	(gr_poly
		(pts
			(xy 384.29438 -270.807434) (xy 384.29438 -270.762984) (xy 383.93878 -270.762984) (xy 383.93878 -270.807434)
			(xy 383.98577 -270.959834) (xy 384.24739 -270.959834)
		)
		(stroke
			(width 0)
			(type solid)
		)
		(fill yes)
		(layer "In2.Cu")
		(net "M_E_CPU0_SA_DQ<13>")
	)
	(gr_poly
		(pts
			(xy 384.29438 -269.587726) (xy 384.24739 -269.435326) (xy 383.98577 -269.435326) (xy 383.93878 -269.587726)
			(xy 383.93878 -269.631922) (xy 384.29438 -269.631922)
		)
		(stroke
			(width 0)
			(type solid)
		)
		(fill yes)
		(layer "In2.Cu")
		(net "M_F_CPU0_SA_DQ<18>")
	)
	(gr_poly
		(pts
			(xy 384.29438 -265.924284) (xy 384.29438 -265.879834) (xy 383.93878 -265.879834) (xy 383.93878 -265.924284)
			(xy 383.98577 -266.076684) (xy 384.24739 -266.076684)
		)
		(stroke
			(width 0)
			(type solid)
		)
		(fill yes)
		(layer "In2.Cu")
		(net "M_F_CPU0_SA_DQ<21>")
	)
	(gr_poly
		(pts
			(xy 384.29438 -264.704322) (xy 384.24739 -264.551922) (xy 383.98577 -264.551922) (xy 383.93878 -264.704322)
			(xy 383.93878 -264.748772) (xy 384.29438 -264.748772)
		)
		(stroke
			(width 0)
			(type solid)
		)
		(fill yes)
		(layer "In2.Cu")
		(net "M_F_CPU0_SA_CB<2>")
	)
	(gr_poly
		(pts
			(xy 384.29692 -275.690584) (xy 384.29692 -275.646388) (xy 383.94132 -275.646388) (xy 383.94132 -275.690584)
			(xy 383.98831 -275.842984) (xy 384.24993 -275.842984)
		)
		(stroke
			(width 0)
			(type solid)
		)
		(fill yes)
		(layer "In2.Cu")
		(net "M_F_CPU0_SA_DQ<5>")
	)
	(gr_poly
		(pts
			(xy 384.302762 -274.062698) (xy 384.302762 -274.018248) (xy 383.947162 -274.018248) (xy 383.947162 -274.062698)
			(xy 383.994152 -274.215098) (xy 384.255772 -274.215098)
		)
		(stroke
			(width 0)
			(type solid)
		)
		(fill yes)
		(layer "In2.Cu")
		(net "M_E_CPU0_SA_DQ<9>")
	)
	(gr_poly
		(pts
			(xy 384.302762 -271.215866) (xy 384.255772 -271.063466) (xy 383.994152 -271.063466) (xy 383.947162 -271.215866)
			(xy 383.947162 -271.260062) (xy 384.302762 -271.260062)
		)
		(stroke
			(width 0)
			(type solid)
		)
		(fill yes)
		(layer "In2.Cu")
		(net "M_E_CPU0_SA_DQ<14>")
	)
	(gr_poly
		(pts
			(xy 384.302762 -269.179294) (xy 384.302762 -269.134844) (xy 383.947162 -269.134844) (xy 383.947162 -269.179294)
			(xy 383.994152 -269.331694) (xy 384.255772 -269.331694)
		)
		(stroke
			(width 0)
			(type solid)
		)
		(fill yes)
		(layer "In2.Cu")
		(net "M_F_CPU0_SA_DQ<17>")
	)
	(gr_poly
		(pts
			(xy 384.302762 -267.960094) (xy 384.255772 -267.807694) (xy 383.994152 -267.807694) (xy 383.947162 -267.960094)
			(xy 383.947162 -268.004544) (xy 384.302762 -268.004544)
		)
		(stroke
			(width 0)
			(type solid)
		)
		(fill yes)
		(layer "In2.Cu")
		(net "M_F_CPU0_SA_DQS_DN<2>")
	)
	(gr_poly
		(pts
			(xy 384.302762 -264.29589) (xy 384.302762 -264.251694) (xy 383.947162 -264.251694) (xy 383.947162 -264.29589)
			(xy 383.994152 -264.44829) (xy 384.255772 -264.44829)
		)
		(stroke
			(width 0)
			(type solid)
		)
		(fill yes)
		(layer "In2.Cu")
		(net "M_F_CPU0_SA_CB<1>")
	)
	(gr_poly
		(pts
			(xy 384.302762 -263.077706) (xy 384.255772 -262.925306) (xy 383.994152 -262.925306) (xy 383.947162 -263.077706)
			(xy 383.947162 -263.121902) (xy 384.302762 -263.121902)
		)
		(stroke
			(width 0)
			(type solid)
		)
		(fill yes)
		(layer "In2.Cu")
		(net "M_F_CPU0_SA_DQS_DN<4>")
	)
	(gr_poly
		(pts
			(xy 384.302762 -261.449058) (xy 384.255772 -261.296658) (xy 383.994152 -261.296658) (xy 383.947162 -261.449058)
			(xy 383.947162 -261.493508) (xy 384.302762 -261.493508)
		)
		(stroke
			(width 0)
			(type solid)
		)
		(fill yes)
		(layer "In2.Cu")
		(net "M_F_CPU0_SA_CB<6>")
	)
	(gr_poly
		(pts
			(xy 384.302762 -261.040626) (xy 384.302762 -260.996176) (xy 383.947162 -260.996176) (xy 383.947162 -261.040626)
			(xy 383.994152 -261.193026) (xy 384.255772 -261.193026)
		)
		(stroke
			(width 0)
			(type solid)
		)
		(fill yes)
		(layer "In2.Cu")
		(net "M_F_CPU0_SA_CB<5>")
	)
	(gr_poly
		(pts
			(xy 384.302762 -254.938022) (xy 384.255772 -254.785622) (xy 383.994152 -254.785622) (xy 383.947162 -254.938022)
			(xy 383.947162 -254.982218) (xy 384.302762 -254.982218)
		)
		(stroke
			(width 0)
			(type solid)
		)
		(fill yes)
		(layer "In2.Cu")
		(net "M_F_CPU0_SA_PAR")
	)
	(gr_poly
		(pts
			(xy 384.302762 -254.529082) (xy 384.302762 -254.484886) (xy 383.947162 -254.484886) (xy 383.947162 -254.529082)
			(xy 383.994152 -254.681482) (xy 384.255772 -254.681482)
		)
		(stroke
			(width 0)
			(type solid)
		)
		(fill yes)
		(layer "In2.Cu")
		(net "M_F_CPU0_CLK_DP<1>")
	)
	(gr_poly
		(pts
			(xy 384.303016 -278.945594) (xy 384.303016 -278.901398) (xy 383.947416 -278.901398) (xy 383.947416 -278.945594)
			(xy 383.994406 -279.097994) (xy 384.256026 -279.097994)
		)
		(stroke
			(width 0)
			(type solid)
		)
		(fill yes)
		(layer "In2.Cu")
		(net "M_F_CPU0_SA_DQS_DP<0>")
	)
	(gr_poly
		(pts
			(xy 384.303016 -256.157222) (xy 384.303016 -256.112772) (xy 383.947416 -256.112772) (xy 383.947416 -256.157222)
			(xy 383.994406 -256.309622) (xy 384.256026 -256.309622)
		)
		(stroke
			(width 0)
			(type solid)
		)
		(fill yes)
		(layer "In2.Cu")
		(net "M_F_CPU0_SA_CA<4>")
	)
	(gr_poly
		(pts
			(xy 384.308858 -279.354534) (xy 384.261868 -279.202134) (xy 384.000248 -279.202134) (xy 383.953258 -279.354534)
			(xy 383.953258 -279.39873) (xy 384.308858 -279.39873)
		)
		(stroke
			(width 0)
			(type solid)
		)
		(fill yes)
		(layer "In2.Cu")
		(net "M_F_CPU0_SA_DQ<1>")
	)
	(gr_poly
		(pts
			(xy 384.518662 -244.385592) (xy 384.557016 -244.363494) (xy 384.379216 -244.055646) (xy 384.340862 -244.077744)
			(xy 384.232404 -244.194584) (xy 384.363214 -244.421152)
		)
		(stroke
			(width 0)
			(type solid)
		)
		(fill yes)
		(layer "In2.Cu")
		(net "M_F_CPU0_SB_CS_N<3>")
	)
	(gr_poly
		(pts
			(xy 384.557016 -228.832156) (xy 384.518662 -228.810058) (xy 384.363214 -228.774498) (xy 384.232404 -229.001066)
			(xy 384.340862 -229.117906) (xy 384.379216 -229.140004)
		)
		(stroke
			(width 0)
			(type solid)
		)
		(fill yes)
		(layer "In2.Cu")
		(net "M_F_CPU0_SB_DQS_DP<6>")
	)
	(gr_poly
		(pts
			(xy 384.62839 -240.510314) (xy 384.736848 -240.393474) (xy 384.606038 -240.166906) (xy 384.45059 -240.202466)
			(xy 384.412236 -240.224564) (xy 384.590036 -240.532412)
		)
		(stroke
			(width 0)
			(type solid)
		)
		(fill yes)
		(layer "In2.Cu")
		(net "M_F_CPU0_SB_DQS_DN<9>")
	)
	(gr_poly
		(pts
			(xy 384.629406 -243.767864) (xy 384.737864 -243.651024) (xy 384.607054 -243.424456) (xy 384.451606 -243.460016)
			(xy 384.413252 -243.482114) (xy 384.591052 -243.789962)
		)
		(stroke
			(width 0)
			(type solid)
		)
		(fill yes)
		(layer "In2.Cu")
		(net "M_F_CPU0_SB_CS_N<1>")
	)
	(gr_poly
		(pts
			(xy 384.662934 -246.974106) (xy 384.662934 -246.929656) (xy 384.307334 -246.929656) (xy 384.307334 -246.974106)
			(xy 384.354324 -247.126506) (xy 384.615944 -247.126506)
		)
		(stroke
			(width 0)
			(type solid)
		)
		(fill yes)
		(layer "In2.Cu")
		(net "M_F_CPU0_SB_CA<4>")
	)
	(gr_poly
		(pts
			(xy 384.662934 -245.754906) (xy 384.615944 -245.602506) (xy 384.354324 -245.602506) (xy 384.307334 -245.754906)
			(xy 384.307334 -245.799356) (xy 384.662934 -245.799356)
		)
		(stroke
			(width 0)
			(type solid)
		)
		(fill yes)
		(layer "In2.Cu")
		(net "M_F_CPU0_SB_PAR")
	)
	(gr_poly
		(pts
			(xy 384.662934 -245.346474) (xy 384.662934 -245.302024) (xy 384.307334 -245.302024) (xy 384.307334 -245.346474)
			(xy 384.354324 -245.498874) (xy 384.615944 -245.498874)
		)
		(stroke
			(width 0)
			(type solid)
		)
		(fill yes)
		(layer "In2.Cu")
		(net "M_F_CPU0_SB_CS_N<2>")
	)
	(gr_poly
		(pts
			(xy 384.662934 -242.499134) (xy 384.615944 -242.346734) (xy 384.354324 -242.346734) (xy 384.307334 -242.499134)
			(xy 384.307334 -242.543584) (xy 384.662934 -242.543584)
		)
		(stroke
			(width 0)
			(type solid)
		)
		(fill yes)
		(layer "In2.Cu")
		(net "M_F_CPU0_SB_CB<6>")
	)
	(gr_poly
		(pts
			(xy 384.662934 -242.090702) (xy 384.662934 -242.046252) (xy 384.307334 -242.046252) (xy 384.307334 -242.090702)
			(xy 384.354324 -242.243102) (xy 384.615944 -242.243102)
		)
		(stroke
			(width 0)
			(type solid)
		)
		(fill yes)
		(layer "In2.Cu")
		(net "M_F_CPU0_SB_CB<5>")
	)
	(gr_poly
		(pts
			(xy 384.662934 -238.83493) (xy 384.662934 -238.790734) (xy 384.307334 -238.790734) (xy 384.307334 -238.83493)
			(xy 384.354324 -238.98733) (xy 384.615944 -238.98733)
		)
		(stroke
			(width 0)
			(type solid)
		)
		(fill yes)
		(layer "In2.Cu")
		(net "M_F_CPU0_SB_CB<0>")
	)
	(gr_poly
		(pts
			(xy 384.662934 -237.61573) (xy 384.615944 -237.46333) (xy 384.354324 -237.46333) (xy 384.307334 -237.61573)
			(xy 384.307334 -237.66018) (xy 384.662934 -237.66018)
		)
		(stroke
			(width 0)
			(type solid)
		)
		(fill yes)
		(layer "In2.Cu")
		(net "M_F_CPU0_SB_CB<3>")
	)
	(gr_poly
		(pts
			(xy 384.662934 -233.952034) (xy 384.662934 -233.907584) (xy 384.307334 -233.907584) (xy 384.307334 -233.952034)
			(xy 384.354324 -234.104434) (xy 384.615944 -234.104434)
		)
		(stroke
			(width 0)
			(type solid)
		)
		(fill yes)
		(layer "In2.Cu")
		(net "M_E_CPU0_SB_DQ<4>")
	)
	(gr_poly
		(pts
			(xy 384.662934 -232.732834) (xy 384.615944 -232.580434) (xy 384.354324 -232.580434) (xy 384.307334 -232.732834)
			(xy 384.307334 -232.77703) (xy 384.662934 -232.77703)
		)
		(stroke
			(width 0)
			(type solid)
		)
		(fill yes)
		(layer "In2.Cu")
		(net "M_E_CPU0_SB_DQ<7>")
	)
	(gr_poly
		(pts
			(xy 384.662934 -232.323894) (xy 384.662934 -232.279698) (xy 384.307334 -232.279698) (xy 384.307334 -232.323894)
			(xy 384.354324 -232.476294) (xy 384.615944 -232.476294)
		)
		(stroke
			(width 0)
			(type solid)
		)
		(fill yes)
		(layer "In2.Cu")
		(net "M_F_CPU0_SB_DQ<8>")
	)
	(gr_poly
		(pts
			(xy 384.662934 -231.104694) (xy 384.615944 -230.952294) (xy 384.354324 -230.952294) (xy 384.307334 -231.104694)
			(xy 384.307334 -231.149144) (xy 384.662934 -231.149144)
		)
		(stroke
			(width 0)
			(type solid)
		)
		(fill yes)
		(layer "In2.Cu")
		(net "M_F_CPU0_SB_DQ<11>")
	)
	(gr_poly
		(pts
			(xy 384.662934 -230.696262) (xy 384.662934 -230.651812) (xy 384.307334 -230.651812) (xy 384.307334 -230.696262)
			(xy 384.354324 -230.848662) (xy 384.615944 -230.848662)
		)
		(stroke
			(width 0)
			(type solid)
		)
		(fill yes)
		(layer "In2.Cu")
		(net "M_F_CPU0_SB_DQS_DP<1>")
	)
	(gr_poly
		(pts
			(xy 384.662934 -227.84943) (xy 384.615944 -227.69703) (xy 384.354324 -227.69703) (xy 384.307334 -227.84943)
			(xy 384.307334 -227.893626) (xy 384.662934 -227.893626)
		)
		(stroke
			(width 0)
			(type solid)
		)
		(fill yes)
		(layer "In2.Cu")
		(net "M_F_CPU0_SB_DQ<14>")
	)
	(gr_poly
		(pts
			(xy 384.662934 -227.44049) (xy 384.662934 -227.396294) (xy 384.307334 -227.396294) (xy 384.307334 -227.44049)
			(xy 384.354324 -227.59289) (xy 384.615944 -227.59289)
		)
		(stroke
			(width 0)
			(type solid)
		)
		(fill yes)
		(layer "In2.Cu")
		(net "M_F_CPU0_SB_DQ<13>")
	)
	(gr_poly
		(pts
			(xy 384.671316 -239.243362) (xy 384.624326 -239.090962) (xy 384.362706 -239.090962) (xy 384.315716 -239.243362)
			(xy 384.315716 -239.287812) (xy 384.671316 -239.287812)
		)
		(stroke
			(width 0)
			(type solid)
		)
		(fill yes)
		(layer "In2.Cu")
		(net "M_F_CPU0_SB_DQS_DP<4>")
	)
	(gr_poly
		(pts
			(xy 384.671316 -237.207806) (xy 384.671316 -237.163356) (xy 384.315716 -237.163356) (xy 384.315716 -237.207806)
			(xy 384.362706 -237.360206) (xy 384.624326 -237.360206)
		)
		(stroke
			(width 0)
			(type solid)
		)
		(fill yes)
		(layer "In2.Cu")
		(net "M_E_CPU0_SB_DQ<0>")
	)
	(gr_poly
		(pts
			(xy 384.671316 -235.988098) (xy 384.624326 -235.835698) (xy 384.362706 -235.835698) (xy 384.315716 -235.988098)
			(xy 384.315716 -236.032294) (xy 384.671316 -236.032294)
		)
		(stroke
			(width 0)
			(type solid)
		)
		(fill yes)
		(layer "In2.Cu")
		(net "M_E_CPU0_SB_DQ<3>")
	)
	(gr_poly
		(pts
			(xy 384.671316 -235.579666) (xy 384.671316 -235.53547) (xy 384.315716 -235.53547) (xy 384.315716 -235.579666)
			(xy 384.362706 -235.732066) (xy 384.624326 -235.732066)
		)
		(stroke
			(width 0)
			(type solid)
		)
		(fill yes)
		(layer "In2.Cu")
		(net "M_E_CPU0_SB_DQS_DP<0>")
	)
	(gr_poly
		(pts
			(xy 384.671316 -234.360466) (xy 384.624326 -234.208066) (xy 384.362706 -234.208066) (xy 384.315716 -234.360466)
			(xy 384.315716 -234.404662) (xy 384.671316 -234.404662)
		)
		(stroke
			(width 0)
			(type solid)
		)
		(fill yes)
		(layer "In2.Cu")
		(net "M_E_CPU0_SB_DQS_DP<5>")
	)
	(gr_poly
		(pts
			(xy 384.737864 -229.544626) (xy 384.629406 -229.427786) (xy 384.591052 -229.405688) (xy 384.413252 -229.713536)
			(xy 384.451606 -229.735634) (xy 384.607054 -229.771194)
		)
		(stroke
			(width 0)
			(type solid)
		)
		(fill yes)
		(layer "In2.Cu")
		(net "M_F_CPU0_SB_DQS_DN<6>")
	)
	(gr_poly
		(pts
			(xy 384.76428 -279.759918) (xy 384.76428 -279.715722) (xy 384.40868 -279.715722) (xy 384.40868 -279.759918)
			(xy 384.45567 -279.912318) (xy 384.71729 -279.912318)
		)
		(stroke
			(width 0)
			(type solid)
		)
		(fill yes)
		(layer "In2.Cu")
		(net "M_F_CPU0_SA_DQ<3>")
	)
	(gr_poly
		(pts
			(xy 384.76428 -278.540718) (xy 384.71729 -278.388318) (xy 384.45567 -278.388318) (xy 384.40868 -278.540718)
			(xy 384.40868 -278.584914) (xy 384.76428 -278.584914)
		)
		(stroke
			(width 0)
			(type solid)
		)
		(fill yes)
		(layer "In2.Cu")
		(net "M_F_CPU0_SA_DQS_DN<0>")
	)
	(gr_poly
		(pts
			(xy 384.76428 -258.599178) (xy 384.76428 -258.554728) (xy 384.40868 -258.554728) (xy 384.40868 -258.599178)
			(xy 384.45567 -258.751578) (xy 384.71729 -258.751578)
		)
		(stroke
			(width 0)
			(type solid)
		)
		(fill yes)
		(layer "In2.Cu")
		(net "M_F_CPU0_SA_CS_N<1>")
	)
	(gr_poly
		(pts
			(xy 384.76428 -257.37947) (xy 384.71729 -257.22707) (xy 384.45567 -257.22707) (xy 384.40868 -257.37947)
			(xy 384.40868 -257.423666) (xy 384.76428 -257.423666)
		)
		(stroke
			(width 0)
			(type solid)
		)
		(fill yes)
		(layer "In2.Cu")
		(net "M_F_CPU0_SA_CA<2>")
	)
	(gr_poly
		(pts
			(xy 384.772662 -280.168604) (xy 384.725672 -280.016204) (xy 384.464052 -280.016204) (xy 384.417062 -280.168604)
			(xy 384.417062 -280.2128) (xy 384.772662 -280.2128)
		)
		(stroke
			(width 0)
			(type solid)
		)
		(fill yes)
		(layer "In2.Cu")
		(net "M_F_CPU0_SA_DQ<2>")
	)
	(gr_poly
		(pts
			(xy 384.772662 -278.132032) (xy 384.772662 -278.087836) (xy 384.417062 -278.087836) (xy 384.417062 -278.132032)
			(xy 384.464052 -278.284432) (xy 384.725672 -278.284432)
		)
		(stroke
			(width 0)
			(type solid)
		)
		(fill yes)
		(layer "In2.Cu")
		(net "M_F_CPU0_SA_DQS_DN<5>")
	)
	(gr_poly
		(pts
			(xy 384.772662 -273.657314) (xy 384.725672 -273.504914) (xy 384.464052 -273.504914) (xy 384.417062 -273.657314)
			(xy 384.417062 -273.701764) (xy 384.772662 -273.701764)
		)
		(stroke
			(width 0)
			(type solid)
		)
		(fill yes)
		(layer "In2.Cu")
		(net "M_E_CPU0_SA_DQ<11>")
	)
	(gr_poly
		(pts
			(xy 384.772662 -268.77391) (xy 384.725672 -268.62151) (xy 384.464052 -268.62151) (xy 384.417062 -268.77391)
			(xy 384.417062 -268.81836) (xy 384.772662 -268.81836)
		)
		(stroke
			(width 0)
			(type solid)
		)
		(fill yes)
		(layer "In2.Cu")
		(net "M_F_CPU0_SA_DQ<19>")
	)
	(gr_poly
		(pts
			(xy 384.772662 -267.146278) (xy 384.725672 -266.993878) (xy 384.464052 -266.993878) (xy 384.417062 -267.146278)
			(xy 384.417062 -267.190474) (xy 384.772662 -267.190474)
		)
		(stroke
			(width 0)
			(type solid)
		)
		(fill yes)
		(layer "In2.Cu")
		(net "M_F_CPU0_SA_DQS_DP<7>")
	)
	(gr_poly
		(pts
			(xy 384.772662 -266.737846) (xy 384.772662 -266.693396) (xy 384.417062 -266.693396) (xy 384.417062 -266.737846)
			(xy 384.464052 -266.890246) (xy 384.725672 -266.890246)
		)
		(stroke
			(width 0)
			(type solid)
		)
		(fill yes)
		(layer "In2.Cu")
		(net "M_F_CPU0_SA_DQ<20>")
	)
	(gr_poly
		(pts
			(xy 384.772662 -263.891014) (xy 384.725672 -263.738614) (xy 384.464052 -263.738614) (xy 384.417062 -263.891014)
			(xy 384.417062 -263.93521) (xy 384.772662 -263.93521)
		)
		(stroke
			(width 0)
			(type solid)
		)
		(fill yes)
		(layer "In2.Cu")
		(net "M_F_CPU0_SA_CB<3>")
	)
	(gr_poly
		(pts
			(xy 384.772662 -263.482074) (xy 384.772662 -263.437878) (xy 384.417062 -263.437878) (xy 384.417062 -263.482074)
			(xy 384.464052 -263.634474) (xy 384.725672 -263.634474)
		)
		(stroke
			(width 0)
			(type solid)
		)
		(fill yes)
		(layer "In2.Cu")
		(net "M_F_CPU0_SA_DQS_DP<4>")
	)
	(gr_poly
		(pts
			(xy 384.772662 -262.262874) (xy 384.725672 -262.110474) (xy 384.464052 -262.110474) (xy 384.417062 -262.262874)
			(xy 384.417062 -262.307324) (xy 384.772662 -262.307324)
		)
		(stroke
			(width 0)
			(type solid)
		)
		(fill yes)
		(layer "In2.Cu")
		(net "M_F_CPU0_SA_DQS_DP<9>")
	)
	(gr_poly
		(pts
			(xy 384.772662 -261.854442) (xy 384.772662 -261.809992) (xy 384.417062 -261.809992) (xy 384.417062 -261.854442)
			(xy 384.464052 -262.006842) (xy 384.725672 -262.006842)
		)
		(stroke
			(width 0)
			(type solid)
		)
		(fill yes)
		(layer "In2.Cu")
		(net "M_F_CPU0_SA_CB<4>")
	)
	(gr_poly
		(pts
			(xy 384.772662 -260.635242) (xy 384.725672 -260.482842) (xy 384.464052 -260.482842) (xy 384.417062 -260.635242)
			(xy 384.417062 -260.679438) (xy 384.772662 -260.679438)
		)
		(stroke
			(width 0)
			(type solid)
		)
		(fill yes)
		(layer "In2.Cu")
		(net "M_F_CPU0_SA_CB<7>")
	)
	(gr_poly
		(pts
			(xy 384.772662 -256.971038) (xy 384.772662 -256.926588) (xy 384.417062 -256.926588) (xy 384.417062 -256.971038)
			(xy 384.464052 -257.123438) (xy 384.725672 -257.123438)
		)
		(stroke
			(width 0)
			(type solid)
		)
		(fill yes)
		(layer "In2.Cu")
		(net "M_F_CPU0_SA_CA<3>")
	)
	(gr_poly
		(pts
			(xy 384.772662 -255.343406) (xy 384.772662 -255.298956) (xy 384.417062 -255.298956) (xy 384.417062 -255.343406)
			(xy 384.464052 -255.495806) (xy 384.725672 -255.495806)
		)
		(stroke
			(width 0)
			(type solid)
		)
		(fill yes)
		(layer "In2.Cu")
		(net "M_F_CPU0_SA_CA<6>")
	)
	(gr_poly
		(pts
			(xy 384.772662 -254.124206) (xy 384.725672 -253.971806) (xy 384.464052 -253.971806) (xy 384.417062 -254.124206)
			(xy 384.417062 -254.168402) (xy 384.772662 -254.168402)
		)
		(stroke
			(width 0)
			(type solid)
		)
		(fill yes)
		(layer "In2.Cu")
		(net "M_F_CPU0_CLK_DN<1>")
	)
	(gr_poly
		(pts
			(xy 384.772916 -271.620742) (xy 384.772916 -271.576546) (xy 384.417316 -271.576546) (xy 384.417316 -271.620742)
			(xy 384.464306 -271.773142) (xy 384.725926 -271.773142)
		)
		(stroke
			(width 0)
			(type solid)
		)
		(fill yes)
		(layer "In2.Cu")
		(net "M_E_CPU0_SA_DQ<12>")
	)
	(gr_poly
		(pts
			(xy 384.777996 -275.284946) (xy 384.731006 -275.132546) (xy 384.469386 -275.132546) (xy 384.422396 -275.284946)
			(xy 384.422396 -275.329396) (xy 384.777996 -275.329396)
		)
		(stroke
			(width 0)
			(type solid)
		)
		(fill yes)
		(layer "In2.Cu")
		(net "M_F_CPU0_SA_DQ<7>")
	)
	(gr_poly
		(pts
			(xy 384.777996 -255.751838) (xy 384.731006 -255.599438) (xy 384.469386 -255.599438) (xy 384.422396 -255.751838)
			(xy 384.422396 -255.796034) (xy 384.777996 -255.796034)
		)
		(stroke
			(width 0)
			(type solid)
		)
		(fill yes)
		(layer "In2.Cu")
		(net "M_F_CPU0_SA_CA<5>")
	)
	(gr_poly
		(pts
			(xy 384.781044 -260.22681) (xy 384.781044 -260.18236) (xy 384.425444 -260.18236) (xy 384.425444 -260.22681)
			(xy 384.472434 -260.37921) (xy 384.734054 -260.37921)
		)
		(stroke
			(width 0)
			(type solid)
		)
		(fill yes)
		(layer "In2.Cu")
		(net "M_F_CPU0_ALERT_N")
	)
	(gr_poly
		(pts
			(xy 384.781044 -259.007102) (xy 384.734054 -258.854702) (xy 384.472434 -258.854702) (xy 384.425444 -259.007102)
			(xy 384.425444 -259.051552) (xy 384.781044 -259.051552)
		)
		(stroke
			(width 0)
			(type solid)
		)
		(fill yes)
		(layer "In2.Cu")
		(net "M_F_CPU0_SA_CS_N<3>")
	)
	(gr_poly
		(pts
			(xy 384.781298 -274.876768) (xy 384.781298 -274.832572) (xy 384.425698 -274.832572) (xy 384.425698 -274.876768)
			(xy 384.472688 -275.029168) (xy 384.734308 -275.029168)
		)
		(stroke
			(width 0)
			(type solid)
		)
		(fill yes)
		(layer "In2.Cu")
		(net "M_E_CPU0_SA_DQ<8>")
	)
	(gr_poly
		(pts
			(xy 384.781298 -272.029174) (xy 384.734308 -271.876774) (xy 384.472688 -271.876774) (xy 384.425698 -272.029174)
			(xy 384.425698 -272.073624) (xy 384.781298 -272.073624)
		)
		(stroke
			(width 0)
			(type solid)
		)
		(fill yes)
		(layer "In2.Cu")
		(net "M_E_CPU0_SA_DQS_DP<6>")
	)
	(gr_poly
		(pts
			(xy 384.781298 -270.401542) (xy 384.734308 -270.249142) (xy 384.472688 -270.249142) (xy 384.425698 -270.401542)
			(xy 384.425698 -270.445992) (xy 384.781298 -270.445992)
		)
		(stroke
			(width 0)
			(type solid)
		)
		(fill yes)
		(layer "In2.Cu")
		(net "M_E_CPU0_SA_DQ<15>")
	)
	(gr_poly
		(pts
			(xy 384.781298 -269.993618) (xy 384.781298 -269.949168) (xy 384.425698 -269.949168) (xy 384.425698 -269.993618)
			(xy 384.472688 -270.146018) (xy 384.734308 -270.146018)
		)
		(stroke
			(width 0)
			(type solid)
		)
		(fill yes)
		(layer "In2.Cu")
		(net "M_F_CPU0_SA_DQ<16>")
	)
	(gr_poly
		(pts
			(xy 384.781298 -265.518392) (xy 384.734308 -265.365992) (xy 384.472688 -265.365992) (xy 384.425698 -265.518392)
			(xy 384.425698 -265.562588) (xy 384.781298 -265.562588)
		)
		(stroke
			(width 0)
			(type solid)
		)
		(fill yes)
		(layer "In2.Cu")
		(net "M_F_CPU0_SA_DQ<23>")
	)
	(gr_poly
		(pts
			(xy 384.781298 -265.110214) (xy 384.781298 -265.065764) (xy 384.425698 -265.065764) (xy 384.425698 -265.110214)
			(xy 384.472688 -265.262614) (xy 384.734308 -265.262614)
		)
		(stroke
			(width 0)
			(type solid)
		)
		(fill yes)
		(layer "In2.Cu")
		(net "M_F_CPU0_SA_CB<0>")
	)
	(gr_poly
		(pts
			(xy 384.988562 -243.571776) (xy 385.026916 -243.549678) (xy 384.849116 -243.24183) (xy 384.810762 -243.263928)
			(xy 384.702304 -243.380768) (xy 384.833114 -243.607336)
		)
		(stroke
			(width 0)
			(type solid)
		)
		(fill yes)
		(layer "In2.Cu")
		(net "M_F_CPU0_SB_CB<4>")
	)
	(gr_poly
		(pts
			(xy 384.989324 -240.318036) (xy 385.027678 -240.295938) (xy 384.849878 -239.98809) (xy 384.811524 -240.010188)
			(xy 384.703066 -240.127028) (xy 384.833876 -240.353596)
		)
		(stroke
			(width 0)
			(type solid)
		)
		(fill yes)
		(layer "In2.Cu")
		(net "M_F_CPU0_SB_DQS_DN<4>")
	)
	(gr_poly
		(pts
			(xy 385.026916 -229.645972) (xy 384.988562 -229.623874) (xy 384.833114 -229.588314) (xy 384.702304 -229.814882)
			(xy 384.810762 -229.931722) (xy 384.849116 -229.95382)
		)
		(stroke
			(width 0)
			(type solid)
		)
		(fill yes)
		(layer "In2.Cu")
		(net "M_F_CPU0_SB_DQS_DN<1>")
	)
	(gr_poly
		(pts
			(xy 385.097274 -242.949984) (xy 385.205732 -242.833144) (xy 385.074922 -242.606576) (xy 384.919474 -242.642136)
			(xy 384.88112 -242.664234) (xy 385.05892 -242.972082)
		)
		(stroke
			(width 0)
			(type solid)
		)
		(fill yes)
		(layer "In2.Cu")
		(net "M_F_CPU0_SB_CB<6>")
	)
	(gr_poly
		(pts
			(xy 385.098036 -239.695736) (xy 385.206494 -239.578896) (xy 385.075684 -239.352328) (xy 384.920236 -239.387888)
			(xy 384.881882 -239.409986) (xy 385.059682 -239.717834)
		)
		(stroke
			(width 0)
			(type solid)
		)
		(fill yes)
		(layer "In2.Cu")
		(net "M_F_CPU0_SB_DQS_DP<4>")
	)
	(gr_poly
		(pts
			(xy 385.09829 -276.357588) (xy 385.136644 -276.33549) (xy 384.958844 -276.027642) (xy 384.92049 -276.04974)
			(xy 384.812032 -276.16658) (xy 384.942842 -276.393148)
		)
		(stroke
			(width 0)
			(type solid)
		)
		(fill yes)
		(layer "In2.Cu")
		(net "M_F_CPU0_SA_DQ<5>")
	)
	(gr_poly
		(pts
			(xy 385.124198 -236.801914) (xy 385.077208 -236.649514) (xy 384.815588 -236.649514) (xy 384.768598 -236.801914)
			(xy 384.768598 -236.84611) (xy 385.124198 -236.84611)
		)
		(stroke
			(width 0)
			(type solid)
		)
		(fill yes)
		(layer "In2.Cu")
		(net "M_E_CPU0_SB_DQ<2>")
	)
	(gr_poly
		(pts
			(xy 385.124198 -236.39399) (xy 385.124198 -236.34954) (xy 384.768598 -236.34954) (xy 384.768598 -236.39399)
			(xy 384.815588 -236.54639) (xy 385.077208 -236.54639)
		)
		(stroke
			(width 0)
			(type solid)
		)
		(fill yes)
		(layer "In2.Cu")
		(net "M_E_CPU0_SB_DQ<1>")
	)
	(gr_poly
		(pts
			(xy 385.124198 -235.174282) (xy 385.077208 -235.021882) (xy 384.815588 -235.021882) (xy 384.768598 -235.174282)
			(xy 384.768598 -235.218478) (xy 385.124198 -235.218478)
		)
		(stroke
			(width 0)
			(type solid)
		)
		(fill yes)
		(layer "In2.Cu")
		(net "M_E_CPU0_SB_DQS_DN<0>")
	)
	(gr_poly
		(pts
			(xy 385.132834 -246.16029) (xy 385.132834 -246.11584) (xy 384.777234 -246.11584) (xy 384.777234 -246.16029)
			(xy 384.824224 -246.31269) (xy 385.085844 -246.31269)
		)
		(stroke
			(width 0)
			(type solid)
		)
		(fill yes)
		(layer "In2.Cu")
		(net "M_F_CPU0_SB_CA<6>")
	)
	(gr_poly
		(pts
			(xy 385.132834 -244.94109) (xy 385.085844 -244.78869) (xy 384.824224 -244.78869) (xy 384.777234 -244.94109)
			(xy 384.777234 -244.985286) (xy 385.132834 -244.985286)
		)
		(stroke
			(width 0)
			(type solid)
		)
		(fill yes)
		(layer "In2.Cu")
		(net "M_F_CPU0_SB_CS_N<0>")
	)
	(gr_poly
		(pts
			(xy 385.132834 -244.53215) (xy 385.132834 -244.487954) (xy 384.777234 -244.487954) (xy 384.777234 -244.53215)
			(xy 384.824224 -244.68455) (xy 385.085844 -244.68455)
		)
		(stroke
			(width 0)
			(type solid)
		)
		(fill yes)
		(layer "In2.Cu")
		(net "M_F_CPU0_SB_CS_N<3>")
	)
	(gr_poly
		(pts
			(xy 385.132834 -241.685318) (xy 385.085844 -241.532918) (xy 384.824224 -241.532918) (xy 384.777234 -241.685318)
			(xy 384.777234 -241.729768) (xy 385.132834 -241.729768)
		)
		(stroke
			(width 0)
			(type solid)
		)
		(fill yes)
		(layer "In2.Cu")
		(net "M_F_CPU0_SB_CB<7>")
	)
	(gr_poly
		(pts
			(xy 385.132834 -241.276886) (xy 385.132834 -241.232436) (xy 384.777234 -241.232436) (xy 384.777234 -241.276886)
			(xy 384.824224 -241.429286) (xy 385.085844 -241.429286)
		)
		(stroke
			(width 0)
			(type solid)
		)
		(fill yes)
		(layer "In2.Cu")
		(net "M_F_CPU0_SB_DQS_DP<9>")
	)
	(gr_poly
		(pts
			(xy 385.132834 -238.430054) (xy 385.085844 -238.277654) (xy 384.824224 -238.277654) (xy 384.777234 -238.430054)
			(xy 384.777234 -238.47425) (xy 385.132834 -238.47425)
		)
		(stroke
			(width 0)
			(type solid)
		)
		(fill yes)
		(layer "In2.Cu")
		(net "M_F_CPU0_SB_CB<2>")
	)
	(gr_poly
		(pts
			(xy 385.132834 -238.021114) (xy 385.132834 -237.976918) (xy 384.777234 -237.976918) (xy 384.777234 -238.021114)
			(xy 384.824224 -238.173514) (xy 385.085844 -238.173514)
		)
		(stroke
			(width 0)
			(type solid)
		)
		(fill yes)
		(layer "In2.Cu")
		(net "M_F_CPU0_SB_CB<1>")
	)
	(gr_poly
		(pts
			(xy 385.132834 -234.765342) (xy 385.132834 -234.720892) (xy 384.777234 -234.720892) (xy 384.777234 -234.765342)
			(xy 384.824224 -234.917742) (xy 385.085844 -234.917742)
		)
		(stroke
			(width 0)
			(type solid)
		)
		(fill yes)
		(layer "In2.Cu")
		(net "M_E_CPU0_SB_DQS_DN<5>")
	)
	(gr_poly
		(pts
			(xy 385.132834 -233.54665) (xy 385.085844 -233.39425) (xy 384.824224 -233.39425) (xy 384.777234 -233.54665)
			(xy 384.777234 -233.590846) (xy 385.132834 -233.590846)
		)
		(stroke
			(width 0)
			(type solid)
		)
		(fill yes)
		(layer "In2.Cu")
		(net "M_E_CPU0_SB_DQ<6>")
	)
	(gr_poly
		(pts
			(xy 385.132834 -233.13771) (xy 385.132834 -233.093514) (xy 384.777234 -233.093514) (xy 384.777234 -233.13771)
			(xy 384.824224 -233.29011) (xy 385.085844 -233.29011)
		)
		(stroke
			(width 0)
			(type solid)
		)
		(fill yes)
		(layer "In2.Cu")
		(net "M_E_CPU0_SB_DQ<5>")
	)
	(gr_poly
		(pts
			(xy 385.132834 -231.919018) (xy 385.085844 -231.766618) (xy 384.824224 -231.766618) (xy 384.777234 -231.919018)
			(xy 384.777234 -231.963214) (xy 385.132834 -231.963214)
		)
		(stroke
			(width 0)
			(type solid)
		)
		(fill yes)
		(layer "In2.Cu")
		(net "M_F_CPU0_SB_DQ<10>")
	)
	(gr_poly
		(pts
			(xy 385.132834 -231.510078) (xy 385.132834 -231.465882) (xy 384.777234 -231.465882) (xy 384.777234 -231.510078)
			(xy 384.824224 -231.662478) (xy 385.085844 -231.662478)
		)
		(stroke
			(width 0)
			(type solid)
		)
		(fill yes)
		(layer "In2.Cu")
		(net "M_F_CPU0_SB_DQ<9>")
	)
	(gr_poly
		(pts
			(xy 385.132834 -228.663246) (xy 385.085844 -228.510846) (xy 384.824224 -228.510846) (xy 384.777234 -228.663246)
			(xy 384.777234 -228.707696) (xy 385.132834 -228.707696)
		)
		(stroke
			(width 0)
			(type solid)
		)
		(fill yes)
		(layer "In2.Cu")
		(net "M_F_CPU0_SB_DQS_DP<6>")
	)
	(gr_poly
		(pts
			(xy 385.132834 -228.254814) (xy 385.132834 -228.210364) (xy 384.777234 -228.210364) (xy 384.777234 -228.254814)
			(xy 384.824224 -228.407214) (xy 385.085844 -228.407214)
		)
		(stroke
			(width 0)
			(type solid)
		)
		(fill yes)
		(layer "In2.Cu")
		(net "M_F_CPU0_SB_DQ<12>")
	)
	(gr_poly
		(pts
			(xy 385.132834 -227.035614) (xy 385.085844 -226.883214) (xy 384.824224 -226.883214) (xy 384.777234 -227.035614)
			(xy 384.777234 -227.07981) (xy 385.132834 -227.07981)
		)
		(stroke
			(width 0)
			(type solid)
		)
		(fill yes)
		(layer "In2.Cu")
		(net "M_F_CPU0_SB_DQ<15>")
	)
	(gr_poly
		(pts
			(xy 385.207764 -230.358442) (xy 385.099306 -230.241602) (xy 385.060952 -230.219504) (xy 384.883152 -230.527352)
			(xy 384.921506 -230.54945) (xy 385.076954 -230.58501)
		)
		(stroke
			(width 0)
			(type solid)
		)
		(fill yes)
		(layer "In2.Cu")
		(net "M_F_CPU0_SB_DQS_DP<1>")
	)
	(gr_poly
		(pts
			(xy 385.209034 -275.73986) (xy 385.317492 -275.62302) (xy 385.186682 -275.396452) (xy 385.031234 -275.432012)
			(xy 384.99288 -275.45411) (xy 385.17068 -275.761958)
		)
		(stroke
			(width 0)
			(type solid)
		)
		(fill yes)
		(layer "In2.Cu")
		(net "M_F_CPU0_SA_DQ<7>")
	)
	(gr_poly
		(pts
			(xy 385.233926 -259.820918) (xy 385.186936 -259.668518) (xy 384.925316 -259.668518) (xy 384.878326 -259.820918)
			(xy 384.878326 -259.865368) (xy 385.233926 -259.865368)
		)
		(stroke
			(width 0)
			(type solid)
		)
		(fill yes)
		(layer "In2.Cu")
		(net "M_F_CPU0_SA_CS_N<0>")
	)
	(gr_poly
		(pts
			(xy 385.233926 -259.412994) (xy 385.233926 -259.368544) (xy 384.878326 -259.368544) (xy 384.878326 -259.412994)
			(xy 384.925316 -259.565394) (xy 385.186936 -259.565394)
		)
		(stroke
			(width 0)
			(type solid)
		)
		(fill yes)
		(layer "In2.Cu")
		(net "M_F_CPU0_SA_CS_N<2>")
	)
	(gr_poly
		(pts
			(xy 385.23418 -274.47113) (xy 385.18719 -274.31873) (xy 384.92557 -274.31873) (xy 384.87858 -274.47113)
			(xy 384.87858 -274.515326) (xy 385.23418 -274.515326)
		)
		(stroke
			(width 0)
			(type solid)
		)
		(fill yes)
		(layer "In2.Cu")
		(net "M_E_CPU0_SA_DQ<10>")
	)
	(gr_poly
		(pts
			(xy 385.23418 -272.435066) (xy 385.23418 -272.39087) (xy 384.87858 -272.39087) (xy 384.87858 -272.435066)
			(xy 384.92557 -272.587466) (xy 385.18719 -272.587466)
		)
		(stroke
			(width 0)
			(type solid)
		)
		(fill yes)
		(layer "In2.Cu")
		(net "M_E_CPU0_SA_DQS_DN<6>")
	)
	(gr_poly
		(pts
			(xy 385.23418 -271.215358) (xy 385.18719 -271.062958) (xy 384.92557 -271.062958) (xy 384.87858 -271.215358)
			(xy 384.87858 -271.259808) (xy 385.23418 -271.259808)
		)
		(stroke
			(width 0)
			(type solid)
		)
		(fill yes)
		(layer "In2.Cu")
		(net "M_E_CPU0_SA_DQ<14>")
	)
	(gr_poly
		(pts
			(xy 385.23418 -270.807434) (xy 385.23418 -270.762984) (xy 384.87858 -270.762984) (xy 384.87858 -270.807434)
			(xy 384.92557 -270.959834) (xy 385.18719 -270.959834)
		)
		(stroke
			(width 0)
			(type solid)
		)
		(fill yes)
		(layer "In2.Cu")
		(net "M_E_CPU0_SA_DQ<13>")
	)
	(gr_poly
		(pts
			(xy 385.23418 -269.587726) (xy 385.18719 -269.435326) (xy 384.92557 -269.435326) (xy 384.87858 -269.587726)
			(xy 384.87858 -269.631922) (xy 385.23418 -269.631922)
		)
		(stroke
			(width 0)
			(type solid)
		)
		(fill yes)
		(layer "In2.Cu")
		(net "M_F_CPU0_SA_DQ<18>")
	)
	(gr_poly
		(pts
			(xy 385.23418 -265.924284) (xy 385.23418 -265.879834) (xy 384.87858 -265.879834) (xy 384.87858 -265.924284)
			(xy 384.92557 -266.076684) (xy 385.18719 -266.076684)
		)
		(stroke
			(width 0)
			(type solid)
		)
		(fill yes)
		(layer "In2.Cu")
		(net "M_F_CPU0_SA_DQ<21>")
	)
	(gr_poly
		(pts
			(xy 385.23418 -264.704322) (xy 385.18719 -264.551922) (xy 384.92557 -264.551922) (xy 384.87858 -264.704322)
			(xy 384.87858 -264.748772) (xy 385.23418 -264.748772)
		)
		(stroke
			(width 0)
			(type solid)
		)
		(fill yes)
		(layer "In2.Cu")
		(net "M_F_CPU0_SA_CB<2>")
	)
	(gr_poly
		(pts
			(xy 385.23418 -256.157222) (xy 385.23418 -256.113026) (xy 384.87858 -256.113026) (xy 384.87858 -256.157222)
			(xy 384.92557 -256.309622) (xy 385.18719 -256.309622)
		)
		(stroke
			(width 0)
			(type solid)
		)
		(fill yes)
		(layer "In2.Cu")
		(net "M_F_CPU0_SA_CA<4>")
	)
	(gr_poly
		(pts
			(xy 385.23418 -254.937514) (xy 385.18719 -254.785114) (xy 384.92557 -254.785114) (xy 384.87858 -254.937514)
			(xy 384.87858 -254.981964) (xy 385.23418 -254.981964)
		)
		(stroke
			(width 0)
			(type solid)
		)
		(fill yes)
		(layer "In2.Cu")
		(net "M_F_CPU0_SA_PAR")
	)
	(gr_poly
		(pts
			(xy 385.242308 -278.945594) (xy 385.242308 -278.901398) (xy 384.886708 -278.901398) (xy 384.886708 -278.945594)
			(xy 384.933698 -279.097994) (xy 385.195318 -279.097994)
		)
		(stroke
			(width 0)
			(type solid)
		)
		(fill yes)
		(layer "In2.Cu")
		(net "M_F_CPU0_SA_DQS_DP<0>")
	)
	(gr_poly
		(pts
			(xy 385.242562 -277.726902) (xy 385.195572 -277.574502) (xy 384.933952 -277.574502) (xy 384.886962 -277.726902)
			(xy 384.886962 -277.771098) (xy 385.242562 -277.771098)
		)
		(stroke
			(width 0)
			(type solid)
		)
		(fill yes)
		(layer "In2.Cu")
		(net "M_F_CPU0_SA_DQS_DP<5>")
	)
	(gr_poly
		(pts
			(xy 385.242562 -277.317962) (xy 385.242562 -277.273766) (xy 384.886962 -277.273766) (xy 384.886962 -277.317962)
			(xy 384.933952 -277.470362) (xy 385.195572 -277.470362)
		)
		(stroke
			(width 0)
			(type solid)
		)
		(fill yes)
		(layer "In2.Cu")
		(net "M_F_CPU0_SA_DQ<4>")
	)
	(gr_poly
		(pts
			(xy 385.242562 -274.062698) (xy 385.242562 -274.018248) (xy 384.886962 -274.018248) (xy 384.886962 -274.062698)
			(xy 384.933952 -274.215098) (xy 385.195572 -274.215098)
		)
		(stroke
			(width 0)
			(type solid)
		)
		(fill yes)
		(layer "In2.Cu")
		(net "M_E_CPU0_SA_DQ<9>")
	)
	(gr_poly
		(pts
			(xy 385.242562 -269.179294) (xy 385.242562 -269.134844) (xy 384.886962 -269.134844) (xy 384.886962 -269.179294)
			(xy 384.933952 -269.331694) (xy 385.195572 -269.331694)
		)
		(stroke
			(width 0)
			(type solid)
		)
		(fill yes)
		(layer "In2.Cu")
		(net "M_F_CPU0_SA_DQ<17>")
	)
	(gr_poly
		(pts
			(xy 385.242562 -267.551662) (xy 385.242562 -267.507212) (xy 384.886962 -267.507212) (xy 384.886962 -267.551662)
			(xy 384.933952 -267.704062) (xy 385.195572 -267.704062)
		)
		(stroke
			(width 0)
			(type solid)
		)
		(fill yes)
		(layer "In2.Cu")
		(net "M_F_CPU0_SA_DQS_DN<7>")
	)
	(gr_poly
		(pts
			(xy 385.242562 -266.332462) (xy 385.195572 -266.180062) (xy 384.933952 -266.180062) (xy 384.886962 -266.332462)
			(xy 384.886962 -266.376658) (xy 385.242562 -266.376658)
		)
		(stroke
			(width 0)
			(type solid)
		)
		(fill yes)
		(layer "In2.Cu")
		(net "M_F_CPU0_SA_DQ<22>")
	)
	(gr_poly
		(pts
			(xy 385.242562 -264.29589) (xy 385.242562 -264.251694) (xy 384.886962 -264.251694) (xy 384.886962 -264.29589)
			(xy 384.933952 -264.44829) (xy 385.195572 -264.44829)
		)
		(stroke
			(width 0)
			(type solid)
		)
		(fill yes)
		(layer "In2.Cu")
		(net "M_F_CPU0_SA_CB<1>")
	)
	(gr_poly
		(pts
			(xy 385.242562 -263.077706) (xy 385.195572 -262.925306) (xy 384.933952 -262.925306) (xy 384.886962 -263.077706)
			(xy 384.886962 -263.121902) (xy 385.242562 -263.121902)
		)
		(stroke
			(width 0)
			(type solid)
		)
		(fill yes)
		(layer "In2.Cu")
		(net "M_F_CPU0_SA_DQS_DN<4>")
	)
	(gr_poly
		(pts
			(xy 385.242562 -262.668258) (xy 385.242562 -262.623808) (xy 384.886962 -262.623808) (xy 384.886962 -262.668258)
			(xy 384.933952 -262.820658) (xy 385.195572 -262.820658)
		)
		(stroke
			(width 0)
			(type solid)
		)
		(fill yes)
		(layer "In2.Cu")
		(net "M_F_CPU0_SA_DQS_DN<9>")
	)
	(gr_poly
		(pts
			(xy 385.242562 -261.449058) (xy 385.195572 -261.296658) (xy 384.933952 -261.296658) (xy 384.886962 -261.449058)
			(xy 384.886962 -261.493508) (xy 385.242562 -261.493508)
		)
		(stroke
			(width 0)
			(type solid)
		)
		(fill yes)
		(layer "In2.Cu")
		(net "M_F_CPU0_SA_CB<6>")
	)
	(gr_poly
		(pts
			(xy 385.242562 -261.040626) (xy 385.242562 -260.996176) (xy 384.886962 -260.996176) (xy 384.886962 -261.040626)
			(xy 384.933952 -261.193026) (xy 385.195572 -261.193026)
		)
		(stroke
			(width 0)
			(type solid)
		)
		(fill yes)
		(layer "In2.Cu")
		(net "M_F_CPU0_SA_CB<5>")
	)
	(gr_poly
		(pts
			(xy 385.242562 -254.529082) (xy 385.242562 -254.484886) (xy 384.886962 -254.484886) (xy 384.886962 -254.529082)
			(xy 384.933952 -254.681482) (xy 385.195572 -254.681482)
		)
		(stroke
			(width 0)
			(type solid)
		)
		(fill yes)
		(layer "In2.Cu")
		(net "M_F_CPU0_CLK_DP<1>")
	)
	(gr_poly
		(pts
			(xy 385.251198 -279.354534) (xy 385.204208 -279.202134) (xy 384.942588 -279.202134) (xy 384.895598 -279.354534)
			(xy 384.895598 -279.39873) (xy 385.251198 -279.39873)
		)
		(stroke
			(width 0)
			(type solid)
		)
		(fill yes)
		(layer "In2.Cu")
		(net "M_F_CPU0_SA_DQ<1>")
	)
	(gr_poly
		(pts
			(xy 385.251198 -258.193286) (xy 385.204208 -258.040886) (xy 384.942588 -258.040886) (xy 384.895598 -258.193286)
			(xy 384.895598 -258.237482) (xy 385.251198 -258.237482)
		)
		(stroke
			(width 0)
			(type solid)
		)
		(fill yes)
		(layer "In2.Cu")
		(net "M_F_CPU0_SA_CA<0>")
	)
	(gr_poly
		(pts
			(xy 385.251198 -257.784854) (xy 385.251198 -257.740658) (xy 384.895598 -257.740658) (xy 384.895598 -257.784854)
			(xy 384.942588 -257.937254) (xy 385.204208 -257.937254)
		)
		(stroke
			(width 0)
			(type solid)
		)
		(fill yes)
		(layer "In2.Cu")
		(net "M_F_CPU0_SA_CA<1>")
	)
	(gr_poly
		(pts
			(xy 385.459478 -239.504728) (xy 385.497832 -239.48263) (xy 385.320032 -239.174782) (xy 385.281678 -239.19688)
			(xy 385.17322 -239.31372) (xy 385.30403 -239.540288)
		)
		(stroke
			(width 0)
			(type solid)
		)
		(fill yes)
		(layer "In2.Cu")
		(net "M_F_CPU0_SB_CB<0>")
	)
	(gr_poly
		(pts
			(xy 385.460494 -242.76177) (xy 385.498848 -242.739672) (xy 385.321048 -242.431824) (xy 385.282694 -242.453922)
			(xy 385.174236 -242.570762) (xy 385.305046 -242.79733)
		)
		(stroke
			(width 0)
			(type solid)
		)
		(fill yes)
		(layer "In2.Cu")
		(net "M_F_CPU0_SB_CB<5>")
	)
	(gr_poly
		(pts
			(xy 385.496816 -230.459788) (xy 385.458462 -230.43769) (xy 385.303014 -230.40213) (xy 385.172204 -230.628698)
			(xy 385.280662 -230.745538) (xy 385.319016 -230.767636)
		)
		(stroke
			(width 0)
			(type solid)
		)
		(fill yes)
		(layer "In2.Cu")
		(net "M_F_CPU0_SB_DQ<11>")
	)
	(gr_poly
		(pts
			(xy 385.569206 -238.88446) (xy 385.677664 -238.76762) (xy 385.546854 -238.541052) (xy 385.391406 -238.576612)
			(xy 385.353052 -238.59871) (xy 385.530852 -238.906558)
		)
		(stroke
			(width 0)
			(type solid)
		)
		(fill yes)
		(layer "In2.Cu")
		(net "M_F_CPU0_SB_CB<2>")
	)
	(gr_poly
		(pts
			(xy 385.571746 -242.144042) (xy 385.680204 -242.027202) (xy 385.549394 -241.800634) (xy 385.393946 -241.836194)
			(xy 385.355592 -241.858292) (xy 385.533392 -242.16614)
		)
		(stroke
			(width 0)
			(type solid)
		)
		(fill yes)
		(layer "In2.Cu")
		(net "M_F_CPU0_SB_CB<7>")
	)
	(gr_poly
		(pts
			(xy 385.602734 -245.754906) (xy 385.555744 -245.602506) (xy 385.294124 -245.602506) (xy 385.247134 -245.754906)
			(xy 385.247134 -245.799356) (xy 385.602734 -245.799356)
		)
		(stroke
			(width 0)
			(type solid)
		)
		(fill yes)
		(layer "In2.Cu")
		(net "M_F_CPU0_SB_PAR")
	)
	(gr_poly
		(pts
			(xy 385.602734 -245.346474) (xy 385.602734 -245.302024) (xy 385.247134 -245.302024) (xy 385.247134 -245.346474)
			(xy 385.294124 -245.498874) (xy 385.555744 -245.498874)
		)
		(stroke
			(width 0)
			(type solid)
		)
		(fill yes)
		(layer "In2.Cu")
		(net "M_F_CPU0_SB_CS_N<2>")
	)
	(gr_poly
		(pts
			(xy 385.602734 -244.127274) (xy 385.555744 -243.974874) (xy 385.294124 -243.974874) (xy 385.247134 -244.127274)
			(xy 385.247134 -244.17147) (xy 385.602734 -244.17147)
		)
		(stroke
			(width 0)
			(type solid)
		)
		(fill yes)
		(layer "In2.Cu")
		(net "M_F_CPU0_SB_CS_N<1>")
	)
	(gr_poly
		(pts
			(xy 385.602734 -243.718334) (xy 385.602734 -243.674138) (xy 385.247134 -243.674138) (xy 385.247134 -243.718334)
			(xy 385.294124 -243.870734) (xy 385.555744 -243.870734)
		)
		(stroke
			(width 0)
			(type solid)
		)
		(fill yes)
		(layer "In2.Cu")
		(net "M_F_CPU0_SB_CB<4>")
	)
	(gr_poly
		(pts
			(xy 385.602734 -240.871502) (xy 385.555744 -240.719102) (xy 385.294124 -240.719102) (xy 385.247134 -240.871502)
			(xy 385.247134 -240.915952) (xy 385.602734 -240.915952)
		)
		(stroke
			(width 0)
			(type solid)
		)
		(fill yes)
		(layer "In2.Cu")
		(net "M_F_CPU0_SB_DQS_DN<9>")
	)
	(gr_poly
		(pts
			(xy 385.602734 -237.61573) (xy 385.555744 -237.46333) (xy 385.294124 -237.46333) (xy 385.247134 -237.61573)
			(xy 385.247134 -237.66018) (xy 385.602734 -237.66018)
		)
		(stroke
			(width 0)
			(type solid)
		)
		(fill yes)
		(layer "In2.Cu")
		(net "M_F_CPU0_SB_CB<3>")
	)
	(gr_poly
		(pts
			(xy 385.602734 -233.952034) (xy 385.602734 -233.907584) (xy 385.247134 -233.907584) (xy 385.247134 -233.952034)
			(xy 385.294124 -234.104434) (xy 385.555744 -234.104434)
		)
		(stroke
			(width 0)
			(type solid)
		)
		(fill yes)
		(layer "In2.Cu")
		(net "M_E_CPU0_SB_DQ<4>")
	)
	(gr_poly
		(pts
			(xy 385.602734 -232.732834) (xy 385.555744 -232.580434) (xy 385.294124 -232.580434) (xy 385.247134 -232.732834)
			(xy 385.247134 -232.77703) (xy 385.602734 -232.77703)
		)
		(stroke
			(width 0)
			(type solid)
		)
		(fill yes)
		(layer "In2.Cu")
		(net "M_E_CPU0_SB_DQ<7>")
	)
	(gr_poly
		(pts
			(xy 385.602734 -232.323894) (xy 385.602734 -232.279698) (xy 385.247134 -232.279698) (xy 385.247134 -232.323894)
			(xy 385.294124 -232.476294) (xy 385.555744 -232.476294)
		)
		(stroke
			(width 0)
			(type solid)
		)
		(fill yes)
		(layer "In2.Cu")
		(net "M_F_CPU0_SB_DQ<8>")
	)
	(gr_poly
		(pts
			(xy 385.602734 -229.477062) (xy 385.555744 -229.324662) (xy 385.294124 -229.324662) (xy 385.247134 -229.477062)
			(xy 385.247134 -229.521512) (xy 385.602734 -229.521512)
		)
		(stroke
			(width 0)
			(type solid)
		)
		(fill yes)
		(layer "In2.Cu")
		(net "M_F_CPU0_SB_DQS_DN<1>")
	)
	(gr_poly
		(pts
			(xy 385.602734 -229.06863) (xy 385.602734 -229.02418) (xy 385.247134 -229.02418) (xy 385.247134 -229.06863)
			(xy 385.294124 -229.22103) (xy 385.555744 -229.22103)
		)
		(stroke
			(width 0)
			(type solid)
		)
		(fill yes)
		(layer "In2.Cu")
		(net "M_F_CPU0_SB_DQS_DN<6>")
	)
	(gr_poly
		(pts
			(xy 385.602734 -227.84943) (xy 385.555744 -227.69703) (xy 385.294124 -227.69703) (xy 385.247134 -227.84943)
			(xy 385.247134 -227.893626) (xy 385.602734 -227.893626)
		)
		(stroke
			(width 0)
			(type solid)
		)
		(fill yes)
		(layer "In2.Cu")
		(net "M_F_CPU0_SB_DQ<14>")
	)
	(gr_poly
		(pts
			(xy 385.602734 -227.44049) (xy 385.602734 -227.396294) (xy 385.247134 -227.396294) (xy 385.247134 -227.44049)
			(xy 385.294124 -227.59289) (xy 385.555744 -227.59289)
		)
		(stroke
			(width 0)
			(type solid)
		)
		(fill yes)
		(layer "In2.Cu")
		(net "M_F_CPU0_SB_DQ<13>")
	)
	(gr_poly
		(pts
			(xy 385.611116 -240.46307) (xy 385.611116 -240.418874) (xy 385.255516 -240.418874) (xy 385.255516 -240.46307)
			(xy 385.302506 -240.61547) (xy 385.564126 -240.61547)
		)
		(stroke
			(width 0)
			(type solid)
		)
		(fill yes)
		(layer "In2.Cu")
		(net "M_F_CPU0_SB_DQS_DN<4>")
	)
	(gr_poly
		(pts
			(xy 385.611116 -237.207806) (xy 385.611116 -237.163356) (xy 385.255516 -237.163356) (xy 385.255516 -237.207806)
			(xy 385.302506 -237.360206) (xy 385.564126 -237.360206)
		)
		(stroke
			(width 0)
			(type solid)
		)
		(fill yes)
		(layer "In2.Cu")
		(net "M_E_CPU0_SB_DQ<0>")
	)
	(gr_poly
		(pts
			(xy 385.611116 -235.988098) (xy 385.564126 -235.835698) (xy 385.302506 -235.835698) (xy 385.255516 -235.988098)
			(xy 385.255516 -236.032294) (xy 385.611116 -236.032294)
		)
		(stroke
			(width 0)
			(type solid)
		)
		(fill yes)
		(layer "In2.Cu")
		(net "M_E_CPU0_SB_DQ<3>")
	)
	(gr_poly
		(pts
			(xy 385.611116 -235.579666) (xy 385.611116 -235.53547) (xy 385.255516 -235.53547) (xy 385.255516 -235.579666)
			(xy 385.302506 -235.732066) (xy 385.564126 -235.732066)
		)
		(stroke
			(width 0)
			(type solid)
		)
		(fill yes)
		(layer "In2.Cu")
		(net "M_E_CPU0_SB_DQS_DP<0>")
	)
	(gr_poly
		(pts
			(xy 385.675632 -231.176322) (xy 385.567174 -231.059482) (xy 385.52882 -231.037384) (xy 385.35102 -231.345232)
			(xy 385.389374 -231.36733) (xy 385.544822 -231.40289)
		)
		(stroke
			(width 0)
			(type solid)
		)
		(fill yes)
		(layer "In2.Cu")
		(net "M_F_CPU0_SB_DQ<9>")
	)
	(gr_poly
		(pts
			(xy 385.70408 -279.759918) (xy 385.70408 -279.715722) (xy 385.34848 -279.715722) (xy 385.34848 -279.759918)
			(xy 385.39547 -279.912318) (xy 385.65709 -279.912318)
		)
		(stroke
			(width 0)
			(type solid)
		)
		(fill yes)
		(layer "In2.Cu")
		(net "M_F_CPU0_SA_DQ<3>")
	)
	(gr_poly
		(pts
			(xy 385.70408 -278.540718) (xy 385.65709 -278.388318) (xy 385.39547 -278.388318) (xy 385.34848 -278.540718)
			(xy 385.34848 -278.584914) (xy 385.70408 -278.584914)
		)
		(stroke
			(width 0)
			(type solid)
		)
		(fill yes)
		(layer "In2.Cu")
		(net "M_F_CPU0_SA_DQS_DN<0>")
	)
	(gr_poly
		(pts
			(xy 385.70408 -258.599178) (xy 385.70408 -258.554728) (xy 385.34848 -258.554728) (xy 385.34848 -258.599178)
			(xy 385.39547 -258.751578) (xy 385.65709 -258.751578)
		)
		(stroke
			(width 0)
			(type solid)
		)
		(fill yes)
		(layer "In2.Cu")
		(net "M_F_CPU0_SA_CS_N<1>")
	)
	(gr_poly
		(pts
			(xy 385.70408 -257.37947) (xy 385.65709 -257.22707) (xy 385.39547 -257.22707) (xy 385.34848 -257.37947)
			(xy 385.34848 -257.423666) (xy 385.70408 -257.423666)
		)
		(stroke
			(width 0)
			(type solid)
		)
		(fill yes)
		(layer "In2.Cu")
		(net "M_F_CPU0_SA_CA<2>")
	)
	(gr_poly
		(pts
			(xy 385.712462 -278.132032) (xy 385.712462 -278.087836) (xy 385.356862 -278.087836) (xy 385.356862 -278.132032)
			(xy 385.403852 -278.284432) (xy 385.665472 -278.284432)
		)
		(stroke
			(width 0)
			(type solid)
		)
		(fill yes)
		(layer "In2.Cu")
		(net "M_F_CPU0_SA_DQS_DN<5>")
	)
	(gr_poly
		(pts
			(xy 385.712462 -276.913086) (xy 385.665472 -276.760686) (xy 385.403852 -276.760686) (xy 385.356862 -276.913086)
			(xy 385.356862 -276.957282) (xy 385.712462 -276.957282)
		)
		(stroke
			(width 0)
			(type solid)
		)
		(fill yes)
		(layer "In2.Cu")
		(net "M_F_CPU0_SA_DQ<6>")
	)
	(gr_poly
		(pts
			(xy 385.712462 -276.504146) (xy 385.712462 -276.45995) (xy 385.356862 -276.45995) (xy 385.356862 -276.504146)
			(xy 385.403852 -276.656546) (xy 385.665472 -276.656546)
		)
		(stroke
			(width 0)
			(type solid)
		)
		(fill yes)
		(layer "In2.Cu")
		(net "M_F_CPU0_SA_DQ<5>")
	)
	(gr_poly
		(pts
			(xy 385.712462 -273.657314) (xy 385.665472 -273.504914) (xy 385.403852 -273.504914) (xy 385.356862 -273.657314)
			(xy 385.356862 -273.701764) (xy 385.712462 -273.701764)
		)
		(stroke
			(width 0)
			(type solid)
		)
		(fill yes)
		(layer "In2.Cu")
		(net "M_E_CPU0_SA_DQ<11>")
	)
	(gr_poly
		(pts
			(xy 385.712462 -273.248882) (xy 385.712462 -273.204432) (xy 385.356862 -273.204432) (xy 385.356862 -273.248882)
			(xy 385.403852 -273.401282) (xy 385.665472 -273.401282)
		)
		(stroke
			(width 0)
			(type solid)
		)
		(fill yes)
		(layer "In2.Cu")
		(net "M_E_CPU0_SA_DQS_DP<1>")
	)
	(gr_poly
		(pts
			(xy 385.712462 -268.77391) (xy 385.665472 -268.62151) (xy 385.403852 -268.62151) (xy 385.356862 -268.77391)
			(xy 385.356862 -268.81836) (xy 385.712462 -268.81836)
		)
		(stroke
			(width 0)
			(type solid)
		)
		(fill yes)
		(layer "In2.Cu")
		(net "M_F_CPU0_SA_DQ<19>")
	)
	(gr_poly
		(pts
			(xy 385.712462 -267.146278) (xy 385.665472 -266.993878) (xy 385.403852 -266.993878) (xy 385.356862 -267.146278)
			(xy 385.356862 -267.190474) (xy 385.712462 -267.190474)
		)
		(stroke
			(width 0)
			(type solid)
		)
		(fill yes)
		(layer "In2.Cu")
		(net "M_F_CPU0_SA_DQS_DP<7>")
	)
	(gr_poly
		(pts
			(xy 385.712462 -266.737846) (xy 385.712462 -266.693396) (xy 385.356862 -266.693396) (xy 385.356862 -266.737846)
			(xy 385.403852 -266.890246) (xy 385.665472 -266.890246)
		)
		(stroke
			(width 0)
			(type solid)
		)
		(fill yes)
		(layer "In2.Cu")
		(net "M_F_CPU0_SA_DQ<20>")
	)
	(gr_poly
		(pts
			(xy 385.712462 -263.891014) (xy 385.665472 -263.738614) (xy 385.403852 -263.738614) (xy 385.356862 -263.891014)
			(xy 385.356862 -263.93521) (xy 385.712462 -263.93521)
		)
		(stroke
			(width 0)
			(type solid)
		)
		(fill yes)
		(layer "In2.Cu")
		(net "M_F_CPU0_SA_CB<3>")
	)
	(gr_poly
		(pts
			(xy 385.712462 -263.482074) (xy 385.712462 -263.437878) (xy 385.356862 -263.437878) (xy 385.356862 -263.482074)
			(xy 385.403852 -263.634474) (xy 385.665472 -263.634474)
		)
		(stroke
			(width 0)
			(type solid)
		)
		(fill yes)
		(layer "In2.Cu")
		(net "M_F_CPU0_SA_DQS_DP<4>")
	)
	(gr_poly
		(pts
			(xy 385.712462 -262.262874) (xy 385.665472 -262.110474) (xy 385.403852 -262.110474) (xy 385.356862 -262.262874)
			(xy 385.356862 -262.307324) (xy 385.712462 -262.307324)
		)
		(stroke
			(width 0)
			(type solid)
		)
		(fill yes)
		(layer "In2.Cu")
		(net "M_F_CPU0_SA_DQS_DP<9>")
	)
	(gr_poly
		(pts
			(xy 385.712462 -261.854442) (xy 385.712462 -261.809992) (xy 385.356862 -261.809992) (xy 385.356862 -261.854442)
			(xy 385.403852 -262.006842) (xy 385.665472 -262.006842)
		)
		(stroke
			(width 0)
			(type solid)
		)
		(fill yes)
		(layer "In2.Cu")
		(net "M_F_CPU0_SA_CB<4>")
	)
	(gr_poly
		(pts
			(xy 385.712462 -260.635242) (xy 385.665472 -260.482842) (xy 385.403852 -260.482842) (xy 385.356862 -260.635242)
			(xy 385.356862 -260.679438) (xy 385.712462 -260.679438)
		)
		(stroke
			(width 0)
			(type solid)
		)
		(fill yes)
		(layer "In2.Cu")
		(net "M_F_CPU0_SA_CB<7>")
	)
	(gr_poly
		(pts
			(xy 385.712462 -256.971038) (xy 385.712462 -256.926588) (xy 385.356862 -256.926588) (xy 385.356862 -256.971038)
			(xy 385.403852 -257.123438) (xy 385.665472 -257.123438)
		)
		(stroke
			(width 0)
			(type solid)
		)
		(fill yes)
		(layer "In2.Cu")
		(net "M_F_CPU0_SA_CA<3>")
	)
	(gr_poly
		(pts
			(xy 385.712462 -254.124206) (xy 385.665472 -253.971806) (xy 385.403852 -253.971806) (xy 385.356862 -254.124206)
			(xy 385.356862 -254.168402) (xy 385.712462 -254.168402)
		)
		(stroke
			(width 0)
			(type solid)
		)
		(fill yes)
		(layer "In2.Cu")
		(net "M_F_CPU0_CLK_DN<1>")
	)
	(gr_poly
		(pts
			(xy 385.720844 -260.22681) (xy 385.720844 -260.18236) (xy 385.365244 -260.18236) (xy 385.365244 -260.22681)
			(xy 385.412234 -260.37921) (xy 385.673854 -260.37921)
		)
		(stroke
			(width 0)
			(type solid)
		)
		(fill yes)
		(layer "In2.Cu")
		(net "M_F_CPU0_ALERT_N")
	)
	(gr_poly
		(pts
			(xy 385.720844 -259.007102) (xy 385.673854 -258.854702) (xy 385.412234 -258.854702) (xy 385.365244 -259.007102)
			(xy 385.365244 -259.051552) (xy 385.720844 -259.051552)
		)
		(stroke
			(width 0)
			(type solid)
		)
		(fill yes)
		(layer "In2.Cu")
		(net "M_F_CPU0_SA_CS_N<3>")
	)
	(gr_poly
		(pts
			(xy 385.721098 -274.876768) (xy 385.721098 -274.832572) (xy 385.365498 -274.832572) (xy 385.365498 -274.876768)
			(xy 385.412488 -275.029168) (xy 385.674108 -275.029168)
		)
		(stroke
			(width 0)
			(type solid)
		)
		(fill yes)
		(layer "In2.Cu")
		(net "M_E_CPU0_SA_DQ<8>")
	)
	(gr_poly
		(pts
			(xy 385.721098 -272.029174) (xy 385.674108 -271.876774) (xy 385.412488 -271.876774) (xy 385.365498 -272.029174)
			(xy 385.365498 -272.073624) (xy 385.721098 -272.073624)
		)
		(stroke
			(width 0)
			(type solid)
		)
		(fill yes)
		(layer "In2.Cu")
		(net "M_E_CPU0_SA_DQS_DP<6>")
	)
	(gr_poly
		(pts
			(xy 385.721098 -271.62125) (xy 385.721098 -271.5768) (xy 385.365498 -271.5768) (xy 385.365498 -271.62125)
			(xy 385.412488 -271.77365) (xy 385.674108 -271.77365)
		)
		(stroke
			(width 0)
			(type solid)
		)
		(fill yes)
		(layer "In2.Cu")
		(net "M_E_CPU0_SA_DQ<12>")
	)
	(gr_poly
		(pts
			(xy 385.721098 -270.401542) (xy 385.674108 -270.249142) (xy 385.412488 -270.249142) (xy 385.365498 -270.401542)
			(xy 385.365498 -270.445992) (xy 385.721098 -270.445992)
		)
		(stroke
			(width 0)
			(type solid)
		)
		(fill yes)
		(layer "In2.Cu")
		(net "M_E_CPU0_SA_DQ<15>")
	)
	(gr_poly
		(pts
			(xy 385.721098 -269.993618) (xy 385.721098 -269.949168) (xy 385.365498 -269.949168) (xy 385.365498 -269.993618)
			(xy 385.412488 -270.146018) (xy 385.674108 -270.146018)
		)
		(stroke
			(width 0)
			(type solid)
		)
		(fill yes)
		(layer "In2.Cu")
		(net "M_F_CPU0_SA_DQ<16>")
	)
	(gr_poly
		(pts
			(xy 385.721098 -265.518392) (xy 385.674108 -265.365992) (xy 385.412488 -265.365992) (xy 385.365498 -265.518392)
			(xy 385.365498 -265.562588) (xy 385.721098 -265.562588)
		)
		(stroke
			(width 0)
			(type solid)
		)
		(fill yes)
		(layer "In2.Cu")
		(net "M_F_CPU0_SA_DQ<23>")
	)
	(gr_poly
		(pts
			(xy 385.721098 -265.110214) (xy 385.721098 -265.065764) (xy 385.365498 -265.065764) (xy 385.365498 -265.110214)
			(xy 385.412488 -265.262614) (xy 385.674108 -265.262614)
		)
		(stroke
			(width 0)
			(type solid)
		)
		(fill yes)
		(layer "In2.Cu")
		(net "M_F_CPU0_SA_CB<0>")
	)
	(gr_poly
		(pts
			(xy 385.721098 -255.75133) (xy 385.674108 -255.59893) (xy 385.412488 -255.59893) (xy 385.365498 -255.75133)
			(xy 385.365498 -255.79578) (xy 385.721098 -255.79578)
		)
		(stroke
			(width 0)
			(type solid)
		)
		(fill yes)
		(layer "In2.Cu")
		(net "M_F_CPU0_SA_CA<5>")
	)
	(gr_poly
		(pts
			(xy 385.721098 -255.343406) (xy 385.721098 -255.298956) (xy 385.365498 -255.298956) (xy 385.365498 -255.343406)
			(xy 385.412488 -255.495806) (xy 385.674108 -255.495806)
		)
		(stroke
			(width 0)
			(type solid)
		)
		(fill yes)
		(layer "In2.Cu")
		(net "M_F_CPU0_SA_CA<6>")
	)
	(gr_poly
		(pts
			(xy 385.928362 -238.688372) (xy 385.966716 -238.666274) (xy 385.788916 -238.358426) (xy 385.750562 -238.380524)
			(xy 385.642104 -238.497364) (xy 385.772914 -238.723932)
		)
		(stroke
			(width 0)
			(type solid)
		)
		(fill yes)
		(layer "In2.Cu")
		(net "M_F_CPU0_SB_CB<1>")
	)
	(gr_poly
		(pts
			(xy 385.967732 -219.876624) (xy 385.929378 -219.854526) (xy 385.77393 -219.818966) (xy 385.64312 -220.045534)
			(xy 385.751578 -220.162374) (xy 385.789932 -220.184472)
		)
		(stroke
			(width 0)
			(type solid)
		)
		(fill yes)
		(layer "In2.Cu")
		(net "M_F_CPU0_SB_DQ<21>")
	)
	(gr_poly
		(pts
			(xy 385.968748 -231.269794) (xy 385.930394 -231.247696) (xy 385.774946 -231.212136) (xy 385.644136 -231.438704)
			(xy 385.752594 -231.555544) (xy 385.790948 -231.577642)
		)
		(stroke
			(width 0)
			(type solid)
		)
		(fill yes)
		(layer "In2.Cu")
		(net "M_F_CPU0_SB_DQ<10>")
	)
	(gr_poly
		(pts
			(xy 386.037074 -238.06658) (xy 386.145532 -237.94974) (xy 386.014722 -237.723172) (xy 385.859274 -237.758732)
			(xy 385.82092 -237.78083) (xy 385.99872 -238.088678)
		)
		(stroke
			(width 0)
			(type solid)
		)
		(fill yes)
		(layer "In2.Cu")
		(net "M_F_CPU0_SB_CB<3>")
	)
	(gr_poly
		(pts
			(xy 386.04444 -241.335814) (xy 386.152898 -241.218974) (xy 386.022088 -240.992406) (xy 385.86664 -241.027966)
			(xy 385.828286 -241.050064) (xy 386.006086 -241.357912)
		)
		(stroke
			(width 0)
			(type solid)
		)
		(fill yes)
		(layer "In2.Cu")
		(net "M_F_CPU0_SB_DQS_DN<9>")
	)
	(gr_poly
		(pts
			(xy 386.063998 -240.057178) (xy 386.017008 -239.904778) (xy 385.755388 -239.904778) (xy 385.708398 -240.057178)
			(xy 385.708398 -240.101628) (xy 386.063998 -240.101628)
		)
		(stroke
			(width 0)
			(type solid)
		)
		(fill yes)
		(layer "In2.Cu")
		(net "M_F_CPU0_SB_DQS_DP<4>")
	)
	(gr_poly
		(pts
			(xy 386.063998 -239.649254) (xy 386.063998 -239.604804) (xy 385.708398 -239.604804) (xy 385.708398 -239.649254)
			(xy 385.755388 -239.801654) (xy 386.017008 -239.801654)
		)
		(stroke
			(width 0)
			(type solid)
		)
		(fill yes)
		(layer "In2.Cu")
		(net "M_F_CPU0_SB_CB<0>")
	)
	(gr_poly
		(pts
			(xy 386.063998 -235.174282) (xy 386.017008 -235.021882) (xy 385.755388 -235.021882) (xy 385.708398 -235.174282)
			(xy 385.708398 -235.218478) (xy 386.063998 -235.218478)
		)
		(stroke
			(width 0)
			(type solid)
		)
		(fill yes)
		(layer "In2.Cu")
		(net "M_E_CPU0_SB_DQS_DN<0>")
	)
	(gr_poly
		(pts
			(xy 386.072634 -244.94109) (xy 386.025644 -244.78869) (xy 385.764024 -244.78869) (xy 385.717034 -244.94109)
			(xy 385.717034 -244.985286) (xy 386.072634 -244.985286)
		)
		(stroke
			(width 0)
			(type solid)
		)
		(fill yes)
		(layer "In2.Cu")
		(net "M_F_CPU0_SB_CS_N<0>")
	)
	(gr_poly
		(pts
			(xy 386.072634 -244.53215) (xy 386.072634 -244.487954) (xy 385.717034 -244.487954) (xy 385.717034 -244.53215)
			(xy 385.764024 -244.68455) (xy 386.025644 -244.68455)
		)
		(stroke
			(width 0)
			(type solid)
		)
		(fill yes)
		(layer "In2.Cu")
		(net "M_F_CPU0_SB_CS_N<3>")
	)
	(gr_poly
		(pts
			(xy 386.072634 -243.313458) (xy 386.025644 -243.161058) (xy 385.764024 -243.161058) (xy 385.717034 -243.313458)
			(xy 385.717034 -243.357654) (xy 386.072634 -243.357654)
		)
		(stroke
			(width 0)
			(type solid)
		)
		(fill yes)
		(layer "In2.Cu")
		(net "M_F_CPU0_SB_CB<6>")
	)
	(gr_poly
		(pts
			(xy 386.072634 -242.904518) (xy 386.072634 -242.860322) (xy 385.717034 -242.860322) (xy 385.717034 -242.904518)
			(xy 385.764024 -243.056918) (xy 386.025644 -243.056918)
		)
		(stroke
			(width 0)
			(type solid)
		)
		(fill yes)
		(layer "In2.Cu")
		(net "M_F_CPU0_SB_CB<5>")
	)
	(gr_poly
		(pts
			(xy 386.072634 -233.54665) (xy 386.025644 -233.39425) (xy 385.764024 -233.39425) (xy 385.717034 -233.54665)
			(xy 385.717034 -233.590846) (xy 386.072634 -233.590846)
		)
		(stroke
			(width 0)
			(type solid)
		)
		(fill yes)
		(layer "In2.Cu")
		(net "M_E_CPU0_SB_DQ<6>")
	)
	(gr_poly
		(pts
			(xy 386.072634 -233.13771) (xy 386.072634 -233.093514) (xy 385.717034 -233.093514) (xy 385.717034 -233.13771)
			(xy 385.764024 -233.29011) (xy 386.025644 -233.29011)
		)
		(stroke
			(width 0)
			(type solid)
		)
		(fill yes)
		(layer "In2.Cu")
		(net "M_E_CPU0_SB_DQ<5>")
	)
	(gr_poly
		(pts
			(xy 386.072634 -230.290878) (xy 386.025644 -230.138478) (xy 385.764024 -230.138478) (xy 385.717034 -230.290878)
			(xy 385.717034 -230.335328) (xy 386.072634 -230.335328)
		)
		(stroke
			(width 0)
			(type solid)
		)
		(fill yes)
		(layer "In2.Cu")
		(net "M_F_CPU0_SB_DQ<11>")
	)
	(gr_poly
		(pts
			(xy 386.072634 -229.882446) (xy 386.072634 -229.837996) (xy 385.717034 -229.837996) (xy 385.717034 -229.882446)
			(xy 385.764024 -230.034846) (xy 386.025644 -230.034846)
		)
		(stroke
			(width 0)
			(type solid)
		)
		(fill yes)
		(layer "In2.Cu")
		(net "M_F_CPU0_SB_DQS_DP<1>")
	)
	(gr_poly
		(pts
			(xy 386.072634 -228.663246) (xy 386.025644 -228.510846) (xy 385.764024 -228.510846) (xy 385.717034 -228.663246)
			(xy 385.717034 -228.707696) (xy 386.072634 -228.707696)
		)
		(stroke
			(width 0)
			(type solid)
		)
		(fill yes)
		(layer "In2.Cu")
		(net "M_F_CPU0_SB_DQS_DP<6>")
	)
	(gr_poly
		(pts
			(xy 386.072634 -228.254814) (xy 386.072634 -228.210364) (xy 385.717034 -228.210364) (xy 385.717034 -228.254814)
			(xy 385.764024 -228.407214) (xy 386.025644 -228.407214)
		)
		(stroke
			(width 0)
			(type solid)
		)
		(fill yes)
		(layer "In2.Cu")
		(net "M_F_CPU0_SB_DQ<12>")
	)
	(gr_poly
		(pts
			(xy 386.072634 -227.035614) (xy 386.025644 -226.883214) (xy 385.764024 -226.883214) (xy 385.717034 -227.035614)
			(xy 385.717034 -227.07981) (xy 386.072634 -227.07981)
		)
		(stroke
			(width 0)
			(type solid)
		)
		(fill yes)
		(layer "In2.Cu")
		(net "M_F_CPU0_SB_DQ<15>")
	)
	(gr_poly
		(pts
			(xy 386.072634 -224.999042) (xy 386.072634 -224.954592) (xy 385.717034 -224.954592) (xy 385.717034 -224.999042)
			(xy 385.764024 -225.151442) (xy 386.025644 -225.151442)
		)
		(stroke
			(width 0)
			(type solid)
		)
		(fill yes)
		(layer "In2.Cu")
		(net "M_F_CPU0_SB_DQ<16>")
	)
	(gr_poly
		(pts
			(xy 386.145532 -220.595698) (xy 386.037074 -220.478858) (xy 385.99872 -220.45676) (xy 385.82092 -220.764608)
			(xy 385.859274 -220.786706) (xy 386.014722 -220.822266)
		)
		(stroke
			(width 0)
			(type solid)
		)
		(fill yes)
		(layer "In2.Cu")
		(net "M_F_CPU0_SB_DQ<23>")
	)
	(gr_poly
		(pts
			(xy 386.147564 -231.986328) (xy 386.039106 -231.869488) (xy 386.000752 -231.84739) (xy 385.822952 -232.155238)
			(xy 385.861306 -232.177336) (xy 386.016754 -232.212896)
		)
		(stroke
			(width 0)
			(type solid)
		)
		(fill yes)
		(layer "In2.Cu")
		(net "M_F_CPU0_SB_DQ<8>")
	)
	(gr_poly
		(pts
			(xy 386.173726 -259.820918) (xy 386.126736 -259.668518) (xy 385.865116 -259.668518) (xy 385.818126 -259.820918)
			(xy 385.818126 -259.865368) (xy 386.173726 -259.865368)
		)
		(stroke
			(width 0)
			(type solid)
		)
		(fill yes)
		(layer "In2.Cu")
		(net "M_F_CPU0_SA_CS_N<0>")
	)
	(gr_poly
		(pts
			(xy 386.173726 -259.412994) (xy 386.173726 -259.368544) (xy 385.818126 -259.368544) (xy 385.818126 -259.412994)
			(xy 385.865116 -259.565394) (xy 386.126736 -259.565394)
		)
		(stroke
			(width 0)
			(type solid)
		)
		(fill yes)
		(layer "In2.Cu")
		(net "M_F_CPU0_SA_CS_N<2>")
	)
	(gr_poly
		(pts
			(xy 386.17398 -274.47113) (xy 386.12699 -274.31873) (xy 385.86537 -274.31873) (xy 385.81838 -274.47113)
			(xy 385.81838 -274.515326) (xy 386.17398 -274.515326)
		)
		(stroke
			(width 0)
			(type solid)
		)
		(fill yes)
		(layer "In2.Cu")
		(net "M_E_CPU0_SA_DQ<10>")
	)
	(gr_poly
		(pts
			(xy 386.17398 -272.435066) (xy 386.17398 -272.39087) (xy 385.81838 -272.39087) (xy 385.81838 -272.435066)
			(xy 385.86537 -272.587466) (xy 386.12699 -272.587466)
		)
		(stroke
			(width 0)
			(type solid)
		)
		(fill yes)
		(layer "In2.Cu")
		(net "M_E_CPU0_SA_DQS_DN<6>")
	)
	(gr_poly
		(pts
			(xy 386.17398 -271.215358) (xy 386.12699 -271.062958) (xy 385.86537 -271.062958) (xy 385.81838 -271.215358)
			(xy 385.81838 -271.259808) (xy 386.17398 -271.259808)
		)
		(stroke
			(width 0)
			(type solid)
		)
		(fill yes)
		(layer "In2.Cu")
		(net "M_E_CPU0_SA_DQ<14>")
	)
	(gr_poly
		(pts
			(xy 386.17398 -270.807434) (xy 386.17398 -270.762984) (xy 385.81838 -270.762984) (xy 385.81838 -270.807434)
			(xy 385.86537 -270.959834) (xy 386.12699 -270.959834)
		)
		(stroke
			(width 0)
			(type solid)
		)
		(fill yes)
		(layer "In2.Cu")
		(net "M_E_CPU0_SA_DQ<13>")
	)
	(gr_poly
		(pts
			(xy 386.17398 -269.587726) (xy 386.12699 -269.435326) (xy 385.86537 -269.435326) (xy 385.81838 -269.587726)
			(xy 385.81838 -269.631922) (xy 386.17398 -269.631922)
		)
		(stroke
			(width 0)
			(type solid)
		)
		(fill yes)
		(layer "In2.Cu")
		(net "M_F_CPU0_SA_DQ<18>")
	)
	(gr_poly
		(pts
			(xy 386.17398 -265.924284) (xy 386.17398 -265.879834) (xy 385.81838 -265.879834) (xy 385.81838 -265.924284)
			(xy 385.86537 -266.076684) (xy 386.12699 -266.076684)
		)
		(stroke
			(width 0)
			(type solid)
		)
		(fill yes)
		(layer "In2.Cu")
		(net "M_F_CPU0_SA_DQ<21>")
	)
	(gr_poly
		(pts
			(xy 386.17398 -264.704322) (xy 386.12699 -264.551922) (xy 385.86537 -264.551922) (xy 385.81838 -264.704322)
			(xy 385.81838 -264.748772) (xy 386.17398 -264.748772)
		)
		(stroke
			(width 0)
			(type solid)
		)
		(fill yes)
		(layer "In2.Cu")
		(net "M_F_CPU0_SA_CB<2>")
	)
	(gr_poly
		(pts
			(xy 386.17398 -256.157222) (xy 386.17398 -256.113026) (xy 385.81838 -256.113026) (xy 385.81838 -256.157222)
			(xy 385.86537 -256.309622) (xy 386.12699 -256.309622)
		)
		(stroke
			(width 0)
			(type solid)
		)
		(fill yes)
		(layer "In2.Cu")
		(net "M_F_CPU0_SA_CA<4>")
	)
	(gr_poly
		(pts
			(xy 386.182108 -278.945594) (xy 386.182108 -278.901398) (xy 385.826508 -278.901398) (xy 385.826508 -278.945594)
			(xy 385.873498 -279.097994) (xy 386.135118 -279.097994)
		)
		(stroke
			(width 0)
			(type solid)
		)
		(fill yes)
		(layer "In2.Cu")
		(net "M_F_CPU0_SA_DQS_DP<0>")
	)
	(gr_poly
		(pts
			(xy 386.182108 -254.52959) (xy 386.182108 -254.48514) (xy 385.826508 -254.48514) (xy 385.826508 -254.52959)
			(xy 385.873498 -254.68199) (xy 386.135118 -254.68199)
		)
		(stroke
			(width 0)
			(type solid)
		)
		(fill yes)
		(layer "In2.Cu")
		(net "M_F_CPU0_CLK_DP<1>")
	)
	(gr_poly
		(pts
			(xy 386.182362 -277.726902) (xy 386.135372 -277.574502) (xy 385.873752 -277.574502) (xy 385.826762 -277.726902)
			(xy 385.826762 -277.771098) (xy 386.182362 -277.771098)
		)
		(stroke
			(width 0)
			(type solid)
		)
		(fill yes)
		(layer "In2.Cu")
		(net "M_F_CPU0_SA_DQS_DP<5>")
	)
	(gr_poly
		(pts
			(xy 386.182362 -277.317962) (xy 386.182362 -277.273766) (xy 385.826762 -277.273766) (xy 385.826762 -277.317962)
			(xy 385.873752 -277.470362) (xy 386.135372 -277.470362)
		)
		(stroke
			(width 0)
			(type solid)
		)
		(fill yes)
		(layer "In2.Cu")
		(net "M_F_CPU0_SA_DQ<4>")
	)
	(gr_poly
		(pts
			(xy 386.182362 -276.09927) (xy 386.135372 -275.94687) (xy 385.873752 -275.94687) (xy 385.826762 -276.09927)
			(xy 385.826762 -276.143466) (xy 386.182362 -276.143466)
		)
		(stroke
			(width 0)
			(type solid)
		)
		(fill yes)
		(layer "In2.Cu")
		(net "M_F_CPU0_SA_DQ<7>")
	)
	(gr_poly
		(pts
			(xy 386.182362 -274.062698) (xy 386.182362 -274.018248) (xy 385.826762 -274.018248) (xy 385.826762 -274.062698)
			(xy 385.873752 -274.215098) (xy 386.135372 -274.215098)
		)
		(stroke
			(width 0)
			(type solid)
		)
		(fill yes)
		(layer "In2.Cu")
		(net "M_E_CPU0_SA_DQ<9>")
	)
	(gr_poly
		(pts
			(xy 386.182362 -272.843498) (xy 386.135372 -272.691098) (xy 385.873752 -272.691098) (xy 385.826762 -272.843498)
			(xy 385.826762 -272.887948) (xy 386.182362 -272.887948)
		)
		(stroke
			(width 0)
			(type solid)
		)
		(fill yes)
		(layer "In2.Cu")
		(net "M_E_CPU0_SA_DQS_DN<1>")
	)
	(gr_poly
		(pts
			(xy 386.182362 -269.179294) (xy 386.182362 -269.134844) (xy 385.826762 -269.134844) (xy 385.826762 -269.179294)
			(xy 385.873752 -269.331694) (xy 386.135372 -269.331694)
		)
		(stroke
			(width 0)
			(type solid)
		)
		(fill yes)
		(layer "In2.Cu")
		(net "M_F_CPU0_SA_DQ<17>")
	)
	(gr_poly
		(pts
			(xy 386.182362 -267.551662) (xy 386.182362 -267.507212) (xy 385.826762 -267.507212) (xy 385.826762 -267.551662)
			(xy 385.873752 -267.704062) (xy 386.135372 -267.704062)
		)
		(stroke
			(width 0)
			(type solid)
		)
		(fill yes)
		(layer "In2.Cu")
		(net "M_F_CPU0_SA_DQS_DN<7>")
	)
	(gr_poly
		(pts
			(xy 386.182362 -266.332462) (xy 386.135372 -266.180062) (xy 385.873752 -266.180062) (xy 385.826762 -266.332462)
			(xy 385.826762 -266.376658) (xy 386.182362 -266.376658)
		)
		(stroke
			(width 0)
			(type solid)
		)
		(fill yes)
		(layer "In2.Cu")
		(net "M_F_CPU0_SA_DQ<22>")
	)
	(gr_poly
		(pts
			(xy 386.182362 -264.29589) (xy 386.182362 -264.251694) (xy 385.826762 -264.251694) (xy 385.826762 -264.29589)
			(xy 385.873752 -264.44829) (xy 386.135372 -264.44829)
		)
		(stroke
			(width 0)
			(type solid)
		)
		(fill yes)
		(layer "In2.Cu")
		(net "M_F_CPU0_SA_CB<1>")
	)
	(gr_poly
		(pts
			(xy 386.182362 -261.449058) (xy 386.135372 -261.296658) (xy 385.873752 -261.296658) (xy 385.826762 -261.449058)
			(xy 385.826762 -261.493508) (xy 386.182362 -261.493508)
		)
		(stroke
			(width 0)
			(type solid)
		)
		(fill yes)
		(layer "In2.Cu")
		(net "M_F_CPU0_SA_CB<6>")
	)
	(gr_poly
		(pts
			(xy 386.182362 -261.040626) (xy 386.182362 -260.996176) (xy 385.826762 -260.996176) (xy 385.826762 -261.040626)
			(xy 385.873752 -261.193026) (xy 386.135372 -261.193026)
		)
		(stroke
			(width 0)
			(type solid)
		)
		(fill yes)
		(layer "In2.Cu")
		(net "M_F_CPU0_SA_CB<5>")
	)
	(gr_poly
		(pts
			(xy 386.182616 -263.077198) (xy 386.135626 -262.924798) (xy 385.874006 -262.924798) (xy 385.827016 -263.077198)
			(xy 385.827016 -263.121648) (xy 386.182616 -263.121648)
		)
		(stroke
			(width 0)
			(type solid)
		)
		(fill yes)
		(layer "In2.Cu")
		(net "M_F_CPU0_SA_DQS_DN<4>")
	)
	(gr_poly
		(pts
			(xy 386.188458 -262.668512) (xy 386.188458 -262.624062) (xy 385.832858 -262.624062) (xy 385.832858 -262.668512)
			(xy 385.879848 -262.820912) (xy 386.141468 -262.820912)
		)
		(stroke
			(width 0)
			(type solid)
		)
		(fill yes)
		(layer "In2.Cu")
		(net "M_F_CPU0_SA_DQS_DN<9>")
	)
	(gr_poly
		(pts
			(xy 386.190998 -258.193286) (xy 386.144008 -258.040886) (xy 385.882388 -258.040886) (xy 385.835398 -258.193286)
			(xy 385.835398 -258.237482) (xy 386.190998 -258.237482)
		)
		(stroke
			(width 0)
			(type solid)
		)
		(fill yes)
		(layer "In2.Cu")
		(net "M_F_CPU0_SA_CA<0>")
	)
	(gr_poly
		(pts
			(xy 386.190998 -257.784854) (xy 386.190998 -257.740658) (xy 385.835398 -257.740658) (xy 385.835398 -257.784854)
			(xy 385.882388 -257.937254) (xy 386.144008 -257.937254)
		)
		(stroke
			(width 0)
			(type solid)
		)
		(fill yes)
		(layer "In2.Cu")
		(net "M_F_CPU0_SA_CA<1>")
	)
	(gr_poly
		(pts
			(xy 386.432044 -219.07246) (xy 386.39369 -219.050362) (xy 386.238242 -219.014802) (xy 386.107432 -219.24137)
			(xy 386.21589 -219.35821) (xy 386.254244 -219.380308)
		)
		(stroke
			(width 0)
			(type solid)
		)
		(fill yes)
		(layer "In2.Cu")
		(net "M_F_CPU0_SB_DQ<21>")
	)
	(gr_poly
		(pts
			(xy 386.542534 -244.127274) (xy 386.495544 -243.974874) (xy 386.233924 -243.974874) (xy 386.186934 -244.127274)
			(xy 386.186934 -244.17147) (xy 386.542534 -244.17147)
		)
		(stroke
			(width 0)
			(type solid)
		)
		(fill yes)
		(layer "In2.Cu")
		(net "M_F_CPU0_SB_CS_N<1>")
	)
	(gr_poly
		(pts
			(xy 386.542534 -243.718334) (xy 386.542534 -243.674138) (xy 386.186934 -243.674138) (xy 386.186934 -243.718334)
			(xy 386.233924 -243.870734) (xy 386.495544 -243.870734)
		)
		(stroke
			(width 0)
			(type solid)
		)
		(fill yes)
		(layer "In2.Cu")
		(net "M_F_CPU0_SB_CB<4>")
	)
	(gr_poly
		(pts
			(xy 386.542534 -238.83493) (xy 386.542534 -238.790734) (xy 386.186934 -238.790734) (xy 386.186934 -238.83493)
			(xy 386.233924 -238.98733) (xy 386.495544 -238.98733)
		)
		(stroke
			(width 0)
			(type solid)
		)
		(fill yes)
		(layer "In2.Cu")
		(net "M_F_CPU0_SB_CB<1>")
	)
	(gr_poly
		(pts
			(xy 386.542534 -231.104694) (xy 386.495544 -230.952294) (xy 386.233924 -230.952294) (xy 386.186934 -231.104694)
			(xy 386.186934 -231.149144) (xy 386.542534 -231.149144)
		)
		(stroke
			(width 0)
			(type solid)
		)
		(fill yes)
		(layer "In2.Cu")
		(net "M_F_CPU0_SB_DQ<10>")
	)
	(gr_poly
		(pts
			(xy 386.542534 -230.696262) (xy 386.542534 -230.651812) (xy 386.186934 -230.651812) (xy 386.186934 -230.696262)
			(xy 386.233924 -230.848662) (xy 386.495544 -230.848662)
		)
		(stroke
			(width 0)
			(type solid)
		)
		(fill yes)
		(layer "In2.Cu")
		(net "M_F_CPU0_SB_DQ<9>")
	)
	(gr_poly
		(pts
			(xy 386.542534 -229.477062) (xy 386.495544 -229.324662) (xy 386.233924 -229.324662) (xy 386.186934 -229.477062)
			(xy 386.186934 -229.521512) (xy 386.542534 -229.521512)
		)
		(stroke
			(width 0)
			(type solid)
		)
		(fill yes)
		(layer "In2.Cu")
		(net "M_F_CPU0_SB_DQS_DN<1>")
	)
	(gr_poly
		(pts
			(xy 386.542534 -229.06863) (xy 386.542534 -229.02418) (xy 386.186934 -229.02418) (xy 386.186934 -229.06863)
			(xy 386.233924 -229.22103) (xy 386.495544 -229.22103)
		)
		(stroke
			(width 0)
			(type solid)
		)
		(fill yes)
		(layer "In2.Cu")
		(net "M_F_CPU0_SB_DQS_DN<6>")
	)
	(gr_poly
		(pts
			(xy 386.542534 -227.84943) (xy 386.495544 -227.69703) (xy 386.233924 -227.69703) (xy 386.186934 -227.84943)
			(xy 386.186934 -227.893626) (xy 386.542534 -227.893626)
		)
		(stroke
			(width 0)
			(type solid)
		)
		(fill yes)
		(layer "In2.Cu")
		(net "M_F_CPU0_SB_DQ<14>")
	)
	(gr_poly
		(pts
			(xy 386.542534 -227.44049) (xy 386.542534 -227.396294) (xy 386.186934 -227.396294) (xy 386.186934 -227.44049)
			(xy 386.233924 -227.59289) (xy 386.495544 -227.59289)
		)
		(stroke
			(width 0)
			(type solid)
		)
		(fill yes)
		(layer "In2.Cu")
		(net "M_F_CPU0_SB_DQ<13>")
	)
	(gr_poly
		(pts
			(xy 386.550916 -240.46307) (xy 386.550916 -240.418874) (xy 386.195316 -240.418874) (xy 386.195316 -240.46307)
			(xy 386.242306 -240.61547) (xy 386.503926 -240.61547)
		)
		(stroke
			(width 0)
			(type solid)
		)
		(fill yes)
		(layer "In2.Cu")
		(net "M_F_CPU0_SB_DQS_DN<4>")
	)
	(gr_poly
		(pts
			(xy 386.550916 -239.243362) (xy 386.503926 -239.090962) (xy 386.242306 -239.090962) (xy 386.195316 -239.243362)
			(xy 386.195316 -239.287812) (xy 386.550916 -239.287812)
		)
		(stroke
			(width 0)
			(type solid)
		)
		(fill yes)
		(layer "In2.Cu")
		(net "M_F_CPU0_SB_CB<2>")
	)
	(gr_poly
		(pts
			(xy 386.550916 -235.988098) (xy 386.503926 -235.835698) (xy 386.242306 -235.835698) (xy 386.195316 -235.988098)
			(xy 386.195316 -236.032294) (xy 386.550916 -236.032294)
		)
		(stroke
			(width 0)
			(type solid)
		)
		(fill yes)
		(layer "In2.Cu")
		(net "M_E_CPU0_SB_DQ<3>")
	)
	(gr_poly
		(pts
			(xy 386.550916 -235.579666) (xy 386.550916 -235.53547) (xy 386.195316 -235.53547) (xy 386.195316 -235.579666)
			(xy 386.242306 -235.732066) (xy 386.503926 -235.732066)
		)
		(stroke
			(width 0)
			(type solid)
		)
		(fill yes)
		(layer "In2.Cu")
		(net "M_E_CPU0_SB_DQS_DP<0>")
	)
	(gr_poly
		(pts
			(xy 386.616194 -219.780358) (xy 386.507736 -219.663518) (xy 386.469382 -219.64142) (xy 386.291582 -219.949268)
			(xy 386.329936 -219.971366) (xy 386.485384 -220.006926)
		)
		(stroke
			(width 0)
			(type solid)
		)
		(fill yes)
		(layer "In2.Cu")
		(net "M_F_CPU0_SB_DQ<23>")
	)
	(gr_poly
		(pts
			(xy 386.64388 -278.540718) (xy 386.59689 -278.388318) (xy 386.33527 -278.388318) (xy 386.28828 -278.540718)
			(xy 386.28828 -278.585168) (xy 386.64388 -278.585168)
		)
		(stroke
			(width 0)
			(type solid)
		)
		(fill yes)
		(layer "In2.Cu")
		(net "M_F_CPU0_SA_DQS_DN<0>")
	)
	(gr_poly
		(pts
			(xy 386.64388 -263.482582) (xy 386.64388 -263.438132) (xy 386.28828 -263.438132) (xy 386.28828 -263.482582)
			(xy 386.33527 -263.634982) (xy 386.59689 -263.634982)
		)
		(stroke
			(width 0)
			(type solid)
		)
		(fill yes)
		(layer "In2.Cu")
		(net "M_F_CPU0_SA_DQS_DP<4>")
	)
	(gr_poly
		(pts
			(xy 386.64388 -262.26262) (xy 386.59689 -262.11022) (xy 386.33527 -262.11022) (xy 386.28828 -262.26262)
			(xy 386.28828 -262.30707) (xy 386.64388 -262.30707)
		)
		(stroke
			(width 0)
			(type solid)
		)
		(fill yes)
		(layer "In2.Cu")
		(net "M_F_CPU0_SA_DQS_DP<9>")
	)
	(gr_poly
		(pts
			(xy 386.64388 -258.599178) (xy 386.64388 -258.554728) (xy 386.28828 -258.554728) (xy 386.28828 -258.599178)
			(xy 386.33527 -258.751578) (xy 386.59689 -258.751578)
		)
		(stroke
			(width 0)
			(type solid)
		)
		(fill yes)
		(layer "In2.Cu")
		(net "M_F_CPU0_SA_CS_N<1>")
	)
	(gr_poly
		(pts
			(xy 386.64388 -257.37947) (xy 386.59689 -257.22707) (xy 386.33527 -257.22707) (xy 386.28828 -257.37947)
			(xy 386.28828 -257.423666) (xy 386.64388 -257.423666)
		)
		(stroke
			(width 0)
			(type solid)
		)
		(fill yes)
		(layer "In2.Cu")
		(net "M_F_CPU0_SA_CA<2>")
	)
	(gr_poly
		(pts
			(xy 386.652008 -273.248374) (xy 386.652008 -273.204178) (xy 386.296408 -273.204178) (xy 386.296408 -273.248374)
			(xy 386.343398 -273.400774) (xy 386.605018 -273.400774)
		)
		(stroke
			(width 0)
			(type solid)
		)
		(fill yes)
		(layer "In2.Cu")
		(net "M_E_CPU0_SA_DQS_DP<1>")
	)
	(gr_poly
		(pts
			(xy 386.652262 -278.132032) (xy 386.652262 -278.087836) (xy 386.296662 -278.087836) (xy 386.296662 -278.132032)
			(xy 386.343652 -278.284432) (xy 386.605272 -278.284432)
		)
		(stroke
			(width 0)
			(type solid)
		)
		(fill yes)
		(layer "In2.Cu")
		(net "M_F_CPU0_SA_DQS_DN<5>")
	)
	(gr_poly
		(pts
			(xy 386.652262 -276.913086) (xy 386.605272 -276.760686) (xy 386.343652 -276.760686) (xy 386.296662 -276.913086)
			(xy 386.296662 -276.957282) (xy 386.652262 -276.957282)
		)
		(stroke
			(width 0)
			(type solid)
		)
		(fill yes)
		(layer "In2.Cu")
		(net "M_F_CPU0_SA_DQ<6>")
	)
	(gr_poly
		(pts
			(xy 386.652262 -276.504146) (xy 386.652262 -276.45995) (xy 386.296662 -276.45995) (xy 386.296662 -276.504146)
			(xy 386.343652 -276.656546) (xy 386.605272 -276.656546)
		)
		(stroke
			(width 0)
			(type solid)
		)
		(fill yes)
		(layer "In2.Cu")
		(net "M_F_CPU0_SA_DQ<5>")
	)
	(gr_poly
		(pts
			(xy 386.652262 -273.657314) (xy 386.605272 -273.504914) (xy 386.343652 -273.504914) (xy 386.296662 -273.657314)
			(xy 386.296662 -273.701764) (xy 386.652262 -273.701764)
		)
		(stroke
			(width 0)
			(type solid)
		)
		(fill yes)
		(layer "In2.Cu")
		(net "M_E_CPU0_SA_DQ<11>")
	)
	(gr_poly
		(pts
			(xy 386.652262 -268.77391) (xy 386.605272 -268.62151) (xy 386.343652 -268.62151) (xy 386.296662 -268.77391)
			(xy 386.296662 -268.81836) (xy 386.652262 -268.81836)
		)
		(stroke
			(width 0)
			(type solid)
		)
		(fill yes)
		(layer "In2.Cu")
		(net "M_F_CPU0_SA_DQ<19>")
	)
	(gr_poly
		(pts
			(xy 386.652262 -268.365478) (xy 386.652262 -268.321028) (xy 386.296662 -268.321028) (xy 386.296662 -268.365478)
			(xy 386.343652 -268.517878) (xy 386.605272 -268.517878)
		)
		(stroke
			(width 0)
			(type solid)
		)
		(fill yes)
		(layer "In2.Cu")
		(net "M_F_CPU0_SA_DQS_DP<2>")
	)
	(gr_poly
		(pts
			(xy 386.652262 -267.146278) (xy 386.605272 -266.993878) (xy 386.343652 -266.993878) (xy 386.296662 -267.146278)
			(xy 386.296662 -267.190474) (xy 386.652262 -267.190474)
		)
		(stroke
			(width 0)
			(type solid)
		)
		(fill yes)
		(layer "In2.Cu")
		(net "M_F_CPU0_SA_DQS_DP<7>")
	)
	(gr_poly
		(pts
			(xy 386.652262 -266.737846) (xy 386.652262 -266.693396) (xy 386.296662 -266.693396) (xy 386.296662 -266.737846)
			(xy 386.343652 -266.890246) (xy 386.605272 -266.890246)
		)
		(stroke
			(width 0)
			(type solid)
		)
		(fill yes)
		(layer "In2.Cu")
		(net "M_F_CPU0_SA_DQ<20>")
	)
	(gr_poly
		(pts
			(xy 386.652262 -263.891014) (xy 386.605272 -263.738614) (xy 386.343652 -263.738614) (xy 386.296662 -263.891014)
			(xy 386.296662 -263.93521) (xy 386.652262 -263.93521)
		)
		(stroke
			(width 0)
			(type solid)
		)
		(fill yes)
		(layer "In2.Cu")
		(net "M_F_CPU0_SA_CB<3>")
	)
	(gr_poly
		(pts
			(xy 386.652262 -261.854442) (xy 386.652262 -261.809992) (xy 386.296662 -261.809992) (xy 386.296662 -261.854442)
			(xy 386.343652 -262.006842) (xy 386.605272 -262.006842)
		)
		(stroke
			(width 0)
			(type solid)
		)
		(fill yes)
		(layer "In2.Cu")
		(net "M_F_CPU0_SA_CB<4>")
	)
	(gr_poly
		(pts
			(xy 386.652262 -260.635242) (xy 386.605272 -260.482842) (xy 386.343652 -260.482842) (xy 386.296662 -260.635242)
			(xy 386.296662 -260.679438) (xy 386.652262 -260.679438)
		)
		(stroke
			(width 0)
			(type solid)
		)
		(fill yes)
		(layer "In2.Cu")
		(net "M_F_CPU0_SA_CB<7>")
	)
	(gr_poly
		(pts
			(xy 386.652262 -256.971038) (xy 386.652262 -256.926588) (xy 386.296662 -256.926588) (xy 386.296662 -256.971038)
			(xy 386.343652 -257.123438) (xy 386.605272 -257.123438)
		)
		(stroke
			(width 0)
			(type solid)
		)
		(fill yes)
		(layer "In2.Cu")
		(net "M_F_CPU0_SA_CA<3>")
	)
	(gr_poly
		(pts
			(xy 386.652516 -254.124206) (xy 386.605526 -253.971806) (xy 386.343906 -253.971806) (xy 386.296916 -254.124206)
			(xy 386.296916 -254.168402) (xy 386.652516 -254.168402)
		)
		(stroke
			(width 0)
			(type solid)
		)
		(fill yes)
		(layer "In2.Cu")
		(net "M_F_CPU0_CLK_DN<1>")
	)
	(gr_poly
		(pts
			(xy 386.660644 -260.22681) (xy 386.660644 -260.18236) (xy 386.305044 -260.18236) (xy 386.305044 -260.22681)
			(xy 386.352034 -260.37921) (xy 386.613654 -260.37921)
		)
		(stroke
			(width 0)
			(type solid)
		)
		(fill yes)
		(layer "In2.Cu")
		(net "M_F_CPU0_ALERT_N")
	)
	(gr_poly
		(pts
			(xy 386.660644 -259.007102) (xy 386.613654 -258.854702) (xy 386.352034 -258.854702) (xy 386.305044 -259.007102)
			(xy 386.305044 -259.051552) (xy 386.660644 -259.051552)
		)
		(stroke
			(width 0)
			(type solid)
		)
		(fill yes)
		(layer "In2.Cu")
		(net "M_F_CPU0_SA_CS_N<3>")
	)
	(gr_poly
		(pts
			(xy 386.660898 -274.876768) (xy 386.660898 -274.832572) (xy 386.305298 -274.832572) (xy 386.305298 -274.876768)
			(xy 386.352288 -275.029168) (xy 386.613908 -275.029168)
		)
		(stroke
			(width 0)
			(type solid)
		)
		(fill yes)
		(layer "In2.Cu")
		(net "M_E_CPU0_SA_DQ<8>")
	)
	(gr_poly
		(pts
			(xy 386.660898 -272.029174) (xy 386.613908 -271.876774) (xy 386.352288 -271.876774) (xy 386.305298 -272.029174)
			(xy 386.305298 -272.073624) (xy 386.660898 -272.073624)
		)
		(stroke
			(width 0)
			(type solid)
		)
		(fill yes)
		(layer "In2.Cu")
		(net "M_E_CPU0_SA_DQS_DP<6>")
	)
	(gr_poly
		(pts
			(xy 386.660898 -271.62125) (xy 386.660898 -271.5768) (xy 386.305298 -271.5768) (xy 386.305298 -271.62125)
			(xy 386.352288 -271.77365) (xy 386.613908 -271.77365)
		)
		(stroke
			(width 0)
			(type solid)
		)
		(fill yes)
		(layer "In2.Cu")
		(net "M_E_CPU0_SA_DQ<12>")
	)
	(gr_poly
		(pts
			(xy 386.660898 -270.401542) (xy 386.613908 -270.249142) (xy 386.352288 -270.249142) (xy 386.305298 -270.401542)
			(xy 386.305298 -270.445992) (xy 386.660898 -270.445992)
		)
		(stroke
			(width 0)
			(type solid)
		)
		(fill yes)
		(layer "In2.Cu")
		(net "M_E_CPU0_SA_DQ<15>")
	)
	(gr_poly
		(pts
			(xy 386.660898 -269.993618) (xy 386.660898 -269.949168) (xy 386.305298 -269.949168) (xy 386.305298 -269.993618)
			(xy 386.352288 -270.146018) (xy 386.613908 -270.146018)
		)
		(stroke
			(width 0)
			(type solid)
		)
		(fill yes)
		(layer "In2.Cu")
		(net "M_F_CPU0_SA_DQ<16>")
	)
	(gr_poly
		(pts
			(xy 386.660898 -265.518392) (xy 386.613908 -265.365992) (xy 386.352288 -265.365992) (xy 386.305298 -265.518392)
			(xy 386.305298 -265.562588) (xy 386.660898 -265.562588)
		)
		(stroke
			(width 0)
			(type solid)
		)
		(fill yes)
		(layer "In2.Cu")
		(net "M_F_CPU0_SA_DQ<23>")
	)
	(gr_poly
		(pts
			(xy 386.660898 -265.110214) (xy 386.660898 -265.065764) (xy 386.305298 -265.065764) (xy 386.305298 -265.110214)
			(xy 386.352288 -265.262614) (xy 386.613908 -265.262614)
		)
		(stroke
			(width 0)
			(type solid)
		)
		(fill yes)
		(layer "In2.Cu")
		(net "M_F_CPU0_SA_CB<0>")
	)
	(gr_poly
		(pts
			(xy 386.906516 -226.390454) (xy 386.868162 -226.368356) (xy 386.712714 -226.332796) (xy 386.581904 -226.559364)
			(xy 386.690362 -226.676204) (xy 386.728716 -226.698302)
		)
		(stroke
			(width 0)
			(type solid)
		)
		(fill yes)
		(layer "In2.Cu")
		(net "M_F_CPU0_SB_DQ<15>")
	)
	(gr_poly
		(pts
			(xy 387.003798 -240.057178) (xy 386.956808 -239.904778) (xy 386.695188 -239.904778) (xy 386.648198 -240.057178)
			(xy 386.648198 -240.101628) (xy 387.003798 -240.101628)
		)
		(stroke
			(width 0)
			(type solid)
		)
		(fill yes)
		(layer "In2.Cu")
		(net "M_F_CPU0_SB_DQS_DP<4>")
	)
	(gr_poly
		(pts
			(xy 387.003798 -239.649254) (xy 387.003798 -239.604804) (xy 386.648198 -239.604804) (xy 386.648198 -239.649254)
			(xy 386.695188 -239.801654) (xy 386.956808 -239.801654)
		)
		(stroke
			(width 0)
			(type solid)
		)
		(fill yes)
		(layer "In2.Cu")
		(net "M_F_CPU0_SB_CB<0>")
	)
	(gr_poly
		(pts
			(xy 387.01218 -229.882446) (xy 387.01218 -229.83825) (xy 386.65658 -229.83825) (xy 386.65658 -229.882446)
			(xy 386.70357 -230.034846) (xy 386.96519 -230.034846)
		)
		(stroke
			(width 0)
			(type solid)
		)
		(fill yes)
		(layer "In2.Cu")
		(net "M_F_CPU0_SB_DQS_DP<1>")
	)
	(gr_poly
		(pts
			(xy 387.012434 -231.510078) (xy 387.012434 -231.465882) (xy 386.656834 -231.465882) (xy 386.656834 -231.510078)
			(xy 386.703824 -231.662478) (xy 386.965444 -231.662478)
		)
		(stroke
			(width 0)
			(type solid)
		)
		(fill yes)
		(layer "In2.Cu")
		(net "M_F_CPU0_SB_DQ<8>")
	)
	(gr_poly
		(pts
			(xy 387.012434 -230.290878) (xy 386.965444 -230.138478) (xy 386.703824 -230.138478) (xy 386.656834 -230.290878)
			(xy 386.656834 -230.335328) (xy 387.012434 -230.335328)
		)
		(stroke
			(width 0)
			(type solid)
		)
		(fill yes)
		(layer "In2.Cu")
		(net "M_F_CPU0_SB_DQ<11>")
	)
	(gr_poly
		(pts
			(xy 387.012434 -228.663246) (xy 386.965444 -228.510846) (xy 386.703824 -228.510846) (xy 386.656834 -228.663246)
			(xy 386.656834 -228.707696) (xy 387.012434 -228.707696)
		)
		(stroke
			(width 0)
			(type solid)
		)
		(fill yes)
		(layer "In2.Cu")
		(net "M_F_CPU0_SB_DQS_DP<6>")
	)
	(gr_poly
		(pts
			(xy 387.012434 -228.254814) (xy 387.012434 -228.210364) (xy 386.656834 -228.210364) (xy 386.656834 -228.254814)
			(xy 386.703824 -228.407214) (xy 386.965444 -228.407214)
		)
		(stroke
			(width 0)
			(type solid)
		)
		(fill yes)
		(layer "In2.Cu")
		(net "M_F_CPU0_SB_DQ<12>")
	)
	(gr_poly
		(pts
			(xy 387.012434 -224.999042) (xy 387.012434 -224.954592) (xy 386.656834 -224.954592) (xy 386.656834 -224.999042)
			(xy 386.703824 -225.151442) (xy 386.965444 -225.151442)
		)
		(stroke
			(width 0)
			(type solid)
		)
		(fill yes)
		(layer "In2.Cu")
		(net "M_F_CPU0_SB_DQ<16>")
	)
	(gr_poly
		(pts
			(xy 387.020816 -218.896438) (xy 386.973826 -218.744038) (xy 386.712206 -218.744038) (xy 386.665216 -218.896438)
			(xy 386.665216 -218.940634) (xy 387.020816 -218.940634)
		)
		(stroke
			(width 0)
			(type solid)
		)
		(fill yes)
		(layer "In2.Cu")
		(net "M_F_CPU0_SB_DQ<21>")
	)
	(gr_poly
		(pts
			(xy 387.087364 -227.102924) (xy 386.978906 -226.986084) (xy 386.940552 -226.963986) (xy 386.762752 -227.271834)
			(xy 386.801106 -227.293932) (xy 386.956554 -227.329492)
		)
		(stroke
			(width 0)
			(type solid)
		)
		(fill yes)
		(layer "In2.Cu")
		(net "M_F_CPU0_SB_DQ<13>")
	)
	(gr_poly
		(pts
			(xy 387.113526 -259.820918) (xy 387.066536 -259.668518) (xy 386.804916 -259.668518) (xy 386.757926 -259.820918)
			(xy 386.757926 -259.865368) (xy 387.113526 -259.865368)
		)
		(stroke
			(width 0)
			(type solid)
		)
		(fill yes)
		(layer "In2.Cu")
		(net "M_F_CPU0_SA_CS_N<0>")
	)
	(gr_poly
		(pts
			(xy 387.113526 -259.412994) (xy 387.113526 -259.368544) (xy 386.757926 -259.368544) (xy 386.757926 -259.412994)
			(xy 386.804916 -259.565394) (xy 387.066536 -259.565394)
		)
		(stroke
			(width 0)
			(type solid)
		)
		(fill yes)
		(layer "In2.Cu")
		(net "M_F_CPU0_SA_CS_N<2>")
	)
	(gr_poly
		(pts
			(xy 387.11378 -269.587726) (xy 387.06679 -269.435326) (xy 386.80517 -269.435326) (xy 386.75818 -269.587726)
			(xy 386.75818 -269.631922) (xy 387.11378 -269.631922)
		)
		(stroke
			(width 0)
			(type solid)
		)
		(fill yes)
		(layer "In2.Cu")
		(net "M_F_CPU0_SA_DQ<18>")
	)
	(gr_poly
		(pts
			(xy 387.11378 -265.924284) (xy 387.11378 -265.879834) (xy 386.75818 -265.879834) (xy 386.75818 -265.924284)
			(xy 386.80517 -266.076684) (xy 387.06679 -266.076684)
		)
		(stroke
			(width 0)
			(type solid)
		)
		(fill yes)
		(layer "In2.Cu")
		(net "M_F_CPU0_SA_DQ<21>")
	)
	(gr_poly
		(pts
			(xy 387.11378 -264.704322) (xy 387.06679 -264.551922) (xy 386.80517 -264.551922) (xy 386.75818 -264.704322)
			(xy 386.75818 -264.748772) (xy 387.11378 -264.748772)
		)
		(stroke
			(width 0)
			(type solid)
		)
		(fill yes)
		(layer "In2.Cu")
		(net "M_F_CPU0_SA_CB<2>")
	)
	(gr_poly
		(pts
			(xy 387.121908 -263.077198) (xy 387.074918 -262.924798) (xy 386.813298 -262.924798) (xy 386.766308 -263.077198)
			(xy 386.766308 -263.121648) (xy 387.121908 -263.121648)
		)
		(stroke
			(width 0)
			(type solid)
		)
		(fill yes)
		(layer "In2.Cu")
		(net "M_F_CPU0_SA_DQS_DN<4>")
	)
	(gr_poly
		(pts
			(xy 387.122162 -272.843498) (xy 387.075172 -272.691098) (xy 386.813552 -272.691098) (xy 386.766562 -272.843498)
			(xy 386.766562 -272.887948) (xy 387.122162 -272.887948)
		)
		(stroke
			(width 0)
			(type solid)
		)
		(fill yes)
		(layer "In2.Cu")
		(net "M_E_CPU0_SA_DQS_DN<1>")
	)
	(gr_poly
		(pts
			(xy 387.122162 -269.179294) (xy 387.122162 -269.134844) (xy 386.766562 -269.134844) (xy 386.766562 -269.179294)
			(xy 386.813552 -269.331694) (xy 387.075172 -269.331694)
		)
		(stroke
			(width 0)
			(type solid)
		)
		(fill yes)
		(layer "In2.Cu")
		(net "M_F_CPU0_SA_DQ<17>")
	)
	(gr_poly
		(pts
			(xy 387.122162 -267.960094) (xy 387.075172 -267.807694) (xy 386.813552 -267.807694) (xy 386.766562 -267.960094)
			(xy 386.766562 -268.004544) (xy 387.122162 -268.004544)
		)
		(stroke
			(width 0)
			(type solid)
		)
		(fill yes)
		(layer "In2.Cu")
		(net "M_F_CPU0_SA_DQS_DN<2>")
	)
	(gr_poly
		(pts
			(xy 387.122162 -267.551662) (xy 387.122162 -267.507212) (xy 386.766562 -267.507212) (xy 386.766562 -267.551662)
			(xy 386.813552 -267.704062) (xy 387.075172 -267.704062)
		)
		(stroke
			(width 0)
			(type solid)
		)
		(fill yes)
		(layer "In2.Cu")
		(net "M_F_CPU0_SA_DQS_DN<7>")
	)
	(gr_poly
		(pts
			(xy 387.122162 -266.332462) (xy 387.075172 -266.180062) (xy 386.813552 -266.180062) (xy 386.766562 -266.332462)
			(xy 386.766562 -266.376658) (xy 387.122162 -266.376658)
		)
		(stroke
			(width 0)
			(type solid)
		)
		(fill yes)
		(layer "In2.Cu")
		(net "M_F_CPU0_SA_DQ<22>")
	)
	(gr_poly
		(pts
			(xy 387.122162 -264.29589) (xy 387.122162 -264.251694) (xy 386.766562 -264.251694) (xy 386.766562 -264.29589)
			(xy 386.813552 -264.44829) (xy 387.075172 -264.44829)
		)
		(stroke
			(width 0)
			(type solid)
		)
		(fill yes)
		(layer "In2.Cu")
		(net "M_F_CPU0_SA_CB<1>")
	)
	(gr_poly
		(pts
			(xy 387.122162 -261.449058) (xy 387.075172 -261.296658) (xy 386.813552 -261.296658) (xy 386.766562 -261.449058)
			(xy 386.766562 -261.493508) (xy 387.122162 -261.493508)
		)
		(stroke
			(width 0)
			(type solid)
		)
		(fill yes)
		(layer "In2.Cu")
		(net "M_F_CPU0_SA_CB<6>")
	)
	(gr_poly
		(pts
			(xy 387.122162 -261.040626) (xy 387.122162 -260.996176) (xy 386.766562 -260.996176) (xy 386.766562 -261.040626)
			(xy 386.813552 -261.193026) (xy 387.075172 -261.193026)
		)
		(stroke
			(width 0)
			(type solid)
		)
		(fill yes)
		(layer "In2.Cu")
		(net "M_F_CPU0_SA_CB<5>")
	)
	(gr_poly
		(pts
			(xy 387.130798 -262.668258) (xy 387.130798 -262.624062) (xy 386.775198 -262.624062) (xy 386.775198 -262.668258)
			(xy 386.822188 -262.820658) (xy 387.083808 -262.820658)
		)
		(stroke
			(width 0)
			(type solid)
		)
		(fill yes)
		(layer "In2.Cu")
		(net "M_F_CPU0_SA_DQS_DN<9>")
	)
	(gr_poly
		(pts
			(xy 387.130798 -258.193286) (xy 387.083808 -258.040886) (xy 386.822188 -258.040886) (xy 386.775198 -258.193286)
			(xy 386.775198 -258.237482) (xy 387.130798 -258.237482)
		)
		(stroke
			(width 0)
			(type solid)
		)
		(fill yes)
		(layer "In2.Cu")
		(net "M_F_CPU0_SA_CA<0>")
	)
	(gr_poly
		(pts
			(xy 387.130798 -257.784854) (xy 387.130798 -257.740658) (xy 386.775198 -257.740658) (xy 386.775198 -257.784854)
			(xy 386.822188 -257.937254) (xy 387.083808 -257.937254)
		)
		(stroke
			(width 0)
			(type solid)
		)
		(fill yes)
		(layer "In2.Cu")
		(net "M_F_CPU0_SA_CA<1>")
	)
	(gr_poly
		(pts
			(xy 387.378448 -225.572574) (xy 387.340094 -225.550476) (xy 387.184646 -225.514916) (xy 387.053836 -225.741484)
			(xy 387.162294 -225.858324) (xy 387.200648 -225.880422)
		)
		(stroke
			(width 0)
			(type solid)
		)
		(fill yes)
		(layer "In2.Cu")
		(net "M_F_CPU0_SB_DQ<15>")
	)
	(gr_poly
		(pts
			(xy 387.378448 -220.68917) (xy 387.340094 -220.667072) (xy 387.184646 -220.631512) (xy 387.053836 -220.85808)
			(xy 387.162294 -220.97492) (xy 387.200648 -220.997018)
		)
		(stroke
			(width 0)
			(type solid)
		)
		(fill yes)
		(layer "In2.Cu")
		(net "M_F_CPU0_SB_DQ<22>")
	)
	(gr_poly
		(pts
			(xy 387.473698 -219.301822) (xy 387.473698 -219.257626) (xy 387.118098 -219.257626) (xy 387.118098 -219.301822)
			(xy 387.165088 -219.454222) (xy 387.426708 -219.454222)
		)
		(stroke
			(width 0)
			(type solid)
		)
		(fill yes)
		(layer "In2.Cu")
		(net "M_F_CPU0_SB_DQ<23>")
	)
	(gr_poly
		(pts
			(xy 387.482334 -230.696262) (xy 387.482334 -230.651812) (xy 387.126734 -230.651812) (xy 387.126734 -230.696262)
			(xy 387.173724 -230.848662) (xy 387.435344 -230.848662)
		)
		(stroke
			(width 0)
			(type solid)
		)
		(fill yes)
		(layer "In2.Cu")
		(net "M_F_CPU0_SB_DQ<9>")
	)
	(gr_poly
		(pts
			(xy 387.482334 -229.06863) (xy 387.482334 -229.02418) (xy 387.126734 -229.02418) (xy 387.126734 -229.06863)
			(xy 387.173724 -229.22103) (xy 387.435344 -229.22103)
		)
		(stroke
			(width 0)
			(type solid)
		)
		(fill yes)
		(layer "In2.Cu")
		(net "M_F_CPU0_SB_DQS_DN<6>")
	)
	(gr_poly
		(pts
			(xy 387.482334 -224.593658) (xy 387.435344 -224.441258) (xy 387.173724 -224.441258) (xy 387.126734 -224.593658)
			(xy 387.126734 -224.638108) (xy 387.482334 -224.638108)
		)
		(stroke
			(width 0)
			(type solid)
		)
		(fill yes)
		(layer "In2.Cu")
		(net "M_F_CPU0_SB_DQ<18>")
	)
	(gr_poly
		(pts
			(xy 387.482334 -224.185226) (xy 387.482334 -224.140776) (xy 387.126734 -224.140776) (xy 387.126734 -224.185226)
			(xy 387.173724 -224.337626) (xy 387.435344 -224.337626)
		)
		(stroke
			(width 0)
			(type solid)
		)
		(fill yes)
		(layer "In2.Cu")
		(net "M_F_CPU0_SB_DQ<17>")
	)
	(gr_poly
		(pts
			(xy 387.557264 -226.289108) (xy 387.448806 -226.172268) (xy 387.410452 -226.15017) (xy 387.232652 -226.458018)
			(xy 387.271006 -226.480116) (xy 387.426454 -226.515676)
		)
		(stroke
			(width 0)
			(type solid)
		)
		(fill yes)
		(layer "In2.Cu")
		(net "M_F_CPU0_SB_DQ<13>")
	)
	(gr_poly
		(pts
			(xy 387.557264 -221.405704) (xy 387.448806 -221.288864) (xy 387.410452 -221.266766) (xy 387.232652 -221.574614)
			(xy 387.271006 -221.596712) (xy 387.426454 -221.632272)
		)
		(stroke
			(width 0)
			(type solid)
		)
		(fill yes)
		(layer "In2.Cu")
		(net "M_F_CPU0_SB_DQ<20>")
	)
	(gr_poly
		(pts
			(xy 387.58368 -262.262874) (xy 387.53669 -262.110474) (xy 387.27507 -262.110474) (xy 387.22808 -262.262874)
			(xy 387.22808 -262.30707) (xy 387.58368 -262.30707)
		)
		(stroke
			(width 0)
			(type solid)
		)
		(fill yes)
		(layer "In2.Cu")
		(net "M_F_CPU0_SA_DQS_DP<9>")
	)
	(gr_poly
		(pts
			(xy 387.58368 -258.599178) (xy 387.58368 -258.554728) (xy 387.22808 -258.554728) (xy 387.22808 -258.599178)
			(xy 387.27507 -258.751578) (xy 387.53669 -258.751578)
		)
		(stroke
			(width 0)
			(type solid)
		)
		(fill yes)
		(layer "In2.Cu")
		(net "M_F_CPU0_SA_CS_N<1>")
	)
	(gr_poly
		(pts
			(xy 387.592062 -268.77391) (xy 387.545072 -268.62151) (xy 387.283452 -268.62151) (xy 387.236462 -268.77391)
			(xy 387.236462 -268.81836) (xy 387.592062 -268.81836)
		)
		(stroke
			(width 0)
			(type solid)
		)
		(fill yes)
		(layer "In2.Cu")
		(net "M_F_CPU0_SA_DQ<19>")
	)
	(gr_poly
		(pts
			(xy 387.592062 -268.365478) (xy 387.592062 -268.321028) (xy 387.236462 -268.321028) (xy 387.236462 -268.365478)
			(xy 387.283452 -268.517878) (xy 387.545072 -268.517878)
		)
		(stroke
			(width 0)
			(type solid)
		)
		(fill yes)
		(layer "In2.Cu")
		(net "M_F_CPU0_SA_DQS_DP<2>")
	)
	(gr_poly
		(pts
			(xy 387.592062 -267.146278) (xy 387.545072 -266.993878) (xy 387.283452 -266.993878) (xy 387.236462 -267.146278)
			(xy 387.236462 -267.190474) (xy 387.592062 -267.190474)
		)
		(stroke
			(width 0)
			(type solid)
		)
		(fill yes)
		(layer "In2.Cu")
		(net "M_F_CPU0_SA_DQS_DP<7>")
	)
	(gr_poly
		(pts
			(xy 387.592062 -266.737846) (xy 387.592062 -266.693396) (xy 387.236462 -266.693396) (xy 387.236462 -266.737846)
			(xy 387.283452 -266.890246) (xy 387.545072 -266.890246)
		)
		(stroke
			(width 0)
			(type solid)
		)
		(fill yes)
		(layer "In2.Cu")
		(net "M_F_CPU0_SA_DQ<20>")
	)
	(gr_poly
		(pts
			(xy 387.592062 -263.891014) (xy 387.545072 -263.738614) (xy 387.283452 -263.738614) (xy 387.236462 -263.891014)
			(xy 387.236462 -263.93521) (xy 387.592062 -263.93521)
		)
		(stroke
			(width 0)
			(type solid)
		)
		(fill yes)
		(layer "In2.Cu")
		(net "M_F_CPU0_SA_CB<3>")
	)
	(gr_poly
		(pts
			(xy 387.592062 -261.854442) (xy 387.592062 -261.809992) (xy 387.236462 -261.809992) (xy 387.236462 -261.854442)
			(xy 387.283452 -262.006842) (xy 387.545072 -262.006842)
		)
		(stroke
			(width 0)
			(type solid)
		)
		(fill yes)
		(layer "In2.Cu")
		(net "M_F_CPU0_SA_CB<4>")
	)
	(gr_poly
		(pts
			(xy 387.600444 -260.22681) (xy 387.600444 -260.18236) (xy 387.244844 -260.18236) (xy 387.244844 -260.22681)
			(xy 387.291834 -260.37921) (xy 387.553454 -260.37921)
		)
		(stroke
			(width 0)
			(type solid)
		)
		(fill yes)
		(layer "In2.Cu")
		(net "M_F_CPU0_ALERT_N")
	)
	(gr_poly
		(pts
			(xy 387.600698 -265.518392) (xy 387.553708 -265.365992) (xy 387.292088 -265.365992) (xy 387.245098 -265.518392)
			(xy 387.245098 -265.562588) (xy 387.600698 -265.562588)
		)
		(stroke
			(width 0)
			(type solid)
		)
		(fill yes)
		(layer "In2.Cu")
		(net "M_F_CPU0_SA_DQ<23>")
	)
	(gr_poly
		(pts
			(xy 387.600698 -265.110214) (xy 387.600698 -265.065764) (xy 387.245098 -265.065764) (xy 387.245098 -265.110214)
			(xy 387.292088 -265.262614) (xy 387.553708 -265.262614)
		)
		(stroke
			(width 0)
			(type solid)
		)
		(fill yes)
		(layer "In2.Cu")
		(net "M_F_CPU0_SA_CB<0>")
	)
	(gr_poly
		(pts
			(xy 387.952234 -225.407474) (xy 387.905244 -225.255074) (xy 387.643624 -225.255074) (xy 387.596634 -225.407474)
			(xy 387.596634 -225.451924) (xy 387.952234 -225.451924)
		)
		(stroke
			(width 0)
			(type solid)
		)
		(fill yes)
		(layer "In2.Cu")
		(net "M_F_CPU0_SB_DQ<15>")
	)
	(gr_poly
		(pts
			(xy 387.952234 -224.999042) (xy 387.952234 -224.954592) (xy 387.596634 -224.954592) (xy 387.596634 -224.999042)
			(xy 387.643624 -225.151442) (xy 387.905244 -225.151442)
		)
		(stroke
			(width 0)
			(type solid)
		)
		(fill yes)
		(layer "In2.Cu")
		(net "M_F_CPU0_SB_DQ<16>")
	)
	(gr_poly
		(pts
			(xy 387.952234 -223.779842) (xy 387.905244 -223.627442) (xy 387.643624 -223.627442) (xy 387.596634 -223.779842)
			(xy 387.596634 -223.824292) (xy 387.952234 -223.824292)
		)
		(stroke
			(width 0)
			(type solid)
		)
		(fill yes)
		(layer "In2.Cu")
		(net "M_F_CPU0_SB_DQ<19>")
	)
	(gr_poly
		(pts
			(xy 387.952234 -220.52407) (xy 387.905244 -220.37167) (xy 387.643624 -220.37167) (xy 387.596634 -220.52407)
			(xy 387.596634 -220.56852) (xy 387.952234 -220.56852)
		)
		(stroke
			(width 0)
			(type solid)
		)
		(fill yes)
		(layer "In2.Cu")
		(net "M_F_CPU0_SB_DQ<22>")
	)
	(gr_poly
		(pts
			(xy 388.422134 -224.185226) (xy 388.422134 -224.140776) (xy 388.066534 -224.140776) (xy 388.066534 -224.185226)
			(xy 388.113524 -224.337626) (xy 388.375144 -224.337626)
		)
		(stroke
			(width 0)
			(type solid)
		)
		(fill yes)
		(layer "In2.Cu")
		(net "M_F_CPU0_SB_DQ<17>")
	)
	(gr_poly
		(pts
			(xy 388.422134 -220.929454) (xy 388.422134 -220.885258) (xy 388.066534 -220.885258) (xy 388.066534 -220.929454)
			(xy 388.113524 -221.081854) (xy 388.375144 -221.081854)
		)
		(stroke
			(width 0)
			(type solid)
		)
		(fill yes)
		(layer "In2.Cu")
		(net "M_F_CPU0_SB_DQ<20>")
	)
	(gr_poly
		(pts
			(xy 388.964932 -220.595698) (xy 388.856474 -220.478858) (xy 388.81812 -220.45676) (xy 388.64032 -220.764608)
			(xy 388.678674 -220.786706) (xy 388.834122 -220.822266)
		)
		(stroke
			(width 0)
			(type solid)
		)
		(fill yes)
		(layer "In2.Cu")
		(net "M_F_CPU0_SB_DQ<20>")
	)
	(gr_poly
		(pts
			(xy 388.966964 -223.847406) (xy 388.858506 -223.730566) (xy 388.820152 -223.708468) (xy 388.642352 -224.016316)
			(xy 388.680706 -224.038414) (xy 388.836154 -224.073974)
		)
		(stroke
			(width 0)
			(type solid)
		)
		(fill yes)
		(layer "In2.Cu")
		(net "M_F_CPU0_SB_DQ<17>")
	)
	(gr_poly
		(pts
			(xy 29.542486 -166.656004) (xy 29.542486 -162.998404) (xy 29.491686 -162.947604) (xy 25.834086 -162.947604)
			(xy 25.783286 -162.998404) (xy 25.783286 -166.656004) (xy 25.834086 -166.706804) (xy 29.491686 -166.706804)
		)
		(stroke
			(width 0)
			(type solid)
		)
		(fill yes)
		(layer "In2.Cu")
		(net "GND")
	)
	(gr_poly
		(pts
			(xy 33.94075 -131.462272) (xy 33.94075 -127.804672) (xy 33.88995 -127.753872) (xy 30.23235 -127.753872)
			(xy 30.18155 -127.804672) (xy 30.18155 -131.462272) (xy 30.23235 -131.513072) (xy 33.88995 -131.513072)
		)
		(stroke
			(width 0)
			(type solid)
		)
		(fill yes)
		(layer "In2.Cu")
		(net "GND")
	)
	(gr_poly
		(pts
			(xy 217.33256 -26.947368) (xy 217.33256 -25.212548) (xy 216.7382 -24.618188) (xy 213.22538 -24.618188)
			(xy 213.03488 -24.808688) (xy 213.03488 -27.396948) (xy 213.26856 -27.630628) (xy 216.6493 -27.630628)
		)
		(stroke
			(width 0)
			(type solid)
		)
		(fill yes)
		(layer "In2.Cu")
		(net "GND")
	)
	(gr_poly
		(pts
			(xy 249.511312 -89.374472) (xy 249.511312 -86.478872) (xy 249.333512 -86.301072) (xy 245.904512 -86.301072)
			(xy 245.752112 -86.453472) (xy 245.752112 -89.653872) (xy 245.929912 -89.831672) (xy 249.054112 -89.831672)
		)
		(stroke
			(width 0)
			(type solid)
		)
		(fill yes)
		(layer "In2.Cu")
		(net "GND")
	)
	(gr_poly
		(pts
			(xy 326.70242 -32.253428) (xy 326.70242 -31.360872) (xy 323.875908 -28.53436) (xy 323.57822 -28.53436)
			(xy 321.00901 -31.10357) (xy 321.00901 -31.812484) (xy 323.807074 -34.610548) (xy 324.3453 -34.610548)
		)
		(stroke
			(width 0)
			(type solid)
		)
		(fill yes)
		(layer "In2.Cu")
		(net "GND")
	)
	(gr_poly
		(pts
			(xy 337.936586 -70.187058) (xy 337.936586 -67.25412) (xy 337.568032 -66.885566) (xy 333.806038 -66.885566)
			(xy 333.422244 -67.26936) (xy 333.422244 -70.586092) (xy 333.54518 -70.709028) (xy 337.414616 -70.709028)
		)
		(stroke
			(width 0)
			(type solid)
		)
		(fill yes)
		(layer "In2.Cu")
		(net "GND")
	)
	(gr_poly
		(pts
			(xy 427.559216 -138.21791) (xy 427.559216 -134.61111) (xy 427.508416 -134.56031) (xy 423.901616 -134.56031)
			(xy 423.850816 -134.61111) (xy 423.850816 -138.21791) (xy 423.901616 -138.26871) (xy 427.508416 -138.26871)
		)
		(stroke
			(width 0)
			(type solid)
		)
		(fill yes)
		(layer "In2.Cu")
		(net "GND")
	)
	(gr_poly
		(pts
			(xy 113.42116 -417.032948) (xy 113.42116 -415.633408) (xy 113.05794 -415.270188) (xy 110.32744 -415.270188)
			(xy 109.91088 -414.853628) (xy 109.91088 -412.913068) (xy 109.76864 -412.770828) (xy 109.23778 -412.770828)
			(xy 108.86186 -413.146748) (xy 108.86186 -416.230308) (xy 109.9439 -417.312348) (xy 113.14176 -417.312348)
		)
		(stroke
			(width 0)
			(type solid)
		)
		(fill yes)
		(layer "In2.Cu")
		(net "P3V3_9ZXL045_VDD")
	)
	(gr_poly
		(pts
			(xy 230.38054 -434.93182) (xy 230.38054 -430.57826) (xy 230.42626 -430.53254) (xy 230.42626 -423.30116)
			(xy 233.09326 -420.63416) (xy 270.3576 -420.63416) (xy 275.54936 -415.4424) (xy 279.79624 -415.4424)
			(xy 280.19756 -415.04108) (xy 280.19756 -408.29992) (xy 279.96896 -408.07132) (xy 239.84458 -408.07132)
			(xy 233.0704 -414.8455) (xy 207.34528 -414.8455) (xy 206.49184 -415.69894) (xy 206.49184 -435.39156)
			(xy 207.63484 -436.53456) (xy 228.7778 -436.53456)
		)
		(stroke
			(width 0)
			(type solid)
		)
		(fill yes)
		(layer "In2.Cu")
		(net "P12V_PSU")
	)
	(gr_poly
		(pts
			(arc
				(start 413.048958 -321.758564)
				(mid 412.821374 -321.758564)
				(end 413.048958 -321.758564)
			)
		)
		(stroke
			(width 0)
			(type solid)
		)
		(fill yes)
		(layer "In2.Cu")
		(net "GND")
	)
	(gr_poly
		(pts
			(arc
				(start 291.77488 -127.345948)
				(mid 291.52088 -127.345948)
				(end 291.77488 -127.345948)
			)
		)
		(stroke
			(width 0)
			(type solid)
		)
		(fill yes)
		(layer "In2.Cu")
		(net "GND")
	)
	(gr_poly
		(pts
			(arc
				(start 297.99788 -134.076948)
				(mid 297.74388 -134.076948)
				(end 297.99788 -134.076948)
			)
		)
		(stroke
			(width 0)
			(type solid)
		)
		(fill yes)
		(layer "In2.Cu")
		(net "GND")
	)
	(gr_poly
		(pts
			(arc
				(start 150.250652 -39.515288)
				(mid 150.54834 -39.354795)
				(end 150.846028 -39.515288)
			)
			(xy 151.5364 -39.515288) (xy 151.706072 -39.345616) (xy 151.706072 -35.75304) (xy 151.46528 -35.512248)
			(xy 149.055582 -35.512248)
			(arc
				(start 149.04212 -35.541966)
				(mid 149.013965 -35.591636)
				(end 148.97735 -35.635438)
			)
			(xy 148.7043 -35.908488) (xy 148.7043 -39.187628) (xy 149.03196 -39.515288)
		)
		(stroke
			(width 0)
			(type solid)
		)
		(fill yes)
		(layer "In2.Cu")
		(net "GND")
	)
	(gr_poly
		(pts
			(arc
				(start 19.429476 -397.477996)
				(mid 19.1389 -397.477996)
				(end 19.429476 -397.477996)
			)
		)
		(stroke
			(width 0)
			(type solid)
		)
		(fill yes)
		(layer "In2.Cu")
		(net "GND")
	)
	(gr_poly
		(pts
			(arc
				(start 19.429476 -395.344396)
				(mid 19.1389 -395.344396)
				(end 19.429476 -395.344396)
			)
		)
		(stroke
			(width 0)
			(type solid)
		)
		(fill yes)
		(layer "In2.Cu")
		(net "GND")
	)
	(gr_poly
		(pts
			(arc
				(start 25.473152 -398.241012)
				(mid 25.182576 -398.241012)
				(end 25.473152 -398.241012)
			)
		)
		(stroke
			(width 0)
			(type solid)
		)
		(fill yes)
		(layer "In2.Cu")
		(net "GND")
	)
	(gr_poly
		(pts
			(arc
				(start 25.481788 -396.107412)
				(mid 25.191212 -396.107412)
				(end 25.481788 -396.107412)
			)
		)
		(stroke
			(width 0)
			(type solid)
		)
		(fill yes)
		(layer "In2.Cu")
		(net "GND")
	)
	(gr_poly
		(pts
			(arc
				(start 59.39282 -438.651396)
				(mid 59.107324 -438.651396)
				(end 59.39282 -438.651396)
			)
		)
		(stroke
			(width 0)
			(type solid)
		)
		(fill yes)
		(layer "In2.Cu")
		(net "GND")
	)
	(gr_poly
		(pts
			(arc
				(start 59.39282 -437.49976)
				(mid 59.107324 -437.49976)
				(end 59.39282 -437.49976)
			)
		)
		(stroke
			(width 0)
			(type solid)
		)
		(fill yes)
		(layer "In2.Cu")
		(net "GND")
	)
	(gr_poly
		(pts
			(arc
				(start 59.39282 -436.347362)
				(mid 59.107324 -436.347362)
				(end 59.39282 -436.347362)
			)
		)
		(stroke
			(width 0)
			(type solid)
		)
		(fill yes)
		(layer "In2.Cu")
		(net "GND")
	)
	(gr_poly
		(pts
			(arc
				(start 59.39282 -435.0512)
				(mid 59.107324 -435.0512)
				(end 59.39282 -435.0512)
			)
		)
		(stroke
			(width 0)
			(type solid)
		)
		(fill yes)
		(layer "In2.Cu")
		(net "GND")
	)
	(gr_poly
		(pts
			(arc
				(start 59.39282 -433.899564)
				(mid 59.107324 -433.899564)
				(end 59.39282 -433.899564)
			)
		)
		(stroke
			(width 0)
			(type solid)
		)
		(fill yes)
		(layer "In2.Cu")
		(net "GND")
	)
	(gr_poly
		(pts
			(arc
				(start 59.39282 -432.747166)
				(mid 59.107324 -432.747166)
				(end 59.39282 -432.747166)
			)
		)
		(stroke
			(width 0)
			(type solid)
		)
		(fill yes)
		(layer "In2.Cu")
		(net "GND")
	)
	(gr_poly
		(pts
			(arc
				(start 59.39282 -431.451258)
				(mid 59.107324 -431.451258)
				(end 59.39282 -431.451258)
			)
		)
		(stroke
			(width 0)
			(type solid)
		)
		(fill yes)
		(layer "In2.Cu")
		(net "GND")
	)
	(gr_poly
		(pts
			(arc
				(start 59.39282 -430.299622)
				(mid 59.107324 -430.299622)
				(end 59.39282 -430.299622)
			)
		)
		(stroke
			(width 0)
			(type solid)
		)
		(fill yes)
		(layer "In2.Cu")
		(net "GND")
	)
	(gr_poly
		(pts
			(arc
				(start 59.39282 -429.147224)
				(mid 59.107324 -429.147224)
				(end 59.39282 -429.147224)
			)
		)
		(stroke
			(width 0)
			(type solid)
		)
		(fill yes)
		(layer "In2.Cu")
		(net "GND")
	)
	(gr_poly
		(pts
			(arc
				(start 59.39282 -427.851316)
				(mid 59.107324 -427.851316)
				(end 59.39282 -427.851316)
			)
		)
		(stroke
			(width 0)
			(type solid)
		)
		(fill yes)
		(layer "In2.Cu")
		(net "GND")
	)
	(gr_poly
		(pts
			(arc
				(start 59.39282 -426.69968)
				(mid 59.107324 -426.69968)
				(end 59.39282 -426.69968)
			)
		)
		(stroke
			(width 0)
			(type solid)
		)
		(fill yes)
		(layer "In2.Cu")
		(net "GND")
	)
	(gr_poly
		(pts
			(arc
				(start 59.39282 -425.547282)
				(mid 59.107324 -425.547282)
				(end 59.39282 -425.547282)
			)
		)
		(stroke
			(width 0)
			(type solid)
		)
		(fill yes)
		(layer "In2.Cu")
		(net "GND")
	)
	(gr_poly
		(pts
			(arc
				(start 61.392816 -439.651394)
				(mid 61.10732 -439.651394)
				(end 61.392816 -439.651394)
			)
		)
		(stroke
			(width 0)
			(type solid)
		)
		(fill yes)
		(layer "In2.Cu")
		(net "GND")
	)
	(gr_poly
		(pts
			(arc
				(start 61.392816 -438.499758)
				(mid 61.10732 -438.499758)
				(end 61.392816 -438.499758)
			)
		)
		(stroke
			(width 0)
			(type solid)
		)
		(fill yes)
		(layer "In2.Cu")
		(net "GND")
	)
	(gr_poly
		(pts
			(arc
				(start 61.392816 -437.34736)
				(mid 61.10732 -437.34736)
				(end 61.392816 -437.34736)
			)
		)
		(stroke
			(width 0)
			(type solid)
		)
		(fill yes)
		(layer "In2.Cu")
		(net "GND")
	)
	(gr_poly
		(pts
			(arc
				(start 61.392816 -436.051198)
				(mid 61.10732 -436.051198)
				(end 61.392816 -436.051198)
			)
		)
		(stroke
			(width 0)
			(type solid)
		)
		(fill yes)
		(layer "In2.Cu")
		(net "GND")
	)
	(gr_poly
		(pts
			(arc
				(start 61.392816 -434.899562)
				(mid 61.10732 -434.899562)
				(end 61.392816 -434.899562)
			)
		)
		(stroke
			(width 0)
			(type solid)
		)
		(fill yes)
		(layer "In2.Cu")
		(net "GND")
	)
	(gr_poly
		(pts
			(arc
				(start 61.392816 -433.747164)
				(mid 61.10732 -433.747164)
				(end 61.392816 -433.747164)
			)
		)
		(stroke
			(width 0)
			(type solid)
		)
		(fill yes)
		(layer "In2.Cu")
		(net "GND")
	)
	(gr_poly
		(pts
			(arc
				(start 61.392816 -432.451256)
				(mid 61.10732 -432.451256)
				(end 61.392816 -432.451256)
			)
		)
		(stroke
			(width 0)
			(type solid)
		)
		(fill yes)
		(layer "In2.Cu")
		(net "GND")
	)
	(gr_poly
		(pts
			(arc
				(start 61.392816 -431.29962)
				(mid 61.10732 -431.29962)
				(end 61.392816 -431.29962)
			)
		)
		(stroke
			(width 0)
			(type solid)
		)
		(fill yes)
		(layer "In2.Cu")
		(net "GND")
	)
	(gr_poly
		(pts
			(arc
				(start 61.392816 -430.147222)
				(mid 61.10732 -430.147222)
				(end 61.392816 -430.147222)
			)
		)
		(stroke
			(width 0)
			(type solid)
		)
		(fill yes)
		(layer "In2.Cu")
		(net "GND")
	)
	(gr_poly
		(pts
			(arc
				(start 61.392816 -428.851314)
				(mid 61.10732 -428.851314)
				(end 61.392816 -428.851314)
			)
		)
		(stroke
			(width 0)
			(type solid)
		)
		(fill yes)
		(layer "In2.Cu")
		(net "GND")
	)
	(gr_poly
		(pts
			(arc
				(start 61.392816 -427.699678)
				(mid 61.10732 -427.699678)
				(end 61.392816 -427.699678)
			)
		)
		(stroke
			(width 0)
			(type solid)
		)
		(fill yes)
		(layer "In2.Cu")
		(net "GND")
	)
	(gr_poly
		(pts
			(arc
				(start 61.392816 -426.54728)
				(mid 61.10732 -426.54728)
				(end 61.392816 -426.54728)
			)
		)
		(stroke
			(width 0)
			(type solid)
		)
		(fill yes)
		(layer "In2.Cu")
		(net "GND")
	)
	(gr_poly
		(pts
			(arc
				(start 63.392812 -438.651396)
				(mid 63.107316 -438.651396)
				(end 63.392812 -438.651396)
			)
		)
		(stroke
			(width 0)
			(type solid)
		)
		(fill yes)
		(layer "In2.Cu")
		(net "GND")
	)
	(gr_poly
		(pts
			(arc
				(start 63.392812 -437.49976)
				(mid 63.107316 -437.49976)
				(end 63.392812 -437.49976)
			)
		)
		(stroke
			(width 0)
			(type solid)
		)
		(fill yes)
		(layer "In2.Cu")
		(net "GND")
	)
	(gr_poly
		(pts
			(arc
				(start 63.392812 -436.347362)
				(mid 63.107316 -436.347362)
				(end 63.392812 -436.347362)
			)
		)
		(stroke
			(width 0)
			(type solid)
		)
		(fill yes)
		(layer "In2.Cu")
		(net "GND")
	)
	(gr_poly
		(pts
			(arc
				(start 63.392812 -435.0512)
				(mid 63.107316 -435.0512)
				(end 63.392812 -435.0512)
			)
		)
		(stroke
			(width 0)
			(type solid)
		)
		(fill yes)
		(layer "In2.Cu")
		(net "GND")
	)
	(gr_poly
		(pts
			(arc
				(start 63.392812 -433.899564)
				(mid 63.107316 -433.899564)
				(end 63.392812 -433.899564)
			)
		)
		(stroke
			(width 0)
			(type solid)
		)
		(fill yes)
		(layer "In2.Cu")
		(net "GND")
	)
	(gr_poly
		(pts
			(arc
				(start 63.392812 -432.747166)
				(mid 63.107316 -432.747166)
				(end 63.392812 -432.747166)
			)
		)
		(stroke
			(width 0)
			(type solid)
		)
		(fill yes)
		(layer "In2.Cu")
		(net "GND")
	)
	(gr_poly
		(pts
			(arc
				(start 63.392812 -431.451258)
				(mid 63.107316 -431.451258)
				(end 63.392812 -431.451258)
			)
		)
		(stroke
			(width 0)
			(type solid)
		)
		(fill yes)
		(layer "In2.Cu")
		(net "GND")
	)
	(gr_poly
		(pts
			(arc
				(start 63.392812 -430.299622)
				(mid 63.107316 -430.299622)
				(end 63.392812 -430.299622)
			)
		)
		(stroke
			(width 0)
			(type solid)
		)
		(fill yes)
		(layer "In2.Cu")
		(net "GND")
	)
	(gr_poly
		(pts
			(arc
				(start 63.392812 -429.147224)
				(mid 63.107316 -429.147224)
				(end 63.392812 -429.147224)
			)
		)
		(stroke
			(width 0)
			(type solid)
		)
		(fill yes)
		(layer "In2.Cu")
		(net "GND")
	)
	(gr_poly
		(pts
			(arc
				(start 63.392812 -427.851316)
				(mid 63.107316 -427.851316)
				(end 63.392812 -427.851316)
			)
		)
		(stroke
			(width 0)
			(type solid)
		)
		(fill yes)
		(layer "In2.Cu")
		(net "GND")
	)
	(gr_poly
		(pts
			(arc
				(start 63.392812 -426.69968)
				(mid 63.107316 -426.69968)
				(end 63.392812 -426.69968)
			)
		)
		(stroke
			(width 0)
			(type solid)
		)
		(fill yes)
		(layer "In2.Cu")
		(net "GND")
	)
	(gr_poly
		(pts
			(arc
				(start 63.392812 -425.547282)
				(mid 63.107316 -425.547282)
				(end 63.392812 -425.547282)
			)
		)
		(stroke
			(width 0)
			(type solid)
		)
		(fill yes)
		(layer "In2.Cu")
		(net "GND")
	)
	(gr_poly
		(pts
			(arc
				(start 65.392808 -439.651394)
				(mid 65.107312 -439.651394)
				(end 65.392808 -439.651394)
			)
		)
		(stroke
			(width 0)
			(type solid)
		)
		(fill yes)
		(layer "In2.Cu")
		(net "GND")
	)
	(gr_poly
		(pts
			(arc
				(start 65.392808 -438.499758)
				(mid 65.107312 -438.499758)
				(end 65.392808 -438.499758)
			)
		)
		(stroke
			(width 0)
			(type solid)
		)
		(fill yes)
		(layer "In2.Cu")
		(net "GND")
	)
	(gr_poly
		(pts
			(arc
				(start 65.392808 -437.34736)
				(mid 65.107312 -437.34736)
				(end 65.392808 -437.34736)
			)
		)
		(stroke
			(width 0)
			(type solid)
		)
		(fill yes)
		(layer "In2.Cu")
		(net "GND")
	)
	(gr_poly
		(pts
			(arc
				(start 65.392808 -436.051198)
				(mid 65.107312 -436.051198)
				(end 65.392808 -436.051198)
			)
		)
		(stroke
			(width 0)
			(type solid)
		)
		(fill yes)
		(layer "In2.Cu")
		(net "GND")
	)
	(gr_poly
		(pts
			(arc
				(start 65.392808 -434.899562)
				(mid 65.107312 -434.899562)
				(end 65.392808 -434.899562)
			)
		)
		(stroke
			(width 0)
			(type solid)
		)
		(fill yes)
		(layer "In2.Cu")
		(net "GND")
	)
	(gr_poly
		(pts
			(arc
				(start 65.392808 -433.747164)
				(mid 65.107312 -433.747164)
				(end 65.392808 -433.747164)
			)
		)
		(stroke
			(width 0)
			(type solid)
		)
		(fill yes)
		(layer "In2.Cu")
		(net "GND")
	)
	(gr_poly
		(pts
			(arc
				(start 65.392808 -432.451256)
				(mid 65.107312 -432.451256)
				(end 65.392808 -432.451256)
			)
		)
		(stroke
			(width 0)
			(type solid)
		)
		(fill yes)
		(layer "In2.Cu")
		(net "GND")
	)
	(gr_poly
		(pts
			(arc
				(start 65.392808 -431.29962)
				(mid 65.107312 -431.29962)
				(end 65.392808 -431.29962)
			)
		)
		(stroke
			(width 0)
			(type solid)
		)
		(fill yes)
		(layer "In2.Cu")
		(net "GND")
	)
	(gr_poly
		(pts
			(arc
				(start 65.392808 -430.147222)
				(mid 65.107312 -430.147222)
				(end 65.392808 -430.147222)
			)
		)
		(stroke
			(width 0)
			(type solid)
		)
		(fill yes)
		(layer "In2.Cu")
		(net "GND")
	)
	(gr_poly
		(pts
			(arc
				(start 65.392808 -428.851314)
				(mid 65.107312 -428.851314)
				(end 65.392808 -428.851314)
			)
		)
		(stroke
			(width 0)
			(type solid)
		)
		(fill yes)
		(layer "In2.Cu")
		(net "GND")
	)
	(gr_poly
		(pts
			(arc
				(start 65.392808 -427.699678)
				(mid 65.107312 -427.699678)
				(end 65.392808 -427.699678)
			)
		)
		(stroke
			(width 0)
			(type solid)
		)
		(fill yes)
		(layer "In2.Cu")
		(net "GND")
	)
	(gr_poly
		(pts
			(arc
				(start 65.392808 -426.54728)
				(mid 65.107312 -426.54728)
				(end 65.392808 -426.54728)
			)
		)
		(stroke
			(width 0)
			(type solid)
		)
		(fill yes)
		(layer "In2.Cu")
		(net "GND")
	)
	(gr_poly
		(pts
			(arc
				(start 67.392804 -438.651396)
				(mid 67.107308 -438.651396)
				(end 67.392804 -438.651396)
			)
		)
		(stroke
			(width 0)
			(type solid)
		)
		(fill yes)
		(layer "In2.Cu")
		(net "GND")
	)
	(gr_poly
		(pts
			(arc
				(start 67.392804 -437.49976)
				(mid 67.107308 -437.49976)
				(end 67.392804 -437.49976)
			)
		)
		(stroke
			(width 0)
			(type solid)
		)
		(fill yes)
		(layer "In2.Cu")
		(net "GND")
	)
	(gr_poly
		(pts
			(arc
				(start 67.392804 -436.347362)
				(mid 67.107308 -436.347362)
				(end 67.392804 -436.347362)
			)
		)
		(stroke
			(width 0)
			(type solid)
		)
		(fill yes)
		(layer "In2.Cu")
		(net "GND")
	)
	(gr_poly
		(pts
			(arc
				(start 67.392804 -435.0512)
				(mid 67.107308 -435.0512)
				(end 67.392804 -435.0512)
			)
		)
		(stroke
			(width 0)
			(type solid)
		)
		(fill yes)
		(layer "In2.Cu")
		(net "GND")
	)
	(gr_poly
		(pts
			(arc
				(start 67.392804 -433.899564)
				(mid 67.107308 -433.899564)
				(end 67.392804 -433.899564)
			)
		)
		(stroke
			(width 0)
			(type solid)
		)
		(fill yes)
		(layer "In2.Cu")
		(net "GND")
	)
	(gr_poly
		(pts
			(arc
				(start 67.392804 -432.747166)
				(mid 67.107308 -432.747166)
				(end 67.392804 -432.747166)
			)
		)
		(stroke
			(width 0)
			(type solid)
		)
		(fill yes)
		(layer "In2.Cu")
		(net "GND")
	)
	(gr_poly
		(pts
			(arc
				(start 67.392804 -431.451258)
				(mid 67.107308 -431.451258)
				(end 67.392804 -431.451258)
			)
		)
		(stroke
			(width 0)
			(type solid)
		)
		(fill yes)
		(layer "In2.Cu")
		(net "GND")
	)
	(gr_poly
		(pts
			(arc
				(start 67.392804 -430.299622)
				(mid 67.107308 -430.299622)
				(end 67.392804 -430.299622)
			)
		)
		(stroke
			(width 0)
			(type solid)
		)
		(fill yes)
		(layer "In2.Cu")
		(net "GND")
	)
	(gr_poly
		(pts
			(arc
				(start 67.392804 -429.147224)
				(mid 67.107308 -429.147224)
				(end 67.392804 -429.147224)
			)
		)
		(stroke
			(width 0)
			(type solid)
		)
		(fill yes)
		(layer "In2.Cu")
		(net "GND")
	)
	(gr_poly
		(pts
			(arc
				(start 67.392804 -427.851316)
				(mid 67.107308 -427.851316)
				(end 67.392804 -427.851316)
			)
		)
		(stroke
			(width 0)
			(type solid)
		)
		(fill yes)
		(layer "In2.Cu")
		(net "GND")
	)
	(gr_poly
		(pts
			(arc
				(start 67.392804 -426.69968)
				(mid 67.107308 -426.69968)
				(end 67.392804 -426.69968)
			)
		)
		(stroke
			(width 0)
			(type solid)
		)
		(fill yes)
		(layer "In2.Cu")
		(net "GND")
	)
	(gr_poly
		(pts
			(arc
				(start 67.392804 -425.547282)
				(mid 67.107308 -425.547282)
				(end 67.392804 -425.547282)
			)
		)
		(stroke
			(width 0)
			(type solid)
		)
		(fill yes)
		(layer "In2.Cu")
		(net "GND")
	)
	(gr_poly
		(pts
			(arc
				(start 69.3928 -439.651394)
				(mid 69.107304 -439.651394)
				(end 69.3928 -439.651394)
			)
		)
		(stroke
			(width 0)
			(type solid)
		)
		(fill yes)
		(layer "In2.Cu")
		(net "GND")
	)
	(gr_poly
		(pts
			(arc
				(start 69.3928 -438.499758)
				(mid 69.107304 -438.499758)
				(end 69.3928 -438.499758)
			)
		)
		(stroke
			(width 0)
			(type solid)
		)
		(fill yes)
		(layer "In2.Cu")
		(net "GND")
	)
	(gr_poly
		(pts
			(arc
				(start 69.3928 -437.34736)
				(mid 69.107304 -437.34736)
				(end 69.3928 -437.34736)
			)
		)
		(stroke
			(width 0)
			(type solid)
		)
		(fill yes)
		(layer "In2.Cu")
		(net "GND")
	)
	(gr_poly
		(pts
			(arc
				(start 69.3928 -436.051198)
				(mid 69.107304 -436.051198)
				(end 69.3928 -436.051198)
			)
		)
		(stroke
			(width 0)
			(type solid)
		)
		(fill yes)
		(layer "In2.Cu")
		(net "GND")
	)
	(gr_poly
		(pts
			(arc
				(start 69.3928 -434.899562)
				(mid 69.107304 -434.899562)
				(end 69.3928 -434.899562)
			)
		)
		(stroke
			(width 0)
			(type solid)
		)
		(fill yes)
		(layer "In2.Cu")
		(net "GND")
	)
	(gr_poly
		(pts
			(arc
				(start 69.3928 -433.747164)
				(mid 69.107304 -433.747164)
				(end 69.3928 -433.747164)
			)
		)
		(stroke
			(width 0)
			(type solid)
		)
		(fill yes)
		(layer "In2.Cu")
		(net "GND")
	)
	(gr_poly
		(pts
			(arc
				(start 69.3928 -432.451256)
				(mid 69.107304 -432.451256)
				(end 69.3928 -432.451256)
			)
		)
		(stroke
			(width 0)
			(type solid)
		)
		(fill yes)
		(layer "In2.Cu")
		(net "GND")
	)
	(gr_poly
		(pts
			(arc
				(start 69.3928 -431.29962)
				(mid 69.107304 -431.29962)
				(end 69.3928 -431.29962)
			)
		)
		(stroke
			(width 0)
			(type solid)
		)
		(fill yes)
		(layer "In2.Cu")
		(net "GND")
	)
	(gr_poly
		(pts
			(arc
				(start 69.3928 -430.147222)
				(mid 69.107304 -430.147222)
				(end 69.3928 -430.147222)
			)
		)
		(stroke
			(width 0)
			(type solid)
		)
		(fill yes)
		(layer "In2.Cu")
		(net "GND")
	)
	(gr_poly
		(pts
			(arc
				(start 69.3928 -428.851314)
				(mid 69.107304 -428.851314)
				(end 69.3928 -428.851314)
			)
		)
		(stroke
			(width 0)
			(type solid)
		)
		(fill yes)
		(layer "In2.Cu")
		(net "GND")
	)
	(gr_poly
		(pts
			(arc
				(start 69.3928 -427.699678)
				(mid 69.107304 -427.699678)
				(end 69.3928 -427.699678)
			)
		)
		(stroke
			(width 0)
			(type solid)
		)
		(fill yes)
		(layer "In2.Cu")
		(net "GND")
	)
	(gr_poly
		(pts
			(arc
				(start 69.3928 -426.54728)
				(mid 69.107304 -426.54728)
				(end 69.3928 -426.54728)
			)
		)
		(stroke
			(width 0)
			(type solid)
		)
		(fill yes)
		(layer "In2.Cu")
		(net "GND")
	)
	(gr_poly
		(pts
			(arc
				(start 71.392796 -438.651396)
				(mid 71.1073 -438.651396)
				(end 71.392796 -438.651396)
			)
		)
		(stroke
			(width 0)
			(type solid)
		)
		(fill yes)
		(layer "In2.Cu")
		(net "GND")
	)
	(gr_poly
		(pts
			(arc
				(start 71.392796 -437.49976)
				(mid 71.1073 -437.49976)
				(end 71.392796 -437.49976)
			)
		)
		(stroke
			(width 0)
			(type solid)
		)
		(fill yes)
		(layer "In2.Cu")
		(net "GND")
	)
	(gr_poly
		(pts
			(arc
				(start 71.392796 -436.347362)
				(mid 71.1073 -436.347362)
				(end 71.392796 -436.347362)
			)
		)
		(stroke
			(width 0)
			(type solid)
		)
		(fill yes)
		(layer "In2.Cu")
		(net "GND")
	)
	(gr_poly
		(pts
			(arc
				(start 71.392796 -435.0512)
				(mid 71.1073 -435.0512)
				(end 71.392796 -435.0512)
			)
		)
		(stroke
			(width 0)
			(type solid)
		)
		(fill yes)
		(layer "In2.Cu")
		(net "GND")
	)
	(gr_poly
		(pts
			(arc
				(start 71.392796 -433.899564)
				(mid 71.1073 -433.899564)
				(end 71.392796 -433.899564)
			)
		)
		(stroke
			(width 0)
			(type solid)
		)
		(fill yes)
		(layer "In2.Cu")
		(net "GND")
	)
	(gr_poly
		(pts
			(arc
				(start 71.392796 -432.747166)
				(mid 71.1073 -432.747166)
				(end 71.392796 -432.747166)
			)
		)
		(stroke
			(width 0)
			(type solid)
		)
		(fill yes)
		(layer "In2.Cu")
		(net "GND")
	)
	(gr_poly
		(pts
			(arc
				(start 71.392796 -431.451258)
				(mid 71.1073 -431.451258)
				(end 71.392796 -431.451258)
			)
		)
		(stroke
			(width 0)
			(type solid)
		)
		(fill yes)
		(layer "In2.Cu")
		(net "GND")
	)
	(gr_poly
		(pts
			(arc
				(start 71.392796 -430.299622)
				(mid 71.1073 -430.299622)
				(end 71.392796 -430.299622)
			)
		)
		(stroke
			(width 0)
			(type solid)
		)
		(fill yes)
		(layer "In2.Cu")
		(net "GND")
	)
	(gr_poly
		(pts
			(arc
				(start 71.392796 -429.147224)
				(mid 71.1073 -429.147224)
				(end 71.392796 -429.147224)
			)
		)
		(stroke
			(width 0)
			(type solid)
		)
		(fill yes)
		(layer "In2.Cu")
		(net "GND")
	)
	(gr_poly
		(pts
			(arc
				(start 71.392796 -427.851316)
				(mid 71.1073 -427.851316)
				(end 71.392796 -427.851316)
			)
		)
		(stroke
			(width 0)
			(type solid)
		)
		(fill yes)
		(layer "In2.Cu")
		(net "GND")
	)
	(gr_poly
		(pts
			(arc
				(start 71.392796 -426.69968)
				(mid 71.1073 -426.69968)
				(end 71.392796 -426.69968)
			)
		)
		(stroke
			(width 0)
			(type solid)
		)
		(fill yes)
		(layer "In2.Cu")
		(net "GND")
	)
	(gr_poly
		(pts
			(arc
				(start 71.392796 -425.547282)
				(mid 71.1073 -425.547282)
				(end 71.392796 -425.547282)
			)
		)
		(stroke
			(width 0)
			(type solid)
		)
		(fill yes)
		(layer "In2.Cu")
		(net "GND")
	)
	(gr_poly
		(pts
			(arc
				(start 76.392786 -438.651396)
				(mid 76.10729 -438.651396)
				(end 76.392786 -438.651396)
			)
		)
		(stroke
			(width 0)
			(type solid)
		)
		(fill yes)
		(layer "In2.Cu")
		(net "GND")
	)
	(gr_poly
		(pts
			(arc
				(start 76.392786 -437.49976)
				(mid 76.10729 -437.49976)
				(end 76.392786 -437.49976)
			)
		)
		(stroke
			(width 0)
			(type solid)
		)
		(fill yes)
		(layer "In2.Cu")
		(net "GND")
	)
	(gr_poly
		(pts
			(arc
				(start 76.392786 -436.347362)
				(mid 76.10729 -436.347362)
				(end 76.392786 -436.347362)
			)
		)
		(stroke
			(width 0)
			(type solid)
		)
		(fill yes)
		(layer "In2.Cu")
		(net "GND")
	)
	(gr_poly
		(pts
			(arc
				(start 76.392786 -435.0512)
				(mid 76.10729 -435.0512)
				(end 76.392786 -435.0512)
			)
		)
		(stroke
			(width 0)
			(type solid)
		)
		(fill yes)
		(layer "In2.Cu")
		(net "GND")
	)
	(gr_poly
		(pts
			(arc
				(start 76.392786 -433.899564)
				(mid 76.10729 -433.899564)
				(end 76.392786 -433.899564)
			)
		)
		(stroke
			(width 0)
			(type solid)
		)
		(fill yes)
		(layer "In2.Cu")
		(net "GND")
	)
	(gr_poly
		(pts
			(arc
				(start 76.392786 -432.747166)
				(mid 76.10729 -432.747166)
				(end 76.392786 -432.747166)
			)
		)
		(stroke
			(width 0)
			(type solid)
		)
		(fill yes)
		(layer "In2.Cu")
		(net "GND")
	)
	(gr_poly
		(pts
			(arc
				(start 76.392786 -431.451258)
				(mid 76.10729 -431.451258)
				(end 76.392786 -431.451258)
			)
		)
		(stroke
			(width 0)
			(type solid)
		)
		(fill yes)
		(layer "In2.Cu")
		(net "GND")
	)
	(gr_poly
		(pts
			(arc
				(start 76.392786 -430.299622)
				(mid 76.10729 -430.299622)
				(end 76.392786 -430.299622)
			)
		)
		(stroke
			(width 0)
			(type solid)
		)
		(fill yes)
		(layer "In2.Cu")
		(net "GND")
	)
	(gr_poly
		(pts
			(arc
				(start 76.392786 -429.147224)
				(mid 76.10729 -429.147224)
				(end 76.392786 -429.147224)
			)
		)
		(stroke
			(width 0)
			(type solid)
		)
		(fill yes)
		(layer "In2.Cu")
		(net "GND")
	)
	(gr_poly
		(pts
			(arc
				(start 76.392786 -427.851316)
				(mid 76.10729 -427.851316)
				(end 76.392786 -427.851316)
			)
		)
		(stroke
			(width 0)
			(type solid)
		)
		(fill yes)
		(layer "In2.Cu")
		(net "GND")
	)
	(gr_poly
		(pts
			(arc
				(start 76.392786 -426.69968)
				(mid 76.10729 -426.69968)
				(end 76.392786 -426.69968)
			)
		)
		(stroke
			(width 0)
			(type solid)
		)
		(fill yes)
		(layer "In2.Cu")
		(net "GND")
	)
	(gr_poly
		(pts
			(arc
				(start 76.392786 -425.547282)
				(mid 76.10729 -425.547282)
				(end 76.392786 -425.547282)
			)
		)
		(stroke
			(width 0)
			(type solid)
		)
		(fill yes)
		(layer "In2.Cu")
		(net "GND")
	)
	(gr_poly
		(pts
			(arc
				(start 78.392782 -439.651394)
				(mid 78.107286 -439.651394)
				(end 78.392782 -439.651394)
			)
		)
		(stroke
			(width 0)
			(type solid)
		)
		(fill yes)
		(layer "In2.Cu")
		(net "GND")
	)
	(gr_poly
		(pts
			(arc
				(start 78.392782 -438.499758)
				(mid 78.107286 -438.499758)
				(end 78.392782 -438.499758)
			)
		)
		(stroke
			(width 0)
			(type solid)
		)
		(fill yes)
		(layer "In2.Cu")
		(net "GND")
	)
	(gr_poly
		(pts
			(arc
				(start 78.392782 -437.34736)
				(mid 78.107286 -437.34736)
				(end 78.392782 -437.34736)
			)
		)
		(stroke
			(width 0)
			(type solid)
		)
		(fill yes)
		(layer "In2.Cu")
		(net "GND")
	)
	(gr_poly
		(pts
			(arc
				(start 78.392782 -436.051198)
				(mid 78.107286 -436.051198)
				(end 78.392782 -436.051198)
			)
		)
		(stroke
			(width 0)
			(type solid)
		)
		(fill yes)
		(layer "In2.Cu")
		(net "GND")
	)
	(gr_poly
		(pts
			(arc
				(start 78.392782 -434.899562)
				(mid 78.107286 -434.899562)
				(end 78.392782 -434.899562)
			)
		)
		(stroke
			(width 0)
			(type solid)
		)
		(fill yes)
		(layer "In2.Cu")
		(net "GND")
	)
	(gr_poly
		(pts
			(arc
				(start 78.392782 -433.747164)
				(mid 78.107286 -433.747164)
				(end 78.392782 -433.747164)
			)
		)
		(stroke
			(width 0)
			(type solid)
		)
		(fill yes)
		(layer "In2.Cu")
		(net "GND")
	)
	(gr_poly
		(pts
			(arc
				(start 78.392782 -432.451256)
				(mid 78.107286 -432.451256)
				(end 78.392782 -432.451256)
			)
		)
		(stroke
			(width 0)
			(type solid)
		)
		(fill yes)
		(layer "In2.Cu")
		(net "GND")
	)
	(gr_poly
		(pts
			(arc
				(start 78.392782 -431.29962)
				(mid 78.107286 -431.29962)
				(end 78.392782 -431.29962)
			)
		)
		(stroke
			(width 0)
			(type solid)
		)
		(fill yes)
		(layer "In2.Cu")
		(net "GND")
	)
	(gr_poly
		(pts
			(arc
				(start 78.392782 -430.147222)
				(mid 78.107286 -430.147222)
				(end 78.392782 -430.147222)
			)
		)
		(stroke
			(width 0)
			(type solid)
		)
		(fill yes)
		(layer "In2.Cu")
		(net "GND")
	)
	(gr_poly
		(pts
			(arc
				(start 78.392782 -428.851314)
				(mid 78.107286 -428.851314)
				(end 78.392782 -428.851314)
			)
		)
		(stroke
			(width 0)
			(type solid)
		)
		(fill yes)
		(layer "In2.Cu")
		(net "GND")
	)
	(gr_poly
		(pts
			(arc
				(start 78.392782 -427.699678)
				(mid 78.107286 -427.699678)
				(end 78.392782 -427.699678)
			)
		)
		(stroke
			(width 0)
			(type solid)
		)
		(fill yes)
		(layer "In2.Cu")
		(net "GND")
	)
	(gr_poly
		(pts
			(arc
				(start 78.392782 -426.54728)
				(mid 78.107286 -426.54728)
				(end 78.392782 -426.54728)
			)
		)
		(stroke
			(width 0)
			(type solid)
		)
		(fill yes)
		(layer "In2.Cu")
		(net "GND")
	)
	(gr_poly
		(pts
			(arc
				(start 80.392778 -438.651396)
				(mid 80.107282 -438.651396)
				(end 80.392778 -438.651396)
			)
		)
		(stroke
			(width 0)
			(type solid)
		)
		(fill yes)
		(layer "In2.Cu")
		(net "GND")
	)
	(gr_poly
		(pts
			(arc
				(start 80.392778 -437.49976)
				(mid 80.107282 -437.49976)
				(end 80.392778 -437.49976)
			)
		)
		(stroke
			(width 0)
			(type solid)
		)
		(fill yes)
		(layer "In2.Cu")
		(net "GND")
	)
	(gr_poly
		(pts
			(arc
				(start 80.392778 -436.347362)
				(mid 80.107282 -436.347362)
				(end 80.392778 -436.347362)
			)
		)
		(stroke
			(width 0)
			(type solid)
		)
		(fill yes)
		(layer "In2.Cu")
		(net "GND")
	)
	(gr_poly
		(pts
			(arc
				(start 80.392778 -435.0512)
				(mid 80.107282 -435.0512)
				(end 80.392778 -435.0512)
			)
		)
		(stroke
			(width 0)
			(type solid)
		)
		(fill yes)
		(layer "In2.Cu")
		(net "GND")
	)
	(gr_poly
		(pts
			(arc
				(start 80.392778 -433.899564)
				(mid 80.107282 -433.899564)
				(end 80.392778 -433.899564)
			)
		)
		(stroke
			(width 0)
			(type solid)
		)
		(fill yes)
		(layer "In2.Cu")
		(net "GND")
	)
	(gr_poly
		(pts
			(arc
				(start 80.392778 -432.747166)
				(mid 80.107282 -432.747166)
				(end 80.392778 -432.747166)
			)
		)
		(stroke
			(width 0)
			(type solid)
		)
		(fill yes)
		(layer "In2.Cu")
		(net "GND")
	)
	(gr_poly
		(pts
			(arc
				(start 80.392778 -431.451258)
				(mid 80.107282 -431.451258)
				(end 80.392778 -431.451258)
			)
		)
		(stroke
			(width 0)
			(type solid)
		)
		(fill yes)
		(layer "In2.Cu")
		(net "GND")
	)
	(gr_poly
		(pts
			(arc
				(start 80.392778 -430.299622)
				(mid 80.107282 -430.299622)
				(end 80.392778 -430.299622)
			)
		)
		(stroke
			(width 0)
			(type solid)
		)
		(fill yes)
		(layer "In2.Cu")
		(net "GND")
	)
	(gr_poly
		(pts
			(arc
				(start 80.392778 -429.147224)
				(mid 80.107282 -429.147224)
				(end 80.392778 -429.147224)
			)
		)
		(stroke
			(width 0)
			(type solid)
		)
		(fill yes)
		(layer "In2.Cu")
		(net "GND")
	)
	(gr_poly
		(pts
			(arc
				(start 80.392778 -427.851316)
				(mid 80.107282 -427.851316)
				(end 80.392778 -427.851316)
			)
		)
		(stroke
			(width 0)
			(type solid)
		)
		(fill yes)
		(layer "In2.Cu")
		(net "GND")
	)
	(gr_poly
		(pts
			(arc
				(start 80.392778 -426.69968)
				(mid 80.107282 -426.69968)
				(end 80.392778 -426.69968)
			)
		)
		(stroke
			(width 0)
			(type solid)
		)
		(fill yes)
		(layer "In2.Cu")
		(net "GND")
	)
	(gr_poly
		(pts
			(arc
				(start 80.392778 -425.547282)
				(mid 80.107282 -425.547282)
				(end 80.392778 -425.547282)
			)
		)
		(stroke
			(width 0)
			(type solid)
		)
		(fill yes)
		(layer "In2.Cu")
		(net "GND")
	)
	(gr_poly
		(pts
			(arc
				(start 82.392774 -439.651394)
				(mid 82.107278 -439.651394)
				(end 82.392774 -439.651394)
			)
		)
		(stroke
			(width 0)
			(type solid)
		)
		(fill yes)
		(layer "In2.Cu")
		(net "GND")
	)
	(gr_poly
		(pts
			(arc
				(start 82.392774 -438.499758)
				(mid 82.107278 -438.499758)
				(end 82.392774 -438.499758)
			)
		)
		(stroke
			(width 0)
			(type solid)
		)
		(fill yes)
		(layer "In2.Cu")
		(net "GND")
	)
	(gr_poly
		(pts
			(arc
				(start 82.392774 -437.34736)
				(mid 82.107278 -437.34736)
				(end 82.392774 -437.34736)
			)
		)
		(stroke
			(width 0)
			(type solid)
		)
		(fill yes)
		(layer "In2.Cu")
		(net "GND")
	)
	(gr_poly
		(pts
			(arc
				(start 82.392774 -436.051198)
				(mid 82.107278 -436.051198)
				(end 82.392774 -436.051198)
			)
		)
		(stroke
			(width 0)
			(type solid)
		)
		(fill yes)
		(layer "In2.Cu")
		(net "GND")
	)
	(gr_poly
		(pts
			(arc
				(start 82.392774 -434.899562)
				(mid 82.107278 -434.899562)
				(end 82.392774 -434.899562)
			)
		)
		(stroke
			(width 0)
			(type solid)
		)
		(fill yes)
		(layer "In2.Cu")
		(net "GND")
	)
	(gr_poly
		(pts
			(arc
				(start 82.392774 -433.747164)
				(mid 82.107278 -433.747164)
				(end 82.392774 -433.747164)
			)
		)
		(stroke
			(width 0)
			(type solid)
		)
		(fill yes)
		(layer "In2.Cu")
		(net "GND")
	)
	(gr_poly
		(pts
			(arc
				(start 82.392774 -432.451256)
				(mid 82.107278 -432.451256)
				(end 82.392774 -432.451256)
			)
		)
		(stroke
			(width 0)
			(type solid)
		)
		(fill yes)
		(layer "In2.Cu")
		(net "GND")
	)
	(gr_poly
		(pts
			(arc
				(start 82.392774 -431.29962)
				(mid 82.107278 -431.29962)
				(end 82.392774 -431.29962)
			)
		)
		(stroke
			(width 0)
			(type solid)
		)
		(fill yes)
		(layer "In2.Cu")
		(net "GND")
	)
	(gr_poly
		(pts
			(arc
				(start 82.392774 -430.147222)
				(mid 82.107278 -430.147222)
				(end 82.392774 -430.147222)
			)
		)
		(stroke
			(width 0)
			(type solid)
		)
		(fill yes)
		(layer "In2.Cu")
		(net "GND")
	)
	(gr_poly
		(pts
			(arc
				(start 82.392774 -428.851314)
				(mid 82.107278 -428.851314)
				(end 82.392774 -428.851314)
			)
		)
		(stroke
			(width 0)
			(type solid)
		)
		(fill yes)
		(layer "In2.Cu")
		(net "GND")
	)
	(gr_poly
		(pts
			(arc
				(start 82.392774 -427.699678)
				(mid 82.107278 -427.699678)
				(end 82.392774 -427.699678)
			)
		)
		(stroke
			(width 0)
			(type solid)
		)
		(fill yes)
		(layer "In2.Cu")
		(net "GND")
	)
	(gr_poly
		(pts
			(arc
				(start 82.392774 -426.54728)
				(mid 82.107278 -426.54728)
				(end 82.392774 -426.54728)
			)
		)
		(stroke
			(width 0)
			(type solid)
		)
		(fill yes)
		(layer "In2.Cu")
		(net "GND")
	)
	(gr_poly
		(pts
			(arc
				(start 84.39277 -438.651396)
				(mid 84.107274 -438.651396)
				(end 84.39277 -438.651396)
			)
		)
		(stroke
			(width 0)
			(type solid)
		)
		(fill yes)
		(layer "In2.Cu")
		(net "GND")
	)
	(gr_poly
		(pts
			(arc
				(start 84.39277 -437.49976)
				(mid 84.107274 -437.49976)
				(end 84.39277 -437.49976)
			)
		)
		(stroke
			(width 0)
			(type solid)
		)
		(fill yes)
		(layer "In2.Cu")
		(net "GND")
	)
	(gr_poly
		(pts
			(arc
				(start 84.39277 -436.347362)
				(mid 84.107274 -436.347362)
				(end 84.39277 -436.347362)
			)
		)
		(stroke
			(width 0)
			(type solid)
		)
		(fill yes)
		(layer "In2.Cu")
		(net "GND")
	)
	(gr_poly
		(pts
			(arc
				(start 84.39277 -435.0512)
				(mid 84.107274 -435.0512)
				(end 84.39277 -435.0512)
			)
		)
		(stroke
			(width 0)
			(type solid)
		)
		(fill yes)
		(layer "In2.Cu")
		(net "GND")
	)
	(gr_poly
		(pts
			(arc
				(start 84.39277 -433.899564)
				(mid 84.107274 -433.899564)
				(end 84.39277 -433.899564)
			)
		)
		(stroke
			(width 0)
			(type solid)
		)
		(fill yes)
		(layer "In2.Cu")
		(net "GND")
	)
	(gr_poly
		(pts
			(arc
				(start 84.39277 -432.747166)
				(mid 84.107274 -432.747166)
				(end 84.39277 -432.747166)
			)
		)
		(stroke
			(width 0)
			(type solid)
		)
		(fill yes)
		(layer "In2.Cu")
		(net "GND")
	)
	(gr_poly
		(pts
			(arc
				(start 84.39277 -431.451258)
				(mid 84.107274 -431.451258)
				(end 84.39277 -431.451258)
			)
		)
		(stroke
			(width 0)
			(type solid)
		)
		(fill yes)
		(layer "In2.Cu")
		(net "GND")
	)
	(gr_poly
		(pts
			(arc
				(start 84.39277 -430.299622)
				(mid 84.107274 -430.299622)
				(end 84.39277 -430.299622)
			)
		)
		(stroke
			(width 0)
			(type solid)
		)
		(fill yes)
		(layer "In2.Cu")
		(net "GND")
	)
	(gr_poly
		(pts
			(arc
				(start 84.39277 -429.147224)
				(mid 84.107274 -429.147224)
				(end 84.39277 -429.147224)
			)
		)
		(stroke
			(width 0)
			(type solid)
		)
		(fill yes)
		(layer "In2.Cu")
		(net "GND")
	)
	(gr_poly
		(pts
			(arc
				(start 84.39277 -427.851316)
				(mid 84.107274 -427.851316)
				(end 84.39277 -427.851316)
			)
		)
		(stroke
			(width 0)
			(type solid)
		)
		(fill yes)
		(layer "In2.Cu")
		(net "GND")
	)
	(gr_poly
		(pts
			(arc
				(start 84.39277 -426.69968)
				(mid 84.107274 -426.69968)
				(end 84.39277 -426.69968)
			)
		)
		(stroke
			(width 0)
			(type solid)
		)
		(fill yes)
		(layer "In2.Cu")
		(net "GND")
	)
	(gr_poly
		(pts
			(arc
				(start 84.39277 -425.547282)
				(mid 84.107274 -425.547282)
				(end 84.39277 -425.547282)
			)
		)
		(stroke
			(width 0)
			(type solid)
		)
		(fill yes)
		(layer "In2.Cu")
		(net "GND")
	)
	(gr_poly
		(pts
			(arc
				(start 86.392766 -439.651394)
				(mid 86.10727 -439.651394)
				(end 86.392766 -439.651394)
			)
		)
		(stroke
			(width 0)
			(type solid)
		)
		(fill yes)
		(layer "In2.Cu")
		(net "GND")
	)
	(gr_poly
		(pts
			(arc
				(start 86.392766 -438.499758)
				(mid 86.10727 -438.499758)
				(end 86.392766 -438.499758)
			)
		)
		(stroke
			(width 0)
			(type solid)
		)
		(fill yes)
		(layer "In2.Cu")
		(net "GND")
	)
	(gr_poly
		(pts
			(arc
				(start 86.392766 -437.34736)
				(mid 86.10727 -437.34736)
				(end 86.392766 -437.34736)
			)
		)
		(stroke
			(width 0)
			(type solid)
		)
		(fill yes)
		(layer "In2.Cu")
		(net "GND")
	)
	(gr_poly
		(pts
			(arc
				(start 86.392766 -436.051198)
				(mid 86.10727 -436.051198)
				(end 86.392766 -436.051198)
			)
		)
		(stroke
			(width 0)
			(type solid)
		)
		(fill yes)
		(layer "In2.Cu")
		(net "GND")
	)
	(gr_poly
		(pts
			(arc
				(start 86.392766 -434.899562)
				(mid 86.10727 -434.899562)
				(end 86.392766 -434.899562)
			)
		)
		(stroke
			(width 0)
			(type solid)
		)
		(fill yes)
		(layer "In2.Cu")
		(net "GND")
	)
	(gr_poly
		(pts
			(arc
				(start 86.392766 -433.747164)
				(mid 86.10727 -433.747164)
				(end 86.392766 -433.747164)
			)
		)
		(stroke
			(width 0)
			(type solid)
		)
		(fill yes)
		(layer "In2.Cu")
		(net "GND")
	)
	(gr_poly
		(pts
			(arc
				(start 86.392766 -432.451256)
				(mid 86.10727 -432.451256)
				(end 86.392766 -432.451256)
			)
		)
		(stroke
			(width 0)
			(type solid)
		)
		(fill yes)
		(layer "In2.Cu")
		(net "GND")
	)
	(gr_poly
		(pts
			(arc
				(start 86.392766 -431.29962)
				(mid 86.10727 -431.29962)
				(end 86.392766 -431.29962)
			)
		)
		(stroke
			(width 0)
			(type solid)
		)
		(fill yes)
		(layer "In2.Cu")
		(net "GND")
	)
	(gr_poly
		(pts
			(arc
				(start 86.392766 -430.147222)
				(mid 86.10727 -430.147222)
				(end 86.392766 -430.147222)
			)
		)
		(stroke
			(width 0)
			(type solid)
		)
		(fill yes)
		(layer "In2.Cu")
		(net "GND")
	)
	(gr_poly
		(pts
			(arc
				(start 86.392766 -428.851314)
				(mid 86.10727 -428.851314)
				(end 86.392766 -428.851314)
			)
		)
		(stroke
			(width 0)
			(type solid)
		)
		(fill yes)
		(layer "In2.Cu")
		(net "GND")
	)
	(gr_poly
		(pts
			(arc
				(start 86.392766 -427.699678)
				(mid 86.10727 -427.699678)
				(end 86.392766 -427.699678)
			)
		)
		(stroke
			(width 0)
			(type solid)
		)
		(fill yes)
		(layer "In2.Cu")
		(net "GND")
	)
	(gr_poly
		(pts
			(arc
				(start 86.392766 -426.54728)
				(mid 86.10727 -426.54728)
				(end 86.392766 -426.54728)
			)
		)
		(stroke
			(width 0)
			(type solid)
		)
		(fill yes)
		(layer "In2.Cu")
		(net "GND")
	)
	(gr_poly
		(pts
			(arc
				(start 88.392762 -438.651396)
				(mid 88.107266 -438.651396)
				(end 88.392762 -438.651396)
			)
		)
		(stroke
			(width 0)
			(type solid)
		)
		(fill yes)
		(layer "In2.Cu")
		(net "GND")
	)
	(gr_poly
		(pts
			(arc
				(start 88.392762 -437.49976)
				(mid 88.107266 -437.49976)
				(end 88.392762 -437.49976)
			)
		)
		(stroke
			(width 0)
			(type solid)
		)
		(fill yes)
		(layer "In2.Cu")
		(net "GND")
	)
	(gr_poly
		(pts
			(arc
				(start 88.392762 -436.347362)
				(mid 88.107266 -436.347362)
				(end 88.392762 -436.347362)
			)
		)
		(stroke
			(width 0)
			(type solid)
		)
		(fill yes)
		(layer "In2.Cu")
		(net "GND")
	)
	(gr_poly
		(pts
			(arc
				(start 88.392762 -435.0512)
				(mid 88.107266 -435.0512)
				(end 88.392762 -435.0512)
			)
		)
		(stroke
			(width 0)
			(type solid)
		)
		(fill yes)
		(layer "In2.Cu")
		(net "GND")
	)
	(gr_poly
		(pts
			(arc
				(start 88.392762 -433.899564)
				(mid 88.107266 -433.899564)
				(end 88.392762 -433.899564)
			)
		)
		(stroke
			(width 0)
			(type solid)
		)
		(fill yes)
		(layer "In2.Cu")
		(net "GND")
	)
	(gr_poly
		(pts
			(arc
				(start 88.392762 -432.747166)
				(mid 88.107266 -432.747166)
				(end 88.392762 -432.747166)
			)
		)
		(stroke
			(width 0)
			(type solid)
		)
		(fill yes)
		(layer "In2.Cu")
		(net "GND")
	)
	(gr_poly
		(pts
			(arc
				(start 88.392762 -431.451258)
				(mid 88.107266 -431.451258)
				(end 88.392762 -431.451258)
			)
		)
		(stroke
			(width 0)
			(type solid)
		)
		(fill yes)
		(layer "In2.Cu")
		(net "GND")
	)
	(gr_poly
		(pts
			(arc
				(start 88.392762 -430.299622)
				(mid 88.107266 -430.299622)
				(end 88.392762 -430.299622)
			)
		)
		(stroke
			(width 0)
			(type solid)
		)
		(fill yes)
		(layer "In2.Cu")
		(net "GND")
	)
	(gr_poly
		(pts
			(arc
				(start 88.392762 -429.147224)
				(mid 88.107266 -429.147224)
				(end 88.392762 -429.147224)
			)
		)
		(stroke
			(width 0)
			(type solid)
		)
		(fill yes)
		(layer "In2.Cu")
		(net "GND")
	)
	(gr_poly
		(pts
			(arc
				(start 88.392762 -427.851316)
				(mid 88.107266 -427.851316)
				(end 88.392762 -427.851316)
			)
		)
		(stroke
			(width 0)
			(type solid)
		)
		(fill yes)
		(layer "In2.Cu")
		(net "GND")
	)
	(gr_poly
		(pts
			(arc
				(start 88.392762 -426.69968)
				(mid 88.107266 -426.69968)
				(end 88.392762 -426.69968)
			)
		)
		(stroke
			(width 0)
			(type solid)
		)
		(fill yes)
		(layer "In2.Cu")
		(net "GND")
	)
	(gr_poly
		(pts
			(arc
				(start 88.392762 -425.547282)
				(mid 88.107266 -425.547282)
				(end 88.392762 -425.547282)
			)
		)
		(stroke
			(width 0)
			(type solid)
		)
		(fill yes)
		(layer "In2.Cu")
		(net "GND")
	)
	(gr_poly
		(pts
			(arc
				(start 90.392758 -439.651394)
				(mid 90.107262 -439.651394)
				(end 90.392758 -439.651394)
			)
		)
		(stroke
			(width 0)
			(type solid)
		)
		(fill yes)
		(layer "In2.Cu")
		(net "GND")
	)
	(gr_poly
		(pts
			(arc
				(start 90.392758 -438.499758)
				(mid 90.107262 -438.499758)
				(end 90.392758 -438.499758)
			)
		)
		(stroke
			(width 0)
			(type solid)
		)
		(fill yes)
		(layer "In2.Cu")
		(net "GND")
	)
	(gr_poly
		(pts
			(arc
				(start 90.392758 -437.34736)
				(mid 90.107262 -437.34736)
				(end 90.392758 -437.34736)
			)
		)
		(stroke
			(width 0)
			(type solid)
		)
		(fill yes)
		(layer "In2.Cu")
		(net "GND")
	)
	(gr_poly
		(pts
			(arc
				(start 90.392758 -436.051198)
				(mid 90.107262 -436.051198)
				(end 90.392758 -436.051198)
			)
		)
		(stroke
			(width 0)
			(type solid)
		)
		(fill yes)
		(layer "In2.Cu")
		(net "GND")
	)
	(gr_poly
		(pts
			(arc
				(start 90.392758 -434.899562)
				(mid 90.107262 -434.899562)
				(end 90.392758 -434.899562)
			)
		)
		(stroke
			(width 0)
			(type solid)
		)
		(fill yes)
		(layer "In2.Cu")
		(net "GND")
	)
	(gr_poly
		(pts
			(arc
				(start 90.392758 -433.747164)
				(mid 90.107262 -433.747164)
				(end 90.392758 -433.747164)
			)
		)
		(stroke
			(width 0)
			(type solid)
		)
		(fill yes)
		(layer "In2.Cu")
		(net "GND")
	)
	(gr_poly
		(pts
			(arc
				(start 90.392758 -432.451256)
				(mid 90.107262 -432.451256)
				(end 90.392758 -432.451256)
			)
		)
		(stroke
			(width 0)
			(type solid)
		)
		(fill yes)
		(layer "In2.Cu")
		(net "GND")
	)
	(gr_poly
		(pts
			(arc
				(start 90.392758 -431.29962)
				(mid 90.107262 -431.29962)
				(end 90.392758 -431.29962)
			)
		)
		(stroke
			(width 0)
			(type solid)
		)
		(fill yes)
		(layer "In2.Cu")
		(net "GND")
	)
	(gr_poly
		(pts
			(arc
				(start 90.392758 -430.147222)
				(mid 90.107262 -430.147222)
				(end 90.392758 -430.147222)
			)
		)
		(stroke
			(width 0)
			(type solid)
		)
		(fill yes)
		(layer "In2.Cu")
		(net "GND")
	)
	(gr_poly
		(pts
			(arc
				(start 90.392758 -428.851314)
				(mid 90.107262 -428.851314)
				(end 90.392758 -428.851314)
			)
		)
		(stroke
			(width 0)
			(type solid)
		)
		(fill yes)
		(layer "In2.Cu")
		(net "GND")
	)
	(gr_poly
		(pts
			(arc
				(start 90.392758 -427.699678)
				(mid 90.107262 -427.699678)
				(end 90.392758 -427.699678)
			)
		)
		(stroke
			(width 0)
			(type solid)
		)
		(fill yes)
		(layer "In2.Cu")
		(net "GND")
	)
	(gr_poly
		(pts
			(arc
				(start 90.392758 -426.54728)
				(mid 90.107262 -426.54728)
				(end 90.392758 -426.54728)
			)
		)
		(stroke
			(width 0)
			(type solid)
		)
		(fill yes)
		(layer "In2.Cu")
		(net "GND")
	)
	(gr_poly
		(pts
			(arc
				(start 126.492762 -438.651396)
				(mid 126.207266 -438.651396)
				(end 126.492762 -438.651396)
			)
		)
		(stroke
			(width 0)
			(type solid)
		)
		(fill yes)
		(layer "In2.Cu")
		(net "GND")
	)
	(gr_poly
		(pts
			(arc
				(start 126.492762 -437.49976)
				(mid 126.207266 -437.49976)
				(end 126.492762 -437.49976)
			)
		)
		(stroke
			(width 0)
			(type solid)
		)
		(fill yes)
		(layer "In2.Cu")
		(net "GND")
	)
	(gr_poly
		(pts
			(arc
				(start 126.492762 -436.347362)
				(mid 126.207266 -436.347362)
				(end 126.492762 -436.347362)
			)
		)
		(stroke
			(width 0)
			(type solid)
		)
		(fill yes)
		(layer "In2.Cu")
		(net "GND")
	)
	(gr_poly
		(pts
			(arc
				(start 126.492762 -435.0512)
				(mid 126.207266 -435.0512)
				(end 126.492762 -435.0512)
			)
		)
		(stroke
			(width 0)
			(type solid)
		)
		(fill yes)
		(layer "In2.Cu")
		(net "GND")
	)
	(gr_poly
		(pts
			(arc
				(start 126.492762 -433.899564)
				(mid 126.207266 -433.899564)
				(end 126.492762 -433.899564)
			)
		)
		(stroke
			(width 0)
			(type solid)
		)
		(fill yes)
		(layer "In2.Cu")
		(net "GND")
	)
	(gr_poly
		(pts
			(arc
				(start 126.492762 -432.747166)
				(mid 126.207266 -432.747166)
				(end 126.492762 -432.747166)
			)
		)
		(stroke
			(width 0)
			(type solid)
		)
		(fill yes)
		(layer "In2.Cu")
		(net "GND")
	)
	(gr_poly
		(pts
			(arc
				(start 126.492762 -431.451258)
				(mid 126.207266 -431.451258)
				(end 126.492762 -431.451258)
			)
		)
		(stroke
			(width 0)
			(type solid)
		)
		(fill yes)
		(layer "In2.Cu")
		(net "GND")
	)
	(gr_poly
		(pts
			(arc
				(start 126.492762 -430.299622)
				(mid 126.207266 -430.299622)
				(end 126.492762 -430.299622)
			)
		)
		(stroke
			(width 0)
			(type solid)
		)
		(fill yes)
		(layer "In2.Cu")
		(net "GND")
	)
	(gr_poly
		(pts
			(arc
				(start 126.492762 -429.147224)
				(mid 126.207266 -429.147224)
				(end 126.492762 -429.147224)
			)
		)
		(stroke
			(width 0)
			(type solid)
		)
		(fill yes)
		(layer "In2.Cu")
		(net "GND")
	)
	(gr_poly
		(pts
			(arc
				(start 126.492762 -427.851316)
				(mid 126.207266 -427.851316)
				(end 126.492762 -427.851316)
			)
		)
		(stroke
			(width 0)
			(type solid)
		)
		(fill yes)
		(layer "In2.Cu")
		(net "GND")
	)
	(gr_poly
		(pts
			(arc
				(start 126.492762 -426.69968)
				(mid 126.207266 -426.69968)
				(end 126.492762 -426.69968)
			)
		)
		(stroke
			(width 0)
			(type solid)
		)
		(fill yes)
		(layer "In2.Cu")
		(net "GND")
	)
	(gr_poly
		(pts
			(arc
				(start 126.492762 -425.547282)
				(mid 126.207266 -425.547282)
				(end 126.492762 -425.547282)
			)
		)
		(stroke
			(width 0)
			(type solid)
		)
		(fill yes)
		(layer "In2.Cu")
		(net "GND")
	)
	(gr_poly
		(pts
			(arc
				(start 128.492758 -439.651394)
				(mid 128.207262 -439.651394)
				(end 128.492758 -439.651394)
			)
		)
		(stroke
			(width 0)
			(type solid)
		)
		(fill yes)
		(layer "In2.Cu")
		(net "GND")
	)
	(gr_poly
		(pts
			(arc
				(start 128.492758 -438.499758)
				(mid 128.207262 -438.499758)
				(end 128.492758 -438.499758)
			)
		)
		(stroke
			(width 0)
			(type solid)
		)
		(fill yes)
		(layer "In2.Cu")
		(net "GND")
	)
	(gr_poly
		(pts
			(arc
				(start 128.492758 -437.34736)
				(mid 128.207262 -437.34736)
				(end 128.492758 -437.34736)
			)
		)
		(stroke
			(width 0)
			(type solid)
		)
		(fill yes)
		(layer "In2.Cu")
		(net "GND")
	)
	(gr_poly
		(pts
			(arc
				(start 128.492758 -436.051198)
				(mid 128.207262 -436.051198)
				(end 128.492758 -436.051198)
			)
		)
		(stroke
			(width 0)
			(type solid)
		)
		(fill yes)
		(layer "In2.Cu")
		(net "GND")
	)
	(gr_poly
		(pts
			(arc
				(start 128.492758 -434.899562)
				(mid 128.207262 -434.899562)
				(end 128.492758 -434.899562)
			)
		)
		(stroke
			(width 0)
			(type solid)
		)
		(fill yes)
		(layer "In2.Cu")
		(net "GND")
	)
	(gr_poly
		(pts
			(arc
				(start 128.492758 -433.747164)
				(mid 128.207262 -433.747164)
				(end 128.492758 -433.747164)
			)
		)
		(stroke
			(width 0)
			(type solid)
		)
		(fill yes)
		(layer "In2.Cu")
		(net "GND")
	)
	(gr_poly
		(pts
			(arc
				(start 128.492758 -432.451256)
				(mid 128.207262 -432.451256)
				(end 128.492758 -432.451256)
			)
		)
		(stroke
			(width 0)
			(type solid)
		)
		(fill yes)
		(layer "In2.Cu")
		(net "GND")
	)
	(gr_poly
		(pts
			(arc
				(start 128.492758 -431.29962)
				(mid 128.207262 -431.29962)
				(end 128.492758 -431.29962)
			)
		)
		(stroke
			(width 0)
			(type solid)
		)
		(fill yes)
		(layer "In2.Cu")
		(net "GND")
	)
	(gr_poly
		(pts
			(arc
				(start 128.492758 -430.147222)
				(mid 128.207262 -430.147222)
				(end 128.492758 -430.147222)
			)
		)
		(stroke
			(width 0)
			(type solid)
		)
		(fill yes)
		(layer "In2.Cu")
		(net "GND")
	)
	(gr_poly
		(pts
			(arc
				(start 128.492758 -428.851314)
				(mid 128.207262 -428.851314)
				(end 128.492758 -428.851314)
			)
		)
		(stroke
			(width 0)
			(type solid)
		)
		(fill yes)
		(layer "In2.Cu")
		(net "GND")
	)
	(gr_poly
		(pts
			(arc
				(start 128.492758 -427.699678)
				(mid 128.207262 -427.699678)
				(end 128.492758 -427.699678)
			)
		)
		(stroke
			(width 0)
			(type solid)
		)
		(fill yes)
		(layer "In2.Cu")
		(net "GND")
	)
	(gr_poly
		(pts
			(arc
				(start 128.492758 -426.54728)
				(mid 128.207262 -426.54728)
				(end 128.492758 -426.54728)
			)
		)
		(stroke
			(width 0)
			(type solid)
		)
		(fill yes)
		(layer "In2.Cu")
		(net "GND")
	)
	(gr_poly
		(pts
			(arc
				(start 130.492754 -438.651396)
				(mid 130.207258 -438.651396)
				(end 130.492754 -438.651396)
			)
		)
		(stroke
			(width 0)
			(type solid)
		)
		(fill yes)
		(layer "In2.Cu")
		(net "GND")
	)
	(gr_poly
		(pts
			(arc
				(start 130.492754 -437.49976)
				(mid 130.207258 -437.49976)
				(end 130.492754 -437.49976)
			)
		)
		(stroke
			(width 0)
			(type solid)
		)
		(fill yes)
		(layer "In2.Cu")
		(net "GND")
	)
	(gr_poly
		(pts
			(arc
				(start 130.492754 -436.347362)
				(mid 130.207258 -436.347362)
				(end 130.492754 -436.347362)
			)
		)
		(stroke
			(width 0)
			(type solid)
		)
		(fill yes)
		(layer "In2.Cu")
		(net "GND")
	)
	(gr_poly
		(pts
			(arc
				(start 130.492754 -435.0512)
				(mid 130.207258 -435.0512)
				(end 130.492754 -435.0512)
			)
		)
		(stroke
			(width 0)
			(type solid)
		)
		(fill yes)
		(layer "In2.Cu")
		(net "GND")
	)
	(gr_poly
		(pts
			(arc
				(start 130.492754 -433.899564)
				(mid 130.207258 -433.899564)
				(end 130.492754 -433.899564)
			)
		)
		(stroke
			(width 0)
			(type solid)
		)
		(fill yes)
		(layer "In2.Cu")
		(net "GND")
	)
	(gr_poly
		(pts
			(arc
				(start 130.492754 -432.747166)
				(mid 130.207258 -432.747166)
				(end 130.492754 -432.747166)
			)
		)
		(stroke
			(width 0)
			(type solid)
		)
		(fill yes)
		(layer "In2.Cu")
		(net "GND")
	)
	(gr_poly
		(pts
			(arc
				(start 130.492754 -431.451258)
				(mid 130.207258 -431.451258)
				(end 130.492754 -431.451258)
			)
		)
		(stroke
			(width 0)
			(type solid)
		)
		(fill yes)
		(layer "In2.Cu")
		(net "GND")
	)
	(gr_poly
		(pts
			(arc
				(start 130.492754 -430.299622)
				(mid 130.207258 -430.299622)
				(end 130.492754 -430.299622)
			)
		)
		(stroke
			(width 0)
			(type solid)
		)
		(fill yes)
		(layer "In2.Cu")
		(net "GND")
	)
	(gr_poly
		(pts
			(arc
				(start 130.492754 -429.147224)
				(mid 130.207258 -429.147224)
				(end 130.492754 -429.147224)
			)
		)
		(stroke
			(width 0)
			(type solid)
		)
		(fill yes)
		(layer "In2.Cu")
		(net "GND")
	)
	(gr_poly
		(pts
			(arc
				(start 130.492754 -427.851316)
				(mid 130.207258 -427.851316)
				(end 130.492754 -427.851316)
			)
		)
		(stroke
			(width 0)
			(type solid)
		)
		(fill yes)
		(layer "In2.Cu")
		(net "GND")
	)
	(gr_poly
		(pts
			(arc
				(start 130.492754 -426.69968)
				(mid 130.207258 -426.69968)
				(end 130.492754 -426.69968)
			)
		)
		(stroke
			(width 0)
			(type solid)
		)
		(fill yes)
		(layer "In2.Cu")
		(net "GND")
	)
	(gr_poly
		(pts
			(arc
				(start 130.492754 -425.547282)
				(mid 130.207258 -425.547282)
				(end 130.492754 -425.547282)
			)
		)
		(stroke
			(width 0)
			(type solid)
		)
		(fill yes)
		(layer "In2.Cu")
		(net "GND")
	)
	(gr_poly
		(pts
			(arc
				(start 132.49275 -439.651394)
				(mid 132.207254 -439.651394)
				(end 132.49275 -439.651394)
			)
		)
		(stroke
			(width 0)
			(type solid)
		)
		(fill yes)
		(layer "In2.Cu")
		(net "GND")
	)
	(gr_poly
		(pts
			(arc
				(start 132.49275 -438.499758)
				(mid 132.207254 -438.499758)
				(end 132.49275 -438.499758)
			)
		)
		(stroke
			(width 0)
			(type solid)
		)
		(fill yes)
		(layer "In2.Cu")
		(net "GND")
	)
	(gr_poly
		(pts
			(arc
				(start 132.49275 -437.34736)
				(mid 132.207254 -437.34736)
				(end 132.49275 -437.34736)
			)
		)
		(stroke
			(width 0)
			(type solid)
		)
		(fill yes)
		(layer "In2.Cu")
		(net "GND")
	)
	(gr_poly
		(pts
			(arc
				(start 132.49275 -436.051198)
				(mid 132.207254 -436.051198)
				(end 132.49275 -436.051198)
			)
		)
		(stroke
			(width 0)
			(type solid)
		)
		(fill yes)
		(layer "In2.Cu")
		(net "GND")
	)
	(gr_poly
		(pts
			(arc
				(start 132.49275 -434.899562)
				(mid 132.207254 -434.899562)
				(end 132.49275 -434.899562)
			)
		)
		(stroke
			(width 0)
			(type solid)
		)
		(fill yes)
		(layer "In2.Cu")
		(net "GND")
	)
	(gr_poly
		(pts
			(arc
				(start 132.49275 -433.747164)
				(mid 132.207254 -433.747164)
				(end 132.49275 -433.747164)
			)
		)
		(stroke
			(width 0)
			(type solid)
		)
		(fill yes)
		(layer "In2.Cu")
		(net "GND")
	)
	(gr_poly
		(pts
			(arc
				(start 132.49275 -432.451256)
				(mid 132.207254 -432.451256)
				(end 132.49275 -432.451256)
			)
		)
		(stroke
			(width 0)
			(type solid)
		)
		(fill yes)
		(layer "In2.Cu")
		(net "GND")
	)
	(gr_poly
		(pts
			(arc
				(start 132.49275 -431.29962)
				(mid 132.207254 -431.29962)
				(end 132.49275 -431.29962)
			)
		)
		(stroke
			(width 0)
			(type solid)
		)
		(fill yes)
		(layer "In2.Cu")
		(net "GND")
	)
	(gr_poly
		(pts
			(arc
				(start 132.49275 -430.147222)
				(mid 132.207254 -430.147222)
				(end 132.49275 -430.147222)
			)
		)
		(stroke
			(width 0)
			(type solid)
		)
		(fill yes)
		(layer "In2.Cu")
		(net "GND")
	)
	(gr_poly
		(pts
			(arc
				(start 132.49275 -428.851314)
				(mid 132.207254 -428.851314)
				(end 132.49275 -428.851314)
			)
		)
		(stroke
			(width 0)
			(type solid)
		)
		(fill yes)
		(layer "In2.Cu")
		(net "GND")
	)
	(gr_poly
		(pts
			(arc
				(start 132.49275 -427.699678)
				(mid 132.207254 -427.699678)
				(end 132.49275 -427.699678)
			)
		)
		(stroke
			(width 0)
			(type solid)
		)
		(fill yes)
		(layer "In2.Cu")
		(net "GND")
	)
	(gr_poly
		(pts
			(arc
				(start 132.49275 -426.54728)
				(mid 132.207254 -426.54728)
				(end 132.49275 -426.54728)
			)
		)
		(stroke
			(width 0)
			(type solid)
		)
		(fill yes)
		(layer "In2.Cu")
		(net "GND")
	)
	(gr_poly
		(pts
			(arc
				(start 134.492746 -438.651396)
				(mid 134.20725 -438.651396)
				(end 134.492746 -438.651396)
			)
		)
		(stroke
			(width 0)
			(type solid)
		)
		(fill yes)
		(layer "In2.Cu")
		(net "GND")
	)
	(gr_poly
		(pts
			(arc
				(start 134.492746 -437.49976)
				(mid 134.20725 -437.49976)
				(end 134.492746 -437.49976)
			)
		)
		(stroke
			(width 0)
			(type solid)
		)
		(fill yes)
		(layer "In2.Cu")
		(net "GND")
	)
	(gr_poly
		(pts
			(arc
				(start 134.492746 -436.347362)
				(mid 134.20725 -436.347362)
				(end 134.492746 -436.347362)
			)
		)
		(stroke
			(width 0)
			(type solid)
		)
		(fill yes)
		(layer "In2.Cu")
		(net "GND")
	)
	(gr_poly
		(pts
			(arc
				(start 134.492746 -435.0512)
				(mid 134.20725 -435.0512)
				(end 134.492746 -435.0512)
			)
		)
		(stroke
			(width 0)
			(type solid)
		)
		(fill yes)
		(layer "In2.Cu")
		(net "GND")
	)
	(gr_poly
		(pts
			(arc
				(start 134.492746 -433.899564)
				(mid 134.20725 -433.899564)
				(end 134.492746 -433.899564)
			)
		)
		(stroke
			(width 0)
			(type solid)
		)
		(fill yes)
		(layer "In2.Cu")
		(net "GND")
	)
	(gr_poly
		(pts
			(arc
				(start 134.492746 -432.747166)
				(mid 134.20725 -432.747166)
				(end 134.492746 -432.747166)
			)
		)
		(stroke
			(width 0)
			(type solid)
		)
		(fill yes)
		(layer "In2.Cu")
		(net "GND")
	)
	(gr_poly
		(pts
			(arc
				(start 134.492746 -431.451258)
				(mid 134.20725 -431.451258)
				(end 134.492746 -431.451258)
			)
		)
		(stroke
			(width 0)
			(type solid)
		)
		(fill yes)
		(layer "In2.Cu")
		(net "GND")
	)
	(gr_poly
		(pts
			(arc
				(start 134.492746 -430.299622)
				(mid 134.20725 -430.299622)
				(end 134.492746 -430.299622)
			)
		)
		(stroke
			(width 0)
			(type solid)
		)
		(fill yes)
		(layer "In2.Cu")
		(net "GND")
	)
	(gr_poly
		(pts
			(arc
				(start 134.492746 -429.147224)
				(mid 134.20725 -429.147224)
				(end 134.492746 -429.147224)
			)
		)
		(stroke
			(width 0)
			(type solid)
		)
		(fill yes)
		(layer "In2.Cu")
		(net "GND")
	)
	(gr_poly
		(pts
			(arc
				(start 134.492746 -427.851316)
				(mid 134.20725 -427.851316)
				(end 134.492746 -427.851316)
			)
		)
		(stroke
			(width 0)
			(type solid)
		)
		(fill yes)
		(layer "In2.Cu")
		(net "GND")
	)
	(gr_poly
		(pts
			(arc
				(start 134.492746 -426.69968)
				(mid 134.20725 -426.69968)
				(end 134.492746 -426.69968)
			)
		)
		(stroke
			(width 0)
			(type solid)
		)
		(fill yes)
		(layer "In2.Cu")
		(net "GND")
	)
	(gr_poly
		(pts
			(arc
				(start 134.492746 -425.547282)
				(mid 134.20725 -425.547282)
				(end 134.492746 -425.547282)
			)
		)
		(stroke
			(width 0)
			(type solid)
		)
		(fill yes)
		(layer "In2.Cu")
		(net "GND")
	)
	(gr_poly
		(pts
			(arc
				(start 136.492742 -439.651394)
				(mid 136.207246 -439.651394)
				(end 136.492742 -439.651394)
			)
		)
		(stroke
			(width 0)
			(type solid)
		)
		(fill yes)
		(layer "In2.Cu")
		(net "GND")
	)
	(gr_poly
		(pts
			(arc
				(start 136.492742 -438.499758)
				(mid 136.207246 -438.499758)
				(end 136.492742 -438.499758)
			)
		)
		(stroke
			(width 0)
			(type solid)
		)
		(fill yes)
		(layer "In2.Cu")
		(net "GND")
	)
	(gr_poly
		(pts
			(arc
				(start 136.492742 -437.34736)
				(mid 136.207246 -437.34736)
				(end 136.492742 -437.34736)
			)
		)
		(stroke
			(width 0)
			(type solid)
		)
		(fill yes)
		(layer "In2.Cu")
		(net "GND")
	)
	(gr_poly
		(pts
			(arc
				(start 136.492742 -436.051198)
				(mid 136.207246 -436.051198)
				(end 136.492742 -436.051198)
			)
		)
		(stroke
			(width 0)
			(type solid)
		)
		(fill yes)
		(layer "In2.Cu")
		(net "GND")
	)
	(gr_poly
		(pts
			(arc
				(start 136.492742 -434.899562)
				(mid 136.207246 -434.899562)
				(end 136.492742 -434.899562)
			)
		)
		(stroke
			(width 0)
			(type solid)
		)
		(fill yes)
		(layer "In2.Cu")
		(net "GND")
	)
	(gr_poly
		(pts
			(arc
				(start 136.492742 -433.747164)
				(mid 136.207246 -433.747164)
				(end 136.492742 -433.747164)
			)
		)
		(stroke
			(width 0)
			(type solid)
		)
		(fill yes)
		(layer "In2.Cu")
		(net "GND")
	)
	(gr_poly
		(pts
			(arc
				(start 136.492742 -432.451256)
				(mid 136.207246 -432.451256)
				(end 136.492742 -432.451256)
			)
		)
		(stroke
			(width 0)
			(type solid)
		)
		(fill yes)
		(layer "In2.Cu")
		(net "GND")
	)
	(gr_poly
		(pts
			(arc
				(start 136.492742 -431.29962)
				(mid 136.207246 -431.29962)
				(end 136.492742 -431.29962)
			)
		)
		(stroke
			(width 0)
			(type solid)
		)
		(fill yes)
		(layer "In2.Cu")
		(net "GND")
	)
	(gr_poly
		(pts
			(arc
				(start 136.492742 -430.147222)
				(mid 136.207246 -430.147222)
				(end 136.492742 -430.147222)
			)
		)
		(stroke
			(width 0)
			(type solid)
		)
		(fill yes)
		(layer "In2.Cu")
		(net "GND")
	)
	(gr_poly
		(pts
			(arc
				(start 136.492742 -428.851314)
				(mid 136.207246 -428.851314)
				(end 136.492742 -428.851314)
			)
		)
		(stroke
			(width 0)
			(type solid)
		)
		(fill yes)
		(layer "In2.Cu")
		(net "GND")
	)
	(gr_poly
		(pts
			(arc
				(start 136.492742 -427.699678)
				(mid 136.207246 -427.699678)
				(end 136.492742 -427.699678)
			)
		)
		(stroke
			(width 0)
			(type solid)
		)
		(fill yes)
		(layer "In2.Cu")
		(net "GND")
	)
	(gr_poly
		(pts
			(arc
				(start 136.492742 -426.54728)
				(mid 136.207246 -426.54728)
				(end 136.492742 -426.54728)
			)
		)
		(stroke
			(width 0)
			(type solid)
		)
		(fill yes)
		(layer "In2.Cu")
		(net "GND")
	)
	(gr_poly
		(pts
			(arc
				(start 138.492738 -438.651396)
				(mid 138.207242 -438.651396)
				(end 138.492738 -438.651396)
			)
		)
		(stroke
			(width 0)
			(type solid)
		)
		(fill yes)
		(layer "In2.Cu")
		(net "GND")
	)
	(gr_poly
		(pts
			(arc
				(start 138.492738 -437.49976)
				(mid 138.207242 -437.49976)
				(end 138.492738 -437.49976)
			)
		)
		(stroke
			(width 0)
			(type solid)
		)
		(fill yes)
		(layer "In2.Cu")
		(net "GND")
	)
	(gr_poly
		(pts
			(arc
				(start 138.492738 -436.347362)
				(mid 138.207242 -436.347362)
				(end 138.492738 -436.347362)
			)
		)
		(stroke
			(width 0)
			(type solid)
		)
		(fill yes)
		(layer "In2.Cu")
		(net "GND")
	)
	(gr_poly
		(pts
			(arc
				(start 138.492738 -435.0512)
				(mid 138.207242 -435.0512)
				(end 138.492738 -435.0512)
			)
		)
		(stroke
			(width 0)
			(type solid)
		)
		(fill yes)
		(layer "In2.Cu")
		(net "GND")
	)
	(gr_poly
		(pts
			(arc
				(start 138.492738 -433.899564)
				(mid 138.207242 -433.899564)
				(end 138.492738 -433.899564)
			)
		)
		(stroke
			(width 0)
			(type solid)
		)
		(fill yes)
		(layer "In2.Cu")
		(net "GND")
	)
	(gr_poly
		(pts
			(arc
				(start 138.492738 -432.747166)
				(mid 138.207242 -432.747166)
				(end 138.492738 -432.747166)
			)
		)
		(stroke
			(width 0)
			(type solid)
		)
		(fill yes)
		(layer "In2.Cu")
		(net "GND")
	)
	(gr_poly
		(pts
			(arc
				(start 138.492738 -431.451258)
				(mid 138.207242 -431.451258)
				(end 138.492738 -431.451258)
			)
		)
		(stroke
			(width 0)
			(type solid)
		)
		(fill yes)
		(layer "In2.Cu")
		(net "GND")
	)
	(gr_poly
		(pts
			(arc
				(start 138.492738 -430.299622)
				(mid 138.207242 -430.299622)
				(end 138.492738 -430.299622)
			)
		)
		(stroke
			(width 0)
			(type solid)
		)
		(fill yes)
		(layer "In2.Cu")
		(net "GND")
	)
	(gr_poly
		(pts
			(arc
				(start 138.492738 -429.147224)
				(mid 138.207242 -429.147224)
				(end 138.492738 -429.147224)
			)
		)
		(stroke
			(width 0)
			(type solid)
		)
		(fill yes)
		(layer "In2.Cu")
		(net "GND")
	)
	(gr_poly
		(pts
			(arc
				(start 138.492738 -427.851316)
				(mid 138.207242 -427.851316)
				(end 138.492738 -427.851316)
			)
		)
		(stroke
			(width 0)
			(type solid)
		)
		(fill yes)
		(layer "In2.Cu")
		(net "GND")
	)
	(gr_poly
		(pts
			(arc
				(start 138.492738 -426.69968)
				(mid 138.207242 -426.69968)
				(end 138.492738 -426.69968)
			)
		)
		(stroke
			(width 0)
			(type solid)
		)
		(fill yes)
		(layer "In2.Cu")
		(net "GND")
	)
	(gr_poly
		(pts
			(arc
				(start 138.492738 -425.547282)
				(mid 138.207242 -425.547282)
				(end 138.492738 -425.547282)
			)
		)
		(stroke
			(width 0)
			(type solid)
		)
		(fill yes)
		(layer "In2.Cu")
		(net "GND")
	)
	(gr_poly
		(pts
			(arc
				(start 140.492734 -439.651394)
				(mid 140.207238 -439.651394)
				(end 140.492734 -439.651394)
			)
		)
		(stroke
			(width 0)
			(type solid)
		)
		(fill yes)
		(layer "In2.Cu")
		(net "GND")
	)
	(gr_poly
		(pts
			(arc
				(start 140.492734 -438.499758)
				(mid 140.207238 -438.499758)
				(end 140.492734 -438.499758)
			)
		)
		(stroke
			(width 0)
			(type solid)
		)
		(fill yes)
		(layer "In2.Cu")
		(net "GND")
	)
	(gr_poly
		(pts
			(arc
				(start 140.492734 -437.34736)
				(mid 140.207238 -437.34736)
				(end 140.492734 -437.34736)
			)
		)
		(stroke
			(width 0)
			(type solid)
		)
		(fill yes)
		(layer "In2.Cu")
		(net "GND")
	)
	(gr_poly
		(pts
			(arc
				(start 140.492734 -436.051198)
				(mid 140.207238 -436.051198)
				(end 140.492734 -436.051198)
			)
		)
		(stroke
			(width 0)
			(type solid)
		)
		(fill yes)
		(layer "In2.Cu")
		(net "GND")
	)
	(gr_poly
		(pts
			(arc
				(start 140.492734 -434.899562)
				(mid 140.207238 -434.899562)
				(end 140.492734 -434.899562)
			)
		)
		(stroke
			(width 0)
			(type solid)
		)
		(fill yes)
		(layer "In2.Cu")
		(net "GND")
	)
	(gr_poly
		(pts
			(arc
				(start 140.492734 -433.747164)
				(mid 140.207238 -433.747164)
				(end 140.492734 -433.747164)
			)
		)
		(stroke
			(width 0)
			(type solid)
		)
		(fill yes)
		(layer "In2.Cu")
		(net "GND")
	)
	(gr_poly
		(pts
			(arc
				(start 140.492734 -432.451256)
				(mid 140.207238 -432.451256)
				(end 140.492734 -432.451256)
			)
		)
		(stroke
			(width 0)
			(type solid)
		)
		(fill yes)
		(layer "In2.Cu")
		(net "GND")
	)
	(gr_poly
		(pts
			(arc
				(start 140.492734 -431.29962)
				(mid 140.207238 -431.29962)
				(end 140.492734 -431.29962)
			)
		)
		(stroke
			(width 0)
			(type solid)
		)
		(fill yes)
		(layer "In2.Cu")
		(net "GND")
	)
	(gr_poly
		(pts
			(arc
				(start 140.492734 -430.147222)
				(mid 140.207238 -430.147222)
				(end 140.492734 -430.147222)
			)
		)
		(stroke
			(width 0)
			(type solid)
		)
		(fill yes)
		(layer "In2.Cu")
		(net "GND")
	)
	(gr_poly
		(pts
			(arc
				(start 140.492734 -428.851314)
				(mid 140.207238 -428.851314)
				(end 140.492734 -428.851314)
			)
		)
		(stroke
			(width 0)
			(type solid)
		)
		(fill yes)
		(layer "In2.Cu")
		(net "GND")
	)
	(gr_poly
		(pts
			(arc
				(start 140.492734 -427.699678)
				(mid 140.207238 -427.699678)
				(end 140.492734 -427.699678)
			)
		)
		(stroke
			(width 0)
			(type solid)
		)
		(fill yes)
		(layer "In2.Cu")
		(net "GND")
	)
	(gr_poly
		(pts
			(arc
				(start 140.492734 -426.54728)
				(mid 140.207238 -426.54728)
				(end 140.492734 -426.54728)
			)
		)
		(stroke
			(width 0)
			(type solid)
		)
		(fill yes)
		(layer "In2.Cu")
		(net "GND")
	)
	(gr_poly
		(pts
			(arc
				(start 143.492728 -438.651396)
				(mid 143.207232 -438.651396)
				(end 143.492728 -438.651396)
			)
		)
		(stroke
			(width 0)
			(type solid)
		)
		(fill yes)
		(layer "In2.Cu")
		(net "GND")
	)
	(gr_poly
		(pts
			(arc
				(start 143.492728 -437.49976)
				(mid 143.207232 -437.49976)
				(end 143.492728 -437.49976)
			)
		)
		(stroke
			(width 0)
			(type solid)
		)
		(fill yes)
		(layer "In2.Cu")
		(net "GND")
	)
	(gr_poly
		(pts
			(arc
				(start 143.492728 -436.347362)
				(mid 143.207232 -436.347362)
				(end 143.492728 -436.347362)
			)
		)
		(stroke
			(width 0)
			(type solid)
		)
		(fill yes)
		(layer "In2.Cu")
		(net "GND")
	)
	(gr_poly
		(pts
			(arc
				(start 143.492728 -435.0512)
				(mid 143.207232 -435.0512)
				(end 143.492728 -435.0512)
			)
		)
		(stroke
			(width 0)
			(type solid)
		)
		(fill yes)
		(layer "In2.Cu")
		(net "GND")
	)
	(gr_poly
		(pts
			(arc
				(start 143.492728 -433.899564)
				(mid 143.207232 -433.899564)
				(end 143.492728 -433.899564)
			)
		)
		(stroke
			(width 0)
			(type solid)
		)
		(fill yes)
		(layer "In2.Cu")
		(net "GND")
	)
	(gr_poly
		(pts
			(arc
				(start 143.492728 -432.747166)
				(mid 143.207232 -432.747166)
				(end 143.492728 -432.747166)
			)
		)
		(stroke
			(width 0)
			(type solid)
		)
		(fill yes)
		(layer "In2.Cu")
		(net "GND")
	)
	(gr_poly
		(pts
			(arc
				(start 143.492728 -431.451258)
				(mid 143.207232 -431.451258)
				(end 143.492728 -431.451258)
			)
		)
		(stroke
			(width 0)
			(type solid)
		)
		(fill yes)
		(layer "In2.Cu")
		(net "GND")
	)
	(gr_poly
		(pts
			(arc
				(start 143.492728 -430.299622)
				(mid 143.207232 -430.299622)
				(end 143.492728 -430.299622)
			)
		)
		(stroke
			(width 0)
			(type solid)
		)
		(fill yes)
		(layer "In2.Cu")
		(net "GND")
	)
	(gr_poly
		(pts
			(arc
				(start 143.492728 -429.147224)
				(mid 143.207232 -429.147224)
				(end 143.492728 -429.147224)
			)
		)
		(stroke
			(width 0)
			(type solid)
		)
		(fill yes)
		(layer "In2.Cu")
		(net "GND")
	)
	(gr_poly
		(pts
			(arc
				(start 143.492728 -427.851316)
				(mid 143.207232 -427.851316)
				(end 143.492728 -427.851316)
			)
		)
		(stroke
			(width 0)
			(type solid)
		)
		(fill yes)
		(layer "In2.Cu")
		(net "GND")
	)
	(gr_poly
		(pts
			(arc
				(start 143.492728 -426.69968)
				(mid 143.207232 -426.69968)
				(end 143.492728 -426.69968)
			)
		)
		(stroke
			(width 0)
			(type solid)
		)
		(fill yes)
		(layer "In2.Cu")
		(net "GND")
	)
	(gr_poly
		(pts
			(arc
				(start 143.492728 -425.547282)
				(mid 143.207232 -425.547282)
				(end 143.492728 -425.547282)
			)
		)
		(stroke
			(width 0)
			(type solid)
		)
		(fill yes)
		(layer "In2.Cu")
		(net "GND")
	)
	(gr_poly
		(pts
			(arc
				(start 145.492724 -439.651394)
				(mid 145.207228 -439.651394)
				(end 145.492724 -439.651394)
			)
		)
		(stroke
			(width 0)
			(type solid)
		)
		(fill yes)
		(layer "In2.Cu")
		(net "GND")
	)
	(gr_poly
		(pts
			(arc
				(start 145.492724 -438.499758)
				(mid 145.207228 -438.499758)
				(end 145.492724 -438.499758)
			)
		)
		(stroke
			(width 0)
			(type solid)
		)
		(fill yes)
		(layer "In2.Cu")
		(net "GND")
	)
	(gr_poly
		(pts
			(arc
				(start 145.492724 -437.34736)
				(mid 145.207228 -437.34736)
				(end 145.492724 -437.34736)
			)
		)
		(stroke
			(width 0)
			(type solid)
		)
		(fill yes)
		(layer "In2.Cu")
		(net "GND")
	)
	(gr_poly
		(pts
			(arc
				(start 145.492724 -436.051198)
				(mid 145.207228 -436.051198)
				(end 145.492724 -436.051198)
			)
		)
		(stroke
			(width 0)
			(type solid)
		)
		(fill yes)
		(layer "In2.Cu")
		(net "GND")
	)
	(gr_poly
		(pts
			(arc
				(start 145.492724 -434.899562)
				(mid 145.207228 -434.899562)
				(end 145.492724 -434.899562)
			)
		)
		(stroke
			(width 0)
			(type solid)
		)
		(fill yes)
		(layer "In2.Cu")
		(net "GND")
	)
	(gr_poly
		(pts
			(arc
				(start 145.492724 -433.747164)
				(mid 145.207228 -433.747164)
				(end 145.492724 -433.747164)
			)
		)
		(stroke
			(width 0)
			(type solid)
		)
		(fill yes)
		(layer "In2.Cu")
		(net "GND")
	)
	(gr_poly
		(pts
			(arc
				(start 145.492724 -432.451256)
				(mid 145.207228 -432.451256)
				(end 145.492724 -432.451256)
			)
		)
		(stroke
			(width 0)
			(type solid)
		)
		(fill yes)
		(layer "In2.Cu")
		(net "GND")
	)
	(gr_poly
		(pts
			(arc
				(start 145.492724 -431.29962)
				(mid 145.207228 -431.29962)
				(end 145.492724 -431.29962)
			)
		)
		(stroke
			(width 0)
			(type solid)
		)
		(fill yes)
		(layer "In2.Cu")
		(net "GND")
	)
	(gr_poly
		(pts
			(arc
				(start 145.492724 -430.147222)
				(mid 145.207228 -430.147222)
				(end 145.492724 -430.147222)
			)
		)
		(stroke
			(width 0)
			(type solid)
		)
		(fill yes)
		(layer "In2.Cu")
		(net "GND")
	)
	(gr_poly
		(pts
			(arc
				(start 145.492724 -428.851314)
				(mid 145.207228 -428.851314)
				(end 145.492724 -428.851314)
			)
		)
		(stroke
			(width 0)
			(type solid)
		)
		(fill yes)
		(layer "In2.Cu")
		(net "GND")
	)
	(gr_poly
		(pts
			(arc
				(start 145.492724 -427.699678)
				(mid 145.207228 -427.699678)
				(end 145.492724 -427.699678)
			)
		)
		(stroke
			(width 0)
			(type solid)
		)
		(fill yes)
		(layer "In2.Cu")
		(net "GND")
	)
	(gr_poly
		(pts
			(arc
				(start 145.492724 -426.54728)
				(mid 145.207228 -426.54728)
				(end 145.492724 -426.54728)
			)
		)
		(stroke
			(width 0)
			(type solid)
		)
		(fill yes)
		(layer "In2.Cu")
		(net "GND")
	)
	(gr_poly
		(pts
			(arc
				(start 147.49272 -438.651396)
				(mid 147.207224 -438.651396)
				(end 147.49272 -438.651396)
			)
		)
		(stroke
			(width 0)
			(type solid)
		)
		(fill yes)
		(layer "In2.Cu")
		(net "GND")
	)
	(gr_poly
		(pts
			(arc
				(start 147.49272 -437.49976)
				(mid 147.207224 -437.49976)
				(end 147.49272 -437.49976)
			)
		)
		(stroke
			(width 0)
			(type solid)
		)
		(fill yes)
		(layer "In2.Cu")
		(net "GND")
	)
	(gr_poly
		(pts
			(arc
				(start 147.49272 -436.347362)
				(mid 147.207224 -436.347362)
				(end 147.49272 -436.347362)
			)
		)
		(stroke
			(width 0)
			(type solid)
		)
		(fill yes)
		(layer "In2.Cu")
		(net "GND")
	)
	(gr_poly
		(pts
			(arc
				(start 147.49272 -435.0512)
				(mid 147.207224 -435.0512)
				(end 147.49272 -435.0512)
			)
		)
		(stroke
			(width 0)
			(type solid)
		)
		(fill yes)
		(layer "In2.Cu")
		(net "GND")
	)
	(gr_poly
		(pts
			(arc
				(start 147.49272 -433.899564)
				(mid 147.207224 -433.899564)
				(end 147.49272 -433.899564)
			)
		)
		(stroke
			(width 0)
			(type solid)
		)
		(fill yes)
		(layer "In2.Cu")
		(net "GND")
	)
	(gr_poly
		(pts
			(arc
				(start 147.49272 -432.747166)
				(mid 147.207224 -432.747166)
				(end 147.49272 -432.747166)
			)
		)
		(stroke
			(width 0)
			(type solid)
		)
		(fill yes)
		(layer "In2.Cu")
		(net "GND")
	)
	(gr_poly
		(pts
			(arc
				(start 147.49272 -431.451258)
				(mid 147.207224 -431.451258)
				(end 147.49272 -431.451258)
			)
		)
		(stroke
			(width 0)
			(type solid)
		)
		(fill yes)
		(layer "In2.Cu")
		(net "GND")
	)
	(gr_poly
		(pts
			(arc
				(start 147.49272 -430.299622)
				(mid 147.207224 -430.299622)
				(end 147.49272 -430.299622)
			)
		)
		(stroke
			(width 0)
			(type solid)
		)
		(fill yes)
		(layer "In2.Cu")
		(net "GND")
	)
	(gr_poly
		(pts
			(arc
				(start 147.49272 -429.147224)
				(mid 147.207224 -429.147224)
				(end 147.49272 -429.147224)
			)
		)
		(stroke
			(width 0)
			(type solid)
		)
		(fill yes)
		(layer "In2.Cu")
		(net "GND")
	)
	(gr_poly
		(pts
			(arc
				(start 147.49272 -427.851316)
				(mid 147.207224 -427.851316)
				(end 147.49272 -427.851316)
			)
		)
		(stroke
			(width 0)
			(type solid)
		)
		(fill yes)
		(layer "In2.Cu")
		(net "GND")
	)
	(gr_poly
		(pts
			(arc
				(start 147.49272 -426.69968)
				(mid 147.207224 -426.69968)
				(end 147.49272 -426.69968)
			)
		)
		(stroke
			(width 0)
			(type solid)
		)
		(fill yes)
		(layer "In2.Cu")
		(net "GND")
	)
	(gr_poly
		(pts
			(arc
				(start 147.49272 -425.547282)
				(mid 147.207224 -425.547282)
				(end 147.49272 -425.547282)
			)
		)
		(stroke
			(width 0)
			(type solid)
		)
		(fill yes)
		(layer "In2.Cu")
		(net "GND")
	)
	(gr_poly
		(pts
			(arc
				(start 149.492716 -439.651394)
				(mid 149.20722 -439.651394)
				(end 149.492716 -439.651394)
			)
		)
		(stroke
			(width 0)
			(type solid)
		)
		(fill yes)
		(layer "In2.Cu")
		(net "GND")
	)
	(gr_poly
		(pts
			(arc
				(start 149.492716 -438.499758)
				(mid 149.20722 -438.499758)
				(end 149.492716 -438.499758)
			)
		)
		(stroke
			(width 0)
			(type solid)
		)
		(fill yes)
		(layer "In2.Cu")
		(net "GND")
	)
	(gr_poly
		(pts
			(arc
				(start 149.492716 -437.34736)
				(mid 149.20722 -437.34736)
				(end 149.492716 -437.34736)
			)
		)
		(stroke
			(width 0)
			(type solid)
		)
		(fill yes)
		(layer "In2.Cu")
		(net "GND")
	)
	(gr_poly
		(pts
			(arc
				(start 149.492716 -436.051198)
				(mid 149.20722 -436.051198)
				(end 149.492716 -436.051198)
			)
		)
		(stroke
			(width 0)
			(type solid)
		)
		(fill yes)
		(layer "In2.Cu")
		(net "GND")
	)
	(gr_poly
		(pts
			(arc
				(start 149.492716 -434.899562)
				(mid 149.20722 -434.899562)
				(end 149.492716 -434.899562)
			)
		)
		(stroke
			(width 0)
			(type solid)
		)
		(fill yes)
		(layer "In2.Cu")
		(net "GND")
	)
	(gr_poly
		(pts
			(arc
				(start 149.492716 -433.747164)
				(mid 149.20722 -433.747164)
				(end 149.492716 -433.747164)
			)
		)
		(stroke
			(width 0)
			(type solid)
		)
		(fill yes)
		(layer "In2.Cu")
		(net "GND")
	)
	(gr_poly
		(pts
			(arc
				(start 149.492716 -432.451256)
				(mid 149.20722 -432.451256)
				(end 149.492716 -432.451256)
			)
		)
		(stroke
			(width 0)
			(type solid)
		)
		(fill yes)
		(layer "In2.Cu")
		(net "GND")
	)
	(gr_poly
		(pts
			(arc
				(start 149.492716 -431.29962)
				(mid 149.20722 -431.29962)
				(end 149.492716 -431.29962)
			)
		)
		(stroke
			(width 0)
			(type solid)
		)
		(fill yes)
		(layer "In2.Cu")
		(net "GND")
	)
	(gr_poly
		(pts
			(arc
				(start 149.492716 -430.147222)
				(mid 149.20722 -430.147222)
				(end 149.492716 -430.147222)
			)
		)
		(stroke
			(width 0)
			(type solid)
		)
		(fill yes)
		(layer "In2.Cu")
		(net "GND")
	)
	(gr_poly
		(pts
			(arc
				(start 149.492716 -428.851314)
				(mid 149.20722 -428.851314)
				(end 149.492716 -428.851314)
			)
		)
		(stroke
			(width 0)
			(type solid)
		)
		(fill yes)
		(layer "In2.Cu")
		(net "GND")
	)
	(gr_poly
		(pts
			(arc
				(start 149.492716 -427.699678)
				(mid 149.20722 -427.699678)
				(end 149.492716 -427.699678)
			)
		)
		(stroke
			(width 0)
			(type solid)
		)
		(fill yes)
		(layer "In2.Cu")
		(net "GND")
	)
	(gr_poly
		(pts
			(arc
				(start 149.492716 -426.54728)
				(mid 149.20722 -426.54728)
				(end 149.492716 -426.54728)
			)
		)
		(stroke
			(width 0)
			(type solid)
		)
		(fill yes)
		(layer "In2.Cu")
		(net "GND")
	)
	(gr_poly
		(pts
			(arc
				(start 151.492712 -438.651396)
				(mid 151.207216 -438.651396)
				(end 151.492712 -438.651396)
			)
		)
		(stroke
			(width 0)
			(type solid)
		)
		(fill yes)
		(layer "In2.Cu")
		(net "GND")
	)
	(gr_poly
		(pts
			(arc
				(start 151.492712 -437.49976)
				(mid 151.207216 -437.49976)
				(end 151.492712 -437.49976)
			)
		)
		(stroke
			(width 0)
			(type solid)
		)
		(fill yes)
		(layer "In2.Cu")
		(net "GND")
	)
	(gr_poly
		(pts
			(arc
				(start 151.492712 -436.347362)
				(mid 151.207216 -436.347362)
				(end 151.492712 -436.347362)
			)
		)
		(stroke
			(width 0)
			(type solid)
		)
		(fill yes)
		(layer "In2.Cu")
		(net "GND")
	)
	(gr_poly
		(pts
			(arc
				(start 151.492712 -435.0512)
				(mid 151.207216 -435.0512)
				(end 151.492712 -435.0512)
			)
		)
		(stroke
			(width 0)
			(type solid)
		)
		(fill yes)
		(layer "In2.Cu")
		(net "GND")
	)
	(gr_poly
		(pts
			(arc
				(start 151.492712 -433.899564)
				(mid 151.207216 -433.899564)
				(end 151.492712 -433.899564)
			)
		)
		(stroke
			(width 0)
			(type solid)
		)
		(fill yes)
		(layer "In2.Cu")
		(net "GND")
	)
	(gr_poly
		(pts
			(arc
				(start 151.492712 -432.747166)
				(mid 151.207216 -432.747166)
				(end 151.492712 -432.747166)
			)
		)
		(stroke
			(width 0)
			(type solid)
		)
		(fill yes)
		(layer "In2.Cu")
		(net "GND")
	)
	(gr_poly
		(pts
			(arc
				(start 151.492712 -431.451258)
				(mid 151.207216 -431.451258)
				(end 151.492712 -431.451258)
			)
		)
		(stroke
			(width 0)
			(type solid)
		)
		(fill yes)
		(layer "In2.Cu")
		(net "GND")
	)
	(gr_poly
		(pts
			(arc
				(start 151.492712 -430.299622)
				(mid 151.207216 -430.299622)
				(end 151.492712 -430.299622)
			)
		)
		(stroke
			(width 0)
			(type solid)
		)
		(fill yes)
		(layer "In2.Cu")
		(net "GND")
	)
	(gr_poly
		(pts
			(arc
				(start 151.492712 -429.147224)
				(mid 151.207216 -429.147224)
				(end 151.492712 -429.147224)
			)
		)
		(stroke
			(width 0)
			(type solid)
		)
		(fill yes)
		(layer "In2.Cu")
		(net "GND")
	)
	(gr_poly
		(pts
			(arc
				(start 151.492712 -427.851316)
				(mid 151.207216 -427.851316)
				(end 151.492712 -427.851316)
			)
		)
		(stroke
			(width 0)
			(type solid)
		)
		(fill yes)
		(layer "In2.Cu")
		(net "GND")
	)
	(gr_poly
		(pts
			(arc
				(start 151.492712 -426.69968)
				(mid 151.207216 -426.69968)
				(end 151.492712 -426.69968)
			)
		)
		(stroke
			(width 0)
			(type solid)
		)
		(fill yes)
		(layer "In2.Cu")
		(net "GND")
	)
	(gr_poly
		(pts
			(arc
				(start 151.492712 -425.547282)
				(mid 151.207216 -425.547282)
				(end 151.492712 -425.547282)
			)
		)
		(stroke
			(width 0)
			(type solid)
		)
		(fill yes)
		(layer "In2.Cu")
		(net "GND")
	)
	(gr_poly
		(pts
			(arc
				(start 153.492708 -439.651394)
				(mid 153.207212 -439.651394)
				(end 153.492708 -439.651394)
			)
		)
		(stroke
			(width 0)
			(type solid)
		)
		(fill yes)
		(layer "In2.Cu")
		(net "GND")
	)
	(gr_poly
		(pts
			(arc
				(start 153.492708 -438.499758)
				(mid 153.207212 -438.499758)
				(end 153.492708 -438.499758)
			)
		)
		(stroke
			(width 0)
			(type solid)
		)
		(fill yes)
		(layer "In2.Cu")
		(net "GND")
	)
	(gr_poly
		(pts
			(arc
				(start 153.492708 -437.34736)
				(mid 153.207212 -437.34736)
				(end 153.492708 -437.34736)
			)
		)
		(stroke
			(width 0)
			(type solid)
		)
		(fill yes)
		(layer "In2.Cu")
		(net "GND")
	)
	(gr_poly
		(pts
			(arc
				(start 153.492708 -436.051198)
				(mid 153.207212 -436.051198)
				(end 153.492708 -436.051198)
			)
		)
		(stroke
			(width 0)
			(type solid)
		)
		(fill yes)
		(layer "In2.Cu")
		(net "GND")
	)
	(gr_poly
		(pts
			(arc
				(start 153.492708 -434.899562)
				(mid 153.207212 -434.899562)
				(end 153.492708 -434.899562)
			)
		)
		(stroke
			(width 0)
			(type solid)
		)
		(fill yes)
		(layer "In2.Cu")
		(net "GND")
	)
	(gr_poly
		(pts
			(arc
				(start 153.492708 -433.747164)
				(mid 153.207212 -433.747164)
				(end 153.492708 -433.747164)
			)
		)
		(stroke
			(width 0)
			(type solid)
		)
		(fill yes)
		(layer "In2.Cu")
		(net "GND")
	)
	(gr_poly
		(pts
			(arc
				(start 153.492708 -432.451256)
				(mid 153.207212 -432.451256)
				(end 153.492708 -432.451256)
			)
		)
		(stroke
			(width 0)
			(type solid)
		)
		(fill yes)
		(layer "In2.Cu")
		(net "GND")
	)
	(gr_poly
		(pts
			(arc
				(start 153.492708 -431.29962)
				(mid 153.207212 -431.29962)
				(end 153.492708 -431.29962)
			)
		)
		(stroke
			(width 0)
			(type solid)
		)
		(fill yes)
		(layer "In2.Cu")
		(net "GND")
	)
	(gr_poly
		(pts
			(arc
				(start 153.492708 -430.147222)
				(mid 153.207212 -430.147222)
				(end 153.492708 -430.147222)
			)
		)
		(stroke
			(width 0)
			(type solid)
		)
		(fill yes)
		(layer "In2.Cu")
		(net "GND")
	)
	(gr_poly
		(pts
			(arc
				(start 153.492708 -428.851314)
				(mid 153.207212 -428.851314)
				(end 153.492708 -428.851314)
			)
		)
		(stroke
			(width 0)
			(type solid)
		)
		(fill yes)
		(layer "In2.Cu")
		(net "GND")
	)
	(gr_poly
		(pts
			(arc
				(start 153.492708 -427.699678)
				(mid 153.207212 -427.699678)
				(end 153.492708 -427.699678)
			)
		)
		(stroke
			(width 0)
			(type solid)
		)
		(fill yes)
		(layer "In2.Cu")
		(net "GND")
	)
	(gr_poly
		(pts
			(arc
				(start 153.492708 -426.54728)
				(mid 153.207212 -426.54728)
				(end 153.492708 -426.54728)
			)
		)
		(stroke
			(width 0)
			(type solid)
		)
		(fill yes)
		(layer "In2.Cu")
		(net "GND")
	)
	(gr_poly
		(pts
			(arc
				(start 155.492704 -438.651396)
				(mid 155.207208 -438.651396)
				(end 155.492704 -438.651396)
			)
		)
		(stroke
			(width 0)
			(type solid)
		)
		(fill yes)
		(layer "In2.Cu")
		(net "GND")
	)
	(gr_poly
		(pts
			(arc
				(start 155.492704 -437.49976)
				(mid 155.207208 -437.49976)
				(end 155.492704 -437.49976)
			)
		)
		(stroke
			(width 0)
			(type solid)
		)
		(fill yes)
		(layer "In2.Cu")
		(net "GND")
	)
	(gr_poly
		(pts
			(arc
				(start 155.492704 -436.347362)
				(mid 155.207208 -436.347362)
				(end 155.492704 -436.347362)
			)
		)
		(stroke
			(width 0)
			(type solid)
		)
		(fill yes)
		(layer "In2.Cu")
		(net "GND")
	)
	(gr_poly
		(pts
			(arc
				(start 155.492704 -435.0512)
				(mid 155.207208 -435.0512)
				(end 155.492704 -435.0512)
			)
		)
		(stroke
			(width 0)
			(type solid)
		)
		(fill yes)
		(layer "In2.Cu")
		(net "GND")
	)
	(gr_poly
		(pts
			(arc
				(start 155.492704 -433.899564)
				(mid 155.207208 -433.899564)
				(end 155.492704 -433.899564)
			)
		)
		(stroke
			(width 0)
			(type solid)
		)
		(fill yes)
		(layer "In2.Cu")
		(net "GND")
	)
	(gr_poly
		(pts
			(arc
				(start 155.492704 -432.747166)
				(mid 155.207208 -432.747166)
				(end 155.492704 -432.747166)
			)
		)
		(stroke
			(width 0)
			(type solid)
		)
		(fill yes)
		(layer "In2.Cu")
		(net "GND")
	)
	(gr_poly
		(pts
			(arc
				(start 155.492704 -431.451258)
				(mid 155.207208 -431.451258)
				(end 155.492704 -431.451258)
			)
		)
		(stroke
			(width 0)
			(type solid)
		)
		(fill yes)
		(layer "In2.Cu")
		(net "GND")
	)
	(gr_poly
		(pts
			(arc
				(start 155.492704 -430.299622)
				(mid 155.207208 -430.299622)
				(end 155.492704 -430.299622)
			)
		)
		(stroke
			(width 0)
			(type solid)
		)
		(fill yes)
		(layer "In2.Cu")
		(net "GND")
	)
	(gr_poly
		(pts
			(arc
				(start 155.492704 -429.147224)
				(mid 155.207208 -429.147224)
				(end 155.492704 -429.147224)
			)
		)
		(stroke
			(width 0)
			(type solid)
		)
		(fill yes)
		(layer "In2.Cu")
		(net "GND")
	)
	(gr_poly
		(pts
			(arc
				(start 155.492704 -427.851316)
				(mid 155.207208 -427.851316)
				(end 155.492704 -427.851316)
			)
		)
		(stroke
			(width 0)
			(type solid)
		)
		(fill yes)
		(layer "In2.Cu")
		(net "GND")
	)
	(gr_poly
		(pts
			(arc
				(start 155.492704 -426.69968)
				(mid 155.207208 -426.69968)
				(end 155.492704 -426.69968)
			)
		)
		(stroke
			(width 0)
			(type solid)
		)
		(fill yes)
		(layer "In2.Cu")
		(net "GND")
	)
	(gr_poly
		(pts
			(arc
				(start 155.492704 -425.547282)
				(mid 155.207208 -425.547282)
				(end 155.492704 -425.547282)
			)
		)
		(stroke
			(width 0)
			(type solid)
		)
		(fill yes)
		(layer "In2.Cu")
		(net "GND")
	)
	(gr_poly
		(pts
			(arc
				(start 157.4927 -439.651394)
				(mid 157.207204 -439.651394)
				(end 157.4927 -439.651394)
			)
		)
		(stroke
			(width 0)
			(type solid)
		)
		(fill yes)
		(layer "In2.Cu")
		(net "GND")
	)
	(gr_poly
		(pts
			(arc
				(start 157.4927 -438.499758)
				(mid 157.207204 -438.499758)
				(end 157.4927 -438.499758)
			)
		)
		(stroke
			(width 0)
			(type solid)
		)
		(fill yes)
		(layer "In2.Cu")
		(net "GND")
	)
	(gr_poly
		(pts
			(arc
				(start 157.4927 -437.34736)
				(mid 157.207204 -437.34736)
				(end 157.4927 -437.34736)
			)
		)
		(stroke
			(width 0)
			(type solid)
		)
		(fill yes)
		(layer "In2.Cu")
		(net "GND")
	)
	(gr_poly
		(pts
			(arc
				(start 157.4927 -436.051198)
				(mid 157.207204 -436.051198)
				(end 157.4927 -436.051198)
			)
		)
		(stroke
			(width 0)
			(type solid)
		)
		(fill yes)
		(layer "In2.Cu")
		(net "GND")
	)
	(gr_poly
		(pts
			(arc
				(start 157.4927 -434.899562)
				(mid 157.207204 -434.899562)
				(end 157.4927 -434.899562)
			)
		)
		(stroke
			(width 0)
			(type solid)
		)
		(fill yes)
		(layer "In2.Cu")
		(net "GND")
	)
	(gr_poly
		(pts
			(arc
				(start 157.4927 -433.747164)
				(mid 157.207204 -433.747164)
				(end 157.4927 -433.747164)
			)
		)
		(stroke
			(width 0)
			(type solid)
		)
		(fill yes)
		(layer "In2.Cu")
		(net "GND")
	)
	(gr_poly
		(pts
			(arc
				(start 157.4927 -432.451256)
				(mid 157.207204 -432.451256)
				(end 157.4927 -432.451256)
			)
		)
		(stroke
			(width 0)
			(type solid)
		)
		(fill yes)
		(layer "In2.Cu")
		(net "GND")
	)
	(gr_poly
		(pts
			(arc
				(start 157.4927 -431.29962)
				(mid 157.207204 -431.29962)
				(end 157.4927 -431.29962)
			)
		)
		(stroke
			(width 0)
			(type solid)
		)
		(fill yes)
		(layer "In2.Cu")
		(net "GND")
	)
	(gr_poly
		(pts
			(arc
				(start 157.4927 -430.147222)
				(mid 157.207204 -430.147222)
				(end 157.4927 -430.147222)
			)
		)
		(stroke
			(width 0)
			(type solid)
		)
		(fill yes)
		(layer "In2.Cu")
		(net "GND")
	)
	(gr_poly
		(pts
			(arc
				(start 157.4927 -428.851314)
				(mid 157.207204 -428.851314)
				(end 157.4927 -428.851314)
			)
		)
		(stroke
			(width 0)
			(type solid)
		)
		(fill yes)
		(layer "In2.Cu")
		(net "GND")
	)
	(gr_poly
		(pts
			(arc
				(start 157.4927 -427.699678)
				(mid 157.207204 -427.699678)
				(end 157.4927 -427.699678)
			)
		)
		(stroke
			(width 0)
			(type solid)
		)
		(fill yes)
		(layer "In2.Cu")
		(net "GND")
	)
	(gr_poly
		(pts
			(arc
				(start 157.4927 -426.54728)
				(mid 157.207204 -426.54728)
				(end 157.4927 -426.54728)
			)
		)
		(stroke
			(width 0)
			(type solid)
		)
		(fill yes)
		(layer "In2.Cu")
		(net "GND")
	)
	(gr_poly
		(pts
			(arc
				(start 315.392816 -438.651396)
				(mid 315.10732 -438.651396)
				(end 315.392816 -438.651396)
			)
		)
		(stroke
			(width 0)
			(type solid)
		)
		(fill yes)
		(layer "In2.Cu")
		(net "GND")
	)
	(gr_poly
		(pts
			(arc
				(start 315.392816 -437.49976)
				(mid 315.10732 -437.49976)
				(end 315.392816 -437.49976)
			)
		)
		(stroke
			(width 0)
			(type solid)
		)
		(fill yes)
		(layer "In2.Cu")
		(net "GND")
	)
	(gr_poly
		(pts
			(arc
				(start 315.392816 -436.347362)
				(mid 315.10732 -436.347362)
				(end 315.392816 -436.347362)
			)
		)
		(stroke
			(width 0)
			(type solid)
		)
		(fill yes)
		(layer "In2.Cu")
		(net "GND")
	)
	(gr_poly
		(pts
			(arc
				(start 315.392816 -435.0512)
				(mid 315.10732 -435.0512)
				(end 315.392816 -435.0512)
			)
		)
		(stroke
			(width 0)
			(type solid)
		)
		(fill yes)
		(layer "In2.Cu")
		(net "GND")
	)
	(gr_poly
		(pts
			(arc
				(start 315.392816 -433.899564)
				(mid 315.10732 -433.899564)
				(end 315.392816 -433.899564)
			)
		)
		(stroke
			(width 0)
			(type solid)
		)
		(fill yes)
		(layer "In2.Cu")
		(net "GND")
	)
	(gr_poly
		(pts
			(arc
				(start 315.392816 -432.747166)
				(mid 315.10732 -432.747166)
				(end 315.392816 -432.747166)
			)
		)
		(stroke
			(width 0)
			(type solid)
		)
		(fill yes)
		(layer "In2.Cu")
		(net "GND")
	)
	(gr_poly
		(pts
			(arc
				(start 315.392816 -431.451258)
				(mid 315.10732 -431.451258)
				(end 315.392816 -431.451258)
			)
		)
		(stroke
			(width 0)
			(type solid)
		)
		(fill yes)
		(layer "In2.Cu")
		(net "GND")
	)
	(gr_poly
		(pts
			(arc
				(start 315.392816 -430.299622)
				(mid 315.10732 -430.299622)
				(end 315.392816 -430.299622)
			)
		)
		(stroke
			(width 0)
			(type solid)
		)
		(fill yes)
		(layer "In2.Cu")
		(net "GND")
	)
	(gr_poly
		(pts
			(arc
				(start 315.392816 -429.147224)
				(mid 315.10732 -429.147224)
				(end 315.392816 -429.147224)
			)
		)
		(stroke
			(width 0)
			(type solid)
		)
		(fill yes)
		(layer "In2.Cu")
		(net "GND")
	)
	(gr_poly
		(pts
			(arc
				(start 315.392816 -427.851316)
				(mid 315.10732 -427.851316)
				(end 315.392816 -427.851316)
			)
		)
		(stroke
			(width 0)
			(type solid)
		)
		(fill yes)
		(layer "In2.Cu")
		(net "GND")
	)
	(gr_poly
		(pts
			(arc
				(start 315.392816 -426.69968)
				(mid 315.10732 -426.69968)
				(end 315.392816 -426.69968)
			)
		)
		(stroke
			(width 0)
			(type solid)
		)
		(fill yes)
		(layer "In2.Cu")
		(net "GND")
	)
	(gr_poly
		(pts
			(arc
				(start 315.392816 -425.547282)
				(mid 315.10732 -425.547282)
				(end 315.392816 -425.547282)
			)
		)
		(stroke
			(width 0)
			(type solid)
		)
		(fill yes)
		(layer "In2.Cu")
		(net "GND")
	)
	(gr_poly
		(pts
			(arc
				(start 317.392812 -439.651394)
				(mid 317.107316 -439.651394)
				(end 317.392812 -439.651394)
			)
		)
		(stroke
			(width 0)
			(type solid)
		)
		(fill yes)
		(layer "In2.Cu")
		(net "GND")
	)
	(gr_poly
		(pts
			(arc
				(start 317.392812 -438.499758)
				(mid 317.107316 -438.499758)
				(end 317.392812 -438.499758)
			)
		)
		(stroke
			(width 0)
			(type solid)
		)
		(fill yes)
		(layer "In2.Cu")
		(net "GND")
	)
	(gr_poly
		(pts
			(arc
				(start 317.392812 -437.34736)
				(mid 317.107316 -437.34736)
				(end 317.392812 -437.34736)
			)
		)
		(stroke
			(width 0)
			(type solid)
		)
		(fill yes)
		(layer "In2.Cu")
		(net "GND")
	)
	(gr_poly
		(pts
			(arc
				(start 317.392812 -436.051198)
				(mid 317.107316 -436.051198)
				(end 317.392812 -436.051198)
			)
		)
		(stroke
			(width 0)
			(type solid)
		)
		(fill yes)
		(layer "In2.Cu")
		(net "GND")
	)
	(gr_poly
		(pts
			(arc
				(start 317.392812 -434.899562)
				(mid 317.107316 -434.899562)
				(end 317.392812 -434.899562)
			)
		)
		(stroke
			(width 0)
			(type solid)
		)
		(fill yes)
		(layer "In2.Cu")
		(net "GND")
	)
	(gr_poly
		(pts
			(arc
				(start 317.392812 -433.747164)
				(mid 317.107316 -433.747164)
				(end 317.392812 -433.747164)
			)
		)
		(stroke
			(width 0)
			(type solid)
		)
		(fill yes)
		(layer "In2.Cu")
		(net "GND")
	)
	(gr_poly
		(pts
			(arc
				(start 317.392812 -432.451256)
				(mid 317.107316 -432.451256)
				(end 317.392812 -432.451256)
			)
		)
		(stroke
			(width 0)
			(type solid)
		)
		(fill yes)
		(layer "In2.Cu")
		(net "GND")
	)
	(gr_poly
		(pts
			(arc
				(start 317.392812 -431.29962)
				(mid 317.107316 -431.29962)
				(end 317.392812 -431.29962)
			)
		)
		(stroke
			(width 0)
			(type solid)
		)
		(fill yes)
		(layer "In2.Cu")
		(net "GND")
	)
	(gr_poly
		(pts
			(arc
				(start 317.392812 -430.147222)
				(mid 317.107316 -430.147222)
				(end 317.392812 -430.147222)
			)
		)
		(stroke
			(width 0)
			(type solid)
		)
		(fill yes)
		(layer "In2.Cu")
		(net "GND")
	)
	(gr_poly
		(pts
			(arc
				(start 317.392812 -428.851314)
				(mid 317.107316 -428.851314)
				(end 317.392812 -428.851314)
			)
		)
		(stroke
			(width 0)
			(type solid)
		)
		(fill yes)
		(layer "In2.Cu")
		(net "GND")
	)
	(gr_poly
		(pts
			(arc
				(start 317.392812 -427.699678)
				(mid 317.107316 -427.699678)
				(end 317.392812 -427.699678)
			)
		)
		(stroke
			(width 0)
			(type solid)
		)
		(fill yes)
		(layer "In2.Cu")
		(net "GND")
	)
	(gr_poly
		(pts
			(arc
				(start 317.392812 -426.54728)
				(mid 317.107316 -426.54728)
				(end 317.392812 -426.54728)
			)
		)
		(stroke
			(width 0)
			(type solid)
		)
		(fill yes)
		(layer "In2.Cu")
		(net "GND")
	)
	(gr_poly
		(pts
			(arc
				(start 319.392808 -438.651396)
				(mid 319.107312 -438.651396)
				(end 319.392808 -438.651396)
			)
		)
		(stroke
			(width 0)
			(type solid)
		)
		(fill yes)
		(layer "In2.Cu")
		(net "GND")
	)
	(gr_poly
		(pts
			(arc
				(start 319.392808 -437.49976)
				(mid 319.107312 -437.49976)
				(end 319.392808 -437.49976)
			)
		)
		(stroke
			(width 0)
			(type solid)
		)
		(fill yes)
		(layer "In2.Cu")
		(net "GND")
	)
	(gr_poly
		(pts
			(arc
				(start 319.392808 -436.347362)
				(mid 319.107312 -436.347362)
				(end 319.392808 -436.347362)
			)
		)
		(stroke
			(width 0)
			(type solid)
		)
		(fill yes)
		(layer "In2.Cu")
		(net "GND")
	)
	(gr_poly
		(pts
			(arc
				(start 319.392808 -435.0512)
				(mid 319.107312 -435.0512)
				(end 319.392808 -435.0512)
			)
		)
		(stroke
			(width 0)
			(type solid)
		)
		(fill yes)
		(layer "In2.Cu")
		(net "GND")
	)
	(gr_poly
		(pts
			(arc
				(start 319.392808 -433.899564)
				(mid 319.107312 -433.899564)
				(end 319.392808 -433.899564)
			)
		)
		(stroke
			(width 0)
			(type solid)
		)
		(fill yes)
		(layer "In2.Cu")
		(net "GND")
	)
	(gr_poly
		(pts
			(arc
				(start 319.392808 -432.747166)
				(mid 319.107312 -432.747166)
				(end 319.392808 -432.747166)
			)
		)
		(stroke
			(width 0)
			(type solid)
		)
		(fill yes)
		(layer "In2.Cu")
		(net "GND")
	)
	(gr_poly
		(pts
			(arc
				(start 319.392808 -431.451258)
				(mid 319.107312 -431.451258)
				(end 319.392808 -431.451258)
			)
		)
		(stroke
			(width 0)
			(type solid)
		)
		(fill yes)
		(layer "In2.Cu")
		(net "GND")
	)
	(gr_poly
		(pts
			(arc
				(start 319.392808 -430.299622)
				(mid 319.107312 -430.299622)
				(end 319.392808 -430.299622)
			)
		)
		(stroke
			(width 0)
			(type solid)
		)
		(fill yes)
		(layer "In2.Cu")
		(net "GND")
	)
	(gr_poly
		(pts
			(arc
				(start 319.392808 -429.147224)
				(mid 319.107312 -429.147224)
				(end 319.392808 -429.147224)
			)
		)
		(stroke
			(width 0)
			(type solid)
		)
		(fill yes)
		(layer "In2.Cu")
		(net "GND")
	)
	(gr_poly
		(pts
			(arc
				(start 319.392808 -427.851316)
				(mid 319.107312 -427.851316)
				(end 319.392808 -427.851316)
			)
		)
		(stroke
			(width 0)
			(type solid)
		)
		(fill yes)
		(layer "In2.Cu")
		(net "GND")
	)
	(gr_poly
		(pts
			(arc
				(start 319.392808 -426.69968)
				(mid 319.107312 -426.69968)
				(end 319.392808 -426.69968)
			)
		)
		(stroke
			(width 0)
			(type solid)
		)
		(fill yes)
		(layer "In2.Cu")
		(net "GND")
	)
	(gr_poly
		(pts
			(arc
				(start 319.392808 -425.547282)
				(mid 319.107312 -425.547282)
				(end 319.392808 -425.547282)
			)
		)
		(stroke
			(width 0)
			(type solid)
		)
		(fill yes)
		(layer "In2.Cu")
		(net "GND")
	)
	(gr_poly
		(pts
			(arc
				(start 321.392804 -439.651394)
				(mid 321.107308 -439.651394)
				(end 321.392804 -439.651394)
			)
		)
		(stroke
			(width 0)
			(type solid)
		)
		(fill yes)
		(layer "In2.Cu")
		(net "GND")
	)
	(gr_poly
		(pts
			(arc
				(start 321.392804 -438.499758)
				(mid 321.107308 -438.499758)
				(end 321.392804 -438.499758)
			)
		)
		(stroke
			(width 0)
			(type solid)
		)
		(fill yes)
		(layer "In2.Cu")
		(net "GND")
	)
	(gr_poly
		(pts
			(arc
				(start 321.392804 -437.34736)
				(mid 321.107308 -437.34736)
				(end 321.392804 -437.34736)
			)
		)
		(stroke
			(width 0)
			(type solid)
		)
		(fill yes)
		(layer "In2.Cu")
		(net "GND")
	)
	(gr_poly
		(pts
			(arc
				(start 321.392804 -436.051198)
				(mid 321.107308 -436.051198)
				(end 321.392804 -436.051198)
			)
		)
		(stroke
			(width 0)
			(type solid)
		)
		(fill yes)
		(layer "In2.Cu")
		(net "GND")
	)
	(gr_poly
		(pts
			(arc
				(start 321.392804 -434.899562)
				(mid 321.107308 -434.899562)
				(end 321.392804 -434.899562)
			)
		)
		(stroke
			(width 0)
			(type solid)
		)
		(fill yes)
		(layer "In2.Cu")
		(net "GND")
	)
	(gr_poly
		(pts
			(arc
				(start 321.392804 -433.747164)
				(mid 321.107308 -433.747164)
				(end 321.392804 -433.747164)
			)
		)
		(stroke
			(width 0)
			(type solid)
		)
		(fill yes)
		(layer "In2.Cu")
		(net "GND")
	)
	(gr_poly
		(pts
			(arc
				(start 321.392804 -432.451256)
				(mid 321.107308 -432.451256)
				(end 321.392804 -432.451256)
			)
		)
		(stroke
			(width 0)
			(type solid)
		)
		(fill yes)
		(layer "In2.Cu")
		(net "GND")
	)
	(gr_poly
		(pts
			(arc
				(start 321.392804 -431.29962)
				(mid 321.107308 -431.29962)
				(end 321.392804 -431.29962)
			)
		)
		(stroke
			(width 0)
			(type solid)
		)
		(fill yes)
		(layer "In2.Cu")
		(net "GND")
	)
	(gr_poly
		(pts
			(arc
				(start 321.392804 -430.147222)
				(mid 321.107308 -430.147222)
				(end 321.392804 -430.147222)
			)
		)
		(stroke
			(width 0)
			(type solid)
		)
		(fill yes)
		(layer "In2.Cu")
		(net "GND")
	)
	(gr_poly
		(pts
			(arc
				(start 321.392804 -428.851314)
				(mid 321.107308 -428.851314)
				(end 321.392804 -428.851314)
			)
		)
		(stroke
			(width 0)
			(type solid)
		)
		(fill yes)
		(layer "In2.Cu")
		(net "GND")
	)
	(gr_poly
		(pts
			(arc
				(start 321.392804 -427.699678)
				(mid 321.107308 -427.699678)
				(end 321.392804 -427.699678)
			)
		)
		(stroke
			(width 0)
			(type solid)
		)
		(fill yes)
		(layer "In2.Cu")
		(net "GND")
	)
	(gr_poly
		(pts
			(arc
				(start 321.392804 -426.54728)
				(mid 321.107308 -426.54728)
				(end 321.392804 -426.54728)
			)
		)
		(stroke
			(width 0)
			(type solid)
		)
		(fill yes)
		(layer "In2.Cu")
		(net "GND")
	)
	(gr_poly
		(pts
			(arc
				(start 323.3928 -438.651396)
				(mid 323.107304 -438.651396)
				(end 323.3928 -438.651396)
			)
		)
		(stroke
			(width 0)
			(type solid)
		)
		(fill yes)
		(layer "In2.Cu")
		(net "GND")
	)
	(gr_poly
		(pts
			(arc
				(start 323.3928 -437.49976)
				(mid 323.107304 -437.49976)
				(end 323.3928 -437.49976)
			)
		)
		(stroke
			(width 0)
			(type solid)
		)
		(fill yes)
		(layer "In2.Cu")
		(net "GND")
	)
	(gr_poly
		(pts
			(arc
				(start 323.3928 -436.347362)
				(mid 323.107304 -436.347362)
				(end 323.3928 -436.347362)
			)
		)
		(stroke
			(width 0)
			(type solid)
		)
		(fill yes)
		(layer "In2.Cu")
		(net "GND")
	)
	(gr_poly
		(pts
			(arc
				(start 323.3928 -435.0512)
				(mid 323.107304 -435.0512)
				(end 323.3928 -435.0512)
			)
		)
		(stroke
			(width 0)
			(type solid)
		)
		(fill yes)
		(layer "In2.Cu")
		(net "GND")
	)
	(gr_poly
		(pts
			(arc
				(start 323.3928 -433.899564)
				(mid 323.107304 -433.899564)
				(end 323.3928 -433.899564)
			)
		)
		(stroke
			(width 0)
			(type solid)
		)
		(fill yes)
		(layer "In2.Cu")
		(net "GND")
	)
	(gr_poly
		(pts
			(arc
				(start 323.3928 -432.747166)
				(mid 323.107304 -432.747166)
				(end 323.3928 -432.747166)
			)
		)
		(stroke
			(width 0)
			(type solid)
		)
		(fill yes)
		(layer "In2.Cu")
		(net "GND")
	)
	(gr_poly
		(pts
			(arc
				(start 323.3928 -431.451258)
				(mid 323.107304 -431.451258)
				(end 323.3928 -431.451258)
			)
		)
		(stroke
			(width 0)
			(type solid)
		)
		(fill yes)
		(layer "In2.Cu")
		(net "GND")
	)
	(gr_poly
		(pts
			(arc
				(start 323.3928 -430.299622)
				(mid 323.107304 -430.299622)
				(end 323.3928 -430.299622)
			)
		)
		(stroke
			(width 0)
			(type solid)
		)
		(fill yes)
		(layer "In2.Cu")
		(net "GND")
	)
	(gr_poly
		(pts
			(arc
				(start 323.3928 -429.147224)
				(mid 323.107304 -429.147224)
				(end 323.3928 -429.147224)
			)
		)
		(stroke
			(width 0)
			(type solid)
		)
		(fill yes)
		(layer "In2.Cu")
		(net "GND")
	)
	(gr_poly
		(pts
			(arc
				(start 323.3928 -427.851316)
				(mid 323.107304 -427.851316)
				(end 323.3928 -427.851316)
			)
		)
		(stroke
			(width 0)
			(type solid)
		)
		(fill yes)
		(layer "In2.Cu")
		(net "GND")
	)
	(gr_poly
		(pts
			(arc
				(start 323.3928 -426.69968)
				(mid 323.107304 -426.69968)
				(end 323.3928 -426.69968)
			)
		)
		(stroke
			(width 0)
			(type solid)
		)
		(fill yes)
		(layer "In2.Cu")
		(net "GND")
	)
	(gr_poly
		(pts
			(arc
				(start 323.3928 -425.547282)
				(mid 323.107304 -425.547282)
				(end 323.3928 -425.547282)
			)
		)
		(stroke
			(width 0)
			(type solid)
		)
		(fill yes)
		(layer "In2.Cu")
		(net "GND")
	)
	(gr_poly
		(pts
			(arc
				(start 325.392796 -439.651394)
				(mid 325.1073 -439.651394)
				(end 325.392796 -439.651394)
			)
		)
		(stroke
			(width 0)
			(type solid)
		)
		(fill yes)
		(layer "In2.Cu")
		(net "GND")
	)
	(gr_poly
		(pts
			(arc
				(start 325.392796 -438.499758)
				(mid 325.1073 -438.499758)
				(end 325.392796 -438.499758)
			)
		)
		(stroke
			(width 0)
			(type solid)
		)
		(fill yes)
		(layer "In2.Cu")
		(net "GND")
	)
	(gr_poly
		(pts
			(arc
				(start 325.392796 -437.34736)
				(mid 325.1073 -437.34736)
				(end 325.392796 -437.34736)
			)
		)
		(stroke
			(width 0)
			(type solid)
		)
		(fill yes)
		(layer "In2.Cu")
		(net "GND")
	)
	(gr_poly
		(pts
			(arc
				(start 325.392796 -436.051198)
				(mid 325.1073 -436.051198)
				(end 325.392796 -436.051198)
			)
		)
		(stroke
			(width 0)
			(type solid)
		)
		(fill yes)
		(layer "In2.Cu")
		(net "GND")
	)
	(gr_poly
		(pts
			(arc
				(start 325.392796 -434.899562)
				(mid 325.1073 -434.899562)
				(end 325.392796 -434.899562)
			)
		)
		(stroke
			(width 0)
			(type solid)
		)
		(fill yes)
		(layer "In2.Cu")
		(net "GND")
	)
	(gr_poly
		(pts
			(arc
				(start 325.392796 -433.747164)
				(mid 325.1073 -433.747164)
				(end 325.392796 -433.747164)
			)
		)
		(stroke
			(width 0)
			(type solid)
		)
		(fill yes)
		(layer "In2.Cu")
		(net "GND")
	)
	(gr_poly
		(pts
			(arc
				(start 325.392796 -432.451256)
				(mid 325.1073 -432.451256)
				(end 325.392796 -432.451256)
			)
		)
		(stroke
			(width 0)
			(type solid)
		)
		(fill yes)
		(layer "In2.Cu")
		(net "GND")
	)
	(gr_poly
		(pts
			(arc
				(start 325.392796 -431.29962)
				(mid 325.1073 -431.29962)
				(end 325.392796 -431.29962)
			)
		)
		(stroke
			(width 0)
			(type solid)
		)
		(fill yes)
		(layer "In2.Cu")
		(net "GND")
	)
	(gr_poly
		(pts
			(arc
				(start 325.392796 -430.147222)
				(mid 325.1073 -430.147222)
				(end 325.392796 -430.147222)
			)
		)
		(stroke
			(width 0)
			(type solid)
		)
		(fill yes)
		(layer "In2.Cu")
		(net "GND")
	)
	(gr_poly
		(pts
			(arc
				(start 325.392796 -428.851314)
				(mid 325.1073 -428.851314)
				(end 325.392796 -428.851314)
			)
		)
		(stroke
			(width 0)
			(type solid)
		)
		(fill yes)
		(layer "In2.Cu")
		(net "GND")
	)
	(gr_poly
		(pts
			(arc
				(start 325.392796 -427.699678)
				(mid 325.1073 -427.699678)
				(end 325.392796 -427.699678)
			)
		)
		(stroke
			(width 0)
			(type solid)
		)
		(fill yes)
		(layer "In2.Cu")
		(net "GND")
	)
	(gr_poly
		(pts
			(arc
				(start 325.392796 -426.54728)
				(mid 325.1073 -426.54728)
				(end 325.392796 -426.54728)
			)
		)
		(stroke
			(width 0)
			(type solid)
		)
		(fill yes)
		(layer "In2.Cu")
		(net "GND")
	)
	(gr_poly
		(pts
			(arc
				(start 327.392792 -438.651396)
				(mid 327.107296 -438.651396)
				(end 327.392792 -438.651396)
			)
		)
		(stroke
			(width 0)
			(type solid)
		)
		(fill yes)
		(layer "In2.Cu")
		(net "GND")
	)
	(gr_poly
		(pts
			(arc
				(start 327.392792 -437.49976)
				(mid 327.107296 -437.49976)
				(end 327.392792 -437.49976)
			)
		)
		(stroke
			(width 0)
			(type solid)
		)
		(fill yes)
		(layer "In2.Cu")
		(net "GND")
	)
	(gr_poly
		(pts
			(arc
				(start 327.392792 -436.347362)
				(mid 327.107296 -436.347362)
				(end 327.392792 -436.347362)
			)
		)
		(stroke
			(width 0)
			(type solid)
		)
		(fill yes)
		(layer "In2.Cu")
		(net "GND")
	)
	(gr_poly
		(pts
			(arc
				(start 327.392792 -435.0512)
				(mid 327.107296 -435.0512)
				(end 327.392792 -435.0512)
			)
		)
		(stroke
			(width 0)
			(type solid)
		)
		(fill yes)
		(layer "In2.Cu")
		(net "GND")
	)
	(gr_poly
		(pts
			(arc
				(start 327.392792 -433.899564)
				(mid 327.107296 -433.899564)
				(end 327.392792 -433.899564)
			)
		)
		(stroke
			(width 0)
			(type solid)
		)
		(fill yes)
		(layer "In2.Cu")
		(net "GND")
	)
	(gr_poly
		(pts
			(arc
				(start 327.392792 -432.747166)
				(mid 327.107296 -432.747166)
				(end 327.392792 -432.747166)
			)
		)
		(stroke
			(width 0)
			(type solid)
		)
		(fill yes)
		(layer "In2.Cu")
		(net "GND")
	)
	(gr_poly
		(pts
			(arc
				(start 327.392792 -431.451258)
				(mid 327.107296 -431.451258)
				(end 327.392792 -431.451258)
			)
		)
		(stroke
			(width 0)
			(type solid)
		)
		(fill yes)
		(layer "In2.Cu")
		(net "GND")
	)
	(gr_poly
		(pts
			(arc
				(start 327.392792 -430.299622)
				(mid 327.107296 -430.299622)
				(end 327.392792 -430.299622)
			)
		)
		(stroke
			(width 0)
			(type solid)
		)
		(fill yes)
		(layer "In2.Cu")
		(net "GND")
	)
	(gr_poly
		(pts
			(arc
				(start 327.392792 -429.147224)
				(mid 327.107296 -429.147224)
				(end 327.392792 -429.147224)
			)
		)
		(stroke
			(width 0)
			(type solid)
		)
		(fill yes)
		(layer "In2.Cu")
		(net "GND")
	)
	(gr_poly
		(pts
			(arc
				(start 327.392792 -427.851316)
				(mid 327.107296 -427.851316)
				(end 327.392792 -427.851316)
			)
		)
		(stroke
			(width 0)
			(type solid)
		)
		(fill yes)
		(layer "In2.Cu")
		(net "GND")
	)
	(gr_poly
		(pts
			(arc
				(start 327.392792 -426.69968)
				(mid 327.107296 -426.69968)
				(end 327.392792 -426.69968)
			)
		)
		(stroke
			(width 0)
			(type solid)
		)
		(fill yes)
		(layer "In2.Cu")
		(net "GND")
	)
	(gr_poly
		(pts
			(arc
				(start 327.392792 -425.547282)
				(mid 327.107296 -425.547282)
				(end 327.392792 -425.547282)
			)
		)
		(stroke
			(width 0)
			(type solid)
		)
		(fill yes)
		(layer "In2.Cu")
		(net "GND")
	)
	(gr_poly
		(pts
			(arc
				(start 329.392788 -439.651394)
				(mid 329.107292 -439.651394)
				(end 329.392788 -439.651394)
			)
		)
		(stroke
			(width 0)
			(type solid)
		)
		(fill yes)
		(layer "In2.Cu")
		(net "GND")
	)
	(gr_poly
		(pts
			(arc
				(start 329.392788 -438.499758)
				(mid 329.107292 -438.499758)
				(end 329.392788 -438.499758)
			)
		)
		(stroke
			(width 0)
			(type solid)
		)
		(fill yes)
		(layer "In2.Cu")
		(net "GND")
	)
	(gr_poly
		(pts
			(arc
				(start 329.392788 -437.34736)
				(mid 329.107292 -437.34736)
				(end 329.392788 -437.34736)
			)
		)
		(stroke
			(width 0)
			(type solid)
		)
		(fill yes)
		(layer "In2.Cu")
		(net "GND")
	)
	(gr_poly
		(pts
			(arc
				(start 329.392788 -436.051198)
				(mid 329.107292 -436.051198)
				(end 329.392788 -436.051198)
			)
		)
		(stroke
			(width 0)
			(type solid)
		)
		(fill yes)
		(layer "In2.Cu")
		(net "GND")
	)
	(gr_poly
		(pts
			(arc
				(start 329.392788 -434.899562)
				(mid 329.107292 -434.899562)
				(end 329.392788 -434.899562)
			)
		)
		(stroke
			(width 0)
			(type solid)
		)
		(fill yes)
		(layer "In2.Cu")
		(net "GND")
	)
	(gr_poly
		(pts
			(arc
				(start 329.392788 -433.747164)
				(mid 329.107292 -433.747164)
				(end 329.392788 -433.747164)
			)
		)
		(stroke
			(width 0)
			(type solid)
		)
		(fill yes)
		(layer "In2.Cu")
		(net "GND")
	)
	(gr_poly
		(pts
			(arc
				(start 329.392788 -432.451256)
				(mid 329.107292 -432.451256)
				(end 329.392788 -432.451256)
			)
		)
		(stroke
			(width 0)
			(type solid)
		)
		(fill yes)
		(layer "In2.Cu")
		(net "GND")
	)
	(gr_poly
		(pts
			(arc
				(start 329.392788 -431.29962)
				(mid 329.107292 -431.29962)
				(end 329.392788 -431.29962)
			)
		)
		(stroke
			(width 0)
			(type solid)
		)
		(fill yes)
		(layer "In2.Cu")
		(net "GND")
	)
	(gr_poly
		(pts
			(arc
				(start 329.392788 -430.147222)
				(mid 329.107292 -430.147222)
				(end 329.392788 -430.147222)
			)
		)
		(stroke
			(width 0)
			(type solid)
		)
		(fill yes)
		(layer "In2.Cu")
		(net "GND")
	)
	(gr_poly
		(pts
			(arc
				(start 329.392788 -428.851314)
				(mid 329.107292 -428.851314)
				(end 329.392788 -428.851314)
			)
		)
		(stroke
			(width 0)
			(type solid)
		)
		(fill yes)
		(layer "In2.Cu")
		(net "GND")
	)
	(gr_poly
		(pts
			(arc
				(start 329.392788 -427.699678)
				(mid 329.107292 -427.699678)
				(end 329.392788 -427.699678)
			)
		)
		(stroke
			(width 0)
			(type solid)
		)
		(fill yes)
		(layer "In2.Cu")
		(net "GND")
	)
	(gr_poly
		(pts
			(arc
				(start 329.392788 -426.54728)
				(mid 329.107292 -426.54728)
				(end 329.392788 -426.54728)
			)
		)
		(stroke
			(width 0)
			(type solid)
		)
		(fill yes)
		(layer "In2.Cu")
		(net "GND")
	)
	(gr_poly
		(pts
			(arc
				(start 332.392782 -438.651396)
				(mid 332.107286 -438.651396)
				(end 332.392782 -438.651396)
			)
		)
		(stroke
			(width 0)
			(type solid)
		)
		(fill yes)
		(layer "In2.Cu")
		(net "GND")
	)
	(gr_poly
		(pts
			(arc
				(start 332.392782 -437.49976)
				(mid 332.107286 -437.49976)
				(end 332.392782 -437.49976)
			)
		)
		(stroke
			(width 0)
			(type solid)
		)
		(fill yes)
		(layer "In2.Cu")
		(net "GND")
	)
	(gr_poly
		(pts
			(arc
				(start 332.392782 -436.347362)
				(mid 332.107286 -436.347362)
				(end 332.392782 -436.347362)
			)
		)
		(stroke
			(width 0)
			(type solid)
		)
		(fill yes)
		(layer "In2.Cu")
		(net "GND")
	)
	(gr_poly
		(pts
			(arc
				(start 332.392782 -435.0512)
				(mid 332.107286 -435.0512)
				(end 332.392782 -435.0512)
			)
		)
		(stroke
			(width 0)
			(type solid)
		)
		(fill yes)
		(layer "In2.Cu")
		(net "GND")
	)
	(gr_poly
		(pts
			(arc
				(start 332.392782 -433.899564)
				(mid 332.107286 -433.899564)
				(end 332.392782 -433.899564)
			)
		)
		(stroke
			(width 0)
			(type solid)
		)
		(fill yes)
		(layer "In2.Cu")
		(net "GND")
	)
	(gr_poly
		(pts
			(arc
				(start 332.392782 -432.747166)
				(mid 332.107286 -432.747166)
				(end 332.392782 -432.747166)
			)
		)
		(stroke
			(width 0)
			(type solid)
		)
		(fill yes)
		(layer "In2.Cu")
		(net "GND")
	)
	(gr_poly
		(pts
			(arc
				(start 332.392782 -431.451258)
				(mid 332.107286 -431.451258)
				(end 332.392782 -431.451258)
			)
		)
		(stroke
			(width 0)
			(type solid)
		)
		(fill yes)
		(layer "In2.Cu")
		(net "GND")
	)
	(gr_poly
		(pts
			(arc
				(start 332.392782 -430.299622)
				(mid 332.107286 -430.299622)
				(end 332.392782 -430.299622)
			)
		)
		(stroke
			(width 0)
			(type solid)
		)
		(fill yes)
		(layer "In2.Cu")
		(net "GND")
	)
	(gr_poly
		(pts
			(arc
				(start 332.392782 -429.147224)
				(mid 332.107286 -429.147224)
				(end 332.392782 -429.147224)
			)
		)
		(stroke
			(width 0)
			(type solid)
		)
		(fill yes)
		(layer "In2.Cu")
		(net "GND")
	)
	(gr_poly
		(pts
			(arc
				(start 332.392782 -427.851316)
				(mid 332.107286 -427.851316)
				(end 332.392782 -427.851316)
			)
		)
		(stroke
			(width 0)
			(type solid)
		)
		(fill yes)
		(layer "In2.Cu")
		(net "GND")
	)
	(gr_poly
		(pts
			(arc
				(start 332.392782 -426.69968)
				(mid 332.107286 -426.69968)
				(end 332.392782 -426.69968)
			)
		)
		(stroke
			(width 0)
			(type solid)
		)
		(fill yes)
		(layer "In2.Cu")
		(net "GND")
	)
	(gr_poly
		(pts
			(arc
				(start 332.392782 -425.547282)
				(mid 332.107286 -425.547282)
				(end 332.392782 -425.547282)
			)
		)
		(stroke
			(width 0)
			(type solid)
		)
		(fill yes)
		(layer "In2.Cu")
		(net "GND")
	)
	(gr_poly
		(pts
			(arc
				(start 334.392778 -439.651394)
				(mid 334.107282 -439.651394)
				(end 334.392778 -439.651394)
			)
		)
		(stroke
			(width 0)
			(type solid)
		)
		(fill yes)
		(layer "In2.Cu")
		(net "GND")
	)
	(gr_poly
		(pts
			(arc
				(start 334.392778 -438.499758)
				(mid 334.107282 -438.499758)
				(end 334.392778 -438.499758)
			)
		)
		(stroke
			(width 0)
			(type solid)
		)
		(fill yes)
		(layer "In2.Cu")
		(net "GND")
	)
	(gr_poly
		(pts
			(arc
				(start 334.392778 -437.34736)
				(mid 334.107282 -437.34736)
				(end 334.392778 -437.34736)
			)
		)
		(stroke
			(width 0)
			(type solid)
		)
		(fill yes)
		(layer "In2.Cu")
		(net "GND")
	)
	(gr_poly
		(pts
			(arc
				(start 334.392778 -436.051198)
				(mid 334.107282 -436.051198)
				(end 334.392778 -436.051198)
			)
		)
		(stroke
			(width 0)
			(type solid)
		)
		(fill yes)
		(layer "In2.Cu")
		(net "GND")
	)
	(gr_poly
		(pts
			(arc
				(start 334.392778 -434.899562)
				(mid 334.107282 -434.899562)
				(end 334.392778 -434.899562)
			)
		)
		(stroke
			(width 0)
			(type solid)
		)
		(fill yes)
		(layer "In2.Cu")
		(net "GND")
	)
	(gr_poly
		(pts
			(arc
				(start 334.392778 -433.747164)
				(mid 334.107282 -433.747164)
				(end 334.392778 -433.747164)
			)
		)
		(stroke
			(width 0)
			(type solid)
		)
		(fill yes)
		(layer "In2.Cu")
		(net "GND")
	)
	(gr_poly
		(pts
			(arc
				(start 334.392778 -432.451256)
				(mid 334.107282 -432.451256)
				(end 334.392778 -432.451256)
			)
		)
		(stroke
			(width 0)
			(type solid)
		)
		(fill yes)
		(layer "In2.Cu")
		(net "GND")
	)
	(gr_poly
		(pts
			(arc
				(start 334.392778 -431.29962)
				(mid 334.107282 -431.29962)
				(end 334.392778 -431.29962)
			)
		)
		(stroke
			(width 0)
			(type solid)
		)
		(fill yes)
		(layer "In2.Cu")
		(net "GND")
	)
	(gr_poly
		(pts
			(arc
				(start 334.392778 -430.147222)
				(mid 334.107282 -430.147222)
				(end 334.392778 -430.147222)
			)
		)
		(stroke
			(width 0)
			(type solid)
		)
		(fill yes)
		(layer "In2.Cu")
		(net "GND")
	)
	(gr_poly
		(pts
			(arc
				(start 334.392778 -428.851314)
				(mid 334.107282 -428.851314)
				(end 334.392778 -428.851314)
			)
		)
		(stroke
			(width 0)
			(type solid)
		)
		(fill yes)
		(layer "In2.Cu")
		(net "GND")
	)
	(gr_poly
		(pts
			(arc
				(start 334.392778 -427.699678)
				(mid 334.107282 -427.699678)
				(end 334.392778 -427.699678)
			)
		)
		(stroke
			(width 0)
			(type solid)
		)
		(fill yes)
		(layer "In2.Cu")
		(net "GND")
	)
	(gr_poly
		(pts
			(arc
				(start 334.392778 -426.54728)
				(mid 334.107282 -426.54728)
				(end 334.392778 -426.54728)
			)
		)
		(stroke
			(width 0)
			(type solid)
		)
		(fill yes)
		(layer "In2.Cu")
		(net "GND")
	)
	(gr_poly
		(pts
			(arc
				(start 336.392774 -438.651396)
				(mid 336.107278 -438.651396)
				(end 336.392774 -438.651396)
			)
		)
		(stroke
			(width 0)
			(type solid)
		)
		(fill yes)
		(layer "In2.Cu")
		(net "GND")
	)
	(gr_poly
		(pts
			(arc
				(start 336.392774 -437.49976)
				(mid 336.107278 -437.49976)
				(end 336.392774 -437.49976)
			)
		)
		(stroke
			(width 0)
			(type solid)
		)
		(fill yes)
		(layer "In2.Cu")
		(net "GND")
	)
	(gr_poly
		(pts
			(arc
				(start 336.392774 -436.347362)
				(mid 336.107278 -436.347362)
				(end 336.392774 -436.347362)
			)
		)
		(stroke
			(width 0)
			(type solid)
		)
		(fill yes)
		(layer "In2.Cu")
		(net "GND")
	)
	(gr_poly
		(pts
			(arc
				(start 336.392774 -435.0512)
				(mid 336.107278 -435.0512)
				(end 336.392774 -435.0512)
			)
		)
		(stroke
			(width 0)
			(type solid)
		)
		(fill yes)
		(layer "In2.Cu")
		(net "GND")
	)
	(gr_poly
		(pts
			(arc
				(start 336.392774 -433.899564)
				(mid 336.107278 -433.899564)
				(end 336.392774 -433.899564)
			)
		)
		(stroke
			(width 0)
			(type solid)
		)
		(fill yes)
		(layer "In2.Cu")
		(net "GND")
	)
	(gr_poly
		(pts
			(arc
				(start 336.392774 -432.747166)
				(mid 336.107278 -432.747166)
				(end 336.392774 -432.747166)
			)
		)
		(stroke
			(width 0)
			(type solid)
		)
		(fill yes)
		(layer "In2.Cu")
		(net "GND")
	)
	(gr_poly
		(pts
			(arc
				(start 336.392774 -431.451258)
				(mid 336.107278 -431.451258)
				(end 336.392774 -431.451258)
			)
		)
		(stroke
			(width 0)
			(type solid)
		)
		(fill yes)
		(layer "In2.Cu")
		(net "GND")
	)
	(gr_poly
		(pts
			(arc
				(start 336.392774 -430.299622)
				(mid 336.107278 -430.299622)
				(end 336.392774 -430.299622)
			)
		)
		(stroke
			(width 0)
			(type solid)
		)
		(fill yes)
		(layer "In2.Cu")
		(net "GND")
	)
	(gr_poly
		(pts
			(arc
				(start 336.392774 -429.147224)
				(mid 336.107278 -429.147224)
				(end 336.392774 -429.147224)
			)
		)
		(stroke
			(width 0)
			(type solid)
		)
		(fill yes)
		(layer "In2.Cu")
		(net "GND")
	)
	(gr_poly
		(pts
			(arc
				(start 336.392774 -427.851316)
				(mid 336.107278 -427.851316)
				(end 336.392774 -427.851316)
			)
		)
		(stroke
			(width 0)
			(type solid)
		)
		(fill yes)
		(layer "In2.Cu")
		(net "GND")
	)
	(gr_poly
		(pts
			(arc
				(start 336.392774 -426.69968)
				(mid 336.107278 -426.69968)
				(end 336.392774 -426.69968)
			)
		)
		(stroke
			(width 0)
			(type solid)
		)
		(fill yes)
		(layer "In2.Cu")
		(net "GND")
	)
	(gr_poly
		(pts
			(arc
				(start 336.392774 -425.547282)
				(mid 336.107278 -425.547282)
				(end 336.392774 -425.547282)
			)
		)
		(stroke
			(width 0)
			(type solid)
		)
		(fill yes)
		(layer "In2.Cu")
		(net "GND")
	)
	(gr_poly
		(pts
			(arc
				(start 338.39277 -439.651394)
				(mid 338.107274 -439.651394)
				(end 338.39277 -439.651394)
			)
		)
		(stroke
			(width 0)
			(type solid)
		)
		(fill yes)
		(layer "In2.Cu")
		(net "GND")
	)
	(gr_poly
		(pts
			(arc
				(start 338.39277 -438.499758)
				(mid 338.107274 -438.499758)
				(end 338.39277 -438.499758)
			)
		)
		(stroke
			(width 0)
			(type solid)
		)
		(fill yes)
		(layer "In2.Cu")
		(net "GND")
	)
	(gr_poly
		(pts
			(arc
				(start 338.39277 -437.34736)
				(mid 338.107274 -437.34736)
				(end 338.39277 -437.34736)
			)
		)
		(stroke
			(width 0)
			(type solid)
		)
		(fill yes)
		(layer "In2.Cu")
		(net "GND")
	)
	(gr_poly
		(pts
			(arc
				(start 338.39277 -436.051198)
				(mid 338.107274 -436.051198)
				(end 338.39277 -436.051198)
			)
		)
		(stroke
			(width 0)
			(type solid)
		)
		(fill yes)
		(layer "In2.Cu")
		(net "GND")
	)
	(gr_poly
		(pts
			(arc
				(start 338.39277 -434.899562)
				(mid 338.107274 -434.899562)
				(end 338.39277 -434.899562)
			)
		)
		(stroke
			(width 0)
			(type solid)
		)
		(fill yes)
		(layer "In2.Cu")
		(net "GND")
	)
	(gr_poly
		(pts
			(arc
				(start 338.39277 -433.747164)
				(mid 338.107274 -433.747164)
				(end 338.39277 -433.747164)
			)
		)
		(stroke
			(width 0)
			(type solid)
		)
		(fill yes)
		(layer "In2.Cu")
		(net "GND")
	)
	(gr_poly
		(pts
			(arc
				(start 338.39277 -432.451256)
				(mid 338.107274 -432.451256)
				(end 338.39277 -432.451256)
			)
		)
		(stroke
			(width 0)
			(type solid)
		)
		(fill yes)
		(layer "In2.Cu")
		(net "GND")
	)
	(gr_poly
		(pts
			(arc
				(start 338.39277 -431.29962)
				(mid 338.107274 -431.29962)
				(end 338.39277 -431.29962)
			)
		)
		(stroke
			(width 0)
			(type solid)
		)
		(fill yes)
		(layer "In2.Cu")
		(net "GND")
	)
	(gr_poly
		(pts
			(arc
				(start 338.39277 -430.147222)
				(mid 338.107274 -430.147222)
				(end 338.39277 -430.147222)
			)
		)
		(stroke
			(width 0)
			(type solid)
		)
		(fill yes)
		(layer "In2.Cu")
		(net "GND")
	)
	(gr_poly
		(pts
			(arc
				(start 338.39277 -428.851314)
				(mid 338.107274 -428.851314)
				(end 338.39277 -428.851314)
			)
		)
		(stroke
			(width 0)
			(type solid)
		)
		(fill yes)
		(layer "In2.Cu")
		(net "GND")
	)
	(gr_poly
		(pts
			(arc
				(start 338.39277 -427.699678)
				(mid 338.107274 -427.699678)
				(end 338.39277 -427.699678)
			)
		)
		(stroke
			(width 0)
			(type solid)
		)
		(fill yes)
		(layer "In2.Cu")
		(net "GND")
	)
	(gr_poly
		(pts
			(arc
				(start 338.39277 -426.54728)
				(mid 338.107274 -426.54728)
				(end 338.39277 -426.54728)
			)
		)
		(stroke
			(width 0)
			(type solid)
		)
		(fill yes)
		(layer "In2.Cu")
		(net "GND")
	)
	(gr_poly
		(pts
			(arc
				(start 340.392766 -438.651396)
				(mid 340.10727 -438.651396)
				(end 340.392766 -438.651396)
			)
		)
		(stroke
			(width 0)
			(type solid)
		)
		(fill yes)
		(layer "In2.Cu")
		(net "GND")
	)
	(gr_poly
		(pts
			(arc
				(start 340.392766 -437.49976)
				(mid 340.10727 -437.49976)
				(end 340.392766 -437.49976)
			)
		)
		(stroke
			(width 0)
			(type solid)
		)
		(fill yes)
		(layer "In2.Cu")
		(net "GND")
	)
	(gr_poly
		(pts
			(arc
				(start 340.392766 -436.347362)
				(mid 340.10727 -436.347362)
				(end 340.392766 -436.347362)
			)
		)
		(stroke
			(width 0)
			(type solid)
		)
		(fill yes)
		(layer "In2.Cu")
		(net "GND")
	)
	(gr_poly
		(pts
			(arc
				(start 340.392766 -435.0512)
				(mid 340.10727 -435.0512)
				(end 340.392766 -435.0512)
			)
		)
		(stroke
			(width 0)
			(type solid)
		)
		(fill yes)
		(layer "In2.Cu")
		(net "GND")
	)
	(gr_poly
		(pts
			(arc
				(start 340.392766 -433.899564)
				(mid 340.10727 -433.899564)
				(end 340.392766 -433.899564)
			)
		)
		(stroke
			(width 0)
			(type solid)
		)
		(fill yes)
		(layer "In2.Cu")
		(net "GND")
	)
	(gr_poly
		(pts
			(arc
				(start 340.392766 -432.747166)
				(mid 340.10727 -432.747166)
				(end 340.392766 -432.747166)
			)
		)
		(stroke
			(width 0)
			(type solid)
		)
		(fill yes)
		(layer "In2.Cu")
		(net "GND")
	)
	(gr_poly
		(pts
			(arc
				(start 340.392766 -431.451258)
				(mid 340.10727 -431.451258)
				(end 340.392766 -431.451258)
			)
		)
		(stroke
			(width 0)
			(type solid)
		)
		(fill yes)
		(layer "In2.Cu")
		(net "GND")
	)
	(gr_poly
		(pts
			(arc
				(start 340.392766 -430.299622)
				(mid 340.10727 -430.299622)
				(end 340.392766 -430.299622)
			)
		)
		(stroke
			(width 0)
			(type solid)
		)
		(fill yes)
		(layer "In2.Cu")
		(net "GND")
	)
	(gr_poly
		(pts
			(arc
				(start 340.392766 -429.147224)
				(mid 340.10727 -429.147224)
				(end 340.392766 -429.147224)
			)
		)
		(stroke
			(width 0)
			(type solid)
		)
		(fill yes)
		(layer "In2.Cu")
		(net "GND")
	)
	(gr_poly
		(pts
			(arc
				(start 340.392766 -427.851316)
				(mid 340.10727 -427.851316)
				(end 340.392766 -427.851316)
			)
		)
		(stroke
			(width 0)
			(type solid)
		)
		(fill yes)
		(layer "In2.Cu")
		(net "GND")
	)
	(gr_poly
		(pts
			(arc
				(start 340.392766 -426.69968)
				(mid 340.10727 -426.69968)
				(end 340.392766 -426.69968)
			)
		)
		(stroke
			(width 0)
			(type solid)
		)
		(fill yes)
		(layer "In2.Cu")
		(net "GND")
	)
	(gr_poly
		(pts
			(arc
				(start 340.392766 -425.547282)
				(mid 340.10727 -425.547282)
				(end 340.392766 -425.547282)
			)
		)
		(stroke
			(width 0)
			(type solid)
		)
		(fill yes)
		(layer "In2.Cu")
		(net "GND")
	)
	(gr_poly
		(pts
			(arc
				(start 342.392762 -439.651394)
				(mid 342.107266 -439.651394)
				(end 342.392762 -439.651394)
			)
		)
		(stroke
			(width 0)
			(type solid)
		)
		(fill yes)
		(layer "In2.Cu")
		(net "GND")
	)
	(gr_poly
		(pts
			(arc
				(start 342.392762 -438.499758)
				(mid 342.107266 -438.499758)
				(end 342.392762 -438.499758)
			)
		)
		(stroke
			(width 0)
			(type solid)
		)
		(fill yes)
		(layer "In2.Cu")
		(net "GND")
	)
	(gr_poly
		(pts
			(arc
				(start 342.392762 -437.34736)
				(mid 342.107266 -437.34736)
				(end 342.392762 -437.34736)
			)
		)
		(stroke
			(width 0)
			(type solid)
		)
		(fill yes)
		(layer "In2.Cu")
		(net "GND")
	)
	(gr_poly
		(pts
			(arc
				(start 342.392762 -436.051198)
				(mid 342.107266 -436.051198)
				(end 342.392762 -436.051198)
			)
		)
		(stroke
			(width 0)
			(type solid)
		)
		(fill yes)
		(layer "In2.Cu")
		(net "GND")
	)
	(gr_poly
		(pts
			(arc
				(start 342.392762 -434.899562)
				(mid 342.107266 -434.899562)
				(end 342.392762 -434.899562)
			)
		)
		(stroke
			(width 0)
			(type solid)
		)
		(fill yes)
		(layer "In2.Cu")
		(net "GND")
	)
	(gr_poly
		(pts
			(arc
				(start 342.392762 -433.747164)
				(mid 342.107266 -433.747164)
				(end 342.392762 -433.747164)
			)
		)
		(stroke
			(width 0)
			(type solid)
		)
		(fill yes)
		(layer "In2.Cu")
		(net "GND")
	)
	(gr_poly
		(pts
			(arc
				(start 342.392762 -432.451256)
				(mid 342.107266 -432.451256)
				(end 342.392762 -432.451256)
			)
		)
		(stroke
			(width 0)
			(type solid)
		)
		(fill yes)
		(layer "In2.Cu")
		(net "GND")
	)
	(gr_poly
		(pts
			(arc
				(start 342.392762 -431.29962)
				(mid 342.107266 -431.29962)
				(end 342.392762 -431.29962)
			)
		)
		(stroke
			(width 0)
			(type solid)
		)
		(fill yes)
		(layer "In2.Cu")
		(net "GND")
	)
	(gr_poly
		(pts
			(arc
				(start 342.392762 -430.147222)
				(mid 342.107266 -430.147222)
				(end 342.392762 -430.147222)
			)
		)
		(stroke
			(width 0)
			(type solid)
		)
		(fill yes)
		(layer "In2.Cu")
		(net "GND")
	)
	(gr_poly
		(pts
			(arc
				(start 342.392762 -428.851314)
				(mid 342.107266 -428.851314)
				(end 342.392762 -428.851314)
			)
		)
		(stroke
			(width 0)
			(type solid)
		)
		(fill yes)
		(layer "In2.Cu")
		(net "GND")
	)
	(gr_poly
		(pts
			(arc
				(start 342.392762 -427.699678)
				(mid 342.107266 -427.699678)
				(end 342.392762 -427.699678)
			)
		)
		(stroke
			(width 0)
			(type solid)
		)
		(fill yes)
		(layer "In2.Cu")
		(net "GND")
	)
	(gr_poly
		(pts
			(arc
				(start 342.392762 -426.54728)
				(mid 342.107266 -426.54728)
				(end 342.392762 -426.54728)
			)
		)
		(stroke
			(width 0)
			(type solid)
		)
		(fill yes)
		(layer "In2.Cu")
		(net "GND")
	)
	(gr_poly
		(pts
			(arc
				(start 344.392758 -438.651396)
				(mid 344.107262 -438.651396)
				(end 344.392758 -438.651396)
			)
		)
		(stroke
			(width 0)
			(type solid)
		)
		(fill yes)
		(layer "In2.Cu")
		(net "GND")
	)
	(gr_poly
		(pts
			(arc
				(start 344.392758 -437.49976)
				(mid 344.107262 -437.49976)
				(end 344.392758 -437.49976)
			)
		)
		(stroke
			(width 0)
			(type solid)
		)
		(fill yes)
		(layer "In2.Cu")
		(net "GND")
	)
	(gr_poly
		(pts
			(arc
				(start 344.392758 -436.347362)
				(mid 344.107262 -436.347362)
				(end 344.392758 -436.347362)
			)
		)
		(stroke
			(width 0)
			(type solid)
		)
		(fill yes)
		(layer "In2.Cu")
		(net "GND")
	)
	(gr_poly
		(pts
			(arc
				(start 344.392758 -435.0512)
				(mid 344.107262 -435.0512)
				(end 344.392758 -435.0512)
			)
		)
		(stroke
			(width 0)
			(type solid)
		)
		(fill yes)
		(layer "In2.Cu")
		(net "GND")
	)
	(gr_poly
		(pts
			(arc
				(start 344.392758 -433.899564)
				(mid 344.107262 -433.899564)
				(end 344.392758 -433.899564)
			)
		)
		(stroke
			(width 0)
			(type solid)
		)
		(fill yes)
		(layer "In2.Cu")
		(net "GND")
	)
	(gr_poly
		(pts
			(arc
				(start 344.392758 -432.747166)
				(mid 344.107262 -432.747166)
				(end 344.392758 -432.747166)
			)
		)
		(stroke
			(width 0)
			(type solid)
		)
		(fill yes)
		(layer "In2.Cu")
		(net "GND")
	)
	(gr_poly
		(pts
			(arc
				(start 344.392758 -431.451258)
				(mid 344.107262 -431.451258)
				(end 344.392758 -431.451258)
			)
		)
		(stroke
			(width 0)
			(type solid)
		)
		(fill yes)
		(layer "In2.Cu")
		(net "GND")
	)
	(gr_poly
		(pts
			(arc
				(start 344.392758 -430.299622)
				(mid 344.107262 -430.299622)
				(end 344.392758 -430.299622)
			)
		)
		(stroke
			(width 0)
			(type solid)
		)
		(fill yes)
		(layer "In2.Cu")
		(net "GND")
	)
	(gr_poly
		(pts
			(arc
				(start 344.392758 -429.147224)
				(mid 344.107262 -429.147224)
				(end 344.392758 -429.147224)
			)
		)
		(stroke
			(width 0)
			(type solid)
		)
		(fill yes)
		(layer "In2.Cu")
		(net "GND")
	)
	(gr_poly
		(pts
			(arc
				(start 344.392758 -427.851316)
				(mid 344.107262 -427.851316)
				(end 344.392758 -427.851316)
			)
		)
		(stroke
			(width 0)
			(type solid)
		)
		(fill yes)
		(layer "In2.Cu")
		(net "GND")
	)
	(gr_poly
		(pts
			(arc
				(start 344.392758 -426.69968)
				(mid 344.107262 -426.69968)
				(end 344.392758 -426.69968)
			)
		)
		(stroke
			(width 0)
			(type solid)
		)
		(fill yes)
		(layer "In2.Cu")
		(net "GND")
	)
	(gr_poly
		(pts
			(arc
				(start 344.392758 -425.547282)
				(mid 344.107262 -425.547282)
				(end 344.392758 -425.547282)
			)
		)
		(stroke
			(width 0)
			(type solid)
		)
		(fill yes)
		(layer "In2.Cu")
		(net "GND")
	)
	(gr_poly
		(pts
			(arc
				(start 346.392754 -439.651394)
				(mid 346.107258 -439.651394)
				(end 346.392754 -439.651394)
			)
		)
		(stroke
			(width 0)
			(type solid)
		)
		(fill yes)
		(layer "In2.Cu")
		(net "GND")
	)
	(gr_poly
		(pts
			(arc
				(start 346.392754 -438.499758)
				(mid 346.107258 -438.499758)
				(end 346.392754 -438.499758)
			)
		)
		(stroke
			(width 0)
			(type solid)
		)
		(fill yes)
		(layer "In2.Cu")
		(net "GND")
	)
	(gr_poly
		(pts
			(arc
				(start 346.392754 -437.34736)
				(mid 346.107258 -437.34736)
				(end 346.392754 -437.34736)
			)
		)
		(stroke
			(width 0)
			(type solid)
		)
		(fill yes)
		(layer "In2.Cu")
		(net "GND")
	)
	(gr_poly
		(pts
			(arc
				(start 346.392754 -436.051198)
				(mid 346.107258 -436.051198)
				(end 346.392754 -436.051198)
			)
		)
		(stroke
			(width 0)
			(type solid)
		)
		(fill yes)
		(layer "In2.Cu")
		(net "GND")
	)
	(gr_poly
		(pts
			(arc
				(start 346.392754 -434.899562)
				(mid 346.107258 -434.899562)
				(end 346.392754 -434.899562)
			)
		)
		(stroke
			(width 0)
			(type solid)
		)
		(fill yes)
		(layer "In2.Cu")
		(net "GND")
	)
	(gr_poly
		(pts
			(arc
				(start 346.392754 -433.747164)
				(mid 346.107258 -433.747164)
				(end 346.392754 -433.747164)
			)
		)
		(stroke
			(width 0)
			(type solid)
		)
		(fill yes)
		(layer "In2.Cu")
		(net "GND")
	)
	(gr_poly
		(pts
			(arc
				(start 346.392754 -432.451256)
				(mid 346.107258 -432.451256)
				(end 346.392754 -432.451256)
			)
		)
		(stroke
			(width 0)
			(type solid)
		)
		(fill yes)
		(layer "In2.Cu")
		(net "GND")
	)
	(gr_poly
		(pts
			(arc
				(start 346.392754 -431.29962)
				(mid 346.107258 -431.29962)
				(end 346.392754 -431.29962)
			)
		)
		(stroke
			(width 0)
			(type solid)
		)
		(fill yes)
		(layer "In2.Cu")
		(net "GND")
	)
	(gr_poly
		(pts
			(arc
				(start 346.392754 -430.147222)
				(mid 346.107258 -430.147222)
				(end 346.392754 -430.147222)
			)
		)
		(stroke
			(width 0)
			(type solid)
		)
		(fill yes)
		(layer "In2.Cu")
		(net "GND")
	)
	(gr_poly
		(pts
			(arc
				(start 346.392754 -428.851314)
				(mid 346.107258 -428.851314)
				(end 346.392754 -428.851314)
			)
		)
		(stroke
			(width 0)
			(type solid)
		)
		(fill yes)
		(layer "In2.Cu")
		(net "GND")
	)
	(gr_poly
		(pts
			(arc
				(start 346.392754 -427.699678)
				(mid 346.107258 -427.699678)
				(end 346.392754 -427.699678)
			)
		)
		(stroke
			(width 0)
			(type solid)
		)
		(fill yes)
		(layer "In2.Cu")
		(net "GND")
	)
	(gr_poly
		(pts
			(arc
				(start 346.392754 -426.54728)
				(mid 346.107258 -426.54728)
				(end 346.392754 -426.54728)
			)
		)
		(stroke
			(width 0)
			(type solid)
		)
		(fill yes)
		(layer "In2.Cu")
		(net "GND")
	)
	(gr_poly
		(pts
			(arc
				(start 382.492758 -438.651396)
				(mid 382.207262 -438.651396)
				(end 382.492758 -438.651396)
			)
		)
		(stroke
			(width 0)
			(type solid)
		)
		(fill yes)
		(layer "In2.Cu")
		(net "GND")
	)
	(gr_poly
		(pts
			(arc
				(start 382.492758 -437.49976)
				(mid 382.207262 -437.49976)
				(end 382.492758 -437.49976)
			)
		)
		(stroke
			(width 0)
			(type solid)
		)
		(fill yes)
		(layer "In2.Cu")
		(net "GND")
	)
	(gr_poly
		(pts
			(arc
				(start 382.492758 -436.347362)
				(mid 382.207262 -436.347362)
				(end 382.492758 -436.347362)
			)
		)
		(stroke
			(width 0)
			(type solid)
		)
		(fill yes)
		(layer "In2.Cu")
		(net "GND")
	)
	(gr_poly
		(pts
			(arc
				(start 382.492758 -435.0512)
				(mid 382.207262 -435.0512)
				(end 382.492758 -435.0512)
			)
		)
		(stroke
			(width 0)
			(type solid)
		)
		(fill yes)
		(layer "In2.Cu")
		(net "GND")
	)
	(gr_poly
		(pts
			(arc
				(start 382.492758 -433.899564)
				(mid 382.207262 -433.899564)
				(end 382.492758 -433.899564)
			)
		)
		(stroke
			(width 0)
			(type solid)
		)
		(fill yes)
		(layer "In2.Cu")
		(net "GND")
	)
	(gr_poly
		(pts
			(arc
				(start 382.492758 -432.747166)
				(mid 382.207262 -432.747166)
				(end 382.492758 -432.747166)
			)
		)
		(stroke
			(width 0)
			(type solid)
		)
		(fill yes)
		(layer "In2.Cu")
		(net "GND")
	)
	(gr_poly
		(pts
			(arc
				(start 382.492758 -431.451258)
				(mid 382.207262 -431.451258)
				(end 382.492758 -431.451258)
			)
		)
		(stroke
			(width 0)
			(type solid)
		)
		(fill yes)
		(layer "In2.Cu")
		(net "GND")
	)
	(gr_poly
		(pts
			(arc
				(start 382.492758 -430.299622)
				(mid 382.207262 -430.299622)
				(end 382.492758 -430.299622)
			)
		)
		(stroke
			(width 0)
			(type solid)
		)
		(fill yes)
		(layer "In2.Cu")
		(net "GND")
	)
	(gr_poly
		(pts
			(arc
				(start 382.492758 -429.147224)
				(mid 382.207262 -429.147224)
				(end 382.492758 -429.147224)
			)
		)
		(stroke
			(width 0)
			(type solid)
		)
		(fill yes)
		(layer "In2.Cu")
		(net "GND")
	)
	(gr_poly
		(pts
			(arc
				(start 382.492758 -427.851316)
				(mid 382.207262 -427.851316)
				(end 382.492758 -427.851316)
			)
		)
		(stroke
			(width 0)
			(type solid)
		)
		(fill yes)
		(layer "In2.Cu")
		(net "GND")
	)
	(gr_poly
		(pts
			(arc
				(start 382.492758 -426.69968)
				(mid 382.207262 -426.69968)
				(end 382.492758 -426.69968)
			)
		)
		(stroke
			(width 0)
			(type solid)
		)
		(fill yes)
		(layer "In2.Cu")
		(net "GND")
	)
	(gr_poly
		(pts
			(arc
				(start 382.492758 -425.547282)
				(mid 382.207262 -425.547282)
				(end 382.492758 -425.547282)
			)
		)
		(stroke
			(width 0)
			(type solid)
		)
		(fill yes)
		(layer "In2.Cu")
		(net "GND")
	)
	(gr_poly
		(pts
			(arc
				(start 384.492754 -439.651394)
				(mid 384.207258 -439.651394)
				(end 384.492754 -439.651394)
			)
		)
		(stroke
			(width 0)
			(type solid)
		)
		(fill yes)
		(layer "In2.Cu")
		(net "GND")
	)
	(gr_poly
		(pts
			(arc
				(start 384.492754 -438.499758)
				(mid 384.207258 -438.499758)
				(end 384.492754 -438.499758)
			)
		)
		(stroke
			(width 0)
			(type solid)
		)
		(fill yes)
		(layer "In2.Cu")
		(net "GND")
	)
	(gr_poly
		(pts
			(arc
				(start 384.492754 -437.34736)
				(mid 384.207258 -437.34736)
				(end 384.492754 -437.34736)
			)
		)
		(stroke
			(width 0)
			(type solid)
		)
		(fill yes)
		(layer "In2.Cu")
		(net "GND")
	)
	(gr_poly
		(pts
			(arc
				(start 384.492754 -436.051198)
				(mid 384.207258 -436.051198)
				(end 384.492754 -436.051198)
			)
		)
		(stroke
			(width 0)
			(type solid)
		)
		(fill yes)
		(layer "In2.Cu")
		(net "GND")
	)
	(gr_poly
		(pts
			(arc
				(start 384.492754 -434.899562)
				(mid 384.207258 -434.899562)
				(end 384.492754 -434.899562)
			)
		)
		(stroke
			(width 0)
			(type solid)
		)
		(fill yes)
		(layer "In2.Cu")
		(net "GND")
	)
	(gr_poly
		(pts
			(arc
				(start 384.492754 -433.747164)
				(mid 384.207258 -433.747164)
				(end 384.492754 -433.747164)
			)
		)
		(stroke
			(width 0)
			(type solid)
		)
		(fill yes)
		(layer "In2.Cu")
		(net "GND")
	)
	(gr_poly
		(pts
			(arc
				(start 384.492754 -432.451256)
				(mid 384.207258 -432.451256)
				(end 384.492754 -432.451256)
			)
		)
		(stroke
			(width 0)
			(type solid)
		)
		(fill yes)
		(layer "In2.Cu")
		(net "GND")
	)
	(gr_poly
		(pts
			(arc
				(start 384.492754 -431.29962)
				(mid 384.207258 -431.29962)
				(end 384.492754 -431.29962)
			)
		)
		(stroke
			(width 0)
			(type solid)
		)
		(fill yes)
		(layer "In2.Cu")
		(net "GND")
	)
	(gr_poly
		(pts
			(arc
				(start 384.492754 -430.147222)
				(mid 384.207258 -430.147222)
				(end 384.492754 -430.147222)
			)
		)
		(stroke
			(width 0)
			(type solid)
		)
		(fill yes)
		(layer "In2.Cu")
		(net "GND")
	)
	(gr_poly
		(pts
			(arc
				(start 384.492754 -428.851314)
				(mid 384.207258 -428.851314)
				(end 384.492754 -428.851314)
			)
		)
		(stroke
			(width 0)
			(type solid)
		)
		(fill yes)
		(layer "In2.Cu")
		(net "GND")
	)
	(gr_poly
		(pts
			(arc
				(start 384.492754 -427.699678)
				(mid 384.207258 -427.699678)
				(end 384.492754 -427.699678)
			)
		)
		(stroke
			(width 0)
			(type solid)
		)
		(fill yes)
		(layer "In2.Cu")
		(net "GND")
	)
	(gr_poly
		(pts
			(arc
				(start 384.492754 -426.54728)
				(mid 384.207258 -426.54728)
				(end 384.492754 -426.54728)
			)
		)
		(stroke
			(width 0)
			(type solid)
		)
		(fill yes)
		(layer "In2.Cu")
		(net "GND")
	)
	(gr_poly
		(pts
			(arc
				(start 386.49275 -438.651396)
				(mid 386.207254 -438.651396)
				(end 386.49275 -438.651396)
			)
		)
		(stroke
			(width 0)
			(type solid)
		)
		(fill yes)
		(layer "In2.Cu")
		(net "GND")
	)
	(gr_poly
		(pts
			(arc
				(start 386.49275 -437.49976)
				(mid 386.207254 -437.49976)
				(end 386.49275 -437.49976)
			)
		)
		(stroke
			(width 0)
			(type solid)
		)
		(fill yes)
		(layer "In2.Cu")
		(net "GND")
	)
	(gr_poly
		(pts
			(arc
				(start 386.49275 -436.347362)
				(mid 386.207254 -436.347362)
				(end 386.49275 -436.347362)
			)
		)
		(stroke
			(width 0)
			(type solid)
		)
		(fill yes)
		(layer "In2.Cu")
		(net "GND")
	)
	(gr_poly
		(pts
			(arc
				(start 386.49275 -435.0512)
				(mid 386.207254 -435.0512)
				(end 386.49275 -435.0512)
			)
		)
		(stroke
			(width 0)
			(type solid)
		)
		(fill yes)
		(layer "In2.Cu")
		(net "GND")
	)
	(gr_poly
		(pts
			(arc
				(start 386.49275 -433.899564)
				(mid 386.207254 -433.899564)
				(end 386.49275 -433.899564)
			)
		)
		(stroke
			(width 0)
			(type solid)
		)
		(fill yes)
		(layer "In2.Cu")
		(net "GND")
	)
	(gr_poly
		(pts
			(arc
				(start 386.49275 -432.747166)
				(mid 386.207254 -432.747166)
				(end 386.49275 -432.747166)
			)
		)
		(stroke
			(width 0)
			(type solid)
		)
		(fill yes)
		(layer "In2.Cu")
		(net "GND")
	)
	(gr_poly
		(pts
			(arc
				(start 386.49275 -431.451258)
				(mid 386.207254 -431.451258)
				(end 386.49275 -431.451258)
			)
		)
		(stroke
			(width 0)
			(type solid)
		)
		(fill yes)
		(layer "In2.Cu")
		(net "GND")
	)
	(gr_poly
		(pts
			(arc
				(start 386.49275 -430.299622)
				(mid 386.207254 -430.299622)
				(end 386.49275 -430.299622)
			)
		)
		(stroke
			(width 0)
			(type solid)
		)
		(fill yes)
		(layer "In2.Cu")
		(net "GND")
	)
	(gr_poly
		(pts
			(arc
				(start 386.49275 -429.147224)
				(mid 386.207254 -429.147224)
				(end 386.49275 -429.147224)
			)
		)
		(stroke
			(width 0)
			(type solid)
		)
		(fill yes)
		(layer "In2.Cu")
		(net "GND")
	)
	(gr_poly
		(pts
			(arc
				(start 386.49275 -427.851316)
				(mid 386.207254 -427.851316)
				(end 386.49275 -427.851316)
			)
		)
		(stroke
			(width 0)
			(type solid)
		)
		(fill yes)
		(layer "In2.Cu")
		(net "GND")
	)
	(gr_poly
		(pts
			(arc
				(start 386.49275 -426.69968)
				(mid 386.207254 -426.69968)
				(end 386.49275 -426.69968)
			)
		)
		(stroke
			(width 0)
			(type solid)
		)
		(fill yes)
		(layer "In2.Cu")
		(net "GND")
	)
	(gr_poly
		(pts
			(arc
				(start 386.49275 -425.547282)
				(mid 386.207254 -425.547282)
				(end 386.49275 -425.547282)
			)
		)
		(stroke
			(width 0)
			(type solid)
		)
		(fill yes)
		(layer "In2.Cu")
		(net "GND")
	)
	(gr_poly
		(pts
			(arc
				(start 388.492746 -439.651394)
				(mid 388.20725 -439.651394)
				(end 388.492746 -439.651394)
			)
		)
		(stroke
			(width 0)
			(type solid)
		)
		(fill yes)
		(layer "In2.Cu")
		(net "GND")
	)
	(gr_poly
		(pts
			(arc
				(start 388.492746 -438.499758)
				(mid 388.20725 -438.499758)
				(end 388.492746 -438.499758)
			)
		)
		(stroke
			(width 0)
			(type solid)
		)
		(fill yes)
		(layer "In2.Cu")
		(net "GND")
	)
	(gr_poly
		(pts
			(arc
				(start 388.492746 -437.34736)
				(mid 388.20725 -437.34736)
				(end 388.492746 -437.34736)
			)
		)
		(stroke
			(width 0)
			(type solid)
		)
		(fill yes)
		(layer "In2.Cu")
		(net "GND")
	)
	(gr_poly
		(pts
			(arc
				(start 388.492746 -436.051198)
				(mid 388.20725 -436.051198)
				(end 388.492746 -436.051198)
			)
		)
		(stroke
			(width 0)
			(type solid)
		)
		(fill yes)
		(layer "In2.Cu")
		(net "GND")
	)
	(gr_poly
		(pts
			(arc
				(start 388.492746 -434.899562)
				(mid 388.20725 -434.899562)
				(end 388.492746 -434.899562)
			)
		)
		(stroke
			(width 0)
			(type solid)
		)
		(fill yes)
		(layer "In2.Cu")
		(net "GND")
	)
	(gr_poly
		(pts
			(arc
				(start 388.492746 -433.747164)
				(mid 388.20725 -433.747164)
				(end 388.492746 -433.747164)
			)
		)
		(stroke
			(width 0)
			(type solid)
		)
		(fill yes)
		(layer "In2.Cu")
		(net "GND")
	)
	(gr_poly
		(pts
			(arc
				(start 388.492746 -432.451256)
				(mid 388.20725 -432.451256)
				(end 388.492746 -432.451256)
			)
		)
		(stroke
			(width 0)
			(type solid)
		)
		(fill yes)
		(layer "In2.Cu")
		(net "GND")
	)
	(gr_poly
		(pts
			(arc
				(start 388.492746 -431.29962)
				(mid 388.20725 -431.29962)
				(end 388.492746 -431.29962)
			)
		)
		(stroke
			(width 0)
			(type solid)
		)
		(fill yes)
		(layer "In2.Cu")
		(net "GND")
	)
	(gr_poly
		(pts
			(arc
				(start 388.492746 -430.147222)
				(mid 388.20725 -430.147222)
				(end 388.492746 -430.147222)
			)
		)
		(stroke
			(width 0)
			(type solid)
		)
		(fill yes)
		(layer "In2.Cu")
		(net "GND")
	)
	(gr_poly
		(pts
			(arc
				(start 388.492746 -428.851314)
				(mid 388.20725 -428.851314)
				(end 388.492746 -428.851314)
			)
		)
		(stroke
			(width 0)
			(type solid)
		)
		(fill yes)
		(layer "In2.Cu")
		(net "GND")
	)
	(gr_poly
		(pts
			(arc
				(start 388.492746 -427.699678)
				(mid 388.20725 -427.699678)
				(end 388.492746 -427.699678)
			)
		)
		(stroke
			(width 0)
			(type solid)
		)
		(fill yes)
		(layer "In2.Cu")
		(net "GND")
	)
	(gr_poly
		(pts
			(arc
				(start 388.492746 -426.54728)
				(mid 388.20725 -426.54728)
				(end 388.492746 -426.54728)
			)
		)
		(stroke
			(width 0)
			(type solid)
		)
		(fill yes)
		(layer "In2.Cu")
		(net "GND")
	)
	(gr_poly
		(pts
			(arc
				(start 390.492742 -438.651396)
				(mid 390.207246 -438.651396)
				(end 390.492742 -438.651396)
			)
		)
		(stroke
			(width 0)
			(type solid)
		)
		(fill yes)
		(layer "In2.Cu")
		(net "GND")
	)
	(gr_poly
		(pts
			(arc
				(start 390.492742 -437.49976)
				(mid 390.207246 -437.49976)
				(end 390.492742 -437.49976)
			)
		)
		(stroke
			(width 0)
			(type solid)
		)
		(fill yes)
		(layer "In2.Cu")
		(net "GND")
	)
	(gr_poly
		(pts
			(arc
				(start 390.492742 -436.347362)
				(mid 390.207246 -436.347362)
				(end 390.492742 -436.347362)
			)
		)
		(stroke
			(width 0)
			(type solid)
		)
		(fill yes)
		(layer "In2.Cu")
		(net "GND")
	)
	(gr_poly
		(pts
			(arc
				(start 390.492742 -435.0512)
				(mid 390.207246 -435.0512)
				(end 390.492742 -435.0512)
			)
		)
		(stroke
			(width 0)
			(type solid)
		)
		(fill yes)
		(layer "In2.Cu")
		(net "GND")
	)
	(gr_poly
		(pts
			(arc
				(start 390.492742 -433.899564)
				(mid 390.207246 -433.899564)
				(end 390.492742 -433.899564)
			)
		)
		(stroke
			(width 0)
			(type solid)
		)
		(fill yes)
		(layer "In2.Cu")
		(net "GND")
	)
	(gr_poly
		(pts
			(arc
				(start 390.492742 -432.747166)
				(mid 390.207246 -432.747166)
				(end 390.492742 -432.747166)
			)
		)
		(stroke
			(width 0)
			(type solid)
		)
		(fill yes)
		(layer "In2.Cu")
		(net "GND")
	)
	(gr_poly
		(pts
			(arc
				(start 390.492742 -431.451258)
				(mid 390.207246 -431.451258)
				(end 390.492742 -431.451258)
			)
		)
		(stroke
			(width 0)
			(type solid)
		)
		(fill yes)
		(layer "In2.Cu")
		(net "GND")
	)
	(gr_poly
		(pts
			(arc
				(start 390.492742 -430.299622)
				(mid 390.207246 -430.299622)
				(end 390.492742 -430.299622)
			)
		)
		(stroke
			(width 0)
			(type solid)
		)
		(fill yes)
		(layer "In2.Cu")
		(net "GND")
	)
	(gr_poly
		(pts
			(arc
				(start 390.492742 -429.147224)
				(mid 390.207246 -429.147224)
				(end 390.492742 -429.147224)
			)
		)
		(stroke
			(width 0)
			(type solid)
		)
		(fill yes)
		(layer "In2.Cu")
		(net "GND")
	)
	(gr_poly
		(pts
			(arc
				(start 390.492742 -427.851316)
				(mid 390.207246 -427.851316)
				(end 390.492742 -427.851316)
			)
		)
		(stroke
			(width 0)
			(type solid)
		)
		(fill yes)
		(layer "In2.Cu")
		(net "GND")
	)
	(gr_poly
		(pts
			(arc
				(start 390.492742 -426.69968)
				(mid 390.207246 -426.69968)
				(end 390.492742 -426.69968)
			)
		)
		(stroke
			(width 0)
			(type solid)
		)
		(fill yes)
		(layer "In2.Cu")
		(net "GND")
	)
	(gr_poly
		(pts
			(arc
				(start 390.492742 -425.547282)
				(mid 390.207246 -425.547282)
				(end 390.492742 -425.547282)
			)
		)
		(stroke
			(width 0)
			(type solid)
		)
		(fill yes)
		(layer "In2.Cu")
		(net "GND")
	)
	(gr_poly
		(pts
			(arc
				(start 392.492738 -439.651394)
				(mid 392.207242 -439.651394)
				(end 392.492738 -439.651394)
			)
		)
		(stroke
			(width 0)
			(type solid)
		)
		(fill yes)
		(layer "In2.Cu")
		(net "GND")
	)
	(gr_poly
		(pts
			(arc
				(start 392.492738 -438.499758)
				(mid 392.207242 -438.499758)
				(end 392.492738 -438.499758)
			)
		)
		(stroke
			(width 0)
			(type solid)
		)
		(fill yes)
		(layer "In2.Cu")
		(net "GND")
	)
	(gr_poly
		(pts
			(arc
				(start 392.492738 -437.34736)
				(mid 392.207242 -437.34736)
				(end 392.492738 -437.34736)
			)
		)
		(stroke
			(width 0)
			(type solid)
		)
		(fill yes)
		(layer "In2.Cu")
		(net "GND")
	)
	(gr_poly
		(pts
			(arc
				(start 392.492738 -436.051198)
				(mid 392.207242 -436.051198)
				(end 392.492738 -436.051198)
			)
		)
		(stroke
			(width 0)
			(type solid)
		)
		(fill yes)
		(layer "In2.Cu")
		(net "GND")
	)
	(gr_poly
		(pts
			(arc
				(start 392.492738 -434.899562)
				(mid 392.207242 -434.899562)
				(end 392.492738 -434.899562)
			)
		)
		(stroke
			(width 0)
			(type solid)
		)
		(fill yes)
		(layer "In2.Cu")
		(net "GND")
	)
	(gr_poly
		(pts
			(arc
				(start 392.492738 -433.747164)
				(mid 392.207242 -433.747164)
				(end 392.492738 -433.747164)
			)
		)
		(stroke
			(width 0)
			(type solid)
		)
		(fill yes)
		(layer "In2.Cu")
		(net "GND")
	)
	(gr_poly
		(pts
			(arc
				(start 392.492738 -432.451256)
				(mid 392.207242 -432.451256)
				(end 392.492738 -432.451256)
			)
		)
		(stroke
			(width 0)
			(type solid)
		)
		(fill yes)
		(layer "In2.Cu")
		(net "GND")
	)
	(gr_poly
		(pts
			(arc
				(start 392.492738 -431.29962)
				(mid 392.207242 -431.29962)
				(end 392.492738 -431.29962)
			)
		)
		(stroke
			(width 0)
			(type solid)
		)
		(fill yes)
		(layer "In2.Cu")
		(net "GND")
	)
	(gr_poly
		(pts
			(arc
				(start 392.492738 -430.147222)
				(mid 392.207242 -430.147222)
				(end 392.492738 -430.147222)
			)
		)
		(stroke
			(width 0)
			(type solid)
		)
		(fill yes)
		(layer "In2.Cu")
		(net "GND")
	)
	(gr_poly
		(pts
			(arc
				(start 392.492738 -428.851314)
				(mid 392.207242 -428.851314)
				(end 392.492738 -428.851314)
			)
		)
		(stroke
			(width 0)
			(type solid)
		)
		(fill yes)
		(layer "In2.Cu")
		(net "GND")
	)
	(gr_poly
		(pts
			(arc
				(start 392.492738 -427.699678)
				(mid 392.207242 -427.699678)
				(end 392.492738 -427.699678)
			)
		)
		(stroke
			(width 0)
			(type solid)
		)
		(fill yes)
		(layer "In2.Cu")
		(net "GND")
	)
	(gr_poly
		(pts
			(arc
				(start 392.492738 -426.54728)
				(mid 392.207242 -426.54728)
				(end 392.492738 -426.54728)
			)
		)
		(stroke
			(width 0)
			(type solid)
		)
		(fill yes)
		(layer "In2.Cu")
		(net "GND")
	)
	(gr_poly
		(pts
			(arc
				(start 394.492734 -438.651396)
				(mid 394.207238 -438.651396)
				(end 394.492734 -438.651396)
			)
		)
		(stroke
			(width 0)
			(type solid)
		)
		(fill yes)
		(layer "In2.Cu")
		(net "GND")
	)
	(gr_poly
		(pts
			(arc
				(start 394.492734 -437.49976)
				(mid 394.207238 -437.49976)
				(end 394.492734 -437.49976)
			)
		)
		(stroke
			(width 0)
			(type solid)
		)
		(fill yes)
		(layer "In2.Cu")
		(net "GND")
	)
	(gr_poly
		(pts
			(arc
				(start 394.492734 -436.347362)
				(mid 394.207238 -436.347362)
				(end 394.492734 -436.347362)
			)
		)
		(stroke
			(width 0)
			(type solid)
		)
		(fill yes)
		(layer "In2.Cu")
		(net "GND")
	)
	(gr_poly
		(pts
			(arc
				(start 394.492734 -435.0512)
				(mid 394.207238 -435.0512)
				(end 394.492734 -435.0512)
			)
		)
		(stroke
			(width 0)
			(type solid)
		)
		(fill yes)
		(layer "In2.Cu")
		(net "GND")
	)
	(gr_poly
		(pts
			(arc
				(start 394.492734 -433.899564)
				(mid 394.207238 -433.899564)
				(end 394.492734 -433.899564)
			)
		)
		(stroke
			(width 0)
			(type solid)
		)
		(fill yes)
		(layer "In2.Cu")
		(net "GND")
	)
	(gr_poly
		(pts
			(arc
				(start 394.492734 -432.747166)
				(mid 394.207238 -432.747166)
				(end 394.492734 -432.747166)
			)
		)
		(stroke
			(width 0)
			(type solid)
		)
		(fill yes)
		(layer "In2.Cu")
		(net "GND")
	)
	(gr_poly
		(pts
			(arc
				(start 394.492734 -431.451258)
				(mid 394.207238 -431.451258)
				(end 394.492734 -431.451258)
			)
		)
		(stroke
			(width 0)
			(type solid)
		)
		(fill yes)
		(layer "In2.Cu")
		(net "GND")
	)
	(gr_poly
		(pts
			(arc
				(start 394.492734 -430.299622)
				(mid 394.207238 -430.299622)
				(end 394.492734 -430.299622)
			)
		)
		(stroke
			(width 0)
			(type solid)
		)
		(fill yes)
		(layer "In2.Cu")
		(net "GND")
	)
	(gr_poly
		(pts
			(arc
				(start 394.492734 -429.147224)
				(mid 394.207238 -429.147224)
				(end 394.492734 -429.147224)
			)
		)
		(stroke
			(width 0)
			(type solid)
		)
		(fill yes)
		(layer "In2.Cu")
		(net "GND")
	)
	(gr_poly
		(pts
			(arc
				(start 394.492734 -427.851316)
				(mid 394.207238 -427.851316)
				(end 394.492734 -427.851316)
			)
		)
		(stroke
			(width 0)
			(type solid)
		)
		(fill yes)
		(layer "In2.Cu")
		(net "GND")
	)
	(gr_poly
		(pts
			(arc
				(start 394.492734 -426.69968)
				(mid 394.207238 -426.69968)
				(end 394.492734 -426.69968)
			)
		)
		(stroke
			(width 0)
			(type solid)
		)
		(fill yes)
		(layer "In2.Cu")
		(net "GND")
	)
	(gr_poly
		(pts
			(arc
				(start 394.492734 -425.547282)
				(mid 394.207238 -425.547282)
				(end 394.492734 -425.547282)
			)
		)
		(stroke
			(width 0)
			(type solid)
		)
		(fill yes)
		(layer "In2.Cu")
		(net "GND")
	)
	(gr_poly
		(pts
			(arc
				(start 396.49273 -439.651394)
				(mid 396.207234 -439.651394)
				(end 396.49273 -439.651394)
			)
		)
		(stroke
			(width 0)
			(type solid)
		)
		(fill yes)
		(layer "In2.Cu")
		(net "GND")
	)
	(gr_poly
		(pts
			(arc
				(start 396.49273 -438.499758)
				(mid 396.207234 -438.499758)
				(end 396.49273 -438.499758)
			)
		)
		(stroke
			(width 0)
			(type solid)
		)
		(fill yes)
		(layer "In2.Cu")
		(net "GND")
	)
	(gr_poly
		(pts
			(arc
				(start 396.49273 -437.34736)
				(mid 396.207234 -437.34736)
				(end 396.49273 -437.34736)
			)
		)
		(stroke
			(width 0)
			(type solid)
		)
		(fill yes)
		(layer "In2.Cu")
		(net "GND")
	)
	(gr_poly
		(pts
			(arc
				(start 396.49273 -436.051198)
				(mid 396.207234 -436.051198)
				(end 396.49273 -436.051198)
			)
		)
		(stroke
			(width 0)
			(type solid)
		)
		(fill yes)
		(layer "In2.Cu")
		(net "GND")
	)
	(gr_poly
		(pts
			(arc
				(start 396.49273 -434.899562)
				(mid 396.207234 -434.899562)
				(end 396.49273 -434.899562)
			)
		)
		(stroke
			(width 0)
			(type solid)
		)
		(fill yes)
		(layer "In2.Cu")
		(net "GND")
	)
	(gr_poly
		(pts
			(arc
				(start 396.49273 -433.747164)
				(mid 396.207234 -433.747164)
				(end 396.49273 -433.747164)
			)
		)
		(stroke
			(width 0)
			(type solid)
		)
		(fill yes)
		(layer "In2.Cu")
		(net "GND")
	)
	(gr_poly
		(pts
			(arc
				(start 396.49273 -432.451256)
				(mid 396.207234 -432.451256)
				(end 396.49273 -432.451256)
			)
		)
		(stroke
			(width 0)
			(type solid)
		)
		(fill yes)
		(layer "In2.Cu")
		(net "GND")
	)
	(gr_poly
		(pts
			(arc
				(start 396.49273 -431.29962)
				(mid 396.207234 -431.29962)
				(end 396.49273 -431.29962)
			)
		)
		(stroke
			(width 0)
			(type solid)
		)
		(fill yes)
		(layer "In2.Cu")
		(net "GND")
	)
	(gr_poly
		(pts
			(arc
				(start 396.49273 -430.147222)
				(mid 396.207234 -430.147222)
				(end 396.49273 -430.147222)
			)
		)
		(stroke
			(width 0)
			(type solid)
		)
		(fill yes)
		(layer "In2.Cu")
		(net "GND")
	)
	(gr_poly
		(pts
			(arc
				(start 396.49273 -428.851314)
				(mid 396.207234 -428.851314)
				(end 396.49273 -428.851314)
			)
		)
		(stroke
			(width 0)
			(type solid)
		)
		(fill yes)
		(layer "In2.Cu")
		(net "GND")
	)
	(gr_poly
		(pts
			(arc
				(start 396.49273 -427.699678)
				(mid 396.207234 -427.699678)
				(end 396.49273 -427.699678)
			)
		)
		(stroke
			(width 0)
			(type solid)
		)
		(fill yes)
		(layer "In2.Cu")
		(net "GND")
	)
	(gr_poly
		(pts
			(arc
				(start 396.49273 -426.54728)
				(mid 396.207234 -426.54728)
				(end 396.49273 -426.54728)
			)
		)
		(stroke
			(width 0)
			(type solid)
		)
		(fill yes)
		(layer "In2.Cu")
		(net "GND")
	)
	(gr_poly
		(pts
			(arc
				(start 399.492724 -438.651396)
				(mid 399.207228 -438.651396)
				(end 399.492724 -438.651396)
			)
		)
		(stroke
			(width 0)
			(type solid)
		)
		(fill yes)
		(layer "In2.Cu")
		(net "GND")
	)
	(gr_poly
		(pts
			(arc
				(start 399.492724 -437.49976)
				(mid 399.207228 -437.49976)
				(end 399.492724 -437.49976)
			)
		)
		(stroke
			(width 0)
			(type solid)
		)
		(fill yes)
		(layer "In2.Cu")
		(net "GND")
	)
	(gr_poly
		(pts
			(arc
				(start 399.492724 -436.347362)
				(mid 399.207228 -436.347362)
				(end 399.492724 -436.347362)
			)
		)
		(stroke
			(width 0)
			(type solid)
		)
		(fill yes)
		(layer "In2.Cu")
		(net "GND")
	)
	(gr_poly
		(pts
			(arc
				(start 399.492724 -435.0512)
				(mid 399.207228 -435.0512)
				(end 399.492724 -435.0512)
			)
		)
		(stroke
			(width 0)
			(type solid)
		)
		(fill yes)
		(layer "In2.Cu")
		(net "GND")
	)
	(gr_poly
		(pts
			(arc
				(start 399.492724 -433.899564)
				(mid 399.207228 -433.899564)
				(end 399.492724 -433.899564)
			)
		)
		(stroke
			(width 0)
			(type solid)
		)
		(fill yes)
		(layer "In2.Cu")
		(net "GND")
	)
	(gr_poly
		(pts
			(arc
				(start 399.492724 -432.747166)
				(mid 399.207228 -432.747166)
				(end 399.492724 -432.747166)
			)
		)
		(stroke
			(width 0)
			(type solid)
		)
		(fill yes)
		(layer "In2.Cu")
		(net "GND")
	)
	(gr_poly
		(pts
			(arc
				(start 399.492724 -431.451258)
				(mid 399.207228 -431.451258)
				(end 399.492724 -431.451258)
			)
		)
		(stroke
			(width 0)
			(type solid)
		)
		(fill yes)
		(layer "In2.Cu")
		(net "GND")
	)
	(gr_poly
		(pts
			(arc
				(start 399.492724 -430.299622)
				(mid 399.207228 -430.299622)
				(end 399.492724 -430.299622)
			)
		)
		(stroke
			(width 0)
			(type solid)
		)
		(fill yes)
		(layer "In2.Cu")
		(net "GND")
	)
	(gr_poly
		(pts
			(arc
				(start 399.492724 -429.147224)
				(mid 399.207228 -429.147224)
				(end 399.492724 -429.147224)
			)
		)
		(stroke
			(width 0)
			(type solid)
		)
		(fill yes)
		(layer "In2.Cu")
		(net "GND")
	)
	(gr_poly
		(pts
			(arc
				(start 399.492724 -427.851316)
				(mid 399.207228 -427.851316)
				(end 399.492724 -427.851316)
			)
		)
		(stroke
			(width 0)
			(type solid)
		)
		(fill yes)
		(layer "In2.Cu")
		(net "GND")
	)
	(gr_poly
		(pts
			(arc
				(start 399.492724 -426.69968)
				(mid 399.207228 -426.69968)
				(end 399.492724 -426.69968)
			)
		)
		(stroke
			(width 0)
			(type solid)
		)
		(fill yes)
		(layer "In2.Cu")
		(net "GND")
	)
	(gr_poly
		(pts
			(arc
				(start 399.492724 -425.547282)
				(mid 399.207228 -425.547282)
				(end 399.492724 -425.547282)
			)
		)
		(stroke
			(width 0)
			(type solid)
		)
		(fill yes)
		(layer "In2.Cu")
		(net "GND")
	)
	(gr_poly
		(pts
			(arc
				(start 401.49272 -439.651394)
				(mid 401.207224 -439.651394)
				(end 401.49272 -439.651394)
			)
		)
		(stroke
			(width 0)
			(type solid)
		)
		(fill yes)
		(layer "In2.Cu")
		(net "GND")
	)
	(gr_poly
		(pts
			(arc
				(start 401.49272 -438.499758)
				(mid 401.207224 -438.499758)
				(end 401.49272 -438.499758)
			)
		)
		(stroke
			(width 0)
			(type solid)
		)
		(fill yes)
		(layer "In2.Cu")
		(net "GND")
	)
	(gr_poly
		(pts
			(arc
				(start 401.49272 -437.34736)
				(mid 401.207224 -437.34736)
				(end 401.49272 -437.34736)
			)
		)
		(stroke
			(width 0)
			(type solid)
		)
		(fill yes)
		(layer "In2.Cu")
		(net "GND")
	)
	(gr_poly
		(pts
			(arc
				(start 401.49272 -436.051198)
				(mid 401.207224 -436.051198)
				(end 401.49272 -436.051198)
			)
		)
		(stroke
			(width 0)
			(type solid)
		)
		(fill yes)
		(layer "In2.Cu")
		(net "GND")
	)
	(gr_poly
		(pts
			(arc
				(start 401.49272 -434.899562)
				(mid 401.207224 -434.899562)
				(end 401.49272 -434.899562)
			)
		)
		(stroke
			(width 0)
			(type solid)
		)
		(fill yes)
		(layer "In2.Cu")
		(net "GND")
	)
	(gr_poly
		(pts
			(arc
				(start 401.49272 -433.747164)
				(mid 401.207224 -433.747164)
				(end 401.49272 -433.747164)
			)
		)
		(stroke
			(width 0)
			(type solid)
		)
		(fill yes)
		(layer "In2.Cu")
		(net "GND")
	)
	(gr_poly
		(pts
			(arc
				(start 401.49272 -432.451256)
				(mid 401.207224 -432.451256)
				(end 401.49272 -432.451256)
			)
		)
		(stroke
			(width 0)
			(type solid)
		)
		(fill yes)
		(layer "In2.Cu")
		(net "GND")
	)
	(gr_poly
		(pts
			(arc
				(start 401.49272 -431.29962)
				(mid 401.207224 -431.29962)
				(end 401.49272 -431.29962)
			)
		)
		(stroke
			(width 0)
			(type solid)
		)
		(fill yes)
		(layer "In2.Cu")
		(net "GND")
	)
	(gr_poly
		(pts
			(arc
				(start 401.49272 -430.147222)
				(mid 401.207224 -430.147222)
				(end 401.49272 -430.147222)
			)
		)
		(stroke
			(width 0)
			(type solid)
		)
		(fill yes)
		(layer "In2.Cu")
		(net "GND")
	)
	(gr_poly
		(pts
			(arc
				(start 401.49272 -428.851314)
				(mid 401.207224 -428.851314)
				(end 401.49272 -428.851314)
			)
		)
		(stroke
			(width 0)
			(type solid)
		)
		(fill yes)
		(layer "In2.Cu")
		(net "GND")
	)
	(gr_poly
		(pts
			(arc
				(start 401.49272 -427.699678)
				(mid 401.207224 -427.699678)
				(end 401.49272 -427.699678)
			)
		)
		(stroke
			(width 0)
			(type solid)
		)
		(fill yes)
		(layer "In2.Cu")
		(net "GND")
	)
	(gr_poly
		(pts
			(arc
				(start 401.49272 -426.54728)
				(mid 401.207224 -426.54728)
				(end 401.49272 -426.54728)
			)
		)
		(stroke
			(width 0)
			(type solid)
		)
		(fill yes)
		(layer "In2.Cu")
		(net "GND")
	)
	(gr_poly
		(pts
			(arc
				(start 403.492716 -438.651396)
				(mid 403.20722 -438.651396)
				(end 403.492716 -438.651396)
			)
		)
		(stroke
			(width 0)
			(type solid)
		)
		(fill yes)
		(layer "In2.Cu")
		(net "GND")
	)
	(gr_poly
		(pts
			(arc
				(start 403.492716 -437.49976)
				(mid 403.20722 -437.49976)
				(end 403.492716 -437.49976)
			)
		)
		(stroke
			(width 0)
			(type solid)
		)
		(fill yes)
		(layer "In2.Cu")
		(net "GND")
	)
	(gr_poly
		(pts
			(arc
				(start 403.492716 -436.347362)
				(mid 403.20722 -436.347362)
				(end 403.492716 -436.347362)
			)
		)
		(stroke
			(width 0)
			(type solid)
		)
		(fill yes)
		(layer "In2.Cu")
		(net "GND")
	)
	(gr_poly
		(pts
			(arc
				(start 403.492716 -435.0512)
				(mid 403.20722 -435.0512)
				(end 403.492716 -435.0512)
			)
		)
		(stroke
			(width 0)
			(type solid)
		)
		(fill yes)
		(layer "In2.Cu")
		(net "GND")
	)
	(gr_poly
		(pts
			(arc
				(start 403.492716 -433.899564)
				(mid 403.20722 -433.899564)
				(end 403.492716 -433.899564)
			)
		)
		(stroke
			(width 0)
			(type solid)
		)
		(fill yes)
		(layer "In2.Cu")
		(net "GND")
	)
	(gr_poly
		(pts
			(arc
				(start 403.492716 -432.747166)
				(mid 403.20722 -432.747166)
				(end 403.492716 -432.747166)
			)
		)
		(stroke
			(width 0)
			(type solid)
		)
		(fill yes)
		(layer "In2.Cu")
		(net "GND")
	)
	(gr_poly
		(pts
			(arc
				(start 403.492716 -431.451258)
				(mid 403.20722 -431.451258)
				(end 403.492716 -431.451258)
			)
		)
		(stroke
			(width 0)
			(type solid)
		)
		(fill yes)
		(layer "In2.Cu")
		(net "GND")
	)
	(gr_poly
		(pts
			(arc
				(start 403.492716 -430.299622)
				(mid 403.20722 -430.299622)
				(end 403.492716 -430.299622)
			)
		)
		(stroke
			(width 0)
			(type solid)
		)
		(fill yes)
		(layer "In2.Cu")
		(net "GND")
	)
	(gr_poly
		(pts
			(arc
				(start 403.492716 -429.147224)
				(mid 403.20722 -429.147224)
				(end 403.492716 -429.147224)
			)
		)
		(stroke
			(width 0)
			(type solid)
		)
		(fill yes)
		(layer "In2.Cu")
		(net "GND")
	)
	(gr_poly
		(pts
			(arc
				(start 403.492716 -427.851316)
				(mid 403.20722 -427.851316)
				(end 403.492716 -427.851316)
			)
		)
		(stroke
			(width 0)
			(type solid)
		)
		(fill yes)
		(layer "In2.Cu")
		(net "GND")
	)
	(gr_poly
		(pts
			(arc
				(start 403.492716 -426.69968)
				(mid 403.20722 -426.69968)
				(end 403.492716 -426.69968)
			)
		)
		(stroke
			(width 0)
			(type solid)
		)
		(fill yes)
		(layer "In2.Cu")
		(net "GND")
	)
	(gr_poly
		(pts
			(arc
				(start 403.492716 -425.547282)
				(mid 403.20722 -425.547282)
				(end 403.492716 -425.547282)
			)
		)
		(stroke
			(width 0)
			(type solid)
		)
		(fill yes)
		(layer "In2.Cu")
		(net "GND")
	)
	(gr_poly
		(pts
			(arc
				(start 405.492712 -439.651394)
				(mid 405.207216 -439.651394)
				(end 405.492712 -439.651394)
			)
		)
		(stroke
			(width 0)
			(type solid)
		)
		(fill yes)
		(layer "In2.Cu")
		(net "GND")
	)
	(gr_poly
		(pts
			(arc
				(start 405.492712 -438.499758)
				(mid 405.207216 -438.499758)
				(end 405.492712 -438.499758)
			)
		)
		(stroke
			(width 0)
			(type solid)
		)
		(fill yes)
		(layer "In2.Cu")
		(net "GND")
	)
	(gr_poly
		(pts
			(arc
				(start 405.492712 -437.34736)
				(mid 405.207216 -437.34736)
				(end 405.492712 -437.34736)
			)
		)
		(stroke
			(width 0)
			(type solid)
		)
		(fill yes)
		(layer "In2.Cu")
		(net "GND")
	)
	(gr_poly
		(pts
			(arc
				(start 405.492712 -436.051198)
				(mid 405.207216 -436.051198)
				(end 405.492712 -436.051198)
			)
		)
		(stroke
			(width 0)
			(type solid)
		)
		(fill yes)
		(layer "In2.Cu")
		(net "GND")
	)
	(gr_poly
		(pts
			(arc
				(start 405.492712 -434.899562)
				(mid 405.207216 -434.899562)
				(end 405.492712 -434.899562)
			)
		)
		(stroke
			(width 0)
			(type solid)
		)
		(fill yes)
		(layer "In2.Cu")
		(net "GND")
	)
	(gr_poly
		(pts
			(arc
				(start 405.492712 -433.747164)
				(mid 405.207216 -433.747164)
				(end 405.492712 -433.747164)
			)
		)
		(stroke
			(width 0)
			(type solid)
		)
		(fill yes)
		(layer "In2.Cu")
		(net "GND")
	)
	(gr_poly
		(pts
			(arc
				(start 405.492712 -432.451256)
				(mid 405.207216 -432.451256)
				(end 405.492712 -432.451256)
			)
		)
		(stroke
			(width 0)
			(type solid)
		)
		(fill yes)
		(layer "In2.Cu")
		(net "GND")
	)
	(gr_poly
		(pts
			(arc
				(start 405.492712 -431.29962)
				(mid 405.207216 -431.29962)
				(end 405.492712 -431.29962)
			)
		)
		(stroke
			(width 0)
			(type solid)
		)
		(fill yes)
		(layer "In2.Cu")
		(net "GND")
	)
	(gr_poly
		(pts
			(arc
				(start 405.492712 -430.147222)
				(mid 405.207216 -430.147222)
				(end 405.492712 -430.147222)
			)
		)
		(stroke
			(width 0)
			(type solid)
		)
		(fill yes)
		(layer "In2.Cu")
		(net "GND")
	)
	(gr_poly
		(pts
			(arc
				(start 405.492712 -428.851314)
				(mid 405.207216 -428.851314)
				(end 405.492712 -428.851314)
			)
		)
		(stroke
			(width 0)
			(type solid)
		)
		(fill yes)
		(layer "In2.Cu")
		(net "GND")
	)
	(gr_poly
		(pts
			(arc
				(start 405.492712 -427.699678)
				(mid 405.207216 -427.699678)
				(end 405.492712 -427.699678)
			)
		)
		(stroke
			(width 0)
			(type solid)
		)
		(fill yes)
		(layer "In2.Cu")
		(net "GND")
	)
	(gr_poly
		(pts
			(arc
				(start 405.492712 -426.54728)
				(mid 405.207216 -426.54728)
				(end 405.492712 -426.54728)
			)
		)
		(stroke
			(width 0)
			(type solid)
		)
		(fill yes)
		(layer "In2.Cu")
		(net "GND")
	)
	(gr_poly
		(pts
			(arc
				(start 407.492708 -438.651396)
				(mid 407.207212 -438.651396)
				(end 407.492708 -438.651396)
			)
		)
		(stroke
			(width 0)
			(type solid)
		)
		(fill yes)
		(layer "In2.Cu")
		(net "GND")
	)
	(gr_poly
		(pts
			(arc
				(start 407.492708 -437.49976)
				(mid 407.207212 -437.49976)
				(end 407.492708 -437.49976)
			)
		)
		(stroke
			(width 0)
			(type solid)
		)
		(fill yes)
		(layer "In2.Cu")
		(net "GND")
	)
	(gr_poly
		(pts
			(arc
				(start 407.492708 -436.347362)
				(mid 407.207212 -436.347362)
				(end 407.492708 -436.347362)
			)
		)
		(stroke
			(width 0)
			(type solid)
		)
		(fill yes)
		(layer "In2.Cu")
		(net "GND")
	)
	(gr_poly
		(pts
			(arc
				(start 407.492708 -435.0512)
				(mid 407.207212 -435.0512)
				(end 407.492708 -435.0512)
			)
		)
		(stroke
			(width 0)
			(type solid)
		)
		(fill yes)
		(layer "In2.Cu")
		(net "GND")
	)
	(gr_poly
		(pts
			(arc
				(start 407.492708 -433.899564)
				(mid 407.207212 -433.899564)
				(end 407.492708 -433.899564)
			)
		)
		(stroke
			(width 0)
			(type solid)
		)
		(fill yes)
		(layer "In2.Cu")
		(net "GND")
	)
	(gr_poly
		(pts
			(arc
				(start 407.492708 -432.747166)
				(mid 407.207212 -432.747166)
				(end 407.492708 -432.747166)
			)
		)
		(stroke
			(width 0)
			(type solid)
		)
		(fill yes)
		(layer "In2.Cu")
		(net "GND")
	)
	(gr_poly
		(pts
			(arc
				(start 407.492708 -431.451258)
				(mid 407.207212 -431.451258)
				(end 407.492708 -431.451258)
			)
		)
		(stroke
			(width 0)
			(type solid)
		)
		(fill yes)
		(layer "In2.Cu")
		(net "GND")
	)
	(gr_poly
		(pts
			(arc
				(start 407.492708 -430.299622)
				(mid 407.207212 -430.299622)
				(end 407.492708 -430.299622)
			)
		)
		(stroke
			(width 0)
			(type solid)
		)
		(fill yes)
		(layer "In2.Cu")
		(net "GND")
	)
	(gr_poly
		(pts
			(arc
				(start 407.492708 -429.147224)
				(mid 407.207212 -429.147224)
				(end 407.492708 -429.147224)
			)
		)
		(stroke
			(width 0)
			(type solid)
		)
		(fill yes)
		(layer "In2.Cu")
		(net "GND")
	)
	(gr_poly
		(pts
			(arc
				(start 407.492708 -427.851316)
				(mid 407.207212 -427.851316)
				(end 407.492708 -427.851316)
			)
		)
		(stroke
			(width 0)
			(type solid)
		)
		(fill yes)
		(layer "In2.Cu")
		(net "GND")
	)
	(gr_poly
		(pts
			(arc
				(start 407.492708 -426.69968)
				(mid 407.207212 -426.69968)
				(end 407.492708 -426.69968)
			)
		)
		(stroke
			(width 0)
			(type solid)
		)
		(fill yes)
		(layer "In2.Cu")
		(net "GND")
	)
	(gr_poly
		(pts
			(arc
				(start 407.492708 -425.547282)
				(mid 407.207212 -425.547282)
				(end 407.492708 -425.547282)
			)
		)
		(stroke
			(width 0)
			(type solid)
		)
		(fill yes)
		(layer "In2.Cu")
		(net "GND")
	)
	(gr_poly
		(pts
			(arc
				(start 409.492704 -439.651394)
				(mid 409.207208 -439.651394)
				(end 409.492704 -439.651394)
			)
		)
		(stroke
			(width 0)
			(type solid)
		)
		(fill yes)
		(layer "In2.Cu")
		(net "GND")
	)
	(gr_poly
		(pts
			(arc
				(start 409.492704 -438.499758)
				(mid 409.207208 -438.499758)
				(end 409.492704 -438.499758)
			)
		)
		(stroke
			(width 0)
			(type solid)
		)
		(fill yes)
		(layer "In2.Cu")
		(net "GND")
	)
	(gr_poly
		(pts
			(arc
				(start 409.492704 -437.34736)
				(mid 409.207208 -437.34736)
				(end 409.492704 -437.34736)
			)
		)
		(stroke
			(width 0)
			(type solid)
		)
		(fill yes)
		(layer "In2.Cu")
		(net "GND")
	)
	(gr_poly
		(pts
			(arc
				(start 409.492704 -436.051198)
				(mid 409.207208 -436.051198)
				(end 409.492704 -436.051198)
			)
		)
		(stroke
			(width 0)
			(type solid)
		)
		(fill yes)
		(layer "In2.Cu")
		(net "GND")
	)
	(gr_poly
		(pts
			(arc
				(start 409.492704 -434.899562)
				(mid 409.207208 -434.899562)
				(end 409.492704 -434.899562)
			)
		)
		(stroke
			(width 0)
			(type solid)
		)
		(fill yes)
		(layer "In2.Cu")
		(net "GND")
	)
	(gr_poly
		(pts
			(arc
				(start 409.492704 -433.747164)
				(mid 409.207208 -433.747164)
				(end 409.492704 -433.747164)
			)
		)
		(stroke
			(width 0)
			(type solid)
		)
		(fill yes)
		(layer "In2.Cu")
		(net "GND")
	)
	(gr_poly
		(pts
			(arc
				(start 409.492704 -432.451256)
				(mid 409.207208 -432.451256)
				(end 409.492704 -432.451256)
			)
		)
		(stroke
			(width 0)
			(type solid)
		)
		(fill yes)
		(layer "In2.Cu")
		(net "GND")
	)
	(gr_poly
		(pts
			(arc
				(start 409.492704 -431.29962)
				(mid 409.207208 -431.29962)
				(end 409.492704 -431.29962)
			)
		)
		(stroke
			(width 0)
			(type solid)
		)
		(fill yes)
		(layer "In2.Cu")
		(net "GND")
	)
	(gr_poly
		(pts
			(arc
				(start 409.492704 -430.147222)
				(mid 409.207208 -430.147222)
				(end 409.492704 -430.147222)
			)
		)
		(stroke
			(width 0)
			(type solid)
		)
		(fill yes)
		(layer "In2.Cu")
		(net "GND")
	)
	(gr_poly
		(pts
			(arc
				(start 409.492704 -428.851314)
				(mid 409.207208 -428.851314)
				(end 409.492704 -428.851314)
			)
		)
		(stroke
			(width 0)
			(type solid)
		)
		(fill yes)
		(layer "In2.Cu")
		(net "GND")
	)
	(gr_poly
		(pts
			(arc
				(start 409.492704 -427.699678)
				(mid 409.207208 -427.699678)
				(end 409.492704 -427.699678)
			)
		)
		(stroke
			(width 0)
			(type solid)
		)
		(fill yes)
		(layer "In2.Cu")
		(net "GND")
	)
	(gr_poly
		(pts
			(arc
				(start 409.492704 -426.54728)
				(mid 409.207208 -426.54728)
				(end 409.492704 -426.54728)
			)
		)
		(stroke
			(width 0)
			(type solid)
		)
		(fill yes)
		(layer "In2.Cu")
		(net "GND")
	)
	(gr_poly
		(pts
			(arc
				(start 411.4927 -438.651396)
				(mid 411.207204 -438.651396)
				(end 411.4927 -438.651396)
			)
		)
		(stroke
			(width 0)
			(type solid)
		)
		(fill yes)
		(layer "In2.Cu")
		(net "GND")
	)
	(gr_poly
		(pts
			(arc
				(start 411.4927 -437.49976)
				(mid 411.207204 -437.49976)
				(end 411.4927 -437.49976)
			)
		)
		(stroke
			(width 0)
			(type solid)
		)
		(fill yes)
		(layer "In2.Cu")
		(net "GND")
	)
	(gr_poly
		(pts
			(arc
				(start 411.4927 -436.347362)
				(mid 411.207204 -436.347362)
				(end 411.4927 -436.347362)
			)
		)
		(stroke
			(width 0)
			(type solid)
		)
		(fill yes)
		(layer "In2.Cu")
		(net "GND")
	)
	(gr_poly
		(pts
			(arc
				(start 411.4927 -435.0512)
				(mid 411.207204 -435.0512)
				(end 411.4927 -435.0512)
			)
		)
		(stroke
			(width 0)
			(type solid)
		)
		(fill yes)
		(layer "In2.Cu")
		(net "GND")
	)
	(gr_poly
		(pts
			(arc
				(start 411.4927 -433.899564)
				(mid 411.207204 -433.899564)
				(end 411.4927 -433.899564)
			)
		)
		(stroke
			(width 0)
			(type solid)
		)
		(fill yes)
		(layer "In2.Cu")
		(net "GND")
	)
	(gr_poly
		(pts
			(arc
				(start 411.4927 -432.747166)
				(mid 411.207204 -432.747166)
				(end 411.4927 -432.747166)
			)
		)
		(stroke
			(width 0)
			(type solid)
		)
		(fill yes)
		(layer "In2.Cu")
		(net "GND")
	)
	(gr_poly
		(pts
			(arc
				(start 411.4927 -431.451258)
				(mid 411.207204 -431.451258)
				(end 411.4927 -431.451258)
			)
		)
		(stroke
			(width 0)
			(type solid)
		)
		(fill yes)
		(layer "In2.Cu")
		(net "GND")
	)
	(gr_poly
		(pts
			(arc
				(start 411.4927 -430.299622)
				(mid 411.207204 -430.299622)
				(end 411.4927 -430.299622)
			)
		)
		(stroke
			(width 0)
			(type solid)
		)
		(fill yes)
		(layer "In2.Cu")
		(net "GND")
	)
	(gr_poly
		(pts
			(arc
				(start 411.4927 -429.147224)
				(mid 411.207204 -429.147224)
				(end 411.4927 -429.147224)
			)
		)
		(stroke
			(width 0)
			(type solid)
		)
		(fill yes)
		(layer "In2.Cu")
		(net "GND")
	)
	(gr_poly
		(pts
			(arc
				(start 411.4927 -427.851316)
				(mid 411.207204 -427.851316)
				(end 411.4927 -427.851316)
			)
		)
		(stroke
			(width 0)
			(type solid)
		)
		(fill yes)
		(layer "In2.Cu")
		(net "GND")
	)
	(gr_poly
		(pts
			(arc
				(start 411.4927 -426.69968)
				(mid 411.207204 -426.69968)
				(end 411.4927 -426.69968)
			)
		)
		(stroke
			(width 0)
			(type solid)
		)
		(fill yes)
		(layer "In2.Cu")
		(net "GND")
	)
	(gr_poly
		(pts
			(arc
				(start 411.4927 -425.547282)
				(mid 411.207204 -425.547282)
				(end 411.4927 -425.547282)
			)
		)
		(stroke
			(width 0)
			(type solid)
		)
		(fill yes)
		(layer "In2.Cu")
		(net "GND")
	)
	(gr_poly
		(pts
			(arc
				(start 413.492696 -439.651394)
				(mid 413.2072 -439.651394)
				(end 413.492696 -439.651394)
			)
		)
		(stroke
			(width 0)
			(type solid)
		)
		(fill yes)
		(layer "In2.Cu")
		(net "GND")
	)
	(gr_poly
		(pts
			(arc
				(start 413.492696 -438.499758)
				(mid 413.2072 -438.499758)
				(end 413.492696 -438.499758)
			)
		)
		(stroke
			(width 0)
			(type solid)
		)
		(fill yes)
		(layer "In2.Cu")
		(net "GND")
	)
	(gr_poly
		(pts
			(arc
				(start 413.492696 -437.34736)
				(mid 413.2072 -437.34736)
				(end 413.492696 -437.34736)
			)
		)
		(stroke
			(width 0)
			(type solid)
		)
		(fill yes)
		(layer "In2.Cu")
		(net "GND")
	)
	(gr_poly
		(pts
			(arc
				(start 413.492696 -436.051198)
				(mid 413.2072 -436.051198)
				(end 413.492696 -436.051198)
			)
		)
		(stroke
			(width 0)
			(type solid)
		)
		(fill yes)
		(layer "In2.Cu")
		(net "GND")
	)
	(gr_poly
		(pts
			(arc
				(start 413.492696 -434.899562)
				(mid 413.2072 -434.899562)
				(end 413.492696 -434.899562)
			)
		)
		(stroke
			(width 0)
			(type solid)
		)
		(fill yes)
		(layer "In2.Cu")
		(net "GND")
	)
	(gr_poly
		(pts
			(arc
				(start 413.492696 -433.747164)
				(mid 413.2072 -433.747164)
				(end 413.492696 -433.747164)
			)
		)
		(stroke
			(width 0)
			(type solid)
		)
		(fill yes)
		(layer "In2.Cu")
		(net "GND")
	)
	(gr_poly
		(pts
			(arc
				(start 413.492696 -432.451256)
				(mid 413.2072 -432.451256)
				(end 413.492696 -432.451256)
			)
		)
		(stroke
			(width 0)
			(type solid)
		)
		(fill yes)
		(layer "In2.Cu")
		(net "GND")
	)
	(gr_poly
		(pts
			(arc
				(start 413.492696 -431.29962)
				(mid 413.2072 -431.29962)
				(end 413.492696 -431.29962)
			)
		)
		(stroke
			(width 0)
			(type solid)
		)
		(fill yes)
		(layer "In2.Cu")
		(net "GND")
	)
	(gr_poly
		(pts
			(arc
				(start 413.492696 -430.147222)
				(mid 413.2072 -430.147222)
				(end 413.492696 -430.147222)
			)
		)
		(stroke
			(width 0)
			(type solid)
		)
		(fill yes)
		(layer "In2.Cu")
		(net "GND")
	)
	(gr_poly
		(pts
			(arc
				(start 413.492696 -428.851314)
				(mid 413.2072 -428.851314)
				(end 413.492696 -428.851314)
			)
		)
		(stroke
			(width 0)
			(type solid)
		)
		(fill yes)
		(layer "In2.Cu")
		(net "GND")
	)
	(gr_poly
		(pts
			(arc
				(start 413.492696 -427.699678)
				(mid 413.2072 -427.699678)
				(end 413.492696 -427.699678)
			)
		)
		(stroke
			(width 0)
			(type solid)
		)
		(fill yes)
		(layer "In2.Cu")
		(net "GND")
	)
	(gr_poly
		(pts
			(arc
				(start 413.492696 -426.54728)
				(mid 413.2072 -426.54728)
				(end 413.492696 -426.54728)
			)
		)
		(stroke
			(width 0)
			(type solid)
		)
		(fill yes)
		(layer "In2.Cu")
		(net "GND")
	)
	(gr_poly
		(pts
			(arc
				(start 168.189656 -10.603992)
				(mid 167.869616 -10.603992)
				(end 168.189656 -10.603992)
			)
		)
		(stroke
			(width 0)
			(type solid)
		)
		(fill yes)
		(layer "In2.Cu")
		(net "GND")
	)
	(gr_poly
		(pts
			(arc
				(start 168.19372 -11.463782)
				(mid 167.87368 -11.463782)
				(end 168.19372 -11.463782)
			)
		)
		(stroke
			(width 0)
			(type solid)
		)
		(fill yes)
		(layer "In2.Cu")
		(net "GND")
	)
	(gr_poly
		(pts
			(arc
				(start 170.03522 -11.496548)
				(mid 169.71518 -11.496548)
				(end 170.03522 -11.496548)
			)
		)
		(stroke
			(width 0)
			(type solid)
		)
		(fill yes)
		(layer "In2.Cu")
		(net "GND")
	)
	(gr_poly
		(pts
			(arc
				(start 170.087036 -10.591292)
				(mid 169.766996 -10.591292)
				(end 170.087036 -10.591292)
			)
		)
		(stroke
			(width 0)
			(type solid)
		)
		(fill yes)
		(layer "In2.Cu")
		(net "GND")
	)
	(gr_poly
		(pts
			(arc
				(start 372.600728 -160.435036)
				(mid 372.275608 -160.435036)
				(end 372.600728 -160.435036)
			)
		)
		(stroke
			(width 0)
			(type solid)
		)
		(fill yes)
		(layer "In2.Cu")
		(net "GND")
	)
	(gr_poly
		(pts
			(arc
				(start 374.362472 -160.435036)
				(mid 374.037352 -160.435036)
				(end 374.362472 -160.435036)
			)
		)
		(stroke
			(width 0)
			(type solid)
		)
		(fill yes)
		(layer "In2.Cu")
		(net "GND")
	)
	(gr_poly
		(pts
			(arc
				(start 18.8214 -398.782032)
				(mid 18.480532 -398.782032)
				(end 18.8214 -398.782032)
			)
		)
		(stroke
			(width 0)
			(type solid)
		)
		(fill yes)
		(layer "In2.Cu")
		(net "GND")
	)
	(gr_poly
		(pts
			(arc
				(start 20.087844 -398.782032)
				(mid 19.746976 -398.782032)
				(end 20.087844 -398.782032)
			)
		)
		(stroke
			(width 0)
			(type solid)
		)
		(fill yes)
		(layer "In2.Cu")
		(net "GND")
	)
	(gr_poly
		(pts
			(arc
				(start 25.684988 -399.974816)
				(mid 25.34412 -399.974816)
				(end 25.684988 -399.974816)
			)
		)
		(stroke
			(width 0)
			(type solid)
		)
		(fill yes)
		(layer "In2.Cu")
		(net "GND")
	)
	(gr_poly
		(pts
			(arc
				(start 27.462988 -399.974816)
				(mid 27.12212 -399.974816)
				(end 27.462988 -399.974816)
			)
		)
		(stroke
			(width 0)
			(type solid)
		)
		(fill yes)
		(layer "In2.Cu")
		(net "GND")
	)
	(gr_poly
		(pts
			(arc
				(start 103.43261 -404.167848)
				(mid 103.082598 -404.167848)
				(end 103.43261 -404.167848)
			)
		)
		(stroke
			(width 0)
			(type solid)
		)
		(fill yes)
		(layer "In2.Cu")
		(net "GND")
	)
	(gr_poly
		(pts
			(arc
				(start 131.715002 -10.733278)
				(mid 131.38531 -10.733278)
				(end 131.715002 -10.733278)
			)
		)
		(stroke
			(width 0)
			(type solid)
		)
		(fill yes)
		(layer "In2.Cu")
		(net "GND")
	)
	(gr_poly
		(pts
			(arc
				(start 133.525768 -10.733278)
				(mid 133.174232 -10.733278)
				(end 133.525768 -10.733278)
			)
		)
		(stroke
			(width 0)
			(type solid)
		)
		(fill yes)
		(layer "In2.Cu")
		(net "GND")
	)
	(gr_poly
		(pts
			(arc
				(start 337.37804 -137.172446)
				(mid 337.043268 -137.172446)
				(end 337.37804 -137.172446)
			)
		)
		(stroke
			(width 0)
			(type solid)
		)
		(fill yes)
		(layer "In2.Cu")
		(net "GND")
	)
	(gr_poly
		(pts
			(arc
				(start 339.420708 -137.172192)
				(mid 339.085936 -137.172192)
				(end 339.420708 -137.172192)
			)
		)
		(stroke
			(width 0)
			(type solid)
		)
		(fill yes)
		(layer "In2.Cu")
		(net "GND")
	)
	(gr_poly
		(pts
			(arc
				(start 340.184994 -138.07186)
				(mid 339.850222 -138.07186)
				(end 340.184994 -138.07186)
			)
		)
		(stroke
			(width 0)
			(type solid)
		)
		(fill yes)
		(layer "In2.Cu")
		(net "GND")
	)
	(gr_poly
		(pts
			(arc
				(start 340.184994 -136.310116)
				(mid 339.850222 -136.310116)
				(end 340.184994 -136.310116)
			)
		)
		(stroke
			(width 0)
			(type solid)
		)
		(fill yes)
		(layer "In2.Cu")
		(net "GND")
	)
	(gr_poly
		(pts
			(arc
				(start 390.445244 -149.609048)
				(mid 390.110472 -149.609048)
				(end 390.445244 -149.609048)
			)
		)
		(stroke
			(width 0)
			(type solid)
		)
		(fill yes)
		(layer "In2.Cu")
		(net "GND")
	)
	(gr_poly
		(pts
			(arc
				(start 391.565384 -146.436588)
				(mid 391.230612 -146.436588)
				(end 391.565384 -146.436588)
			)
		)
		(stroke
			(width 0)
			(type solid)
		)
		(fill yes)
		(layer "In2.Cu")
		(net "GND")
	)
	(gr_poly
		(pts
			(arc
				(start 393.184634 -147.08632)
				(mid 392.849862 -147.08632)
				(end 393.184634 -147.08632)
			)
		)
		(stroke
			(width 0)
			(type solid)
		)
		(fill yes)
		(layer "In2.Cu")
		(net "GND")
	)
	(gr_poly
		(pts
			(arc
				(start 79.38516 -152.085548)
				(mid 79.0194 -152.085548)
				(end 79.38516 -152.085548)
			)
		)
		(stroke
			(width 0)
			(type solid)
		)
		(fill yes)
		(layer "In2.Cu")
		(net "GND")
	)
	(gr_poly
		(pts
			(arc
				(start 79.98968 -148.661628)
				(mid 79.62392 -148.661628)
				(end 79.98968 -148.661628)
			)
		)
		(stroke
			(width 0)
			(type solid)
		)
		(fill yes)
		(layer "In2.Cu")
		(net "GND")
	)
	(gr_poly
		(pts
			(arc
				(start 80.4672 -146.878548)
				(mid 80.10144 -146.878548)
				(end 80.4672 -146.878548)
			)
		)
		(stroke
			(width 0)
			(type solid)
		)
		(fill yes)
		(layer "In2.Cu")
		(net "GND")
	)
	(gr_poly
		(pts
			(arc
				(start 98.25736 -55.961788)
				(mid 97.8916 -55.961788)
				(end 98.25736 -55.961788)
			)
		)
		(stroke
			(width 0)
			(type solid)
		)
		(fill yes)
		(layer "In2.Cu")
		(net "GND")
	)
	(gr_poly
		(pts
			(arc
				(start 103.445056 -405.426672)
				(mid 103.070152 -405.426672)
				(end 103.445056 -405.426672)
			)
		)
		(stroke
			(width 0)
			(type solid)
		)
		(fill yes)
		(layer "In2.Cu")
		(net "GND")
	)
	(gr_poly
		(pts
			(arc
				(start 174.643796 -11.100054)
				(mid 174.278036 -11.100054)
				(end 174.643796 -11.100054)
			)
		)
		(stroke
			(width 0)
			(type solid)
		)
		(fill yes)
		(layer "In2.Cu")
		(net "GND")
	)
	(gr_poly
		(pts
			(arc
				(start 348.648274 -170.930316)
				(mid 348.277942 -170.930316)
				(end 348.648274 -170.930316)
			)
		)
		(stroke
			(width 0)
			(type solid)
		)
		(fill yes)
		(layer "In2.Cu")
		(net "GND")
	)
	(gr_poly
		(pts
			(arc
				(start 350.985074 -172.784516)
				(mid 350.614742 -172.784516)
				(end 350.985074 -172.784516)
			)
		)
		(stroke
			(width 0)
			(type solid)
		)
		(fill yes)
		(layer "In2.Cu")
		(net "GND")
	)
	(gr_poly
		(pts
			(arc
				(start 350.99244 -172.790612)
				(mid 350.622108 -172.790612)
				(end 350.99244 -172.790612)
			)
		)
		(stroke
			(width 0)
			(type solid)
		)
		(fill yes)
		(layer "In2.Cu")
		(net "GND")
	)
	(gr_poly
		(pts
			(arc
				(start 352.458274 -171.565316)
				(mid 352.087942 -171.565316)
				(end 352.458274 -171.565316)
			)
		)
		(stroke
			(width 0)
			(type solid)
		)
		(fill yes)
		(layer "In2.Cu")
		(net "GND")
	)
	(gr_poly
		(pts
			(xy 245.03126 -251.765308) (xy 245.03126 -247.239028) (xy 244.602 -246.809768) (xy 240.5253 -246.809768)
			(xy 240.23574 -247.099328) (xy 240.23574 -249.273568) (xy 240.806222 -249.273568) (xy 240.810293 -249.217946)
			(xy 240.822419 -249.163509) (xy 240.842342 -249.111418) (xy 240.869638 -249.062783) (xy 240.903724 -249.01864)
			(xy 240.943873 -248.979931) (xy 240.989231 -248.94748) (xy 241.038831 -248.921979) (xy 241.091615 -248.903972)
			(xy 241.146458 -248.893842) (xy 241.202192 -248.891805) (xy 241.257629 -248.897905) (xy 241.311586 -248.912011)
			(xy 241.362915 -248.933823) (xy 241.410521 -248.962877) (xy 241.453389 -248.998552) (xy 241.490606 -249.040089)
			(xy 241.521379 -249.086602) (xy 241.545051 -249.137099) (xy 241.561119 -249.190506) (xy 241.569239 -249.245682)
			(xy 241.569748 -249.273568) (xy 241.569239 -249.301454) (xy 241.561119 -249.35663) (xy 241.545051 -249.410037)
			(xy 241.521379 -249.460534) (xy 241.490606 -249.507047) (xy 241.453389 -249.548584) (xy 241.410521 -249.584259)
			(xy 241.362915 -249.613313) (xy 241.311586 -249.635125) (xy 241.257629 -249.649231) (xy 241.202192 -249.655331)
			(xy 241.146458 -249.653294) (xy 241.091615 -249.643164) (xy 241.038831 -249.625157) (xy 240.989231 -249.599656)
			(xy 240.943873 -249.567205) (xy 240.903724 -249.528496) (xy 240.869638 -249.484353) (xy 240.842342 -249.435718)
			(xy 240.822419 -249.383627) (xy 240.810293 -249.32919) (xy 240.806222 -249.273568) (xy 240.23574 -249.273568)
			(xy 240.23574 -251.965968) (xy 240.46434 -252.194568) (xy 244.602 -252.194568)
		)
		(stroke
			(width 0)
			(type solid)
		)
		(fill yes)
		(layer "In2.Cu")
		(net "GND")
	)
	(gr_poly
		(pts
			(xy 319.2526 -138.0871) (xy 319.2526 -132.1562) (xy 318.77 -131.6736) (xy 310.6674 -131.6736) (xy 302.6664 -139.6746)
			(xy 302.6664 -149.2123) (xy 302.987456 -149.533356) (xy 304.17084 -149.533356) (xy 304.174911 -149.477734)
			(xy 304.187037 -149.423297) (xy 304.20696 -149.371206) (xy 304.234256 -149.322571) (xy 304.268342 -149.278428)
			(xy 304.308491 -149.239719) (xy 304.353849 -149.207268) (xy 304.403449 -149.181767) (xy 304.456233 -149.16376)
			(xy 304.511076 -149.15363) (xy 304.56681 -149.151593) (xy 304.622247 -149.157693) (xy 304.676204 -149.171799)
			(xy 304.727533 -149.193611) (xy 304.775139 -149.222665) (xy 304.818007 -149.25834) (xy 304.855224 -149.299877)
			(xy 304.885997 -149.34639) (xy 304.909669 -149.396887) (xy 304.925737 -149.450294) (xy 304.933857 -149.50547)
			(xy 304.934366 -149.533356) (xy 304.933857 -149.561242) (xy 304.925737 -149.616418) (xy 304.909669 -149.669825)
			(xy 304.885997 -149.720322) (xy 304.855224 -149.766835) (xy 304.818007 -149.808372) (xy 304.775139 -149.844047)
			(xy 304.727533 -149.873101) (xy 304.676204 -149.894913) (xy 304.622247 -149.909019) (xy 304.56681 -149.915119)
			(xy 304.511076 -149.913082) (xy 304.456233 -149.902952) (xy 304.403449 -149.884945) (xy 304.353849 -149.859444)
			(xy 304.308491 -149.826993) (xy 304.268342 -149.788284) (xy 304.234256 -149.744141) (xy 304.20696 -149.695506)
			(xy 304.187037 -149.643415) (xy 304.174911 -149.588978) (xy 304.17084 -149.533356) (xy 302.987456 -149.533356)
			(xy 303.53 -150.0759) (xy 307.2638 -150.0759)
		)
		(stroke
			(width 0)
			(type solid)
		)
		(fill yes)
		(layer "In2.Cu")
		(net "P3V3_AUX")
	)
	(gr_poly
		(pts
			(xy 170.71848 -54.066948) (xy 170.71848 -53.915056)
			(arc
				(start 170.708828 -53.901594)
				(mid 170.655164 -53.795645)
				(end 170.636692 -53.678328)
			)
			(arc
				(start 170.636692 -53.678328)
				(mid 170.65772 -53.55346)
				(end 170.71848 -53.442362)
			)
			(xy 170.71848 -37.760148) (xy 170.05808 -37.099748) (xy 168.28008 -37.099748) (xy 168.07688 -37.302948)
			(arc
				(start 168.07688 -53.924708)
				(mid 168.115542 -54.004466)
				(end 168.202102 -54.023514)
			)
			(arc
				(start 168.202102 -54.023514)
				(mid 168.245866 -54.015722)
				(end 168.29024 -54.0131)
			)
			(arc
				(start 168.29024 -54.0131)
				(mid 168.560007 -54.124841)
				(end 168.671748 -54.394608)
			)
			(arc
				(start 168.671748 -54.394608)
				(mid 168.649363 -54.523623)
				(end 168.584626 -54.637432)
			)
			(arc
				(start 168.584626 -54.637432)
				(mid 168.571196 -54.745236)
				(end 168.662858 -54.803548)
			)
			(xy 169.98188 -54.803548)
		)
		(stroke
			(width 0)
			(type solid)
		)
		(fill yes)
		(layer "In2.Cu")
		(net "P3V3_M2_0")
	)
	(gr_poly
		(pts
			(arc
				(start 68.8848 -178.953668)
				(mid 68.903252 -178.835061)
				(end 68.795646 -178.78171)
			)
			(arc
				(start 68.795646 -178.78171)
				(mid 68.720104 -178.791426)
				(end 68.644008 -178.794664)
			)
			(arc
				(start 68.644008 -178.794664)
				(mid 67.7545 -177.905156)
				(end 68.644008 -177.015648)
			)
			(arc
				(start 68.644008 -177.015648)
				(mid 69.011792 -177.095218)
				(end 69.313806 -177.319686)
			)
			(arc
				(start 69.313806 -177.319686)
				(mid 69.425936 -177.347936)
				(end 69.49186 -177.252884)
			)
			(xy 69.49186 -175.771048) (xy 66.95948 -173.238668) (xy 66.95948 -171.564808) (xy 66.490342 -171.09567)
			(xy 61.061854 -171.09567) (xy 60.661804 -171.49572) (xy 60.661804 -178.746912) (xy 61.5188 -179.603908)
			(xy 68.23456 -179.603908)
		)
		(stroke
			(width 0)
			(type solid)
		)
		(fill yes)
		(layer "In2.Cu")
		(net "PVCCFA_EHV_CPU1")
	)
	(gr_poly
		(pts
			(xy 10.35558 -100.975668)
			(arc
				(start 10.35558 -100.736908)
				(mid 10.269496 -100.495608)
				(end 10.35558 -100.254308)
			)
			(arc
				(start 10.35558 -100.03917)
				(mid 10.302076 -99.949675)
				(end 10.197846 -99.954334)
			)
			(arc
				(start 10.197846 -99.954334)
				(mid 10.09724 -100.001603)
				(end 9.98728 -100.017834)
			)
			(arc
				(start 9.98728 -100.017834)
				(mid 9.605772 -99.636326)
				(end 9.98728 -99.254818)
			)
			(arc
				(start 9.98728 -99.254818)
				(mid 10.097231 -99.271082)
				(end 10.197846 -99.318318)
			)
			(arc
				(start 10.197846 -99.318318)
				(mid 10.302135 -99.323088)
				(end 10.35558 -99.233482)
			)
			(xy 10.35558 -98.755962)
			(arc
				(start 10.315702 -98.747072)
				(mid 10.017245 -98.374708)
				(end 10.315702 -98.002344)
			)
			(xy 10.35558 -97.993454) (xy 10.35558 -97.711768) (xy 9.72566 -97.081848) (xy 6.02742 -97.081848)
			(xy 5.527548 -97.58172) (xy 5.527548 -100.993956) (xy 5.91312 -101.379528) (xy 9.95172 -101.379528)
		)
		(stroke
			(width 0)
			(type solid)
		)
		(fill yes)
		(layer "In2.Cu")
		(net "GND")
	)
	(gr_poly
		(pts
			(arc
				(start 467.7029 -308.028086)
				(mid 467.728929 -308.041896)
				(end 467.758272 -308.039008)
			)
			(xy 467.772496 -308.033166) (xy 467.789514 -308.007766)
			(arc
				(start 467.789514 -82.82813)
				(mid 467.980666 -81.867526)
				(end 468.524844 -81.053178)
			)
			(arc
				(start 470.853262 -78.72476)
				(mid 471.176045 -78.241587)
				(end 471.28938 -77.671676)
			)
			(arc
				(start 471.28938 -26.830528)
				(mid 471.282263 -26.804596)
				(end 471.262964 -26.785824)
			)
			(xy 471.17254 -26.736294) (xy 471.145108 -26.73731)
			(arc
				(start 471.13317 -26.744676)
				(mid 470.972569 -26.843078)
				(end 470.808558 -26.935684)
			)
			(arc
				(start 470.808558 -26.935684)
				(mid 470.789062 -26.95436)
				(end 470.781888 -26.980388)
			)
			(arc
				(start 470.781888 -77.67193)
				(mid 470.707224 -78.04756)
				(end 470.494614 -78.366112)
			)
			(arc
				(start 468.166196 -80.69453)
				(mid 467.512084 -81.673433)
				(end 467.282276 -82.82813)
			)
			(xy 467.282276 -115.104926) (xy 467.284816 -115.116356)
			(arc
				(start 467.287864 -115.121944)
				(mid 467.319142 -115.206449)
				(end 467.329774 -115.295934)
			)
			(arc
				(start 467.329774 -115.295934)
				(mid 467.31919 -115.38543)
				(end 467.287864 -115.469924)
			)
			(xy 467.284816 -115.475512) (xy 467.282276 -115.486942)
			(arc
				(start 467.282276 -307.58638)
				(mid 467.286109 -307.605737)
				(end 467.297008 -307.622194)
			)
		)
		(stroke
			(width 0)
			(type solid)
		)
		(fill yes)
		(layer "In2.Cu")
		(net "GND")
	)
	(gr_poly
		(pts
			(xy 435.385464 -109.244384) (xy 435.395654 -109.233404) (xy 435.409726 -109.206975) (xy 435.415531 -109.177601)
			(xy 435.412568 -109.147806) (xy 435.401094 -109.12015) (xy 435.382094 -109.097009) (xy 435.357201 -109.080372)
			(xy 435.328552 -109.071667) (xy 435.313582 -109.071156) (xy 432.973734 -109.071156) (xy 432.381411 -109.66323)
			(xy 433.334158 -109.66323) (xy 433.338229 -109.607608) (xy 433.350355 -109.553171) (xy 433.370278 -109.50108)
			(xy 433.397574 -109.452445) (xy 433.43166 -109.408302) (xy 433.471809 -109.369593) (xy 433.517167 -109.337142)
			(xy 433.566767 -109.311641) (xy 433.619551 -109.293634) (xy 433.674394 -109.283504) (xy 433.730128 -109.281467)
			(xy 433.785565 -109.287567) (xy 433.839522 -109.301673) (xy 433.890851 -109.323485) (xy 433.938457 -109.352539)
			(xy 433.981325 -109.388214) (xy 434.018542 -109.429751) (xy 434.049315 -109.476264) (xy 434.072987 -109.526761)
			(xy 434.089055 -109.580168) (xy 434.097175 -109.635344) (xy 434.097684 -109.66323) (xy 434.097175 -109.691116)
			(xy 434.089055 -109.746292) (xy 434.072987 -109.799699) (xy 434.049315 -109.850196) (xy 434.018542 -109.896709)
			(xy 433.981325 -109.938246) (xy 433.938457 -109.973921) (xy 433.890851 -110.002975) (xy 433.839522 -110.024787)
			(xy 433.785565 -110.038893) (xy 433.730128 -110.044993) (xy 433.674394 -110.042956) (xy 433.619551 -110.032826)
			(xy 433.566767 -110.014819) (xy 433.517167 -109.989318) (xy 433.471809 -109.956867) (xy 433.43166 -109.918158)
			(xy 433.397574 -109.874015) (xy 433.370278 -109.82538) (xy 433.350355 -109.773289) (xy 433.338229 -109.718852)
			(xy 433.334158 -109.66323) (xy 432.381411 -109.66323) (xy 432.370484 -109.674152) (xy 432.349635 -109.69428)
			(xy 432.302787 -109.728387) (xy 432.251178 -109.754742) (xy 432.196082 -109.772697) (xy 432.138854 -109.781808)
			(xy 432.10988 -109.782356) (xy 428.325534 -109.782356) (xy 428.059088 -110.048802) (xy 428.059088 -110.27664)
			(xy 428.913542 -110.27664) (xy 428.917613 -110.221018) (xy 428.929739 -110.166581) (xy 428.949662 -110.11449)
			(xy 428.976958 -110.065855) (xy 429.011044 -110.021712) (xy 429.051193 -109.983003) (xy 429.096551 -109.950552)
			(xy 429.146151 -109.925051) (xy 429.198935 -109.907044) (xy 429.253778 -109.896914) (xy 429.309512 -109.894877)
			(xy 429.364949 -109.900977) (xy 429.418906 -109.915083) (xy 429.470235 -109.936895) (xy 429.517841 -109.965949)
			(xy 429.560709 -110.001624) (xy 429.597926 -110.043161) (xy 429.628699 -110.089674) (xy 429.652371 -110.140171)
			(xy 429.668439 -110.193578) (xy 429.676559 -110.248754) (xy 429.677068 -110.27664) (xy 429.676559 -110.304526)
			(xy 429.668439 -110.359702) (xy 429.652371 -110.413109) (xy 429.628699 -110.463606) (xy 429.597926 -110.510119)
			(xy 429.560709 -110.551656) (xy 429.517841 -110.587331) (xy 429.470235 -110.616385) (xy 429.418906 -110.638197)
			(xy 429.364949 -110.652303) (xy 429.309512 -110.658403) (xy 429.253778 -110.656366) (xy 429.198935 -110.646236)
			(xy 429.146151 -110.628229) (xy 429.096551 -110.602728) (xy 429.051193 -110.570277) (xy 429.011044 -110.531568)
			(xy 428.976958 -110.487425) (xy 428.949662 -110.43879) (xy 428.929739 -110.386699) (xy 428.917613 -110.332262)
			(xy 428.913542 -110.27664) (xy 428.059088 -110.27664) (xy 428.059088 -110.790228) (xy 433.83962 -110.790228)
		)
		(stroke
			(width 0)
			(type solid)
		)
		(fill yes)
		(layer "In2.Cu")
		(net "GND")
	)
	(gr_poly
		(pts
			(arc
				(start 187.10275 -27.409902)
				(mid 187.213534 -27.431938)
				(end 187.276232 -27.33802)
			)
			(arc
				(start 187.276232 -26.30297)
				(mid 187.242787 -26.227621)
				(end 187.164472 -26.201878)
			)
			(arc
				(start 187.12688 -26.203656)
				(mid 186.745372 -25.822148)
				(end 187.12688 -25.44064)
			)
			(arc
				(start 187.12688 -25.44064)
				(mid 187.239016 -25.457414)
				(end 187.341256 -25.506426)
			)
			(arc
				(start 187.341256 -25.506426)
				(mid 187.44563 -25.512082)
				(end 187.499752 -25.422606)
			)
			(xy 187.499752 -24.478742)
			(arc
				(start 187.353194 -24.332184)
				(mid 187.272559 -24.302787)
				(end 187.198254 -24.345646)
			)
			(arc
				(start 187.198254 -24.345646)
				(mid 187.06183 -24.465282)
				(end 186.88558 -24.50846)
			)
			(arc
				(start 186.88558 -24.50846)
				(mid 186.615813 -24.396719)
				(end 186.504072 -24.126952)
			)
			(arc
				(start 186.504072 -24.126952)
				(mid 186.6055 -23.867908)
				(end 186.855862 -23.746714)
			)
			(arc
				(start 186.855862 -23.746714)
				(mid 186.922598 -23.714406)
				(end 186.949588 -23.645368)
			)
			(arc
				(start 186.949588 -21.262594)
				(mid 186.886869 -21.168728)
				(end 186.776106 -21.190712)
			)
			(xy 186.739784 -21.227034)
			(arc
				(start 186.739784 -21.589492)
				(mid 186.711612 -21.730561)
				(end 186.63158 -21.850096)
			)
			(xy 186.352688 -22.129242) (xy 186.352688 -26.65984)
		)
		(stroke
			(width 0)
			(type solid)
		)
		(fill yes)
		(layer "In2.Cu")
		(net "GND")
	)
	(gr_poly
		(pts
			(xy 234.87888 -128.869948) (xy 234.87888 -127.803148) (xy 234.47248 -127.396748) (xy 234.247182 -127.396748)
			(xy 234.233487 -127.397195) (xy 234.207084 -127.404479) (xy 234.183566 -127.418517) (xy 234.164625 -127.438301)
			(xy 234.151622 -127.462408) (xy 234.145494 -127.489103) (xy 234.146681 -127.516467) (xy 234.155097 -127.542531)
			(xy 234.170138 -127.565422) (xy 234.180126 -127.574802) (xy 234.200209 -127.592992) (xy 234.235539 -127.634073)
			(xy 234.264697 -127.679742) (xy 234.287095 -127.72908) (xy 234.302281 -127.781092) (xy 234.30995 -127.83473)
			(xy 234.310428 -127.861822) (xy 234.309942 -127.889073) (xy 234.302186 -127.943021) (xy 234.286831 -127.995316)
			(xy 234.264189 -128.044893) (xy 234.234723 -128.090743) (xy 234.199032 -128.131934) (xy 234.157841 -128.167625)
			(xy 234.111991 -128.197091) (xy 234.062414 -128.219733) (xy 234.010119 -128.235088) (xy 233.956171 -128.242844)
			(xy 233.901669 -128.242844) (xy 233.847721 -128.235088) (xy 233.795426 -128.219733) (xy 233.745849 -128.197091)
			(xy 233.699999 -128.167625) (xy 233.658808 -128.131934) (xy 233.623117 -128.090743) (xy 233.593651 -128.044893)
			(xy 233.571009 -127.995316) (xy 233.555654 -127.943021) (xy 233.547898 -127.889073) (xy 233.547412 -127.861822)
			(xy 233.547886 -127.834729) (xy 233.555554 -127.781089) (xy 233.570739 -127.729075) (xy 233.593134 -127.679735)
			(xy 233.622289 -127.634062) (xy 233.657617 -127.592977) (xy 233.677714 -127.574802) (xy 233.687718 -127.565435)
			(xy 233.702768 -127.542546) (xy 233.711192 -127.516478) (xy 233.712381 -127.48911) (xy 233.706252 -127.46241)
			(xy 233.693244 -127.438301) (xy 233.674294 -127.418518) (xy 233.650767 -127.404485) (xy 233.624355 -127.397212)
			(xy 233.610658 -127.396748) (xy 233.540554 -127.396748) (xy 233.52584 -127.419141) (xy 233.491002 -127.459849)
			(xy 233.450686 -127.495141) (xy 233.405726 -127.524287) (xy 233.357052 -127.546685) (xy 233.305668 -127.561872)
			(xy 233.252638 -127.569534) (xy 233.225848 -127.569976) (xy 233.196188 -127.569399) (xy 233.137618 -127.559999)
			(xy 233.081275 -127.541444) (xy 233.02858 -127.514202) (xy 232.980863 -127.478961) (xy 232.959656 -127.458216)
			(xy 232.959402 -127.457962) (xy 232.923334 -127.421894) (xy 232.49128 -127.853948) (xy 232.49128 -128.553443)
			(xy 232.883446 -128.553443) (xy 232.883446 -128.500145) (xy 232.891389 -128.447441) (xy 232.907099 -128.396511)
			(xy 232.930225 -128.34849) (xy 232.960249 -128.304453) (xy 232.996501 -128.265382) (xy 233.038172 -128.232151)
			(xy 233.08433 -128.205502) (xy 233.133944 -128.18603) (xy 233.185906 -128.17417) (xy 233.239056 -128.170187)
			(xy 233.292206 -128.17417) (xy 233.344168 -128.18603) (xy 233.393782 -128.205502) (xy 233.43994 -128.232151)
			(xy 233.481611 -128.265382) (xy 233.517863 -128.304453) (xy 233.547887 -128.34849) (xy 233.571013 -128.396511)
			(xy 233.586723 -128.447441) (xy 233.594666 -128.500145) (xy 233.595164 -128.526794) (xy 233.594666 -128.553443)
			(xy 233.586723 -128.606147) (xy 233.571013 -128.657077) (xy 233.547887 -128.705098) (xy 233.517863 -128.749135)
			(xy 233.481611 -128.788206) (xy 233.43994 -128.821437) (xy 233.393782 -128.848086) (xy 233.344168 -128.867558)
			(xy 233.292206 -128.879418) (xy 233.239056 -128.883402) (xy 233.185906 -128.879418) (xy 233.133944 -128.867558)
			(xy 233.08433 -128.848086) (xy 233.038172 -128.821437) (xy 232.996501 -128.788206) (xy 232.960249 -128.749135)
			(xy 232.930225 -128.705098) (xy 232.907099 -128.657077) (xy 232.891389 -128.606147) (xy 232.883446 -128.553443)
			(xy 232.49128 -128.553443) (xy 232.49128 -129.073148) (xy 232.64368 -129.225548) (xy 234.52328 -129.225548)
		)
		(stroke
			(width 0)
			(type solid)
		)
		(fill yes)
		(layer "In2.Cu")
		(net "FM_DB2000_1_OE_N")
	)
	(gr_poly
		(pts
			(xy 409.22956 -156.088588) (xy 409.22956 -148.760688) (xy 408.62758 -148.158708) (xy 400.4818 -148.158708)
			(xy 399.31594 -149.324568) (xy 399.31594 -150.339552) (xy 399.642589 -150.339552) (xy 399.646611 -150.253832)
			(xy 399.658642 -150.168864) (xy 399.678578 -150.085397) (xy 399.706241 -150.004163) (xy 399.74139 -149.925877)
			(xy 399.783716 -149.851226) (xy 399.832845 -149.780867) (xy 399.888348 -149.715417) (xy 399.949735 -149.655453)
			(xy 400.016468 -149.6015) (xy 400.08796 -149.554033) (xy 400.163582 -149.513469) (xy 400.242671 -149.480165)
			(xy 400.324531 -149.454413) (xy 400.408442 -149.43644) (xy 400.493668 -149.426404) (xy 400.57946 -149.424392)
			(xy 400.665062 -149.430423) (xy 400.749724 -149.444443) (xy 400.832701 -149.466329) (xy 400.913264 -149.49589)
			(xy 400.990704 -149.532864) (xy 401.064343 -149.576928) (xy 401.133531 -149.627694) (xy 401.197662 -149.684715)
			(xy 401.256171 -149.747491) (xy 401.308544 -149.815471) (xy 401.354322 -149.888056) (xy 401.393102 -149.964608)
			(xy 401.424543 -150.044456) (xy 401.448369 -150.126897) (xy 401.46437 -150.211207) (xy 401.472405 -150.296645)
			(xy 401.472908 -150.339552) (xy 401.472405 -150.382459) (xy 401.46437 -150.467897) (xy 401.448369 -150.552207)
			(xy 401.424543 -150.634648) (xy 401.393102 -150.714496) (xy 401.354322 -150.791048) (xy 401.308544 -150.863633)
			(xy 401.256171 -150.931613) (xy 401.197662 -150.994389) (xy 401.133531 -151.05141) (xy 401.064343 -151.102176)
			(xy 400.990704 -151.14624) (xy 400.913264 -151.183214) (xy 400.832701 -151.212775) (xy 400.749724 -151.234661)
			(xy 400.665062 -151.248681) (xy 400.57946 -151.254712) (xy 400.493668 -151.2527) (xy 400.408442 -151.242664)
			(xy 400.324531 -151.224691) (xy 400.242671 -151.198939) (xy 400.163582 -151.165635) (xy 400.08796 -151.125071)
			(xy 400.016468 -151.077604) (xy 399.949735 -151.023651) (xy 399.888348 -150.963687) (xy 399.832845 -150.898237)
			(xy 399.783716 -150.827878) (xy 399.74139 -150.753227) (xy 399.706241 -150.674941) (xy 399.678578 -150.593707)
			(xy 399.658642 -150.51024) (xy 399.646611 -150.425272) (xy 399.642589 -150.339552) (xy 399.31594 -150.339552)
			(xy 399.31594 -152.381896) (xy 399.668996 -152.381896) (xy 399.668996 -152.2972) (xy 399.677047 -152.212886)
			(xy 399.693076 -152.12972) (xy 399.716937 -152.048453) (xy 399.748416 -151.969823) (xy 399.787227 -151.894542)
			(xy 399.833017 -151.82329) (xy 399.885373 -151.756714) (xy 399.943821 -151.695416) (xy 400.007831 -151.639951)
			(xy 400.076823 -151.590822) (xy 400.150173 -151.548473) (xy 400.227216 -151.513289) (xy 400.307255 -151.485587)
			(xy 400.389564 -151.465619) (xy 400.473399 -151.453566) (xy 400.558 -151.449536) (xy 400.642601 -151.453566)
			(xy 400.726436 -151.465619) (xy 400.808745 -151.485587) (xy 400.888784 -151.513289) (xy 400.965827 -151.548473)
			(xy 401.039177 -151.590822) (xy 401.108169 -151.639951) (xy 401.172179 -151.695416) (xy 401.230627 -151.756714)
			(xy 401.282983 -151.82329) (xy 401.328773 -151.894542) (xy 401.367584 -151.969823) (xy 401.399063 -152.048453)
			(xy 401.422924 -152.12972) (xy 401.438953 -152.212886) (xy 401.447004 -152.2972) (xy 401.447508 -152.339548)
			(xy 401.447004 -152.381896) (xy 401.438953 -152.46621) (xy 401.422924 -152.549376) (xy 401.399063 -152.630643)
			(xy 401.367584 -152.709273) (xy 401.328773 -152.784554) (xy 401.282983 -152.855806) (xy 401.230627 -152.922382)
			(xy 401.172179 -152.98368) (xy 401.108169 -153.039145) (xy 401.039177 -153.088274) (xy 400.965827 -153.130623)
			(xy 400.888784 -153.165807) (xy 400.808745 -153.193509) (xy 400.726436 -153.213477) (xy 400.642601 -153.22553)
			(xy 400.558 -153.229561) (xy 400.473399 -153.22553) (xy 400.389564 -153.213477) (xy 400.307255 -153.193509)
			(xy 400.227216 -153.165807) (xy 400.150173 -153.130623) (xy 400.076823 -153.088274) (xy 400.007831 -153.039145)
			(xy 399.943821 -152.98368) (xy 399.885373 -152.922382) (xy 399.833017 -152.855806) (xy 399.787227 -152.784554)
			(xy 399.748416 -152.709273) (xy 399.716937 -152.630643) (xy 399.693076 -152.549376) (xy 399.677047 -152.46621)
			(xy 399.668996 -152.381896) (xy 399.31594 -152.381896) (xy 399.31594 -156.131768) (xy 399.515838 -156.331666)
			(xy 399.526776 -156.341811) (xy 399.553089 -156.355838) (xy 399.582331 -156.361675) (xy 399.612012 -156.358822)
			(xy 399.639608 -156.347525) (xy 399.662768 -156.328743) (xy 399.679521 -156.304076) (xy 399.684494 -156.29001)
			(xy 399.697296 -156.250582) (xy 399.729071 -156.174009) (xy 399.76764 -156.100624) (xy 399.812689 -156.031028)
			(xy 399.863847 -155.965791) (xy 399.920696 -155.905449) (xy 399.98277 -155.850495) (xy 400.049559 -155.801381)
			(xy 400.120516 -155.758509) (xy 400.19506 -155.722229) (xy 400.27258 -155.692841) (xy 400.35244 -155.670583)
			(xy 400.433985 -155.65564) (xy 400.516548 -155.648133) (xy 400.558 -155.647644) (xy 400.601441 -155.648157)
			(xy 400.687931 -155.656394) (xy 400.773251 -155.672794) (xy 400.856631 -155.697208) (xy 400.937322 -155.729418)
			(xy 401.014595 -155.769133) (xy 401.087755 -155.815995) (xy 401.156142 -155.869581) (xy 401.219141 -155.92941)
			(xy 401.276185 -155.994943) (xy 401.326758 -156.065588) (xy 401.370406 -156.14071) (xy 401.406735 -156.219631)
			(xy 401.435418 -156.301641) (xy 401.456197 -156.386001) (xy 401.468885 -156.471952) (xy 401.471638 -156.515308)
			(xy 401.474178 -156.563568) (xy 408.75458 -156.563568)
		)
		(stroke
			(width 0)
			(type solid)
		)
		(fill yes)
		(layer "In2.Cu")
		(net "PVCCFA_EHV_CPU0")
	)
	(gr_poly
		(pts
			(xy 198.43496 -113.538762) (xy 198.434485 -113.5241) (xy 198.426171 -113.495981) (xy 198.41021 -113.471384)
			(xy 198.387918 -113.452334) (xy 198.361132 -113.440404) (xy 198.332061 -113.436575) (xy 198.3031 -113.441165)
			(xy 198.289672 -113.447068) (xy 198.263848 -113.458844) (xy 198.209585 -113.475481) (xy 198.153458 -113.483899)
			(xy 198.12508 -113.484406) (xy 198.09783 -113.483919) (xy 198.043885 -113.47616) (xy 197.991592 -113.460803)
			(xy 197.942018 -113.438161) (xy 197.89617 -113.408694) (xy 197.854983 -113.373003) (xy 197.819294 -113.331814)
			(xy 197.789829 -113.285964) (xy 197.76719 -113.236389) (xy 197.751836 -113.184096) (xy 197.74408 -113.13015)
			(xy 197.74408 -113.07565) (xy 197.751836 -113.021704) (xy 197.76719 -112.969411) (xy 197.789829 -112.919836)
			(xy 197.819294 -112.873986) (xy 197.854983 -112.832797) (xy 197.89617 -112.797106) (xy 197.942018 -112.767639)
			(xy 197.991592 -112.744997) (xy 198.043885 -112.72964) (xy 198.09783 -112.721881) (xy 198.12508 -112.72139)
			(xy 198.153458 -112.72191) (xy 198.209586 -112.730317) (xy 198.26385 -112.746949) (xy 198.289672 -112.758728)
			(xy 198.303113 -112.7646) (xy 198.332072 -112.769183) (xy 198.361141 -112.765354) (xy 198.387926 -112.75343)
			(xy 198.410222 -112.73439) (xy 198.426195 -112.709804) (xy 198.43453 -112.681694) (xy 198.43496 -112.667034)
			(xy 198.43496 -112.560862) (xy 198.434485 -112.5462) (xy 198.426171 -112.518081) (xy 198.41021 -112.493484)
			(xy 198.387918 -112.474434) (xy 198.361132 -112.462504) (xy 198.332061 -112.458675) (xy 198.3031 -112.463265)
			(xy 198.289672 -112.469168) (xy 198.263848 -112.480944) (xy 198.209585 -112.497581) (xy 198.153458 -112.505999)
			(xy 198.12508 -112.506506) (xy 198.09783 -112.506019) (xy 198.043885 -112.49826) (xy 197.991592 -112.482903)
			(xy 197.942018 -112.460261) (xy 197.89617 -112.430794) (xy 197.854983 -112.395103) (xy 197.819294 -112.353914)
			(xy 197.789829 -112.308064) (xy 197.76719 -112.258489) (xy 197.751836 -112.206196) (xy 197.74408 -112.15225)
			(xy 197.74408 -112.09775) (xy 197.751836 -112.043804) (xy 197.76719 -111.991511) (xy 197.789829 -111.941936)
			(xy 197.819294 -111.896086) (xy 197.854983 -111.854897) (xy 197.89617 -111.819206) (xy 197.942018 -111.789739)
			(xy 197.991592 -111.767097) (xy 198.043885 -111.75174) (xy 198.09783 -111.743981) (xy 198.12508 -111.74349)
			(xy 198.153458 -111.74401) (xy 198.209586 -111.752417) (xy 198.26385 -111.769049) (xy 198.289672 -111.780828)
			(xy 198.303113 -111.7867) (xy 198.332072 -111.791283) (xy 198.361141 -111.787454) (xy 198.387926 -111.77553)
			(xy 198.410222 -111.75649) (xy 198.426195 -111.731904) (xy 198.43453 -111.703794) (xy 198.43496 -111.689134)
			(xy 198.43496 -110.942628) (xy 198.41464 -110.922308) (xy 193.381376 -110.922308) (xy 193.367067 -110.922795)
			(xy 193.339573 -110.930735) (xy 193.315358 -110.945985) (xy 193.296319 -110.967351) (xy 193.283949 -110.993157)
			(xy 193.279219 -111.021381) (xy 193.282497 -111.04981) (xy 193.293529 -111.076216) (xy 193.302128 -111.087662)
			(xy 193.316963 -111.106715) (xy 193.341899 -111.148068) (xy 193.361012 -111.192414) (xy 193.373951 -111.238937)
			(xy 193.380479 -111.286783) (xy 193.380868 -111.310928) (xy 193.38035 -111.338136) (xy 193.372067 -111.391917)
			(xy 193.355696 -111.443812) (xy 193.331621 -111.492611) (xy 193.3004 -111.537179) (xy 193.262762 -111.576478)
			(xy 193.219583 -111.609593) (xy 193.195956 -111.623094) (xy 193.16954 -111.637572) (xy 193.16954 -112.048544)
			(xy 193.213228 -112.05464) (xy 193.240149 -112.058967) (xy 193.292471 -112.074307) (xy 193.342077 -112.09694)
			(xy 193.387955 -112.126404) (xy 193.429171 -112.1621) (xy 193.464887 -112.203299) (xy 193.494373 -112.249164)
			(xy 193.517029 -112.298758) (xy 193.532395 -112.351073) (xy 193.540156 -112.405043) (xy 193.540155 -112.459568)
			(xy 193.532392 -112.513537) (xy 193.517025 -112.565852) (xy 193.494367 -112.615446) (xy 193.46488 -112.661309)
			(xy 193.429164 -112.702508) (xy 193.387946 -112.738202) (xy 193.342067 -112.767665) (xy 193.292461 -112.790297)
			(xy 193.240138 -112.805636) (xy 193.213228 -112.810036) (xy 193.16954 -112.816132) (xy 193.16954 -113.514632)
			(xy 196.46341 -113.514632) (xy 196.467481 -113.45901) (xy 196.479607 -113.404573) (xy 196.49953 -113.352482)
			(xy 196.526826 -113.303847) (xy 196.560912 -113.259704) (xy 196.601061 -113.220995) (xy 196.646419 -113.188544)
			(xy 196.696019 -113.163043) (xy 196.748803 -113.145036) (xy 196.803646 -113.134906) (xy 196.85938 -113.132869)
			(xy 196.914817 -113.138969) (xy 196.968774 -113.153075) (xy 197.020103 -113.174887) (xy 197.067709 -113.203941)
			(xy 197.110577 -113.239616) (xy 197.147794 -113.281153) (xy 197.178567 -113.327666) (xy 197.202239 -113.378163)
			(xy 197.218307 -113.43157) (xy 197.226427 -113.486746) (xy 197.226936 -113.514632) (xy 197.226427 -113.542518)
			(xy 197.218307 -113.597694) (xy 197.202239 -113.651101) (xy 197.178567 -113.701598) (xy 197.147794 -113.748111)
			(xy 197.110577 -113.789648) (xy 197.067709 -113.825323) (xy 197.020103 -113.854377) (xy 196.968774 -113.876189)
			(xy 196.914817 -113.890295) (xy 196.85938 -113.896395) (xy 196.803646 -113.894358) (xy 196.748803 -113.884228)
			(xy 196.696019 -113.866221) (xy 196.646419 -113.84072) (xy 196.601061 -113.808269) (xy 196.560912 -113.76956)
			(xy 196.526826 -113.725417) (xy 196.49953 -113.676782) (xy 196.479607 -113.624691) (xy 196.467481 -113.570254)
			(xy 196.46341 -113.514632) (xy 193.16954 -113.514632) (xy 193.16954 -114.117628) (xy 198.43496 -114.117628)
		)
		(stroke
			(width 0)
			(type solid)
		)
		(fill yes)
		(layer "In2.Cu")
		(net "GND")
	)
	(gr_poly
		(pts
			(xy 424.276012 -107.073192) (xy 424.276478 -107.0411) (xy 424.283696 -106.977321) (xy 424.298005 -106.914752)
			(xy 424.319227 -106.854176) (xy 424.347094 -106.796356) (xy 424.381257 -106.742018) (xy 424.421287 -106.691845)
			(xy 424.443652 -106.668824) (xy 426.206412 -104.90581) (xy 426.206412 -95.832168) (xy 418.15512 -95.832168)
			(xy 417.3347 -96.652588) (xy 417.3347 -104.501188) (xy 418.035232 -104.501188) (xy 418.035683 -104.473817)
			(xy 418.043503 -104.419637) (xy 418.058996 -104.367134) (xy 418.081841 -104.317387) (xy 418.111569 -104.271421)
			(xy 418.129212 -104.25049) (xy 418.138459 -104.239171) (xy 418.150634 -104.21261) (xy 418.154804 -104.183691)
			(xy 418.150629 -104.154773) (xy 418.13845 -104.128214) (xy 418.129212 -104.116886) (xy 418.111602 -104.095931)
			(xy 418.081885 -104.049965) (xy 418.059043 -104.000223) (xy 418.043546 -103.947727) (xy 418.03571 -103.893556)
			(xy 418.035232 -103.866188) (xy 418.035644 -103.838933) (xy 418.043403 -103.784978) (xy 418.058763 -103.732677)
			(xy 418.08141 -103.683094) (xy 418.110883 -103.637239) (xy 418.146582 -103.596045) (xy 418.187781 -103.560352)
			(xy 418.23364 -103.530885) (xy 418.283226 -103.508245) (xy 418.335529 -103.492892) (xy 418.389485 -103.48514)
			(xy 418.41674 -103.48468) (xy 418.442319 -103.485084) (xy 418.493018 -103.491932) (xy 418.542348 -103.505486)
			(xy 418.589428 -103.525504) (xy 418.633414 -103.551628) (xy 418.673519 -103.583389) (xy 418.691568 -103.60152)
			(xy 418.701199 -103.61092) (xy 418.724293 -103.624724) (xy 418.750189 -103.632019) (xy 418.777092 -103.6323)
			(xy 418.803136 -103.625548) (xy 418.826513 -103.612231) (xy 418.836348 -103.603044) (xy 418.857913 -103.582417)
			(xy 418.906289 -103.547481) (xy 418.959517 -103.520507) (xy 419.016298 -103.502155) (xy 419.075244 -103.492872)
			(xy 419.10508 -103.4923) (xy 419.132333 -103.492774) (xy 419.186284 -103.500528) (xy 419.238582 -103.515882)
			(xy 419.288162 -103.538523) (xy 419.334016 -103.56799) (xy 419.375209 -103.603682) (xy 419.410903 -103.644874)
			(xy 419.440371 -103.690727) (xy 419.463013 -103.740307) (xy 419.478369 -103.792605) (xy 419.486125 -103.846555)
			(xy 419.486588 -103.873808) (xy 419.48613 -103.901179) (xy 419.47831 -103.955358) (xy 419.46282 -104.007861)
			(xy 419.439976 -104.057608) (xy 419.41025 -104.103575) (xy 419.392608 -104.124506) (xy 419.383363 -104.135827)
			(xy 419.371185 -104.162387) (xy 419.367014 -104.191306) (xy 419.371189 -104.220225) (xy 419.383369 -104.246783)
			(xy 419.392608 -104.25811) (xy 419.410266 -104.279026) (xy 419.439975 -104.325004) (xy 419.462807 -104.374755)
			(xy 419.478294 -104.427259) (xy 419.486117 -104.481438) (xy 419.486588 -104.508808) (xy 419.486152 -104.536062)
			(xy 419.478393 -104.590015) (xy 419.463035 -104.642314) (xy 419.440391 -104.691896) (xy 419.41092 -104.73775)
			(xy 419.375223 -104.778943) (xy 419.334028 -104.814637) (xy 419.288171 -104.844104) (xy 419.238588 -104.866745)
			(xy 419.186287 -104.882099) (xy 419.132334 -104.889854) (xy 419.10508 -104.890316) (xy 419.079501 -104.8899)
			(xy 419.028803 -104.883055) (xy 418.979473 -104.869503) (xy 418.932393 -104.849487) (xy 418.888407 -104.823365)
			(xy 418.848301 -104.791606) (xy 418.830252 -104.773476) (xy 418.820603 -104.764096) (xy 418.797514 -104.750292)
			(xy 418.771623 -104.742994) (xy 418.744724 -104.742709) (xy 418.718683 -104.749456) (xy 418.695307 -104.762768)
			(xy 418.685472 -104.771952) (xy 418.663898 -104.792569) (xy 418.615524 -104.827506) (xy 418.562298 -104.854482)
			(xy 418.50552 -104.872837) (xy 418.446576 -104.882123) (xy 418.41674 -104.882696) (xy 418.389488 -104.882207)
			(xy 418.335537 -104.874456) (xy 418.283239 -104.859104) (xy 418.233658 -104.836465) (xy 418.187804 -104.807)
			(xy 418.146611 -104.771309) (xy 418.110916 -104.730118) (xy 418.081448 -104.684267) (xy 418.058806 -104.634687)
			(xy 418.04345 -104.58239) (xy 418.035695 -104.52844) (xy 418.035232 -104.501188) (xy 417.3347 -104.501188)
			(xy 417.3347 -104.93756) (xy 417.35545 -104.956133) (xy 417.39148 -104.998592) (xy 417.420458 -105.046144)
			(xy 417.441677 -105.097628) (xy 417.454618 -105.151789) (xy 417.458967 -105.207305) (xy 417.454617 -105.262821)
			(xy 417.441673 -105.316982) (xy 417.420453 -105.368466) (xy 417.391474 -105.416017) (xy 417.355443 -105.458475)
			(xy 417.3347 -105.477056) (xy 417.3347 -110.188248) (xy 417.42741 -110.280958) (xy 419.761922 -110.280958)
			(xy 419.765993 -110.225336) (xy 419.778119 -110.170899) (xy 419.798042 -110.118808) (xy 419.825338 -110.070173)
			(xy 419.859424 -110.02603) (xy 419.899573 -109.987321) (xy 419.944931 -109.95487) (xy 419.994531 -109.929369)
			(xy 420.047315 -109.911362) (xy 420.102158 -109.901232) (xy 420.157892 -109.899195) (xy 420.213329 -109.905295)
			(xy 420.267286 -109.919401) (xy 420.318615 -109.941213) (xy 420.366221 -109.970267) (xy 420.409089 -110.005942)
			(xy 420.446306 -110.047479) (xy 420.477079 -110.093992) (xy 420.500751 -110.144489) (xy 420.516819 -110.197896)
			(xy 420.524939 -110.253072) (xy 420.525448 -110.280958) (xy 420.524939 -110.308844) (xy 420.516819 -110.36402)
			(xy 420.500751 -110.417427) (xy 420.477079 -110.467924) (xy 420.446306 -110.514437) (xy 420.409089 -110.555974)
			(xy 420.366221 -110.591649) (xy 420.318615 -110.620703) (xy 420.267286 -110.642515) (xy 420.213329 -110.656621)
			(xy 420.157892 -110.662721) (xy 420.102158 -110.660684) (xy 420.047315 -110.650554) (xy 419.994531 -110.632547)
			(xy 419.944931 -110.607046) (xy 419.899573 -110.574595) (xy 419.859424 -110.535886) (xy 419.825338 -110.491743)
			(xy 419.798042 -110.443108) (xy 419.778119 -110.391017) (xy 419.765993 -110.33658) (xy 419.761922 -110.280958)
			(xy 417.42741 -110.280958) (xy 417.93668 -110.790228) (xy 424.276012 -110.790228)
		)
		(stroke
			(width 0)
			(type solid)
		)
		(fill yes)
		(layer "In2.Cu")
		(net "GND")
	)
	(gr_poly
		(pts
			(xy 332.909672 -20.739608) (xy 332.93352 -20.729819) (xy 332.98319 -20.716025) (xy 333.034265 -20.709047)
			(xy 333.06004 -20.70862) (xy 333.085814 -20.709061) (xy 333.13689 -20.716033) (xy 333.186562 -20.729818)
			(xy 333.210408 -20.739608) (xy 333.22006 -20.743672) (xy 337.95208 -20.743672) (xy 339.13445 -19.561302)
			(xy 339.13445 -14.55547) (xy 338.351368 -14.55547) (xy 338.259166 -14.647672) (xy 338.259166 -15.246604)
			(xy 337.245706 -16.260064) (xy 335.464404 -16.260064) (xy 334.32877 -17.395698) (xy 335.468974 -17.395698)
			(xy 335.473045 -17.340076) (xy 335.485171 -17.285639) (xy 335.505094 -17.233548) (xy 335.53239 -17.184913)
			(xy 335.566476 -17.14077) (xy 335.606625 -17.102061) (xy 335.651983 -17.06961) (xy 335.701583 -17.044109)
			(xy 335.754367 -17.026102) (xy 335.80921 -17.015972) (xy 335.864944 -17.013935) (xy 335.920381 -17.020035)
			(xy 335.974338 -17.034141) (xy 336.025667 -17.055953) (xy 336.073273 -17.085007) (xy 336.116141 -17.120682)
			(xy 336.153358 -17.162219) (xy 336.184131 -17.208732) (xy 336.207803 -17.259229) (xy 336.223871 -17.312636)
			(xy 336.231991 -17.367812) (xy 336.2325 -17.395698) (xy 336.231991 -17.423584) (xy 336.223871 -17.47876)
			(xy 336.207803 -17.532167) (xy 336.184131 -17.582664) (xy 336.153358 -17.629177) (xy 336.116141 -17.670714)
			(xy 336.073273 -17.706389) (xy 336.025667 -17.735443) (xy 335.974338 -17.757255) (xy 335.920381 -17.771361)
			(xy 335.864944 -17.777461) (xy 335.80921 -17.775424) (xy 335.754367 -17.765294) (xy 335.701583 -17.747287)
			(xy 335.651983 -17.721786) (xy 335.606625 -17.689335) (xy 335.566476 -17.650626) (xy 335.53239 -17.606483)
			(xy 335.505094 -17.557848) (xy 335.485171 -17.505757) (xy 335.473045 -17.45132) (xy 335.468974 -17.395698)
			(xy 334.32877 -17.395698) (xy 334.324452 -17.400016) (xy 334.325468 -17.422114) (xy 334.325722 -17.437608)
			(xy 334.325236 -17.464859) (xy 334.317478 -17.518807) (xy 334.302123 -17.571101) (xy 334.279481 -17.620679)
			(xy 334.250015 -17.666529) (xy 334.214324 -17.707719) (xy 334.173134 -17.743411) (xy 334.127284 -17.772878)
			(xy 334.077707 -17.795521) (xy 334.025413 -17.810877) (xy 333.971465 -17.818635) (xy 333.944214 -17.819116)
			(xy 333.9125 -17.818489) (xy 333.849942 -17.808026) (xy 333.819754 -17.798288) (xy 333.81188 -17.795494)
			(xy 333.23403 -17.795494) (xy 333.226156 -17.798288) (xy 333.195971 -17.80804) (xy 333.133411 -17.818505)
			(xy 333.101696 -17.819116) (xy 333.069983 -17.818487) (xy 333.007425 -17.808021) (xy 332.977236 -17.798288)
			(xy 332.969362 -17.795494) (xy 332.540356 -17.795494) (xy 332.517331 -17.811952) (xy 332.467912 -17.839537)
			(xy 332.415395 -17.860637) (xy 332.360628 -17.874913) (xy 332.304494 -17.882135) (xy 332.276196 -17.882616)
			(xy 332.247896 -17.88216) (xy 332.191757 -17.874951) (xy 332.136986 -17.860675) (xy 332.08447 -17.839564)
			(xy 332.035058 -17.811958) (xy 332.012036 -17.795494) (xy 331.50302 -17.795494) (xy 331.103732 -17.396206)
			(xy 331.103732 -16.244316) (xy 329.43038 -14.570964) (xy 329.103228 -14.570964) (xy 329.08969 -14.571385)
			(xy 329.063565 -14.578501) (xy 329.040232 -14.592239) (xy 329.021336 -14.611631) (xy 329.008206 -14.635312)
			(xy 329.001769 -14.661612) (xy 329.002478 -14.68868) (xy 329.005946 -14.701774) (xy 329.013413 -14.728525)
			(xy 329.021441 -14.783479) (xy 329.021948 -14.811248) (xy 329.021459 -14.838498) (xy 329.013697 -14.892443)
			(xy 328.998338 -14.944734) (xy 328.975695 -14.994308) (xy 328.946228 -15.040155) (xy 328.910537 -15.081343)
			(xy 328.869349 -15.117033) (xy 328.823501 -15.146499) (xy 328.773926 -15.169141) (xy 328.721635 -15.184499)
			(xy 328.66769 -15.19226) (xy 328.64044 -15.192756) (xy 328.61125 -15.192204) (xy 328.55355 -15.183319)
			(xy 328.497876 -15.165751) (xy 328.445527 -15.139908) (xy 328.397725 -15.106395) (xy 328.37628 -15.086584)
			(xy 328.364937 -15.076469) (xy 328.337816 -15.062791) (xy 328.307875 -15.057675) (xy 328.277752 -15.061572)
			(xy 328.250098 -15.07414) (xy 328.238358 -15.08379) (xy 328.217313 -15.101821) (xy 328.170992 -15.132241)
			(xy 328.120755 -15.155635) (xy 328.067661 -15.171512) (xy 328.012828 -15.179536) (xy 327.98512 -15.180056)
			(xy 327.957867 -15.179572) (xy 327.903914 -15.171818) (xy 327.851614 -15.156465) (xy 327.802031 -15.133825)
			(xy 327.756175 -15.10436) (xy 327.714979 -15.06867) (xy 327.67928 -15.027479) (xy 327.649807 -14.981628)
			(xy 327.627159 -14.93205) (xy 327.611797 -14.879752) (xy 327.604033 -14.825801) (xy 327.603612 -14.798548)
			(xy 327.604026 -14.773418) (xy 327.610645 -14.723596) (xy 327.61682 -14.699234) (xy 327.619935 -14.686249)
			(xy 327.620014 -14.659554) (xy 327.613168 -14.633752) (xy 327.599865 -14.610608) (xy 327.581014 -14.591706)
			(xy 327.557907 -14.578339) (xy 327.532124 -14.571422) (xy 327.518776 -14.570964) (xy 324.05574 -14.570964)
			(xy 323.856096 -14.770608) (xy 323.856096 -18.824194) (xy 324.203822 -19.17192) (xy 335.511392 -19.17192)
			(xy 335.515463 -19.116298) (xy 335.527589 -19.061861) (xy 335.547512 -19.00977) (xy 335.574808 -18.961135)
			(xy 335.608894 -18.916992) (xy 335.649043 -18.878283) (xy 335.694401 -18.845832) (xy 335.744001 -18.820331)
			(xy 335.796785 -18.802324) (xy 335.851628 -18.792194) (xy 335.907362 -18.790157) (xy 335.962799 -18.796257)
			(xy 336.016756 -18.810363) (xy 336.068085 -18.832175) (xy 336.115691 -18.861229) (xy 336.158559 -18.896904)
			(xy 336.195776 -18.938441) (xy 336.226549 -18.984954) (xy 336.250221 -19.035451) (xy 336.266289 -19.088858)
			(xy 336.274409 -19.144034) (xy 336.274918 -19.17192) (xy 336.274409 -19.199806) (xy 336.266289 -19.254982)
			(xy 336.250221 -19.308389) (xy 336.226549 -19.358886) (xy 336.195776 -19.405399) (xy 336.158559 -19.446936)
			(xy 336.115691 -19.482611) (xy 336.068085 -19.511665) (xy 336.016756 -19.533477) (xy 335.962799 -19.547583)
			(xy 335.907362 -19.553683) (xy 335.851628 -19.551646) (xy 335.796785 -19.541516) (xy 335.744001 -19.523509)
			(xy 335.694401 -19.498008) (xy 335.649043 -19.465557) (xy 335.608894 -19.426848) (xy 335.574808 -19.382705)
			(xy 335.547512 -19.33407) (xy 335.527589 -19.281979) (xy 335.515463 -19.227542) (xy 335.511392 -19.17192)
			(xy 324.203822 -19.17192) (xy 324.20941 -19.177508) (xy 328.846434 -19.177508) (xy 330.412598 -20.743672)
			(xy 332.90002 -20.743672)
		)
		(stroke
			(width 0)
			(type solid)
		)
		(fill yes)
		(layer "In2.Cu")
		(net "PGPPA_AUX")
	)
	(gr_poly
		(pts
			(xy 286.495744 -28.561792) (xy 286.495744 -16.366744) (xy 284.822646 -14.693646) (xy 274.118832 -14.693646)
			(xy 273.711162 -15.101316) (xy 273.711162 -17.043908) (xy 274.991066 -17.043908) (xy 274.995137 -16.988286)
			(xy 275.007263 -16.933849) (xy 275.027186 -16.881758) (xy 275.054482 -16.833123) (xy 275.088568 -16.78898)
			(xy 275.128717 -16.750271) (xy 275.174075 -16.71782) (xy 275.223675 -16.692319) (xy 275.276459 -16.674312)
			(xy 275.331302 -16.664182) (xy 275.387036 -16.662145) (xy 275.442473 -16.668245) (xy 275.49643 -16.682351)
			(xy 275.547759 -16.704163) (xy 275.595365 -16.733217) (xy 275.638233 -16.768892) (xy 275.67545 -16.810429)
			(xy 275.706223 -16.856942) (xy 275.729895 -16.907439) (xy 275.745963 -16.960846) (xy 275.754083 -17.016022)
			(xy 275.754592 -17.043908) (xy 275.754083 -17.071794) (xy 275.745963 -17.12697) (xy 275.729895 -17.180377)
			(xy 275.706223 -17.230874) (xy 275.699012 -17.241774) (xy 278.457658 -17.241774) (xy 278.461729 -17.186152)
			(xy 278.473855 -17.131715) (xy 278.493778 -17.079624) (xy 278.521074 -17.030989) (xy 278.55516 -16.986846)
			(xy 278.595309 -16.948137) (xy 278.640667 -16.915686) (xy 278.690267 -16.890185) (xy 278.743051 -16.872178)
			(xy 278.797894 -16.862048) (xy 278.853628 -16.860011) (xy 278.909065 -16.866111) (xy 278.963022 -16.880217)
			(xy 279.014351 -16.902029) (xy 279.061957 -16.931083) (xy 279.104825 -16.966758) (xy 279.142042 -17.008295)
			(xy 279.172815 -17.054808) (xy 279.196487 -17.105305) (xy 279.212555 -17.158712) (xy 279.220675 -17.213888)
			(xy 279.221184 -17.241774) (xy 279.220675 -17.26966) (xy 279.212555 -17.324836) (xy 279.196487 -17.378243)
			(xy 279.172815 -17.42874) (xy 279.142042 -17.475253) (xy 279.104825 -17.51679) (xy 279.061957 -17.552465)
			(xy 279.014351 -17.581519) (xy 278.963022 -17.603331) (xy 278.909065 -17.617437) (xy 278.853628 -17.623537)
			(xy 278.797894 -17.6215) (xy 278.743051 -17.61137) (xy 278.690267 -17.593363) (xy 278.640667 -17.567862)
			(xy 278.595309 -17.535411) (xy 278.55516 -17.496702) (xy 278.521074 -17.452559) (xy 278.493778 -17.403924)
			(xy 278.473855 -17.351833) (xy 278.461729 -17.297396) (xy 278.457658 -17.241774) (xy 275.699012 -17.241774)
			(xy 275.67545 -17.277387) (xy 275.638233 -17.318924) (xy 275.595365 -17.354599) (xy 275.547759 -17.383653)
			(xy 275.49643 -17.405465) (xy 275.442473 -17.419571) (xy 275.387036 -17.425671) (xy 275.331302 -17.423634)
			(xy 275.276459 -17.413504) (xy 275.223675 -17.395497) (xy 275.174075 -17.369996) (xy 275.128717 -17.337545)
			(xy 275.088568 -17.298836) (xy 275.054482 -17.254693) (xy 275.027186 -17.206058) (xy 275.007263 -17.153967)
			(xy 274.995137 -17.09953) (xy 274.991066 -17.043908) (xy 273.711162 -17.043908) (xy 273.711162 -17.744948)
			(xy 282.470858 -17.744948) (xy 282.474929 -17.689326) (xy 282.487055 -17.634889) (xy 282.506978 -17.582798)
			(xy 282.534274 -17.534163) (xy 282.56836 -17.49002) (xy 282.608509 -17.451311) (xy 282.653867 -17.41886)
			(xy 282.703467 -17.393359) (xy 282.756251 -17.375352) (xy 282.811094 -17.365222) (xy 282.866828 -17.363185)
			(xy 282.922265 -17.369285) (xy 282.976222 -17.383391) (xy 283.027551 -17.405203) (xy 283.075157 -17.434257)
			(xy 283.118025 -17.469932) (xy 283.155242 -17.511469) (xy 283.186015 -17.557982) (xy 283.209687 -17.608479)
			(xy 283.225755 -17.661886) (xy 283.233875 -17.717062) (xy 283.234384 -17.744948) (xy 283.233875 -17.772834)
			(xy 283.225755 -17.82801) (xy 283.209687 -17.881417) (xy 283.186015 -17.931914) (xy 283.155242 -17.978427)
			(xy 283.118025 -18.019964) (xy 283.075157 -18.055639) (xy 283.027551 -18.084693) (xy 282.976222 -18.106505)
			(xy 282.922265 -18.120611) (xy 282.866828 -18.126711) (xy 282.811094 -18.124674) (xy 282.756251 -18.114544)
			(xy 282.703467 -18.096537) (xy 282.653867 -18.071036) (xy 282.608509 -18.038585) (xy 282.56836 -17.999876)
			(xy 282.534274 -17.955733) (xy 282.506978 -17.907098) (xy 282.487055 -17.855007) (xy 282.474929 -17.80057)
			(xy 282.470858 -17.744948) (xy 273.711162 -17.744948) (xy 273.711162 -19.509486) (xy 273.689572 -19.531076)
			(xy 273.689572 -19.929094) (xy 279.668476 -19.929094) (xy 279.672547 -19.873472) (xy 279.684673 -19.819035)
			(xy 279.704596 -19.766944) (xy 279.731892 -19.718309) (xy 279.765978 -19.674166) (xy 279.806127 -19.635457)
			(xy 279.851485 -19.603006) (xy 279.901085 -19.577505) (xy 279.953869 -19.559498) (xy 280.008712 -19.549368)
			(xy 280.064446 -19.547331) (xy 280.119883 -19.553431) (xy 280.17384 -19.567537) (xy 280.225169 -19.589349)
			(xy 280.272775 -19.618403) (xy 280.315643 -19.654078) (xy 280.35286 -19.695615) (xy 280.383633 -19.742128)
			(xy 280.407305 -19.792625) (xy 280.423373 -19.846032) (xy 280.431493 -19.901208) (xy 280.432002 -19.929094)
			(xy 280.431493 -19.95698) (xy 280.423373 -20.012156) (xy 280.407305 -20.065563) (xy 280.383633 -20.11606)
			(xy 280.35286 -20.162573) (xy 280.315643 -20.20411) (xy 280.272775 -20.239785) (xy 280.225169 -20.268839)
			(xy 280.17384 -20.290651) (xy 280.119883 -20.304757) (xy 280.064446 -20.310857) (xy 280.008712 -20.30882)
			(xy 279.953869 -20.29869) (xy 279.901085 -20.280683) (xy 279.851485 -20.255182) (xy 279.806127 -20.222731)
			(xy 279.765978 -20.184022) (xy 279.731892 -20.139879) (xy 279.704596 -20.091244) (xy 279.684673 -20.039153)
			(xy 279.672547 -19.984716) (xy 279.668476 -19.929094) (xy 273.689572 -19.929094) (xy 273.689572 -20.470368)
			(xy 281.309062 -20.470368) (xy 281.313133 -20.414746) (xy 281.325259 -20.360309) (xy 281.345182 -20.308218)
			(xy 281.372478 -20.259583) (xy 281.406564 -20.21544) (xy 281.446713 -20.176731) (xy 281.492071 -20.14428)
			(xy 281.541671 -20.118779) (xy 281.594455 -20.100772) (xy 281.649298 -20.090642) (xy 281.705032 -20.088605)
			(xy 281.760469 -20.094705) (xy 281.814426 -20.108811) (xy 281.865755 -20.130623) (xy 281.913361 -20.159677)
			(xy 281.956229 -20.195352) (xy 281.993446 -20.236889) (xy 282.024219 -20.283402) (xy 282.047891 -20.333899)
			(xy 282.063959 -20.387306) (xy 282.072079 -20.442482) (xy 282.072588 -20.470368) (xy 282.072079 -20.498254)
			(xy 282.063959 -20.55343) (xy 282.047891 -20.606837) (xy 282.024219 -20.657334) (xy 281.993446 -20.703847)
			(xy 281.956229 -20.745384) (xy 281.913361 -20.781059) (xy 281.865755 -20.810113) (xy 281.814426 -20.831925)
			(xy 281.760469 -20.846031) (xy 281.705032 -20.852131) (xy 281.649298 -20.850094) (xy 281.594455 -20.839964)
			(xy 281.541671 -20.821957) (xy 281.492071 -20.796456) (xy 281.446713 -20.764005) (xy 281.406564 -20.725296)
			(xy 281.372478 -20.681153) (xy 281.345182 -20.632518) (xy 281.325259 -20.580427) (xy 281.313133 -20.52599)
			(xy 281.309062 -20.470368) (xy 273.689572 -20.470368) (xy 273.689572 -21.204174) (xy 275.663152 -23.177754)
			(xy 275.663152 -29.119576) (xy 277.700994 -31.157418) (xy 283.900118 -31.157418)
		)
		(stroke
			(width 0)
			(type solid)
		)
		(fill yes)
		(layer "In2.Cu")
		(net "P3V3_AUX")
	)
	(gr_poly
		(pts
			(xy 409.455366 -165.563042) (xy 409.464968 -165.552825) (xy 409.478672 -165.528374) (xy 409.485218 -165.501121)
			(xy 409.484116 -165.473114) (xy 409.475447 -165.44646) (xy 409.459864 -165.423162) (xy 409.449524 -165.41369)
			(xy 409.428885 -165.395489) (xy 409.392543 -165.354167) (xy 409.362521 -165.30805) (xy 409.339443 -165.258094)
			(xy 409.323787 -165.20534) (xy 409.315879 -165.150882) (xy 409.315412 -165.123368) (xy 409.315907 -165.095699)
			(xy 409.323905 -165.040942) (xy 409.339729 -164.987914) (xy 409.363046 -164.937729) (xy 409.393368 -164.891437)
			(xy 409.430058 -164.850011) (xy 409.472348 -164.81432) (xy 409.51935 -164.785111) (xy 409.54452 -164.77361)
			(xy 409.575 -164.760402) (xy 409.575 -159.458914) (xy 409.54452 -159.445706) (xy 409.519352 -159.434201)
			(xy 409.472347 -159.404997) (xy 409.430056 -159.369309) (xy 409.393365 -159.327883) (xy 409.363045 -159.281591)
			(xy 409.339732 -159.231404) (xy 409.323915 -159.178375) (xy 409.315927 -159.123617) (xy 409.315412 -159.095948)
			(xy 409.315929 -159.067208) (xy 409.324546 -159.010376) (xy 409.341591 -158.955481) (xy 409.366679 -158.903765)
			(xy 409.399242 -158.856397) (xy 409.418536 -158.83509) (xy 409.428618 -158.823557) (xy 409.441978 -158.796007)
			(xy 409.446577 -158.765735) (xy 409.441999 -158.73546) (xy 409.428658 -158.707901) (xy 409.418536 -158.696406)
			(xy 409.399262 -158.67508) (xy 409.36669 -158.62772) (xy 409.341591 -158.576008) (xy 409.324533 -158.521117)
			(xy 409.315903 -158.464288) (xy 409.315412 -158.435548) (xy 409.315908 -158.40788) (xy 409.323909 -158.353125)
			(xy 409.339734 -158.300099) (xy 409.363053 -158.249916) (xy 409.393376 -158.203627) (xy 409.430067 -158.162203)
			(xy 409.472356 -158.126513) (xy 409.519357 -158.097307) (xy 409.54452 -158.08579) (xy 409.575 -158.072582)
			(xy 409.575 -157.599888) (xy 408.97048 -156.995368) (xy 401.363942 -156.995368) (xy 401.343218 -157.032919)
			(xy 401.295757 -157.104366) (xy 401.241816 -157.171056) (xy 401.181868 -157.232404) (xy 401.11644 -157.28787)
			(xy 401.046107 -157.336966) (xy 400.971487 -157.379263) (xy 400.893234 -157.414388) (xy 400.812036 -157.442032)
			(xy 400.728608 -157.461953) (xy 400.64368 -157.473977) (xy 400.558 -157.477996) (xy 400.47232 -157.473977)
			(xy 400.387392 -157.461953) (xy 400.303964 -157.442032) (xy 400.222766 -157.414388) (xy 400.144513 -157.379263)
			(xy 400.069893 -157.336966) (xy 399.99956 -157.28787) (xy 399.934132 -157.232404) (xy 399.874184 -157.171056)
			(xy 399.820243 -157.104366) (xy 399.772782 -157.032919) (xy 399.752058 -156.995368) (xy 398.36852 -156.995368)
			(xy 397.80718 -157.556708) (xy 397.80718 -158.604896) (xy 399.668996 -158.604896) (xy 399.668996 -158.5202)
			(xy 399.677047 -158.435886) (xy 399.693076 -158.35272) (xy 399.716937 -158.271453) (xy 399.748416 -158.192823)
			(xy 399.787227 -158.117542) (xy 399.833017 -158.04629) (xy 399.885373 -157.979714) (xy 399.943821 -157.918416)
			(xy 400.007831 -157.862951) (xy 400.076823 -157.813822) (xy 400.150173 -157.771473) (xy 400.227216 -157.736289)
			(xy 400.307255 -157.708587) (xy 400.389564 -157.688619) (xy 400.473399 -157.676566) (xy 400.558 -157.672536)
			(xy 400.642601 -157.676566) (xy 400.726436 -157.688619) (xy 400.808745 -157.708587) (xy 400.888784 -157.736289)
			(xy 400.965827 -157.771473) (xy 401.039177 -157.813822) (xy 401.108169 -157.862951) (xy 401.172179 -157.918416)
			(xy 401.230627 -157.979714) (xy 401.282983 -158.04629) (xy 401.328773 -158.117542) (xy 401.367584 -158.192823)
			(xy 401.399063 -158.271453) (xy 401.422924 -158.35272) (xy 401.438953 -158.435886) (xy 401.447004 -158.5202)
			(xy 401.447508 -158.562548) (xy 401.447004 -158.604896) (xy 401.438953 -158.68921) (xy 401.422924 -158.772376)
			(xy 401.399063 -158.853643) (xy 401.367584 -158.932273) (xy 401.328773 -159.007554) (xy 401.282983 -159.078806)
			(xy 401.230627 -159.145382) (xy 401.172179 -159.20668) (xy 401.108169 -159.262145) (xy 401.039177 -159.311274)
			(xy 400.965827 -159.353623) (xy 400.888784 -159.388807) (xy 400.808745 -159.416509) (xy 400.726436 -159.436477)
			(xy 400.642601 -159.44853) (xy 400.558 -159.452561) (xy 400.473399 -159.44853) (xy 400.389564 -159.436477)
			(xy 400.307255 -159.416509) (xy 400.227216 -159.388807) (xy 400.150173 -159.353623) (xy 400.076823 -159.311274)
			(xy 400.007831 -159.262145) (xy 399.943821 -159.20668) (xy 399.885373 -159.145382) (xy 399.833017 -159.078806)
			(xy 399.787227 -159.007554) (xy 399.748416 -158.932273) (xy 399.716937 -158.853643) (xy 399.693076 -158.772376)
			(xy 399.677047 -158.68921) (xy 399.668996 -158.604896) (xy 397.80718 -158.604896) (xy 397.80718 -162.785552)
			(xy 399.642589 -162.785552) (xy 399.646611 -162.699832) (xy 399.658642 -162.614864) (xy 399.678578 -162.531397)
			(xy 399.706241 -162.450163) (xy 399.74139 -162.371877) (xy 399.783716 -162.297226) (xy 399.832845 -162.226867)
			(xy 399.888348 -162.161417) (xy 399.949735 -162.101453) (xy 400.016468 -162.0475) (xy 400.08796 -162.000033)
			(xy 400.163582 -161.959469) (xy 400.242671 -161.926165) (xy 400.324531 -161.900413) (xy 400.408442 -161.88244)
			(xy 400.493668 -161.872404) (xy 400.57946 -161.870392) (xy 400.665062 -161.876423) (xy 400.749724 -161.890443)
			(xy 400.832701 -161.912329) (xy 400.913264 -161.94189) (xy 400.990704 -161.978864) (xy 401.064343 -162.022928)
			(xy 401.133531 -162.073694) (xy 401.197662 -162.130715) (xy 401.256171 -162.193491) (xy 401.308544 -162.261471)
			(xy 401.354322 -162.334056) (xy 401.393102 -162.410608) (xy 401.424543 -162.490456) (xy 401.448369 -162.572897)
			(xy 401.46437 -162.657207) (xy 401.472405 -162.742645) (xy 401.472908 -162.785552) (xy 401.472405 -162.828459)
			(xy 401.46437 -162.913897) (xy 401.448369 -162.998207) (xy 401.424543 -163.080648) (xy 401.393102 -163.160496)
			(xy 401.354322 -163.237048) (xy 401.308544 -163.309633) (xy 401.256171 -163.377613) (xy 401.197662 -163.440389)
			(xy 401.133531 -163.49741) (xy 401.064343 -163.548176) (xy 400.990704 -163.59224) (xy 400.913264 -163.629214)
			(xy 400.832701 -163.658775) (xy 400.749724 -163.680661) (xy 400.665062 -163.694681) (xy 400.57946 -163.700712)
			(xy 400.493668 -163.6987) (xy 400.408442 -163.688664) (xy 400.324531 -163.670691) (xy 400.242671 -163.644939)
			(xy 400.163582 -163.611635) (xy 400.08796 -163.571071) (xy 400.016468 -163.523604) (xy 399.949735 -163.469651)
			(xy 399.888348 -163.409687) (xy 399.832845 -163.344237) (xy 399.783716 -163.273878) (xy 399.74139 -163.199227)
			(xy 399.706241 -163.120941) (xy 399.678578 -163.039707) (xy 399.658642 -162.95624) (xy 399.646611 -162.871272)
			(xy 399.642589 -162.785552) (xy 397.80718 -162.785552) (xy 397.80718 -164.827896) (xy 399.668996 -164.827896)
			(xy 399.668996 -164.7432) (xy 399.677047 -164.658886) (xy 399.693076 -164.57572) (xy 399.716937 -164.494453)
			(xy 399.748416 -164.415823) (xy 399.787227 -164.340542) (xy 399.833017 -164.26929) (xy 399.885373 -164.202714)
			(xy 399.943821 -164.141416) (xy 400.007831 -164.085951) (xy 400.076823 -164.036822) (xy 400.150173 -163.994473)
			(xy 400.227216 -163.959289) (xy 400.307255 -163.931587) (xy 400.389564 -163.911619) (xy 400.473399 -163.899566)
			(xy 400.558 -163.895536) (xy 400.642601 -163.899566) (xy 400.726436 -163.911619) (xy 400.808745 -163.931587)
			(xy 400.888784 -163.959289) (xy 400.965827 -163.994473) (xy 401.039177 -164.036822) (xy 401.108169 -164.085951)
			(xy 401.172179 -164.141416) (xy 401.230627 -164.202714) (xy 401.282983 -164.26929) (xy 401.328773 -164.340542)
			(xy 401.367584 -164.415823) (xy 401.399063 -164.494453) (xy 401.422924 -164.57572) (xy 401.438953 -164.658886)
			(xy 401.447004 -164.7432) (xy 401.447508 -164.785548) (xy 401.447004 -164.827896) (xy 401.438953 -164.91221)
			(xy 401.422924 -164.995376) (xy 401.399063 -165.076643) (xy 401.367584 -165.155273) (xy 401.328773 -165.230554)
			(xy 401.282983 -165.301806) (xy 401.230627 -165.368382) (xy 401.172179 -165.42968) (xy 401.108169 -165.485145)
			(xy 401.039177 -165.534274) (xy 400.965827 -165.576623) (xy 400.888784 -165.611807) (xy 400.808745 -165.639509)
			(xy 400.726436 -165.659477) (xy 400.642601 -165.67153) (xy 400.558 -165.675561) (xy 400.473399 -165.67153)
			(xy 400.389564 -165.659477) (xy 400.307255 -165.639509) (xy 400.227216 -165.611807) (xy 400.150173 -165.576623)
			(xy 400.076823 -165.534274) (xy 400.007831 -165.485145) (xy 399.943821 -165.42968) (xy 399.885373 -165.368382)
			(xy 399.833017 -165.301806) (xy 399.787227 -165.230554) (xy 399.748416 -165.155273) (xy 399.716937 -165.076643)
			(xy 399.693076 -164.995376) (xy 399.677047 -164.91221) (xy 399.668996 -164.827896) (xy 397.80718 -164.827896)
			(xy 397.80718 -164.965888) (xy 399.01622 -166.174928) (xy 408.84348 -166.174928)
		)
		(stroke
			(width 0)
			(type solid)
		)
		(fill yes)
		(layer "In2.Cu")
		(net "PVCCD_HV_CPU0")
	)
	(gr_poly
		(pts
			(xy 0.654812 -17.86255)
			(arc
				(start 0.66675 -17.85493)
				(mid 0.827347 -17.756522)
				(end 0.991362 -17.663922)
			)
			(xy 1.017524 -17.61998)
			(arc
				(start 1.017524 -13.780008)
				(mid 1.305283 -13.085295)
				(end 1.999996 -12.797536)
			)
			(arc
				(start 11.102594 -12.797536)
				(mid 13.236139 -11.913635)
				(end 14.11986 -9.780016)
			)
			(xy 14.11986 -3.945382)
			(arc
				(start 14.10081 -3.90779)
				(mid 13.825764 -3.583504)
				(end 13.726922 -3.16992)
			)
			(arc
				(start 13.726922 -3.16992)
				(mid 13.825371 -2.757062)
				(end 14.09954 -2.433066)
			)
			(xy 14.11986 -2.392934) (xy 14.11986 -1.016) (xy 80.684116 -1.016) (xy 80.684116 -2.39141)
			(arc
				(start 80.704944 -2.43205)
				(mid 81.07796 -3.169158)
				(end 80.704944 -3.906266)
			)
			(xy 80.684116 -3.946906)
			(arc
				(start 80.684116 -9.780016)
				(mid 80.732231 -10.316244)
				(end 80.87487 -10.835386)
			)
			(arc
				(start 80.87487 -10.835386)
				(mid 80.879304 -10.843196)
				(end 80.88503 -10.850118)
			)
			(arc
				(start 82.631788 -12.596876)
				(mid 82.638698 -12.602618)
				(end 82.64652 -12.607036)
			)
			(arc
				(start 82.64652 -12.607036)
				(mid 83.165425 -12.749492)
				(end 83.701382 -12.797536)
			)
			(arc
				(start 124.102622 -12.797536)
				(mid 126.236167 -11.913635)
				(end 127.119888 -9.780016)
			)
			(arc
				(start 127.119888 -9.223756)
				(mid 127.113727 -9.202804)
				(end 127.099314 -9.186418)
			)
			(arc
				(start 127.099314 -9.186418)
				(mid 126.839825 -8.890054)
				(end 126.728982 -8.512048)
			)
			(xy 126.700534 -8.46963) (xy 126.687326 -8.463026)
			(arc
				(start 126.66345 -8.457184)
				(mid 126.627619 -8.471973)
				(end 126.61265 -8.50773)
			)
			(arc
				(start 126.61265 -9.780016)
				(mid 125.877331 -11.555233)
				(end 124.102114 -12.290552)
			)
			(arc
				(start 83.70189 -12.290552)
				(mid 81.926673 -11.555233)
				(end 81.191354 -9.780016)
			)
			(xy 81.191354 -1.28524) (xy 81.19364 -1.28524)
			(arc
				(start 81.19364 -0.999998)
				(mid 81.049612 -0.652282)
				(end 80.701896 -0.508254)
			)
			(arc
				(start 14.10208 -0.508254)
				(mid 13.754364 -0.652282)
				(end 13.610336 -0.999998)
			)
			(xy 13.610336 -1.28524) (xy 13.612622 -1.28524)
			(arc
				(start 13.612622 -9.780016)
				(mid 12.877303 -11.555233)
				(end 11.102086 -12.290552)
			)
			(arc
				(start 1.999996 -12.290552)
				(mid 0.946792 -12.726804)
				(end 0.51054 -13.780008)
			)
			(arc
				(start 0.51054 -17.769332)
				(mid 0.517626 -17.795211)
				(end 0.536956 -17.813782)
			)
			(xy 0.62738 -17.863566)
		)
		(stroke
			(width 0)
			(type solid)
		)
		(fill yes)
		(layer "In2.Cu")
		(net "GND")
	)
	(gr_poly
		(pts
			(xy 110.17377 -408.79903) (xy 110.171484 -408.775154) (xy 110.169452 -408.7368) (xy 110.169938 -408.709548)
			(xy 110.177694 -408.655598) (xy 110.193049 -408.603301) (xy 110.215689 -408.553721) (xy 110.245155 -408.507868)
			(xy 110.280846 -408.466674) (xy 110.322036 -408.430979) (xy 110.367886 -408.401509) (xy 110.417463 -408.378863)
			(xy 110.469759 -408.363503) (xy 110.523708 -408.355741) (xy 110.55096 -408.355292) (xy 110.589314 -408.357324)
			(xy 110.61319 -408.35961) (xy 111.0742 -407.8986) (xy 113.2332 -407.8986) (xy 113.5888 -407.543)
			(xy 113.5888 -406.0952) (xy 113.1824 -405.6888) (xy 105.7148 -405.6888) (xy 105.2957 -406.1079) (xy 105.2957 -406.477724)
			(xy 106.045 -406.477724) (xy 106.045486 -406.450473) (xy 106.053242 -406.396525) (xy 106.068597 -406.34423)
			(xy 106.091239 -406.294653) (xy 106.120705 -406.248803) (xy 106.156396 -406.207612) (xy 106.197587 -406.171921)
			(xy 106.243437 -406.142455) (xy 106.293014 -406.119813) (xy 106.345309 -406.104458) (xy 106.399257 -406.096702)
			(xy 106.453759 -406.096702) (xy 106.507707 -406.104458) (xy 106.560002 -406.119813) (xy 106.609579 -406.142455)
			(xy 106.655429 -406.171921) (xy 106.69662 -406.207612) (xy 106.732311 -406.248803) (xy 106.761777 -406.294653)
			(xy 106.784419 -406.34423) (xy 106.799774 -406.396525) (xy 106.80753 -406.450473) (xy 106.808016 -406.477724)
			(xy 106.807456 -406.50803) (xy 106.797879 -406.567879) (xy 106.788966 -406.59685) (xy 106.785125 -406.610037)
			(xy 106.783808 -406.63746) (xy 106.789847 -406.664242) (xy 106.802806 -406.688445) (xy 106.821746 -406.70832)
			(xy 106.845299 -406.722428) (xy 106.871759 -406.729748) (xy 106.885486 -406.7302) (xy 107.226354 -406.7302)
			(xy 107.240082 -406.72972) (xy 107.266548 -406.722412) (xy 107.290106 -406.708312) (xy 107.309053 -406.688441)
			(xy 107.322016 -406.664238) (xy 107.328057 -406.637455) (xy 107.326738 -406.610031) (xy 107.322874 -406.59685)
			(xy 107.313967 -406.567879) (xy 107.304404 -406.508029) (xy 107.303824 -406.477724) (xy 107.30431 -406.450473)
			(xy 107.312066 -406.396525) (xy 107.327421 -406.34423) (xy 107.350063 -406.294653) (xy 107.379529 -406.248803)
			(xy 107.41522 -406.207612) (xy 107.456411 -406.171921) (xy 107.502261 -406.142455) (xy 107.551838 -406.119813)
			(xy 107.604133 -406.104458) (xy 107.658081 -406.096702) (xy 107.712583 -406.096702) (xy 107.766531 -406.104458)
			(xy 107.818826 -406.119813) (xy 107.868403 -406.142455) (xy 107.914253 -406.171921) (xy 107.955444 -406.207612)
			(xy 107.991135 -406.248803) (xy 108.020601 -406.294653) (xy 108.043243 -406.34423) (xy 108.058598 -406.396525)
			(xy 108.066354 -406.450473) (xy 108.06684 -406.477724) (xy 108.066308 -406.506612) (xy 108.057606 -406.56373)
			(xy 108.040389 -406.618881) (xy 108.015052 -406.670805) (xy 107.982173 -406.718314) (xy 107.942505 -406.760321)
			(xy 107.896956 -406.795865) (xy 107.872022 -406.810464) (xy 107.8588 -406.818463) (xy 107.837563 -406.840892)
			(xy 107.824001 -406.868644) (xy 107.819355 -406.899181) (xy 107.82405 -406.92971) (xy 107.830366 -406.943814)
			(xy 107.842654 -406.970075) (xy 107.859981 -407.025403) (xy 107.866436 -407.067766) (xy 109.697264 -407.067766)
			(xy 109.701335 -407.012144) (xy 109.713461 -406.957707) (xy 109.733384 -406.905616) (xy 109.76068 -406.856981)
			(xy 109.794766 -406.812838) (xy 109.834915 -406.774129) (xy 109.880273 -406.741678) (xy 109.929873 -406.716177)
			(xy 109.982657 -406.69817) (xy 110.0375 -406.68804) (xy 110.093234 -406.686003) (xy 110.148671 -406.692103)
			(xy 110.202628 -406.706209) (xy 110.253957 -406.728021) (xy 110.301563 -406.757075) (xy 110.344431 -406.79275)
			(xy 110.381648 -406.834287) (xy 110.412421 -406.8808) (xy 110.436093 -406.931297) (xy 110.452161 -406.984704)
			(xy 110.460281 -407.03988) (xy 110.46079 -407.067766) (xy 110.460674 -407.074116) (xy 111.710214 -407.074116)
			(xy 111.714285 -407.018494) (xy 111.726411 -406.964057) (xy 111.746334 -406.911966) (xy 111.77363 -406.863331)
			(xy 111.807716 -406.819188) (xy 111.847865 -406.780479) (xy 111.893223 -406.748028) (xy 111.942823 -406.722527)
			(xy 111.995607 -406.70452) (xy 112.05045 -406.69439) (xy 112.106184 -406.692353) (xy 112.161621 -406.698453)
			(xy 112.215578 -406.712559) (xy 112.266907 -406.734371) (xy 112.314513 -406.763425) (xy 112.357381 -406.7991)
			(xy 112.394598 -406.840637) (xy 112.425371 -406.88715) (xy 112.449043 -406.937647) (xy 112.465111 -406.991054)
			(xy 112.473231 -407.04623) (xy 112.47374 -407.074116) (xy 112.473231 -407.102002) (xy 112.465111 -407.157178)
			(xy 112.449043 -407.210585) (xy 112.425371 -407.261082) (xy 112.394598 -407.307595) (xy 112.357381 -407.349132)
			(xy 112.314513 -407.384807) (xy 112.266907 -407.413861) (xy 112.215578 -407.435673) (xy 112.161621 -407.449779)
			(xy 112.106184 -407.455879) (xy 112.05045 -407.453842) (xy 111.995607 -407.443712) (xy 111.942823 -407.425705)
			(xy 111.893223 -407.400204) (xy 111.847865 -407.367753) (xy 111.807716 -407.329044) (xy 111.77363 -407.284901)
			(xy 111.746334 -407.236266) (xy 111.726411 -407.184175) (xy 111.714285 -407.129738) (xy 111.710214 -407.074116)
			(xy 110.460674 -407.074116) (xy 110.460281 -407.095652) (xy 110.452161 -407.150828) (xy 110.436093 -407.204235)
			(xy 110.412421 -407.254732) (xy 110.381648 -407.301245) (xy 110.344431 -407.342782) (xy 110.301563 -407.378457)
			(xy 110.253957 -407.407511) (xy 110.202628 -407.429323) (xy 110.148671 -407.443429) (xy 110.093234 -407.449529)
			(xy 110.0375 -407.447492) (xy 109.982657 -407.437362) (xy 109.929873 -407.419355) (xy 109.880273 -407.393854)
			(xy 109.834915 -407.361403) (xy 109.794766 -407.322694) (xy 109.76068 -407.278551) (xy 109.733384 -407.229916)
			(xy 109.713461 -407.177825) (xy 109.701335 -407.123388) (xy 109.697264 -407.067766) (xy 107.866436 -407.067766)
			(xy 107.868715 -407.082719) (xy 107.869228 -407.111708) (xy 107.86873 -407.138959) (xy 107.860973 -407.192905)
			(xy 107.845618 -407.245198) (xy 107.822977 -407.294774) (xy 107.793512 -407.340623) (xy 107.757822 -407.381813)
			(xy 107.716633 -407.417504) (xy 107.670785 -407.446971) (xy 107.621209 -407.469613) (xy 107.568917 -407.48497)
			(xy 107.514971 -407.492729) (xy 107.48772 -407.493216) (xy 106.62412 -407.493216) (xy 106.596868 -407.492726)
			(xy 106.542918 -407.484972) (xy 106.490622 -407.469619) (xy 106.441042 -407.446979) (xy 106.395189 -407.417514)
			(xy 106.353997 -407.381823) (xy 106.318303 -407.340633) (xy 106.288834 -407.294783) (xy 106.266191 -407.245205)
			(xy 106.250834 -407.192909) (xy 106.243076 -407.13896) (xy 106.242612 -407.111708) (xy 106.243153 -407.082722)
			(xy 106.251915 -407.025417) (xy 106.269225 -406.97009) (xy 106.281474 -406.943814) (xy 106.287772 -406.929704)
			(xy 106.292463 -406.899179) (xy 106.287819 -406.868647) (xy 106.274263 -406.840898) (xy 106.253035 -406.818467)
			(xy 106.239818 -406.810464) (xy 106.214889 -406.79586) (xy 106.169347 -406.76031) (xy 106.129685 -406.718301)
			(xy 106.096808 -406.670793) (xy 106.071469 -406.618872) (xy 106.054246 -406.563725) (xy 106.045534 -406.506611)
			(xy 106.045 -406.477724) (xy 105.2957 -406.477724) (xy 105.2957 -406.7683) (xy 104.4194 -407.6446)
			(xy 103.94823 -407.6446) (xy 103.939848 -407.647648) (xy 103.914731 -407.656274) (xy 103.862778 -407.667284)
			(xy 103.8098 -407.670978) (xy 103.756822 -407.667284) (xy 103.704869 -407.656274) (xy 103.679752 -407.647648)
			(xy 103.67137 -407.6446) (xy 103.5558 -407.6446) (xy 103.3526 -407.8478) (xy 103.3526 -408.063252)
			(xy 108.569969 -408.063252) (xy 108.569969 -408.008748) (xy 108.577726 -407.954797) (xy 108.593083 -407.9025)
			(xy 108.615725 -407.852921) (xy 108.645193 -407.807069) (xy 108.680887 -407.765877) (xy 108.72208 -407.730185)
			(xy 108.767933 -407.700719) (xy 108.817513 -407.678078) (xy 108.869811 -407.662723) (xy 108.923761 -407.654968)
			(xy 108.951014 -407.654506) (xy 108.977454 -407.655001) (xy 109.029827 -407.662293) (xy 109.080691 -407.67675)
			(xy 109.129071 -407.698093) (xy 109.174039 -407.725915) (xy 109.214733 -407.759681) (xy 109.250373 -407.798745)
			(xy 109.280276 -407.842357) (xy 109.303868 -407.889681) (xy 109.31271 -407.914602) (xy 109.317438 -407.92722)
			(xy 109.33239 -407.949622) (xy 109.352684 -407.967329) (xy 109.376906 -407.979105) (xy 109.403366 -407.984131)
			(xy 109.430219 -407.982055) (xy 109.455592 -407.973022) (xy 109.477716 -407.957662) (xy 109.4867 -407.947622)
			(xy 109.504944 -407.926732) (xy 109.546404 -407.889899) (xy 109.592765 -407.859462) (xy 109.643048 -407.836065)
			(xy 109.69619 -407.820203) (xy 109.75107 -407.812209) (xy 109.7788 -407.811732) (xy 109.806054 -407.812138)
			(xy 109.860007 -407.819895) (xy 109.912308 -407.835252) (xy 109.96189 -407.857895) (xy 110.007745 -407.887365)
			(xy 110.04894 -407.92306) (xy 110.084635 -407.964255) (xy 110.114105 -408.01011) (xy 110.136748 -408.059692)
			(xy 110.152105 -408.111993) (xy 110.159862 -408.165946) (xy 110.159862 -408.220454) (xy 110.152105 -408.274407)
			(xy 110.136748 -408.326708) (xy 110.114105 -408.37629) (xy 110.084635 -408.422145) (xy 110.04894 -408.46334)
			(xy 110.007745 -408.499035) (xy 109.96189 -408.528505) (xy 109.912308 -408.551148) (xy 109.860007 -408.566505)
			(xy 109.806054 -408.574262) (xy 109.7788 -408.574748) (xy 109.752357 -408.57436) (xy 109.699977 -408.567055)
			(xy 109.649109 -408.552586) (xy 109.600726 -408.531229) (xy 109.555758 -408.503394) (xy 109.515064 -408.469614)
			(xy 109.479427 -408.430538) (xy 109.449529 -408.386914) (xy 109.425942 -408.339579) (xy 109.417104 -408.314652)
			(xy 109.412343 -408.302045) (xy 109.397402 -408.279638) (xy 109.377114 -408.261925) (xy 109.352896 -408.250143)
			(xy 109.326438 -408.245115) (xy 109.299586 -408.24719) (xy 109.274215 -408.256226) (xy 109.252095 -408.27159)
			(xy 109.243114 -408.281632) (xy 109.224875 -408.302526) (xy 109.183412 -408.339357) (xy 109.13705 -408.369791)
			(xy 109.086766 -408.393187) (xy 109.033624 -408.409049) (xy 108.978744 -408.417044) (xy 108.951014 -408.417522)
			(xy 108.923761 -408.417032) (xy 108.869811 -408.409277) (xy 108.817513 -408.393922) (xy 108.767933 -408.371281)
			(xy 108.72208 -408.341815) (xy 108.680887 -408.306123) (xy 108.645193 -408.264931) (xy 108.615725 -408.219079)
			(xy 108.593083 -408.1695) (xy 108.577726 -408.117203) (xy 108.569969 -408.063252) (xy 103.3526 -408.063252)
			(xy 103.3526 -409.1686) (xy 103.8352 -409.6512) (xy 103.852726 -409.653232) (xy 103.881001 -409.65697)
			(xy 103.936084 -409.671756) (xy 103.988351 -409.69458) (xy 104.036636 -409.724933) (xy 104.079862 -409.762138)
			(xy 104.117067 -409.805364) (xy 104.14742 -409.853649) (xy 104.170244 -409.905916) (xy 104.18503 -409.960999)
			(xy 104.188768 -409.989274) (xy 104.1908 -410.0068) (xy 105.2322 -411.0482) (xy 107.9246 -411.0482)
		)
		(stroke
			(width 0)
			(type solid)
		)
		(fill yes)
		(layer "In2.Cu")
		(net "P3V3_AUX")
	)
	(gr_poly
		(pts
			(xy 35.784282 -131.419092) (xy 35.798084 -131.419017) (xy 35.824864 -131.412377) (xy 35.848891 -131.398816)
			(xy 35.858958 -131.389374) (xy 36.555172 -130.69316) (xy 36.555172 -124.725684) (xy 36.49726 -124.667772)
			(xy 36.445698 -124.61621) (xy 36.036758 -124.207016) (xy 34.502598 -124.207016) (xy 34.46907 -124.227082)
			(xy 34.445838 -124.238819) (xy 34.396896 -124.256536) (xy 34.371534 -124.262388) (xy 34.357153 -124.266527)
			(xy 34.331478 -124.281875) (xy 34.311345 -124.303997) (xy 34.298477 -124.330999) (xy 34.293977 -124.360571)
			(xy 34.298229 -124.390179) (xy 34.310869 -124.417289) (xy 34.32048 -124.428758) (xy 34.477706 -124.585984)
			(xy 34.548318 -124.656342) (xy 34.565671 -124.674327) (xy 34.595069 -124.714741) (xy 34.617776 -124.75926)
			(xy 34.63323 -124.806785) (xy 34.641052 -124.856144) (xy 34.641536 -124.881132) (xy 34.641536 -125.780546)
			(xy 34.642036 -125.794723) (xy 34.649895 -125.82197) (xy 34.66494 -125.846007) (xy 34.686011 -125.864985)
			(xy 34.711486 -125.877441) (xy 34.739403 -125.882416) (xy 34.75355 -125.881384) (xy 34.763491 -125.880417)
			(xy 34.78344 -125.879401) (xy 34.793428 -125.879352) (xy 34.820681 -125.87984) (xy 34.874631 -125.8876)
			(xy 34.926928 -125.90296) (xy 34.976507 -125.925605) (xy 35.022359 -125.955075) (xy 35.06355 -125.99077)
			(xy 35.099242 -126.031964) (xy 35.128709 -126.077818) (xy 35.15135 -126.127398) (xy 35.166706 -126.179696)
			(xy 35.174462 -126.233647) (xy 35.174462 -126.288153) (xy 35.166706 -126.342104) (xy 35.15135 -126.394402)
			(xy 35.128709 -126.443982) (xy 35.099242 -126.489836) (xy 35.06355 -126.53103) (xy 35.022359 -126.566725)
			(xy 34.976507 -126.596195) (xy 34.926928 -126.61884) (xy 34.874631 -126.6342) (xy 34.820681 -126.64196)
			(xy 34.793428 -126.642368) (xy 34.78344 -126.642314) (xy 34.763492 -126.641296) (xy 34.75355 -126.640336)
			(xy 34.739397 -126.639342) (xy 34.711473 -126.644295) (xy 34.685987 -126.656737) (xy 34.664907 -126.675709)
			(xy 34.651112 -126.69774) (xy 35.487862 -126.69774) (xy 35.491933 -126.642118) (xy 35.504059 -126.587681)
			(xy 35.523982 -126.53559) (xy 35.551278 -126.486955) (xy 35.585364 -126.442812) (xy 35.625513 -126.404103)
			(xy 35.670871 -126.371652) (xy 35.720471 -126.346151) (xy 35.773255 -126.328144) (xy 35.828098 -126.318014)
			(xy 35.883832 -126.315977) (xy 35.939269 -126.322077) (xy 35.993226 -126.336183) (xy 36.044555 -126.357995)
			(xy 36.092161 -126.387049) (xy 36.135029 -126.422724) (xy 36.172246 -126.464261) (xy 36.203019 -126.510774)
			(xy 36.226691 -126.561271) (xy 36.242759 -126.614678) (xy 36.250879 -126.669854) (xy 36.251388 -126.69774)
			(xy 36.250879 -126.725626) (xy 36.242759 -126.780802) (xy 36.226691 -126.834209) (xy 36.203019 -126.884706)
			(xy 36.172246 -126.931219) (xy 36.135029 -126.972756) (xy 36.092161 -127.008431) (xy 36.044555 -127.037485)
			(xy 35.993226 -127.059297) (xy 35.939269 -127.073403) (xy 35.883832 -127.079503) (xy 35.828098 -127.077466)
			(xy 35.773255 -127.067336) (xy 35.720471 -127.049329) (xy 35.670871 -127.023828) (xy 35.625513 -126.991377)
			(xy 35.585364 -126.952668) (xy 35.551278 -126.908525) (xy 35.523982 -126.85989) (xy 35.504059 -126.807799)
			(xy 35.491933 -126.753362) (xy 35.487862 -126.69774) (xy 34.651112 -126.69774) (xy 34.649856 -126.699746)
			(xy 34.641996 -126.726995) (xy 34.641536 -126.741174) (xy 34.641536 -127.966724) (xy 35.514532 -127.966724)
			(xy 35.518603 -127.911102) (xy 35.530729 -127.856665) (xy 35.550652 -127.804574) (xy 35.577948 -127.755939)
			(xy 35.612034 -127.711796) (xy 35.652183 -127.673087) (xy 35.697541 -127.640636) (xy 35.747141 -127.615135)
			(xy 35.799925 -127.597128) (xy 35.854768 -127.586998) (xy 35.910502 -127.584961) (xy 35.965939 -127.591061)
			(xy 36.019896 -127.605167) (xy 36.071225 -127.626979) (xy 36.118831 -127.656033) (xy 36.161699 -127.691708)
			(xy 36.198916 -127.733245) (xy 36.229689 -127.779758) (xy 36.253361 -127.830255) (xy 36.269429 -127.883662)
			(xy 36.277549 -127.938838) (xy 36.278058 -127.966724) (xy 36.277549 -127.99461) (xy 36.269429 -128.049786)
			(xy 36.253361 -128.103193) (xy 36.229689 -128.15369) (xy 36.198916 -128.200203) (xy 36.161699 -128.24174)
			(xy 36.118831 -128.277415) (xy 36.071225 -128.306469) (xy 36.019896 -128.328281) (xy 35.965939 -128.342387)
			(xy 35.910502 -128.348487) (xy 35.854768 -128.34645) (xy 35.799925 -128.33632) (xy 35.747141 -128.318313)
			(xy 35.697541 -128.292812) (xy 35.652183 -128.260361) (xy 35.612034 -128.221652) (xy 35.577948 -128.177509)
			(xy 35.550652 -128.128874) (xy 35.530729 -128.076783) (xy 35.518603 -128.022346) (xy 35.514532 -127.966724)
			(xy 34.641536 -127.966724) (xy 34.641536 -128.898257) (xy 34.774519 -128.898257) (xy 34.774519 -128.843743)
			(xy 34.782278 -128.789784) (xy 34.797637 -128.737479) (xy 34.820284 -128.687892) (xy 34.849757 -128.642033)
			(xy 34.885458 -128.600835) (xy 34.926658 -128.565138) (xy 34.97252 -128.535668) (xy 35.022109 -128.513025)
			(xy 35.074416 -128.497671) (xy 35.128375 -128.489917) (xy 35.155632 -128.489456) (xy 35.183235 -128.48994)
			(xy 35.237867 -128.497876) (xy 35.290784 -128.513608) (xy 35.340879 -128.536805) (xy 35.387106 -128.566983)
			(xy 35.428498 -128.603512) (xy 35.46419 -128.645628) (xy 35.479228 -128.66878) (xy 35.486745 -128.680134)
			(xy 35.506723 -128.698627) (xy 35.530881 -128.711177) (xy 35.557498 -128.716889) (xy 35.584678 -128.715357)
			(xy 35.610485 -128.70669) (xy 35.633079 -128.691506) (xy 35.642296 -128.68148) (xy 35.660491 -128.661057)
			(xy 35.701733 -128.625128) (xy 35.747683 -128.595458) (xy 35.7974 -128.572655) (xy 35.849864 -128.557185)
			(xy 35.904 -128.549366) (xy 35.931348 -128.548892) (xy 35.9586 -128.549333) (xy 36.01255 -128.557096)
			(xy 36.064845 -128.572457) (xy 36.114423 -128.595104) (xy 36.160273 -128.624575) (xy 36.201463 -128.660271)
			(xy 36.237153 -128.701466) (xy 36.266619 -128.747319) (xy 36.289259 -128.7969) (xy 36.304614 -128.849197)
			(xy 36.31237 -128.903148) (xy 36.312856 -128.9304) (xy 36.312354 -128.959318) (xy 36.303624 -129.01649)
			(xy 36.286364 -129.07169) (xy 36.260969 -129.123652) (xy 36.228022 -129.171186) (xy 36.188277 -129.213201)
			(xy 36.16579 -129.23139) (xy 36.154505 -129.240742) (xy 36.137427 -129.264546) (xy 36.127817 -129.292223)
			(xy 36.12647 -129.321489) (xy 36.133495 -129.349931) (xy 36.148314 -129.375205) (xy 36.158678 -129.385568)
			(xy 36.177306 -129.403687) (xy 36.210021 -129.444059) (xy 36.236951 -129.4885) (xy 36.257598 -129.536186)
			(xy 36.271578 -129.586234) (xy 36.278634 -129.637716) (xy 36.279074 -129.663698) (xy 36.278643 -129.690952)
			(xy 36.270885 -129.744906) (xy 36.255528 -129.797207) (xy 36.232883 -129.846789) (xy 36.203412 -129.892644)
			(xy 36.167715 -129.933837) (xy 36.126518 -129.969531) (xy 36.080661 -129.998998) (xy 36.031077 -130.021639)
			(xy 35.978775 -130.036992) (xy 35.92482 -130.044745) (xy 35.897566 -130.045206) (xy 35.868794 -130.044675)
			(xy 35.811906 -130.035999) (xy 35.784282 -130.027934) (xy 35.770239 -130.023972) (xy 35.741071 -130.023495)
			(xy 35.712955 -130.031276) (xy 35.688183 -130.046681) (xy 35.66877 -130.068456) (xy 35.656298 -130.094827)
			(xy 35.651782 -130.123647) (xy 35.653218 -130.13817) (xy 35.654756 -130.150495) (xy 35.656405 -130.17528)
			(xy 35.65652 -130.1877) (xy 35.656045 -130.214953) (xy 35.648288 -130.268904) (xy 35.632931 -130.321202)
			(xy 35.610289 -130.370783) (xy 35.58082 -130.416636) (xy 35.545126 -130.457829) (xy 35.503933 -130.493523)
			(xy 35.458079 -130.52299) (xy 35.408499 -130.545633) (xy 35.3562 -130.560988) (xy 35.302249 -130.568745)
			(xy 35.247743 -130.568744) (xy 35.193792 -130.560987) (xy 35.141494 -130.54563) (xy 35.091914 -130.522987)
			(xy 35.046061 -130.493518) (xy 35.004868 -130.457823) (xy 34.969175 -130.41663) (xy 34.939708 -130.370776)
			(xy 34.917066 -130.321195) (xy 34.901711 -130.268896) (xy 34.893955 -130.214945) (xy 34.893956 -130.160439)
			(xy 34.901714 -130.106488) (xy 34.917071 -130.05419) (xy 34.939715 -130.00461) (xy 34.969185 -129.958757)
			(xy 35.00488 -129.917565) (xy 35.046073 -129.881873) (xy 35.091928 -129.852406) (xy 35.141509 -129.829764)
			(xy 35.193807 -129.81441) (xy 35.247759 -129.806654) (xy 35.275012 -129.806192) (xy 35.303784 -129.806728)
			(xy 35.360672 -129.815401) (xy 35.388296 -129.823464) (xy 35.402345 -129.827403) (xy 35.431511 -129.827886)
			(xy 35.459625 -129.820109) (xy 35.484397 -129.804708) (xy 35.50381 -129.782936) (xy 35.516281 -129.756567)
			(xy 35.520797 -129.72775) (xy 35.51936 -129.713228) (xy 35.517822 -129.700903) (xy 35.516173 -129.676118)
			(xy 35.516058 -129.663698) (xy 35.516553 -129.63478) (xy 35.525284 -129.577607) (xy 35.542545 -129.522406)
			(xy 35.567941 -129.470444) (xy 35.600889 -129.422911) (xy 35.640636 -129.380897) (xy 35.663124 -129.362708)
			(xy 35.67441 -129.353358) (xy 35.691486 -129.329553) (xy 35.701094 -129.301876) (xy 35.702441 -129.27261)
			(xy 35.695417 -129.244168) (xy 35.680599 -129.218894) (xy 35.670236 -129.20853) (xy 35.65251 -129.191376)
			(xy 35.62117 -129.153283) (xy 35.607752 -129.132584) (xy 35.600137 -129.121302) (xy 35.580177 -129.102818)
			(xy 35.556041 -129.09027) (xy 35.529445 -129.084551) (xy 35.502284 -129.086069) (xy 35.47649 -129.094714)
			(xy 35.453901 -129.109872) (xy 35.444684 -129.119884) (xy 35.426492 -129.14031) (xy 35.38525 -129.176239)
			(xy 35.339299 -129.20591) (xy 35.289582 -129.228714) (xy 35.237117 -129.244183) (xy 35.182981 -129.251999)
			(xy 35.155632 -129.252472) (xy 35.128375 -129.252083) (xy 35.074416 -129.244329) (xy 35.022109 -129.228975)
			(xy 34.97252 -129.206332) (xy 34.926658 -129.176862) (xy 34.885458 -129.141165) (xy 34.849757 -129.099967)
			(xy 34.820284 -129.054108) (xy 34.797637 -129.004521) (xy 34.782278 -128.952216) (xy 34.774519 -128.898257)
			(xy 34.641536 -128.898257) (xy 34.641536 -129.521712) (xy 34.651696 -129.531872) (xy 34.651696 -130.895598)
			(xy 34.825432 -131.069334) (xy 34.835923 -131.079075) (xy 34.861018 -131.092826) (xy 34.888941 -131.099081)
			(xy 34.917504 -131.097349) (xy 34.944468 -131.087768) (xy 34.967719 -131.071087) (xy 34.985434 -131.048614)
			(xy 34.991294 -131.035552) (xy 35.0024 -131.009539) (xy 35.031167 -130.960841) (xy 35.066812 -130.916926)
			(xy 35.108551 -130.878757) (xy 35.15547 -130.847171) (xy 35.206539 -130.822861) (xy 35.260638 -130.80636)
			(xy 35.316582 -130.79803) (xy 35.344862 -130.797554) (xy 35.372116 -130.798037) (xy 35.42607 -130.805789)
			(xy 35.478371 -130.821141) (xy 35.527956 -130.843779) (xy 35.573814 -130.873244) (xy 35.615012 -130.908935)
			(xy 35.650711 -130.950125) (xy 35.680185 -130.995977) (xy 35.702833 -131.045557) (xy 35.718195 -131.097856)
			(xy 35.725957 -131.151808) (xy 35.72637 -131.179062) (xy 35.725827 -131.207871) (xy 35.717118 -131.264826)
			(xy 35.699922 -131.319818) (xy 35.687762 -131.34594) (xy 35.682682 -131.356608) (xy 35.682682 -131.419092)
		)
		(stroke
			(width 0)
			(type solid)
		)
		(fill yes)
		(layer "In2.Cu")
		(net "GND")
	)
	(gr_poly
		(pts
			(xy 124.92228 -425.084748) (xy 124.92228 -416.956748) (xy 124.05868 -416.093148) (xy 119.91848 -416.093148)
			(xy 119.59336 -416.418268) (xy 119.610886 -416.451288) (xy 119.624724 -416.47886) (xy 119.644297 -416.537359)
			(xy 119.654213 -416.598244) (xy 119.654828 -416.629088) (xy 119.654343 -416.65634) (xy 119.646588 -416.71029)
			(xy 119.631234 -416.762588) (xy 119.608594 -416.812168) (xy 119.579128 -416.858021) (xy 119.543437 -416.899214)
			(xy 119.538597 -416.903408) (xy 123.402342 -416.903408) (xy 123.406413 -416.847786) (xy 123.418539 -416.793349)
			(xy 123.438462 -416.741258) (xy 123.465758 -416.692623) (xy 123.499844 -416.64848) (xy 123.539993 -416.609771)
			(xy 123.585351 -416.57732) (xy 123.634951 -416.551819) (xy 123.687735 -416.533812) (xy 123.742578 -416.523682)
			(xy 123.798312 -416.521645) (xy 123.853749 -416.527745) (xy 123.907706 -416.541851) (xy 123.959035 -416.563663)
			(xy 124.006641 -416.592717) (xy 124.049509 -416.628392) (xy 124.086726 -416.669929) (xy 124.117499 -416.716442)
			(xy 124.141171 -416.766939) (xy 124.157239 -416.820346) (xy 124.165359 -416.875522) (xy 124.165868 -416.903408)
			(xy 124.165359 -416.931294) (xy 124.157239 -416.98647) (xy 124.141171 -417.039877) (xy 124.117499 -417.090374)
			(xy 124.086726 -417.136887) (xy 124.049509 -417.178424) (xy 124.006641 -417.214099) (xy 123.959035 -417.243153)
			(xy 123.907706 -417.264965) (xy 123.853749 -417.279071) (xy 123.798312 -417.285171) (xy 123.742578 -417.283134)
			(xy 123.687735 -417.273004) (xy 123.634951 -417.254997) (xy 123.585351 -417.229496) (xy 123.539993 -417.197045)
			(xy 123.499844 -417.158336) (xy 123.465758 -417.114193) (xy 123.438462 -417.065558) (xy 123.418539 -417.013467)
			(xy 123.406413 -416.95903) (xy 123.402342 -416.903408) (xy 119.538597 -416.903408) (xy 119.502247 -416.934909)
			(xy 119.456396 -416.964379) (xy 119.406818 -416.987023) (xy 119.354522 -417.002381) (xy 119.300572 -417.010141)
			(xy 119.27332 -417.010596) (xy 119.242475 -417.010005) (xy 119.181588 -417.000085) (xy 119.123089 -416.980499)
			(xy 119.09552 -416.966654) (xy 119.0625 -416.949128) (xy 117.42928 -418.582348) (xy 117.42928 -420.320978)
			(xy 118.500142 -420.320978) (xy 118.504213 -420.265356) (xy 118.516339 -420.210919) (xy 118.536262 -420.158828)
			(xy 118.563558 -420.110193) (xy 118.597644 -420.06605) (xy 118.637793 -420.027341) (xy 118.683151 -419.99489)
			(xy 118.732751 -419.969389) (xy 118.785535 -419.951382) (xy 118.840378 -419.941252) (xy 118.896112 -419.939215)
			(xy 118.951549 -419.945315) (xy 119.005506 -419.959421) (xy 119.056835 -419.981233) (xy 119.104441 -420.010287)
			(xy 119.147309 -420.045962) (xy 119.184526 -420.087499) (xy 119.215299 -420.134012) (xy 119.238971 -420.184509)
			(xy 119.241438 -420.192708) (xy 120.306082 -420.192708) (xy 120.310153 -420.137086) (xy 120.322279 -420.082649)
			(xy 120.342202 -420.030558) (xy 120.369498 -419.981923) (xy 120.403584 -419.93778) (xy 120.443733 -419.899071)
			(xy 120.489091 -419.86662) (xy 120.538691 -419.841119) (xy 120.591475 -419.823112) (xy 120.646318 -419.812982)
			(xy 120.702052 -419.810945) (xy 120.757489 -419.817045) (xy 120.811446 -419.831151) (xy 120.862775 -419.852963)
			(xy 120.910381 -419.882017) (xy 120.953249 -419.917692) (xy 120.990466 -419.959229) (xy 121.021239 -420.005742)
			(xy 121.044911 -420.056239) (xy 121.060979 -420.109646) (xy 121.069099 -420.164822) (xy 121.069608 -420.192708)
			(xy 121.069099 -420.220594) (xy 121.060979 -420.27577) (xy 121.044911 -420.329177) (xy 121.021239 -420.379674)
			(xy 120.990466 -420.426187) (xy 120.953249 -420.467724) (xy 120.910381 -420.503399) (xy 120.862775 -420.532453)
			(xy 120.811446 -420.554265) (xy 120.757489 -420.568371) (xy 120.702052 -420.574471) (xy 120.646318 -420.572434)
			(xy 120.591475 -420.562304) (xy 120.538691 -420.544297) (xy 120.489091 -420.518796) (xy 120.443733 -420.486345)
			(xy 120.403584 -420.447636) (xy 120.369498 -420.403493) (xy 120.342202 -420.354858) (xy 120.322279 -420.302767)
			(xy 120.310153 -420.24833) (xy 120.306082 -420.192708) (xy 119.241438 -420.192708) (xy 119.255039 -420.237916)
			(xy 119.263159 -420.293092) (xy 119.263668 -420.320978) (xy 119.263159 -420.348864) (xy 119.255039 -420.40404)
			(xy 119.238971 -420.457447) (xy 119.215299 -420.507944) (xy 119.184526 -420.554457) (xy 119.147309 -420.595994)
			(xy 119.104441 -420.631669) (xy 119.056835 -420.660723) (xy 119.005506 -420.682535) (xy 118.951549 -420.696641)
			(xy 118.896112 -420.702741) (xy 118.840378 -420.700704) (xy 118.785535 -420.690574) (xy 118.732751 -420.672567)
			(xy 118.683151 -420.647066) (xy 118.637793 -420.614615) (xy 118.597644 -420.575906) (xy 118.563558 -420.531763)
			(xy 118.536262 -420.483128) (xy 118.516339 -420.431037) (xy 118.504213 -420.3766) (xy 118.500142 -420.320978)
			(xy 117.42928 -420.320978) (xy 117.42928 -421.447468) (xy 121.005852 -421.447468) (xy 121.009923 -421.391846)
			(xy 121.022049 -421.337409) (xy 121.041972 -421.285318) (xy 121.069268 -421.236683) (xy 121.103354 -421.19254)
			(xy 121.143503 -421.153831) (xy 121.188861 -421.12138) (xy 121.238461 -421.095879) (xy 121.291245 -421.077872)
			(xy 121.346088 -421.067742) (xy 121.401822 -421.065705) (xy 121.457259 -421.071805) (xy 121.511216 -421.085911)
			(xy 121.562545 -421.107723) (xy 121.610151 -421.136777) (xy 121.653019 -421.172452) (xy 121.690236 -421.213989)
			(xy 121.721009 -421.260502) (xy 121.744681 -421.310999) (xy 121.760749 -421.364406) (xy 121.768869 -421.419582)
			(xy 121.769378 -421.447468) (xy 121.768869 -421.475354) (xy 121.760749 -421.53053) (xy 121.744681 -421.583937)
			(xy 121.721009 -421.634434) (xy 121.690236 -421.680947) (xy 121.653019 -421.722484) (xy 121.610151 -421.758159)
			(xy 121.562545 -421.787213) (xy 121.511216 -421.809025) (xy 121.457259 -421.823131) (xy 121.401822 -421.829231)
			(xy 121.346088 -421.827194) (xy 121.291245 -421.817064) (xy 121.238461 -421.799057) (xy 121.188861 -421.773556)
			(xy 121.143503 -421.741105) (xy 121.103354 -421.702396) (xy 121.069268 -421.658253) (xy 121.041972 -421.609618)
			(xy 121.022049 -421.557527) (xy 121.009923 -421.50309) (xy 121.005852 -421.447468) (xy 117.42928 -421.447468)
			(xy 117.42928 -423.479468) (xy 121.005852 -423.479468) (xy 121.009923 -423.423846) (xy 121.022049 -423.369409)
			(xy 121.041972 -423.317318) (xy 121.069268 -423.268683) (xy 121.103354 -423.22454) (xy 121.143503 -423.185831)
			(xy 121.188861 -423.15338) (xy 121.238461 -423.127879) (xy 121.291245 -423.109872) (xy 121.346088 -423.099742)
			(xy 121.401822 -423.097705) (xy 121.457259 -423.103805) (xy 121.511216 -423.117911) (xy 121.562545 -423.139723)
			(xy 121.610151 -423.168777) (xy 121.653019 -423.204452) (xy 121.690236 -423.245989) (xy 121.721009 -423.292502)
			(xy 121.744681 -423.342999) (xy 121.760749 -423.396406) (xy 121.768869 -423.451582) (xy 121.769378 -423.479468)
			(xy 121.768869 -423.507354) (xy 121.760749 -423.56253) (xy 121.744681 -423.615937) (xy 121.721009 -423.666434)
			(xy 121.690236 -423.712947) (xy 121.653019 -423.754484) (xy 121.610151 -423.790159) (xy 121.562545 -423.819213)
			(xy 121.511216 -423.841025) (xy 121.457259 -423.855131) (xy 121.401822 -423.861231) (xy 121.346088 -423.859194)
			(xy 121.291245 -423.849064) (xy 121.238461 -423.831057) (xy 121.188861 -423.805556) (xy 121.143503 -423.773105)
			(xy 121.103354 -423.734396) (xy 121.069268 -423.690253) (xy 121.041972 -423.641618) (xy 121.022049 -423.589527)
			(xy 121.009923 -423.53509) (xy 121.005852 -423.479468) (xy 117.42928 -423.479468) (xy 117.42928 -424.772328)
			(xy 118.098822 -424.772328) (xy 118.102893 -424.716706) (xy 118.115019 -424.662269) (xy 118.134942 -424.610178)
			(xy 118.162238 -424.561543) (xy 118.196324 -424.5174) (xy 118.236473 -424.478691) (xy 118.281831 -424.44624)
			(xy 118.331431 -424.420739) (xy 118.384215 -424.402732) (xy 118.439058 -424.392602) (xy 118.494792 -424.390565)
			(xy 118.550229 -424.396665) (xy 118.604186 -424.410771) (xy 118.655515 -424.432583) (xy 118.703121 -424.461637)
			(xy 118.745989 -424.497312) (xy 118.783206 -424.538849) (xy 118.813979 -424.585362) (xy 118.837651 -424.635859)
			(xy 118.853719 -424.689266) (xy 118.861839 -424.744442) (xy 118.862348 -424.772328) (xy 118.861839 -424.800214)
			(xy 118.853719 -424.85539) (xy 118.837651 -424.908797) (xy 118.813979 -424.959294) (xy 118.783206 -425.005807)
			(xy 118.745989 -425.047344) (xy 118.731565 -425.059348) (xy 120.988072 -425.059348) (xy 120.992143 -425.003726)
			(xy 121.004269 -424.949289) (xy 121.024192 -424.897198) (xy 121.051488 -424.848563) (xy 121.085574 -424.80442)
			(xy 121.125723 -424.765711) (xy 121.171081 -424.73326) (xy 121.220681 -424.707759) (xy 121.273465 -424.689752)
			(xy 121.328308 -424.679622) (xy 121.384042 -424.677585) (xy 121.439479 -424.683685) (xy 121.493436 -424.697791)
			(xy 121.544765 -424.719603) (xy 121.592371 -424.748657) (xy 121.635239 -424.784332) (xy 121.672456 -424.825869)
			(xy 121.703229 -424.872382) (xy 121.726901 -424.922879) (xy 121.742969 -424.976286) (xy 121.751089 -425.031462)
			(xy 121.751598 -425.059348) (xy 121.751089 -425.087234) (xy 121.742969 -425.14241) (xy 121.726901 -425.195817)
			(xy 121.703229 -425.246314) (xy 121.672456 -425.292827) (xy 121.635239 -425.334364) (xy 121.592371 -425.370039)
			(xy 121.544765 -425.399093) (xy 121.493436 -425.420905) (xy 121.439479 -425.435011) (xy 121.384042 -425.441111)
			(xy 121.328308 -425.439074) (xy 121.273465 -425.428944) (xy 121.220681 -425.410937) (xy 121.171081 -425.385436)
			(xy 121.125723 -425.352985) (xy 121.085574 -425.314276) (xy 121.051488 -425.270133) (xy 121.024192 -425.221498)
			(xy 121.004269 -425.169407) (xy 120.992143 -425.11497) (xy 120.988072 -425.059348) (xy 118.731565 -425.059348)
			(xy 118.703121 -425.083019) (xy 118.655515 -425.112073) (xy 118.604186 -425.133885) (xy 118.550229 -425.147991)
			(xy 118.494792 -425.154091) (xy 118.439058 -425.152054) (xy 118.384215 -425.141924) (xy 118.331431 -425.123917)
			(xy 118.281831 -425.098416) (xy 118.236473 -425.065965) (xy 118.196324 -425.027256) (xy 118.162238 -424.983113)
			(xy 118.134942 -424.934478) (xy 118.115019 -424.882387) (xy 118.102893 -424.82795) (xy 118.098822 -424.772328)
			(xy 117.42928 -424.772328) (xy 117.42928 -425.795948) (xy 117.875812 -426.24248) (xy 117.886766 -426.252699)
			(xy 117.913163 -426.266832) (xy 117.942526 -426.272694) (xy 117.972326 -426.269778) (xy 117.999997 -426.258337)
			(xy 118.023153 -426.239355) (xy 118.039802 -426.214468) (xy 118.044722 -426.200316) (xy 118.053054 -426.17459)
			(xy 118.075963 -426.125607) (xy 118.105561 -426.080351) (xy 118.141254 -426.039728) (xy 118.182326 -426.004554)
			(xy 118.227954 -425.975532) (xy 118.277223 -425.953246) (xy 118.329146 -425.938141) (xy 118.382682 -425.930521)
			(xy 118.40972 -425.93006) (xy 118.436971 -425.930547) (xy 118.490918 -425.938306) (xy 118.543213 -425.953662)
			(xy 118.592789 -425.976304) (xy 118.63864 -426.00577) (xy 118.67983 -426.041462) (xy 118.715522 -426.082651)
			(xy 118.74499 -426.1285) (xy 118.767633 -426.178076) (xy 118.782992 -426.23037) (xy 118.790752 -426.284317)
			(xy 118.791228 -426.311568) (xy 118.790753 -426.338603) (xy 118.783114 -426.392132) (xy 118.767997 -426.444046)
			(xy 118.745706 -426.493308) (xy 118.716686 -426.538932) (xy 118.681519 -426.580004) (xy 118.640908 -426.615702)
			(xy 118.595666 -426.645313) (xy 118.546698 -426.668243) (xy 118.520972 -426.676566) (xy 118.506828 -426.681461)
			(xy 118.481998 -426.698148) (xy 118.463066 -426.721312) (xy 118.451654 -426.748966) (xy 118.44874 -426.77874)
			(xy 118.454573 -426.808082) (xy 118.468655 -426.834477) (xy 118.478808 -426.845476) (xy 118.95328 -427.319948)
			(xy 122.68708 -427.319948)
		)
		(stroke
			(width 0)
			(type solid)
		)
		(fill yes)
		(layer "In2.Cu")
		(net "P3V3_AUX")
	)
	(gr_poly
		(pts
			(xy 251.8283 -51.653186) (xy 251.8283 -46.733206) (xy 250.9266 -45.831506) (xy 250.9266 -39.849298)
			(xy 250.926163 -39.835243) (xy 250.918519 -39.808195) (xy 250.903783 -39.784258) (xy 250.883075 -39.765252)
			(xy 250.857967 -39.752617) (xy 250.830363 -39.747314) (xy 250.80236 -39.749744) (xy 250.776084 -39.759724)
			(xy 250.764548 -39.767764) (xy 250.739765 -39.78534) (xy 250.685797 -39.813238) (xy 250.62809 -39.832235)
			(xy 250.568103 -39.841848) (xy 250.537726 -39.84244) (xy 250.51047 -39.841979) (xy 250.456511 -39.834224)
			(xy 250.404206 -39.818869) (xy 250.354618 -39.796226) (xy 250.308758 -39.766756) (xy 250.267559 -39.73106)
			(xy 250.231859 -39.689863) (xy 250.202386 -39.644005) (xy 250.17974 -39.594419) (xy 250.164381 -39.542114)
			(xy 250.156623 -39.488156) (xy 250.156623 -39.433644) (xy 250.164381 -39.379686) (xy 250.17974 -39.327381)
			(xy 250.202386 -39.277795) (xy 250.231859 -39.231937) (xy 250.267559 -39.19074) (xy 250.308758 -39.155044)
			(xy 250.354618 -39.125574) (xy 250.404206 -39.102931) (xy 250.456511 -39.087576) (xy 250.51047 -39.079821)
			(xy 250.537726 -39.079424) (xy 250.564042 -39.079886) (xy 250.616171 -39.087155) (xy 250.641612 -39.093902)
			(xy 250.670314 -39.10203) (xy 250.72721 -39.04488) (xy 250.641612 -38.959536) (xy 250.641612 -38.856412)
			(xy 250.49988 -38.714426) (xy 250.49988 -37.871146) (xy 250.1138 -37.485066) (xy 243.84508 -37.485066)
			(xy 242.79098 -38.539166) (xy 242.79098 -38.654736) (xy 242.791443 -38.668866) (xy 242.799189 -38.696043)
			(xy 242.814078 -38.720062) (xy 242.834974 -38.739088) (xy 242.86028 -38.751667) (xy 242.888063 -38.756838)
			(xy 242.916199 -38.754206) (xy 242.942541 -38.743972) (xy 242.954048 -38.735762) (xy 242.979077 -38.717487)
			(xy 243.033821 -38.688447) (xy 243.092543 -38.66865) (xy 243.153695 -38.658618) (xy 243.18468 -38.658038)
			(xy 243.213597 -38.658571) (xy 243.270769 -38.667296) (xy 243.325969 -38.684549) (xy 243.377934 -38.709935)
			(xy 243.425472 -38.742872) (xy 243.467495 -38.782607) (xy 243.48567 -38.805104) (xy 243.495567 -38.816909)
			(xy 243.520891 -38.834428) (xy 243.550284 -38.843604) (xy 243.581076 -38.843604) (xy 243.610469 -38.834428)
			(xy 243.635793 -38.816909) (xy 243.64569 -38.805104) (xy 243.663881 -38.782621) (xy 243.705899 -38.742886)
			(xy 243.753434 -38.70995) (xy 243.805396 -38.684566) (xy 243.860595 -38.667318) (xy 243.917765 -38.6586)
			(xy 243.94668 -38.658038) (xy 243.973931 -38.6585) (xy 244.027877 -38.666254) (xy 244.080171 -38.681606)
			(xy 244.129748 -38.704245) (xy 244.175598 -38.733709) (xy 244.216788 -38.769398) (xy 244.252479 -38.810586)
			(xy 244.27736 -38.8493) (xy 247.443244 -38.8493) (xy 247.443746 -38.820382) (xy 247.452476 -38.76321)
			(xy 247.469736 -38.70801) (xy 247.495131 -38.656048) (xy 247.528078 -38.608514) (xy 247.567823 -38.566499)
			(xy 247.59031 -38.54831) (xy 247.602113 -38.538411) (xy 247.619627 -38.513087) (xy 247.6288 -38.483695)
			(xy 247.6288 -38.452905) (xy 247.619627 -38.423513) (xy 247.602113 -38.398189) (xy 247.59031 -38.38829)
			(xy 247.567824 -38.370102) (xy 247.528088 -38.328082) (xy 247.495149 -38.280547) (xy 247.469761 -38.228585)
			(xy 247.452506 -38.173386) (xy 247.443778 -38.116216) (xy 247.443244 -38.0873) (xy 247.44373 -38.060049)
			(xy 247.451486 -38.006101) (xy 247.466841 -37.953806) (xy 247.489483 -37.904229) (xy 247.518949 -37.858379)
			(xy 247.55464 -37.817188) (xy 247.595831 -37.781497) (xy 247.641681 -37.752031) (xy 247.691258 -37.729389)
			(xy 247.743553 -37.714034) (xy 247.797501 -37.706278) (xy 247.852003 -37.706278) (xy 247.905951 -37.714034)
			(xy 247.958246 -37.729389) (xy 248.007823 -37.752031) (xy 248.053673 -37.781497) (xy 248.094864 -37.817188)
			(xy 248.130555 -37.858379) (xy 248.160021 -37.904229) (xy 248.182663 -37.953806) (xy 248.198018 -38.006101)
			(xy 248.205774 -38.060049) (xy 248.20626 -38.0873) (xy 248.205757 -38.116218) (xy 248.197027 -38.17339)
			(xy 248.179767 -38.22859) (xy 248.154372 -38.280552) (xy 248.121425 -38.328085) (xy 248.081681 -38.370101)
			(xy 248.059194 -38.38829) (xy 248.047391 -38.398188) (xy 248.029876 -38.423512) (xy 248.020702 -38.452905)
			(xy 248.020702 -38.483695) (xy 248.029876 -38.513088) (xy 248.047391 -38.538412) (xy 248.059194 -38.54831)
			(xy 248.081681 -38.566497) (xy 248.121416 -38.608517) (xy 248.154355 -38.656053) (xy 248.179743 -38.708015)
			(xy 248.196998 -38.763214) (xy 248.205726 -38.820384) (xy 248.20626 -38.8493) (xy 248.205774 -38.876551)
			(xy 248.198018 -38.930499) (xy 248.182663 -38.982794) (xy 248.160021 -39.032371) (xy 248.130555 -39.078221)
			(xy 248.094864 -39.119412) (xy 248.053673 -39.155103) (xy 248.007823 -39.184569) (xy 247.958246 -39.207211)
			(xy 247.905951 -39.222566) (xy 247.852003 -39.230322) (xy 247.797501 -39.230322) (xy 247.743553 -39.222566)
			(xy 247.691258 -39.207211) (xy 247.641681 -39.184569) (xy 247.595831 -39.155103) (xy 247.55464 -39.119412)
			(xy 247.518949 -39.078221) (xy 247.489483 -39.032371) (xy 247.466841 -38.982794) (xy 247.451486 -38.930499)
			(xy 247.44373 -38.876551) (xy 247.443244 -38.8493) (xy 244.27736 -38.8493) (xy 244.281946 -38.856435)
			(xy 244.304587 -38.90601) (xy 244.319942 -38.958303) (xy 244.327699 -39.01225) (xy 244.327699 -39.06675)
			(xy 244.319942 -39.120697) (xy 244.304587 -39.17299) (xy 244.281946 -39.222565) (xy 244.252479 -39.268414)
			(xy 244.216788 -39.309602) (xy 244.175598 -39.345291) (xy 244.129748 -39.374755) (xy 244.080171 -39.397394)
			(xy 244.027877 -39.412746) (xy 243.973931 -39.4205) (xy 243.94668 -39.421054) (xy 243.917764 -39.420518)
			(xy 243.860596 -39.411788) (xy 243.8054 -39.39453) (xy 243.75344 -39.369141) (xy 243.705907 -39.3362)
			(xy 243.66389 -39.296464) (xy 243.64569 -39.273988) (xy 243.635793 -39.262183) (xy 243.610469 -39.244664)
			(xy 243.581076 -39.235488) (xy 243.550284 -39.235488) (xy 243.520891 -39.244664) (xy 243.495567 -39.262183)
			(xy 243.48567 -39.273988) (xy 243.467481 -39.296474) (xy 243.425465 -39.336217) (xy 243.377931 -39.369162)
			(xy 243.325969 -39.394554) (xy 243.270769 -39.411812) (xy 243.213597 -39.420539) (xy 243.18468 -39.421054)
			(xy 243.153699 -39.420426) (xy 243.092558 -39.410376) (xy 243.033839 -39.390591) (xy 242.979083 -39.36159)
			(xy 242.954048 -39.34333) (xy 242.942516 -39.335147) (xy 242.916184 -39.324873) (xy 242.888044 -39.322213)
			(xy 242.860254 -39.327371) (xy 242.834943 -39.339952) (xy 242.814051 -39.358991) (xy 242.799181 -39.383029)
			(xy 242.791473 -39.410223) (xy 242.79098 -39.424356) (xy 242.79098 -40.723566) (xy 241.30762 -42.206926)
			(xy 237.41888 -42.206926) (xy 236.92866 -42.697146) (xy 236.92866 -42.863262) (xy 249.934728 -42.863262)
			(xy 249.938799 -42.80764) (xy 249.950925 -42.753203) (xy 249.970848 -42.701112) (xy 249.998144 -42.652477)
			(xy 250.03223 -42.608334) (xy 250.072379 -42.569625) (xy 250.117737 -42.537174) (xy 250.167337 -42.511673)
			(xy 250.220121 -42.493666) (xy 250.274964 -42.483536) (xy 250.330698 -42.481499) (xy 250.386135 -42.487599)
			(xy 250.440092 -42.501705) (xy 250.491421 -42.523517) (xy 250.539027 -42.552571) (xy 250.581895 -42.588246)
			(xy 250.619112 -42.629783) (xy 250.649885 -42.676296) (xy 250.673557 -42.726793) (xy 250.689625 -42.7802)
			(xy 250.697745 -42.835376) (xy 250.698254 -42.863262) (xy 250.697745 -42.891148) (xy 250.689625 -42.946324)
			(xy 250.673557 -42.999731) (xy 250.649885 -43.050228) (xy 250.619112 -43.096741) (xy 250.581895 -43.138278)
			(xy 250.539027 -43.173953) (xy 250.491421 -43.203007) (xy 250.440092 -43.224819) (xy 250.386135 -43.238925)
			(xy 250.330698 -43.245025) (xy 250.274964 -43.242988) (xy 250.220121 -43.232858) (xy 250.167337 -43.214851)
			(xy 250.117737 -43.18935) (xy 250.072379 -43.156899) (xy 250.03223 -43.11819) (xy 249.998144 -43.074047)
			(xy 249.970848 -43.025412) (xy 249.950925 -42.973321) (xy 249.938799 -42.918884) (xy 249.934728 -42.863262)
			(xy 236.92866 -42.863262) (xy 236.92866 -45.503846) (xy 237.0328 -45.607986) (xy 242.08486 -45.607986)
			(xy 242.465606 -45.988732) (xy 248.905012 -45.988732) (xy 248.909083 -45.93311) (xy 248.921209 -45.878673)
			(xy 248.941132 -45.826582) (xy 248.968428 -45.777947) (xy 249.002514 -45.733804) (xy 249.042663 -45.695095)
			(xy 249.088021 -45.662644) (xy 249.137621 -45.637143) (xy 249.190405 -45.619136) (xy 249.245248 -45.609006)
			(xy 249.300982 -45.606969) (xy 249.356419 -45.613069) (xy 249.410376 -45.627175) (xy 249.461705 -45.648987)
			(xy 249.509311 -45.678041) (xy 249.552179 -45.713716) (xy 249.589396 -45.755253) (xy 249.620169 -45.801766)
			(xy 249.643841 -45.852263) (xy 249.659909 -45.90567) (xy 249.668029 -45.960846) (xy 249.668538 -45.988732)
			(xy 249.917456 -45.988732) (xy 249.921527 -45.93311) (xy 249.933653 -45.878673) (xy 249.953576 -45.826582)
			(xy 249.980872 -45.777947) (xy 250.014958 -45.733804) (xy 250.055107 -45.695095) (xy 250.100465 -45.662644)
			(xy 250.150065 -45.637143) (xy 250.202849 -45.619136) (xy 250.257692 -45.609006) (xy 250.313426 -45.606969)
			(xy 250.368863 -45.613069) (xy 250.42282 -45.627175) (xy 250.474149 -45.648987) (xy 250.521755 -45.678041)
			(xy 250.564623 -45.713716) (xy 250.60184 -45.755253) (xy 250.632613 -45.801766) (xy 250.656285 -45.852263)
			(xy 250.672353 -45.90567) (xy 250.680473 -45.960846) (xy 250.680982 -45.988732) (xy 250.680473 -46.016618)
			(xy 250.672353 -46.071794) (xy 250.656285 -46.125201) (xy 250.632613 -46.175698) (xy 250.60184 -46.222211)
			(xy 250.564623 -46.263748) (xy 250.521755 -46.299423) (xy 250.474149 -46.328477) (xy 250.42282 -46.350289)
			(xy 250.368863 -46.364395) (xy 250.313426 -46.370495) (xy 250.257692 -46.368458) (xy 250.202849 -46.358328)
			(xy 250.150065 -46.340321) (xy 250.100465 -46.31482) (xy 250.055107 -46.282369) (xy 250.014958 -46.24366)
			(xy 249.980872 -46.199517) (xy 249.953576 -46.150882) (xy 249.933653 -46.098791) (xy 249.921527 -46.044354)
			(xy 249.917456 -45.988732) (xy 249.668538 -45.988732) (xy 249.668029 -46.016618) (xy 249.659909 -46.071794)
			(xy 249.643841 -46.125201) (xy 249.620169 -46.175698) (xy 249.589396 -46.222211) (xy 249.552179 -46.263748)
			(xy 249.509311 -46.299423) (xy 249.461705 -46.328477) (xy 249.410376 -46.350289) (xy 249.356419 -46.364395)
			(xy 249.300982 -46.370495) (xy 249.245248 -46.368458) (xy 249.190405 -46.358328) (xy 249.137621 -46.340321)
			(xy 249.088021 -46.31482) (xy 249.042663 -46.282369) (xy 249.002514 -46.24366) (xy 248.968428 -46.199517)
			(xy 248.941132 -46.150882) (xy 248.921209 -46.098791) (xy 248.909083 -46.044354) (xy 248.905012 -45.988732)
			(xy 242.465606 -45.988732) (xy 242.79098 -46.314106) (xy 242.79098 -46.549564) (xy 242.797076 -46.555406)
			(xy 242.797076 -47.102522) (xy 250.782072 -47.102522) (xy 250.786143 -47.0469) (xy 250.798269 -46.992463)
			(xy 250.818192 -46.940372) (xy 250.845488 -46.891737) (xy 250.879574 -46.847594) (xy 250.919723 -46.808885)
			(xy 250.965081 -46.776434) (xy 251.014681 -46.750933) (xy 251.067465 -46.732926) (xy 251.122308 -46.722796)
			(xy 251.178042 -46.720759) (xy 251.233479 -46.726859) (xy 251.287436 -46.740965) (xy 251.338765 -46.762777)
			(xy 251.386371 -46.791831) (xy 251.429239 -46.827506) (xy 251.466456 -46.869043) (xy 251.497229 -46.915556)
			(xy 251.520901 -46.966053) (xy 251.536969 -47.01946) (xy 251.545089 -47.074636) (xy 251.545598 -47.102522)
			(xy 251.545089 -47.130408) (xy 251.536969 -47.185584) (xy 251.520901 -47.238991) (xy 251.497229 -47.289488)
			(xy 251.466456 -47.336001) (xy 251.429239 -47.377538) (xy 251.386371 -47.413213) (xy 251.338765 -47.442267)
			(xy 251.287436 -47.464079) (xy 251.233479 -47.478185) (xy 251.178042 -47.484285) (xy 251.122308 -47.482248)
			(xy 251.067465 -47.472118) (xy 251.014681 -47.454111) (xy 250.965081 -47.42861) (xy 250.919723 -47.396159)
			(xy 250.879574 -47.35745) (xy 250.845488 -47.313307) (xy 250.818192 -47.264672) (xy 250.798269 -47.212581)
			(xy 250.786143 -47.158144) (xy 250.782072 -47.102522) (xy 242.797076 -47.102522) (xy 242.797076 -49.624742)
			(xy 242.75796 -49.663604) (xy 242.75796 -49.885346) (xy 244.75186 -51.879246) (xy 251.60224 -51.879246)
		)
		(stroke
			(width 0)
			(type solid)
		)
		(fill yes)
		(layer "In2.Cu")
		(net "P12V_E1S_0")
	)
	(gr_poly
		(pts
			(xy 408.615134 -184.622948) (xy 408.62996 -184.622449) (xy 408.658368 -184.613949) (xy 408.683136 -184.597646)
			(xy 408.702177 -184.574915) (xy 408.713884 -184.547672) (xy 408.717272 -184.518214) (xy 408.712054 -184.489025)
			(xy 408.69867 -184.462565) (xy 408.688794 -184.451498) (xy 408.669207 -184.430089) (xy 408.636079 -184.382451)
			(xy 408.610544 -184.330347) (xy 408.593191 -184.274978) (xy 408.584421 -184.21762) (xy 408.583892 -184.188608)
			(xy 408.584355 -184.161355) (xy 408.592111 -184.107403) (xy 408.607466 -184.055104) (xy 408.630108 -184.005523)
			(xy 408.659576 -183.959669) (xy 408.69527 -183.918475) (xy 408.736463 -183.882781) (xy 408.782316 -183.853312)
			(xy 408.831897 -183.830669) (xy 408.884195 -183.815313) (xy 408.938147 -183.807555) (xy 408.9654 -183.8071)
			(xy 408.993166 -183.807601) (xy 409.04811 -183.815656) (xy 409.101304 -183.831596) (xy 409.151624 -183.855084)
			(xy 409.198004 -183.885623) (xy 409.239464 -183.922566) (xy 409.275127 -183.965133) (xy 409.304237 -184.012423)
			(xy 409.315666 -184.037732) (xy 409.321721 -184.050569) (xy 409.339703 -184.072516) (xy 409.363025 -184.088673)
			(xy 409.389891 -184.097796) (xy 409.41823 -184.099181) (xy 409.445857 -184.092721) (xy 409.470643 -184.078915)
			(xy 409.48102 -184.069228) (xy 409.53182 -184.018428) (xy 409.53182 -182.739284) (xy 409.507863 -182.72728)
			(xy 409.463277 -182.697559) (xy 409.42329 -182.66189) (xy 409.388688 -182.620976) (xy 409.360152 -182.575622)
			(xy 409.338244 -182.526721) (xy 409.323395 -182.475235) (xy 409.315898 -182.422178) (xy 409.3159 -182.368594)
			(xy 409.323401 -182.315538) (xy 409.338253 -182.264053) (xy 409.360165 -182.215153) (xy 409.388704 -182.169802)
			(xy 409.423309 -182.12889) (xy 409.463299 -182.093224) (xy 409.507887 -182.063506) (xy 409.53182 -182.051452)
			(xy 409.53182 -176.711864) (xy 409.507864 -176.699857) (xy 409.46328 -176.67013) (xy 409.423294 -176.634457)
			(xy 409.388692 -176.593541) (xy 409.360155 -176.548186) (xy 409.338244 -176.499285) (xy 409.32339 -176.447799)
			(xy 409.315886 -176.394741) (xy 409.315412 -176.367948) (xy 409.315929 -176.339208) (xy 409.324546 -176.282376)
			(xy 409.341591 -176.227481) (xy 409.366679 -176.175765) (xy 409.399242 -176.128397) (xy 409.418536 -176.10709)
			(xy 409.428618 -176.095557) (xy 409.441978 -176.068007) (xy 409.446577 -176.037735) (xy 409.441999 -176.00746)
			(xy 409.428658 -175.979901) (xy 409.418536 -175.968406) (xy 409.399262 -175.94708) (xy 409.36669 -175.89972)
			(xy 409.341591 -175.848008) (xy 409.324533 -175.793117) (xy 409.315903 -175.736288) (xy 409.315412 -175.707548)
			(xy 409.315863 -175.680752) (xy 409.323357 -175.627686) (xy 409.338204 -175.576192) (xy 409.360112 -175.527282)
			(xy 409.38865 -175.48192) (xy 409.423255 -175.440998) (xy 409.463247 -175.405322) (xy 409.507839 -175.375595)
			(xy 409.53182 -175.363632) (xy 409.53182 -174.103284) (xy 409.507863 -174.09128) (xy 409.463277 -174.061559)
			(xy 409.42329 -174.02589) (xy 409.388688 -173.984976) (xy 409.360152 -173.939622) (xy 409.338244 -173.890721)
			(xy 409.323395 -173.839235) (xy 409.315898 -173.786178) (xy 409.3159 -173.732594) (xy 409.323401 -173.679538)
			(xy 409.338253 -173.628053) (xy 409.360165 -173.579153) (xy 409.388704 -173.533802) (xy 409.423309 -173.49289)
			(xy 409.463299 -173.457224) (xy 409.507887 -173.427506) (xy 409.53182 -173.415452) (xy 409.53182 -168.075864)
			(xy 409.507864 -168.063857) (xy 409.46328 -168.03413) (xy 409.423294 -167.998457) (xy 409.388692 -167.957541)
			(xy 409.360155 -167.912186) (xy 409.338244 -167.863285) (xy 409.32339 -167.811799) (xy 409.315886 -167.758741)
			(xy 409.315412 -167.731948) (xy 409.315848 -167.705679) (xy 409.323055 -167.653638) (xy 409.337338 -167.603079)
			(xy 409.358428 -167.55496) (xy 409.385924 -167.510192) (xy 409.40228 -167.489632) (xy 409.407917 -167.482096)
			(xy 409.413822 -167.464245) (xy 409.412913 -167.445465) (xy 409.405309 -167.428269) (xy 409.398978 -167.421306)
			(xy 408.71394 -166.736268) (xy 400.37512 -166.736268) (xy 398.128236 -168.983152) (xy 399.642589 -168.983152)
			(xy 399.646611 -168.897432) (xy 399.658642 -168.812464) (xy 399.678578 -168.728997) (xy 399.706241 -168.647763)
			(xy 399.74139 -168.569477) (xy 399.783716 -168.494826) (xy 399.832845 -168.424467) (xy 399.888348 -168.359017)
			(xy 399.949735 -168.299053) (xy 400.016468 -168.2451) (xy 400.08796 -168.197633) (xy 400.163582 -168.157069)
			(xy 400.242671 -168.123765) (xy 400.324531 -168.098013) (xy 400.408442 -168.08004) (xy 400.493668 -168.070004)
			(xy 400.57946 -168.067992) (xy 400.665062 -168.074023) (xy 400.749724 -168.088043) (xy 400.832701 -168.109929)
			(xy 400.913264 -168.13949) (xy 400.990704 -168.176464) (xy 401.064343 -168.220528) (xy 401.133531 -168.271294)
			(xy 401.197662 -168.328315) (xy 401.256171 -168.391091) (xy 401.308544 -168.459071) (xy 401.354322 -168.531656)
			(xy 401.393102 -168.608208) (xy 401.424543 -168.688056) (xy 401.448369 -168.770497) (xy 401.46437 -168.854807)
			(xy 401.472405 -168.940245) (xy 401.472908 -168.983152) (xy 401.472405 -169.026059) (xy 401.46437 -169.111497)
			(xy 401.448369 -169.195807) (xy 401.424543 -169.278248) (xy 401.393102 -169.358096) (xy 401.354322 -169.434648)
			(xy 401.308544 -169.507233) (xy 401.256171 -169.575213) (xy 401.197662 -169.637989) (xy 401.133531 -169.69501)
			(xy 401.064343 -169.745776) (xy 400.990704 -169.78984) (xy 400.913264 -169.826814) (xy 400.832701 -169.856375)
			(xy 400.749724 -169.878261) (xy 400.665062 -169.892281) (xy 400.57946 -169.898312) (xy 400.493668 -169.8963)
			(xy 400.408442 -169.886264) (xy 400.324531 -169.868291) (xy 400.242671 -169.842539) (xy 400.163582 -169.809235)
			(xy 400.08796 -169.768671) (xy 400.016468 -169.721204) (xy 399.949735 -169.667251) (xy 399.888348 -169.607287)
			(xy 399.832845 -169.541837) (xy 399.783716 -169.471478) (xy 399.74139 -169.396827) (xy 399.706241 -169.318541)
			(xy 399.678578 -169.237307) (xy 399.658642 -169.15384) (xy 399.646611 -169.068872) (xy 399.642589 -168.983152)
			(xy 398.128236 -168.983152) (xy 398.02308 -169.088308) (xy 398.02308 -171.025496) (xy 399.668996 -171.025496)
			(xy 399.668996 -170.9408) (xy 399.677047 -170.856486) (xy 399.693076 -170.77332) (xy 399.716937 -170.692053)
			(xy 399.748416 -170.613423) (xy 399.787227 -170.538142) (xy 399.833017 -170.46689) (xy 399.885373 -170.400314)
			(xy 399.943821 -170.339016) (xy 400.007831 -170.283551) (xy 400.076823 -170.234422) (xy 400.150173 -170.192073)
			(xy 400.227216 -170.156889) (xy 400.307255 -170.129187) (xy 400.389564 -170.109219) (xy 400.473399 -170.097166)
			(xy 400.558 -170.093136) (xy 400.642601 -170.097166) (xy 400.726436 -170.109219) (xy 400.808745 -170.129187)
			(xy 400.888784 -170.156889) (xy 400.965827 -170.192073) (xy 401.039177 -170.234422) (xy 401.108169 -170.283551)
			(xy 401.172179 -170.339016) (xy 401.230627 -170.400314) (xy 401.282983 -170.46689) (xy 401.328773 -170.538142)
			(xy 401.367584 -170.613423) (xy 401.399063 -170.692053) (xy 401.422924 -170.77332) (xy 401.438953 -170.856486)
			(xy 401.447004 -170.9408) (xy 401.447508 -170.983148) (xy 401.447004 -171.025496) (xy 401.438953 -171.10981)
			(xy 401.422924 -171.192976) (xy 401.399063 -171.274243) (xy 401.367584 -171.352873) (xy 401.328773 -171.428154)
			(xy 401.282983 -171.499406) (xy 401.230627 -171.565982) (xy 401.172179 -171.62728) (xy 401.108169 -171.682745)
			(xy 401.039177 -171.731874) (xy 400.965827 -171.774223) (xy 400.888784 -171.809407) (xy 400.808745 -171.837109)
			(xy 400.726436 -171.857077) (xy 400.642601 -171.86913) (xy 400.558 -171.873161) (xy 400.473399 -171.86913)
			(xy 400.389564 -171.857077) (xy 400.307255 -171.837109) (xy 400.227216 -171.809407) (xy 400.150173 -171.774223)
			(xy 400.076823 -171.731874) (xy 400.007831 -171.682745) (xy 399.943821 -171.62728) (xy 399.885373 -171.565982)
			(xy 399.833017 -171.499406) (xy 399.787227 -171.428154) (xy 399.748416 -171.352873) (xy 399.716937 -171.274243)
			(xy 399.693076 -171.192976) (xy 399.677047 -171.10981) (xy 399.668996 -171.025496) (xy 398.02308 -171.025496)
			(xy 398.02308 -175.206152) (xy 399.642589 -175.206152) (xy 399.646611 -175.120432) (xy 399.658642 -175.035464)
			(xy 399.678578 -174.951997) (xy 399.706241 -174.870763) (xy 399.74139 -174.792477) (xy 399.783716 -174.717826)
			(xy 399.832845 -174.647467) (xy 399.888348 -174.582017) (xy 399.949735 -174.522053) (xy 400.016468 -174.4681)
			(xy 400.08796 -174.420633) (xy 400.163582 -174.380069) (xy 400.242671 -174.346765) (xy 400.324531 -174.321013)
			(xy 400.408442 -174.30304) (xy 400.493668 -174.293004) (xy 400.57946 -174.290992) (xy 400.665062 -174.297023)
			(xy 400.749724 -174.311043) (xy 400.832701 -174.332929) (xy 400.913264 -174.36249) (xy 400.990704 -174.399464)
			(xy 401.064343 -174.443528) (xy 401.133531 -174.494294) (xy 401.197662 -174.551315) (xy 401.256171 -174.614091)
			(xy 401.308544 -174.682071) (xy 401.354322 -174.754656) (xy 401.393102 -174.831208) (xy 401.424543 -174.911056)
			(xy 401.448369 -174.993497) (xy 401.46437 -175.077807) (xy 401.472405 -175.163245) (xy 401.472908 -175.206152)
			(xy 401.472405 -175.249059) (xy 401.46437 -175.334497) (xy 401.448369 -175.418807) (xy 401.424543 -175.501248)
			(xy 401.393102 -175.581096) (xy 401.354322 -175.657648) (xy 401.308544 -175.730233) (xy 401.256171 -175.798213)
			(xy 401.197662 -175.860989) (xy 401.133531 -175.91801) (xy 401.064343 -175.968776) (xy 400.990704 -176.01284)
			(xy 400.913264 -176.049814) (xy 400.832701 -176.079375) (xy 400.749724 -176.101261) (xy 400.665062 -176.115281)
			(xy 400.57946 -176.121312) (xy 400.493668 -176.1193) (xy 400.408442 -176.109264) (xy 400.324531 -176.091291)
			(xy 400.242671 -176.065539) (xy 400.163582 -176.032235) (xy 400.08796 -175.991671) (xy 400.016468 -175.944204)
			(xy 399.949735 -175.890251) (xy 399.888348 -175.830287) (xy 399.832845 -175.764837) (xy 399.783716 -175.694478)
			(xy 399.74139 -175.619827) (xy 399.706241 -175.541541) (xy 399.678578 -175.460307) (xy 399.658642 -175.37684)
			(xy 399.646611 -175.291872) (xy 399.642589 -175.206152) (xy 398.02308 -175.206152) (xy 398.02308 -177.248496)
			(xy 399.668996 -177.248496) (xy 399.668996 -177.1638) (xy 399.677047 -177.079486) (xy 399.693076 -176.99632)
			(xy 399.716937 -176.915053) (xy 399.748416 -176.836423) (xy 399.787227 -176.761142) (xy 399.833017 -176.68989)
			(xy 399.885373 -176.623314) (xy 399.943821 -176.562016) (xy 400.007831 -176.506551) (xy 400.076823 -176.457422)
			(xy 400.150173 -176.415073) (xy 400.227216 -176.379889) (xy 400.307255 -176.352187) (xy 400.389564 -176.332219)
			(xy 400.473399 -176.320166) (xy 400.558 -176.316136) (xy 400.642601 -176.320166) (xy 400.726436 -176.332219)
			(xy 400.808745 -176.352187) (xy 400.888784 -176.379889) (xy 400.965827 -176.415073) (xy 401.039177 -176.457422)
			(xy 401.108169 -176.506551) (xy 401.172179 -176.562016) (xy 401.230627 -176.623314) (xy 401.282983 -176.68989)
			(xy 401.328773 -176.761142) (xy 401.367584 -176.836423) (xy 401.399063 -176.915053) (xy 401.422924 -176.99632)
			(xy 401.438953 -177.079486) (xy 401.447004 -177.1638) (xy 401.447508 -177.206148) (xy 401.447004 -177.248496)
			(xy 401.438953 -177.33281) (xy 401.422924 -177.415976) (xy 401.399063 -177.497243) (xy 401.367584 -177.575873)
			(xy 401.328773 -177.651154) (xy 401.282983 -177.722406) (xy 401.230627 -177.788982) (xy 401.172179 -177.85028)
			(xy 401.108169 -177.905745) (xy 401.039177 -177.954874) (xy 400.965827 -177.997223) (xy 400.888784 -178.032407)
			(xy 400.808745 -178.060109) (xy 400.726436 -178.080077) (xy 400.642601 -178.09213) (xy 400.558 -178.096161)
			(xy 400.473399 -178.09213) (xy 400.389564 -178.080077) (xy 400.307255 -178.060109) (xy 400.227216 -178.032407)
			(xy 400.150173 -177.997223) (xy 400.076823 -177.954874) (xy 400.007831 -177.905745) (xy 399.943821 -177.85028)
			(xy 399.885373 -177.788982) (xy 399.833017 -177.722406) (xy 399.787227 -177.651154) (xy 399.748416 -177.575873)
			(xy 399.716937 -177.497243) (xy 399.693076 -177.415976) (xy 399.677047 -177.33281) (xy 399.668996 -177.248496)
			(xy 398.02308 -177.248496) (xy 398.02308 -181.429152) (xy 399.642589 -181.429152) (xy 399.646611 -181.343432)
			(xy 399.658642 -181.258464) (xy 399.678578 -181.174997) (xy 399.706241 -181.093763) (xy 399.74139 -181.015477)
			(xy 399.783716 -180.940826) (xy 399.832845 -180.870467) (xy 399.888348 -180.805017) (xy 399.949735 -180.745053)
			(xy 400.016468 -180.6911) (xy 400.08796 -180.643633) (xy 400.163582 -180.603069) (xy 400.242671 -180.569765)
			(xy 400.324531 -180.544013) (xy 400.408442 -180.52604) (xy 400.493668 -180.516004) (xy 400.57946 -180.513992)
			(xy 400.665062 -180.520023) (xy 400.749724 -180.534043) (xy 400.832701 -180.555929) (xy 400.913264 -180.58549)
			(xy 400.990704 -180.622464) (xy 401.064343 -180.666528) (xy 401.133531 -180.717294) (xy 401.197662 -180.774315)
			(xy 401.256171 -180.837091) (xy 401.308544 -180.905071) (xy 401.354322 -180.977656) (xy 401.393102 -181.054208)
			(xy 401.424543 -181.134056) (xy 401.448369 -181.216497) (xy 401.46437 -181.300807) (xy 401.472405 -181.386245)
			(xy 401.472908 -181.429152) (xy 401.472405 -181.472059) (xy 401.46437 -181.557497) (xy 401.448369 -181.641807)
			(xy 401.424543 -181.724248) (xy 401.393102 -181.804096) (xy 401.354322 -181.880648) (xy 401.308544 -181.953233)
			(xy 401.256171 -182.021213) (xy 401.197662 -182.083989) (xy 401.133531 -182.14101) (xy 401.064343 -182.191776)
			(xy 400.990704 -182.23584) (xy 400.913264 -182.272814) (xy 400.832701 -182.302375) (xy 400.749724 -182.324261)
			(xy 400.665062 -182.338281) (xy 400.57946 -182.344312) (xy 400.493668 -182.3423) (xy 400.408442 -182.332264)
			(xy 400.324531 -182.314291) (xy 400.242671 -182.288539) (xy 400.163582 -182.255235) (xy 400.08796 -182.214671)
			(xy 400.016468 -182.167204) (xy 399.949735 -182.113251) (xy 399.888348 -182.053287) (xy 399.832845 -181.987837)
			(xy 399.783716 -181.917478) (xy 399.74139 -181.842827) (xy 399.706241 -181.764541) (xy 399.678578 -181.683307)
			(xy 399.658642 -181.59984) (xy 399.646611 -181.514872) (xy 399.642589 -181.429152) (xy 398.02308 -181.429152)
			(xy 398.02308 -183.471496) (xy 399.668996 -183.471496) (xy 399.668996 -183.3868) (xy 399.677047 -183.302486)
			(xy 399.693076 -183.21932) (xy 399.716937 -183.138053) (xy 399.748416 -183.059423) (xy 399.787227 -182.984142)
			(xy 399.833017 -182.91289) (xy 399.885373 -182.846314) (xy 399.943821 -182.785016) (xy 400.007831 -182.729551)
			(xy 400.076823 -182.680422) (xy 400.150173 -182.638073) (xy 400.227216 -182.602889) (xy 400.307255 -182.575187)
			(xy 400.389564 -182.555219) (xy 400.473399 -182.543166) (xy 400.558 -182.539136) (xy 400.642601 -182.543166)
			(xy 400.726436 -182.555219) (xy 400.808745 -182.575187) (xy 400.888784 -182.602889) (xy 400.965827 -182.638073)
			(xy 401.039177 -182.680422) (xy 401.108169 -182.729551) (xy 401.172179 -182.785016) (xy 401.230627 -182.846314)
			(xy 401.282983 -182.91289) (xy 401.328773 -182.984142) (xy 401.367584 -183.059423) (xy 401.399063 -183.138053)
			(xy 401.422924 -183.21932) (xy 401.438953 -183.302486) (xy 401.447004 -183.3868) (xy 401.447508 -183.429148)
			(xy 401.447004 -183.471496) (xy 401.438953 -183.55581) (xy 401.422924 -183.638976) (xy 401.399063 -183.720243)
			(xy 401.367584 -183.798873) (xy 401.328773 -183.874154) (xy 401.282983 -183.945406) (xy 401.230627 -184.011982)
			(xy 401.172179 -184.07328) (xy 401.108169 -184.128745) (xy 401.039177 -184.177874) (xy 400.965827 -184.220223)
			(xy 400.888784 -184.255407) (xy 400.808745 -184.283109) (xy 400.726436 -184.303077) (xy 400.642601 -184.31513)
			(xy 400.558 -184.319161) (xy 400.473399 -184.31513) (xy 400.389564 -184.303077) (xy 400.307255 -184.283109)
			(xy 400.227216 -184.255407) (xy 400.150173 -184.220223) (xy 400.076823 -184.177874) (xy 400.007831 -184.128745)
			(xy 399.943821 -184.07328) (xy 399.885373 -184.011982) (xy 399.833017 -183.945406) (xy 399.787227 -183.874154)
			(xy 399.748416 -183.798873) (xy 399.716937 -183.720243) (xy 399.693076 -183.638976) (xy 399.677047 -183.55581)
			(xy 399.668996 -183.471496) (xy 398.02308 -183.471496) (xy 398.02308 -183.761888) (xy 398.88414 -184.622948)
		)
		(stroke
			(width 0)
			(type solid)
		)
		(fill yes)
		(layer "In2.Cu")
		(net "PVCCINFAON_CPU0")
	)
	(gr_poly
		(pts
			(xy 71.86168 -160.251648) (xy 72.40905 -160.251648) (xy 72.41032 -160.210246) (xy 72.410944 -160.18309)
			(xy 72.418934 -160.129362) (xy 72.434465 -160.07731) (xy 72.457221 -160.027988) (xy 72.486743 -159.982392)
			(xy 72.522433 -159.941444) (xy 72.56357 -159.905972) (xy 72.609323 -159.876694) (xy 72.658766 -159.854201)
			(xy 72.710899 -159.838948) (xy 72.764669 -159.831244) (xy 72.818987 -159.831244) (xy 72.872757 -159.838948)
			(xy 72.92489 -159.854201) (xy 72.974333 -159.876694) (xy 73.020086 -159.905972) (xy 73.061223 -159.941444)
			(xy 73.096913 -159.982392) (xy 73.126435 -160.027988) (xy 73.149191 -160.07731) (xy 73.164722 -160.129362)
			(xy 73.172712 -160.18309) (xy 73.173336 -160.210246) (xy 73.174606 -160.251648) (xy 73.64476 -160.251648)
			(xy 75.95108 -157.945328) (xy 75.95108 -156.224732) (xy 75.932354 -156.204076) (xy 75.899656 -156.158914)
			(xy 75.872862 -156.110019) (xy 75.852391 -156.058158) (xy 75.838565 -156.004144) (xy 75.831601 -155.948826)
			(xy 75.831192 -155.920948) (xy 75.831192 -149.80539) (xy 75.830717 -149.791773) (xy 75.82344 -149.765525)
			(xy 75.809488 -149.742133) (xy 75.78985 -149.723258) (xy 75.765924 -149.710243) (xy 75.739409 -149.704011)
			(xy 75.725782 -149.704044) (xy 75.692 -149.705568) (xy 75.664752 -149.705082) (xy 75.61081 -149.697326)
			(xy 75.55852 -149.681973) (xy 75.508948 -149.659334) (xy 75.463103 -149.629871) (xy 75.421917 -149.594183)
			(xy 75.386229 -149.552997) (xy 75.356766 -149.507152) (xy 75.334127 -149.45758) (xy 75.318774 -149.40529)
			(xy 75.311018 -149.351348) (xy 75.311018 -149.296852) (xy 75.318774 -149.24291) (xy 75.334127 -149.19062)
			(xy 75.356766 -149.141048) (xy 75.386229 -149.095203) (xy 75.421917 -149.054017) (xy 75.463103 -149.018329)
			(xy 75.508948 -148.988866) (xy 75.55852 -148.966227) (xy 75.61081 -148.950874) (xy 75.664752 -148.943118)
			(xy 75.692 -148.942552) (xy 75.725782 -148.944076) (xy 75.739412 -148.944152) (xy 75.765939 -148.937934)
			(xy 75.789875 -148.924917) (xy 75.809512 -148.906029) (xy 75.823449 -148.882618) (xy 75.830694 -148.856353)
			(xy 75.831192 -148.84273) (xy 75.831192 -146.681698) (xy 75.420728 -146.27098) (xy 75.397182 -146.246542)
			(xy 75.357021 -146.191843) (xy 75.325619 -146.131686) (xy 75.314048 -146.099784) (xy 75.302945 -146.065013)
			(xy 75.290943 -145.99302) (xy 75.290172 -145.956528) (xy 75.290172 -145.17751) (xy 75.154282 -145.17751)
			(xy 75.139804 -145.190718) (xy 75.109697 -145.217412) (xy 75.044813 -145.265004) (xy 74.97528 -145.305503)
			(xy 74.901872 -145.338459) (xy 74.825402 -145.363507) (xy 74.746722 -145.380367) (xy 74.666703 -145.388853)
			(xy 74.62647 -145.389346) (xy 74.586536 -145.388822) (xy 74.507107 -145.380471) (xy 74.428985 -145.363863)
			(xy 74.353027 -145.339181) (xy 74.280065 -145.306695) (xy 74.210899 -145.266761) (xy 74.146285 -145.219816)
			(xy 74.086932 -145.166374) (xy 74.033489 -145.107022) (xy 73.986544 -145.042408) (xy 73.946609 -144.973242)
			(xy 73.914122 -144.90028) (xy 73.889439 -144.824323) (xy 73.872831 -144.746201) (xy 73.864479 -144.666772)
			(xy 73.863962 -144.626838) (xy 73.864431 -144.588575) (xy 73.872097 -144.512433) (xy 73.887355 -144.437442)
			(xy 73.910052 -144.364359) (xy 73.939959 -144.293918) (xy 73.976775 -144.226828) (xy 73.998074 -144.195038)
			(xy 73.976787 -144.16324) (xy 73.939974 -144.096151) (xy 73.910069 -144.025711) (xy 73.887371 -143.952629)
			(xy 73.87211 -143.877641) (xy 73.864439 -143.801501) (xy 73.863962 -143.763238) (xy 73.864442 -143.724744)
			(xy 73.872197 -143.648148) (xy 73.887632 -143.572724) (xy 73.91059 -143.499239) (xy 73.940837 -143.428442)
			(xy 73.978065 -143.361054) (xy 74.021895 -143.297761) (xy 74.071881 -143.239208) (xy 74.127514 -143.18599)
			(xy 74.188226 -143.13865) (xy 74.253401 -143.09767) (xy 74.322373 -143.063467) (xy 74.358246 -143.049498)
			(xy 74.371628 -143.043893) (xy 74.394781 -143.026433) (xy 74.412097 -143.003172) (xy 74.422182 -142.975984)
			(xy 74.424223 -142.947057) (xy 74.418056 -142.918722) (xy 74.404178 -142.893259) (xy 74.394314 -142.88262)
			(xy 73.589642 -142.077948) (xy 63.3222 -142.077948) (xy 63.123572 -142.276576) (xy 63.123572 -144.665192)
			(xy 71.87641 -144.665192) (xy 71.880481 -144.60957) (xy 71.892607 -144.555133) (xy 71.91253 -144.503042)
			(xy 71.939826 -144.454407) (xy 71.973912 -144.410264) (xy 72.014061 -144.371555) (xy 72.059419 -144.339104)
			(xy 72.109019 -144.313603) (xy 72.161803 -144.295596) (xy 72.216646 -144.285466) (xy 72.27238 -144.283429)
			(xy 72.327817 -144.289529) (xy 72.381774 -144.303635) (xy 72.433103 -144.325447) (xy 72.480709 -144.354501)
			(xy 72.523577 -144.390176) (xy 72.560794 -144.431713) (xy 72.591567 -144.478226) (xy 72.615239 -144.528723)
			(xy 72.631307 -144.58213) (xy 72.639427 -144.637306) (xy 72.639936 -144.665192) (xy 72.639427 -144.693078)
			(xy 72.631307 -144.748254) (xy 72.615239 -144.801661) (xy 72.591567 -144.852158) (xy 72.560794 -144.898671)
			(xy 72.523577 -144.940208) (xy 72.480709 -144.975883) (xy 72.433103 -145.004937) (xy 72.381774 -145.026749)
			(xy 72.327817 -145.040855) (xy 72.27238 -145.046955) (xy 72.216646 -145.044918) (xy 72.161803 -145.034788)
			(xy 72.109019 -145.016781) (xy 72.059419 -144.99128) (xy 72.014061 -144.958829) (xy 71.973912 -144.92012)
			(xy 71.939826 -144.875977) (xy 71.91253 -144.827342) (xy 71.892607 -144.775251) (xy 71.880481 -144.720814)
			(xy 71.87641 -144.665192) (xy 63.123572 -144.665192) (xy 63.123572 -146.228308) (xy 69.007995 -146.228308)
			(xy 69.012017 -146.142588) (xy 69.024048 -146.05762) (xy 69.043984 -145.974153) (xy 69.071647 -145.892919)
			(xy 69.106796 -145.814633) (xy 69.149122 -145.739982) (xy 69.198251 -145.669623) (xy 69.253754 -145.604173)
			(xy 69.315141 -145.544209) (xy 69.381874 -145.490256) (xy 69.453366 -145.442789) (xy 69.528988 -145.402225)
			(xy 69.608077 -145.368921) (xy 69.689937 -145.343169) (xy 69.773848 -145.325196) (xy 69.859074 -145.31516)
			(xy 69.944866 -145.313148) (xy 70.030468 -145.319179) (xy 70.11513 -145.333199) (xy 70.198107 -145.355085)
			(xy 70.27867 -145.384646) (xy 70.35611 -145.42162) (xy 70.429749 -145.465684) (xy 70.498937 -145.51645)
			(xy 70.563068 -145.573471) (xy 70.621577 -145.636247) (xy 70.67395 -145.704227) (xy 70.719728 -145.776812)
			(xy 70.758508 -145.853364) (xy 70.789949 -145.933212) (xy 70.813775 -146.015653) (xy 70.829776 -146.099963)
			(xy 70.837811 -146.185401) (xy 70.838314 -146.228308) (xy 70.837811 -146.271215) (xy 70.829776 -146.356653)
			(xy 70.813775 -146.440963) (xy 70.789949 -146.523404) (xy 70.758508 -146.603252) (xy 70.719728 -146.679804)
			(xy 70.67395 -146.752389) (xy 70.621577 -146.820369) (xy 70.563068 -146.883145) (xy 70.498937 -146.940166)
			(xy 70.429749 -146.990932) (xy 70.35611 -147.034996) (xy 70.27867 -147.07197) (xy 70.198107 -147.101531)
			(xy 70.11513 -147.123417) (xy 70.030468 -147.137437) (xy 69.944866 -147.143468) (xy 69.859074 -147.141456)
			(xy 69.773848 -147.13142) (xy 69.689937 -147.113447) (xy 69.608077 -147.087695) (xy 69.528988 -147.054391)
			(xy 69.453366 -147.013827) (xy 69.381874 -146.96636) (xy 69.315141 -146.912407) (xy 69.253754 -146.852443)
			(xy 69.198251 -146.786993) (xy 69.149122 -146.716634) (xy 69.106796 -146.641983) (xy 69.071647 -146.563697)
			(xy 69.043984 -146.482463) (xy 69.024048 -146.398996) (xy 69.012017 -146.314028) (xy 69.007995 -146.228308)
			(xy 63.123572 -146.228308) (xy 63.123572 -148.270652) (xy 69.034402 -148.270652) (xy 69.034402 -148.185956)
			(xy 69.042453 -148.101642) (xy 69.058482 -148.018476) (xy 69.082343 -147.937209) (xy 69.113822 -147.858579)
			(xy 69.152633 -147.783298) (xy 69.198423 -147.712046) (xy 69.250779 -147.64547) (xy 69.309227 -147.584172)
			(xy 69.373237 -147.528707) (xy 69.442229 -147.479578) (xy 69.515579 -147.437229) (xy 69.592622 -147.402045)
			(xy 69.672661 -147.374343) (xy 69.75497 -147.354375) (xy 69.838805 -147.342322) (xy 69.923406 -147.338292)
			(xy 70.008007 -147.342322) (xy 70.091842 -147.354375) (xy 70.174151 -147.374343) (xy 70.25419 -147.402045)
			(xy 70.331233 -147.437229) (xy 70.404583 -147.479578) (xy 70.473575 -147.528707) (xy 70.537585 -147.584172)
			(xy 70.596033 -147.64547) (xy 70.648389 -147.712046) (xy 70.694179 -147.783298) (xy 70.73299 -147.858579)
			(xy 70.764469 -147.937209) (xy 70.78833 -148.018476) (xy 70.804359 -148.101642) (xy 70.81241 -148.185956)
			(xy 70.812914 -148.228304) (xy 70.81241 -148.270652) (xy 70.804359 -148.354966) (xy 70.78833 -148.438132)
			(xy 70.764469 -148.519399) (xy 70.73299 -148.598029) (xy 70.694179 -148.67331) (xy 70.648389 -148.744562)
			(xy 70.596033 -148.811138) (xy 70.537585 -148.872436) (xy 70.473575 -148.927901) (xy 70.404583 -148.97703)
			(xy 70.331233 -149.019379) (xy 70.25419 -149.054563) (xy 70.174151 -149.082265) (xy 70.091842 -149.102233)
			(xy 70.008007 -149.114286) (xy 69.923406 -149.118317) (xy 69.838805 -149.114286) (xy 69.75497 -149.102233)
			(xy 69.672661 -149.082265) (xy 69.592622 -149.054563) (xy 69.515579 -149.019379) (xy 69.442229 -148.97703)
			(xy 69.373237 -148.927901) (xy 69.309227 -148.872436) (xy 69.250779 -148.811138) (xy 69.198423 -148.744562)
			(xy 69.152633 -148.67331) (xy 69.113822 -148.598029) (xy 69.082343 -148.519399) (xy 69.058482 -148.438132)
			(xy 69.042453 -148.354966) (xy 69.034402 -148.270652) (xy 63.123572 -148.270652) (xy 63.123572 -152.364694)
			(xy 69.007995 -152.364694) (xy 69.012017 -152.278974) (xy 69.024048 -152.194006) (xy 69.043984 -152.110539)
			(xy 69.071647 -152.029305) (xy 69.106796 -151.951019) (xy 69.149122 -151.876368) (xy 69.198251 -151.806009)
			(xy 69.253754 -151.740559) (xy 69.315141 -151.680595) (xy 69.381874 -151.626642) (xy 69.453366 -151.579175)
			(xy 69.528988 -151.538611) (xy 69.608077 -151.505307) (xy 69.689937 -151.479555) (xy 69.773848 -151.461582)
			(xy 69.859074 -151.451546) (xy 69.944866 -151.449534) (xy 70.030468 -151.455565) (xy 70.11513 -151.469585)
			(xy 70.198107 -151.491471) (xy 70.27867 -151.521032) (xy 70.35611 -151.558006) (xy 70.429749 -151.60207)
			(xy 70.498937 -151.652836) (xy 70.563068 -151.709857) (xy 70.621577 -151.772633) (xy 70.67395 -151.840613)
			(xy 70.719728 -151.913198) (xy 70.758508 -151.98975) (xy 70.789949 -152.069598) (xy 70.813775 -152.152039)
			(xy 70.829776 -152.236349) (xy 70.837811 -152.321787) (xy 70.838314 -152.364694) (xy 70.837811 -152.407601)
			(xy 70.829776 -152.493039) (xy 70.813775 -152.577349) (xy 70.789949 -152.65979) (xy 70.758508 -152.739638)
			(xy 70.719728 -152.81619) (xy 70.67395 -152.888775) (xy 70.621577 -152.956755) (xy 70.563068 -153.019531)
			(xy 70.498937 -153.076552) (xy 70.429749 -153.127318) (xy 70.35611 -153.171382) (xy 70.27867 -153.208356)
			(xy 70.198107 -153.237917) (xy 70.11513 -153.259803) (xy 70.030468 -153.273823) (xy 69.944866 -153.279854)
			(xy 69.859074 -153.277842) (xy 69.773848 -153.267806) (xy 69.689937 -153.249833) (xy 69.608077 -153.224081)
			(xy 69.528988 -153.190777) (xy 69.453366 -153.150213) (xy 69.381874 -153.102746) (xy 69.315141 -153.048793)
			(xy 69.253754 -152.988829) (xy 69.198251 -152.923379) (xy 69.149122 -152.85302) (xy 69.106796 -152.778369)
			(xy 69.071647 -152.700083) (xy 69.043984 -152.618849) (xy 69.024048 -152.535382) (xy 69.012017 -152.450414)
			(xy 69.007995 -152.364694) (xy 63.123572 -152.364694) (xy 63.123572 -154.407038) (xy 69.034402 -154.407038)
			(xy 69.034402 -154.322342) (xy 69.042453 -154.238028) (xy 69.058482 -154.154862) (xy 69.082343 -154.073595)
			(xy 69.113822 -153.994965) (xy 69.152633 -153.919684) (xy 69.198423 -153.848432) (xy 69.250779 -153.781856)
			(xy 69.309227 -153.720558) (xy 69.373237 -153.665093) (xy 69.442229 -153.615964) (xy 69.515579 -153.573615)
			(xy 69.592622 -153.538431) (xy 69.672661 -153.510729) (xy 69.75497 -153.490761) (xy 69.838805 -153.478708)
			(xy 69.923406 -153.474678) (xy 70.008007 -153.478708) (xy 70.091842 -153.490761) (xy 70.174151 -153.510729)
			(xy 70.25419 -153.538431) (xy 70.331233 -153.573615) (xy 70.404583 -153.615964) (xy 70.473575 -153.665093)
			(xy 70.537585 -153.720558) (xy 70.596033 -153.781856) (xy 70.648389 -153.848432) (xy 70.694179 -153.919684)
			(xy 70.73299 -153.994965) (xy 70.764469 -154.073595) (xy 70.78833 -154.154862) (xy 70.804359 -154.238028)
			(xy 70.81241 -154.322342) (xy 70.812914 -154.36469) (xy 70.81241 -154.407038) (xy 70.804359 -154.491352)
			(xy 70.78833 -154.574518) (xy 70.764469 -154.655785) (xy 70.73299 -154.734415) (xy 70.694179 -154.809696)
			(xy 70.648389 -154.880948) (xy 70.596033 -154.947524) (xy 70.537585 -155.008822) (xy 70.473575 -155.064287)
			(xy 70.404583 -155.113416) (xy 70.331233 -155.155765) (xy 70.25419 -155.190949) (xy 70.174151 -155.218651)
			(xy 70.091842 -155.238619) (xy 70.008007 -155.250672) (xy 69.923406 -155.254703) (xy 69.838805 -155.250672)
			(xy 69.75497 -155.238619) (xy 69.672661 -155.218651) (xy 69.592622 -155.190949) (xy 69.515579 -155.155765)
			(xy 69.442229 -155.113416) (xy 69.373237 -155.064287) (xy 69.309227 -155.008822) (xy 69.250779 -154.947524)
			(xy 69.198423 -154.880948) (xy 69.152633 -154.809696) (xy 69.113822 -154.734415) (xy 69.082343 -154.655785)
			(xy 69.058482 -154.574518) (xy 69.042453 -154.491352) (xy 69.034402 -154.407038) (xy 63.123572 -154.407038)
			(xy 63.123572 -158.49981) (xy 69.007995 -158.49981) (xy 69.012017 -158.41409) (xy 69.024048 -158.329122)
			(xy 69.043984 -158.245655) (xy 69.071647 -158.164421) (xy 69.106796 -158.086135) (xy 69.149122 -158.011484)
			(xy 69.198251 -157.941125) (xy 69.253754 -157.875675) (xy 69.315141 -157.815711) (xy 69.381874 -157.761758)
			(xy 69.453366 -157.714291) (xy 69.528988 -157.673727) (xy 69.608077 -157.640423) (xy 69.689937 -157.614671)
			(xy 69.773848 -157.596698) (xy 69.859074 -157.586662) (xy 69.944866 -157.58465) (xy 70.030468 -157.590681)
			(xy 70.11513 -157.604701) (xy 70.198107 -157.626587) (xy 70.27867 -157.656148) (xy 70.35611 -157.693122)
			(xy 70.429749 -157.737186) (xy 70.498937 -157.787952) (xy 70.563068 -157.844973) (xy 70.621577 -157.907749)
			(xy 70.67395 -157.975729) (xy 70.719728 -158.048314) (xy 70.758508 -158.124866) (xy 70.789949 -158.204714)
			(xy 70.813775 -158.287155) (xy 70.829776 -158.371465) (xy 70.837811 -158.456903) (xy 70.838314 -158.49981)
			(xy 70.837811 -158.542717) (xy 70.829776 -158.628155) (xy 70.813775 -158.712465) (xy 70.789949 -158.794906)
			(xy 70.758508 -158.874754) (xy 70.719728 -158.951306) (xy 70.67395 -159.023891) (xy 70.621577 -159.091871)
			(xy 70.563068 -159.154647) (xy 70.498937 -159.211668) (xy 70.429749 -159.262434) (xy 70.35611 -159.306498)
			(xy 70.27867 -159.343472) (xy 70.198107 -159.373033) (xy 70.11513 -159.394919) (xy 70.030468 -159.408939)
			(xy 69.944866 -159.41497) (xy 69.859074 -159.412958) (xy 69.773848 -159.402922) (xy 69.689937 -159.384949)
			(xy 69.608077 -159.359197) (xy 69.528988 -159.325893) (xy 69.453366 -159.285329) (xy 69.381874 -159.237862)
			(xy 69.315141 -159.183909) (xy 69.253754 -159.123945) (xy 69.198251 -159.058495) (xy 69.149122 -158.988136)
			(xy 69.106796 -158.913485) (xy 69.071647 -158.835199) (xy 69.043984 -158.753965) (xy 69.024048 -158.670498)
			(xy 69.012017 -158.58553) (xy 69.007995 -158.49981) (xy 63.123572 -158.49981) (xy 63.123572 -160.542154)
			(xy 69.034402 -160.542154) (xy 69.034402 -160.457458) (xy 69.042453 -160.373144) (xy 69.058482 -160.289978)
			(xy 69.082343 -160.208711) (xy 69.113822 -160.130081) (xy 69.152633 -160.0548) (xy 69.198423 -159.983548)
			(xy 69.250779 -159.916972) (xy 69.309227 -159.855674) (xy 69.373237 -159.800209) (xy 69.442229 -159.75108)
			(xy 69.515579 -159.708731) (xy 69.592622 -159.673547) (xy 69.672661 -159.645845) (xy 69.75497 -159.625877)
			(xy 69.838805 -159.613824) (xy 69.923406 -159.609794) (xy 70.008007 -159.613824) (xy 70.091842 -159.625877)
			(xy 70.174151 -159.645845) (xy 70.25419 -159.673547) (xy 70.331233 -159.708731) (xy 70.404583 -159.75108)
			(xy 70.473575 -159.800209) (xy 70.537585 -159.855674) (xy 70.596033 -159.916972) (xy 70.648389 -159.983548)
			(xy 70.694179 -160.0548) (xy 70.73299 -160.130081) (xy 70.764469 -160.208711) (xy 70.78833 -160.289978)
			(xy 70.804359 -160.373144) (xy 70.81241 -160.457458) (xy 70.812914 -160.499806) (xy 70.81241 -160.542154)
			(xy 70.804359 -160.626468) (xy 70.78833 -160.709634) (xy 70.764469 -160.790901) (xy 70.73299 -160.869531)
			(xy 70.694179 -160.944812) (xy 70.648389 -161.016064) (xy 70.596033 -161.08264) (xy 70.537585 -161.143938)
			(xy 70.473575 -161.199403) (xy 70.404583 -161.248532) (xy 70.331233 -161.290881) (xy 70.25419 -161.326065)
			(xy 70.174151 -161.353767) (xy 70.091842 -161.373735) (xy 70.008007 -161.385788) (xy 69.923406 -161.389819)
			(xy 69.838805 -161.385788) (xy 69.75497 -161.373735) (xy 69.672661 -161.353767) (xy 69.592622 -161.326065)
			(xy 69.515579 -161.290881) (xy 69.442229 -161.248532) (xy 69.373237 -161.199403) (xy 69.309227 -161.143938)
			(xy 69.250779 -161.08264) (xy 69.198423 -161.016064) (xy 69.152633 -160.944812) (xy 69.113822 -160.869531)
			(xy 69.082343 -160.790901) (xy 69.058482 -160.709634) (xy 69.042453 -160.626468) (xy 69.034402 -160.542154)
			(xy 63.123572 -160.542154) (xy 63.123572 -160.549844) (xy 63.284608 -160.71088) (xy 68.447412 -160.71088)
			(xy 69.34962 -161.613088) (xy 70.50024 -161.613088)
		)
		(stroke
			(width 0)
			(type solid)
		)
		(fill yes)
		(layer "In2.Cu")
		(net "PVCCINFAON_CPU1")
	)
	(gr_poly
		(pts
			(xy 192.926208 -28.86202) (xy 192.936222 -28.851327) (xy 192.950204 -28.825598) (xy 192.95631 -28.796959)
			(xy 192.954039 -28.767764) (xy 192.943577 -28.740413) (xy 192.925785 -28.717155) (xy 192.91427 -28.708096)
			(xy 192.89044 -28.689979) (xy 192.848193 -28.647574) (xy 192.813081 -28.599096) (xy 192.785964 -28.545733)
			(xy 192.767506 -28.488793) (xy 192.758159 -28.429669) (xy 192.757552 -28.39974) (xy 192.758083 -28.370836)
			(xy 192.766799 -28.313688) (xy 192.78404 -28.258511) (xy 192.809408 -28.206566) (xy 192.842325 -28.159045)
			(xy 192.882035 -28.117034) (xy 192.927629 -28.081496) (xy 192.978064 -28.053245) (xy 193.004948 -28.042616)
			(xy 193.037968 -28.03017) (xy 193.037968 -24.11603) (xy 192.668398 -23.74646) (xy 192.632584 -23.78202)
			(xy 192.611016 -23.802536) (xy 192.5627 -23.8373) (xy 192.509572 -23.864142) (xy 192.452922 -23.882409)
			(xy 192.394122 -23.89166) (xy 192.36436 -23.892256) (xy 192.337109 -23.891768) (xy 192.283163 -23.884007)
			(xy 192.230871 -23.868649) (xy 192.181295 -23.846006) (xy 192.135447 -23.816539) (xy 192.094257 -23.780848)
			(xy 192.058566 -23.73966) (xy 192.029098 -23.693812) (xy 192.006454 -23.644237) (xy 191.991095 -23.591944)
			(xy 191.983333 -23.537999) (xy 191.982852 -23.510748) (xy 191.983391 -23.481346) (xy 191.992406 -23.423237)
			(xy 192.010229 -23.3672) (xy 192.036439 -23.31456) (xy 192.070414 -23.266565) (xy 192.111352 -23.224351)
			(xy 192.13449 -23.206202) (xy 192.115482 -23.181068) (xy 192.08248 -23.127381) (xy 192.055572 -23.070395)
			(xy 192.035086 -23.010799) (xy 192.021267 -22.949314) (xy 192.014284 -22.886683) (xy 192.01384 -22.855174)
			(xy 192.01384 -20.371308) (xy 191.99098 -20.348448) (xy 189.29858 -20.348448) (xy 188.85408 -19.903948)
			(xy 188.331856 -20.426426) (xy 188.322638 -20.436208) (xy 188.309236 -20.459497) (xy 188.302378 -20.485476)
			(xy 188.302541 -20.512345) (xy 188.309711 -20.53824) (xy 188.323394 -20.561365) (xy 188.342638 -20.580117)
			(xy 188.354208 -20.586954) (xy 188.379192 -20.60154) (xy 188.42484 -20.637078) (xy 188.464599 -20.6791)
			(xy 188.497556 -20.726644) (xy 188.522958 -20.77862) (xy 188.54022 -20.833835) (xy 188.548948 -20.891023)
			(xy 188.549534 -20.919948) (xy 188.549045 -20.947198) (xy 188.541283 -21.001142) (xy 188.525924 -21.053432)
			(xy 188.503281 -21.103005) (xy 188.473813 -21.148851) (xy 188.438122 -21.190038) (xy 188.396934 -21.225727)
			(xy 188.351086 -21.255191) (xy 188.301511 -21.277832) (xy 188.24922 -21.293188) (xy 188.195276 -21.300947)
			(xy 188.168026 -21.301456) (xy 188.1389 -21.300908) (xy 188.081323 -21.292057) (xy 188.025762 -21.274558)
			(xy 187.973505 -21.248816) (xy 187.925769 -21.21543) (xy 187.883662 -21.175176) (xy 187.848164 -21.12899)
			(xy 187.820098 -21.077944) (xy 187.809632 -21.050758) (xy 187.805822 -21.04009) (xy 187.76188 -20.996402)
			(xy 187.686696 -21.071332) (xy 187.686696 -22.661118) (xy 187.687098 -22.674468) (xy 187.694026 -22.700253)
			(xy 187.707403 -22.72336) (xy 187.726314 -22.742207) (xy 187.749466 -22.755506) (xy 187.775275 -22.762347)
			(xy 187.801974 -22.762261) (xy 187.814966 -22.759162) (xy 187.839511 -22.752899) (xy 187.889715 -22.746141)
			(xy 187.915042 -22.7457) (xy 187.942291 -22.746189) (xy 187.996233 -22.75395) (xy 188.048521 -22.769308)
			(xy 188.098092 -22.791951) (xy 188.143936 -22.821418) (xy 188.185121 -22.857109) (xy 188.220807 -22.898297)
			(xy 188.250269 -22.944145) (xy 188.272906 -22.993718) (xy 188.288259 -23.046008) (xy 188.296014 -23.099951)
			(xy 188.296014 -23.154449) (xy 188.288259 -23.208392) (xy 188.272906 -23.260682) (xy 188.250269 -23.310255)
			(xy 188.220807 -23.356103) (xy 188.185121 -23.397291) (xy 188.143936 -23.432982) (xy 188.098092 -23.462449)
			(xy 188.048521 -23.485092) (xy 187.996233 -23.50045) (xy 187.942291 -23.508211) (xy 187.915042 -23.508716)
			(xy 187.889714 -23.508285) (xy 187.839509 -23.501527) (xy 187.814966 -23.495254) (xy 187.801977 -23.492135)
			(xy 187.775274 -23.492049) (xy 187.749462 -23.498891) (xy 187.726307 -23.512193) (xy 187.707395 -23.531045)
			(xy 187.694018 -23.554156) (xy 187.687092 -23.579946) (xy 187.686696 -23.593298) (xy 187.686696 -23.593552)
			(xy 190.126874 -23.593552) (xy 190.127385 -23.565979) (xy 190.135329 -23.511409) (xy 190.151046 -23.45855)
			(xy 190.174208 -23.408504) (xy 190.204332 -23.362313) (xy 190.240791 -23.32094) (xy 190.261494 -23.302722)
			(xy 190.272439 -23.292872) (xy 190.288511 -23.268208) (xy 190.296889 -23.239988) (xy 190.29688 -23.21055)
			(xy 190.288484 -23.182335) (xy 190.272398 -23.157681) (xy 190.261494 -23.147782) (xy 190.24077 -23.129585)
			(xy 190.204301 -23.088213) (xy 190.17417 -23.04202) (xy 190.151007 -22.99197) (xy 190.135293 -22.939104)
			(xy 190.127357 -22.884528) (xy 190.126874 -22.856952) (xy 190.12736 -22.829701) (xy 190.135116 -22.775753)
			(xy 190.150471 -22.723458) (xy 190.173113 -22.673881) (xy 190.202579 -22.628031) (xy 190.23827 -22.58684)
			(xy 190.279461 -22.551149) (xy 190.325311 -22.521683) (xy 190.374888 -22.499041) (xy 190.427183 -22.483686)
			(xy 190.481131 -22.47593) (xy 190.535633 -22.47593) (xy 190.589581 -22.483686) (xy 190.641876 -22.499041)
			(xy 190.691453 -22.521683) (xy 190.737303 -22.551149) (xy 190.778494 -22.58684) (xy 190.814185 -22.628031)
			(xy 190.843651 -22.673881) (xy 190.866293 -22.723458) (xy 190.881648 -22.775753) (xy 190.889404 -22.829701)
			(xy 190.88989 -22.856952) (xy 190.889395 -22.884526) (xy 190.881449 -22.939097) (xy 190.86573 -22.991957)
			(xy 190.842565 -23.042003) (xy 190.812438 -23.088193) (xy 190.775975 -23.129565) (xy 190.75527 -23.147782)
			(xy 190.744424 -23.157731) (xy 190.728355 -23.182368) (xy 190.719969 -23.210562) (xy 190.71996 -23.239976)
			(xy 190.728329 -23.268175) (xy 190.744383 -23.292822) (xy 190.75527 -23.302722) (xy 190.775989 -23.320925)
			(xy 190.81246 -23.362295) (xy 190.842592 -23.408486) (xy 190.865757 -23.458536) (xy 190.881471 -23.5114)
			(xy 190.889407 -23.565977) (xy 190.88989 -23.593552) (xy 190.889404 -23.620803) (xy 190.881648 -23.674751)
			(xy 190.866293 -23.727046) (xy 190.843651 -23.776623) (xy 190.814185 -23.822473) (xy 190.778494 -23.863664)
			(xy 190.737303 -23.899355) (xy 190.691453 -23.928821) (xy 190.641876 -23.951463) (xy 190.589581 -23.966818)
			(xy 190.535633 -23.974574) (xy 190.481131 -23.974574) (xy 190.427183 -23.966818) (xy 190.374888 -23.951463)
			(xy 190.325311 -23.928821) (xy 190.279461 -23.899355) (xy 190.23827 -23.863664) (xy 190.202579 -23.822473)
			(xy 190.173113 -23.776623) (xy 190.150471 -23.727046) (xy 190.135116 -23.674751) (xy 190.12736 -23.620803)
			(xy 190.126874 -23.593552) (xy 187.686696 -23.593552) (xy 187.686696 -23.623016) (xy 188.100208 -24.036528)
			(xy 188.856872 -24.036528) (xy 188.860943 -23.980906) (xy 188.873069 -23.926469) (xy 188.892992 -23.874378)
			(xy 188.920288 -23.825743) (xy 188.954374 -23.7816) (xy 188.994523 -23.742891) (xy 189.039881 -23.71044)
			(xy 189.089481 -23.684939) (xy 189.142265 -23.666932) (xy 189.197108 -23.656802) (xy 189.252842 -23.654765)
			(xy 189.308279 -23.660865) (xy 189.362236 -23.674971) (xy 189.413565 -23.696783) (xy 189.461171 -23.725837)
			(xy 189.504039 -23.761512) (xy 189.541256 -23.803049) (xy 189.572029 -23.849562) (xy 189.595701 -23.900059)
			(xy 189.611769 -23.953466) (xy 189.619889 -24.008642) (xy 189.620398 -24.036528) (xy 189.619889 -24.064414)
			(xy 189.611769 -24.11959) (xy 189.595701 -24.172997) (xy 189.572029 -24.223494) (xy 189.541256 -24.270007)
			(xy 189.504039 -24.311544) (xy 189.461171 -24.347219) (xy 189.413565 -24.376273) (xy 189.362236 -24.398085)
			(xy 189.308279 -24.412191) (xy 189.252842 -24.418291) (xy 189.197108 -24.416254) (xy 189.142265 -24.406124)
			(xy 189.089481 -24.388117) (xy 189.039881 -24.362616) (xy 188.994523 -24.330165) (xy 188.954374 -24.291456)
			(xy 188.920288 -24.247313) (xy 188.892992 -24.198678) (xy 188.873069 -24.146587) (xy 188.860943 -24.09215)
			(xy 188.856872 -24.036528) (xy 188.100208 -24.036528) (xy 188.129164 -24.065484) (xy 188.149293 -24.086332)
			(xy 188.183403 -24.13318) (xy 188.209762 -24.184788) (xy 188.227721 -24.239885) (xy 188.236837 -24.297113)
			(xy 188.237368 -24.326088) (xy 188.237368 -24.686049) (xy 191.338206 -24.686049) (xy 191.338206 -24.631551)
			(xy 191.345962 -24.577607) (xy 191.361316 -24.525316) (xy 191.383956 -24.475743) (xy 191.41342 -24.429896)
			(xy 191.449109 -24.388709) (xy 191.490296 -24.35302) (xy 191.536143 -24.323556) (xy 191.585716 -24.300916)
			(xy 191.638007 -24.285562) (xy 191.691951 -24.277806) (xy 191.7192 -24.27732) (xy 191.744806 -24.277739)
			(xy 191.795561 -24.284561) (xy 191.844948 -24.298108) (xy 191.892081 -24.318138) (xy 191.936111 -24.344291)
			(xy 191.956436 -24.35987) (xy 191.968626 -24.368901) (xy 191.996881 -24.379922) (xy 192.027124 -24.38217)
			(xy 192.056698 -24.375449) (xy 192.082999 -24.360349) (xy 192.103714 -24.3382) (xy 192.110868 -24.324818)
			(xy 192.122938 -24.301012) (xy 192.152705 -24.256709) (xy 192.188359 -24.216989) (xy 192.229202 -24.182629)
			(xy 192.274438 -24.1543) (xy 192.323182 -24.132555) (xy 192.374481 -24.117818) (xy 192.427335 -24.110379)
			(xy 192.454022 -24.109934) (xy 192.481275 -24.110337) (xy 192.535227 -24.118097) (xy 192.587524 -24.133456)
			(xy 192.637104 -24.156101) (xy 192.682957 -24.185571) (xy 192.724149 -24.221266) (xy 192.759842 -24.262461)
			(xy 192.78931 -24.308315) (xy 192.811952 -24.357896) (xy 192.827307 -24.410195) (xy 192.835064 -24.464147)
			(xy 192.835064 -24.518653) (xy 192.827307 -24.572605) (xy 192.811952 -24.624904) (xy 192.78931 -24.674485)
			(xy 192.759842 -24.720339) (xy 192.724149 -24.761534) (xy 192.682957 -24.797229) (xy 192.637104 -24.826699)
			(xy 192.587524 -24.849344) (xy 192.535227 -24.864703) (xy 192.481275 -24.872463) (xy 192.454022 -24.87295)
			(xy 192.428416 -24.872525) (xy 192.377661 -24.865706) (xy 192.328273 -24.85216) (xy 192.281141 -24.832131)
			(xy 192.237111 -24.805979) (xy 192.216786 -24.7904) (xy 192.204572 -24.781406) (xy 192.176326 -24.770387)
			(xy 192.146091 -24.768136) (xy 192.116524 -24.77485) (xy 192.090227 -24.789939) (xy 192.069511 -24.812077)
			(xy 192.062354 -24.825452) (xy 192.050254 -24.849242) (xy 192.020492 -24.893546) (xy 191.984844 -24.933267)
			(xy 191.944005 -24.967629) (xy 191.898773 -24.99596) (xy 191.850033 -25.017708) (xy 191.798737 -25.032447)
			(xy 191.745886 -25.039889) (xy 191.7192 -25.040336) (xy 191.691951 -25.039794) (xy 191.638007 -25.032038)
			(xy 191.585716 -25.016684) (xy 191.536143 -24.994044) (xy 191.490296 -24.96458) (xy 191.449109 -24.928891)
			(xy 191.41342 -24.887704) (xy 191.383956 -24.841857) (xy 191.361316 -24.792284) (xy 191.345962 -24.739993)
			(xy 191.338206 -24.686049) (xy 188.237368 -24.686049) (xy 188.237368 -25.565862) (xy 192.072004 -25.565862)
			(xy 192.076075 -25.51024) (xy 192.088201 -25.455803) (xy 192.108124 -25.403712) (xy 192.13542 -25.355077)
			(xy 192.169506 -25.310934) (xy 192.209655 -25.272225) (xy 192.255013 -25.239774) (xy 192.304613 -25.214273)
			(xy 192.357397 -25.196266) (xy 192.41224 -25.186136) (xy 192.467974 -25.184099) (xy 192.523411 -25.190199)
			(xy 192.577368 -25.204305) (xy 192.628697 -25.226117) (xy 192.676303 -25.255171) (xy 192.719171 -25.290846)
			(xy 192.756388 -25.332383) (xy 192.787161 -25.378896) (xy 192.810833 -25.429393) (xy 192.826901 -25.4828)
			(xy 192.835021 -25.537976) (xy 192.83553 -25.565862) (xy 192.835021 -25.593748) (xy 192.826901 -25.648924)
			(xy 192.810833 -25.702331) (xy 192.787161 -25.752828) (xy 192.756388 -25.799341) (xy 192.719171 -25.840878)
			(xy 192.676303 -25.876553) (xy 192.628697 -25.905607) (xy 192.577368 -25.927419) (xy 192.523411 -25.941525)
			(xy 192.467974 -25.947625) (xy 192.41224 -25.945588) (xy 192.357397 -25.935458) (xy 192.304613 -25.917451)
			(xy 192.255013 -25.89195) (xy 192.209655 -25.859499) (xy 192.169506 -25.82079) (xy 192.13542 -25.776647)
			(xy 192.108124 -25.728012) (xy 192.088201 -25.675921) (xy 192.076075 -25.621484) (xy 192.072004 -25.565862)
			(xy 188.237368 -25.565862) (xy 188.237368 -25.944322) (xy 188.236811 -25.973297) (xy 188.227708 -26.030527)
			(xy 188.209761 -26.085628) (xy 188.183412 -26.137242) (xy 188.149311 -26.184096) (xy 188.129164 -26.204926)
			(xy 188.01334 -26.32075) (xy 188.01334 -27.087068) (xy 190.295782 -27.087068) (xy 190.299853 -27.031446)
			(xy 190.311979 -26.977009) (xy 190.331902 -26.924918) (xy 190.359198 -26.876283) (xy 190.393284 -26.83214)
			(xy 190.433433 -26.793431) (xy 190.478791 -26.76098) (xy 190.528391 -26.735479) (xy 190.581175 -26.717472)
			(xy 190.636018 -26.707342) (xy 190.691752 -26.705305) (xy 190.747189 -26.711405) (xy 190.801146 -26.725511)
			(xy 190.852475 -26.747323) (xy 190.900081 -26.776377) (xy 190.942949 -26.812052) (xy 190.980166 -26.853589)
			(xy 191.010939 -26.900102) (xy 191.034611 -26.950599) (xy 191.050679 -27.004006) (xy 191.058799 -27.059182)
			(xy 191.059308 -27.087068) (xy 191.058799 -27.114954) (xy 191.050679 -27.17013) (xy 191.034611 -27.223537)
			(xy 191.010939 -27.274034) (xy 190.980166 -27.320547) (xy 190.942949 -27.362084) (xy 190.900081 -27.397759)
			(xy 190.852475 -27.426813) (xy 190.801146 -27.448625) (xy 190.747189 -27.462731) (xy 190.691752 -27.468831)
			(xy 190.636018 -27.466794) (xy 190.581175 -27.456664) (xy 190.528391 -27.438657) (xy 190.478791 -27.413156)
			(xy 190.433433 -27.380705) (xy 190.393284 -27.341996) (xy 190.359198 -27.297853) (xy 190.331902 -27.249218)
			(xy 190.311979 -27.197127) (xy 190.299853 -27.14269) (xy 190.295782 -27.087068) (xy 188.01334 -27.087068)
			(xy 188.01334 -27.171142) (xy 188.013809 -27.185292) (xy 188.021591 -27.212502) (xy 188.036544 -27.23653)
			(xy 188.05752 -27.255529) (xy 188.082906 -27.268039) (xy 188.110751 -27.273098) (xy 188.138915 -27.270317)
			(xy 188.152278 -27.26563) (xy 188.174636 -27.257192) (xy 188.220926 -27.24532) (xy 188.268338 -27.239333)
			(xy 188.292232 -27.23896) (xy 188.319483 -27.239448) (xy 188.373429 -27.247208) (xy 188.425721 -27.262566)
			(xy 188.475297 -27.285208) (xy 188.521145 -27.314675) (xy 188.562334 -27.350366) (xy 188.598025 -27.391555)
			(xy 188.627492 -27.437403) (xy 188.650134 -27.486979) (xy 188.665492 -27.539271) (xy 188.670961 -27.577288)
			(xy 189.414402 -27.577288) (xy 189.418473 -27.521666) (xy 189.430599 -27.467229) (xy 189.450522 -27.415138)
			(xy 189.477818 -27.366503) (xy 189.511904 -27.32236) (xy 189.552053 -27.283651) (xy 189.597411 -27.2512)
			(xy 189.647011 -27.225699) (xy 189.699795 -27.207692) (xy 189.754638 -27.197562) (xy 189.810372 -27.195525)
			(xy 189.865809 -27.201625) (xy 189.919766 -27.215731) (xy 189.971095 -27.237543) (xy 190.018701 -27.266597)
			(xy 190.061569 -27.302272) (xy 190.098786 -27.343809) (xy 190.129559 -27.390322) (xy 190.153231 -27.440819)
			(xy 190.169299 -27.494226) (xy 190.177419 -27.549402) (xy 190.177928 -27.577288) (xy 190.177419 -27.605174)
			(xy 190.169299 -27.66035) (xy 190.153231 -27.713757) (xy 190.129559 -27.764254) (xy 190.098786 -27.810767)
			(xy 190.061569 -27.852304) (xy 190.018701 -27.887979) (xy 189.971095 -27.917033) (xy 189.919766 -27.938845)
			(xy 189.865809 -27.952951) (xy 189.810372 -27.959051) (xy 189.754638 -27.957014) (xy 189.699795 -27.946884)
			(xy 189.647011 -27.928877) (xy 189.597411 -27.903376) (xy 189.552053 -27.870925) (xy 189.511904 -27.832216)
			(xy 189.477818 -27.788073) (xy 189.450522 -27.739438) (xy 189.430599 -27.687347) (xy 189.418473 -27.63291)
			(xy 189.414402 -27.577288) (xy 188.670961 -27.577288) (xy 188.673252 -27.593217) (xy 188.67374 -27.620468)
			(xy 188.673274 -27.64707) (xy 188.665877 -27.699756) (xy 188.651235 -27.750905) (xy 188.629632 -27.799526)
			(xy 188.601487 -27.844675) (xy 188.567345 -27.885479) (xy 188.527867 -27.921146) (xy 188.5061 -27.936444)
			(xy 188.494038 -27.945258) (xy 188.475224 -27.968445) (xy 188.46391 -27.996079) (xy 188.461059 -28.025802)
			(xy 188.466915 -28.055082) (xy 188.480978 -28.081423) (xy 188.491114 -28.0924) (xy 188.559948 -28.161488)
			(xy 188.580078 -28.182336) (xy 188.614188 -28.229184) (xy 188.640548 -28.280792) (xy 188.658507 -28.335889)
			(xy 188.667623 -28.393117) (xy 188.668152 -28.422092) (xy 188.668152 -29.285692) (xy 188.919612 -29.537152)
			(xy 189.618364 -29.537152) (xy 189.622435 -29.48153) (xy 189.634561 -29.427093) (xy 189.654484 -29.375002)
			(xy 189.68178 -29.326367) (xy 189.715866 -29.282224) (xy 189.756015 -29.243515) (xy 189.801373 -29.211064)
			(xy 189.850973 -29.185563) (xy 189.903757 -29.167556) (xy 189.9586 -29.157426) (xy 190.014334 -29.155389)
			(xy 190.069771 -29.161489) (xy 190.123728 -29.175595) (xy 190.175057 -29.197407) (xy 190.222663 -29.226461)
			(xy 190.265531 -29.262136) (xy 190.302748 -29.303673) (xy 190.333521 -29.350186) (xy 190.357193 -29.400683)
			(xy 190.373261 -29.45409) (xy 190.381381 -29.509266) (xy 190.38189 -29.537152) (xy 190.381381 -29.565038)
			(xy 190.373261 -29.620214) (xy 190.357193 -29.673621) (xy 190.333521 -29.724118) (xy 190.302748 -29.770631)
			(xy 190.265531 -29.812168) (xy 190.222663 -29.847843) (xy 190.175057 -29.876897) (xy 190.123728 -29.898709)
			(xy 190.069771 -29.912815) (xy 190.014334 -29.918915) (xy 189.9586 -29.916878) (xy 189.903757 -29.906748)
			(xy 189.850973 -29.888741) (xy 189.801373 -29.86324) (xy 189.756015 -29.830789) (xy 189.715866 -29.79208)
			(xy 189.68178 -29.747937) (xy 189.654484 -29.699302) (xy 189.634561 -29.647211) (xy 189.622435 -29.592774)
			(xy 189.618364 -29.537152) (xy 188.919612 -29.537152) (xy 189.827408 -30.444948) (xy 191.34328 -30.444948)
		)
		(stroke
			(width 0)
			(type solid)
		)
		(fill yes)
		(layer "In2.Cu")
		(net "GND")
	)
	(gr_poly
		(pts
			(arc
				(start 256.800096 -36.291012)
				(mid 258.932727 -35.407647)
				(end 259.816092 -33.275016)
			)
			(xy 259.817616 -32.293306) (xy 259.817616 -32.275018)
			(arc
				(start 259.817616 -13.780008)
				(mid 260.105375 -13.085295)
				(end 260.800088 -12.797536)
			)
			(arc
				(start 297.582844 -12.797536)
				(mid 297.598921 -12.792794)
				(end 297.612562 -12.783058)
			)
			(arc
				(start 297.619166 -12.776454)
				(mid 297.738732 -12.696562)
				(end 297.87977 -12.668504)
			)
			(arc
				(start 310.53659 -12.668504)
				(mid 310.67763 -12.696559)
				(end 310.797194 -12.776454)
			)
			(arc
				(start 310.803798 -12.783058)
				(mid 310.817444 -12.792784)
				(end 310.833516 -12.797536)
			)
			(arc
				(start 385.601972 -12.797536)
				(mid 387.735681 -11.913725)
				(end 388.619492 -9.780016)
			)
			(xy 388.619492 -3.928364)
			(arc
				(start 388.614158 -3.917442)
				(mid 388.329377 -3.590886)
				(end 388.226808 -3.16992)
			)
			(arc
				(start 388.226808 -3.16992)
				(mid 388.275543 -2.875216)
				(end 388.416546 -2.611882)
			)
			(arc
				(start 388.416546 -2.611882)
				(mid 388.501545 -2.513276)
				(end 388.59968 -2.427732)
			)
			(xy 388.619492 -2.388108) (xy 388.619492 -1.016) (xy 455.184256 -1.016) (xy 455.184256 -2.375154)
			(arc
				(start 455.205338 -2.416048)
				(mid 455.573689 -3.012402)
				(end 455.41184 -3.69443)
			)
			(arc
				(start 455.41184 -3.69443)
				(mid 455.315091 -3.810755)
				(end 455.200512 -3.909568)
			)
			(xy 455.184256 -3.941318)
			(arc
				(start 455.184256 -9.780016)
				(mid 455.693364 -11.457304)
				(end 457.04887 -12.568682)
			)
			(arc
				(start 457.04887 -12.568682)
				(mid 457.056529 -12.570412)
				(end 457.064364 -12.570968)
			)
			(arc
				(start 457.454508 -12.570968)
				(mid 457.576151 -12.595258)
				(end 457.679298 -12.664186)
			)
			(arc
				(start 457.771754 -12.756642)
				(mid 457.782995 -12.765181)
				(end 457.796138 -12.770358)
			)
			(arc
				(start 457.796138 -12.770358)
				(mid 457.998625 -12.790797)
				(end 458.20203 -12.797536)
			)
			(arc
				(start 469.799924 -12.797536)
				(mid 470.494637 -13.085295)
				(end 470.782396 -13.780008)
			)
			(xy 470.782396 -17.620234)
			(arc
				(start 470.808558 -17.664176)
				(mid 470.972568 -17.756784)
				(end 471.13317 -17.855184)
			)
			(arc
				(start 471.13317 -17.855184)
				(mid 471.158695 -17.863037)
				(end 471.184732 -17.856962)
			)
			(arc
				(start 471.262964 -17.814036)
				(mid 471.282207 -17.795414)
				(end 471.28938 -17.769586)
			)
			(arc
				(start 471.28938 -13.780008)
				(mid 470.853128 -12.726804)
				(end 469.799924 -12.290552)
			)
			(arc
				(start 458.20203 -12.290552)
				(mid 456.426813 -11.555233)
				(end 455.691494 -9.780016)
			)
			(xy 455.691494 -1.30556) (xy 455.69378 -1.30556)
			(arc
				(start 455.69378 -0.999998)
				(mid 455.549752 -0.652282)
				(end 455.202036 -0.508254)
			)
			(arc
				(start 388.601966 -0.508254)
				(mid 388.25425 -0.652282)
				(end 388.110222 -0.999998)
			)
			(xy 388.110222 -1.30556) (xy 388.112508 -1.30556)
			(arc
				(start 388.112508 -9.780016)
				(mid 387.377189 -11.555233)
				(end 385.601972 -12.290552)
			)
			(arc
				(start 260.800088 -12.290552)
				(mid 259.746884 -12.726804)
				(end 259.310632 -13.780008)
			)
			(arc
				(start 259.310632 -32.275018)
				(mid 259.308727 -32.775015)
				(end 259.308092 -33.275016)
			)
			(arc
				(start 259.308092 -33.275016)
				(mid 258.573517 -35.048437)
				(end 256.800096 -35.783012)
			)
			(arc
				(start 225.300032 -35.783012)
				(mid 223.526611 -35.048437)
				(end 222.792036 -33.275016)
			)
			(arc
				(start 222.792036 -33.275016)
				(mid 222.790131 -32.775019)
				(end 222.789496 -32.275018)
			)
			(arc
				(start 222.789496 -13.780008)
				(mid 222.353244 -12.726804)
				(end 221.30004 -12.290552)
			)
			(arc
				(start 196.701918 -12.290552)
				(mid 194.926701 -11.555233)
				(end 194.191382 -9.780016)
			)
			(xy 194.191382 -6.53796) (xy 194.193668 -6.53796)
			(arc
				(start 194.193668 -6.279896)
				(mid 194.04964 -5.93218)
				(end 193.701924 -5.788152)
			)
			(arc
				(start 127.102108 -5.788152)
				(mid 126.754392 -5.93218)
				(end 126.610364 -6.279896)
			)
			(xy 126.610364 -6.53796) (xy 126.61265 -6.53796)
			(arc
				(start 126.61265 -7.744206)
				(mid 126.627618 -7.779963)
				(end 126.66345 -7.794752)
			)
			(arc
				(start 126.687326 -7.78891)
				(mid 126.774244 -7.75555)
				(end 126.86665 -7.744206)
			)
			(arc
				(start 126.86665 -7.744206)
				(mid 126.931475 -7.749794)
				(end 126.994412 -7.766304)
			)
			(arc
				(start 126.994412 -7.766304)
				(mid 127.020815 -7.768359)
				(end 127.044704 -7.756906)
			)
			(arc
				(start 127.044704 -7.756906)
				(mid 127.071589 -7.734537)
				(end 127.099314 -7.713218)
			)
			(xy 127.119888 -7.672832) (xy 127.119888 -6.295898) (xy 193.684144 -6.295898) (xy 193.684144 -7.673086)
			(arc
				(start 193.704718 -7.713472)
				(mid 194.076604 -8.449818)
				(end 193.704718 -9.186164)
			)
			(xy 193.684144 -9.22655)
			(arc
				(start 193.684144 -9.780016)
				(mid 194.568119 -11.91374)
				(end 196.701918 -12.797536)
			)
			(arc
				(start 221.30004 -12.797536)
				(mid 221.994753 -13.085295)
				(end 222.282512 -13.780008)
			)
			(xy 222.282512 -32.275018)
			(arc
				(start 222.284036 -33.275016)
				(mid 223.167401 -35.407647)
				(end 225.300032 -36.291012)
			)
		)
		(stroke
			(width 0)
			(type solid)
		)
		(fill yes)
		(layer "In2.Cu")
		(net "GND")
	)
	(gr_poly
		(pts
			(xy 187.207652 -29.445204) (xy 187.207652 -29.423868) (xy 187.207652 -28.557474) (xy 185.723276 -27.073098)
			(xy 185.703151 -27.052248) (xy 185.669049 -27.005398) (xy 185.642697 -26.953789) (xy 185.624744 -26.898693)
			(xy 185.615632 -26.841467) (xy 185.615072 -26.812494) (xy 185.615072 -21.976588) (xy 185.615628 -21.947613)
			(xy 185.624731 -21.890383) (xy 185.642678 -21.835282) (xy 185.669028 -21.783669) (xy 185.703131 -21.736816)
			(xy 185.723276 -21.715984) (xy 186.002168 -21.436838) (xy 186.002168 -21.07438) (xy 186.002725 -21.045406)
			(xy 186.011828 -20.988175) (xy 186.029776 -20.933075) (xy 186.056127 -20.881463) (xy 186.09023 -20.834611)
			(xy 186.110372 -20.813776) (xy 187.619132 -19.304762) (xy 187.619132 -18.887948) (xy 185.408824 -18.887948)
			(xy 185.393812 -18.888437) (xy 185.365062 -18.897083) (xy 185.340073 -18.913723) (xy 185.32101 -18.936915)
			(xy 185.309522 -18.964652) (xy 185.306604 -18.994531) (xy 185.309002 -19.00936) (xy 185.31244 -19.027709)
			(xy 185.316126 -19.064861) (xy 185.316368 -19.083528) (xy 185.315882 -19.110779) (xy 185.308126 -19.164727)
			(xy 185.292771 -19.217022) (xy 185.270129 -19.266599) (xy 185.240663 -19.312449) (xy 185.204972 -19.35364)
			(xy 185.163781 -19.389331) (xy 185.117931 -19.418797) (xy 185.068354 -19.441439) (xy 185.016059 -19.456794)
			(xy 184.962111 -19.46455) (xy 184.907609 -19.46455) (xy 184.853661 -19.456794) (xy 184.801366 -19.441439)
			(xy 184.751789 -19.418797) (xy 184.705939 -19.389331) (xy 184.664748 -19.35364) (xy 184.629057 -19.312449)
			(xy 184.599591 -19.266599) (xy 184.576949 -19.217022) (xy 184.561594 -19.164727) (xy 184.553838 -19.110779)
			(xy 184.553352 -19.083528) (xy 184.553604 -19.064862) (xy 184.557292 -19.027711) (xy 184.560718 -19.00936)
			(xy 184.563112 -18.99454) (xy 184.560147 -18.964681) (xy 184.548642 -18.936968) (xy 184.529586 -18.91379)
			(xy 184.504622 -18.897143) (xy 184.475899 -18.888461) (xy 184.460896 -18.887948) (xy 178.409346 -18.887948)
			(xy 178.395582 -18.888398) (xy 178.369056 -18.895752) (xy 178.345465 -18.909936) (xy 178.326529 -18.929915)
			(xy 178.31363 -18.954232) (xy 178.307708 -18.981114) (xy 178.308 -18.994882) (xy 178.308508 -19.014948)
			(xy 178.308022 -19.042199) (xy 178.300266 -19.096147) (xy 178.284911 -19.148442) (xy 178.262269 -19.198019)
			(xy 178.232803 -19.243869) (xy 178.197112 -19.28506) (xy 178.155921 -19.320751) (xy 178.110071 -19.350217)
			(xy 178.060494 -19.372859) (xy 178.008199 -19.388214) (xy 177.954251 -19.39597) (xy 177.899749 -19.39597)
			(xy 177.845801 -19.388214) (xy 177.793506 -19.372859) (xy 177.743929 -19.350217) (xy 177.698079 -19.320751)
			(xy 177.656888 -19.28506) (xy 177.621197 -19.243869) (xy 177.591731 -19.198019) (xy 177.569089 -19.148442)
			(xy 177.553734 -19.096147) (xy 177.545978 -19.042199) (xy 177.545492 -19.014948) (xy 177.546 -18.994882)
			(xy 177.546263 -18.981123) (xy 177.540307 -18.954266) (xy 177.527399 -18.929974) (xy 177.508475 -18.910009)
			(xy 177.484907 -18.895819) (xy 177.458408 -18.888436) (xy 177.444654 -18.887948) (xy 174.908972 -18.887948)
			(xy 174.888406 -18.904294) (xy 174.843636 -18.931781) (xy 174.795517 -18.952864) (xy 174.744961 -18.967145)
			(xy 174.692923 -18.974354) (xy 174.640389 -18.974354) (xy 174.588351 -18.967145) (xy 174.537795 -18.952864)
			(xy 174.489676 -18.931781) (xy 174.444906 -18.904294) (xy 174.42434 -18.887948) (xy 173.235366 -18.887948)
			(xy 173.220894 -18.88846) (xy 173.193114 -18.896586) (xy 173.168728 -18.912176) (xy 173.149692 -18.933979)
			(xy 173.137533 -18.960245) (xy 173.133228 -18.988867) (xy 173.137122 -19.017548) (xy 173.148902 -19.043986)
			(xy 173.157896 -19.055334) (xy 173.174892 -19.076099) (xy 173.2035 -19.121496) (xy 173.225463 -19.170454)
			(xy 173.240347 -19.222008) (xy 173.247858 -19.275138) (xy 173.24832 -19.301968) (xy 173.247834 -19.329219)
			(xy 173.240078 -19.383167) (xy 173.224723 -19.435462) (xy 173.202081 -19.485039) (xy 173.172615 -19.530889)
			(xy 173.136924 -19.57208) (xy 173.095733 -19.607771) (xy 173.049883 -19.637237) (xy 173.000306 -19.659879)
			(xy 172.948011 -19.675234) (xy 172.894063 -19.68299) (xy 172.839561 -19.68299) (xy 172.785613 -19.675234)
			(xy 172.733318 -19.659879) (xy 172.683741 -19.637237) (xy 172.637891 -19.607771) (xy 172.5967 -19.57208)
			(xy 172.561009 -19.530889) (xy 172.531543 -19.485039) (xy 172.508901 -19.435462) (xy 172.493546 -19.383167)
			(xy 172.48579 -19.329219) (xy 172.485304 -19.301968) (xy 172.485762 -19.275139) (xy 172.493283 -19.222011)
			(xy 172.508173 -19.17046) (xy 172.530137 -19.121504) (xy 172.558744 -19.076108) (xy 172.575728 -19.055334)
			(xy 172.584704 -19.043976) (xy 172.59649 -19.017549) (xy 172.600387 -18.988878) (xy 172.596084 -18.960264)
			(xy 172.583926 -18.934007) (xy 172.564889 -18.912216) (xy 172.540503 -18.896641) (xy 172.512726 -18.888534)
			(xy 172.498258 -18.887948) (xy 172.39488 -18.887948) (xy 171.93768 -19.345148) (xy 171.93768 -21.275548)
			(xy 172.62348 -21.961348) (xy 176.989232 -21.961348) (xy 177.002682 -21.960932) (xy 177.028646 -21.9539)
			(xy 177.051874 -21.940333) (xy 177.070754 -21.921171) (xy 177.083975 -21.897745) (xy 177.090621 -21.871678)
			(xy 177.090832 -21.858224) (xy 177.090832 -21.85289) (xy 177.091086 -21.83638) (xy 177.091268 -21.822302)
			(xy 177.084807 -21.79491) (xy 177.071108 -21.770325) (xy 177.051211 -21.75042) (xy 177.026633 -21.736709)
			(xy 176.999244 -21.730236) (xy 176.985168 -21.730462) (xy 176.968658 -21.730716) (xy 176.941409 -21.730227)
			(xy 176.887465 -21.722466) (xy 176.835175 -21.707107) (xy 176.785602 -21.684464) (xy 176.739757 -21.654997)
			(xy 176.698571 -21.619305) (xy 176.662883 -21.578116) (xy 176.63342 -21.532268) (xy 176.610781 -21.482693)
			(xy 176.595427 -21.430402) (xy 176.58767 -21.376458) (xy 176.58715 -21.349208) (xy 176.587621 -21.321838)
			(xy 176.595445 -21.26766) (xy 176.610933 -21.215157) (xy 176.633767 -21.165407) (xy 176.663477 -21.119431)
			(xy 176.68113 -21.09851) (xy 176.690366 -21.087182) (xy 176.702541 -21.060623) (xy 176.706715 -21.031706)
			(xy 176.702545 -21.002789) (xy 176.690372 -20.976229) (xy 176.68113 -20.964906) (xy 176.663486 -20.943975)
			(xy 176.633757 -20.89801) (xy 176.610912 -20.848263) (xy 176.595419 -20.795759) (xy 176.587599 -20.741579)
			(xy 176.58715 -20.714208) (xy 176.587591 -20.688195) (xy 176.594661 -20.636653) (xy 176.60867 -20.58655)
			(xy 176.629359 -20.538815) (xy 176.656344 -20.494336) (xy 176.689124 -20.453936) (xy 176.7078 -20.435824)
			(xy 176.717429 -20.426204) (xy 176.731664 -20.403017) (xy 176.739279 -20.376896) (xy 176.739734 -20.349692)
			(xy 176.732997 -20.323331) (xy 176.719545 -20.299681) (xy 176.700331 -20.280417) (xy 176.68875 -20.273264)
			(xy 176.66411 -20.25859) (xy 176.619137 -20.223009) (xy 176.579993 -20.1811) (xy 176.54756 -20.133806)
			(xy 176.522568 -20.082191) (xy 176.50558 -20.027419) (xy 176.496978 -19.970721) (xy 176.496472 -19.942048)
			(xy 176.496958 -19.914797) (xy 176.504714 -19.860849) (xy 176.520069 -19.808554) (xy 176.542711 -19.758977)
			(xy 176.572177 -19.713127) (xy 176.607868 -19.671936) (xy 176.649059 -19.636245) (xy 176.694909 -19.606779)
			(xy 176.744486 -19.584137) (xy 176.796781 -19.568782) (xy 176.850729 -19.561026) (xy 176.905231 -19.561026)
			(xy 176.959179 -19.568782) (xy 177.011474 -19.584137) (xy 177.061051 -19.606779) (xy 177.106901 -19.636245)
			(xy 177.148092 -19.671936) (xy 177.178701 -19.707262) (xy 180.08231 -19.707262) (xy 180.090065 -19.653302)
			(xy 180.105422 -19.600996) (xy 180.128066 -19.551407) (xy 180.157538 -19.505546) (xy 180.193236 -19.464346)
			(xy 180.234435 -19.428646) (xy 180.280295 -19.399173) (xy 180.329883 -19.376527) (xy 180.382189 -19.361168)
			(xy 180.436148 -19.353411) (xy 180.490662 -19.353411) (xy 180.544622 -19.361171) (xy 180.596927 -19.37653)
			(xy 180.646515 -19.399178) (xy 180.692374 -19.428652) (xy 180.733571 -19.464354) (xy 180.769269 -19.505554)
			(xy 180.798739 -19.551416) (xy 180.821382 -19.601006) (xy 180.836737 -19.653313) (xy 180.844491 -19.707273)
			(xy 180.844952 -19.73453) (xy 180.844846 -19.748102) (xy 180.842941 -19.775179) (xy 180.842025 -19.782028)
			(xy 182.097932 -19.782028) (xy 182.102003 -19.726406) (xy 182.114129 -19.671969) (xy 182.134052 -19.619878)
			(xy 182.161348 -19.571243) (xy 182.195434 -19.5271) (xy 182.235583 -19.488391) (xy 182.280941 -19.45594)
			(xy 182.330541 -19.430439) (xy 182.383325 -19.412432) (xy 182.438168 -19.402302) (xy 182.493902 -19.400265)
			(xy 182.549339 -19.406365) (xy 182.603296 -19.420471) (xy 182.654625 -19.442283) (xy 182.702231 -19.471337)
			(xy 182.745099 -19.507012) (xy 182.782316 -19.548549) (xy 182.813089 -19.595062) (xy 182.836761 -19.645559)
			(xy 182.852829 -19.698966) (xy 182.860949 -19.754142) (xy 182.861365 -19.776948) (xy 183.111392 -19.776948)
			(xy 183.115463 -19.721326) (xy 183.127589 -19.666889) (xy 183.147512 -19.614798) (xy 183.174808 -19.566163)
			(xy 183.208894 -19.52202) (xy 183.249043 -19.483311) (xy 183.294401 -19.45086) (xy 183.344001 -19.425359)
			(xy 183.396785 -19.407352) (xy 183.451628 -19.397222) (xy 183.507362 -19.395185) (xy 183.562799 -19.401285)
			(xy 183.616756 -19.415391) (xy 183.668085 -19.437203) (xy 183.715691 -19.466257) (xy 183.758559 -19.501932)
			(xy 183.795776 -19.543469) (xy 183.826549 -19.589982) (xy 183.850221 -19.640479) (xy 183.866289 -19.693886)
			(xy 183.874409 -19.749062) (xy 183.874918 -19.776948) (xy 183.874409 -19.804834) (xy 183.866289 -19.86001)
			(xy 183.850221 -19.913417) (xy 183.826549 -19.963914) (xy 183.795776 -20.010427) (xy 183.758559 -20.051964)
			(xy 183.715691 -20.087639) (xy 183.668085 -20.116693) (xy 183.616756 -20.138505) (xy 183.562799 -20.152611)
			(xy 183.507362 -20.158711) (xy 183.451628 -20.156674) (xy 183.396785 -20.146544) (xy 183.344001 -20.128537)
			(xy 183.294401 -20.103036) (xy 183.249043 -20.070585) (xy 183.208894 -20.031876) (xy 183.174808 -19.987733)
			(xy 183.147512 -19.939098) (xy 183.127589 -19.887007) (xy 183.115463 -19.83257) (xy 183.111392 -19.776948)
			(xy 182.861365 -19.776948) (xy 182.861458 -19.782028) (xy 182.860949 -19.809914) (xy 182.852829 -19.86509)
			(xy 182.836761 -19.918497) (xy 182.813089 -19.968994) (xy 182.782316 -20.015507) (xy 182.745099 -20.057044)
			(xy 182.702231 -20.092719) (xy 182.654625 -20.121773) (xy 182.603296 -20.143585) (xy 182.549339 -20.157691)
			(xy 182.493902 -20.163791) (xy 182.438168 -20.161754) (xy 182.383325 -20.151624) (xy 182.330541 -20.133617)
			(xy 182.280941 -20.108116) (xy 182.235583 -20.075665) (xy 182.195434 -20.036956) (xy 182.161348 -19.992813)
			(xy 182.134052 -19.944178) (xy 182.114129 -19.892087) (xy 182.102003 -19.83765) (xy 182.097932 -19.782028)
			(xy 180.842025 -19.782028) (xy 180.841142 -19.788632) (xy 180.839545 -19.803664) (xy 180.844203 -19.833517)
			(xy 180.857381 -19.860706) (xy 180.87793 -19.882857) (xy 180.904054 -19.898036) (xy 180.933474 -19.904918)
			(xy 180.948584 -19.904456) (xy 180.975 -19.90344) (xy 181.002251 -19.903878) (xy 181.056197 -19.911634)
			(xy 181.10849 -19.926988) (xy 181.158066 -19.949628) (xy 181.203916 -19.979093) (xy 181.245106 -20.014783)
			(xy 181.280797 -20.055971) (xy 181.310264 -20.101819) (xy 181.332906 -20.151395) (xy 181.348263 -20.203687)
			(xy 181.356021 -20.257633) (xy 181.356023 -20.312135) (xy 181.34827 -20.366081) (xy 181.332917 -20.418375)
			(xy 181.31028 -20.467952) (xy 181.280817 -20.513803) (xy 181.245129 -20.554995) (xy 181.203942 -20.590688)
			(xy 181.158095 -20.620157) (xy 181.10852 -20.642801) (xy 181.056228 -20.658159) (xy 181.002282 -20.66592)
			(xy 180.947781 -20.665925) (xy 180.893834 -20.658173) (xy 180.84154 -20.642823) (xy 180.791962 -20.620187)
			(xy 180.74611 -20.590726) (xy 180.704917 -20.55504) (xy 180.669222 -20.513855) (xy 180.639751 -20.468009)
			(xy 180.617105 -20.418435) (xy 180.601744 -20.366144) (xy 180.593981 -20.312198) (xy 180.593492 -20.284948)
			(xy 180.593596 -20.271376) (xy 180.595502 -20.244299) (xy 180.597302 -20.230846) (xy 180.598881 -20.21581)
			(xy 180.594241 -20.185952) (xy 180.581071 -20.158756) (xy 180.560524 -20.136602) (xy 180.534395 -20.121425)
			(xy 180.504971 -20.114553) (xy 180.48986 -20.115022) (xy 180.463444 -20.116038) (xy 180.436187 -20.115592)
			(xy 180.382227 -20.10784) (xy 180.329919 -20.092487) (xy 180.280329 -20.069846) (xy 180.234466 -20.040377)
			(xy 180.193263 -20.004681) (xy 180.157561 -19.963485) (xy 180.128085 -19.917627) (xy 180.105435 -19.868041)
			(xy 180.090074 -19.815735) (xy 180.082312 -19.761776) (xy 180.08231 -19.707262) (xy 177.178701 -19.707262)
			(xy 177.183783 -19.713127) (xy 177.213249 -19.758977) (xy 177.235891 -19.808554) (xy 177.251246 -19.860849)
			(xy 177.259002 -19.914797) (xy 177.259488 -19.942048) (xy 177.25905 -19.968062) (xy 177.251986 -20.019608)
			(xy 177.237982 -20.069716) (xy 177.217298 -20.117456) (xy 177.190318 -20.161942) (xy 177.157543 -20.202348)
			(xy 177.138838 -20.220432) (xy 177.1292 -20.230051) (xy 177.114948 -20.253241) (xy 177.10732 -20.27937)
			(xy 177.106857 -20.306585) (xy 177.113592 -20.332959) (xy 177.127048 -20.35662) (xy 177.14627 -20.375892)
			(xy 177.157888 -20.382992) (xy 177.182523 -20.397668) (xy 177.227487 -20.433253) (xy 177.266621 -20.475165)
			(xy 177.299043 -20.52246) (xy 177.324025 -20.574073) (xy 177.341003 -20.628843) (xy 177.349596 -20.685537)
			(xy 177.350166 -20.714208) (xy 177.349694 -20.741578) (xy 177.341868 -20.795755) (xy 177.326379 -20.848257)
			(xy 177.303545 -20.898006) (xy 177.273834 -20.943981) (xy 177.256186 -20.964906) (xy 177.246951 -20.976234)
			(xy 177.234778 -21.002791) (xy 177.230608 -21.031706) (xy 177.234781 -21.060621) (xy 177.246958 -21.087177)
			(xy 177.256186 -21.09851) (xy 177.273828 -21.119441) (xy 177.303554 -21.165408) (xy 177.326397 -21.215154)
			(xy 177.341886 -21.267658) (xy 177.349704 -21.321838) (xy 177.350166 -21.349208) (xy 177.349912 -21.365718)
			(xy 177.349729 -21.379796) (xy 177.35619 -21.407189) (xy 177.36989 -21.431774) (xy 177.389786 -21.45168)
			(xy 177.414364 -21.465392) (xy 177.441754 -21.471866) (xy 177.45583 -21.471636) (xy 177.47234 -21.471382)
			(xy 177.49959 -21.471871) (xy 177.553534 -21.479632) (xy 177.605824 -21.49499) (xy 177.655397 -21.517633)
			(xy 177.701243 -21.547101) (xy 177.742429 -21.582792) (xy 177.778117 -21.623981) (xy 177.807581 -21.669829)
			(xy 177.83022 -21.719404) (xy 177.845575 -21.771696) (xy 177.853332 -21.82564) (xy 177.853848 -21.85289)
			(xy 177.853848 -21.858224) (xy 177.854053 -21.871683) (xy 177.860682 -21.897761) (xy 177.873898 -21.9212)
			(xy 177.892781 -21.940369) (xy 177.916018 -21.953936) (xy 177.941994 -21.960957) (xy 177.955448 -21.961348)
			(xy 178.187096 -21.961348) (xy 178.201426 -21.960861) (xy 178.228958 -21.952903) (xy 178.253197 -21.93761)
			(xy 178.272235 -21.916188) (xy 178.284574 -21.890321) (xy 178.289244 -21.862044) (xy 178.285876 -21.833583)
			(xy 178.274737 -21.807177) (xy 178.26609 -21.79574) (xy 178.249982 -21.775238) (xy 178.22289 -21.730692)
			(xy 178.202114 -21.682872) (xy 178.188043 -21.632669) (xy 178.180938 -21.581017) (xy 178.180492 -21.554948)
			(xy 178.180952 -21.527693) (xy 178.188703 -21.473737) (xy 178.204055 -21.421433) (xy 178.226695 -21.371847)
			(xy 178.256162 -21.325988) (xy 178.291855 -21.284789) (xy 178.333049 -21.249091) (xy 178.378905 -21.219618)
			(xy 178.428488 -21.196972) (xy 178.48079 -21.181614) (xy 178.534745 -21.173855) (xy 178.562 -21.17344)
			(xy 178.588497 -21.173894) (xy 178.640983 -21.181226) (xy 178.691949 -21.195748) (xy 178.740415 -21.217183)
			(xy 178.785451 -21.245116) (xy 178.826188 -21.279011) (xy 178.861845 -21.318217) (xy 178.891734 -21.361979)
			(xy 178.903884 -21.38553) (xy 178.911039 -21.398817) (xy 178.931696 -21.420797) (xy 178.957877 -21.435776)
			(xy 178.987293 -21.442447) (xy 179.017374 -21.440225) (xy 179.031646 -21.435314) (xy 179.05364 -21.427209)
			(xy 179.099105 -21.415805) (xy 179.145623 -21.410039) (xy 179.16906 -21.40966) (xy 179.196316 -21.41012)
			(xy 179.250273 -21.417872) (xy 179.302577 -21.433225) (xy 179.352164 -21.455864) (xy 179.398025 -21.485331)
			(xy 179.439225 -21.521024) (xy 179.474926 -21.562217) (xy 179.504401 -21.608072) (xy 179.526544 -21.656548)
			(xy 182.269382 -21.656548) (xy 182.273453 -21.600926) (xy 182.285579 -21.546489) (xy 182.305502 -21.494398)
			(xy 182.332798 -21.445763) (xy 182.366884 -21.40162) (xy 182.407033 -21.362911) (xy 182.452391 -21.33046)
			(xy 182.501991 -21.304959) (xy 182.554775 -21.286952) (xy 182.609618 -21.276822) (xy 182.665352 -21.274785)
			(xy 182.720789 -21.280885) (xy 182.774746 -21.294991) (xy 182.826075 -21.316803) (xy 182.873681 -21.345857)
			(xy 182.916549 -21.381532) (xy 182.953766 -21.423069) (xy 182.984539 -21.469582) (xy 183.008211 -21.520079)
			(xy 183.024279 -21.573486) (xy 183.032399 -21.628662) (xy 183.032908 -21.656548) (xy 183.032399 -21.684434)
			(xy 183.024279 -21.73961) (xy 183.008211 -21.793017) (xy 182.984539 -21.843514) (xy 182.953766 -21.890027)
			(xy 182.916549 -21.931564) (xy 182.873681 -21.967239) (xy 182.826075 -21.996293) (xy 182.774746 -22.018105)
			(xy 182.720789 -22.032211) (xy 182.665352 -22.038311) (xy 182.609618 -22.036274) (xy 182.554775 -22.026144)
			(xy 182.501991 -22.008137) (xy 182.452391 -21.982636) (xy 182.407033 -21.950185) (xy 182.366884 -21.911476)
			(xy 182.332798 -21.867333) (xy 182.305502 -21.818698) (xy 182.285579 -21.766607) (xy 182.273453 -21.71217)
			(xy 182.269382 -21.656548) (xy 179.526544 -21.656548) (xy 179.52705 -21.657655) (xy 179.542412 -21.709957)
			(xy 179.550175 -21.763912) (xy 179.550568 -21.791168) (xy 179.550458 -21.80474) (xy 179.548554 -21.831817)
			(xy 179.546758 -21.84527) (xy 179.54514 -21.859736) (xy 179.549266 -21.888539) (xy 179.561344 -21.91501)
			(xy 179.580395 -21.937003) (xy 179.604873 -21.952733) (xy 179.632793 -21.960925) (xy 179.647342 -21.961348)
			(xy 181.48808 -21.961348) (xy 181.633622 -22.10689) (xy 181.647846 -22.110192) (xy 181.672743 -22.116459)
			(xy 181.720633 -22.134956) (xy 181.765493 -22.159922) (xy 181.806452 -22.190874) (xy 181.824884 -22.208744)
			(xy 182.726076 -23.109936) (xy 184.407554 -23.109936) (xy 184.411625 -23.054314) (xy 184.423751 -22.999877)
			(xy 184.443674 -22.947786) (xy 184.47097 -22.899151) (xy 184.505056 -22.855008) (xy 184.545205 -22.816299)
			(xy 184.590563 -22.783848) (xy 184.640163 -22.758347) (xy 184.692947 -22.74034) (xy 184.74779 -22.73021)
			(xy 184.803524 -22.728173) (xy 184.858961 -22.734273) (xy 184.912918 -22.748379) (xy 184.964247 -22.770191)
			(xy 185.011853 -22.799245) (xy 185.054721 -22.83492) (xy 185.091938 -22.876457) (xy 185.122711 -22.92297)
			(xy 185.146383 -22.973467) (xy 185.162451 -23.026874) (xy 185.170571 -23.08205) (xy 185.17108 -23.109936)
			(xy 185.170571 -23.137822) (xy 185.162451 -23.192998) (xy 185.146383 -23.246405) (xy 185.122711 -23.296902)
			(xy 185.091938 -23.343415) (xy 185.054721 -23.384952) (xy 185.011853 -23.420627) (xy 184.964247 -23.449681)
			(xy 184.912918 -23.471493) (xy 184.858961 -23.485599) (xy 184.803524 -23.491699) (xy 184.74779 -23.489662)
			(xy 184.692947 -23.479532) (xy 184.640163 -23.461525) (xy 184.590563 -23.436024) (xy 184.545205 -23.403573)
			(xy 184.505056 -23.364864) (xy 184.47097 -23.320721) (xy 184.443674 -23.272086) (xy 184.423751 -23.219995)
			(xy 184.411625 -23.165558) (xy 184.407554 -23.109936) (xy 182.726076 -23.109936) (xy 184.364884 -24.748744)
			(xy 184.385009 -24.769594) (xy 184.419109 -24.816444) (xy 184.445458 -24.868053) (xy 184.463407 -24.923149)
			(xy 184.472513 -24.980375) (xy 184.473088 -25.009348) (xy 184.473088 -26.812494) (xy 184.957212 -27.296618)
			(xy 184.967572 -27.306266) (xy 184.992342 -27.319948) (xy 185.019915 -27.326314) (xy 185.048177 -27.324875)
			(xy 185.074961 -27.315743) (xy 185.098214 -27.299616) (xy 185.10758 -27.288998) (xy 185.125811 -27.267528)
			(xy 185.167508 -27.229665) (xy 185.214316 -27.198339) (xy 185.265218 -27.174228) (xy 185.319109 -27.157857)
			(xy 185.37482 -27.14958) (xy 185.402982 -27.149044) (xy 185.430235 -27.149529) (xy 185.484188 -27.157283)
			(xy 185.536487 -27.172636) (xy 185.58607 -27.195275) (xy 185.631926 -27.22474) (xy 185.673122 -27.260431)
			(xy 185.70882 -27.301621) (xy 185.738293 -27.347472) (xy 185.760941 -27.397051) (xy 185.776303 -27.449348)
			(xy 185.784067 -27.503299) (xy 185.78449 -27.530552) (xy 185.783989 -27.558716) (xy 185.775718 -27.614434)
			(xy 185.759347 -27.668332) (xy 185.735233 -27.719238) (xy 185.703899 -27.766047) (xy 185.666026 -27.807743)
			(xy 185.644536 -27.825954) (xy 185.633847 -27.835264) (xy 185.617651 -27.858515) (xy 185.60848 -27.885326)
			(xy 185.607042 -27.913624) (xy 185.613448 -27.941226) (xy 185.627202 -27.965999) (xy 185.636916 -27.976322)
			(xy 187.156852 -29.496258)
		)
		(stroke
			(width 0)
			(type solid)
		)
		(fill yes)
		(layer "In2.Cu")
		(net "GND")
	)
	(gr_poly
		(pts
			(xy 404.867364 -194.569588) (xy 404.867364 -192.18402) (xy 404.344124 -191.66078) (xy 403.808946 -191.66078)
			(xy 403.175724 -192.294002) (xy 398.845786 -192.294002) (xy 398.83163 -192.294467) (xy 398.804407 -192.302245)
			(xy 398.780366 -192.317197) (xy 398.761354 -192.338176) (xy 398.748833 -192.363569) (xy 398.743765 -192.391424)
			(xy 398.74654 -192.419599) (xy 398.751298 -192.43294) (xy 398.759762 -192.455334) (xy 398.771639 -192.501711)
			(xy 398.77761 -192.549211) (xy 398.777968 -192.573148) (xy 398.777968 -192.57899) (xy 398.77817 -192.592362)
			(xy 398.784725 -192.618282) (xy 398.797783 -192.641612) (xy 398.816448 -192.660753) (xy 398.839442 -192.674394)
			(xy 398.865189 -192.681599) (xy 398.878552 -192.682114) (xy 398.905637 -192.682841) (xy 398.9592 -192.691005)
			(xy 399.011068 -192.706666) (xy 399.060199 -192.729508) (xy 399.105604 -192.759071) (xy 399.14637 -192.79476)
			(xy 399.181676 -192.835859) (xy 399.210813 -192.881539) (xy 399.233193 -192.930882) (xy 399.248367 -192.982895)
			(xy 399.25603 -193.036531) (xy 399.256504 -193.063622) (xy 399.256136 -193.086924) (xy 399.250424 -193.133178)
			(xy 399.239125 -193.178392) (xy 399.231104 -193.200274) (xy 399.226089 -193.214865) (xy 399.224151 -193.245644)
			(xy 399.231487 -193.275598) (xy 399.247428 -193.301998) (xy 399.270522 -193.322437) (xy 399.298663 -193.335052)
			(xy 399.313908 -193.337434) (xy 399.341305 -193.341274) (xy 399.394674 -193.355836) (xy 399.445379 -193.377954)
			(xy 399.492359 -193.407165) (xy 399.534626 -193.442855) (xy 399.571295 -193.484276) (xy 399.601597 -193.530559)
			(xy 399.624895 -193.580733) (xy 399.640702 -193.633747) (xy 399.648686 -193.688488) (xy 399.649188 -193.716148)
			(xy 399.648702 -193.743399) (xy 399.640946 -193.797347) (xy 399.625591 -193.849642) (xy 399.602949 -193.899219)
			(xy 399.573483 -193.945069) (xy 399.537792 -193.98626) (xy 399.496601 -194.021951) (xy 399.450751 -194.051417)
			(xy 399.401174 -194.074059) (xy 399.348879 -194.089414) (xy 399.294931 -194.09717) (xy 399.240429 -194.09717)
			(xy 399.186481 -194.089414) (xy 399.134186 -194.074059) (xy 399.084609 -194.051417) (xy 399.038759 -194.021951)
			(xy 398.997568 -193.98626) (xy 398.961877 -193.945069) (xy 398.932411 -193.899219) (xy 398.909769 -193.849642)
			(xy 398.894414 -193.797347) (xy 398.886658 -193.743399) (xy 398.886172 -193.716148) (xy 398.886535 -193.692845)
			(xy 398.892239 -193.646589) (xy 398.90353 -193.60137) (xy 398.911572 -193.579496) (xy 398.916583 -193.564908)
			(xy 398.918514 -193.534138) (xy 398.911174 -193.504194) (xy 398.895231 -193.477805) (xy 398.872139 -193.457377)
			(xy 398.844002 -193.444773) (xy 398.828768 -193.442336) (xy 398.801373 -193.438495) (xy 398.748009 -193.423929)
			(xy 398.697308 -193.401809) (xy 398.650334 -193.372597) (xy 398.608072 -193.336906) (xy 398.571409 -193.295485)
			(xy 398.541113 -193.249203) (xy 398.51782 -193.19903) (xy 398.502018 -193.146018) (xy 398.494039 -193.09128)
			(xy 398.493488 -193.063622) (xy 398.493488 -193.05778) (xy 398.493282 -193.044412) (xy 398.486721 -193.018504)
			(xy 398.47366 -192.995186) (xy 398.454994 -192.976058) (xy 398.432003 -192.962431) (xy 398.406262 -192.955239)
			(xy 398.392904 -192.954656) (xy 398.365817 -192.953933) (xy 398.31225 -192.945774) (xy 398.260377 -192.930118)
			(xy 398.211241 -192.907279) (xy 398.165831 -192.877717) (xy 398.125061 -192.842027) (xy 398.089752 -192.800927)
			(xy 398.060613 -192.755244) (xy 398.038232 -192.705898) (xy 398.023059 -192.653881) (xy 398.015399 -192.60024)
			(xy 398.014952 -192.573148) (xy 398.015327 -192.549212) (xy 398.021311 -192.501717) (xy 398.033179 -192.45534)
			(xy 398.041622 -192.43294) (xy 398.046393 -192.419601) (xy 398.049167 -192.391421) (xy 398.044098 -192.363561)
			(xy 398.031576 -192.338163) (xy 398.012563 -192.317179) (xy 397.988519 -192.302221) (xy 397.961292 -192.294438)
			(xy 397.947134 -192.294002) (xy 387.117844 -192.294002) (xy 384.148076 -189.324234) (xy 384.148076 -187.182506)
			(xy 377.295918 -180.330348) (xy 373.3292 -180.330348) (xy 372.5672 -181.092348) (xy 372.5672 -181.381251)
			(xy 372.910346 -181.381251) (xy 372.910346 -181.326749) (xy 372.918102 -181.2728) (xy 372.933456 -181.220505)
			(xy 372.956095 -181.170927) (xy 372.98556 -181.125075) (xy 373.021249 -181.083882) (xy 373.062438 -181.048188)
			(xy 373.108286 -181.018718) (xy 373.157862 -180.996072) (xy 373.210155 -180.980711) (xy 373.264103 -180.972949)
			(xy 373.291354 -180.97246) (xy 373.319727 -180.972978) (xy 373.375847 -180.981391) (xy 373.430102 -180.998023)
			(xy 373.481295 -181.022507) (xy 373.528297 -181.054303) (xy 373.570071 -181.09271) (xy 373.605696 -181.136881)
			(xy 373.634386 -181.185841) (xy 373.64543 -181.211982) (xy 373.649555 -181.221205) (xy 373.663696 -181.235614)
			(xy 373.682312 -181.243426) (xy 373.7025 -181.243423) (xy 373.711978 -181.239922) (xy 373.743057 -181.227621)
			(xy 373.807615 -181.210305) (xy 373.873884 -181.201579) (xy 373.907304 -181.20106) (xy 373.907812 -181.20106)
			(xy 373.941031 -181.201606) (xy 374.006903 -181.210264) (xy 374.071088 -181.227419) (xy 374.132496 -181.252778)
			(xy 374.161558 -181.268878) (xy 375.08561 -181.802532) (xy 375.114227 -181.819663) (xy 375.167141 -181.860264)
			(xy 375.214298 -181.90743) (xy 375.25489 -181.960352) (xy 375.288221 -182.018122) (xy 375.313719 -182.079752)
			(xy 375.330949 -182.144184) (xy 375.3358 -182.177182) (xy 375.337563 -182.187112) (xy 375.347644 -182.204558)
			(xy 375.363672 -182.216767) (xy 375.383168 -182.221853) (xy 375.393204 -182.22087) (xy 375.406657 -182.219077)
			(xy 375.433734 -182.217171) (xy 375.447306 -182.21706) (xy 375.474555 -182.217611) (xy 375.528497 -182.225367)
			(xy 375.580787 -182.240721) (xy 375.630359 -182.263361) (xy 375.676205 -182.292825) (xy 375.717391 -182.328513)
			(xy 375.753079 -182.3697) (xy 375.782542 -182.415546) (xy 375.805181 -182.465119) (xy 375.820534 -182.517409)
			(xy 375.82829 -182.571351) (xy 375.82829 -182.625849) (xy 375.820534 -182.679791) (xy 375.805181 -182.732081)
			(xy 375.782542 -182.781654) (xy 375.753079 -182.8275) (xy 375.717391 -182.868687) (xy 375.676205 -182.904375)
			(xy 375.630359 -182.933839) (xy 375.580787 -182.956479) (xy 375.528497 -182.971833) (xy 375.474555 -182.979589)
			(xy 375.447306 -182.980076) (xy 375.418933 -182.979569) (xy 375.362813 -182.971152) (xy 375.30856 -182.954516)
			(xy 375.257368 -182.93003) (xy 375.210366 -182.898232) (xy 375.168592 -182.859824) (xy 375.132966 -182.815654)
			(xy 375.104275 -182.766695) (xy 375.09323 -182.740554) (xy 375.089063 -182.731357) (xy 375.07493 -182.716961)
			(xy 375.056331 -182.709146) (xy 375.036158 -182.709128) (xy 375.026682 -182.712614) (xy 374.995609 -182.724929)
			(xy 374.931047 -182.742239) (xy 374.864777 -182.75096) (xy 374.831356 -182.751476) (xy 374.830848 -182.751476)
			(xy 374.797629 -182.750942) (xy 374.731757 -182.74228) (xy 374.667571 -182.725122) (xy 374.606164 -182.699759)
			(xy 374.577102 -182.683658) (xy 373.65305 -182.150004) (xy 373.624423 -182.132889) (xy 373.571507 -182.092287)
			(xy 373.524348 -182.04512) (xy 373.483757 -181.992196) (xy 373.450428 -181.934422) (xy 373.424932 -181.872789)
			(xy 373.407708 -181.808353) (xy 373.40286 -181.775354) (xy 373.401115 -181.765418) (xy 373.391034 -181.747964)
			(xy 373.374999 -181.735753) (xy 373.355494 -181.730676) (xy 373.345456 -181.731666) (xy 373.332002 -181.733453)
			(xy 373.304926 -181.735363) (xy 373.291354 -181.735476) (xy 373.264103 -181.735051) (xy 373.210155 -181.727289)
			(xy 373.157862 -181.711928) (xy 373.108286 -181.689282) (xy 373.062438 -181.659812) (xy 373.021249 -181.624118)
			(xy 372.98556 -181.582925) (xy 372.956095 -181.537073) (xy 372.933456 -181.487495) (xy 372.918102 -181.4352)
			(xy 372.910346 -181.381251) (xy 372.5672 -181.381251) (xy 372.5672 -182.329836) (xy 370.26596 -184.631076)
			(xy 370.265706 -184.651396) (xy 370.264731 -184.677967) (xy 370.263885 -184.683251) (xy 372.097546 -184.683251)
			(xy 372.097546 -184.628749) (xy 372.105302 -184.5748) (xy 372.120656 -184.522505) (xy 372.143295 -184.472927)
			(xy 372.17276 -184.427075) (xy 372.208449 -184.385882) (xy 372.249638 -184.350188) (xy 372.295486 -184.320718)
			(xy 372.345062 -184.298072) (xy 372.397355 -184.282711) (xy 372.451303 -184.274949) (xy 372.478554 -184.27446)
			(xy 372.506927 -184.274978) (xy 372.563047 -184.283391) (xy 372.617302 -184.300023) (xy 372.668495 -184.324507)
			(xy 372.715497 -184.356303) (xy 372.757271 -184.39471) (xy 372.792896 -184.438881) (xy 372.821586 -184.487841)
			(xy 372.83263 -184.513982) (xy 372.836755 -184.523205) (xy 372.850896 -184.537614) (xy 372.869512 -184.545426)
			(xy 372.8897 -184.545423) (xy 372.899178 -184.541922) (xy 372.930257 -184.529621) (xy 372.994815 -184.512305)
			(xy 373.061084 -184.503579) (xy 373.094504 -184.50306) (xy 373.095012 -184.50306) (xy 373.128231 -184.503606)
			(xy 373.194103 -184.512264) (xy 373.258288 -184.529419) (xy 373.319696 -184.554778) (xy 373.348758 -184.570878)
			(xy 374.27281 -185.104532) (xy 374.301427 -185.121663) (xy 374.354341 -185.162264) (xy 374.401498 -185.20943)
			(xy 374.44209 -185.262352) (xy 374.475421 -185.320122) (xy 374.500919 -185.381752) (xy 374.518149 -185.446184)
			(xy 374.523 -185.479182) (xy 374.524763 -185.489112) (xy 374.534844 -185.506558) (xy 374.550872 -185.518767)
			(xy 374.570368 -185.523853) (xy 374.580404 -185.52287) (xy 374.593857 -185.521077) (xy 374.620934 -185.519171)
			(xy 374.634506 -185.51906) (xy 374.661755 -185.519611) (xy 374.715697 -185.527367) (xy 374.767987 -185.542721)
			(xy 374.817559 -185.565361) (xy 374.863405 -185.594825) (xy 374.904591 -185.630513) (xy 374.940279 -185.6717)
			(xy 374.969742 -185.717546) (xy 374.992381 -185.767119) (xy 375.007734 -185.819409) (xy 375.01549 -185.873351)
			(xy 375.01549 -185.927849) (xy 375.007734 -185.981791) (xy 374.992381 -186.034081) (xy 374.982596 -186.055508)
			(xy 380.051562 -186.055508) (xy 380.055633 -185.999886) (xy 380.067759 -185.945449) (xy 380.087682 -185.893358)
			(xy 380.114978 -185.844723) (xy 380.149064 -185.80058) (xy 380.189213 -185.761871) (xy 380.234571 -185.72942)
			(xy 380.284171 -185.703919) (xy 380.336955 -185.685912) (xy 380.391798 -185.675782) (xy 380.447532 -185.673745)
			(xy 380.502969 -185.679845) (xy 380.556926 -185.693951) (xy 380.608255 -185.715763) (xy 380.655861 -185.744817)
			(xy 380.698729 -185.780492) (xy 380.735946 -185.822029) (xy 380.766719 -185.868542) (xy 380.790391 -185.919039)
			(xy 380.806459 -185.972446) (xy 380.814579 -186.027622) (xy 380.815088 -186.055508) (xy 380.814579 -186.083394)
			(xy 380.806459 -186.13857) (xy 380.790391 -186.191977) (xy 380.766719 -186.242474) (xy 380.735946 -186.288987)
			(xy 380.698729 -186.330524) (xy 380.655861 -186.366199) (xy 380.608255 -186.395253) (xy 380.556926 -186.417065)
			(xy 380.502969 -186.431171) (xy 380.447532 -186.437271) (xy 380.391798 -186.435234) (xy 380.336955 -186.425104)
			(xy 380.284171 -186.407097) (xy 380.234571 -186.381596) (xy 380.189213 -186.349145) (xy 380.149064 -186.310436)
			(xy 380.114978 -186.266293) (xy 380.087682 -186.217658) (xy 380.067759 -186.165567) (xy 380.055633 -186.11113)
			(xy 380.051562 -186.055508) (xy 374.982596 -186.055508) (xy 374.969742 -186.083654) (xy 374.940279 -186.1295)
			(xy 374.904591 -186.170687) (xy 374.863405 -186.206375) (xy 374.817559 -186.235839) (xy 374.767987 -186.258479)
			(xy 374.715697 -186.273833) (xy 374.661755 -186.281589) (xy 374.634506 -186.282076) (xy 374.606133 -186.281569)
			(xy 374.550013 -186.273152) (xy 374.49576 -186.256516) (xy 374.444568 -186.23203) (xy 374.397566 -186.200232)
			(xy 374.355792 -186.161824) (xy 374.320166 -186.117654) (xy 374.291475 -186.068695) (xy 374.28043 -186.042554)
			(xy 374.276263 -186.033357) (xy 374.26213 -186.018961) (xy 374.243531 -186.011146) (xy 374.223358 -186.011128)
			(xy 374.213882 -186.014614) (xy 374.182809 -186.026929) (xy 374.118247 -186.044239) (xy 374.051977 -186.05296)
			(xy 374.018556 -186.053476) (xy 374.018048 -186.053476) (xy 373.984829 -186.052942) (xy 373.918957 -186.04428)
			(xy 373.854771 -186.027122) (xy 373.793364 -186.001759) (xy 373.764302 -185.985658) (xy 372.84025 -185.452004)
			(xy 372.811623 -185.434889) (xy 372.758707 -185.394287) (xy 372.711548 -185.34712) (xy 372.670957 -185.294196)
			(xy 372.637628 -185.236422) (xy 372.612132 -185.174789) (xy 372.594908 -185.110353) (xy 372.59006 -185.077354)
			(xy 372.588315 -185.067418) (xy 372.578234 -185.049964) (xy 372.562199 -185.037753) (xy 372.542694 -185.032676)
			(xy 372.532656 -185.033666) (xy 372.519202 -185.035453) (xy 372.492126 -185.037363) (xy 372.478554 -185.037476)
			(xy 372.451303 -185.037051) (xy 372.397355 -185.029289) (xy 372.345062 -185.013928) (xy 372.295486 -184.991282)
			(xy 372.249638 -184.961812) (xy 372.208449 -184.926118) (xy 372.17276 -184.884925) (xy 372.143295 -184.839073)
			(xy 372.120656 -184.789495) (xy 372.105302 -184.7372) (xy 372.097546 -184.683251) (xy 370.263885 -184.683251)
			(xy 370.25633 -184.730468) (xy 370.240721 -184.781295) (xy 370.218208 -184.829462) (xy 370.189225 -184.874037)
			(xy 370.154334 -184.914157) (xy 370.114211 -184.949045) (xy 370.069634 -184.978024) (xy 370.021464 -185.000533)
			(xy 369.970636 -185.016137) (xy 369.918134 -185.024534) (xy 369.891564 -185.025538) (xy 369.871244 -185.025792)
			(xy 369.676172 -185.220864) (xy 369.665965 -185.231817) (xy 369.651843 -185.258199) (xy 369.645971 -185.287541)
			(xy 369.648853 -185.317326) (xy 369.660242 -185.344998) (xy 369.679161 -185.368183) (xy 369.703985 -185.384891)
			(xy 369.732587 -185.39369) (xy 369.747546 -185.394346) (xy 369.774714 -185.394951) (xy 369.82847 -185.402909)
			(xy 369.880552 -185.418415) (xy 369.929907 -185.441156) (xy 369.975535 -185.470671) (xy 370.016512 -185.506362)
			(xy 370.05201 -185.547507) (xy 370.081309 -185.593274) (xy 370.103816 -185.642735) (xy 370.119077 -185.69489)
			(xy 370.126781 -185.748683) (xy 370.127276 -185.775854) (xy 370.12679 -185.803105) (xy 370.119034 -185.857053)
			(xy 370.103679 -185.909348) (xy 370.081037 -185.958925) (xy 370.051571 -186.004775) (xy 370.01588 -186.045966)
			(xy 369.974689 -186.081657) (xy 369.928839 -186.111123) (xy 369.879262 -186.133765) (xy 369.826967 -186.14912)
			(xy 369.773019 -186.156876) (xy 369.718517 -186.156876) (xy 369.664569 -186.14912) (xy 369.612274 -186.133765)
			(xy 369.562697 -186.111123) (xy 369.516847 -186.081657) (xy 369.475656 -186.045966) (xy 369.439965 -186.004775)
			(xy 369.410499 -185.958925) (xy 369.387857 -185.909348) (xy 369.372502 -185.857053) (xy 369.364746 -185.803105)
			(xy 369.36426 -185.775854) (xy 369.364964 -185.743059) (xy 369.3762 -185.678437) (xy 369.386612 -185.64733)
			(xy 369.397534 -185.61685) (xy 369.33886 -185.558176) (xy 369.243356 -185.65368) (xy 369.172581 -187.71489)
			(xy 369.84813 -187.71489) (xy 369.848588 -187.687829) (xy 369.856255 -187.634252) (xy 369.871419 -187.582297)
			(xy 369.893775 -187.533008) (xy 369.922876 -187.487374) (xy 369.958135 -187.446312) (xy 369.978178 -187.428124)
			(xy 369.988628 -187.418318) (xy 370.004113 -187.394223) (xy 370.012298 -187.366775) (xy 370.01254 -187.338134)
			(xy 370.00482 -187.310552) (xy 369.989744 -187.286198) (xy 369.979448 -187.276232) (xy 369.960047 -187.258099)
			(xy 369.925991 -187.217353) (xy 369.897921 -187.172273) (xy 369.876382 -187.123734) (xy 369.861789 -187.072674)
			(xy 369.854427 -187.020082) (xy 369.853972 -186.99353) (xy 369.854486 -186.966592) (xy 369.862063 -186.913251)
			(xy 369.877068 -186.861507) (xy 369.899205 -186.812389) (xy 369.928033 -186.766874) (xy 369.962978 -186.725867)
			(xy 370.003345 -186.690186) (xy 370.04833 -186.660539) (xy 370.09704 -186.637517) (xy 370.148504 -186.621576)
			(xy 370.175028 -186.616848) (xy 370.188069 -186.614283) (xy 370.212312 -186.603417) (xy 370.232929 -186.586664)
			(xy 370.248525 -186.565157) (xy 370.258042 -186.540354) (xy 370.260837 -186.513936) (xy 370.256719 -186.487691)
			(xy 370.251736 -186.47537) (xy 370.241367 -186.450871) (xy 370.226766 -186.399716) (xy 370.219412 -186.347029)
			(xy 370.21897 -186.32043) (xy 370.219456 -186.293179) (xy 370.227212 -186.239231) (xy 370.242567 -186.186936)
			(xy 370.265209 -186.137359) (xy 370.294675 -186.091509) (xy 370.330366 -186.050318) (xy 370.371557 -186.014627)
			(xy 370.417407 -185.985161) (xy 370.466984 -185.962519) (xy 370.519279 -185.947164) (xy 370.573227 -185.939408)
			(xy 370.627729 -185.939408) (xy 370.681677 -185.947164) (xy 370.733972 -185.962519) (xy 370.783549 -185.985161)
			(xy 370.829399 -186.014627) (xy 370.87059 -186.050318) (xy 370.906281 -186.091509) (xy 370.935747 -186.137359)
			(xy 370.958389 -186.186936) (xy 370.973744 -186.239231) (xy 370.9815 -186.293179) (xy 370.981986 -186.32043)
			(xy 370.981562 -186.347371) (xy 370.973977 -186.400718) (xy 370.958961 -186.452466) (xy 370.936814 -186.501587)
			(xy 370.907976 -186.547103) (xy 370.873021 -186.588109) (xy 370.832644 -186.623789) (xy 370.787649 -186.653433)
			(xy 370.73893 -186.676452) (xy 370.687458 -186.692387) (xy 370.66093 -186.697112) (xy 370.647897 -186.699704)
			(xy 370.623663 -186.710572) (xy 370.603052 -186.727323) (xy 370.58746 -186.748824) (xy 370.577941 -186.773619)
			(xy 370.57514 -186.80003) (xy 370.579246 -186.82627) (xy 370.584222 -186.83859) (xy 370.592486 -186.858148)
			(xy 374.039382 -186.858148) (xy 374.043453 -186.802526) (xy 374.055579 -186.748089) (xy 374.075502 -186.695998)
			(xy 374.102798 -186.647363) (xy 374.136884 -186.60322) (xy 374.177033 -186.564511) (xy 374.222391 -186.53206)
			(xy 374.271991 -186.506559) (xy 374.324775 -186.488552) (xy 374.379618 -186.478422) (xy 374.435352 -186.476385)
			(xy 374.490789 -186.482485) (xy 374.544746 -186.496591) (xy 374.596075 -186.518403) (xy 374.643681 -186.547457)
			(xy 374.686549 -186.583132) (xy 374.723766 -186.624669) (xy 374.754539 -186.671182) (xy 374.778211 -186.721679)
			(xy 374.794279 -186.775086) (xy 374.802399 -186.830262) (xy 374.802908 -186.858148) (xy 374.802399 -186.886034)
			(xy 374.794279 -186.94121) (xy 374.778211 -186.994617) (xy 374.754539 -187.045114) (xy 374.723766 -187.091627)
			(xy 374.686549 -187.133164) (xy 374.643681 -187.168839) (xy 374.596075 -187.197893) (xy 374.544746 -187.219705)
			(xy 374.490789 -187.233811) (xy 374.435352 -187.239911) (xy 374.379618 -187.237874) (xy 374.324775 -187.227744)
			(xy 374.271991 -187.209737) (xy 374.222391 -187.184236) (xy 374.177033 -187.151785) (xy 374.136884 -187.113076)
			(xy 374.102798 -187.068933) (xy 374.075502 -187.020298) (xy 374.055579 -186.968207) (xy 374.043453 -186.91377)
			(xy 374.039382 -186.858148) (xy 370.592486 -186.858148) (xy 370.594576 -186.863095) (xy 370.609184 -186.914246)
			(xy 370.616543 -186.966931) (xy 370.616988 -186.99353) (xy 370.61647 -187.020589) (xy 370.608814 -187.074163)
			(xy 370.593662 -187.126117) (xy 370.571317 -187.175406) (xy 370.542227 -187.221041) (xy 370.506978 -187.262106)
			(xy 370.48694 -187.280296) (xy 370.476476 -187.290085) (xy 370.461005 -187.314188) (xy 370.452829 -187.341638)
			(xy 370.45259 -187.370279) (xy 370.460309 -187.397861) (xy 370.475378 -187.422218) (xy 370.48567 -187.432188)
			(xy 370.505035 -187.450357) (xy 370.539094 -187.491096) (xy 370.567168 -187.536168) (xy 370.588714 -187.584701)
			(xy 370.603314 -187.635754) (xy 370.610686 -187.68834) (xy 370.611146 -187.71489) (xy 370.61066 -187.742141)
			(xy 370.602904 -187.796089) (xy 370.587549 -187.848384) (xy 370.564907 -187.897961) (xy 370.535441 -187.943811)
			(xy 370.49975 -187.985002) (xy 370.458559 -188.020693) (xy 370.412709 -188.050159) (xy 370.363132 -188.072801)
			(xy 370.310837 -188.088156) (xy 370.256889 -188.095912) (xy 370.202387 -188.095912) (xy 370.148439 -188.088156)
			(xy 370.096144 -188.072801) (xy 370.046567 -188.050159) (xy 370.000717 -188.020693) (xy 369.959526 -187.985002)
			(xy 369.923835 -187.943811) (xy 369.894369 -187.897961) (xy 369.871727 -187.848384) (xy 369.856372 -187.796089)
			(xy 369.848616 -187.742141) (xy 369.84813 -187.71489) (xy 369.172581 -187.71489) (xy 369.152696 -188.29401)
			(xy 382.992882 -188.29401) (xy 382.996953 -188.238388) (xy 383.009079 -188.183951) (xy 383.029002 -188.13186)
			(xy 383.056298 -188.083225) (xy 383.090384 -188.039082) (xy 383.130533 -188.000373) (xy 383.175891 -187.967922)
			(xy 383.225491 -187.942421) (xy 383.278275 -187.924414) (xy 383.333118 -187.914284) (xy 383.388852 -187.912247)
			(xy 383.444289 -187.918347) (xy 383.498246 -187.932453) (xy 383.549575 -187.954265) (xy 383.597181 -187.983319)
			(xy 383.640049 -188.018994) (xy 383.677266 -188.060531) (xy 383.708039 -188.107044) (xy 383.731711 -188.157541)
			(xy 383.747779 -188.210948) (xy 383.755899 -188.266124) (xy 383.756408 -188.29401) (xy 383.755899 -188.321896)
			(xy 383.747779 -188.377072) (xy 383.731711 -188.430479) (xy 383.708039 -188.480976) (xy 383.677266 -188.527489)
			(xy 383.640049 -188.569026) (xy 383.597181 -188.604701) (xy 383.549575 -188.633755) (xy 383.498246 -188.655567)
			(xy 383.444289 -188.669673) (xy 383.388852 -188.675773) (xy 383.333118 -188.673736) (xy 383.278275 -188.663606)
			(xy 383.225491 -188.645599) (xy 383.175891 -188.620098) (xy 383.130533 -188.587647) (xy 383.090384 -188.548938)
			(xy 383.056298 -188.504795) (xy 383.029002 -188.45616) (xy 383.009079 -188.404069) (xy 382.996953 -188.349632)
			(xy 382.992882 -188.29401) (xy 369.152696 -188.29401) (xy 369.105688 -189.66307) (xy 369.105688 -190.3222)
			(xy 369.738656 -190.955168) (xy 369.860068 -190.955168) (xy 373.973598 -195.068698) (xy 404.368254 -195.068698)
		)
		(stroke
			(width 0)
			(type solid)
		)
		(fill yes)
		(layer "In2.Cu")
		(net "PVNN_TERM_CPU0")
	)
	(gr_poly
		(pts
			(xy 457.120752 -17.737074) (xy 453.69988 -14.315948) (xy 451.79488 -14.315948) (xy 451.021196 -15.089632)
			(xy 451.033642 -15.12062) (xy 451.042255 -15.143201) (xy 451.054361 -15.18999) (xy 451.060463 -15.237933)
			(xy 451.06082 -15.262098) (xy 451.060333 -15.289672) (xy 451.052392 -15.344245) (xy 451.036673 -15.397106)
			(xy 451.013505 -15.447152) (xy 450.983372 -15.493339) (xy 450.946901 -15.534706) (xy 450.9262 -15.552928)
			(xy 450.915303 -15.562827) (xy 450.89923 -15.587477) (xy 450.890846 -15.615685) (xy 450.890846 -15.645112)
			(xy 450.899229 -15.67332) (xy 450.915301 -15.697971) (xy 450.9262 -15.707868) (xy 450.946906 -15.726084)
			(xy 450.983372 -15.767456) (xy 451.013503 -15.813646) (xy 451.036672 -15.863692) (xy 451.052396 -15.916551)
			(xy 451.060349 -15.971124) (xy 451.06082 -15.998698) (xy 451.060334 -16.02595) (xy 451.052578 -16.079898)
			(xy 451.037223 -16.132194) (xy 451.014582 -16.181772) (xy 450.985116 -16.227624) (xy 450.949425 -16.268815)
			(xy 450.908235 -16.304508) (xy 450.862384 -16.333976) (xy 450.812807 -16.356618) (xy 450.760512 -16.371975)
			(xy 450.706564 -16.379733) (xy 450.679312 -16.380206) (xy 450.651565 -16.379701) (xy 450.596657 -16.37165)
			(xy 450.543495 -16.355731) (xy 450.493199 -16.33228) (xy 450.44683 -16.30179) (xy 450.405367 -16.264906)
			(xy 450.369683 -16.222404) (xy 450.340532 -16.175183) (xy 450.318528 -16.124237) (xy 450.304136 -16.070641)
			(xy 450.300344 -16.043148) (xy 450.298186 -16.029072) (xy 450.287146 -16.002835) (xy 450.269296 -15.980662)
			(xy 450.246022 -15.964272) (xy 450.21913 -15.95494) (xy 450.190708 -15.953387) (xy 450.162959 -15.959735)
			(xy 450.138039 -15.973492) (xy 450.127624 -15.983204) (xy 449.38188 -16.728948) (xy 449.38188 -18.019268)
			(xy 449.382367 -18.033625) (xy 449.39035 -18.061206) (xy 449.405693 -18.085476) (xy 449.427186 -18.104516)
			(xy 449.453128 -18.116822) (xy 449.48147 -18.121422) (xy 449.509973 -18.117952) (xy 449.523358 -18.11274)
			(xy 449.547172 -18.103003) (xy 449.596763 -18.089303) (xy 449.647747 -18.082409) (xy 449.673472 -18.082006)
			(xy 449.700725 -18.082467) (xy 449.754677 -18.090221) (xy 449.806976 -18.105574) (xy 449.856558 -18.128214)
			(xy 449.902413 -18.15768) (xy 449.943608 -18.193372) (xy 449.979303 -18.234564) (xy 450.008773 -18.280417)
			(xy 450.031416 -18.329997) (xy 450.046773 -18.382295) (xy 450.054531 -18.436247) (xy 450.054531 -18.490753)
			(xy 450.046773 -18.544705) (xy 450.031416 -18.597003) (xy 450.018255 -18.62582) (xy 450.615302 -18.62582)
			(xy 450.619373 -18.570198) (xy 450.631499 -18.515761) (xy 450.651422 -18.46367) (xy 450.678718 -18.415035)
			(xy 450.712804 -18.370892) (xy 450.752953 -18.332183) (xy 450.798311 -18.299732) (xy 450.847911 -18.274231)
			(xy 450.900695 -18.256224) (xy 450.955538 -18.246094) (xy 451.011272 -18.244057) (xy 451.066709 -18.250157)
			(xy 451.120666 -18.264263) (xy 451.171995 -18.286075) (xy 451.219601 -18.315129) (xy 451.262469 -18.350804)
			(xy 451.299686 -18.392341) (xy 451.330459 -18.438854) (xy 451.354131 -18.489351) (xy 451.364392 -18.523458)
			(xy 451.682104 -18.523458) (xy 451.682608 -18.495885) (xy 451.690553 -18.441314) (xy 451.70627 -18.388454)
			(xy 451.729433 -18.338408) (xy 451.759559 -18.292218) (xy 451.79602 -18.250845) (xy 451.816724 -18.232628)
			(xy 451.827661 -18.222771) (xy 451.843728 -18.198108) (xy 451.852104 -18.16989) (xy 451.852096 -18.140456)
			(xy 451.843705 -18.112242) (xy 451.827625 -18.087588) (xy 451.816724 -18.077688) (xy 451.796009 -18.059481)
			(xy 451.759538 -18.018112) (xy 451.729405 -17.971922) (xy 451.70624 -17.921873) (xy 451.690525 -17.869009)
			(xy 451.682588 -17.814433) (xy 451.682104 -17.786858) (xy 451.68259 -17.759607) (xy 451.690346 -17.705659)
			(xy 451.705701 -17.653364) (xy 451.728343 -17.603787) (xy 451.757809 -17.557937) (xy 451.7935 -17.516746)
			(xy 451.834691 -17.481055) (xy 451.880541 -17.451589) (xy 451.930118 -17.428947) (xy 451.982413 -17.413592)
			(xy 452.036361 -17.405836) (xy 452.090863 -17.405836) (xy 452.144811 -17.413592) (xy 452.197106 -17.428947)
			(xy 452.246683 -17.451589) (xy 452.292533 -17.481055) (xy 452.333724 -17.516746) (xy 452.369415 -17.557937)
			(xy 452.398881 -17.603787) (xy 452.421523 -17.653364) (xy 452.436878 -17.705659) (xy 452.444634 -17.759607)
			(xy 452.44512 -17.786858) (xy 452.444618 -17.814431) (xy 452.436672 -17.869002) (xy 452.420954 -17.921861)
			(xy 452.39779 -17.971907) (xy 452.367665 -18.018098) (xy 452.331204 -18.059471) (xy 452.3105 -18.077688)
			(xy 452.299645 -18.087629) (xy 452.283572 -18.112268) (xy 452.275183 -18.140464) (xy 452.275176 -18.169882)
			(xy 452.283549 -18.198083) (xy 452.299609 -18.222729) (xy 452.3105 -18.232628) (xy 452.331228 -18.250821)
			(xy 452.367697 -18.292194) (xy 452.397827 -18.338387) (xy 452.42099 -18.388439) (xy 452.436703 -18.441305)
			(xy 452.444637 -18.495882) (xy 452.44512 -18.523458) (xy 452.444634 -18.550709) (xy 452.436878 -18.604657)
			(xy 452.421523 -18.656952) (xy 452.398881 -18.706529) (xy 452.369415 -18.752379) (xy 452.333724 -18.79357)
			(xy 452.292533 -18.829261) (xy 452.246683 -18.858727) (xy 452.197106 -18.881369) (xy 452.144811 -18.896724)
			(xy 452.090863 -18.90448) (xy 452.036361 -18.90448) (xy 451.982413 -18.896724) (xy 451.930118 -18.881369)
			(xy 451.880541 -18.858727) (xy 451.834691 -18.829261) (xy 451.7935 -18.79357) (xy 451.757809 -18.752379)
			(xy 451.728343 -18.706529) (xy 451.705701 -18.656952) (xy 451.690346 -18.604657) (xy 451.68259 -18.550709)
			(xy 451.682104 -18.523458) (xy 451.364392 -18.523458) (xy 451.370199 -18.542758) (xy 451.378319 -18.597934)
			(xy 451.378828 -18.62582) (xy 451.378319 -18.653706) (xy 451.370199 -18.708882) (xy 451.354131 -18.762289)
			(xy 451.330459 -18.812786) (xy 451.299686 -18.859299) (xy 451.262469 -18.900836) (xy 451.219601 -18.936511)
			(xy 451.171995 -18.965565) (xy 451.120666 -18.987377) (xy 451.066709 -19.001483) (xy 451.011272 -19.007583)
			(xy 450.955538 -19.005546) (xy 450.900695 -18.995416) (xy 450.847911 -18.977409) (xy 450.798311 -18.951908)
			(xy 450.752953 -18.919457) (xy 450.712804 -18.880748) (xy 450.678718 -18.836605) (xy 450.651422 -18.78797)
			(xy 450.631499 -18.735879) (xy 450.619373 -18.681442) (xy 450.615302 -18.62582) (xy 450.018255 -18.62582)
			(xy 450.008773 -18.646583) (xy 449.979303 -18.692436) (xy 449.943608 -18.733628) (xy 449.902413 -18.76932)
			(xy 449.856558 -18.798786) (xy 449.806976 -18.821426) (xy 449.754677 -18.836779) (xy 449.700725 -18.844533)
			(xy 449.673472 -18.845022) (xy 449.64775 -18.844595) (xy 449.596772 -18.837682) (xy 449.547182 -18.823996)
			(xy 449.523358 -18.814288) (xy 449.509965 -18.809108) (xy 449.481474 -18.805638) (xy 449.453143 -18.810236)
			(xy 449.427212 -18.822539) (xy 449.40573 -18.841574) (xy 449.390397 -18.865837) (xy 449.382423 -18.893409)
			(xy 449.38188 -18.90776) (xy 449.38188 -19.28749) (xy 449.398164 -19.31169) (xy 449.411812 -19.339348)
			(xy 453.045106 -19.339348) (xy 453.045106 -19.284852) (xy 453.052861 -19.230911) (xy 453.068214 -19.178623)
			(xy 453.090851 -19.129052) (xy 453.120312 -19.083206) (xy 453.155997 -19.04202) (xy 453.197181 -19.006331)
			(xy 453.243024 -18.976866) (xy 453.292593 -18.954225) (xy 453.34488 -18.938868) (xy 453.39882 -18.931108)
			(xy 453.426068 -18.93062) (xy 453.452759 -18.931048) (xy 453.505623 -18.938468) (xy 453.556937 -18.953181)
			(xy 453.6057 -18.9749) (xy 453.650961 -19.003203) (xy 453.671686 -19.020028) (xy 453.683668 -19.029415)
			(xy 453.711676 -19.041295) (xy 453.741941 -19.044396) (xy 453.771777 -19.038442) (xy 453.798534 -19.023963)
			(xy 453.819837 -19.002243) (xy 453.833796 -18.97521) (xy 453.83704 -18.960338) (xy 453.84216 -18.934245)
			(xy 453.858715 -18.883713) (xy 453.882129 -18.83597) (xy 453.911946 -18.791942) (xy 453.94759 -18.752482)
			(xy 453.988368 -18.718356) (xy 454.033492 -18.690223) (xy 454.082085 -18.668631) (xy 454.133206 -18.653996)
			(xy 454.185865 -18.646604) (xy 454.212452 -18.64614) (xy 454.239706 -18.6466) (xy 454.293659 -18.654352)
			(xy 454.34596 -18.669704) (xy 454.395543 -18.692345) (xy 454.441399 -18.721812) (xy 454.482594 -18.757506)
			(xy 454.518288 -18.798701) (xy 454.547755 -18.844557) (xy 454.570396 -18.89414) (xy 454.585748 -18.946441)
			(xy 454.5935 -19.000394) (xy 454.59396 -19.027648) (xy 454.593489 -19.054251) (xy 454.586114 -19.106944)
			(xy 454.571485 -19.1581) (xy 454.549886 -19.206726) (xy 454.521737 -19.251877) (xy 454.487586 -19.292676)
			(xy 454.448093 -19.328331) (xy 454.42632 -19.343624) (xy 454.41484 -19.35196) (xy 454.396633 -19.373702)
			(xy 454.385114 -19.399615) (xy 454.381172 -19.427699) (xy 454.385113 -19.455782) (xy 454.396632 -19.481696)
			(xy 454.414838 -19.503439) (xy 454.42632 -19.511772) (xy 454.448077 -19.527085) (xy 454.487558 -19.562747)
			(xy 454.521704 -19.603547) (xy 454.549852 -19.648694) (xy 454.571456 -19.697312) (xy 454.586099 -19.748461)
			(xy 454.593495 -19.801147) (xy 454.59396 -19.827748) (xy 454.593474 -19.854999) (xy 454.585718 -19.908947)
			(xy 454.570363 -19.961242) (xy 454.547721 -20.010819) (xy 454.518255 -20.056669) (xy 454.482564 -20.09786)
			(xy 454.441373 -20.133551) (xy 454.395523 -20.163017) (xy 454.345946 -20.185659) (xy 454.293651 -20.201014)
			(xy 454.239703 -20.20877) (xy 454.185201 -20.20877) (xy 454.131253 -20.201014) (xy 454.078958 -20.185659)
			(xy 454.029381 -20.163017) (xy 453.983531 -20.133551) (xy 453.94234 -20.09786) (xy 453.906649 -20.056669)
			(xy 453.877183 -20.010819) (xy 453.854541 -19.961242) (xy 453.839186 -19.908947) (xy 453.83143 -19.854999)
			(xy 453.830944 -19.827748) (xy 453.83141 -19.801144) (xy 453.838786 -19.748451) (xy 453.853416 -19.697295)
			(xy 453.875015 -19.64867) (xy 453.903165 -19.603519) (xy 453.937317 -19.56272) (xy 453.97681 -19.527064)
			(xy 453.998584 -19.511772) (xy 454.010068 -19.503441) (xy 454.028274 -19.481698) (xy 454.039793 -19.455783)
			(xy 454.043733 -19.427699) (xy 454.039792 -19.399615) (xy 454.028273 -19.3737) (xy 454.010066 -19.351958)
			(xy 453.998584 -19.343624) (xy 453.99038 -19.338018) (xy 453.974496 -19.326074) (xy 453.966834 -19.319748)
			(xy 453.954892 -19.310292) (xy 453.926864 -19.298389) (xy 453.896573 -19.295278) (xy 453.866711 -19.301235)
			(xy 453.839932 -19.31573) (xy 453.818617 -19.337476) (xy 453.80466 -19.36454) (xy 453.80148 -19.379438)
			(xy 453.796323 -19.405524) (xy 453.779772 -19.456054) (xy 453.756363 -19.503796) (xy 453.72655 -19.547823)
			(xy 453.690911 -19.587284) (xy 453.650136 -19.621411) (xy 453.605017 -19.649545) (xy 453.556427 -19.671139)
			(xy 453.505309 -19.685776) (xy 453.452654 -19.69317) (xy 453.426068 -19.693636) (xy 453.39882 -19.693092)
			(xy 453.34488 -19.685332) (xy 453.292593 -19.669975) (xy 453.243024 -19.647334) (xy 453.197181 -19.617869)
			(xy 453.155997 -19.58218) (xy 453.120312 -19.540994) (xy 453.090851 -19.495148) (xy 453.068214 -19.445577)
			(xy 453.052861 -19.393289) (xy 453.045106 -19.339348) (xy 449.411812 -19.339348) (xy 449.423975 -19.363995)
			(xy 449.441523 -19.41962) (xy 449.450397 -19.477268) (xy 449.450393 -19.535595) (xy 449.441508 -19.593241)
			(xy 449.423952 -19.648863) (xy 449.398132 -19.701163) (xy 449.38188 -19.725386) (xy 449.38188 -20.21078)
			(xy 449.398541 -20.230395) (xy 449.426632 -20.273517) (xy 449.448226 -20.320232) (xy 449.462876 -20.369567)
			(xy 449.470275 -20.420496) (xy 449.470271 -20.471961) (xy 449.462863 -20.522889) (xy 449.448206 -20.572222)
			(xy 449.426604 -20.618933) (xy 449.398507 -20.66205) (xy 449.38188 -20.681696) (xy 449.38188 -21.623528)
			(xy 453.717152 -21.623528) (xy 453.717637 -21.595899) (xy 453.725599 -21.541219) (xy 453.741363 -21.488258)
			(xy 453.764597 -21.438123) (xy 453.794816 -21.391861) (xy 453.83139 -21.35044) (xy 453.873553 -21.314725)
			(xy 453.89673 -21.299678) (xy 453.908805 -21.291585) (xy 453.928135 -21.269892) (xy 453.940583 -21.243638)
			(xy 453.945145 -21.214942) (xy 453.941451 -21.186121) (xy 453.9298 -21.159504) (xy 453.92086 -21.14804)
			(xy 453.90395 -21.127324) (xy 453.875493 -21.082051) (xy 453.85365 -21.033242) (xy 453.838851 -20.981856)
			(xy 453.831387 -20.928905) (xy 453.830944 -20.902168) (xy 453.83143 -20.874917) (xy 453.839186 -20.820969)
			(xy 453.854541 -20.768674) (xy 453.877183 -20.719097) (xy 453.906649 -20.673247) (xy 453.94234 -20.632056)
			(xy 453.983531 -20.596365) (xy 454.029381 -20.566899) (xy 454.078958 -20.544257) (xy 454.131253 -20.528902)
			(xy 454.185201 -20.521146) (xy 454.239703 -20.521146) (xy 454.293651 -20.528902) (xy 454.345946 -20.544257)
			(xy 454.395523 -20.566899) (xy 454.441373 -20.596365) (xy 454.482564 -20.632056) (xy 454.518255 -20.673247)
			(xy 454.547721 -20.719097) (xy 454.570363 -20.768674) (xy 454.585718 -20.820969) (xy 454.593474 -20.874917)
			(xy 454.59396 -20.902168) (xy 454.593513 -20.929798) (xy 454.585549 -20.984482) (xy 454.569782 -21.037446)
			(xy 454.546543 -21.087583) (xy 454.516317 -21.133844) (xy 454.479735 -21.175263) (xy 454.437563 -21.210974)
			(xy 454.414382 -21.226018) (xy 454.402311 -21.234117) (xy 454.382979 -21.255808) (xy 454.370529 -21.282061)
			(xy 454.365967 -21.310756) (xy 454.369661 -21.339576) (xy 454.381312 -21.366193) (xy 454.390252 -21.377656)
			(xy 454.407162 -21.398372) (xy 454.435619 -21.443645) (xy 454.457462 -21.492455) (xy 454.472261 -21.54384)
			(xy 454.479725 -21.596791) (xy 454.480168 -21.623528) (xy 454.479682 -21.650779) (xy 454.471926 -21.704727)
			(xy 454.456571 -21.757022) (xy 454.433929 -21.806599) (xy 454.404463 -21.852449) (xy 454.368772 -21.89364)
			(xy 454.327581 -21.929331) (xy 454.281731 -21.958797) (xy 454.232154 -21.981439) (xy 454.179859 -21.996794)
			(xy 454.125911 -22.00455) (xy 454.071409 -22.00455) (xy 454.017461 -21.996794) (xy 453.965166 -21.981439)
			(xy 453.915589 -21.958797) (xy 453.869739 -21.929331) (xy 453.828548 -21.89364) (xy 453.792857 -21.852449)
			(xy 453.763391 -21.806599) (xy 453.740749 -21.757022) (xy 453.725394 -21.704727) (xy 453.717638 -21.650779)
			(xy 453.717152 -21.623528) (xy 449.38188 -21.623528) (xy 449.38188 -22.426422) (xy 450.115176 -22.426422)
			(xy 450.119247 -22.3708) (xy 450.131373 -22.316363) (xy 450.151296 -22.264272) (xy 450.178592 -22.215637)
			(xy 450.212678 -22.171494) (xy 450.252827 -22.132785) (xy 450.298185 -22.100334) (xy 450.347785 -22.074833)
			(xy 450.400569 -22.056826) (xy 450.455412 -22.046696) (xy 450.511146 -22.044659) (xy 450.566583 -22.050759)
			(xy 450.62054 -22.064865) (xy 450.671869 -22.086677) (xy 450.719475 -22.115731) (xy 450.762343 -22.151406)
			(xy 450.79956 -22.192943) (xy 450.830333 -22.239456) (xy 450.854005 -22.289953) (xy 450.870073 -22.34336)
			(xy 450.878193 -22.398536) (xy 450.878234 -22.400768) (xy 452.115172 -22.400768) (xy 452.119243 -22.345146)
			(xy 452.131369 -22.290709) (xy 452.151292 -22.238618) (xy 452.178588 -22.189983) (xy 452.212674 -22.14584)
			(xy 452.252823 -22.107131) (xy 452.298181 -22.07468) (xy 452.347781 -22.049179) (xy 452.400565 -22.031172)
			(xy 452.455408 -22.021042) (xy 452.511142 -22.019005) (xy 452.566579 -22.025105) (xy 452.620536 -22.039211)
			(xy 452.671865 -22.061023) (xy 452.719471 -22.090077) (xy 452.762339 -22.125752) (xy 452.799556 -22.167289)
			(xy 452.830329 -22.213802) (xy 452.854001 -22.264299) (xy 452.870069 -22.317706) (xy 452.878189 -22.372882)
			(xy 452.878698 -22.400768) (xy 452.878189 -22.428654) (xy 452.870069 -22.48383) (xy 452.854001 -22.537237)
			(xy 452.830329 -22.587734) (xy 452.799556 -22.634247) (xy 452.762339 -22.675784) (xy 452.719471 -22.711459)
			(xy 452.671865 -22.740513) (xy 452.620536 -22.762325) (xy 452.566579 -22.776431) (xy 452.511142 -22.782531)
			(xy 452.455408 -22.780494) (xy 452.400565 -22.770364) (xy 452.347781 -22.752357) (xy 452.298181 -22.726856)
			(xy 452.252823 -22.694405) (xy 452.212674 -22.655696) (xy 452.178588 -22.611553) (xy 452.151292 -22.562918)
			(xy 452.131369 -22.510827) (xy 452.119243 -22.45639) (xy 452.115172 -22.400768) (xy 450.878234 -22.400768)
			(xy 450.878702 -22.426422) (xy 450.878193 -22.454308) (xy 450.870073 -22.509484) (xy 450.854005 -22.562891)
			(xy 450.830333 -22.613388) (xy 450.79956 -22.659901) (xy 450.762343 -22.701438) (xy 450.719475 -22.737113)
			(xy 450.671869 -22.766167) (xy 450.62054 -22.787979) (xy 450.566583 -22.802085) (xy 450.511146 -22.808185)
			(xy 450.455412 -22.806148) (xy 450.400569 -22.796018) (xy 450.347785 -22.778011) (xy 450.298185 -22.75251)
			(xy 450.252827 -22.720059) (xy 450.212678 -22.68135) (xy 450.178592 -22.637207) (xy 450.151296 -22.588572)
			(xy 450.131373 -22.536481) (xy 450.119247 -22.482044) (xy 450.115176 -22.426422) (xy 449.38188 -22.426422)
			(xy 449.38188 -23.019258) (xy 451.351394 -23.019258) (xy 451.355465 -22.963636) (xy 451.367591 -22.909199)
			(xy 451.387514 -22.857108) (xy 451.41481 -22.808473) (xy 451.448896 -22.76433) (xy 451.489045 -22.725621)
			(xy 451.534403 -22.69317) (xy 451.584003 -22.667669) (xy 451.636787 -22.649662) (xy 451.69163 -22.639532)
			(xy 451.747364 -22.637495) (xy 451.802801 -22.643595) (xy 451.856758 -22.657701) (xy 451.908087 -22.679513)
			(xy 451.955693 -22.708567) (xy 451.998561 -22.744242) (xy 452.035778 -22.785779) (xy 452.066551 -22.832292)
			(xy 452.090223 -22.882789) (xy 452.106291 -22.936196) (xy 452.114411 -22.991372) (xy 452.11492 -23.019258)
			(xy 452.114411 -23.047144) (xy 452.106291 -23.10232) (xy 452.090223 -23.155727) (xy 452.066551 -23.206224)
			(xy 452.035778 -23.252737) (xy 451.998561 -23.294274) (xy 451.955693 -23.329949) (xy 451.908087 -23.359003)
			(xy 451.856758 -23.380815) (xy 451.802801 -23.394921) (xy 451.747364 -23.401021) (xy 451.69163 -23.398984)
			(xy 451.636787 -23.388854) (xy 451.584003 -23.370847) (xy 451.534403 -23.345346) (xy 451.489045 -23.312895)
			(xy 451.448896 -23.274186) (xy 451.41481 -23.230043) (xy 451.387514 -23.181408) (xy 451.367591 -23.129317)
			(xy 451.355465 -23.07488) (xy 451.351394 -23.019258) (xy 449.38188 -23.019258) (xy 449.38188 -24.729948)
			(xy 449.52539 -24.873458) (xy 451.376794 -24.873458) (xy 451.380865 -24.817836) (xy 451.392991 -24.763399)
			(xy 451.412914 -24.711308) (xy 451.44021 -24.662673) (xy 451.474296 -24.61853) (xy 451.514445 -24.579821)
			(xy 451.559803 -24.54737) (xy 451.609403 -24.521869) (xy 451.662187 -24.503862) (xy 451.71703 -24.493732)
			(xy 451.772764 -24.491695) (xy 451.828201 -24.497795) (xy 451.882158 -24.511901) (xy 451.933487 -24.533713)
			(xy 451.981093 -24.562767) (xy 452.023961 -24.598442) (xy 452.061178 -24.639979) (xy 452.091951 -24.686492)
			(xy 452.115623 -24.736989) (xy 452.131691 -24.790396) (xy 452.139811 -24.845572) (xy 452.14032 -24.873458)
			(xy 452.139811 -24.901344) (xy 452.131691 -24.95652) (xy 452.115623 -25.009927) (xy 452.091951 -25.060424)
			(xy 452.061178 -25.106937) (xy 452.023961 -25.148474) (xy 451.981093 -25.184149) (xy 451.933487 -25.213203)
			(xy 451.882158 -25.235015) (xy 451.828201 -25.249121) (xy 451.772764 -25.255221) (xy 451.71703 -25.253184)
			(xy 451.662187 -25.243054) (xy 451.609403 -25.225047) (xy 451.559803 -25.199546) (xy 451.514445 -25.167095)
			(xy 451.474296 -25.128386) (xy 451.44021 -25.084243) (xy 451.412914 -25.035608) (xy 451.392991 -24.983517)
			(xy 451.380865 -24.92908) (xy 451.376794 -24.873458) (xy 449.52539 -24.873458) (xy 451.79488 -27.142948)
			(xy 451.79488 -28.937458) (xy 452.799704 -28.937458) (xy 452.800148 -28.911142) (xy 452.80737 -28.859007)
			(xy 452.821685 -28.808359) (xy 452.842821 -28.760157) (xy 452.870378 -28.715315) (xy 452.903833 -28.674684)
			(xy 452.922894 -28.656534) (xy 452.932957 -28.646762) (xy 452.947653 -28.622878) (xy 452.955286 -28.595893)
			(xy 452.955278 -28.56785) (xy 452.94763 -28.54087) (xy 452.932921 -28.516994) (xy 452.922894 -28.507182)
			(xy 452.903805 -28.489057) (xy 452.870328 -28.448435) (xy 452.842759 -28.403592) (xy 452.821622 -28.355383)
			(xy 452.80732 -28.304723) (xy 452.800123 -28.252578) (xy 452.799704 -28.226258) (xy 452.800208 -28.198685)
			(xy 452.808153 -28.144114) (xy 452.82387 -28.091254) (xy 452.847033 -28.041208) (xy 452.877159 -27.995018)
			(xy 452.91362 -27.953645) (xy 452.934324 -27.935428) (xy 452.945261 -27.925571) (xy 452.961328 -27.900908)
			(xy 452.969704 -27.87269) (xy 452.969696 -27.843256) (xy 452.961305 -27.815042) (xy 452.945225 -27.790388)
			(xy 452.934324 -27.780488) (xy 452.913609 -27.762281) (xy 452.877138 -27.720912) (xy 452.847005 -27.674722)
			(xy 452.82384 -27.624673) (xy 452.808125 -27.571809) (xy 452.800188 -27.517233) (xy 452.799704 -27.489658)
			(xy 452.80019 -27.462407) (xy 452.807946 -27.408459) (xy 452.823301 -27.356164) (xy 452.845943 -27.306587)
			(xy 452.875409 -27.260737) (xy 452.9111 -27.219546) (xy 452.952291 -27.183855) (xy 452.998141 -27.154389)
			(xy 453.047718 -27.131747) (xy 453.100013 -27.116392) (xy 453.153961 -27.108636) (xy 453.208463 -27.108636)
			(xy 453.262411 -27.116392) (xy 453.314706 -27.131747) (xy 453.364283 -27.154389) (xy 453.410133 -27.183855)
			(xy 453.451324 -27.219546) (xy 453.487015 -27.260737) (xy 453.516481 -27.306587) (xy 453.539123 -27.356164)
			(xy 453.554478 -27.408459) (xy 453.562234 -27.462407) (xy 453.56272 -27.489658) (xy 453.562218 -27.517231)
			(xy 453.554272 -27.571802) (xy 453.538554 -27.624661) (xy 453.51539 -27.674707) (xy 453.485265 -27.720898)
			(xy 453.448804 -27.762271) (xy 453.4281 -27.780488) (xy 453.417245 -27.790429) (xy 453.401172 -27.815068)
			(xy 453.392783 -27.843264) (xy 453.392776 -27.872682) (xy 453.401149 -27.900883) (xy 453.417209 -27.925529)
			(xy 453.4281 -27.935428) (xy 453.448828 -27.953621) (xy 453.485297 -27.994994) (xy 453.515427 -28.041187)
			(xy 453.53859 -28.091239) (xy 453.554303 -28.144105) (xy 453.562237 -28.198682) (xy 453.56272 -28.226258)
			(xy 453.562279 -28.252574) (xy 453.555055 -28.304709) (xy 453.54074 -28.355357) (xy 453.519603 -28.403559)
			(xy 453.492046 -28.4484) (xy 453.458591 -28.489032) (xy 453.43953 -28.507182) (xy 453.42955 -28.517033)
			(xy 453.414845 -28.540893) (xy 453.4072 -28.567858) (xy 453.407192 -28.595885) (xy 453.414822 -28.622854)
			(xy 453.429513 -28.646723) (xy 453.43953 -28.656534) (xy 453.458613 -28.674666) (xy 453.492093 -28.715285)
			(xy 453.519665 -28.760126) (xy 453.540803 -28.808334) (xy 453.555106 -28.858993) (xy 453.562301 -28.911138)
			(xy 453.56272 -28.937458) (xy 453.562234 -28.964709) (xy 453.554478 -29.018657) (xy 453.539123 -29.070952)
			(xy 453.516481 -29.120529) (xy 453.487015 -29.166379) (xy 453.451324 -29.20757) (xy 453.410133 -29.243261)
			(xy 453.364283 -29.272727) (xy 453.314706 -29.295369) (xy 453.262411 -29.310724) (xy 453.208463 -29.31848)
			(xy 453.153961 -29.31848) (xy 453.100013 -29.310724) (xy 453.047718 -29.295369) (xy 452.998141 -29.272727)
			(xy 452.952291 -29.243261) (xy 452.9111 -29.20757) (xy 452.875409 -29.166379) (xy 452.845943 -29.120529)
			(xy 452.823301 -29.070952) (xy 452.807946 -29.018657) (xy 452.80019 -28.964709) (xy 452.799704 -28.937458)
			(xy 451.79488 -28.937458) (xy 451.79488 -33.873948) (xy 452.55688 -34.635948) (xy 457.120752 -34.635948)
		)
		(stroke
			(width 0)
			(type solid)
		)
		(fill yes)
		(layer "In2.Cu")
		(net "GND")
	)
	(gr_poly
		(pts
			(arc
				(start 194.443604 -441.479432)
				(mid 194.479525 -441.464553)
				(end 194.494404 -441.428632)
			)
			(arc
				(start 194.494404 -441.17006)
				(mid 194.790421 -440.455411)
				(end 195.50507 -440.159394)
			)
			(arc
				(start 276.314916 -440.159394)
				(mid 277.029565 -440.455411)
				(end 277.325582 -441.17006)
			)
			(arc
				(start 277.325582 -441.428632)
				(mid 277.340461 -441.464553)
				(end 277.376382 -441.479432)
			)
			(arc
				(start 463.300064 -441.479432)
				(mid 464.353268 -441.04318)
				(end 464.78952 -439.989976)
			)
			(arc
				(start 464.78952 -409.528264)
				(mid 464.980687 -408.567674)
				(end 465.52485 -407.753312)
			)
			(arc
				(start 467.353396 -405.924766)
				(mid 467.676179 -405.441593)
				(end 467.789514 -404.871682)
			)
			(arc
				(start 467.789514 -316.871858)
				(mid 467.780912 -316.843574)
				(end 467.758018 -316.824868)
			)
			(xy 467.743794 -316.818772) (xy 467.713822 -316.824868)
			(arc
				(start 467.672674 -316.866016)
				(mid 467.661563 -316.88255)
				(end 467.657688 -316.902084)
			)
			(arc
				(start 467.657688 -331.340968)
				(mid 467.629516 -331.482037)
				(end 467.549484 -331.601572)
			)
			(arc
				(start 467.297262 -331.854048)
				(mid 467.286151 -331.870582)
				(end 467.282276 -331.890116)
			)
			(arc
				(start 467.282276 -358.935274)
				(mid 467.28295 -358.943778)
				(end 467.28507 -358.952038)
			)
			(arc
				(start 467.28507 -358.952038)
				(mid 467.514132 -359.845086)
				(end 467.59114 -360.76382)
			)
			(arc
				(start 467.59114 -360.76382)
				(mid 467.514124 -361.682553)
				(end 467.28507 -362.575602)
			)
			(arc
				(start 467.28507 -362.575602)
				(mid 467.282984 -362.583868)
				(end 467.282276 -362.592366)
			)
			(arc
				(start 467.282276 -404.871936)
				(mid 467.207495 -405.247595)
				(end 466.994748 -405.566118)
			)
			(arc
				(start 465.166202 -407.394664)
				(mid 464.5119 -408.373524)
				(end 464.282028 -409.528264)
			)
			(arc
				(start 464.282028 -439.989976)
				(mid 463.994417 -440.684329)
				(end 463.300064 -440.97194)
			)
			(xy 410.917898 -440.97194)
			(arc
				(start 410.910024 -440.974734)
				(mid 410.831038 -440.993945)
				(end 410.750004 -441.000388)
			)
			(arc
				(start 410.750004 -441.000388)
				(mid 410.668968 -440.993957)
				(end 410.589984 -440.974734)
			)
			(xy 410.58211 -440.97194) (xy 406.917906 -440.97194)
			(arc
				(start 406.910032 -440.974734)
				(mid 406.831046 -440.993945)
				(end 406.750012 -441.000388)
			)
			(arc
				(start 406.750012 -441.000388)
				(mid 406.668976 -440.993957)
				(end 406.589992 -440.974734)
			)
			(xy 406.582118 -440.97194) (xy 402.917914 -440.97194)
			(arc
				(start 402.91004 -440.974734)
				(mid 402.831054 -440.993945)
				(end 402.75002 -441.000388)
			)
			(arc
				(start 402.75002 -441.000388)
				(mid 402.668984 -440.993957)
				(end 402.59 -440.974734)
			)
			(xy 402.582126 -440.97194) (xy 398.917922 -440.97194)
			(arc
				(start 398.910048 -440.974734)
				(mid 398.831062 -440.993945)
				(end 398.750028 -441.000388)
			)
			(arc
				(start 398.750028 -441.000388)
				(mid 398.668992 -440.993957)
				(end 398.590008 -440.974734)
			)
			(xy 398.582134 -440.97194) (xy 393.917932 -440.97194)
			(arc
				(start 393.910058 -440.974734)
				(mid 393.831072 -440.993945)
				(end 393.750038 -441.000388)
			)
			(arc
				(start 393.750038 -441.000388)
				(mid 393.669002 -440.993957)
				(end 393.590018 -440.974734)
			)
			(xy 393.582144 -440.97194) (xy 389.91794 -440.97194)
			(arc
				(start 389.910066 -440.974734)
				(mid 389.83108 -440.993945)
				(end 389.750046 -441.000388)
			)
			(arc
				(start 389.750046 -441.000388)
				(mid 389.66901 -440.993957)
				(end 389.590026 -440.974734)
			)
			(xy 389.582152 -440.97194) (xy 385.917948 -440.97194)
			(arc
				(start 385.910074 -440.974734)
				(mid 385.831088 -440.993945)
				(end 385.750054 -441.000388)
			)
			(arc
				(start 385.750054 -441.000388)
				(mid 385.669018 -440.993957)
				(end 385.590034 -440.974734)
			)
			(xy 385.58216 -440.97194) (xy 381.917956 -440.97194)
			(arc
				(start 381.910082 -440.974734)
				(mid 381.831096 -440.993945)
				(end 381.750062 -441.000388)
			)
			(arc
				(start 381.750062 -441.000388)
				(mid 381.669026 -440.993957)
				(end 381.590042 -440.974734)
			)
			(xy 381.582168 -440.97194) (xy 343.817956 -440.97194)
			(arc
				(start 343.810082 -440.974734)
				(mid 343.731096 -440.993945)
				(end 343.650062 -441.000388)
			)
			(arc
				(start 343.650062 -441.000388)
				(mid 343.569026 -440.993957)
				(end 343.490042 -440.974734)
			)
			(xy 343.482168 -440.97194) (xy 339.817964 -440.97194)
			(arc
				(start 339.81009 -440.974734)
				(mid 339.731104 -440.993945)
				(end 339.65007 -441.000388)
			)
			(arc
				(start 339.65007 -441.000388)
				(mid 339.569034 -440.993957)
				(end 339.49005 -440.974734)
			)
			(xy 339.482176 -440.97194) (xy 335.817972 -440.97194)
			(arc
				(start 335.810098 -440.974734)
				(mid 335.731112 -440.993945)
				(end 335.650078 -441.000388)
			)
			(arc
				(start 335.650078 -441.000388)
				(mid 335.569042 -440.993957)
				(end 335.490058 -440.974734)
			)
			(xy 335.482184 -440.97194) (xy 331.81798 -440.97194)
			(arc
				(start 331.810106 -440.974734)
				(mid 331.73112 -440.993945)
				(end 331.650086 -441.000388)
			)
			(arc
				(start 331.650086 -441.000388)
				(mid 331.56905 -440.993957)
				(end 331.490066 -440.974734)
			)
			(xy 331.482192 -440.97194) (xy 326.81799 -440.97194)
			(arc
				(start 326.810116 -440.974734)
				(mid 326.73113 -440.993945)
				(end 326.650096 -441.000388)
			)
			(arc
				(start 326.650096 -441.000388)
				(mid 326.56906 -440.993957)
				(end 326.490076 -440.974734)
			)
			(xy 326.482202 -440.97194) (xy 322.817998 -440.97194)
			(arc
				(start 322.810124 -440.974734)
				(mid 322.731138 -440.993945)
				(end 322.650104 -441.000388)
			)
			(arc
				(start 322.650104 -441.000388)
				(mid 322.569068 -440.993957)
				(end 322.490084 -440.974734)
			)
			(xy 322.48221 -440.97194) (xy 318.818006 -440.97194)
			(arc
				(start 318.810132 -440.974734)
				(mid 318.731146 -440.993945)
				(end 318.650112 -441.000388)
			)
			(arc
				(start 318.650112 -441.000388)
				(mid 318.569076 -440.993957)
				(end 318.490092 -440.974734)
			)
			(xy 318.482218 -440.97194) (xy 314.818014 -440.97194)
			(arc
				(start 314.81014 -440.974734)
				(mid 314.731154 -440.993945)
				(end 314.65012 -441.000388)
			)
			(arc
				(start 314.65012 -441.000388)
				(mid 314.569084 -440.993957)
				(end 314.4901 -440.974734)
			)
			(xy 314.482226 -440.97194)
			(arc
				(start 277.82012 -440.97194)
				(mid 277.31587 -440.028787)
				(end 276.314916 -439.652156)
			)
			(arc
				(start 195.50507 -439.652156)
				(mid 194.504157 -440.028834)
				(end 193.999866 -440.97194)
			)
			(xy 154.917902 -440.97194)
			(arc
				(start 154.910028 -440.974734)
				(mid 154.831042 -440.993945)
				(end 154.750008 -441.000388)
			)
			(arc
				(start 154.750008 -441.000388)
				(mid 154.668972 -440.993957)
				(end 154.589988 -440.974734)
			)
			(xy 154.582114 -440.97194) (xy 150.91791 -440.97194)
			(arc
				(start 150.910036 -440.974734)
				(mid 150.83105 -440.993945)
				(end 150.750016 -441.000388)
			)
			(arc
				(start 150.750016 -441.000388)
				(mid 150.66898 -440.993957)
				(end 150.589996 -440.974734)
			)
			(xy 150.582122 -440.97194) (xy 146.917918 -440.97194)
			(arc
				(start 146.910044 -440.974734)
				(mid 146.831058 -440.993945)
				(end 146.750024 -441.000388)
			)
			(arc
				(start 146.750024 -441.000388)
				(mid 146.668988 -440.993957)
				(end 146.590004 -440.974734)
			)
			(xy 146.58213 -440.97194) (xy 142.917926 -440.97194)
			(arc
				(start 142.910052 -440.974734)
				(mid 142.831066 -440.993945)
				(end 142.750032 -441.000388)
			)
			(arc
				(start 142.750032 -441.000388)
				(mid 142.668996 -440.993957)
				(end 142.590012 -440.974734)
			)
			(xy 142.582138 -440.97194) (xy 137.917936 -440.97194)
			(arc
				(start 137.910062 -440.974734)
				(mid 137.831076 -440.993945)
				(end 137.750042 -441.000388)
			)
			(arc
				(start 137.750042 -441.000388)
				(mid 137.669006 -440.993957)
				(end 137.590022 -440.974734)
			)
			(xy 137.582148 -440.97194) (xy 133.917944 -440.97194)
			(arc
				(start 133.91007 -440.974734)
				(mid 133.831084 -440.993945)
				(end 133.75005 -441.000388)
			)
			(arc
				(start 133.75005 -441.000388)
				(mid 133.669014 -440.993957)
				(end 133.59003 -440.974734)
			)
			(xy 133.582156 -440.97194) (xy 129.917952 -440.97194)
			(arc
				(start 129.910078 -440.974734)
				(mid 129.831092 -440.993945)
				(end 129.750058 -441.000388)
			)
			(arc
				(start 129.750058 -441.000388)
				(mid 129.669022 -440.993957)
				(end 129.590038 -440.974734)
			)
			(xy 129.582164 -440.97194) (xy 125.91796 -440.97194)
			(arc
				(start 125.910086 -440.974734)
				(mid 125.8311 -440.993945)
				(end 125.750066 -441.000388)
			)
			(arc
				(start 125.750066 -441.000388)
				(mid 125.66903 -440.993957)
				(end 125.590046 -440.974734)
			)
			(xy 125.582172 -440.97194) (xy 87.81796 -440.97194)
			(arc
				(start 87.810086 -440.974734)
				(mid 87.7311 -440.993945)
				(end 87.650066 -441.000388)
			)
			(arc
				(start 87.650066 -441.000388)
				(mid 87.56903 -440.993957)
				(end 87.490046 -440.974734)
			)
			(xy 87.482172 -440.97194) (xy 83.817968 -440.97194)
			(arc
				(start 83.810094 -440.974734)
				(mid 83.731108 -440.993945)
				(end 83.650074 -441.000388)
			)
			(arc
				(start 83.650074 -441.000388)
				(mid 83.569038 -440.993957)
				(end 83.490054 -440.974734)
			)
			(xy 83.48218 -440.97194) (xy 79.817976 -440.97194)
			(arc
				(start 79.810102 -440.974734)
				(mid 79.731116 -440.993945)
				(end 79.650082 -441.000388)
			)
			(arc
				(start 79.650082 -441.000388)
				(mid 79.569046 -440.993957)
				(end 79.490062 -440.974734)
			)
			(xy 79.482188 -440.97194) (xy 75.817984 -440.97194)
			(arc
				(start 75.81011 -440.974734)
				(mid 75.731124 -440.993945)
				(end 75.65009 -441.000388)
			)
			(arc
				(start 75.65009 -441.000388)
				(mid 75.569054 -440.993957)
				(end 75.49007 -440.974734)
			)
			(xy 75.482196 -440.97194) (xy 70.817994 -440.97194)
			(arc
				(start 70.81012 -440.974734)
				(mid 70.731134 -440.993945)
				(end 70.6501 -441.000388)
			)
			(arc
				(start 70.6501 -441.000388)
				(mid 70.569064 -440.993957)
				(end 70.49008 -440.974734)
			)
			(xy 70.482206 -440.97194) (xy 66.818002 -440.97194)
			(arc
				(start 66.810128 -440.974734)
				(mid 66.731142 -440.993945)
				(end 66.650108 -441.000388)
			)
			(arc
				(start 66.650108 -441.000388)
				(mid 66.569072 -440.993957)
				(end 66.490088 -440.974734)
			)
			(xy 66.482214 -440.97194) (xy 62.81801 -440.97194)
			(arc
				(start 62.810136 -440.974734)
				(mid 62.73115 -440.993945)
				(end 62.650116 -441.000388)
			)
			(arc
				(start 62.650116 -441.000388)
				(mid 62.56908 -440.993957)
				(end 62.490096 -440.974734)
			)
			(xy 62.482222 -440.97194) (xy 58.818018 -440.97194)
			(arc
				(start 58.810144 -440.974734)
				(mid 58.731158 -440.993945)
				(end 58.650124 -441.000388)
			)
			(arc
				(start 58.650124 -441.000388)
				(mid 58.569088 -440.993957)
				(end 58.490104 -440.974734)
			)
			(xy 58.48223 -440.97194)
			(arc
				(start 8.50011 -440.97194)
				(mid 7.805667 -440.684345)
				(end 7.517892 -439.989976)
			)
			(arc
				(start 7.517892 -409.528264)
				(mid 7.287997 -408.373534)
				(end 6.633718 -407.394664)
			)
			(arc
				(start 3.305302 -404.066248)
				(mid 3.092701 -403.747829)
				(end 3.018028 -403.37232)
			)
			(arc
				(start 3.018028 -81.32826)
				(mid 2.788133 -80.17353)
				(end 2.133854 -79.19466)
			)
			(arc
				(start 1.305306 -78.366112)
				(mid 1.092705 -78.047693)
				(end 1.018032 -77.672184)
			)
			(arc
				(start 1.018032 -42.244772)
				(mid 1.013298 -42.223357)
				(end 0.999998 -42.20591)
			)
			(arc
				(start 0.999998 -42.20591)
				(mid 0.873253 -41.933622)
				(end 0.999998 -41.661334)
			)
			(arc
				(start 0.999998 -41.661334)
				(mid 1.013327 -41.6439)
				(end 1.018032 -41.622472)
			)
			(arc
				(start 1.018032 -41.222422)
				(mid 1.013298 -41.201007)
				(end 0.999998 -41.18356)
			)
			(arc
				(start 0.999998 -41.18356)
				(mid 0.873253 -40.911272)
				(end 0.999998 -40.638984)
			)
			(arc
				(start 0.999998 -40.638984)
				(mid 1.013327 -40.62155)
				(end 1.018032 -40.600122)
			)
			(arc
				(start 1.018032 -40.167814)
				(mid 1.012748 -40.145255)
				(end 0.997966 -40.127428)
			)
			(arc
				(start 0.997966 -40.127428)
				(mid 0.84779 -39.824152)
				(end 0.997966 -39.520876)
			)
			(arc
				(start 0.997966 -39.520876)
				(mid 1.012704 -39.503027)
				(end 1.018032 -39.48049)
			)
			(arc
				(start 1.018032 -39.099998)
				(mid 1.013298 -39.078583)
				(end 0.999998 -39.061136)
			)
			(arc
				(start 0.999998 -39.061136)
				(mid 0.873253 -38.788848)
				(end 0.999998 -38.51656)
			)
			(arc
				(start 0.999998 -38.51656)
				(mid 1.013327 -38.499126)
				(end 1.018032 -38.477698)
			)
			(arc
				(start 1.018032 -38.110414)
				(mid 1.011311 -38.085415)
				(end 0.99314 -38.06698)
			)
			(arc
				(start 0.99314 -38.06698)
				(mid 0.807128 -37.73932)
				(end 0.99314 -37.41166)
			)
			(arc
				(start 0.99314 -37.41166)
				(mid 1.011304 -37.393221)
				(end 1.018032 -37.368226)
			)
			(arc
				(start 1.018032 -37.067236)
				(mid 1.011311 -37.042237)
				(end 0.99314 -37.023802)
			)
			(arc
				(start 0.99314 -37.023802)
				(mid 0.807128 -36.696142)
				(end 0.99314 -36.368482)
			)
			(arc
				(start 0.99314 -36.368482)
				(mid 1.011304 -36.350043)
				(end 1.018032 -36.325048)
			)
			(arc
				(start 1.018032 -35.987228)
				(mid 1.011311 -35.962229)
				(end 0.99314 -35.943794)
			)
			(arc
				(start 0.99314 -35.943794)
				(mid 0.807128 -35.616134)
				(end 0.99314 -35.288474)
			)
			(arc
				(start 0.99314 -35.288474)
				(mid 1.011304 -35.270035)
				(end 1.018032 -35.24504)
			)
			(arc
				(start 1.018032 -26.980642)
				(mid 1.010858 -26.954615)
				(end 0.991362 -26.935938)
			)
			(arc
				(start 0.991362 -26.935938)
				(mid 0.827352 -26.84333)
				(end 0.66675 -26.74493)
			)
			(xy 0.654812 -26.73731) (xy 0.62738 -26.736294)
			(arc
				(start 0.536956 -26.786078)
				(mid 0.517713 -26.8047)
				(end 0.51054 -26.830528)
			)
			(arc
				(start 0.51054 -77.671676)
				(mid 0.623884 -78.241583)
				(end 0.946658 -78.72476)
			)
			(arc
				(start 1.775206 -79.553308)
				(mid 2.319424 -80.367648)
				(end 2.510536 -81.32826)
			)
			(arc
				(start 2.510536 -403.371812)
				(mid 2.62388 -403.941719)
				(end 2.946654 -404.424896)
			)
			(arc
				(start 6.27507 -407.753312)
				(mid 6.819424 -408.567623)
				(end 7.010654 -409.528264)
			)
			(arc
				(start 7.010654 -439.989976)
				(mid 7.446906 -441.04318)
				(end 8.50011 -441.479432)
			)
		)
		(stroke
			(width 0)
			(type solid)
		)
		(fill yes)
		(layer "In2.Cu")
		(net "GND")
	)
	(gr_poly
		(pts
			(xy 105.313226 -235.95838) (xy 105.313226 -233.590084) (xy 105.294409 -233.572869) (xy 105.261785 -233.533671)
			(xy 105.235571 -233.489926) (xy 105.21639 -233.442673) (xy 105.204697 -233.393033) (xy 105.200769 -233.342187)
			(xy 105.204701 -233.29134) (xy 105.216398 -233.241702) (xy 105.235583 -233.19445) (xy 105.2618 -233.150707)
			(xy 105.294427 -233.111512) (xy 105.313226 -233.094276) (xy 105.313226 -232.933494) (xy 105.312783 -232.91949)
			(xy 105.305174 -232.892534) (xy 105.29053 -232.868659) (xy 105.269951 -232.849658) (xy 105.244986 -232.836961)
			(xy 105.21751 -232.831523) (xy 105.18959 -232.833751) (xy 105.17632 -232.838244) (xy 105.148655 -232.847825)
			(xy 105.091036 -232.858173) (xy 105.061766 -232.858818) (xy 105.035803 -232.858306) (xy 104.984518 -232.850179)
			(xy 104.935135 -232.834129) (xy 104.888871 -232.810552) (xy 104.846865 -232.780028) (xy 104.81015 -232.74331)
			(xy 104.77963 -232.7013) (xy 104.756058 -232.655033) (xy 104.740013 -232.605649) (xy 104.731891 -232.554363)
			(xy 104.731891 -232.502437) (xy 104.740013 -232.451151) (xy 104.756058 -232.401767) (xy 104.77963 -232.3555)
			(xy 104.81015 -232.31349) (xy 104.846865 -232.276772) (xy 104.888871 -232.246248) (xy 104.935135 -232.222671)
			(xy 104.984518 -232.206621) (xy 105.035803 -232.198494) (xy 105.061766 -232.19791) (xy 105.091036 -232.19856)
			(xy 105.148655 -232.208905) (xy 105.17632 -232.218484) (xy 105.189601 -232.222931) (xy 105.21751 -232.225157)
			(xy 105.244975 -232.219721) (xy 105.269932 -232.20703) (xy 105.290505 -232.18804) (xy 105.305148 -232.164176)
			(xy 105.31276 -232.137233) (xy 105.313226 -232.123234) (xy 105.313226 -231.962706) (xy 105.294359 -231.945488)
			(xy 105.261641 -231.906267) (xy 105.235348 -231.862478) (xy 105.216106 -231.815165) (xy 105.204371 -231.765455)
			(xy 105.200426 -231.714532) (xy 105.204362 -231.663607) (xy 105.216086 -231.613895) (xy 105.23532 -231.566579)
			(xy 105.261605 -231.522785) (xy 105.294315 -231.483557) (xy 105.313226 -231.46639) (xy 105.313226 -231.305608)
			(xy 105.312785 -231.291602) (xy 105.305178 -231.264643) (xy 105.290534 -231.240764) (xy 105.269955 -231.221761)
			(xy 105.244987 -231.209062) (xy 105.217509 -231.203623) (xy 105.189587 -231.205852) (xy 105.17632 -231.210358)
			(xy 105.148655 -231.219938) (xy 105.091036 -231.230286) (xy 105.061766 -231.230932) (xy 105.035802 -231.23042)
			(xy 104.984515 -231.222292) (xy 104.93513 -231.206242) (xy 104.888864 -231.182664) (xy 104.846855 -231.152139)
			(xy 104.810139 -231.115419) (xy 104.779618 -231.073407) (xy 104.756045 -231.027139) (xy 104.74 -230.977752)
			(xy 104.731877 -230.926464) (xy 104.731877 -230.874536) (xy 104.74 -230.823248) (xy 104.756045 -230.773861)
			(xy 104.779618 -230.727593) (xy 104.810139 -230.685581) (xy 104.846855 -230.648861) (xy 104.888864 -230.618336)
			(xy 104.93513 -230.594758) (xy 104.984515 -230.578708) (xy 105.035802 -230.57058) (xy 105.061766 -230.570024)
			(xy 105.091036 -230.570674) (xy 105.148655 -230.581019) (xy 105.17632 -230.590598) (xy 105.189602 -230.595044)
			(xy 105.217512 -230.59727) (xy 105.244978 -230.591834) (xy 105.269936 -230.579144) (xy 105.29051 -230.560154)
			(xy 105.305156 -230.53629) (xy 105.312771 -230.509347) (xy 105.313226 -230.495348) (xy 105.313226 -230.33482)
			(xy 105.294365 -230.317602) (xy 105.261661 -230.278383) (xy 105.235381 -230.234598) (xy 105.21615 -230.187291)
			(xy 105.204427 -230.137589) (xy 105.20049 -230.086675) (xy 105.204434 -230.035761) (xy 105.216165 -229.986061)
			(xy 105.235403 -229.938757) (xy 105.26169 -229.894976) (xy 105.2944 -229.855762) (xy 105.313226 -229.838504)
			(xy 105.313226 -229.70998) (xy 105.211626 -229.60838) (xy 102.798626 -229.60838) (xy 102.69728 -229.709726)
			(xy 102.745032 -229.757478) (xy 102.761542 -229.760018) (xy 102.787256 -229.764421) (xy 102.83696 -229.780261)
			(xy 102.88356 -229.803711) (xy 102.925897 -229.83419) (xy 102.962921 -229.870941) (xy 102.993712 -229.913052)
			(xy 103.017506 -229.959477) (xy 103.033713 -230.009063) (xy 103.041929 -230.060579) (xy 103.042466 -230.086662)
			(xy 103.041986 -230.112634) (xy 103.033866 -230.163938) (xy 103.017819 -230.21334) (xy 102.994242 -230.259624)
			(xy 102.963714 -230.30165) (xy 102.926988 -230.338382) (xy 102.884967 -230.368916) (xy 102.838687 -230.3925)
			(xy 102.789287 -230.408554) (xy 102.737984 -230.416682) (xy 102.712012 -230.417116) (xy 102.687145 -230.416667)
			(xy 102.637972 -230.40921) (xy 102.590474 -230.394464) (xy 102.545725 -230.372761) (xy 102.504736 -230.344593)
			(xy 102.468435 -230.310596) (xy 102.437643 -230.27154) (xy 102.413056 -230.228308) (xy 102.403656 -230.20528)
			(xy 102.397971 -230.191988) (xy 102.380417 -230.169036) (xy 102.357142 -230.151912) (xy 102.330005 -230.141985)
			(xy 102.301174 -230.140046) (xy 102.272953 -230.146252) (xy 102.247595 -230.160106) (xy 102.237032 -230.169974)
			(xy 101.884226 -230.52278) (xy 101.884226 -230.552752) (xy 101.884666 -230.566786) (xy 101.892296 -230.593796)
			(xy 101.906992 -230.617708) (xy 101.927645 -230.636715) (xy 101.952692 -230.649379) (xy 101.980242 -230.654745)
			(xy 102.008211 -230.652406) (xy 102.034487 -230.64254) (xy 102.046024 -230.63454) (xy 102.067485 -230.619349)
			(xy 102.11421 -230.595239) (xy 102.164159 -230.578823) (xy 102.216077 -230.570516) (xy 102.242366 -230.570024)
			(xy 102.268339 -230.570504) (xy 102.319645 -230.578626) (xy 102.36905 -230.594674) (xy 102.415335 -230.618253)
			(xy 102.457362 -230.648783) (xy 102.494095 -230.685512) (xy 102.524629 -230.727536) (xy 102.548213 -230.773819)
			(xy 102.564266 -230.823221) (xy 102.572393 -230.874527) (xy 102.572393 -230.926445) (xy 102.852221 -230.926445)
			(xy 102.852221 -230.874511) (xy 102.860346 -230.823216) (xy 102.876394 -230.773823) (xy 102.899972 -230.727549)
			(xy 102.930498 -230.685533) (xy 102.967221 -230.64881) (xy 103.009237 -230.618284) (xy 103.055511 -230.594706)
			(xy 103.104904 -230.578658) (xy 103.156199 -230.570533) (xy 103.208133 -230.570533) (xy 103.259428 -230.578658)
			(xy 103.308821 -230.594706) (xy 103.355095 -230.618284) (xy 103.397111 -230.64881) (xy 103.433834 -230.685533)
			(xy 103.46436 -230.727549) (xy 103.487938 -230.773823) (xy 103.503986 -230.823216) (xy 103.512111 -230.874511)
			(xy 103.51262 -230.900478) (xy 103.512111 -230.926445) (xy 103.792021 -230.926445) (xy 103.792021 -230.874511)
			(xy 103.800146 -230.823216) (xy 103.816194 -230.773823) (xy 103.839772 -230.727549) (xy 103.870298 -230.685533)
			(xy 103.907021 -230.64881) (xy 103.949037 -230.618284) (xy 103.995311 -230.594706) (xy 104.044704 -230.578658)
			(xy 104.095999 -230.570533) (xy 104.147933 -230.570533) (xy 104.199228 -230.578658) (xy 104.248621 -230.594706)
			(xy 104.294895 -230.618284) (xy 104.336911 -230.64881) (xy 104.373634 -230.685533) (xy 104.40416 -230.727549)
			(xy 104.427738 -230.773823) (xy 104.443786 -230.823216) (xy 104.451911 -230.874511) (xy 104.45242 -230.900478)
			(xy 104.451911 -230.926445) (xy 104.443786 -230.97774) (xy 104.427738 -231.027133) (xy 104.40416 -231.073407)
			(xy 104.373634 -231.115423) (xy 104.336911 -231.152146) (xy 104.294895 -231.182672) (xy 104.248621 -231.20625)
			(xy 104.199228 -231.222298) (xy 104.147933 -231.230423) (xy 104.095999 -231.230423) (xy 104.044704 -231.222298)
			(xy 103.995311 -231.20625) (xy 103.949037 -231.182672) (xy 103.907021 -231.152146) (xy 103.870298 -231.115423)
			(xy 103.839772 -231.073407) (xy 103.816194 -231.027133) (xy 103.800146 -230.97774) (xy 103.792021 -230.926445)
			(xy 103.512111 -230.926445) (xy 103.503986 -230.97774) (xy 103.487938 -231.027133) (xy 103.46436 -231.073407)
			(xy 103.433834 -231.115423) (xy 103.397111 -231.152146) (xy 103.355095 -231.182672) (xy 103.308821 -231.20625)
			(xy 103.259428 -231.222298) (xy 103.208133 -231.230423) (xy 103.156199 -231.230423) (xy 103.104904 -231.222298)
			(xy 103.055511 -231.20625) (xy 103.009237 -231.182672) (xy 102.967221 -231.152146) (xy 102.930498 -231.115423)
			(xy 102.899972 -231.073407) (xy 102.876394 -231.027133) (xy 102.860346 -230.97774) (xy 102.852221 -230.926445)
			(xy 102.572393 -230.926445) (xy 102.572393 -230.926473) (xy 102.564266 -230.977779) (xy 102.548213 -231.027181)
			(xy 102.524629 -231.073464) (xy 102.494095 -231.115488) (xy 102.457362 -231.152217) (xy 102.415335 -231.182747)
			(xy 102.36905 -231.206326) (xy 102.319645 -231.222374) (xy 102.268339 -231.230496) (xy 102.242366 -231.230932)
			(xy 102.216074 -231.230451) (xy 102.164147 -231.222171) (xy 102.114189 -231.205761) (xy 102.067466 -231.181638)
			(xy 102.046024 -231.166416) (xy 102.034459 -231.158463) (xy 102.008185 -231.148614) (xy 101.980224 -231.146284)
			(xy 101.952683 -231.151648) (xy 101.92764 -231.164301) (xy 101.906983 -231.18329) (xy 101.892271 -231.207182)
			(xy 101.884613 -231.234175) (xy 101.884226 -231.248204) (xy 101.884226 -231.401874) (xy 101.913436 -231.415844)
			(xy 101.935736 -231.426889) (xy 101.977023 -231.454669) (xy 102.013676 -231.488328) (xy 102.044866 -231.527103)
			(xy 102.069888 -231.570118) (xy 102.088175 -231.616398) (xy 102.099315 -231.664898) (xy 102.103054 -231.714521)
			(xy 102.101092 -231.740515) (xy 102.382067 -231.740515) (xy 102.382067 -231.688581) (xy 102.390192 -231.637286)
			(xy 102.40624 -231.587893) (xy 102.429818 -231.541619) (xy 102.460344 -231.499603) (xy 102.497067 -231.46288)
			(xy 102.539083 -231.432354) (xy 102.585357 -231.408776) (xy 102.63475 -231.392728) (xy 102.686045 -231.384603)
			(xy 102.737979 -231.384603) (xy 102.789274 -231.392728) (xy 102.838667 -231.408776) (xy 102.884941 -231.432354)
			(xy 102.926957 -231.46288) (xy 102.96368 -231.499603) (xy 102.994206 -231.541619) (xy 103.017784 -231.587893)
			(xy 103.033832 -231.637286) (xy 103.041957 -231.688581) (xy 103.042466 -231.714548) (xy 103.041957 -231.740515)
			(xy 103.321867 -231.740515) (xy 103.321867 -231.688581) (xy 103.329992 -231.637286) (xy 103.34604 -231.587893)
			(xy 103.369618 -231.541619) (xy 103.400144 -231.499603) (xy 103.436867 -231.46288) (xy 103.478883 -231.432354)
			(xy 103.525157 -231.408776) (xy 103.57455 -231.392728) (xy 103.625845 -231.384603) (xy 103.677779 -231.384603)
			(xy 103.729074 -231.392728) (xy 103.778467 -231.408776) (xy 103.824741 -231.432354) (xy 103.866757 -231.46288)
			(xy 103.90348 -231.499603) (xy 103.934006 -231.541619) (xy 103.957584 -231.587893) (xy 103.973632 -231.637286)
			(xy 103.981757 -231.688581) (xy 103.982266 -231.714548) (xy 103.981757 -231.740515) (xy 104.261667 -231.740515)
			(xy 104.261667 -231.688581) (xy 104.269792 -231.637286) (xy 104.28584 -231.587893) (xy 104.309418 -231.541619)
			(xy 104.339944 -231.499603) (xy 104.376667 -231.46288) (xy 104.418683 -231.432354) (xy 104.464957 -231.408776)
			(xy 104.51435 -231.392728) (xy 104.565645 -231.384603) (xy 104.617579 -231.384603) (xy 104.668874 -231.392728)
			(xy 104.718267 -231.408776) (xy 104.764541 -231.432354) (xy 104.806557 -231.46288) (xy 104.84328 -231.499603)
			(xy 104.873806 -231.541619) (xy 104.897384 -231.587893) (xy 104.913432 -231.637286) (xy 104.921557 -231.688581)
			(xy 104.922066 -231.714548) (xy 104.921557 -231.740515) (xy 104.913432 -231.79181) (xy 104.897384 -231.841203)
			(xy 104.873806 -231.887477) (xy 104.84328 -231.929493) (xy 104.806557 -231.966216) (xy 104.764541 -231.996742)
			(xy 104.718267 -232.02032) (xy 104.668874 -232.036368) (xy 104.617579 -232.044493) (xy 104.565645 -232.044493)
			(xy 104.51435 -232.036368) (xy 104.464957 -232.02032) (xy 104.418683 -231.996742) (xy 104.376667 -231.966216)
			(xy 104.339944 -231.929493) (xy 104.309418 -231.887477) (xy 104.28584 -231.841203) (xy 104.269792 -231.79181)
			(xy 104.261667 -231.740515) (xy 103.981757 -231.740515) (xy 103.973632 -231.79181) (xy 103.957584 -231.841203)
			(xy 103.934006 -231.887477) (xy 103.90348 -231.929493) (xy 103.866757 -231.966216) (xy 103.824741 -231.996742)
			(xy 103.778467 -232.02032) (xy 103.729074 -232.036368) (xy 103.677779 -232.044493) (xy 103.625845 -232.044493)
			(xy 103.57455 -232.036368) (xy 103.525157 -232.02032) (xy 103.478883 -231.996742) (xy 103.436867 -231.966216)
			(xy 103.400144 -231.929493) (xy 103.369618 -231.887477) (xy 103.34604 -231.841203) (xy 103.329992 -231.79181)
			(xy 103.321867 -231.740515) (xy 103.041957 -231.740515) (xy 103.033832 -231.79181) (xy 103.017784 -231.841203)
			(xy 102.994206 -231.887477) (xy 102.96368 -231.929493) (xy 102.926957 -231.966216) (xy 102.884941 -231.996742)
			(xy 102.838667 -232.02032) (xy 102.789274 -232.036368) (xy 102.737979 -232.044493) (xy 102.686045 -232.044493)
			(xy 102.63475 -232.036368) (xy 102.585357 -232.02032) (xy 102.539083 -231.996742) (xy 102.497067 -231.966216)
			(xy 102.460344 -231.929493) (xy 102.429818 -231.887477) (xy 102.40624 -231.841203) (xy 102.390192 -231.79181)
			(xy 102.382067 -231.740515) (xy 102.101092 -231.740515) (xy 102.099309 -231.764142) (xy 102.088163 -231.812641)
			(xy 102.06987 -231.858919) (xy 102.044843 -231.901931) (xy 102.013648 -231.940702) (xy 101.976991 -231.974356)
			(xy 101.935701 -232.002132) (xy 101.913436 -232.013252) (xy 101.884226 -232.027222) (xy 101.884226 -232.180638)
			(xy 101.884664 -232.194673) (xy 101.892292 -232.221687) (xy 101.906988 -232.245603) (xy 101.927641 -232.264612)
			(xy 101.952691 -232.277279) (xy 101.980243 -232.282645) (xy 102.008215 -232.280306) (xy 102.034493 -232.270437)
			(xy 102.046024 -232.262426) (xy 102.067486 -232.247235) (xy 102.11421 -232.223126) (xy 102.16416 -232.206712)
			(xy 102.216077 -232.198405) (xy 102.242366 -232.19791) (xy 102.26834 -232.19839) (xy 102.319649 -232.206512)
			(xy 102.369055 -232.222561) (xy 102.415343 -232.246141) (xy 102.457371 -232.276673) (xy 102.494105 -232.313403)
			(xy 102.524641 -232.355428) (xy 102.548226 -232.401713) (xy 102.56428 -232.451118) (xy 102.572407 -232.502426)
			(xy 102.572407 -232.554331) (xy 102.852221 -232.554331) (xy 102.852221 -232.502397) (xy 102.860346 -232.451102)
			(xy 102.876394 -232.401709) (xy 102.899972 -232.355435) (xy 102.930498 -232.313419) (xy 102.967221 -232.276696)
			(xy 103.009237 -232.24617) (xy 103.055511 -232.222592) (xy 103.104904 -232.206544) (xy 103.156199 -232.198419)
			(xy 103.208133 -232.198419) (xy 103.259428 -232.206544) (xy 103.308821 -232.222592) (xy 103.355095 -232.24617)
			(xy 103.397111 -232.276696) (xy 103.433834 -232.313419) (xy 103.46436 -232.355435) (xy 103.487938 -232.401709)
			(xy 103.503986 -232.451102) (xy 103.512111 -232.502397) (xy 103.51262 -232.528364) (xy 103.512111 -232.554331)
			(xy 103.792021 -232.554331) (xy 103.792021 -232.502397) (xy 103.800146 -232.451102) (xy 103.816194 -232.401709)
			(xy 103.839772 -232.355435) (xy 103.870298 -232.313419) (xy 103.907021 -232.276696) (xy 103.949037 -232.24617)
			(xy 103.995311 -232.222592) (xy 104.044704 -232.206544) (xy 104.095999 -232.198419) (xy 104.147933 -232.198419)
			(xy 104.199228 -232.206544) (xy 104.248621 -232.222592) (xy 104.294895 -232.24617) (xy 104.336911 -232.276696)
			(xy 104.373634 -232.313419) (xy 104.40416 -232.355435) (xy 104.427738 -232.401709) (xy 104.443786 -232.451102)
			(xy 104.451911 -232.502397) (xy 104.45242 -232.528364) (xy 104.451911 -232.554331) (xy 104.443786 -232.605626)
			(xy 104.427738 -232.655019) (xy 104.40416 -232.701293) (xy 104.373634 -232.743309) (xy 104.336911 -232.780032)
			(xy 104.294895 -232.810558) (xy 104.248621 -232.834136) (xy 104.199228 -232.850184) (xy 104.147933 -232.858309)
			(xy 104.095999 -232.858309) (xy 104.044704 -232.850184) (xy 103.995311 -232.834136) (xy 103.949037 -232.810558)
			(xy 103.907021 -232.780032) (xy 103.870298 -232.743309) (xy 103.839772 -232.701293) (xy 103.816194 -232.655019)
			(xy 103.800146 -232.605626) (xy 103.792021 -232.554331) (xy 103.512111 -232.554331) (xy 103.503986 -232.605626)
			(xy 103.487938 -232.655019) (xy 103.46436 -232.701293) (xy 103.433834 -232.743309) (xy 103.397111 -232.780032)
			(xy 103.355095 -232.810558) (xy 103.308821 -232.834136) (xy 103.259428 -232.850184) (xy 103.208133 -232.858309)
			(xy 103.156199 -232.858309) (xy 103.104904 -232.850184) (xy 103.055511 -232.834136) (xy 103.009237 -232.810558)
			(xy 102.967221 -232.780032) (xy 102.930498 -232.743309) (xy 102.899972 -232.701293) (xy 102.876394 -232.655019)
			(xy 102.860346 -232.605626) (xy 102.852221 -232.554331) (xy 102.572407 -232.554331) (xy 102.572407 -232.554374)
			(xy 102.56428 -232.605682) (xy 102.548226 -232.655087) (xy 102.524641 -232.701372) (xy 102.494105 -232.743397)
			(xy 102.457371 -232.780127) (xy 102.415343 -232.810659) (xy 102.369055 -232.834239) (xy 102.319649 -232.850288)
			(xy 102.26834 -232.85841) (xy 102.242366 -232.858818) (xy 102.216074 -232.858337) (xy 102.164147 -232.850056)
			(xy 102.11419 -232.833646) (xy 102.067467 -232.809522) (xy 102.046024 -232.794302) (xy 102.034463 -232.786344)
			(xy 102.008195 -232.776487) (xy 101.980236 -232.774152) (xy 101.952697 -232.779516) (xy 101.927658 -232.792173)
			(xy 101.907009 -232.811168) (xy 101.89231 -232.835065) (xy 101.88467 -232.862062) (xy 101.884226 -232.87609)
			(xy 101.884226 -233.368147) (xy 102.382067 -233.368147) (xy 102.382067 -233.316213) (xy 102.390192 -233.264918)
			(xy 102.40624 -233.215525) (xy 102.429818 -233.169251) (xy 102.460344 -233.127235) (xy 102.497067 -233.090512)
			(xy 102.539083 -233.059986) (xy 102.585357 -233.036408) (xy 102.63475 -233.02036) (xy 102.686045 -233.012235)
			(xy 102.737979 -233.012235) (xy 102.789274 -233.02036) (xy 102.838667 -233.036408) (xy 102.884941 -233.059986)
			(xy 102.926957 -233.090512) (xy 102.96368 -233.127235) (xy 102.994206 -233.169251) (xy 103.017784 -233.215525)
			(xy 103.033832 -233.264918) (xy 103.041957 -233.316213) (xy 103.042466 -233.34218) (xy 103.041957 -233.368147)
			(xy 103.321867 -233.368147) (xy 103.321867 -233.316213) (xy 103.329992 -233.264918) (xy 103.34604 -233.215525)
			(xy 103.369618 -233.169251) (xy 103.400144 -233.127235) (xy 103.436867 -233.090512) (xy 103.478883 -233.059986)
			(xy 103.525157 -233.036408) (xy 103.57455 -233.02036) (xy 103.625845 -233.012235) (xy 103.677779 -233.012235)
			(xy 103.729074 -233.02036) (xy 103.778467 -233.036408) (xy 103.824741 -233.059986) (xy 103.866757 -233.090512)
			(xy 103.90348 -233.127235) (xy 103.934006 -233.169251) (xy 103.957584 -233.215525) (xy 103.973632 -233.264918)
			(xy 103.981757 -233.316213) (xy 103.982266 -233.34218) (xy 103.981757 -233.368147) (xy 104.261921 -233.368147)
			(xy 104.261921 -233.316213) (xy 104.270046 -233.264918) (xy 104.286094 -233.215525) (xy 104.309672 -233.169251)
			(xy 104.340198 -233.127235) (xy 104.376921 -233.090512) (xy 104.418937 -233.059986) (xy 104.465211 -233.036408)
			(xy 104.514604 -233.02036) (xy 104.565899 -233.012235) (xy 104.617833 -233.012235) (xy 104.669128 -233.02036)
			(xy 104.718521 -233.036408) (xy 104.764795 -233.059986) (xy 104.806811 -233.090512) (xy 104.843534 -233.127235)
			(xy 104.87406 -233.169251) (xy 104.897638 -233.215525) (xy 104.913686 -233.264918) (xy 104.921811 -233.316213)
			(xy 104.92232 -233.34218) (xy 104.921811 -233.368147) (xy 104.913686 -233.419442) (xy 104.897638 -233.468835)
			(xy 104.87406 -233.515109) (xy 104.843534 -233.557125) (xy 104.806811 -233.593848) (xy 104.764795 -233.624374)
			(xy 104.718521 -233.647952) (xy 104.669128 -233.664) (xy 104.617833 -233.672125) (xy 104.565899 -233.672125)
			(xy 104.514604 -233.664) (xy 104.465211 -233.647952) (xy 104.418937 -233.624374) (xy 104.376921 -233.593848)
			(xy 104.340198 -233.557125) (xy 104.309672 -233.515109) (xy 104.286094 -233.468835) (xy 104.270046 -233.419442)
			(xy 104.261921 -233.368147) (xy 103.981757 -233.368147) (xy 103.973632 -233.419442) (xy 103.957584 -233.468835)
			(xy 103.934006 -233.515109) (xy 103.90348 -233.557125) (xy 103.866757 -233.593848) (xy 103.824741 -233.624374)
			(xy 103.778467 -233.647952) (xy 103.729074 -233.664) (xy 103.677779 -233.672125) (xy 103.625845 -233.672125)
			(xy 103.57455 -233.664) (xy 103.525157 -233.647952) (xy 103.478883 -233.624374) (xy 103.436867 -233.593848)
			(xy 103.400144 -233.557125) (xy 103.369618 -233.515109) (xy 103.34604 -233.468835) (xy 103.329992 -233.419442)
			(xy 103.321867 -233.368147) (xy 103.041957 -233.368147) (xy 103.033832 -233.419442) (xy 103.017784 -233.468835)
			(xy 102.994206 -233.515109) (xy 102.96368 -233.557125) (xy 102.926957 -233.593848) (xy 102.884941 -233.624374)
			(xy 102.838667 -233.647952) (xy 102.789274 -233.664) (xy 102.737979 -233.672125) (xy 102.686045 -233.672125)
			(xy 102.63475 -233.664) (xy 102.585357 -233.647952) (xy 102.539083 -233.624374) (xy 102.497067 -233.593848)
			(xy 102.460344 -233.557125) (xy 102.429818 -233.515109) (xy 102.40624 -233.468835) (xy 102.390192 -233.419442)
			(xy 102.382067 -233.368147) (xy 101.884226 -233.368147) (xy 101.884226 -233.808524) (xy 101.884662 -233.822561)
			(xy 101.892288 -233.849578) (xy 101.906983 -233.873497) (xy 101.927638 -233.89251) (xy 101.952689 -233.905178)
			(xy 101.980244 -233.910545) (xy 102.008219 -233.908205) (xy 102.034499 -233.898333) (xy 102.046024 -233.890312)
			(xy 102.067486 -233.875122) (xy 102.11421 -233.851014) (xy 102.16416 -233.8346) (xy 102.216077 -233.826294)
			(xy 102.242366 -233.825796) (xy 102.268333 -233.826276) (xy 102.319629 -233.834396) (xy 102.369022 -233.85044)
			(xy 102.415298 -233.874014) (xy 102.457315 -233.904538) (xy 102.49404 -233.941259) (xy 102.524568 -233.983273)
			(xy 102.548147 -234.029546) (xy 102.564196 -234.078938) (xy 102.572321 -234.130233) (xy 102.572321 -234.182167)
			(xy 102.572313 -234.182217) (xy 102.852221 -234.182217) (xy 102.852221 -234.130283) (xy 102.860346 -234.078988)
			(xy 102.876394 -234.029595) (xy 102.899972 -233.983321) (xy 102.930498 -233.941305) (xy 102.967221 -233.904582)
			(xy 103.009237 -233.874056) (xy 103.055511 -233.850478) (xy 103.104904 -233.83443) (xy 103.156199 -233.826305)
			(xy 103.208133 -233.826305) (xy 103.259428 -233.83443) (xy 103.308821 -233.850478) (xy 103.355095 -233.874056)
			(xy 103.397111 -233.904582) (xy 103.433834 -233.941305) (xy 103.46436 -233.983321) (xy 103.487938 -234.029595)
			(xy 103.503986 -234.078988) (xy 103.512111 -234.130283) (xy 103.51262 -234.15625) (xy 103.512111 -234.182217)
			(xy 103.792021 -234.182217) (xy 103.792021 -234.130283) (xy 103.800146 -234.078988) (xy 103.816194 -234.029595)
			(xy 103.839772 -233.983321) (xy 103.870298 -233.941305) (xy 103.907021 -233.904582) (xy 103.949037 -233.874056)
			(xy 103.995311 -233.850478) (xy 104.044704 -233.83443) (xy 104.095999 -233.826305) (xy 104.147933 -233.826305)
			(xy 104.199228 -233.83443) (xy 104.248621 -233.850478) (xy 104.294895 -233.874056) (xy 104.336911 -233.904582)
			(xy 104.373634 -233.941305) (xy 104.40416 -233.983321) (xy 104.427738 -234.029595) (xy 104.443786 -234.078988)
			(xy 104.451911 -234.130283) (xy 104.45242 -234.15625) (xy 104.451911 -234.182217) (xy 104.443786 -234.233512)
			(xy 104.427738 -234.282905) (xy 104.40416 -234.329179) (xy 104.373634 -234.371195) (xy 104.336911 -234.407918)
			(xy 104.294895 -234.438444) (xy 104.248621 -234.462022) (xy 104.199228 -234.47807) (xy 104.147933 -234.486195)
			(xy 104.095999 -234.486195) (xy 104.044704 -234.47807) (xy 103.995311 -234.462022) (xy 103.949037 -234.438444)
			(xy 103.907021 -234.407918) (xy 103.870298 -234.371195) (xy 103.839772 -234.329179) (xy 103.816194 -234.282905)
			(xy 103.800146 -234.233512) (xy 103.792021 -234.182217) (xy 103.512111 -234.182217) (xy 103.503986 -234.233512)
			(xy 103.487938 -234.282905) (xy 103.46436 -234.329179) (xy 103.433834 -234.371195) (xy 103.397111 -234.407918)
			(xy 103.355095 -234.438444) (xy 103.308821 -234.462022) (xy 103.259428 -234.47807) (xy 103.208133 -234.486195)
			(xy 103.156199 -234.486195) (xy 103.104904 -234.47807) (xy 103.055511 -234.462022) (xy 103.009237 -234.438444)
			(xy 102.967221 -234.407918) (xy 102.930498 -234.371195) (xy 102.899972 -234.329179) (xy 102.876394 -234.282905)
			(xy 102.860346 -234.233512) (xy 102.852221 -234.182217) (xy 102.572313 -234.182217) (xy 102.564196 -234.233462)
			(xy 102.548147 -234.282854) (xy 102.524568 -234.329127) (xy 102.49404 -234.371141) (xy 102.457315 -234.407862)
			(xy 102.415298 -234.438386) (xy 102.369022 -234.46196) (xy 102.319629 -234.478004) (xy 102.268333 -234.486124)
			(xy 102.242366 -234.486704) (xy 102.216073 -234.486223) (xy 102.164145 -234.477944) (xy 102.114186 -234.461538)
			(xy 102.06746 -234.437419) (xy 102.046024 -234.422188) (xy 102.034462 -234.414231) (xy 102.008193 -234.404375)
			(xy 101.980234 -234.402041) (xy 101.952695 -234.407405) (xy 101.927655 -234.420061) (xy 101.907005 -234.439055)
			(xy 101.892303 -234.462952) (xy 101.884661 -234.489948) (xy 101.884226 -234.503976) (xy 101.884226 -234.657392)
			(xy 101.913436 -234.671362) (xy 101.935742 -234.682407) (xy 101.977041 -234.710189) (xy 102.013706 -234.743852)
			(xy 102.044907 -234.782632) (xy 102.069939 -234.825654) (xy 102.088236 -234.871943) (xy 102.099383 -234.920453)
			(xy 102.103128 -234.970085) (xy 102.099387 -235.019719) (xy 102.094034 -235.043023) (xy 104.285543 -235.043023)
			(xy 104.285543 -234.991089) (xy 104.293668 -234.939794) (xy 104.309716 -234.890401) (xy 104.333294 -234.844127)
			(xy 104.36382 -234.802111) (xy 104.400543 -234.765388) (xy 104.442559 -234.734862) (xy 104.488833 -234.711284)
			(xy 104.538226 -234.695236) (xy 104.589521 -234.687111) (xy 104.641455 -234.687111) (xy 104.69275 -234.695236)
			(xy 104.742143 -234.711284) (xy 104.788417 -234.734862) (xy 104.830433 -234.765388) (xy 104.867156 -234.802111)
			(xy 104.897682 -234.844127) (xy 104.92126 -234.890401) (xy 104.937308 -234.939794) (xy 104.945433 -234.991089)
			(xy 104.945942 -235.017056) (xy 104.945433 -235.043023) (xy 104.937308 -235.094318) (xy 104.92126 -235.143711)
			(xy 104.897682 -235.189985) (xy 104.867156 -235.232001) (xy 104.830433 -235.268724) (xy 104.788417 -235.29925)
			(xy 104.742143 -235.322828) (xy 104.69275 -235.338876) (xy 104.641455 -235.347001) (xy 104.589521 -235.347001)
			(xy 104.538226 -235.338876) (xy 104.488833 -235.322828) (xy 104.442559 -235.29925) (xy 104.400543 -235.268724)
			(xy 104.36382 -235.232001) (xy 104.333294 -235.189985) (xy 104.309716 -235.143711) (xy 104.293668 -235.094318)
			(xy 104.285543 -235.043023) (xy 102.094034 -235.043023) (xy 102.088244 -235.068229) (xy 102.069952 -235.11452)
			(xy 102.044924 -235.157544) (xy 102.013726 -235.196327) (xy 101.977064 -235.229993) (xy 101.935768 -235.257779)
			(xy 101.913436 -235.26877) (xy 101.884226 -235.28274) (xy 101.884226 -235.50118) (xy 101.971094 -235.588048)
			(xy 102.006908 -235.55198) (xy 102.007162 -235.551726) (xy 102.02591 -235.533435) (xy 102.068116 -235.502422)
			(xy 102.114688 -235.478459) (xy 102.164458 -235.462145) (xy 102.216178 -235.45389) (xy 102.242366 -235.453428)
			(xy 102.268338 -235.453908) (xy 102.319642 -235.462029) (xy 102.369044 -235.478076) (xy 102.415328 -235.501653)
			(xy 102.457353 -235.532181) (xy 102.494085 -235.568907) (xy 102.52462 -235.610928) (xy 102.548204 -235.657208)
			(xy 102.564259 -235.706607) (xy 102.572388 -235.757911) (xy 102.57282 -235.783882) (xy 102.572315 -235.810065)
			(xy 102.564047 -235.861775) (xy 102.547731 -235.911536) (xy 102.523775 -235.958102) (xy 102.492778 -236.000309)
			(xy 102.474522 -236.019086) (xy 102.474268 -236.01934) (xy 102.4382 -236.055154) (xy 102.61219 -236.229144)
			(xy 102.648004 -236.193076) (xy 102.666723 -236.174964) (xy 102.708806 -236.144274) (xy 102.755184 -236.12057)
			(xy 102.804708 -236.104437) (xy 102.856149 -236.096277) (xy 102.882192 -236.095794) (xy 102.907012 -236.09624)
			(xy 102.956094 -236.103665) (xy 103.003513 -236.118348) (xy 103.048202 -236.139961) (xy 103.089155 -236.168015)
			(xy 103.12545 -236.201881) (xy 103.15627 -236.240794) (xy 103.180922 -236.283881) (xy 103.190294 -236.306868)
			(xy 103.202994 -236.33938) (xy 104.932226 -236.33938)
		)
		(stroke
			(width 0)
			(type solid)
		)
		(fill yes)
		(layer "In2.Cu")
		(net "P3V3_AUX")
	)
	(gr_poly
		(pts
			(xy 350.673924 -236.130592) (xy 350.697028 -236.11954) (xy 350.7458 -236.103916) (xy 350.796399 -236.096009)
			(xy 350.847613 -236.096009) (xy 350.898212 -236.103916) (xy 350.946984 -236.11954) (xy 350.970088 -236.130592)
			(xy 350.980756 -236.135926) (xy 353.089464 -236.135926) (xy 353.546664 -235.678726) (xy 353.546664 -235.43768)
			(xy 353.546249 -235.424529) (xy 353.539525 -235.3991) (xy 353.526527 -235.376233) (xy 353.508119 -235.357445)
			(xy 353.485523 -235.343983) (xy 353.460237 -235.336741) (xy 353.447096 -235.33608) (xy 353.421466 -235.335084)
			(xy 353.370961 -235.326151) (xy 353.322441 -235.309524) (xy 353.277072 -235.285602) (xy 353.235943 -235.25496)
			(xy 353.20004 -235.218332) (xy 353.170225 -235.176599) (xy 353.147214 -235.130761) (xy 353.13156 -235.081919)
			(xy 353.123638 -235.031245) (xy 353.123638 -234.979956) (xy 353.13156 -234.929282) (xy 353.147214 -234.88044)
			(xy 353.170224 -234.834602) (xy 353.200039 -234.792868) (xy 353.235942 -234.756241) (xy 353.277071 -234.725598)
			(xy 353.32244 -234.701676) (xy 353.37096 -234.685049) (xy 353.421465 -234.676116) (xy 353.447096 -234.675172)
			(xy 353.46024 -234.674501) (xy 353.485537 -234.667275) (xy 353.508145 -234.653821) (xy 353.526562 -234.635034)
			(xy 353.539562 -234.612162) (xy 353.546282 -234.586726) (xy 353.546664 -234.573572) (xy 353.546664 -233.773472)
			(xy 353.546145 -233.758111) (xy 353.537028 -233.728775) (xy 353.519596 -233.703479) (xy 353.495428 -233.684513)
			(xy 353.466713 -233.673596) (xy 353.451414 -233.672126) (xy 353.42522 -233.670008) (xy 353.373941 -233.658525)
			(xy 353.325125 -233.639074) (xy 353.280001 -233.612144) (xy 353.239706 -233.578414) (xy 353.205256 -233.538734)
			(xy 353.177517 -233.494103) (xy 353.157189 -233.445645) (xy 353.144783 -233.394582) (xy 353.140613 -233.342199)
			(xy 353.144784 -233.289816) (xy 353.157189 -233.238752) (xy 353.177518 -233.190295) (xy 353.205257 -233.145664)
			(xy 353.239708 -233.105984) (xy 353.280003 -233.072254) (xy 353.325127 -233.045325) (xy 353.373944 -233.025874)
			(xy 353.425223 -233.014392) (xy 353.451414 -233.012234) (xy 353.466702 -233.010741) (xy 353.495388 -232.999796)
			(xy 353.519532 -232.980829) (xy 353.536959 -232.955551) (xy 353.546098 -232.926239) (xy 353.546664 -232.910888)
			(xy 353.546664 -232.14584) (xy 353.546137 -232.130457) (xy 353.536984 -232.101085) (xy 353.519497 -232.075774)
			(xy 353.495263 -232.05682) (xy 353.466484 -232.045947) (xy 353.45116 -232.044494) (xy 353.424964 -232.042372)
			(xy 353.373681 -232.030881) (xy 353.324861 -232.011422) (xy 353.279735 -231.984485) (xy 353.239439 -231.950749)
			(xy 353.204987 -231.911062) (xy 353.177247 -231.866425) (xy 353.156918 -231.817961) (xy 353.144512 -231.766892)
			(xy 353.140342 -231.714503) (xy 353.144511 -231.662114) (xy 353.156916 -231.611045) (xy 353.177244 -231.562581)
			(xy 353.204983 -231.517943) (xy 353.239435 -231.478256) (xy 353.27973 -231.444518) (xy 353.324856 -231.41758)
			(xy 353.373675 -231.39812) (xy 353.424958 -231.386629) (xy 353.45116 -231.384602) (xy 353.466478 -231.383143)
			(xy 353.495238 -231.372241) (xy 353.519459 -231.353285) (xy 353.536952 -231.327987) (xy 353.546137 -231.298634)
			(xy 353.546664 -231.283256) (xy 353.546664 -230.517954) (xy 353.546139 -230.50257) (xy 353.536988 -230.473194)
			(xy 353.519502 -230.447879) (xy 353.495267 -230.428923) (xy 353.466486 -230.418047) (xy 353.45116 -230.416608)
			(xy 353.426279 -230.414623) (xy 353.377487 -230.404105) (xy 353.330834 -230.386365) (xy 353.28738 -230.361809)
			(xy 353.248115 -230.330995) (xy 353.213933 -230.294624) (xy 353.185612 -230.253524) (xy 353.163797 -230.208632)
			(xy 353.148984 -230.160968) (xy 353.14151 -230.111619) (xy 353.141026 -230.086662) (xy 353.141557 -230.060131)
			(xy 353.150041 -230.007751) (xy 353.166787 -229.9574) (xy 353.191363 -229.910372) (xy 353.206812 -229.888796)
			(xy 353.233228 -229.85349) (xy 352.987864 -229.608126) (xy 350.701864 -229.608126) (xy 350.60382 -229.70617)
			(xy 350.65335 -229.7557) (xy 350.672654 -229.756716) (xy 350.697513 -229.758747) (xy 350.74625 -229.769342)
			(xy 350.792844 -229.787131) (xy 350.836241 -229.811713) (xy 350.875456 -229.842531) (xy 350.909601 -229.878885)
			(xy 350.937902 -229.919953) (xy 350.959718 -229.964803) (xy 350.974556 -230.01242) (xy 350.982077 -230.061725)
			(xy 350.982534 -230.086662) (xy 350.982054 -230.112633) (xy 350.973934 -230.163935) (xy 350.957887 -230.213336)
			(xy 350.934309 -230.259617) (xy 350.90378 -230.30164) (xy 350.867053 -230.338369) (xy 350.825032 -230.368899)
			(xy 350.778752 -230.39248) (xy 350.729353 -230.408529) (xy 350.678051 -230.416653) (xy 350.65208 -230.417116)
			(xy 350.625813 -230.416608) (xy 350.57394 -230.408292) (xy 350.524038 -230.391873) (xy 350.477362 -230.367764)
			(xy 350.435089 -230.336573) (xy 350.398284 -230.299085) (xy 350.367874 -230.256247) (xy 350.344627 -230.209136)
			(xy 350.336358 -230.184198) (xy 350.331416 -230.170082) (xy 350.314655 -230.145328) (xy 350.29145 -230.126481)
			(xy 350.263785 -230.115153) (xy 350.234026 -230.112314) (xy 350.204718 -230.118205) (xy 350.178367 -230.132323)
			(xy 350.167448 -230.142542) (xy 349.889064 -230.420926) (xy 349.889064 -230.513382) (xy 349.889563 -230.528158)
			(xy 349.89802 -230.556474) (xy 349.914232 -230.581181) (xy 349.936841 -230.600212) (xy 349.963952 -230.611971)
			(xy 349.993296 -230.615474) (xy 350.022414 -230.610427) (xy 350.035876 -230.604314) (xy 350.058785 -230.59352)
			(xy 350.107068 -230.578248) (xy 350.157114 -230.570517) (xy 350.182434 -230.570024) (xy 350.208401 -230.570536)
			(xy 350.259696 -230.578665) (xy 350.309087 -230.594718) (xy 350.355359 -230.618299) (xy 350.397373 -230.648828)
			(xy 350.434094 -230.685553) (xy 350.464619 -230.72757) (xy 350.488195 -230.773845) (xy 350.504243 -230.823238)
			(xy 350.512367 -230.874533) (xy 350.512367 -230.926445) (xy 350.792289 -230.926445) (xy 350.792289 -230.874511)
			(xy 350.800414 -230.823216) (xy 350.816462 -230.773823) (xy 350.84004 -230.727549) (xy 350.870566 -230.685533)
			(xy 350.907289 -230.64881) (xy 350.949305 -230.618284) (xy 350.995579 -230.594706) (xy 351.044972 -230.578658)
			(xy 351.096267 -230.570533) (xy 351.148201 -230.570533) (xy 351.199496 -230.578658) (xy 351.248889 -230.594706)
			(xy 351.295163 -230.618284) (xy 351.337179 -230.64881) (xy 351.373902 -230.685533) (xy 351.404428 -230.727549)
			(xy 351.428006 -230.773823) (xy 351.444054 -230.823216) (xy 351.452179 -230.874511) (xy 351.452688 -230.900478)
			(xy 351.452179 -230.926445) (xy 351.732089 -230.926445) (xy 351.732089 -230.874511) (xy 351.740214 -230.823216)
			(xy 351.756262 -230.773823) (xy 351.77984 -230.727549) (xy 351.810366 -230.685533) (xy 351.847089 -230.64881)
			(xy 351.889105 -230.618284) (xy 351.935379 -230.594706) (xy 351.984772 -230.578658) (xy 352.036067 -230.570533)
			(xy 352.088001 -230.570533) (xy 352.139296 -230.578658) (xy 352.188689 -230.594706) (xy 352.234963 -230.618284)
			(xy 352.276979 -230.64881) (xy 352.313702 -230.685533) (xy 352.344228 -230.727549) (xy 352.367806 -230.773823)
			(xy 352.383854 -230.823216) (xy 352.391979 -230.874511) (xy 352.392488 -230.900478) (xy 352.391979 -230.926445)
			(xy 352.671889 -230.926445) (xy 352.671889 -230.874511) (xy 352.680014 -230.823216) (xy 352.696062 -230.773823)
			(xy 352.71964 -230.727549) (xy 352.750166 -230.685533) (xy 352.786889 -230.64881) (xy 352.828905 -230.618284)
			(xy 352.875179 -230.594706) (xy 352.924572 -230.578658) (xy 352.975867 -230.570533) (xy 353.027801 -230.570533)
			(xy 353.079096 -230.578658) (xy 353.128489 -230.594706) (xy 353.174763 -230.618284) (xy 353.216779 -230.64881)
			(xy 353.253502 -230.685533) (xy 353.284028 -230.727549) (xy 353.307606 -230.773823) (xy 353.323654 -230.823216)
			(xy 353.331779 -230.874511) (xy 353.332288 -230.900478) (xy 353.331779 -230.926445) (xy 353.323654 -230.97774)
			(xy 353.307606 -231.027133) (xy 353.284028 -231.073407) (xy 353.253502 -231.115423) (xy 353.216779 -231.152146)
			(xy 353.174763 -231.182672) (xy 353.128489 -231.20625) (xy 353.079096 -231.222298) (xy 353.027801 -231.230423)
			(xy 352.975867 -231.230423) (xy 352.924572 -231.222298) (xy 352.875179 -231.20625) (xy 352.828905 -231.182672)
			(xy 352.786889 -231.152146) (xy 352.750166 -231.115423) (xy 352.71964 -231.073407) (xy 352.696062 -231.027133)
			(xy 352.680014 -230.97774) (xy 352.671889 -230.926445) (xy 352.391979 -230.926445) (xy 352.383854 -230.97774)
			(xy 352.367806 -231.027133) (xy 352.344228 -231.073407) (xy 352.313702 -231.115423) (xy 352.276979 -231.152146)
			(xy 352.234963 -231.182672) (xy 352.188689 -231.20625) (xy 352.139296 -231.222298) (xy 352.088001 -231.230423)
			(xy 352.036067 -231.230423) (xy 351.984772 -231.222298) (xy 351.935379 -231.20625) (xy 351.889105 -231.182672)
			(xy 351.847089 -231.152146) (xy 351.810366 -231.115423) (xy 351.77984 -231.073407) (xy 351.756262 -231.027133)
			(xy 351.740214 -230.97774) (xy 351.732089 -230.926445) (xy 351.452179 -230.926445) (xy 351.444054 -230.97774)
			(xy 351.428006 -231.027133) (xy 351.404428 -231.073407) (xy 351.373902 -231.115423) (xy 351.337179 -231.152146)
			(xy 351.295163 -231.182672) (xy 351.248889 -231.20625) (xy 351.199496 -231.222298) (xy 351.148201 -231.230423)
			(xy 351.096267 -231.230423) (xy 351.044972 -231.222298) (xy 350.995579 -231.20625) (xy 350.949305 -231.182672)
			(xy 350.907289 -231.152146) (xy 350.870566 -231.115423) (xy 350.84004 -231.073407) (xy 350.816462 -231.027133)
			(xy 350.800414 -230.97774) (xy 350.792289 -230.926445) (xy 350.512367 -230.926445) (xy 350.512367 -230.926467)
			(xy 350.504243 -230.977762) (xy 350.488195 -231.027155) (xy 350.464619 -231.07343) (xy 350.434094 -231.115447)
			(xy 350.397373 -231.152172) (xy 350.355359 -231.182701) (xy 350.309087 -231.206282) (xy 350.259696 -231.222335)
			(xy 350.208401 -231.230464) (xy 350.182434 -231.230932) (xy 350.157111 -231.230474) (xy 350.107058 -231.222747)
			(xy 350.058772 -231.207468) (xy 350.035876 -231.196642) (xy 350.022427 -231.19052) (xy 349.99332 -231.185501)
			(xy 349.963994 -231.189021) (xy 349.936901 -231.200786) (xy 349.914308 -231.219811) (xy 349.898104 -231.244506)
			(xy 349.889645 -231.272806) (xy 349.889064 -231.287574) (xy 349.889064 -231.435402) (xy 349.910423 -231.449498)
			(xy 349.948917 -231.483217) (xy 349.98175 -231.522469) (xy 350.008138 -231.566314) (xy 350.02745 -231.613704)
			(xy 350.039223 -231.663505) (xy 350.043176 -231.714526) (xy 350.041158 -231.740515) (xy 350.322135 -231.740515)
			(xy 350.322135 -231.688581) (xy 350.33026 -231.637286) (xy 350.346308 -231.587893) (xy 350.369886 -231.541619)
			(xy 350.400412 -231.499603) (xy 350.437135 -231.46288) (xy 350.479151 -231.432354) (xy 350.525425 -231.408776)
			(xy 350.574818 -231.392728) (xy 350.626113 -231.384603) (xy 350.678047 -231.384603) (xy 350.729342 -231.392728)
			(xy 350.778735 -231.408776) (xy 350.825009 -231.432354) (xy 350.867025 -231.46288) (xy 350.903748 -231.499603)
			(xy 350.934274 -231.541619) (xy 350.957852 -231.587893) (xy 350.9739 -231.637286) (xy 350.982025 -231.688581)
			(xy 350.982534 -231.714548) (xy 350.982025 -231.740515) (xy 351.261935 -231.740515) (xy 351.261935 -231.688581)
			(xy 351.27006 -231.637286) (xy 351.286108 -231.587893) (xy 351.309686 -231.541619) (xy 351.340212 -231.499603)
			(xy 351.376935 -231.46288) (xy 351.418951 -231.432354) (xy 351.465225 -231.408776) (xy 351.514618 -231.392728)
			(xy 351.565913 -231.384603) (xy 351.617847 -231.384603) (xy 351.669142 -231.392728) (xy 351.718535 -231.408776)
			(xy 351.764809 -231.432354) (xy 351.806825 -231.46288) (xy 351.843548 -231.499603) (xy 351.874074 -231.541619)
			(xy 351.897652 -231.587893) (xy 351.9137 -231.637286) (xy 351.921825 -231.688581) (xy 351.922334 -231.714548)
			(xy 351.921825 -231.740515) (xy 352.201735 -231.740515) (xy 352.201735 -231.688581) (xy 352.20986 -231.637286)
			(xy 352.225908 -231.587893) (xy 352.249486 -231.541619) (xy 352.280012 -231.499603) (xy 352.316735 -231.46288)
			(xy 352.358751 -231.432354) (xy 352.405025 -231.408776) (xy 352.454418 -231.392728) (xy 352.505713 -231.384603)
			(xy 352.557647 -231.384603) (xy 352.608942 -231.392728) (xy 352.658335 -231.408776) (xy 352.704609 -231.432354)
			(xy 352.746625 -231.46288) (xy 352.783348 -231.499603) (xy 352.813874 -231.541619) (xy 352.837452 -231.587893)
			(xy 352.8535 -231.637286) (xy 352.861625 -231.688581) (xy 352.862134 -231.714548) (xy 352.861625 -231.740515)
			(xy 352.8535 -231.79181) (xy 352.837452 -231.841203) (xy 352.813874 -231.887477) (xy 352.783348 -231.929493)
			(xy 352.746625 -231.966216) (xy 352.704609 -231.996742) (xy 352.658335 -232.02032) (xy 352.608942 -232.036368)
			(xy 352.557647 -232.044493) (xy 352.505713 -232.044493) (xy 352.454418 -232.036368) (xy 352.405025 -232.02032)
			(xy 352.358751 -231.996742) (xy 352.316735 -231.966216) (xy 352.280012 -231.929493) (xy 352.249486 -231.887477)
			(xy 352.225908 -231.841203) (xy 352.20986 -231.79181) (xy 352.201735 -231.740515) (xy 351.921825 -231.740515)
			(xy 351.9137 -231.79181) (xy 351.897652 -231.841203) (xy 351.874074 -231.887477) (xy 351.843548 -231.929493)
			(xy 351.806825 -231.966216) (xy 351.764809 -231.996742) (xy 351.718535 -232.02032) (xy 351.669142 -232.036368)
			(xy 351.617847 -232.044493) (xy 351.565913 -232.044493) (xy 351.514618 -232.036368) (xy 351.465225 -232.02032)
			(xy 351.418951 -231.996742) (xy 351.376935 -231.966216) (xy 351.340212 -231.929493) (xy 351.309686 -231.887477)
			(xy 351.286108 -231.841203) (xy 351.27006 -231.79181) (xy 351.261935 -231.740515) (xy 350.982025 -231.740515)
			(xy 350.9739 -231.79181) (xy 350.957852 -231.841203) (xy 350.934274 -231.887477) (xy 350.903748 -231.929493)
			(xy 350.867025 -231.966216) (xy 350.825009 -231.996742) (xy 350.778735 -232.02032) (xy 350.729342 -232.036368)
			(xy 350.678047 -232.044493) (xy 350.626113 -232.044493) (xy 350.574818 -232.036368) (xy 350.525425 -232.02032)
			(xy 350.479151 -231.996742) (xy 350.437135 -231.966216) (xy 350.400412 -231.929493) (xy 350.369886 -231.887477)
			(xy 350.346308 -231.841203) (xy 350.33026 -231.79181) (xy 350.322135 -231.740515) (xy 350.041158 -231.740515)
			(xy 350.039215 -231.765546) (xy 350.027434 -231.815345) (xy 350.008115 -231.862732) (xy 349.98172 -231.906573)
			(xy 349.948881 -231.945819) (xy 349.910382 -231.979533) (xy 349.889064 -231.993694) (xy 349.889064 -232.141268)
			(xy 349.889561 -232.156045) (xy 349.898016 -232.184365) (xy 349.914228 -232.209076) (xy 349.936838 -232.22811)
			(xy 349.963951 -232.239871) (xy 349.993298 -232.243374) (xy 350.022418 -232.238326) (xy 350.035876 -232.2322)
			(xy 350.058785 -232.221406) (xy 350.107068 -232.206135) (xy 350.157114 -232.198404) (xy 350.182434 -232.19791)
			(xy 350.208402 -232.198422) (xy 350.259699 -232.206551) (xy 350.309092 -232.222605) (xy 350.355366 -232.246187)
			(xy 350.397382 -232.276717) (xy 350.434105 -232.313444) (xy 350.464631 -232.355463) (xy 350.488208 -232.401739)
			(xy 350.504257 -232.451134) (xy 350.512381 -232.502432) (xy 350.512381 -232.554331) (xy 350.792289 -232.554331)
			(xy 350.792289 -232.502397) (xy 350.800414 -232.451102) (xy 350.816462 -232.401709) (xy 350.84004 -232.355435)
			(xy 350.870566 -232.313419) (xy 350.907289 -232.276696) (xy 350.949305 -232.24617) (xy 350.995579 -232.222592)
			(xy 351.044972 -232.206544) (xy 351.096267 -232.198419) (xy 351.148201 -232.198419) (xy 351.199496 -232.206544)
			(xy 351.248889 -232.222592) (xy 351.295163 -232.24617) (xy 351.337179 -232.276696) (xy 351.373902 -232.313419)
			(xy 351.404428 -232.355435) (xy 351.428006 -232.401709) (xy 351.444054 -232.451102) (xy 351.452179 -232.502397)
			(xy 351.452688 -232.528364) (xy 351.452179 -232.554331) (xy 351.732089 -232.554331) (xy 351.732089 -232.502397)
			(xy 351.740214 -232.451102) (xy 351.756262 -232.401709) (xy 351.77984 -232.355435) (xy 351.810366 -232.313419)
			(xy 351.847089 -232.276696) (xy 351.889105 -232.24617) (xy 351.935379 -232.222592) (xy 351.984772 -232.206544)
			(xy 352.036067 -232.198419) (xy 352.088001 -232.198419) (xy 352.139296 -232.206544) (xy 352.188689 -232.222592)
			(xy 352.234963 -232.24617) (xy 352.276979 -232.276696) (xy 352.313702 -232.313419) (xy 352.344228 -232.355435)
			(xy 352.367806 -232.401709) (xy 352.383854 -232.451102) (xy 352.391979 -232.502397) (xy 352.392488 -232.528364)
			(xy 352.391979 -232.554331) (xy 352.671889 -232.554331) (xy 352.671889 -232.502397) (xy 352.680014 -232.451102)
			(xy 352.696062 -232.401709) (xy 352.71964 -232.355435) (xy 352.750166 -232.313419) (xy 352.786889 -232.276696)
			(xy 352.828905 -232.24617) (xy 352.875179 -232.222592) (xy 352.924572 -232.206544) (xy 352.975867 -232.198419)
			(xy 353.027801 -232.198419) (xy 353.079096 -232.206544) (xy 353.128489 -232.222592) (xy 353.174763 -232.24617)
			(xy 353.216779 -232.276696) (xy 353.253502 -232.313419) (xy 353.284028 -232.355435) (xy 353.307606 -232.401709)
			(xy 353.323654 -232.451102) (xy 353.331779 -232.502397) (xy 353.332288 -232.528364) (xy 353.331779 -232.554331)
			(xy 353.323654 -232.605626) (xy 353.307606 -232.655019) (xy 353.284028 -232.701293) (xy 353.253502 -232.743309)
			(xy 353.216779 -232.780032) (xy 353.174763 -232.810558) (xy 353.128489 -232.834136) (xy 353.079096 -232.850184)
			(xy 353.027801 -232.858309) (xy 352.975867 -232.858309) (xy 352.924572 -232.850184) (xy 352.875179 -232.834136)
			(xy 352.828905 -232.810558) (xy 352.786889 -232.780032) (xy 352.750166 -232.743309) (xy 352.71964 -232.701293)
			(xy 352.696062 -232.655019) (xy 352.680014 -232.605626) (xy 352.671889 -232.554331) (xy 352.391979 -232.554331)
			(xy 352.383854 -232.605626) (xy 352.367806 -232.655019) (xy 352.344228 -232.701293) (xy 352.313702 -232.743309)
			(xy 352.276979 -232.780032) (xy 352.234963 -232.810558) (xy 352.188689 -232.834136) (xy 352.139296 -232.850184)
			(xy 352.088001 -232.858309) (xy 352.036067 -232.858309) (xy 351.984772 -232.850184) (xy 351.935379 -232.834136)
			(xy 351.889105 -232.810558) (xy 351.847089 -232.780032) (xy 351.810366 -232.743309) (xy 351.77984 -232.701293)
			(xy 351.756262 -232.655019) (xy 351.740214 -232.605626) (xy 351.732089 -232.554331) (xy 351.452179 -232.554331)
			(xy 351.444054 -232.605626) (xy 351.428006 -232.655019) (xy 351.404428 -232.701293) (xy 351.373902 -232.743309)
			(xy 351.337179 -232.780032) (xy 351.295163 -232.810558) (xy 351.248889 -232.834136) (xy 351.199496 -232.850184)
			(xy 351.148201 -232.858309) (xy 351.096267 -232.858309) (xy 351.044972 -232.850184) (xy 350.995579 -232.834136)
			(xy 350.949305 -232.810558) (xy 350.907289 -232.780032) (xy 350.870566 -232.743309) (xy 350.84004 -232.701293)
			(xy 350.816462 -232.655019) (xy 350.800414 -232.605626) (xy 350.792289 -232.554331) (xy 350.512381 -232.554331)
			(xy 350.512381 -232.554368) (xy 350.504257 -232.605666) (xy 350.488208 -232.655061) (xy 350.464631 -232.701337)
			(xy 350.434105 -232.743356) (xy 350.397382 -232.780083) (xy 350.355366 -232.810613) (xy 350.309092 -232.834195)
			(xy 350.259699 -232.850249) (xy 350.208402 -232.858378) (xy 350.182434 -232.858818) (xy 350.157111 -232.85836)
			(xy 350.107059 -232.850633) (xy 350.058773 -232.835353) (xy 350.035876 -232.824528) (xy 350.022426 -232.818407)
			(xy 349.993318 -232.813389) (xy 349.963991 -232.816909) (xy 349.936898 -232.828673) (xy 349.914303 -232.847698)
			(xy 349.898097 -232.872392) (xy 349.889634 -232.900692) (xy 349.889064 -232.91546) (xy 349.889064 -233.368147)
			(xy 350.322135 -233.368147) (xy 350.322135 -233.316213) (xy 350.33026 -233.264918) (xy 350.346308 -233.215525)
			(xy 350.369886 -233.169251) (xy 350.400412 -233.127235) (xy 350.437135 -233.090512) (xy 350.479151 -233.059986)
			(xy 350.525425 -233.036408) (xy 350.574818 -233.02036) (xy 350.626113 -233.012235) (xy 350.678047 -233.012235)
			(xy 350.729342 -233.02036) (xy 350.778735 -233.036408) (xy 350.825009 -233.059986) (xy 350.867025 -233.090512)
			(xy 350.903748 -233.127235) (xy 350.934274 -233.169251) (xy 350.957852 -233.215525) (xy 350.9739 -233.264918)
			(xy 350.982025 -233.316213) (xy 350.982534 -233.34218) (xy 350.982025 -233.368147) (xy 351.261935 -233.368147)
			(xy 351.261935 -233.316213) (xy 351.27006 -233.264918) (xy 351.286108 -233.215525) (xy 351.309686 -233.169251)
			(xy 351.340212 -233.127235) (xy 351.376935 -233.090512) (xy 351.418951 -233.059986) (xy 351.465225 -233.036408)
			(xy 351.514618 -233.02036) (xy 351.565913 -233.012235) (xy 351.617847 -233.012235) (xy 351.669142 -233.02036)
			(xy 351.718535 -233.036408) (xy 351.764809 -233.059986) (xy 351.806825 -233.090512) (xy 351.843548 -233.127235)
			(xy 351.874074 -233.169251) (xy 351.897652 -233.215525) (xy 351.9137 -233.264918) (xy 351.921825 -233.316213)
			(xy 351.922334 -233.34218) (xy 351.921825 -233.368147) (xy 352.201989 -233.368147) (xy 352.201989 -233.316213)
			(xy 352.210114 -233.264918) (xy 352.226162 -233.215525) (xy 352.24974 -233.169251) (xy 352.280266 -233.127235)
			(xy 352.316989 -233.090512) (xy 352.359005 -233.059986) (xy 352.405279 -233.036408) (xy 352.454672 -233.02036)
			(xy 352.505967 -233.012235) (xy 352.557901 -233.012235) (xy 352.609196 -233.02036) (xy 352.658589 -233.036408)
			(xy 352.704863 -233.059986) (xy 352.746879 -233.090512) (xy 352.783602 -233.127235) (xy 352.814128 -233.169251)
			(xy 352.837706 -233.215525) (xy 352.853754 -233.264918) (xy 352.861879 -233.316213) (xy 352.862388 -233.34218)
			(xy 352.861879 -233.368147) (xy 352.853754 -233.419442) (xy 352.837706 -233.468835) (xy 352.814128 -233.515109)
			(xy 352.783602 -233.557125) (xy 352.746879 -233.593848) (xy 352.704863 -233.624374) (xy 352.658589 -233.647952)
			(xy 352.609196 -233.664) (xy 352.557901 -233.672125) (xy 352.505967 -233.672125) (xy 352.454672 -233.664)
			(xy 352.405279 -233.647952) (xy 352.359005 -233.624374) (xy 352.316989 -233.593848) (xy 352.280266 -233.557125)
			(xy 352.24974 -233.515109) (xy 352.226162 -233.468835) (xy 352.210114 -233.419442) (xy 352.201989 -233.368147)
			(xy 351.921825 -233.368147) (xy 351.9137 -233.419442) (xy 351.897652 -233.468835) (xy 351.874074 -233.515109)
			(xy 351.843548 -233.557125) (xy 351.806825 -233.593848) (xy 351.764809 -233.624374) (xy 351.718535 -233.647952)
			(xy 351.669142 -233.664) (xy 351.617847 -233.672125) (xy 351.565913 -233.672125) (xy 351.514618 -233.664)
			(xy 351.465225 -233.647952) (xy 351.418951 -233.624374) (xy 351.376935 -233.593848) (xy 351.340212 -233.557125)
			(xy 351.309686 -233.515109) (xy 351.286108 -233.468835) (xy 351.27006 -233.419442) (xy 351.261935 -233.368147)
			(xy 350.982025 -233.368147) (xy 350.9739 -233.419442) (xy 350.957852 -233.468835) (xy 350.934274 -233.515109)
			(xy 350.903748 -233.557125) (xy 350.867025 -233.593848) (xy 350.825009 -233.624374) (xy 350.778735 -233.647952)
			(xy 350.729342 -233.664) (xy 350.678047 -233.672125) (xy 350.626113 -233.672125) (xy 350.574818 -233.664)
			(xy 350.525425 -233.647952) (xy 350.479151 -233.624374) (xy 350.437135 -233.593848) (xy 350.400412 -233.557125)
			(xy 350.369886 -233.515109) (xy 350.346308 -233.468835) (xy 350.33026 -233.419442) (xy 350.322135 -233.368147)
			(xy 349.889064 -233.368147) (xy 349.889064 -233.769154) (xy 349.889559 -233.783933) (xy 349.898012 -233.812256)
			(xy 349.914223 -233.836971) (xy 349.936834 -233.856008) (xy 349.96395 -233.867771) (xy 349.9933 -233.871274)
			(xy 350.022423 -233.866224) (xy 350.035876 -233.860086) (xy 350.058784 -233.849289) (xy 350.107067 -233.834015)
			(xy 350.157114 -233.826282) (xy 350.182434 -233.825796) (xy 350.208396 -233.826308) (xy 350.259679 -233.834435)
			(xy 350.309059 -233.850484) (xy 350.355321 -233.87406) (xy 350.397326 -233.904582) (xy 350.43404 -233.9413)
			(xy 350.464558 -233.983308) (xy 350.488129 -234.029572) (xy 350.504173 -234.078954) (xy 350.512295 -234.130238)
			(xy 350.512295 -234.182162) (xy 350.512286 -234.182217) (xy 350.792289 -234.182217) (xy 350.792289 -234.130283)
			(xy 350.800414 -234.078988) (xy 350.816462 -234.029595) (xy 350.84004 -233.983321) (xy 350.870566 -233.941305)
			(xy 350.907289 -233.904582) (xy 350.949305 -233.874056) (xy 350.995579 -233.850478) (xy 351.044972 -233.83443)
			(xy 351.096267 -233.826305) (xy 351.148201 -233.826305) (xy 351.199496 -233.83443) (xy 351.248889 -233.850478)
			(xy 351.295163 -233.874056) (xy 351.337179 -233.904582) (xy 351.373902 -233.941305) (xy 351.404428 -233.983321)
			(xy 351.428006 -234.029595) (xy 351.444054 -234.078988) (xy 351.452179 -234.130283) (xy 351.452688 -234.15625)
			(xy 351.452179 -234.182217) (xy 351.732089 -234.182217) (xy 351.732089 -234.130283) (xy 351.740214 -234.078988)
			(xy 351.756262 -234.029595) (xy 351.77984 -233.983321) (xy 351.810366 -233.941305) (xy 351.847089 -233.904582)
			(xy 351.889105 -233.874056) (xy 351.935379 -233.850478) (xy 351.984772 -233.83443) (xy 352.036067 -233.826305)
			(xy 352.088001 -233.826305) (xy 352.139296 -233.83443) (xy 352.188689 -233.850478) (xy 352.234963 -233.874056)
			(xy 352.276979 -233.904582) (xy 352.313702 -233.941305) (xy 352.344228 -233.983321) (xy 352.367806 -234.029595)
			(xy 352.383854 -234.078988) (xy 352.391979 -234.130283) (xy 352.392488 -234.15625) (xy 352.391979 -234.182217)
			(xy 352.383854 -234.233512) (xy 352.367806 -234.282905) (xy 352.344228 -234.329179) (xy 352.313702 -234.371195)
			(xy 352.276979 -234.407918) (xy 352.234963 -234.438444) (xy 352.188689 -234.462022) (xy 352.139296 -234.47807)
			(xy 352.088001 -234.486195) (xy 352.036067 -234.486195) (xy 351.984772 -234.47807) (xy 351.935379 -234.462022)
			(xy 351.889105 -234.438444) (xy 351.847089 -234.407918) (xy 351.810366 -234.371195) (xy 351.77984 -234.329179)
			(xy 351.756262 -234.282905) (xy 351.740214 -234.233512) (xy 351.732089 -234.182217) (xy 351.452179 -234.182217)
			(xy 351.444054 -234.233512) (xy 351.428006 -234.282905) (xy 351.404428 -234.329179) (xy 351.373902 -234.371195)
			(xy 351.337179 -234.407918) (xy 351.295163 -234.438444) (xy 351.248889 -234.462022) (xy 351.199496 -234.47807)
			(xy 351.148201 -234.486195) (xy 351.096267 -234.486195) (xy 351.044972 -234.47807) (xy 350.995579 -234.462022)
			(xy 350.949305 -234.438444) (xy 350.907289 -234.407918) (xy 350.870566 -234.371195) (xy 350.84004 -234.329179)
			(xy 350.816462 -234.282905) (xy 350.800414 -234.233512) (xy 350.792289 -234.182217) (xy 350.512286 -234.182217)
			(xy 350.504173 -234.233446) (xy 350.488129 -234.282828) (xy 350.464558 -234.329092) (xy 350.43404 -234.3711)
			(xy 350.397326 -234.407818) (xy 350.355321 -234.43834) (xy 350.309059 -234.461916) (xy 350.259679 -234.477965)
			(xy 350.208396 -234.486092) (xy 350.182434 -234.486704) (xy 350.157111 -234.486246) (xy 350.107059 -234.478518)
			(xy 350.058773 -234.463238) (xy 350.035876 -234.452414) (xy 350.022425 -234.446294) (xy 349.993317 -234.441276)
			(xy 349.963989 -234.444796) (xy 349.936894 -234.45656) (xy 349.914298 -234.475584) (xy 349.89809 -234.500278)
			(xy 349.889624 -234.528577) (xy 349.889064 -234.543346) (xy 349.889064 -234.69092) (xy 349.91043 -234.705016)
			(xy 349.948935 -234.738737) (xy 349.981781 -234.777993) (xy 350.00818 -234.821844) (xy 350.027502 -234.869241)
			(xy 350.039285 -234.919051) (xy 350.043246 -234.970082) (xy 350.03929 -235.021113) (xy 350.027513 -235.070924)
			(xy 350.008197 -235.118323) (xy 349.981802 -235.162177) (xy 349.948961 -235.201436) (xy 349.910459 -235.235162)
			(xy 349.889064 -235.249212) (xy 349.889064 -235.399326) (xy 349.997268 -235.50753) (xy 350.030288 -235.490512)
			(xy 350.053933 -235.478838) (xy 350.104008 -235.462314) (xy 350.156069 -235.45394) (xy 350.182434 -235.453428)
			(xy 350.2084 -235.45394) (xy 350.259692 -235.462068) (xy 350.309081 -235.47812) (xy 350.355352 -235.501699)
			(xy 350.397364 -235.532225) (xy 350.434085 -235.568948) (xy 350.46461 -235.610962) (xy 350.488187 -235.657234)
			(xy 350.504236 -235.706624) (xy 350.512361 -235.757916) (xy 350.512888 -235.783882) (xy 350.512376 -235.810247)
			(xy 350.504008 -235.86231) (xy 350.487482 -235.912384) (xy 350.475804 -235.936028) (xy 350.458786 -235.969048)
			(xy 350.625664 -236.135926) (xy 350.663256 -236.135926)
		)
		(stroke
			(width 0)
			(type solid)
		)
		(fill yes)
		(layer "In2.Cu")
		(net "P3V3_AUX")
	)
	(gr_poly
		(pts
			(xy 427.321472 -109.896148) (xy 427.322031 -109.867175) (xy 427.331139 -109.809947) (xy 427.349091 -109.75485)
			(xy 427.375445 -109.703242) (xy 427.40955 -109.656394) (xy 427.429676 -109.635544) (xy 427.912276 -109.152944)
			(xy 427.933124 -109.132814) (xy 427.979971 -109.098703) (xy 428.031579 -109.072342) (xy 428.086676 -109.054381)
			(xy 428.143905 -109.045264) (xy 428.17288 -109.04474) (xy 431.957226 -109.04474) (xy 432.560476 -108.441744)
			(xy 432.581324 -108.421614) (xy 432.628171 -108.387503) (xy 432.679779 -108.361142) (xy 432.734876 -108.343181)
			(xy 432.792105 -108.334064) (xy 432.82108 -108.33354) (xy 436.296054 -108.33354) (xy 437.07304 -107.556808)
			(xy 437.07304 -97.170748) (xy 436.722266 -96.819974) (xy 436.712109 -96.810413) (xy 436.687803 -96.796744)
			(xy 436.660705 -96.790165) (xy 436.632837 -96.791166) (xy 436.606281 -96.799672) (xy 436.583018 -96.815049)
			(xy 436.564786 -96.836149) (xy 436.552946 -96.861396) (xy 436.550308 -96.875092) (xy 436.545466 -96.901499)
			(xy 436.529345 -96.952707) (xy 436.506203 -97.00115) (xy 436.476498 -97.045868) (xy 436.440815 -97.08598)
			(xy 436.399861 -97.120692) (xy 436.354443 -97.149319) (xy 436.305461 -97.171295) (xy 436.253881 -97.186185)
			(xy 436.200723 -97.193696) (xy 436.17388 -97.194116) (xy 436.146629 -97.193629) (xy 436.092683 -97.18587)
			(xy 436.040391 -97.170513) (xy 435.990815 -97.147871) (xy 435.944967 -97.118404) (xy 435.903778 -97.082713)
			(xy 435.868088 -97.041523) (xy 435.838623 -96.995674) (xy 435.815982 -96.946098) (xy 435.800627 -96.893805)
			(xy 435.79287 -96.839859) (xy 435.792372 -96.812608) (xy 435.792835 -96.785771) (xy 435.800368 -96.732629)
			(xy 435.815273 -96.681067) (xy 435.837256 -96.632102) (xy 435.865882 -96.5867) (xy 435.900588 -96.545757)
			(xy 435.940689 -96.510081) (xy 435.985392 -96.480376) (xy 436.033817 -96.457227) (xy 436.085008 -96.441092)
			(xy 436.111396 -96.43618) (xy 436.125048 -96.433441) (xy 436.150226 -96.421572) (xy 436.171264 -96.403344)
			(xy 436.186598 -96.380113) (xy 436.195088 -96.353605) (xy 436.196105 -96.325788) (xy 436.189573 -96.29873)
			(xy 436.175977 -96.274441) (xy 436.166514 -96.264222) (xy 435.73446 -95.832168) (xy 428.054008 -95.832168)
			(xy 428.054008 -96.812608) (xy 434.902862 -96.812608) (xy 434.906933 -96.756986) (xy 434.919059 -96.702549)
			(xy 434.938982 -96.650458) (xy 434.966278 -96.601823) (xy 435.000364 -96.55768) (xy 435.040513 -96.518971)
			(xy 435.085871 -96.48652) (xy 435.135471 -96.461019) (xy 435.188255 -96.443012) (xy 435.243098 -96.432882)
			(xy 435.298832 -96.430845) (xy 435.354269 -96.436945) (xy 435.408226 -96.451051) (xy 435.459555 -96.472863)
			(xy 435.507161 -96.501917) (xy 435.550029 -96.537592) (xy 435.587246 -96.579129) (xy 435.618019 -96.625642)
			(xy 435.641691 -96.676139) (xy 435.657759 -96.729546) (xy 435.665879 -96.784722) (xy 435.666388 -96.812608)
			(xy 435.665879 -96.840494) (xy 435.657759 -96.89567) (xy 435.641691 -96.949077) (xy 435.618019 -96.999574)
			(xy 435.587246 -97.046087) (xy 435.550029 -97.087624) (xy 435.507161 -97.123299) (xy 435.459555 -97.152353)
			(xy 435.408226 -97.174165) (xy 435.354269 -97.188271) (xy 435.298832 -97.194371) (xy 435.243098 -97.192334)
			(xy 435.188255 -97.182204) (xy 435.135471 -97.164197) (xy 435.085871 -97.138696) (xy 435.040513 -97.106245)
			(xy 435.000364 -97.067536) (xy 434.966278 -97.023393) (xy 434.938982 -96.974758) (xy 434.919059 -96.922667)
			(xy 434.906933 -96.86823) (xy 434.902862 -96.812608) (xy 428.054008 -96.812608) (xy 428.054008 -97.701608)
			(xy 434.902862 -97.701608) (xy 434.906933 -97.645986) (xy 434.919059 -97.591549) (xy 434.938982 -97.539458)
			(xy 434.966278 -97.490823) (xy 435.000364 -97.44668) (xy 435.040513 -97.407971) (xy 435.085871 -97.37552)
			(xy 435.135471 -97.350019) (xy 435.188255 -97.332012) (xy 435.243098 -97.321882) (xy 435.298832 -97.319845)
			(xy 435.354269 -97.325945) (xy 435.408226 -97.340051) (xy 435.459555 -97.361863) (xy 435.507161 -97.390917)
			(xy 435.550029 -97.426592) (xy 435.587246 -97.468129) (xy 435.618019 -97.514642) (xy 435.641691 -97.565139)
			(xy 435.657759 -97.618546) (xy 435.665879 -97.673722) (xy 435.666388 -97.701608) (xy 435.791862 -97.701608)
			(xy 435.795933 -97.645986) (xy 435.808059 -97.591549) (xy 435.827982 -97.539458) (xy 435.855278 -97.490823)
			(xy 435.889364 -97.44668) (xy 435.929513 -97.407971) (xy 435.974871 -97.37552) (xy 436.024471 -97.350019)
			(xy 436.077255 -97.332012) (xy 436.132098 -97.321882) (xy 436.187832 -97.319845) (xy 436.243269 -97.325945)
			(xy 436.297226 -97.340051) (xy 436.348555 -97.361863) (xy 436.396161 -97.390917) (xy 436.439029 -97.426592)
			(xy 436.476246 -97.468129) (xy 436.507019 -97.514642) (xy 436.530691 -97.565139) (xy 436.546759 -97.618546)
			(xy 436.554879 -97.673722) (xy 436.555388 -97.701608) (xy 436.554879 -97.729494) (xy 436.546759 -97.78467)
			(xy 436.530691 -97.838077) (xy 436.507019 -97.888574) (xy 436.476246 -97.935087) (xy 436.439029 -97.976624)
			(xy 436.396161 -98.012299) (xy 436.348555 -98.041353) (xy 436.297226 -98.063165) (xy 436.243269 -98.077271)
			(xy 436.187832 -98.083371) (xy 436.132098 -98.081334) (xy 436.077255 -98.071204) (xy 436.024471 -98.053197)
			(xy 435.974871 -98.027696) (xy 435.929513 -97.995245) (xy 435.889364 -97.956536) (xy 435.855278 -97.912393)
			(xy 435.827982 -97.863758) (xy 435.808059 -97.811667) (xy 435.795933 -97.75723) (xy 435.791862 -97.701608)
			(xy 435.666388 -97.701608) (xy 435.665879 -97.729494) (xy 435.657759 -97.78467) (xy 435.641691 -97.838077)
			(xy 435.618019 -97.888574) (xy 435.587246 -97.935087) (xy 435.550029 -97.976624) (xy 435.507161 -98.012299)
			(xy 435.459555 -98.041353) (xy 435.408226 -98.063165) (xy 435.354269 -98.077271) (xy 435.298832 -98.083371)
			(xy 435.243098 -98.081334) (xy 435.188255 -98.071204) (xy 435.135471 -98.053197) (xy 435.085871 -98.027696)
			(xy 435.040513 -97.995245) (xy 435.000364 -97.956536) (xy 434.966278 -97.912393) (xy 434.938982 -97.863758)
			(xy 434.919059 -97.811667) (xy 434.906933 -97.75723) (xy 434.902862 -97.701608) (xy 428.054008 -97.701608)
			(xy 428.054008 -98.590608) (xy 434.902862 -98.590608) (xy 434.906933 -98.534986) (xy 434.919059 -98.480549)
			(xy 434.938982 -98.428458) (xy 434.966278 -98.379823) (xy 435.000364 -98.33568) (xy 435.040513 -98.296971)
			(xy 435.085871 -98.26452) (xy 435.135471 -98.239019) (xy 435.188255 -98.221012) (xy 435.243098 -98.210882)
			(xy 435.298832 -98.208845) (xy 435.354269 -98.214945) (xy 435.408226 -98.229051) (xy 435.459555 -98.250863)
			(xy 435.507161 -98.279917) (xy 435.550029 -98.315592) (xy 435.587246 -98.357129) (xy 435.618019 -98.403642)
			(xy 435.641691 -98.454139) (xy 435.657759 -98.507546) (xy 435.665879 -98.562722) (xy 435.666388 -98.590608)
			(xy 435.791862 -98.590608) (xy 435.795933 -98.534986) (xy 435.808059 -98.480549) (xy 435.827982 -98.428458)
			(xy 435.855278 -98.379823) (xy 435.889364 -98.33568) (xy 435.929513 -98.296971) (xy 435.974871 -98.26452)
			(xy 436.024471 -98.239019) (xy 436.077255 -98.221012) (xy 436.132098 -98.210882) (xy 436.187832 -98.208845)
			(xy 436.243269 -98.214945) (xy 436.297226 -98.229051) (xy 436.348555 -98.250863) (xy 436.396161 -98.279917)
			(xy 436.439029 -98.315592) (xy 436.476246 -98.357129) (xy 436.507019 -98.403642) (xy 436.530691 -98.454139)
			(xy 436.546759 -98.507546) (xy 436.554879 -98.562722) (xy 436.555388 -98.590608) (xy 436.554879 -98.618494)
			(xy 436.546759 -98.67367) (xy 436.530691 -98.727077) (xy 436.507019 -98.777574) (xy 436.476246 -98.824087)
			(xy 436.439029 -98.865624) (xy 436.396161 -98.901299) (xy 436.348555 -98.930353) (xy 436.297226 -98.952165)
			(xy 436.243269 -98.966271) (xy 436.187832 -98.972371) (xy 436.132098 -98.970334) (xy 436.077255 -98.960204)
			(xy 436.024471 -98.942197) (xy 435.974871 -98.916696) (xy 435.929513 -98.884245) (xy 435.889364 -98.845536)
			(xy 435.855278 -98.801393) (xy 435.827982 -98.752758) (xy 435.808059 -98.700667) (xy 435.795933 -98.64623)
			(xy 435.791862 -98.590608) (xy 435.666388 -98.590608) (xy 435.665879 -98.618494) (xy 435.657759 -98.67367)
			(xy 435.641691 -98.727077) (xy 435.618019 -98.777574) (xy 435.587246 -98.824087) (xy 435.550029 -98.865624)
			(xy 435.507161 -98.901299) (xy 435.459555 -98.930353) (xy 435.408226 -98.952165) (xy 435.354269 -98.966271)
			(xy 435.298832 -98.972371) (xy 435.243098 -98.970334) (xy 435.188255 -98.960204) (xy 435.135471 -98.942197)
			(xy 435.085871 -98.916696) (xy 435.040513 -98.884245) (xy 435.000364 -98.845536) (xy 434.966278 -98.801393)
			(xy 434.938982 -98.752758) (xy 434.919059 -98.700667) (xy 434.906933 -98.64623) (xy 434.902862 -98.590608)
			(xy 428.054008 -98.590608) (xy 428.054008 -99.479608) (xy 434.902862 -99.479608) (xy 434.906933 -99.423986)
			(xy 434.919059 -99.369549) (xy 434.938982 -99.317458) (xy 434.966278 -99.268823) (xy 435.000364 -99.22468)
			(xy 435.040513 -99.185971) (xy 435.085871 -99.15352) (xy 435.135471 -99.128019) (xy 435.188255 -99.110012)
			(xy 435.243098 -99.099882) (xy 435.298832 -99.097845) (xy 435.354269 -99.103945) (xy 435.408226 -99.118051)
			(xy 435.459555 -99.139863) (xy 435.507161 -99.168917) (xy 435.550029 -99.204592) (xy 435.587246 -99.246129)
			(xy 435.618019 -99.292642) (xy 435.641691 -99.343139) (xy 435.657759 -99.396546) (xy 435.665879 -99.451722)
			(xy 435.666388 -99.479608) (xy 435.791862 -99.479608) (xy 435.795933 -99.423986) (xy 435.808059 -99.369549)
			(xy 435.827982 -99.317458) (xy 435.855278 -99.268823) (xy 435.889364 -99.22468) (xy 435.929513 -99.185971)
			(xy 435.974871 -99.15352) (xy 436.024471 -99.128019) (xy 436.077255 -99.110012) (xy 436.132098 -99.099882)
			(xy 436.187832 -99.097845) (xy 436.243269 -99.103945) (xy 436.297226 -99.118051) (xy 436.348555 -99.139863)
			(xy 436.396161 -99.168917) (xy 436.439029 -99.204592) (xy 436.476246 -99.246129) (xy 436.507019 -99.292642)
			(xy 436.530691 -99.343139) (xy 436.546759 -99.396546) (xy 436.554879 -99.451722) (xy 436.555388 -99.479608)
			(xy 436.554879 -99.507494) (xy 436.546759 -99.56267) (xy 436.530691 -99.616077) (xy 436.507019 -99.666574)
			(xy 436.476246 -99.713087) (xy 436.439029 -99.754624) (xy 436.396161 -99.790299) (xy 436.348555 -99.819353)
			(xy 436.297226 -99.841165) (xy 436.243269 -99.855271) (xy 436.187832 -99.861371) (xy 436.132098 -99.859334)
			(xy 436.077255 -99.849204) (xy 436.024471 -99.831197) (xy 435.974871 -99.805696) (xy 435.929513 -99.773245)
			(xy 435.889364 -99.734536) (xy 435.855278 -99.690393) (xy 435.827982 -99.641758) (xy 435.808059 -99.589667)
			(xy 435.795933 -99.53523) (xy 435.791862 -99.479608) (xy 435.666388 -99.479608) (xy 435.665879 -99.507494)
			(xy 435.657759 -99.56267) (xy 435.641691 -99.616077) (xy 435.618019 -99.666574) (xy 435.587246 -99.713087)
			(xy 435.550029 -99.754624) (xy 435.507161 -99.790299) (xy 435.459555 -99.819353) (xy 435.408226 -99.841165)
			(xy 435.354269 -99.855271) (xy 435.298832 -99.861371) (xy 435.243098 -99.859334) (xy 435.188255 -99.849204)
			(xy 435.135471 -99.831197) (xy 435.085871 -99.805696) (xy 435.040513 -99.773245) (xy 435.000364 -99.734536)
			(xy 434.966278 -99.690393) (xy 434.938982 -99.641758) (xy 434.919059 -99.589667) (xy 434.906933 -99.53523)
			(xy 434.902862 -99.479608) (xy 428.054008 -99.479608) (xy 428.054008 -102.63945) (xy 429.495968 -102.63945)
			(xy 429.495968 -102.58495) (xy 429.503724 -102.531003) (xy 429.519077 -102.47871) (xy 429.541717 -102.429134)
			(xy 429.57118 -102.383284) (xy 429.606869 -102.342093) (xy 429.648057 -102.306401) (xy 429.693904 -102.276933)
			(xy 429.743478 -102.254289) (xy 429.79577 -102.238931) (xy 429.849716 -102.23117) (xy 429.876966 -102.230682)
			(xy 429.903569 -102.231164) (xy 429.95626 -102.238541) (xy 430.007415 -102.25317) (xy 430.056039 -102.274767)
			(xy 430.10119 -102.302914) (xy 430.14199 -102.337062) (xy 430.177648 -102.376551) (xy 430.192942 -102.398322)
			(xy 430.201276 -102.409802) (xy 430.22302 -102.428006) (xy 430.248933 -102.439524) (xy 430.277016 -102.443464)
			(xy 430.305099 -102.439524) (xy 430.331012 -102.428006) (xy 430.352756 -102.409802) (xy 430.36109 -102.398322)
			(xy 430.376374 -102.376544) (xy 430.412042 -102.337065) (xy 430.452848 -102.302923) (xy 430.498 -102.274779)
			(xy 430.546623 -102.253178) (xy 430.597775 -102.238539) (xy 430.650463 -102.231145) (xy 430.677066 -102.230682)
			(xy 430.704318 -102.231187) (xy 430.758266 -102.238939) (xy 430.810563 -102.25429) (xy 430.860142 -102.276928)
			(xy 430.905995 -102.306392) (xy 430.947188 -102.342081) (xy 430.982882 -102.38327) (xy 431.012351 -102.429119)
			(xy 431.034994 -102.478696) (xy 431.050352 -102.53099) (xy 431.05811 -102.584938) (xy 431.058574 -102.61219)
			(xy 431.058169 -102.636998) (xy 431.057848 -102.639451) (xy 431.370468 -102.639451) (xy 431.370468 -102.584949)
			(xy 431.378224 -102.531001) (xy 431.393579 -102.478706) (xy 431.41622 -102.429128) (xy 431.445685 -102.383277)
			(xy 431.481376 -102.342086) (xy 431.522566 -102.306394) (xy 431.568416 -102.276926) (xy 431.617993 -102.254284)
			(xy 431.670287 -102.238927) (xy 431.724235 -102.231169) (xy 431.751486 -102.230682) (xy 431.780451 -102.231233)
			(xy 431.837715 -102.240002) (xy 431.892995 -102.257325) (xy 431.945022 -102.282805) (xy 431.9926 -102.315856)
			(xy 432.034635 -102.355719) (xy 432.070163 -102.401477) (xy 432.084734 -102.426516) (xy 432.092088 -102.438728)
			(xy 432.112316 -102.458797) (xy 432.137304 -102.472494) (xy 432.165104 -102.47875) (xy 432.19355 -102.47708)
			(xy 432.220426 -102.467612) (xy 432.243639 -102.451085) (xy 432.252882 -102.440232) (xy 432.271098 -102.418176)
			(xy 432.313 -102.379236) (xy 432.360242 -102.346983) (xy 432.411768 -102.322139) (xy 432.466423 -102.30526)
			(xy 432.522985 -102.296724) (xy 432.551586 -102.296214) (xy 432.578841 -102.296632) (xy 432.632797 -102.304388)
			(xy 432.685099 -102.319743) (xy 432.734684 -102.342386) (xy 432.780542 -102.371856) (xy 432.821738 -102.407552)
			(xy 432.857436 -102.448747) (xy 432.886907 -102.494604) (xy 432.909552 -102.544188) (xy 432.924909 -102.59649)
			(xy 432.932667 -102.650445) (xy 432.932667 -102.704955) (xy 432.924909 -102.75891) (xy 432.909552 -102.811212)
			(xy 432.886907 -102.860796) (xy 432.857436 -102.906653) (xy 432.821738 -102.947848) (xy 432.780542 -102.983544)
			(xy 432.734684 -103.013014) (xy 432.685099 -103.035657) (xy 432.632797 -103.051012) (xy 432.578841 -103.058768)
			(xy 432.551586 -103.05923) (xy 432.522618 -103.058746) (xy 432.465349 -103.049971) (xy 432.410065 -103.032639)
			(xy 432.358036 -103.007149) (xy 432.310459 -102.974086) (xy 432.268427 -102.934212) (xy 432.232905 -102.888441)
			(xy 432.218338 -102.863396) (xy 432.211021 -102.851159) (xy 432.190786 -102.831086) (xy 432.16579 -102.817388)
			(xy 432.137982 -102.811133) (xy 432.109529 -102.812809) (xy 432.082648 -102.822285) (xy 432.059433 -102.838822)
			(xy 432.05019 -102.84968) (xy 432.031993 -102.871752) (xy 431.990086 -102.91069) (xy 431.94284 -102.942941)
			(xy 431.891311 -102.967782) (xy 431.836652 -102.984658) (xy 431.780088 -102.99319) (xy 431.751486 -102.993698)
			(xy 431.724235 -102.993231) (xy 431.670287 -102.985473) (xy 431.617993 -102.970116) (xy 431.568416 -102.947474)
			(xy 431.522566 -102.918006) (xy 431.481376 -102.882314) (xy 431.445685 -102.841123) (xy 431.41622 -102.795272)
			(xy 431.393579 -102.745694) (xy 431.378224 -102.693399) (xy 431.370468 -102.639451) (xy 431.057848 -102.639451)
			(xy 431.051732 -102.686194) (xy 431.038953 -102.734135) (xy 431.029872 -102.757224) (xy 431.025139 -102.769969)
			(xy 431.0218 -102.796937) (xy 431.025686 -102.823832) (xy 431.036521 -102.848752) (xy 431.053541 -102.869936)
			(xy 431.075541 -102.885887) (xy 431.100967 -102.895476) (xy 431.114454 -102.897178) (xy 431.142478 -102.90029)
			(xy 431.197232 -102.913751) (xy 431.249408 -102.935124) (xy 431.29787 -102.963943) (xy 431.341562 -102.999582)
			(xy 431.379534 -103.041264) (xy 431.410956 -103.08808) (xy 431.435146 -103.139011) (xy 431.451576 -103.192948)
			(xy 431.459889 -103.248716) (xy 431.460402 -103.276908) (xy 431.459916 -103.304159) (xy 431.45216 -103.358107)
			(xy 431.436805 -103.410402) (xy 431.414163 -103.459979) (xy 431.384697 -103.505829) (xy 431.349006 -103.54702)
			(xy 431.307815 -103.582711) (xy 431.261965 -103.612177) (xy 431.212388 -103.634819) (xy 431.160093 -103.650174)
			(xy 431.106145 -103.65793) (xy 431.051643 -103.65793) (xy 430.997695 -103.650174) (xy 430.9454 -103.634819)
			(xy 430.895823 -103.612177) (xy 430.849973 -103.582711) (xy 430.808782 -103.54702) (xy 430.773091 -103.505829)
			(xy 430.743625 -103.459979) (xy 430.720983 -103.410402) (xy 430.705628 -103.358107) (xy 430.697872 -103.304159)
			(xy 430.697386 -103.276908) (xy 430.697793 -103.2521) (xy 430.704229 -103.202905) (xy 430.717007 -103.154963)
			(xy 430.726088 -103.131874) (xy 430.730856 -103.11914) (xy 430.734198 -103.092165) (xy 430.730311 -103.065263)
			(xy 430.71947 -103.040337) (xy 430.702443 -103.019151) (xy 430.680433 -103.003201) (xy 430.654997 -102.993618)
			(xy 430.641506 -102.99192) (xy 430.613609 -102.988818) (xy 430.559087 -102.975477) (xy 430.50711 -102.95429)
			(xy 430.458798 -102.925714) (xy 430.415195 -102.890368) (xy 430.377243 -102.849014) (xy 430.36109 -102.826058)
			(xy 430.352756 -102.814578) (xy 430.331012 -102.796374) (xy 430.305099 -102.784856) (xy 430.277016 -102.780916)
			(xy 430.248933 -102.784856) (xy 430.22302 -102.796374) (xy 430.201276 -102.814578) (xy 430.192942 -102.826058)
			(xy 430.177632 -102.847817) (xy 430.141968 -102.887297) (xy 430.101167 -102.921441) (xy 430.05602 -102.949588)
			(xy 430.007401 -102.971192) (xy 429.956253 -102.985835) (xy 429.903567 -102.993232) (xy 429.876966 -102.993698)
			(xy 429.849716 -102.99323) (xy 429.79577 -102.985469) (xy 429.743478 -102.970111) (xy 429.693904 -102.947467)
			(xy 429.648057 -102.917999) (xy 429.606869 -102.882307) (xy 429.57118 -102.841116) (xy 429.541717 -102.795266)
			(xy 429.519077 -102.74569) (xy 429.503724 -102.693397) (xy 429.495968 -102.63945) (xy 428.054008 -102.63945)
			(xy 428.054008 -105.40746) (xy 428.053544 -105.439554) (xy 428.046332 -105.503334) (xy 428.032027 -105.565908)
			(xy 428.01081 -105.626487) (xy 427.982946 -105.684311) (xy 427.948787 -105.738654) (xy 427.90876 -105.788833)
			(xy 427.886368 -105.811828) (xy 427.870876 -105.827322) (xy 429.906682 -105.827322) (xy 429.910753 -105.7717)
			(xy 429.922879 -105.717263) (xy 429.942802 -105.665172) (xy 429.970098 -105.616537) (xy 430.004184 -105.572394)
			(xy 430.044333 -105.533685) (xy 430.089691 -105.501234) (xy 430.139291 -105.475733) (xy 430.192075 -105.457726)
			(xy 430.246918 -105.447596) (xy 430.302652 -105.445559) (xy 430.358089 -105.451659) (xy 430.412046 -105.465765)
			(xy 430.463375 -105.487577) (xy 430.510981 -105.516631) (xy 430.553849 -105.552306) (xy 430.591066 -105.593843)
			(xy 430.614291 -105.628948) (xy 433.069492 -105.628948) (xy 433.069988 -105.601579) (xy 433.077799 -105.547401)
			(xy 433.093281 -105.494898) (xy 433.116116 -105.445151) (xy 433.145834 -105.399183) (xy 433.163472 -105.37825)
			(xy 433.172664 -105.366889) (xy 433.184851 -105.340344) (xy 433.189034 -105.311436) (xy 433.184871 -105.282526)
			(xy 433.172704 -105.255972) (xy 433.163472 -105.244646) (xy 433.145837 -105.223711) (xy 433.116125 -105.177739)
			(xy 433.093289 -105.127992) (xy 433.077797 -105.075492) (xy 433.069967 -105.021317) (xy 433.069492 -104.993948)
			(xy 433.069991 -104.965775) (xy 433.078298 -104.910045) (xy 433.094709 -104.856142) (xy 433.118868 -104.805238)
			(xy 433.150249 -104.75844) (xy 433.188171 -104.716765) (xy 433.231808 -104.681118) (xy 433.280212 -104.652276)
			(xy 433.332331 -104.630864) (xy 433.35956 -104.623616) (xy 433.373871 -104.619591) (xy 433.399467 -104.604497)
			(xy 433.419628 -104.582668) (xy 433.432644 -104.555955) (xy 433.437411 -104.526624) (xy 433.433523 -104.497164)
			(xy 433.427886 -104.483408) (xy 433.417375 -104.458766) (xy 433.402561 -104.407283) (xy 433.395071 -104.354238)
			(xy 433.394612 -104.327452) (xy 433.395098 -104.300201) (xy 433.402854 -104.246253) (xy 433.418209 -104.193958)
			(xy 433.440851 -104.144381) (xy 433.470317 -104.098531) (xy 433.506008 -104.05734) (xy 433.547199 -104.021649)
			(xy 433.593049 -103.992183) (xy 433.642626 -103.969541) (xy 433.694921 -103.954186) (xy 433.748869 -103.94643)
			(xy 433.803371 -103.94643) (xy 433.857319 -103.954186) (xy 433.909614 -103.969541) (xy 433.959191 -103.992183)
			(xy 434.005041 -104.021649) (xy 434.046232 -104.05734) (xy 434.081923 -104.098531) (xy 434.111389 -104.144381)
			(xy 434.134031 -104.193958) (xy 434.149386 -104.246253) (xy 434.157142 -104.300201) (xy 434.157628 -104.327452)
			(xy 434.157175 -104.354753) (xy 434.149421 -104.4088) (xy 434.134021 -104.461184) (xy 434.123084 -104.486202)
			(xy 434.117403 -104.499723) (xy 434.113306 -104.528754) (xy 434.117603 -104.557756) (xy 434.129943 -104.584351)
			(xy 434.149314 -104.606359) (xy 434.174127 -104.621976) (xy 434.188108 -104.62641) (xy 434.214542 -104.634228)
			(xy 434.264983 -104.656465) (xy 434.311697 -104.685732) (xy 434.353711 -104.721419) (xy 434.390149 -104.762783)
			(xy 434.420254 -104.808961) (xy 434.443397 -104.858992) (xy 434.459097 -104.911834) (xy 434.467026 -104.966386)
			(xy 434.467508 -104.993948) (xy 434.467009 -105.021317) (xy 434.459199 -105.075495) (xy 434.443718 -105.127997)
			(xy 434.420883 -105.177745) (xy 434.391166 -105.223713) (xy 434.373528 -105.244646) (xy 434.364243 -105.255938)
			(xy 434.352068 -105.282508) (xy 434.347903 -105.311436) (xy 434.352088 -105.340362) (xy 434.364282 -105.366923)
			(xy 434.373528 -105.37825) (xy 434.391161 -105.399187) (xy 434.420873 -105.445159) (xy 434.44371 -105.494905)
			(xy 434.459202 -105.547404) (xy 434.467033 -105.601579) (xy 434.467508 -105.628948) (xy 434.467067 -105.6562)
			(xy 434.459304 -105.71015) (xy 434.443943 -105.762445) (xy 434.421296 -105.812023) (xy 434.391825 -105.857873)
			(xy 434.356129 -105.899063) (xy 434.314934 -105.934753) (xy 434.269081 -105.964219) (xy 434.2195 -105.986859)
			(xy 434.167203 -106.002214) (xy 434.113252 -106.00997) (xy 434.086 -106.010456) (xy 434.058629 -106.010001)
			(xy 434.004449 -106.002182) (xy 433.951946 -105.986691) (xy 433.902199 -105.963847) (xy 433.856233 -105.934119)
			(xy 433.835302 -105.916476) (xy 433.823974 -105.90724) (xy 433.797417 -105.895064) (xy 433.7685 -105.890891)
			(xy 433.739583 -105.895064) (xy 433.713026 -105.90724) (xy 433.701698 -105.916476) (xy 433.680774 -105.934126)
			(xy 433.6348 -105.963837) (xy 433.58505 -105.986671) (xy 433.532547 -106.00216) (xy 433.47837 -106.009984)
			(xy 433.451 -106.010456) (xy 433.423751 -106.009922) (xy 433.369807 -106.002167) (xy 433.317516 -105.986814)
			(xy 433.267942 -105.964177) (xy 433.222094 -105.934715) (xy 433.180905 -105.899029) (xy 433.145214 -105.857844)
			(xy 433.115746 -105.812) (xy 433.093102 -105.762429) (xy 433.077743 -105.71014) (xy 433.069981 -105.656197)
			(xy 433.069492 -105.628948) (xy 430.614291 -105.628948) (xy 430.621839 -105.640356) (xy 430.645511 -105.690853)
			(xy 430.661579 -105.74426) (xy 430.669699 -105.799436) (xy 430.670208 -105.827322) (xy 430.669699 -105.855208)
			(xy 430.661579 -105.910384) (xy 430.645511 -105.963791) (xy 430.621839 -106.014288) (xy 430.591066 -106.060801)
			(xy 430.553849 -106.102338) (xy 430.510981 -106.138013) (xy 430.463375 -106.167067) (xy 430.412046 -106.188879)
			(xy 430.358089 -106.202985) (xy 430.302652 -106.209085) (xy 430.246918 -106.207048) (xy 430.192075 -106.196918)
			(xy 430.139291 -106.178911) (xy 430.089691 -106.15341) (xy 430.044333 -106.120959) (xy 430.004184 -106.08225)
			(xy 429.970098 -106.038107) (xy 429.942802 -105.989472) (xy 429.922879 -105.937381) (xy 429.910753 -105.882944)
			(xy 429.906682 -105.827322) (xy 427.870876 -105.827322) (xy 426.547217 -107.15117) (xy 428.930814 -107.15117)
			(xy 428.934885 -107.095548) (xy 428.947011 -107.041111) (xy 428.966934 -106.98902) (xy 428.99423 -106.940385)
			(xy 429.028316 -106.896242) (xy 429.068465 -106.857533) (xy 429.113823 -106.825082) (xy 429.163423 -106.799581)
			(xy 429.216207 -106.781574) (xy 429.27105 -106.771444) (xy 429.326784 -106.769407) (xy 429.368344 -106.77398)
			(xy 433.340254 -106.77398) (xy 433.344325 -106.718358) (xy 433.356451 -106.663921) (xy 433.376374 -106.61183)
			(xy 433.40367 -106.563195) (xy 433.437756 -106.519052) (xy 433.477905 -106.480343) (xy 433.523263 -106.447892)
			(xy 433.572863 -106.422391) (xy 433.625647 -106.404384) (xy 433.68049 -106.394254) (xy 433.736224 -106.392217)
			(xy 433.791661 -106.398317) (xy 433.845618 -106.412423) (xy 433.896947 -106.434235) (xy 433.944553 -106.463289)
			(xy 433.987421 -106.498964) (xy 434.024638 -106.540501) (xy 434.055411 -106.587014) (xy 434.079083 -106.637511)
			(xy 434.095151 -106.690918) (xy 434.103271 -106.746094) (xy 434.10378 -106.77398) (xy 434.103271 -106.801866)
			(xy 434.095151 -106.857042) (xy 434.079083 -106.910449) (xy 434.055411 -106.960946) (xy 434.024638 -107.007459)
			(xy 433.987421 -107.048996) (xy 433.944553 -107.084671) (xy 433.896947 -107.113725) (xy 433.845618 -107.135537)
			(xy 433.791661 -107.149643) (xy 433.736224 -107.155743) (xy 433.68049 -107.153706) (xy 433.625647 -107.143576)
			(xy 433.572863 -107.125569) (xy 433.523263 -107.100068) (xy 433.477905 -107.067617) (xy 433.437756 -107.028908)
			(xy 433.40367 -106.984765) (xy 433.376374 -106.93613) (xy 433.356451 -106.884039) (xy 433.344325 -106.829602)
			(xy 433.340254 -106.77398) (xy 429.368344 -106.77398) (xy 429.382221 -106.775507) (xy 429.436178 -106.789613)
			(xy 429.487507 -106.811425) (xy 429.535113 -106.840479) (xy 429.577981 -106.876154) (xy 429.615198 -106.917691)
			(xy 429.645971 -106.964204) (xy 429.669643 -107.014701) (xy 429.685711 -107.068108) (xy 429.693831 -107.123284)
			(xy 429.69434 -107.15117) (xy 429.693831 -107.179056) (xy 429.685711 -107.234232) (xy 429.677688 -107.260898)
			(xy 430.263552 -107.260898) (xy 430.267623 -107.205276) (xy 430.279749 -107.150839) (xy 430.299672 -107.098748)
			(xy 430.326968 -107.050113) (xy 430.361054 -107.00597) (xy 430.401203 -106.967261) (xy 430.446561 -106.93481)
			(xy 430.496161 -106.909309) (xy 430.548945 -106.891302) (xy 430.603788 -106.881172) (xy 430.659522 -106.879135)
			(xy 430.714959 -106.885235) (xy 430.768916 -106.899341) (xy 430.820245 -106.921153) (xy 430.867851 -106.950207)
			(xy 430.910719 -106.985882) (xy 430.947936 -107.027419) (xy 430.978709 -107.073932) (xy 431.002381 -107.124429)
			(xy 431.018449 -107.177836) (xy 431.026569 -107.233012) (xy 431.027078 -107.260898) (xy 431.026569 -107.288784)
			(xy 431.018449 -107.34396) (xy 431.002381 -107.397367) (xy 430.978709 -107.447864) (xy 430.947936 -107.494377)
			(xy 430.910719 -107.535914) (xy 430.867851 -107.571589) (xy 430.820245 -107.600643) (xy 430.768916 -107.622455)
			(xy 430.714959 -107.636561) (xy 430.659522 -107.642661) (xy 430.603788 -107.640624) (xy 430.548945 -107.630494)
			(xy 430.496161 -107.612487) (xy 430.446561 -107.586986) (xy 430.401203 -107.554535) (xy 430.361054 -107.515826)
			(xy 430.326968 -107.471683) (xy 430.299672 -107.423048) (xy 430.279749 -107.370957) (xy 430.267623 -107.31652)
			(xy 430.263552 -107.260898) (xy 429.677688 -107.260898) (xy 429.669643 -107.287639) (xy 429.645971 -107.338136)
			(xy 429.615198 -107.384649) (xy 429.577981 -107.426186) (xy 429.535113 -107.461861) (xy 429.487507 -107.490915)
			(xy 429.436178 -107.512727) (xy 429.382221 -107.526833) (xy 429.326784 -107.532933) (xy 429.27105 -107.530896)
			(xy 429.216207 -107.520766) (xy 429.163423 -107.502759) (xy 429.113823 -107.477258) (xy 429.068465 -107.444807)
			(xy 429.028316 -107.406098) (xy 428.99423 -107.361955) (xy 428.966934 -107.31332) (xy 428.947011 -107.261229)
			(xy 428.934885 -107.206792) (xy 428.930814 -107.15117) (xy 426.547217 -107.15117) (xy 426.108368 -107.590082)
			(xy 426.108368 -107.645708) (xy 431.703478 -107.645708) (xy 431.707549 -107.590086) (xy 431.719675 -107.535649)
			(xy 431.739598 -107.483558) (xy 431.766894 -107.434923) (xy 431.80098 -107.39078) (xy 431.841129 -107.352071)
			(xy 431.886487 -107.31962) (xy 431.936087 -107.294119) (xy 431.988871 -107.276112) (xy 432.043714 -107.265982)
			(xy 432.099448 -107.263945) (xy 432.154885 -107.270045) (xy 432.208842 -107.284151) (xy 432.260171 -107.305963)
			(xy 432.307777 -107.335017) (xy 432.350645 -107.370692) (xy 432.387862 -107.412229) (xy 432.418635 -107.458742)
			(xy 432.442307 -107.509239) (xy 432.458375 -107.562646) (xy 432.466495 -107.617822) (xy 432.467004 -107.645708)
			(xy 432.466495 -107.673594) (xy 432.458375 -107.72877) (xy 432.442307 -107.782177) (xy 432.418635 -107.832674)
			(xy 432.387862 -107.879187) (xy 432.350645 -107.920724) (xy 432.307777 -107.956399) (xy 432.260171 -107.985453)
			(xy 432.208842 -108.007265) (xy 432.154885 -108.021371) (xy 432.099448 -108.027471) (xy 432.043714 -108.025434)
			(xy 431.988871 -108.015304) (xy 431.936087 -107.997297) (xy 431.886487 -107.971796) (xy 431.841129 -107.939345)
			(xy 431.80098 -107.900636) (xy 431.766894 -107.856493) (xy 431.739598 -107.807858) (xy 431.719675 -107.755767)
			(xy 431.707549 -107.70133) (xy 431.703478 -107.645708) (xy 426.108368 -107.645708) (xy 426.108368 -110.726982)
			(xy 426.17136 -110.790228) (xy 427.321472 -110.790228)
		)
		(stroke
			(width 0)
			(type solid)
		)
		(fill yes)
		(layer "In2.Cu")
		(net "GND")
	)
	(gr_poly
		(pts
			(xy 335.535524 -57.120028) (xy 335.548813 -57.119595) (xy 335.574487 -57.112727) (xy 335.597519 -57.099463)
			(xy 335.616345 -57.080703) (xy 335.629689 -57.057719) (xy 335.636647 -57.032069) (xy 335.636747 -57.005491)
			(xy 335.633822 -56.99252) (xy 335.628717 -56.971877) (xy 335.623238 -56.929708) (xy 335.6229 -56.908446)
			(xy 335.62341 -56.882459) (xy 335.63154 -56.831124) (xy 335.647601 -56.781694) (xy 335.671197 -56.735384)
			(xy 335.701747 -56.693336) (xy 335.738498 -56.656585) (xy 335.780546 -56.626035) (xy 335.826856 -56.602439)
			(xy 335.876286 -56.586378) (xy 335.927621 -56.578248) (xy 335.979595 -56.578248) (xy 336.03093 -56.586378)
			(xy 336.08036 -56.602439) (xy 336.12667 -56.626035) (xy 336.168718 -56.656585) (xy 336.205469 -56.693336)
			(xy 336.236019 -56.735384) (xy 336.259615 -56.781694) (xy 336.275676 -56.831124) (xy 336.283806 -56.882459)
			(xy 336.284316 -56.908446) (xy 336.283967 -56.929707) (xy 336.278483 -56.971874) (xy 336.273394 -56.99252)
			(xy 336.270425 -57.005481) (xy 336.270522 -57.032061) (xy 336.277484 -57.057713) (xy 336.290837 -57.080695)
			(xy 336.309675 -57.099447) (xy 336.332718 -57.112695) (xy 336.358402 -57.119539) (xy 336.371692 -57.120028)
			(xy 337.16341 -57.120028) (xy 337.1767 -57.119596) (xy 337.202378 -57.112731) (xy 337.225412 -57.099468)
			(xy 337.244241 -57.080708) (xy 337.257588 -57.057722) (xy 337.264547 -57.032069) (xy 337.264647 -57.005489)
			(xy 337.261708 -56.99252) (xy 337.256603 -56.971877) (xy 337.251124 -56.929708) (xy 337.250786 -56.908446)
			(xy 337.251296 -56.882459) (xy 337.259426 -56.831124) (xy 337.275487 -56.781694) (xy 337.299083 -56.735384)
			(xy 337.329633 -56.693336) (xy 337.366384 -56.656585) (xy 337.408432 -56.626035) (xy 337.454742 -56.602439)
			(xy 337.504172 -56.586378) (xy 337.555507 -56.578248) (xy 337.607481 -56.578248) (xy 337.658816 -56.586378)
			(xy 337.708246 -56.602439) (xy 337.754556 -56.626035) (xy 337.796604 -56.656585) (xy 337.833355 -56.693336)
			(xy 337.863905 -56.735384) (xy 337.887501 -56.781694) (xy 337.903562 -56.831124) (xy 337.911692 -56.882459)
			(xy 337.912202 -56.908446) (xy 337.911791 -56.932445) (xy 337.904883 -56.979942) (xy 337.891175 -57.02594)
			(xy 337.881468 -57.047892) (xy 337.876642 -57.058052) (xy 337.876642 -57.120028) (xy 338.013802 -57.120028)
			(xy 338.250022 -56.883808) (xy 338.259078 -56.874093) (xy 338.272313 -56.851078) (xy 338.279169 -56.82543)
			(xy 338.279184 -56.798881) (xy 338.272355 -56.773225) (xy 338.259146 -56.750195) (xy 338.240448 -56.731348)
			(xy 338.229194 -56.724296) (xy 338.20814 -56.711472) (xy 338.169733 -56.680572) (xy 338.136331 -56.64432)
			(xy 338.108673 -56.603515) (xy 338.08737 -56.559061) (xy 338.072894 -56.51194) (xy 338.065564 -56.463193)
			(xy 338.06511 -56.438546) (xy 338.06559 -56.412555) (xy 338.073715 -56.361212) (xy 338.089774 -56.311772)
			(xy 338.113369 -56.265454) (xy 338.143921 -56.223398) (xy 338.180676 -56.186639) (xy 338.22273 -56.156084)
			(xy 338.269046 -56.132484) (xy 338.318485 -56.116422) (xy 338.369827 -56.108292) (xy 338.395818 -56.107838)
			(xy 338.421183 -56.108346) (xy 338.471313 -56.116132) (xy 338.49564 -56.123332) (xy 338.508783 -56.127046)
			(xy 338.536063 -56.128119) (xy 338.562652 -56.121924) (xy 338.586648 -56.108902) (xy 338.606334 -56.089986)
			(xy 338.620302 -56.066529) (xy 338.627553 -56.040208) (xy 338.627974 -56.026558) (xy 338.627974 -55.91048)
			(xy 338.627529 -55.896812) (xy 338.620268 -55.870459) (xy 338.606272 -55.846978) (xy 338.586545 -55.828055)
			(xy 338.562502 -55.815048) (xy 338.53587 -55.808889) (xy 338.508557 -55.81002) (xy 338.495386 -55.813706)
			(xy 338.470828 -55.821059) (xy 338.420179 -55.828963) (xy 338.394548 -55.829454) (xy 338.368553 -55.828974)
			(xy 338.317201 -55.820848) (xy 338.267753 -55.804788) (xy 338.221427 -55.781189) (xy 338.179363 -55.750634)
			(xy 338.142598 -55.713873) (xy 338.112036 -55.671814) (xy 338.088431 -55.625491) (xy 338.072363 -55.576046)
			(xy 338.064229 -55.524695) (xy 338.064229 -55.472705) (xy 338.072363 -55.421354) (xy 338.088431 -55.371909)
			(xy 338.112036 -55.325586) (xy 338.142598 -55.283527) (xy 338.179363 -55.246766) (xy 338.221427 -55.216211)
			(xy 338.267753 -55.192612) (xy 338.317201 -55.176552) (xy 338.368553 -55.168426) (xy 338.394548 -55.168038)
			(xy 338.420179 -55.168523) (xy 338.470826 -55.176439) (xy 338.495386 -55.183786) (xy 338.508545 -55.187539)
			(xy 338.535875 -55.188671) (xy 338.562525 -55.182508) (xy 338.586582 -55.169492) (xy 338.606321 -55.150556)
			(xy 338.620326 -55.127059) (xy 338.62759 -55.100689) (xy 338.627974 -55.087012) (xy 338.627974 -54.97068)
			(xy 338.627529 -54.957012) (xy 338.620268 -54.930659) (xy 338.606272 -54.907178) (xy 338.586545 -54.888255)
			(xy 338.562502 -54.875248) (xy 338.53587 -54.869089) (xy 338.508557 -54.87022) (xy 338.495386 -54.873906)
			(xy 338.470828 -54.881259) (xy 338.420179 -54.889163) (xy 338.394548 -54.889654) (xy 338.368553 -54.889174)
			(xy 338.317201 -54.881048) (xy 338.267753 -54.864988) (xy 338.221427 -54.841389) (xy 338.179363 -54.810834)
			(xy 338.142598 -54.774073) (xy 338.112036 -54.732014) (xy 338.088431 -54.685691) (xy 338.072363 -54.636246)
			(xy 338.064229 -54.584895) (xy 338.064229 -54.532905) (xy 338.072363 -54.481554) (xy 338.088431 -54.432109)
			(xy 338.112036 -54.385786) (xy 338.142598 -54.343727) (xy 338.179363 -54.306966) (xy 338.221427 -54.276411)
			(xy 338.267753 -54.252812) (xy 338.317201 -54.236752) (xy 338.368553 -54.228626) (xy 338.394548 -54.228238)
			(xy 338.420179 -54.228723) (xy 338.470826 -54.236639) (xy 338.495386 -54.243986) (xy 338.508545 -54.247739)
			(xy 338.535875 -54.248871) (xy 338.562525 -54.242708) (xy 338.586582 -54.229692) (xy 338.606321 -54.210756)
			(xy 338.620326 -54.187259) (xy 338.62759 -54.160889) (xy 338.627974 -54.147212) (xy 338.627974 -54.03088)
			(xy 338.627529 -54.017212) (xy 338.620268 -53.990859) (xy 338.606272 -53.967378) (xy 338.586545 -53.948455)
			(xy 338.562502 -53.935448) (xy 338.53587 -53.929289) (xy 338.508557 -53.93042) (xy 338.495386 -53.934106)
			(xy 338.470828 -53.941459) (xy 338.420179 -53.949363) (xy 338.394548 -53.949854) (xy 338.368553 -53.949374)
			(xy 338.317201 -53.941248) (xy 338.267753 -53.925188) (xy 338.221427 -53.901589) (xy 338.179363 -53.871034)
			(xy 338.142598 -53.834273) (xy 338.112036 -53.792214) (xy 338.088431 -53.745891) (xy 338.072363 -53.696446)
			(xy 338.064229 -53.645095) (xy 338.064229 -53.593105) (xy 338.072363 -53.541754) (xy 338.088431 -53.492309)
			(xy 338.112036 -53.445986) (xy 338.142598 -53.403927) (xy 338.179363 -53.367166) (xy 338.221427 -53.336611)
			(xy 338.267753 -53.313012) (xy 338.317201 -53.296952) (xy 338.368553 -53.288826) (xy 338.394548 -53.288438)
			(xy 338.420179 -53.288923) (xy 338.470826 -53.296839) (xy 338.495386 -53.304186) (xy 338.508545 -53.307939)
			(xy 338.535875 -53.309071) (xy 338.562525 -53.302908) (xy 338.586582 -53.289892) (xy 338.606321 -53.270956)
			(xy 338.620326 -53.247459) (xy 338.62759 -53.221089) (xy 338.627974 -53.207412) (xy 338.627974 -53.09108)
			(xy 338.627529 -53.077412) (xy 338.620268 -53.051059) (xy 338.606272 -53.027578) (xy 338.586545 -53.008655)
			(xy 338.562502 -52.995648) (xy 338.53587 -52.989489) (xy 338.508557 -52.99062) (xy 338.495386 -52.994306)
			(xy 338.470828 -53.001659) (xy 338.420179 -53.009563) (xy 338.394548 -53.010054) (xy 338.368553 -53.009574)
			(xy 338.317201 -53.001448) (xy 338.267753 -52.985388) (xy 338.221427 -52.961789) (xy 338.179363 -52.931234)
			(xy 338.142598 -52.894473) (xy 338.112036 -52.852414) (xy 338.088431 -52.806091) (xy 338.072363 -52.756646)
			(xy 338.064229 -52.705295) (xy 338.064229 -52.653305) (xy 338.072363 -52.601954) (xy 338.088431 -52.552509)
			(xy 338.112036 -52.506186) (xy 338.142598 -52.464127) (xy 338.179363 -52.427366) (xy 338.221427 -52.396811)
			(xy 338.267753 -52.373212) (xy 338.317201 -52.357152) (xy 338.368553 -52.349026) (xy 338.394548 -52.348638)
			(xy 338.420179 -52.349123) (xy 338.470826 -52.357039) (xy 338.495386 -52.364386) (xy 338.508545 -52.368139)
			(xy 338.535875 -52.369271) (xy 338.562525 -52.363108) (xy 338.586582 -52.350092) (xy 338.606321 -52.331156)
			(xy 338.620326 -52.307659) (xy 338.62759 -52.281289) (xy 338.627974 -52.267612) (xy 338.627974 -52.14493)
			(xy 338.013802 -51.530758) (xy 338.013802 -51.223672) (xy 337.50377 -50.71364) (xy 337.469988 -50.734214)
			(xy 337.444088 -50.748983) (xy 337.388279 -50.769951) (xy 337.329617 -50.780581) (xy 337.299808 -50.781204)
			(xy 337.276341 -50.780794) (xy 337.229877 -50.77416) (xy 337.184819 -50.761022) (xy 337.14207 -50.741646)
			(xy 337.102491 -50.716421) (xy 337.084416 -50.701448) (xy 335.915 -50.701448) (xy 335.894891 -50.718061)
			(xy 335.850471 -50.745398) (xy 335.802311 -50.765423) (xy 335.751604 -50.77764) (xy 335.699608 -50.781746)
			(xy 335.647612 -50.77764) (xy 335.596905 -50.765423) (xy 335.548745 -50.745398) (xy 335.504325 -50.718061)
			(xy 335.484216 -50.701448) (xy 335.131156 -50.701448) (xy 334.556021 -51.276583) (xy 335.36941 -51.276583)
			(xy 335.36941 -51.224609) (xy 335.37754 -51.173274) (xy 335.393601 -51.123844) (xy 335.417197 -51.077534)
			(xy 335.447747 -51.035486) (xy 335.484498 -50.998735) (xy 335.526546 -50.968185) (xy 335.572856 -50.944589)
			(xy 335.622286 -50.928528) (xy 335.673621 -50.920398) (xy 335.725595 -50.920398) (xy 335.77693 -50.928528)
			(xy 335.82636 -50.944589) (xy 335.87267 -50.968185) (xy 335.914718 -50.998735) (xy 335.951469 -51.035486)
			(xy 335.982019 -51.077534) (xy 336.005615 -51.123844) (xy 336.021676 -51.173274) (xy 336.029806 -51.224609)
			(xy 336.030316 -51.250596) (xy 336.029806 -51.276583) (xy 336.96961 -51.276583) (xy 336.96961 -51.224609)
			(xy 336.97774 -51.173274) (xy 336.993801 -51.123844) (xy 337.017397 -51.077534) (xy 337.047947 -51.035486)
			(xy 337.084698 -50.998735) (xy 337.126746 -50.968185) (xy 337.173056 -50.944589) (xy 337.222486 -50.928528)
			(xy 337.273821 -50.920398) (xy 337.325795 -50.920398) (xy 337.37713 -50.928528) (xy 337.42656 -50.944589)
			(xy 337.47287 -50.968185) (xy 337.514918 -50.998735) (xy 337.551669 -51.035486) (xy 337.582219 -51.077534)
			(xy 337.605815 -51.123844) (xy 337.621876 -51.173274) (xy 337.630006 -51.224609) (xy 337.630516 -51.250596)
			(xy 337.630006 -51.276583) (xy 337.621876 -51.327918) (xy 337.605815 -51.377348) (xy 337.582219 -51.423658)
			(xy 337.551669 -51.465706) (xy 337.514918 -51.502457) (xy 337.47287 -51.533007) (xy 337.42656 -51.556603)
			(xy 337.37713 -51.572664) (xy 337.325795 -51.580794) (xy 337.273821 -51.580794) (xy 337.222486 -51.572664)
			(xy 337.173056 -51.556603) (xy 337.126746 -51.533007) (xy 337.084698 -51.502457) (xy 337.047947 -51.465706)
			(xy 337.017397 -51.423658) (xy 336.993801 -51.377348) (xy 336.97774 -51.327918) (xy 336.96961 -51.276583)
			(xy 336.029806 -51.276583) (xy 336.021676 -51.327918) (xy 336.005615 -51.377348) (xy 335.982019 -51.423658)
			(xy 335.951469 -51.465706) (xy 335.914718 -51.502457) (xy 335.87267 -51.533007) (xy 335.82636 -51.556603)
			(xy 335.77693 -51.572664) (xy 335.725595 -51.580794) (xy 335.673621 -51.580794) (xy 335.622286 -51.572664)
			(xy 335.572856 -51.556603) (xy 335.526546 -51.533007) (xy 335.484498 -51.502457) (xy 335.447747 -51.465706)
			(xy 335.417197 -51.423658) (xy 335.393601 -51.377348) (xy 335.37754 -51.327918) (xy 335.36941 -51.276583)
			(xy 334.556021 -51.276583) (xy 334.338168 -51.494436) (xy 334.320151 -51.511739) (xy 334.279724 -51.541077)
			(xy 334.235206 -51.563732) (xy 334.187693 -51.579145) (xy 334.138354 -51.586938) (xy 334.113378 -51.5874)
			(xy 334.087724 -51.5874) (xy 333.81823 -51.856894) (xy 333.81442 -51.866292) (xy 333.804109 -51.889808)
			(xy 333.777298 -51.933598) (xy 333.744047 -51.972723) (xy 333.705153 -52.006244) (xy 333.68361 -52.020216)
			(xy 333.68361 -52.705333) (xy 334.80807 -52.705333) (xy 334.80807 -52.653359) (xy 334.8162 -52.602024)
			(xy 334.832261 -52.552594) (xy 334.855857 -52.506284) (xy 334.886407 -52.464236) (xy 334.923158 -52.427485)
			(xy 334.965206 -52.396935) (xy 335.011516 -52.373339) (xy 335.060946 -52.357278) (xy 335.112281 -52.349148)
			(xy 335.164255 -52.349148) (xy 335.21559 -52.357278) (xy 335.26502 -52.373339) (xy 335.31133 -52.396935)
			(xy 335.353378 -52.427485) (xy 335.390129 -52.464236) (xy 335.420679 -52.506284) (xy 335.444275 -52.552594)
			(xy 335.460336 -52.602024) (xy 335.468466 -52.653359) (xy 335.468976 -52.679346) (xy 335.468466 -52.705333)
			(xy 335.460336 -52.756668) (xy 335.444275 -52.806098) (xy 335.420679 -52.852408) (xy 335.390129 -52.894456)
			(xy 335.353378 -52.931207) (xy 335.31133 -52.961757) (xy 335.26502 -52.985353) (xy 335.21559 -53.001414)
			(xy 335.164255 -53.009544) (xy 335.112281 -53.009544) (xy 335.060946 -53.001414) (xy 335.011516 -52.985353)
			(xy 334.965206 -52.961757) (xy 334.923158 -52.931207) (xy 334.886407 -52.894456) (xy 334.855857 -52.852408)
			(xy 334.832261 -52.806098) (xy 334.8162 -52.756668) (xy 334.80807 -52.705333) (xy 333.68361 -52.705333)
			(xy 333.68361 -53.175233) (xy 333.99527 -53.175233) (xy 333.99527 -53.123259) (xy 334.0034 -53.071924)
			(xy 334.019461 -53.022494) (xy 334.043057 -52.976184) (xy 334.073607 -52.934136) (xy 334.110358 -52.897385)
			(xy 334.152406 -52.866835) (xy 334.198716 -52.843239) (xy 334.248146 -52.827178) (xy 334.299481 -52.819048)
			(xy 334.351455 -52.819048) (xy 334.40279 -52.827178) (xy 334.45222 -52.843239) (xy 334.49853 -52.866835)
			(xy 334.540578 -52.897385) (xy 334.577329 -52.934136) (xy 334.607879 -52.976184) (xy 334.631475 -53.022494)
			(xy 334.647536 -53.071924) (xy 334.655666 -53.123259) (xy 334.656176 -53.149246) (xy 334.655666 -53.175233)
			(xy 335.62341 -53.175233) (xy 335.62341 -53.123259) (xy 335.63154 -53.071924) (xy 335.647601 -53.022494)
			(xy 335.671197 -52.976184) (xy 335.701747 -52.934136) (xy 335.738498 -52.897385) (xy 335.780546 -52.866835)
			(xy 335.826856 -52.843239) (xy 335.876286 -52.827178) (xy 335.927621 -52.819048) (xy 335.979595 -52.819048)
			(xy 336.03093 -52.827178) (xy 336.08036 -52.843239) (xy 336.12667 -52.866835) (xy 336.168718 -52.897385)
			(xy 336.205469 -52.934136) (xy 336.236019 -52.976184) (xy 336.259615 -53.022494) (xy 336.275676 -53.071924)
			(xy 336.283806 -53.123259) (xy 336.284316 -53.149246) (xy 336.283806 -53.175233) (xy 337.25155 -53.175233)
			(xy 337.25155 -53.123259) (xy 337.25968 -53.071924) (xy 337.275741 -53.022494) (xy 337.299337 -52.976184)
			(xy 337.329887 -52.934136) (xy 337.366638 -52.897385) (xy 337.408686 -52.866835) (xy 337.454996 -52.843239)
			(xy 337.504426 -52.827178) (xy 337.555761 -52.819048) (xy 337.607735 -52.819048) (xy 337.65907 -52.827178)
			(xy 337.7085 -52.843239) (xy 337.75481 -52.866835) (xy 337.796858 -52.897385) (xy 337.833609 -52.934136)
			(xy 337.864159 -52.976184) (xy 337.887755 -53.022494) (xy 337.903816 -53.071924) (xy 337.911946 -53.123259)
			(xy 337.912456 -53.149246) (xy 337.911946 -53.175233) (xy 337.903816 -53.226568) (xy 337.887755 -53.275998)
			(xy 337.864159 -53.322308) (xy 337.833609 -53.364356) (xy 337.796858 -53.401107) (xy 337.75481 -53.431657)
			(xy 337.7085 -53.455253) (xy 337.65907 -53.471314) (xy 337.607735 -53.479444) (xy 337.555761 -53.479444)
			(xy 337.504426 -53.471314) (xy 337.454996 -53.455253) (xy 337.408686 -53.431657) (xy 337.366638 -53.401107)
			(xy 337.329887 -53.364356) (xy 337.299337 -53.322308) (xy 337.275741 -53.275998) (xy 337.25968 -53.226568)
			(xy 337.25155 -53.175233) (xy 336.283806 -53.175233) (xy 336.275676 -53.226568) (xy 336.259615 -53.275998)
			(xy 336.236019 -53.322308) (xy 336.205469 -53.364356) (xy 336.168718 -53.401107) (xy 336.12667 -53.431657)
			(xy 336.08036 -53.455253) (xy 336.03093 -53.471314) (xy 335.979595 -53.479444) (xy 335.927621 -53.479444)
			(xy 335.876286 -53.471314) (xy 335.826856 -53.455253) (xy 335.780546 -53.431657) (xy 335.738498 -53.401107)
			(xy 335.701747 -53.364356) (xy 335.671197 -53.322308) (xy 335.647601 -53.275998) (xy 335.63154 -53.226568)
			(xy 335.62341 -53.175233) (xy 334.655666 -53.175233) (xy 334.647536 -53.226568) (xy 334.631475 -53.275998)
			(xy 334.607879 -53.322308) (xy 334.577329 -53.364356) (xy 334.540578 -53.401107) (xy 334.49853 -53.431657)
			(xy 334.45222 -53.455253) (xy 334.40279 -53.471314) (xy 334.351455 -53.479444) (xy 334.299481 -53.479444)
			(xy 334.248146 -53.471314) (xy 334.198716 -53.455253) (xy 334.152406 -53.431657) (xy 334.110358 -53.401107)
			(xy 334.073607 -53.364356) (xy 334.043057 -53.322308) (xy 334.019461 -53.275998) (xy 334.0034 -53.226568)
			(xy 333.99527 -53.175233) (xy 333.68361 -53.175233) (xy 333.68361 -53.645133) (xy 336.43621 -53.645133)
			(xy 336.43621 -53.593159) (xy 336.44434 -53.541824) (xy 336.460401 -53.492394) (xy 336.483997 -53.446084)
			(xy 336.514547 -53.404036) (xy 336.551298 -53.367285) (xy 336.593346 -53.336735) (xy 336.639656 -53.313139)
			(xy 336.689086 -53.297078) (xy 336.740421 -53.288948) (xy 336.792395 -53.288948) (xy 336.84373 -53.297078)
			(xy 336.89316 -53.313139) (xy 336.93947 -53.336735) (xy 336.981518 -53.367285) (xy 337.018269 -53.404036)
			(xy 337.048819 -53.446084) (xy 337.072415 -53.492394) (xy 337.088476 -53.541824) (xy 337.096606 -53.593159)
			(xy 337.097116 -53.619146) (xy 337.096606 -53.645133) (xy 337.088476 -53.696468) (xy 337.072415 -53.745898)
			(xy 337.048819 -53.792208) (xy 337.018269 -53.834256) (xy 336.981518 -53.871007) (xy 336.93947 -53.901557)
			(xy 336.89316 -53.925153) (xy 336.84373 -53.941214) (xy 336.792395 -53.949344) (xy 336.740421 -53.949344)
			(xy 336.689086 -53.941214) (xy 336.639656 -53.925153) (xy 336.593346 -53.901557) (xy 336.551298 -53.871007)
			(xy 336.514547 -53.834256) (xy 336.483997 -53.792208) (xy 336.460401 -53.745898) (xy 336.44434 -53.696468)
			(xy 336.43621 -53.645133) (xy 333.68361 -53.645133) (xy 333.68361 -54.115033) (xy 337.25155 -54.115033)
			(xy 337.25155 -54.063059) (xy 337.25968 -54.011724) (xy 337.275741 -53.962294) (xy 337.299337 -53.915984)
			(xy 337.329887 -53.873936) (xy 337.366638 -53.837185) (xy 337.408686 -53.806635) (xy 337.454996 -53.783039)
			(xy 337.504426 -53.766978) (xy 337.555761 -53.758848) (xy 337.607735 -53.758848) (xy 337.65907 -53.766978)
			(xy 337.7085 -53.783039) (xy 337.75481 -53.806635) (xy 337.796858 -53.837185) (xy 337.833609 -53.873936)
			(xy 337.864159 -53.915984) (xy 337.887755 -53.962294) (xy 337.903816 -54.011724) (xy 337.911946 -54.063059)
			(xy 337.912456 -54.089046) (xy 337.911946 -54.115033) (xy 337.903816 -54.166368) (xy 337.887755 -54.215798)
			(xy 337.864159 -54.262108) (xy 337.833609 -54.304156) (xy 337.796858 -54.340907) (xy 337.75481 -54.371457)
			(xy 337.7085 -54.395053) (xy 337.65907 -54.411114) (xy 337.607735 -54.419244) (xy 337.555761 -54.419244)
			(xy 337.504426 -54.411114) (xy 337.454996 -54.395053) (xy 337.408686 -54.371457) (xy 337.366638 -54.340907)
			(xy 337.329887 -54.304156) (xy 337.299337 -54.262108) (xy 337.275741 -54.215798) (xy 337.25968 -54.166368)
			(xy 337.25155 -54.115033) (xy 333.68361 -54.115033) (xy 333.68361 -54.277514) (xy 333.705415 -54.29153)
			(xy 333.74477 -54.325259) (xy 333.778377 -54.364719) (xy 333.80541 -54.408943) (xy 333.825206 -54.456846)
			(xy 333.837279 -54.507251) (xy 333.841335 -54.558924) (xy 333.83929 -54.584933) (xy 336.43621 -54.584933)
			(xy 336.43621 -54.532959) (xy 336.44434 -54.481624) (xy 336.460401 -54.432194) (xy 336.483997 -54.385884)
			(xy 336.514547 -54.343836) (xy 336.551298 -54.307085) (xy 336.593346 -54.276535) (xy 336.639656 -54.252939)
			(xy 336.689086 -54.236878) (xy 336.740421 -54.228748) (xy 336.792395 -54.228748) (xy 336.84373 -54.236878)
			(xy 336.89316 -54.252939) (xy 336.93947 -54.276535) (xy 336.981518 -54.307085) (xy 337.018269 -54.343836)
			(xy 337.048819 -54.385884) (xy 337.072415 -54.432194) (xy 337.088476 -54.481624) (xy 337.096606 -54.532959)
			(xy 337.097116 -54.558946) (xy 337.096606 -54.584933) (xy 337.088476 -54.636268) (xy 337.072415 -54.685698)
			(xy 337.048819 -54.732008) (xy 337.018269 -54.774056) (xy 336.981518 -54.810807) (xy 336.93947 -54.841357)
			(xy 336.89316 -54.864953) (xy 336.84373 -54.881014) (xy 336.792395 -54.889144) (xy 336.740421 -54.889144)
			(xy 336.689086 -54.881014) (xy 336.639656 -54.864953) (xy 336.593346 -54.841357) (xy 336.551298 -54.810807)
			(xy 336.514547 -54.774056) (xy 336.483997 -54.732008) (xy 336.460401 -54.685698) (xy 336.44434 -54.636268)
			(xy 336.43621 -54.584933) (xy 333.83929 -54.584933) (xy 333.837272 -54.610596) (xy 333.825191 -54.661)
			(xy 333.805388 -54.7089) (xy 333.778348 -54.75312) (xy 333.744736 -54.792575) (xy 333.705376 -54.826299)
			(xy 333.68361 -54.840378) (xy 333.68361 -55.054833) (xy 335.62341 -55.054833) (xy 335.62341 -55.002859)
			(xy 335.63154 -54.951524) (xy 335.647601 -54.902094) (xy 335.671197 -54.855784) (xy 335.701747 -54.813736)
			(xy 335.738498 -54.776985) (xy 335.780546 -54.746435) (xy 335.826856 -54.722839) (xy 335.876286 -54.706778)
			(xy 335.927621 -54.698648) (xy 335.979595 -54.698648) (xy 336.03093 -54.706778) (xy 336.08036 -54.722839)
			(xy 336.12667 -54.746435) (xy 336.168718 -54.776985) (xy 336.205469 -54.813736) (xy 336.236019 -54.855784)
			(xy 336.259615 -54.902094) (xy 336.275676 -54.951524) (xy 336.283806 -55.002859) (xy 336.284316 -55.028846)
			(xy 336.283806 -55.054833) (xy 337.25155 -55.054833) (xy 337.25155 -55.002859) (xy 337.25968 -54.951524)
			(xy 337.275741 -54.902094) (xy 337.299337 -54.855784) (xy 337.329887 -54.813736) (xy 337.366638 -54.776985)
			(xy 337.408686 -54.746435) (xy 337.454996 -54.722839) (xy 337.504426 -54.706778) (xy 337.555761 -54.698648)
			(xy 337.607735 -54.698648) (xy 337.65907 -54.706778) (xy 337.7085 -54.722839) (xy 337.75481 -54.746435)
			(xy 337.796858 -54.776985) (xy 337.833609 -54.813736) (xy 337.864159 -54.855784) (xy 337.887755 -54.902094)
			(xy 337.903816 -54.951524) (xy 337.911946 -55.002859) (xy 337.912456 -55.028846) (xy 337.911946 -55.054833)
			(xy 337.903816 -55.106168) (xy 337.887755 -55.155598) (xy 337.864159 -55.201908) (xy 337.833609 -55.243956)
			(xy 337.796858 -55.280707) (xy 337.75481 -55.311257) (xy 337.7085 -55.334853) (xy 337.65907 -55.350914)
			(xy 337.607735 -55.359044) (xy 337.555761 -55.359044) (xy 337.504426 -55.350914) (xy 337.454996 -55.334853)
			(xy 337.408686 -55.311257) (xy 337.366638 -55.280707) (xy 337.329887 -55.243956) (xy 337.299337 -55.201908)
			(xy 337.275741 -55.155598) (xy 337.25968 -55.106168) (xy 337.25155 -55.054833) (xy 336.283806 -55.054833)
			(xy 336.275676 -55.106168) (xy 336.259615 -55.155598) (xy 336.236019 -55.201908) (xy 336.205469 -55.243956)
			(xy 336.168718 -55.280707) (xy 336.12667 -55.311257) (xy 336.08036 -55.334853) (xy 336.03093 -55.350914)
			(xy 335.979595 -55.359044) (xy 335.927621 -55.359044) (xy 335.876286 -55.350914) (xy 335.826856 -55.334853)
			(xy 335.780546 -55.311257) (xy 335.738498 -55.280707) (xy 335.701747 -55.243956) (xy 335.671197 -55.201908)
			(xy 335.647601 -55.155598) (xy 335.63154 -55.106168) (xy 335.62341 -55.054833) (xy 333.68361 -55.054833)
			(xy 333.68361 -55.524733) (xy 334.80807 -55.524733) (xy 334.80807 -55.472759) (xy 334.8162 -55.421424)
			(xy 334.832261 -55.371994) (xy 334.855857 -55.325684) (xy 334.886407 -55.283636) (xy 334.923158 -55.246885)
			(xy 334.965206 -55.216335) (xy 335.011516 -55.192739) (xy 335.060946 -55.176678) (xy 335.112281 -55.168548)
			(xy 335.164255 -55.168548) (xy 335.21559 -55.176678) (xy 335.26502 -55.192739) (xy 335.31133 -55.216335)
			(xy 335.353378 -55.246885) (xy 335.390129 -55.283636) (xy 335.420679 -55.325684) (xy 335.444275 -55.371994)
			(xy 335.460336 -55.421424) (xy 335.468466 -55.472759) (xy 335.468976 -55.498746) (xy 335.468466 -55.524733)
			(xy 336.43748 -55.524733) (xy 336.43748 -55.472759) (xy 336.44561 -55.421424) (xy 336.461671 -55.371994)
			(xy 336.485267 -55.325684) (xy 336.515817 -55.283636) (xy 336.552568 -55.246885) (xy 336.594616 -55.216335)
			(xy 336.640926 -55.192739) (xy 336.690356 -55.176678) (xy 336.741691 -55.168548) (xy 336.793665 -55.168548)
			(xy 336.845 -55.176678) (xy 336.89443 -55.192739) (xy 336.94074 -55.216335) (xy 336.982788 -55.246885)
			(xy 337.019539 -55.283636) (xy 337.050089 -55.325684) (xy 337.073685 -55.371994) (xy 337.089746 -55.421424)
			(xy 337.097876 -55.472759) (xy 337.098386 -55.498746) (xy 337.097876 -55.524733) (xy 337.089746 -55.576068)
			(xy 337.073685 -55.625498) (xy 337.050089 -55.671808) (xy 337.019539 -55.713856) (xy 336.982788 -55.750607)
			(xy 336.94074 -55.781157) (xy 336.89443 -55.804753) (xy 336.845 -55.820814) (xy 336.793665 -55.828944)
			(xy 336.741691 -55.828944) (xy 336.690356 -55.820814) (xy 336.640926 -55.804753) (xy 336.594616 -55.781157)
			(xy 336.552568 -55.750607) (xy 336.515817 -55.713856) (xy 336.485267 -55.671808) (xy 336.461671 -55.625498)
			(xy 336.44561 -55.576068) (xy 336.43748 -55.524733) (xy 335.468466 -55.524733) (xy 335.460336 -55.576068)
			(xy 335.444275 -55.625498) (xy 335.420679 -55.671808) (xy 335.390129 -55.713856) (xy 335.353378 -55.750607)
			(xy 335.31133 -55.781157) (xy 335.26502 -55.804753) (xy 335.21559 -55.820814) (xy 335.164255 -55.828944)
			(xy 335.112281 -55.828944) (xy 335.060946 -55.820814) (xy 335.011516 -55.804753) (xy 334.965206 -55.781157)
			(xy 334.923158 -55.750607) (xy 334.886407 -55.713856) (xy 334.855857 -55.671808) (xy 334.832261 -55.625498)
			(xy 334.8162 -55.576068) (xy 334.80807 -55.524733) (xy 333.68361 -55.524733) (xy 333.68361 -55.994633)
			(xy 335.62341 -55.994633) (xy 335.62341 -55.942659) (xy 335.63154 -55.891324) (xy 335.647601 -55.841894)
			(xy 335.671197 -55.795584) (xy 335.701747 -55.753536) (xy 335.738498 -55.716785) (xy 335.780546 -55.686235)
			(xy 335.826856 -55.662639) (xy 335.876286 -55.646578) (xy 335.927621 -55.638448) (xy 335.979595 -55.638448)
			(xy 336.03093 -55.646578) (xy 336.08036 -55.662639) (xy 336.12667 -55.686235) (xy 336.168718 -55.716785)
			(xy 336.205469 -55.753536) (xy 336.236019 -55.795584) (xy 336.259615 -55.841894) (xy 336.275676 -55.891324)
			(xy 336.283806 -55.942659) (xy 336.284316 -55.968646) (xy 336.283806 -55.994633) (xy 337.25155 -55.994633)
			(xy 337.25155 -55.942659) (xy 337.25968 -55.891324) (xy 337.275741 -55.841894) (xy 337.299337 -55.795584)
			(xy 337.329887 -55.753536) (xy 337.366638 -55.716785) (xy 337.408686 -55.686235) (xy 337.454996 -55.662639)
			(xy 337.504426 -55.646578) (xy 337.555761 -55.638448) (xy 337.607735 -55.638448) (xy 337.65907 -55.646578)
			(xy 337.7085 -55.662639) (xy 337.75481 -55.686235) (xy 337.796858 -55.716785) (xy 337.833609 -55.753536)
			(xy 337.864159 -55.795584) (xy 337.887755 -55.841894) (xy 337.903816 -55.891324) (xy 337.911946 -55.942659)
			(xy 337.912456 -55.968646) (xy 337.911946 -55.994633) (xy 337.903816 -56.045968) (xy 337.887755 -56.095398)
			(xy 337.864159 -56.141708) (xy 337.833609 -56.183756) (xy 337.796858 -56.220507) (xy 337.75481 -56.251057)
			(xy 337.7085 -56.274653) (xy 337.65907 -56.290714) (xy 337.607735 -56.298844) (xy 337.555761 -56.298844)
			(xy 337.504426 -56.290714) (xy 337.454996 -56.274653) (xy 337.408686 -56.251057) (xy 337.366638 -56.220507)
			(xy 337.329887 -56.183756) (xy 337.299337 -56.141708) (xy 337.275741 -56.095398) (xy 337.25968 -56.045968)
			(xy 337.25155 -55.994633) (xy 336.283806 -55.994633) (xy 336.275676 -56.045968) (xy 336.259615 -56.095398)
			(xy 336.236019 -56.141708) (xy 336.205469 -56.183756) (xy 336.168718 -56.220507) (xy 336.12667 -56.251057)
			(xy 336.08036 -56.274653) (xy 336.03093 -56.290714) (xy 335.979595 -56.298844) (xy 335.927621 -56.298844)
			(xy 335.876286 -56.290714) (xy 335.826856 -56.274653) (xy 335.780546 -56.251057) (xy 335.738498 -56.220507)
			(xy 335.701747 -56.183756) (xy 335.671197 -56.141708) (xy 335.647601 -56.095398) (xy 335.63154 -56.045968)
			(xy 335.62341 -55.994633) (xy 333.68361 -55.994633) (xy 333.68361 -56.15686) (xy 333.705443 -56.170882)
			(xy 333.744851 -56.204633) (xy 333.778504 -56.244126) (xy 333.805575 -56.28839) (xy 333.825399 -56.33634)
			(xy 333.83749 -56.386797) (xy 333.841551 -56.438524) (xy 333.839505 -56.464533) (xy 334.80807 -56.464533)
			(xy 334.80807 -56.412559) (xy 334.8162 -56.361224) (xy 334.832261 -56.311794) (xy 334.855857 -56.265484)
			(xy 334.886407 -56.223436) (xy 334.923158 -56.186685) (xy 334.965206 -56.156135) (xy 335.011516 -56.132539)
			(xy 335.060946 -56.116478) (xy 335.112281 -56.108348) (xy 335.164255 -56.108348) (xy 335.21559 -56.116478)
			(xy 335.26502 -56.132539) (xy 335.31133 -56.156135) (xy 335.353378 -56.186685) (xy 335.390129 -56.223436)
			(xy 335.420679 -56.265484) (xy 335.444275 -56.311794) (xy 335.460336 -56.361224) (xy 335.468466 -56.412559)
			(xy 335.468976 -56.438546) (xy 335.468466 -56.464533) (xy 336.437226 -56.464533) (xy 336.437226 -56.412559)
			(xy 336.445356 -56.361224) (xy 336.461417 -56.311794) (xy 336.485013 -56.265484) (xy 336.515563 -56.223436)
			(xy 336.552314 -56.186685) (xy 336.594362 -56.156135) (xy 336.640672 -56.132539) (xy 336.690102 -56.116478)
			(xy 336.741437 -56.108348) (xy 336.793411 -56.108348) (xy 336.844746 -56.116478) (xy 336.894176 -56.132539)
			(xy 336.940486 -56.156135) (xy 336.982534 -56.186685) (xy 337.019285 -56.223436) (xy 337.049835 -56.265484)
			(xy 337.073431 -56.311794) (xy 337.089492 -56.361224) (xy 337.097622 -56.412559) (xy 337.098132 -56.438546)
			(xy 337.097622 -56.464533) (xy 337.089492 -56.515868) (xy 337.073431 -56.565298) (xy 337.049835 -56.611608)
			(xy 337.019285 -56.653656) (xy 336.982534 -56.690407) (xy 336.940486 -56.720957) (xy 336.894176 -56.744553)
			(xy 336.844746 -56.760614) (xy 336.793411 -56.768744) (xy 336.741437 -56.768744) (xy 336.690102 -56.760614)
			(xy 336.640672 -56.744553) (xy 336.594362 -56.720957) (xy 336.552314 -56.690407) (xy 336.515563 -56.653656)
			(xy 336.485013 -56.611608) (xy 336.461417 -56.565298) (xy 336.445356 -56.515868) (xy 336.437226 -56.464533)
			(xy 335.468466 -56.464533) (xy 335.460336 -56.515868) (xy 335.444275 -56.565298) (xy 335.420679 -56.611608)
			(xy 335.390129 -56.653656) (xy 335.353378 -56.690407) (xy 335.31133 -56.720957) (xy 335.26502 -56.744553)
			(xy 335.21559 -56.760614) (xy 335.164255 -56.768744) (xy 335.112281 -56.768744) (xy 335.060946 -56.760614)
			(xy 335.011516 -56.744553) (xy 334.965206 -56.720957) (xy 334.923158 -56.690407) (xy 334.886407 -56.653656)
			(xy 334.855857 -56.611608) (xy 334.832261 -56.565298) (xy 334.8162 -56.515868) (xy 334.80807 -56.464533)
			(xy 333.839505 -56.464533) (xy 333.837482 -56.49025) (xy 333.825384 -56.540706) (xy 333.805553 -56.588653)
			(xy 333.778476 -56.632913) (xy 333.744817 -56.672401) (xy 333.705404 -56.706146) (xy 333.68361 -56.720232)
			(xy 333.68361 -56.797702) (xy 334.005936 -57.120028)
		)
		(stroke
			(width 0)
			(type solid)
		)
		(fill yes)
		(layer "In2.Cu")
		(net "P1V8_PCH_AUX")
	)
	(gr_poly
		(pts
			(xy 239.09274 -400.24304) (xy 239.09274 -396.70228) (xy 239.3823 -396.41272) (xy 278.86406 -396.41272)
			(xy 279.2603 -396.01648) (xy 279.2603 -395.510766) (xy 279.22698 -395.484207) (xy 279.165036 -395.42569)
			(xy 279.10897 -395.361518) (xy 279.059296 -395.29228) (xy 279.016469 -395.218611) (xy 278.980881 -395.141184)
			(xy 278.952858 -395.06071) (xy 278.932657 -394.977926) (xy 278.920463 -394.893589) (xy 278.916388 -394.808473)
			(xy 278.920468 -394.723357) (xy 278.932667 -394.639021) (xy 278.952873 -394.556238) (xy 278.980901 -394.475765)
			(xy 279.016494 -394.398341) (xy 279.059325 -394.324674) (xy 279.109004 -394.255439) (xy 279.165073 -394.191271)
			(xy 279.227021 -394.132757) (xy 279.2603 -394.106146) (xy 279.2603 -390.36752) (xy 278.94788 -390.0551)
			(xy 266.9667 -390.0551) (xy 256.87274 -379.96114) (xy 197.69328 -379.96114) (xy 189.64148 -388.01294)
			(xy 233.776012 -388.01294) (xy 233.776499 -387.98557) (xy 233.784311 -387.931392) (xy 233.799795 -387.878889)
			(xy 233.822632 -387.829142) (xy 233.852353 -387.783174) (xy 233.869992 -387.762242) (xy 233.879191 -387.750886)
			(xy 233.891374 -387.724339) (xy 233.895555 -387.69543) (xy 233.891391 -387.666519) (xy 233.879224 -387.639965)
			(xy 233.869992 -387.628638) (xy 233.852356 -387.607703) (xy 233.822644 -387.561731) (xy 233.799808 -387.511984)
			(xy 233.784316 -387.459484) (xy 233.776487 -387.405309) (xy 233.776012 -387.37794) (xy 233.776493 -387.350687)
			(xy 233.784245 -387.296736) (xy 233.799597 -387.244437) (xy 233.822236 -387.194856) (xy 233.851702 -387.149002)
			(xy 233.887394 -387.107808) (xy 233.928585 -387.072114) (xy 233.974438 -387.042645) (xy 234.024018 -387.020004)
			(xy 234.076316 -387.004649) (xy 234.130267 -386.996894) (xy 234.15752 -386.996432) (xy 234.184891 -386.996879)
			(xy 234.239071 -387.0047) (xy 234.291575 -387.020193) (xy 234.341321 -387.043039) (xy 234.387287 -387.072769)
			(xy 234.408218 -387.090412) (xy 234.419546 -387.099648) (xy 234.446103 -387.111824) (xy 234.47502 -387.115997)
			(xy 234.503937 -387.111824) (xy 234.530494 -387.099648) (xy 234.541822 -387.090412) (xy 234.562755 -387.072771)
			(xy 234.608723 -387.043047) (xy 234.658469 -387.020201) (xy 234.710971 -387.004705) (xy 234.765149 -386.996876)
			(xy 234.819891 -386.996876) (xy 234.874069 -387.004705) (xy 234.926571 -387.020201) (xy 234.976317 -387.043047)
			(xy 235.022285 -387.072771) (xy 235.043218 -387.090412) (xy 235.054546 -387.099648) (xy 235.081103 -387.111824)
			(xy 235.11002 -387.115997) (xy 235.138937 -387.111824) (xy 235.165494 -387.099648) (xy 235.176822 -387.090412)
			(xy 235.197755 -387.072771) (xy 235.243723 -387.043047) (xy 235.293469 -387.020201) (xy 235.345971 -387.004705)
			(xy 235.400149 -386.996876) (xy 235.454891 -386.996876) (xy 235.509069 -387.004705) (xy 235.561571 -387.020201)
			(xy 235.611317 -387.043047) (xy 235.657285 -387.072771) (xy 235.678218 -387.090412) (xy 235.689546 -387.099648)
			(xy 235.716103 -387.111824) (xy 235.74502 -387.115997) (xy 235.773937 -387.111824) (xy 235.800494 -387.099648)
			(xy 235.811822 -387.090412) (xy 235.832755 -387.072771) (xy 235.878723 -387.043047) (xy 235.928469 -387.020201)
			(xy 235.980971 -387.004705) (xy 236.035149 -386.996876) (xy 236.089891 -386.996876) (xy 236.144069 -387.004705)
			(xy 236.196571 -387.020201) (xy 236.246317 -387.043047) (xy 236.292285 -387.072771) (xy 236.313218 -387.090412)
			(xy 236.324546 -387.099648) (xy 236.351103 -387.111824) (xy 236.38002 -387.115997) (xy 236.408937 -387.111824)
			(xy 236.435494 -387.099648) (xy 236.446822 -387.090412) (xy 236.467755 -387.072771) (xy 236.513723 -387.043047)
			(xy 236.563469 -387.020201) (xy 236.615971 -387.004705) (xy 236.670149 -386.996876) (xy 236.724891 -386.996876)
			(xy 236.779069 -387.004705) (xy 236.831571 -387.020201) (xy 236.881317 -387.043047) (xy 236.927285 -387.072771)
			(xy 236.948218 -387.090412) (xy 236.959546 -387.099648) (xy 236.986103 -387.111824) (xy 237.01502 -387.115997)
			(xy 237.043937 -387.111824) (xy 237.070494 -387.099648) (xy 237.081822 -387.090412) (xy 237.102755 -387.072771)
			(xy 237.148723 -387.043047) (xy 237.198469 -387.020201) (xy 237.250971 -387.004705) (xy 237.305149 -386.996876)
			(xy 237.359891 -386.996876) (xy 237.414069 -387.004705) (xy 237.466571 -387.020201) (xy 237.516317 -387.043047)
			(xy 237.562285 -387.072771) (xy 237.583218 -387.090412) (xy 237.594546 -387.099648) (xy 237.621103 -387.111824)
			(xy 237.65002 -387.115997) (xy 237.678937 -387.111824) (xy 237.705494 -387.099648) (xy 237.716822 -387.090412)
			(xy 237.737755 -387.072771) (xy 237.783723 -387.043047) (xy 237.833469 -387.020201) (xy 237.885971 -387.004705)
			(xy 237.940149 -386.996876) (xy 237.994891 -386.996876) (xy 238.049069 -387.004705) (xy 238.101571 -387.020201)
			(xy 238.151317 -387.043047) (xy 238.197285 -387.072771) (xy 238.218218 -387.090412) (xy 238.229546 -387.099648)
			(xy 238.256103 -387.111824) (xy 238.28502 -387.115997) (xy 238.313937 -387.111824) (xy 238.340494 -387.099648)
			(xy 238.351822 -387.090412) (xy 238.372774 -387.072798) (xy 238.418741 -387.043082) (xy 238.468484 -387.020241)
			(xy 238.52098 -387.004744) (xy 238.575152 -386.996909) (xy 238.60252 -386.996432) (xy 238.629775 -386.996836)
			(xy 238.68373 -387.004597) (xy 238.736032 -387.019958) (xy 238.785615 -387.042605) (xy 238.83147 -387.072079)
			(xy 238.872663 -387.107779) (xy 238.908357 -387.148978) (xy 238.937823 -387.194838) (xy 238.960463 -387.244424)
			(xy 238.975816 -387.296728) (xy 238.983568 -387.350685) (xy 238.984028 -387.37794) (xy 238.983544 -387.40531)
			(xy 238.975733 -387.459489) (xy 238.960249 -387.511992) (xy 238.937411 -387.56174) (xy 238.907689 -387.607707)
			(xy 238.890048 -387.628638) (xy 238.880776 -387.639938) (xy 238.86861 -387.666507) (xy 238.864447 -387.69543)
			(xy 238.868627 -387.724352) (xy 238.880809 -387.750913) (xy 238.890048 -387.762242) (xy 238.907665 -387.783192)
			(xy 238.937382 -387.829159) (xy 238.960223 -387.878902) (xy 238.975719 -387.931399) (xy 238.983552 -387.985572)
			(xy 238.984028 -388.01294) (xy 238.983559 -388.040191) (xy 238.975798 -388.094139) (xy 238.960439 -388.146432)
			(xy 238.937794 -388.196009) (xy 238.908326 -388.241858) (xy 238.872633 -388.283047) (xy 238.831442 -388.318738)
			(xy 238.785591 -388.348204) (xy 238.736014 -388.370846) (xy 238.683719 -388.386202) (xy 238.629771 -388.393961)
			(xy 238.60252 -388.394448) (xy 238.57515 -388.393983) (xy 238.52097 -388.386167) (xy 238.468466 -388.370678)
			(xy 238.418719 -388.347836) (xy 238.372753 -388.31811) (xy 238.351822 -388.300468) (xy 238.340494 -388.291232)
			(xy 238.313937 -388.279056) (xy 238.28502 -388.274883) (xy 238.256103 -388.279056) (xy 238.229546 -388.291232)
			(xy 238.218218 -388.300468) (xy 238.197285 -388.318109) (xy 238.151317 -388.347833) (xy 238.101571 -388.370679)
			(xy 238.049069 -388.386175) (xy 237.994891 -388.394004) (xy 237.940149 -388.394004) (xy 237.885971 -388.386175)
			(xy 237.833469 -388.370679) (xy 237.783723 -388.347833) (xy 237.737755 -388.318109) (xy 237.716822 -388.300468)
			(xy 237.705494 -388.291232) (xy 237.678937 -388.279056) (xy 237.65002 -388.274883) (xy 237.621103 -388.279056)
			(xy 237.594546 -388.291232) (xy 237.583218 -388.300468) (xy 237.562285 -388.318109) (xy 237.516317 -388.347833)
			(xy 237.466571 -388.370679) (xy 237.414069 -388.386175) (xy 237.359891 -388.394004) (xy 237.305149 -388.394004)
			(xy 237.250971 -388.386175) (xy 237.198469 -388.370679) (xy 237.148723 -388.347833) (xy 237.102755 -388.318109)
			(xy 237.081822 -388.300468) (xy 237.070494 -388.291232) (xy 237.043937 -388.279056) (xy 237.01502 -388.274883)
			(xy 236.986103 -388.279056) (xy 236.959546 -388.291232) (xy 236.948218 -388.300468) (xy 236.927285 -388.318109)
			(xy 236.881317 -388.347833) (xy 236.831571 -388.370679) (xy 236.779069 -388.386175) (xy 236.724891 -388.394004)
			(xy 236.670149 -388.394004) (xy 236.615971 -388.386175) (xy 236.563469 -388.370679) (xy 236.513723 -388.347833)
			(xy 236.467755 -388.318109) (xy 236.446822 -388.300468) (xy 236.435494 -388.291232) (xy 236.408937 -388.279056)
			(xy 236.38002 -388.274883) (xy 236.351103 -388.279056) (xy 236.324546 -388.291232) (xy 236.313218 -388.300468)
			(xy 236.292285 -388.318109) (xy 236.246317 -388.347833) (xy 236.196571 -388.370679) (xy 236.144069 -388.386175)
			(xy 236.089891 -388.394004) (xy 236.035149 -388.394004) (xy 235.980971 -388.386175) (xy 235.928469 -388.370679)
			(xy 235.878723 -388.347833) (xy 235.832755 -388.318109) (xy 235.811822 -388.300468) (xy 235.800494 -388.291232)
			(xy 235.773937 -388.279056) (xy 235.74502 -388.274883) (xy 235.716103 -388.279056) (xy 235.689546 -388.291232)
			(xy 235.678218 -388.300468) (xy 235.657285 -388.318109) (xy 235.611317 -388.347833) (xy 235.561571 -388.370679)
			(xy 235.509069 -388.386175) (xy 235.454891 -388.394004) (xy 235.400149 -388.394004) (xy 235.345971 -388.386175)
			(xy 235.293469 -388.370679) (xy 235.243723 -388.347833) (xy 235.197755 -388.318109) (xy 235.176822 -388.300468)
			(xy 235.165494 -388.291232) (xy 235.138937 -388.279056) (xy 235.11002 -388.274883) (xy 235.081103 -388.279056)
			(xy 235.054546 -388.291232) (xy 235.043218 -388.300468) (xy 235.022285 -388.318109) (xy 234.976317 -388.347833)
			(xy 234.926571 -388.370679) (xy 234.874069 -388.386175) (xy 234.819891 -388.394004) (xy 234.765149 -388.394004)
			(xy 234.710971 -388.386175) (xy 234.658469 -388.370679) (xy 234.608723 -388.347833) (xy 234.562755 -388.318109)
			(xy 234.541822 -388.300468) (xy 234.530494 -388.291232) (xy 234.503937 -388.279056) (xy 234.47502 -388.274883)
			(xy 234.446103 -388.279056) (xy 234.419546 -388.291232) (xy 234.408218 -388.300468) (xy 234.387286 -388.318107)
			(xy 234.341314 -388.34782) (xy 234.291566 -388.370657) (xy 234.239065 -388.386147) (xy 234.184889 -388.393975)
			(xy 234.15752 -388.394448) (xy 234.130271 -388.393903) (xy 234.076328 -388.386151) (xy 234.024036 -388.3708)
			(xy 233.974462 -388.348164) (xy 233.928614 -388.318704) (xy 233.887424 -388.283018) (xy 233.851732 -388.241835)
			(xy 233.822265 -388.195991) (xy 233.799621 -388.14642) (xy 233.784262 -388.094131) (xy 233.776501 -388.040189)
			(xy 233.776012 -388.01294) (xy 189.64148 -388.01294) (xy 185.2549 -392.39952) (xy 185.2549 -394.8085)
			(xy 243.179528 -394.8085) (xy 243.183558 -394.723892) (xy 243.195613 -394.640051) (xy 243.215583 -394.557735)
			(xy 243.243287 -394.47769) (xy 243.278475 -394.400641) (xy 243.320827 -394.327286) (xy 243.36996 -394.258289)
			(xy 243.42543 -394.194274) (xy 243.486733 -394.135823) (xy 243.553315 -394.083463) (xy 243.624573 -394.03767)
			(xy 243.699861 -393.998857) (xy 243.778498 -393.967377) (xy 243.859771 -393.943515) (xy 243.942944 -393.927486)
			(xy 244.027264 -393.919435) (xy 244.069616 -393.918948) (xy 244.11084 -393.919417) (xy 244.192933 -393.927053)
			(xy 244.273968 -393.94225) (xy 244.35325 -393.964876) (xy 244.430099 -393.994739) (xy 244.503857 -394.031582)
			(xy 244.573891 -394.075088) (xy 244.639601 -394.124886) (xy 244.670326 -394.152374) (xy 244.677558 -394.158461)
			(xy 244.695171 -394.165287) (xy 244.714061 -394.165287) (xy 244.731674 -394.158461) (xy 244.738906 -394.152374)
			(xy 244.769639 -394.124894) (xy 244.835341 -394.075085) (xy 244.905371 -394.03157) (xy 244.979128 -393.994723)
			(xy 245.055977 -393.964858) (xy 245.13526 -393.942233) (xy 245.216297 -393.927041) (xy 245.298392 -393.919413)
			(xy 245.339616 -393.918948) (xy 245.381408 -393.919476) (xy 245.464624 -393.927312) (xy 245.546738 -393.942923)
			(xy 245.627024 -393.96617) (xy 245.704775 -393.996849) (xy 245.779303 -394.034689) (xy 245.849951 -394.079356)
			(xy 245.916096 -394.130456) (xy 245.977154 -394.187537) (xy 246.032585 -394.250097) (xy 246.081902 -394.317582)
			(xy 246.124667 -394.389397) (xy 246.143018 -394.426948) (xy 246.170089 -394.428781) (xy 246.223268 -394.43954)
			(xy 246.274197 -394.458246) (xy 246.321697 -394.484466) (xy 246.364667 -394.51759) (xy 246.402111 -394.556853)
			(xy 246.433163 -394.601345) (xy 246.457102 -394.650034) (xy 246.473374 -394.701792) (xy 246.481601 -394.75542)
			(xy 246.482108 -394.782548) (xy 246.481601 -394.8085) (xy 249.114543 -394.8085) (xy 249.118574 -394.723896)
			(xy 249.130628 -394.640058) (xy 249.150596 -394.557746) (xy 249.178298 -394.477704) (xy 249.213483 -394.400658)
			(xy 249.255833 -394.327305) (xy 249.304963 -394.25831) (xy 249.360429 -394.194298) (xy 249.421729 -394.135847)
			(xy 249.488307 -394.083488) (xy 249.55956 -394.037695) (xy 249.634844 -393.998882) (xy 249.713476 -393.967401)
			(xy 249.794745 -393.943537) (xy 249.877914 -393.927506) (xy 249.96223 -393.919453) (xy 250.00458 -393.918948)
			(xy 250.045803 -393.919439) (xy 250.127896 -393.927072) (xy 250.20893 -393.942266) (xy 250.288212 -393.964889)
			(xy 250.365061 -393.994749) (xy 250.438819 -394.031588) (xy 250.508854 -394.075092) (xy 250.574564 -394.124887)
			(xy 250.60529 -394.152374) (xy 250.612522 -394.158461) (xy 250.630135 -394.165287) (xy 250.649025 -394.165287)
			(xy 250.666638 -394.158461) (xy 250.67387 -394.152374) (xy 250.704576 -394.124863) (xy 250.770283 -394.075057)
			(xy 250.840317 -394.031545) (xy 250.914078 -393.994701) (xy 250.990931 -393.96484) (xy 251.070218 -393.942219)
			(xy 251.151257 -393.927032) (xy 251.233355 -393.91941) (xy 251.27458 -393.918948) (xy 251.316356 -393.919458)
			(xy 251.399539 -393.927298) (xy 251.481621 -393.942901) (xy 251.561879 -393.966129) (xy 251.639606 -393.996779)
			(xy 251.714118 -394.03458) (xy 251.784758 -394.079199) (xy 251.850904 -394.130243) (xy 251.911974 -394.187264)
			(xy 251.96743 -394.249758) (xy 252.016784 -394.317175) (xy 252.059601 -394.388922) (xy 252.077982 -394.42644)
			(xy 252.086364 -394.42644) (xy 252.114351 -394.426946) (xy 252.169636 -394.435698) (xy 252.222871 -394.452992)
			(xy 252.272744 -394.478402) (xy 252.318028 -394.511302) (xy 252.357606 -394.550881) (xy 252.390505 -394.596166)
			(xy 252.415913 -394.646041) (xy 252.433205 -394.699276) (xy 252.441955 -394.754561) (xy 252.442472 -394.782548)
			(xy 252.441992 -394.8085) (xy 255.049428 -394.8085) (xy 255.053459 -394.723891) (xy 255.065514 -394.640048)
			(xy 255.085484 -394.55773) (xy 255.11319 -394.477684) (xy 255.148379 -394.400634) (xy 255.190732 -394.327277)
			(xy 255.239868 -394.258279) (xy 255.295339 -394.194265) (xy 255.356645 -394.135813) (xy 255.423229 -394.083453)
			(xy 255.494489 -394.03766) (xy 255.56978 -393.998849) (xy 255.648419 -393.96737) (xy 255.729694 -393.943509)
			(xy 255.812869 -393.927482) (xy 255.897191 -393.919434) (xy 255.939544 -393.918948) (xy 255.980768 -393.919399)
			(xy 256.062862 -393.927038) (xy 256.143897 -393.942237) (xy 256.223179 -393.964866) (xy 256.300029 -393.994731)
			(xy 256.373786 -394.031576) (xy 256.44382 -394.075085) (xy 256.509529 -394.124885) (xy 256.540254 -394.152374)
			(xy 256.547486 -394.158461) (xy 256.565099 -394.165287) (xy 256.583989 -394.165287) (xy 256.601602 -394.158461)
			(xy 256.608834 -394.152374) (xy 256.639555 -394.12488) (xy 256.70526 -394.075073) (xy 256.775292 -394.031559)
			(xy 256.849049 -393.994713) (xy 256.925901 -393.96485) (xy 257.005185 -393.942227) (xy 257.086223 -393.927037)
			(xy 257.168319 -393.919412) (xy 257.209544 -393.918948) (xy 257.251493 -393.919491) (xy 257.335018 -393.927401)
			(xy 257.417428 -393.943137) (xy 257.497991 -393.96656) (xy 257.575991 -393.997462) (xy 257.650737 -394.035568)
			(xy 257.721565 -394.08054) (xy 257.787845 -394.131979) (xy 257.848989 -394.189427) (xy 257.904455 -394.252376)
			(xy 257.95375 -394.320266) (xy 257.996436 -394.392494) (xy 258.014724 -394.43025) (xy 258.027542 -394.428485)
			(xy 258.053348 -394.426578) (xy 258.066286 -394.42644) (xy 258.067048 -394.42644) (xy 258.093699 -394.426845)
			(xy 258.146403 -394.434796) (xy 258.197335 -394.450512) (xy 258.245356 -394.473643) (xy 258.289393 -394.503673)
			(xy 258.328463 -394.539929) (xy 258.361693 -394.581604) (xy 258.388341 -394.627765) (xy 258.407813 -394.677383)
			(xy 258.419673 -394.729348) (xy 258.423656 -394.7825) (xy 258.421708 -394.8085) (xy 260.984428 -394.8085)
			(xy 260.988458 -394.723893) (xy 261.000513 -394.640052) (xy 261.020483 -394.557736) (xy 261.048186 -394.477692)
			(xy 261.083374 -394.400643) (xy 261.125725 -394.327288) (xy 261.174858 -394.258291) (xy 261.230327 -394.194277)
			(xy 261.29163 -394.135826) (xy 261.358212 -394.083466) (xy 261.429469 -394.037672) (xy 261.504756 -393.99886)
			(xy 261.583392 -393.967379) (xy 261.664664 -393.943516) (xy 261.747837 -393.927487) (xy 261.832156 -393.919436)
			(xy 261.874508 -393.918948) (xy 261.915732 -393.919422) (xy 261.997825 -393.927057) (xy 262.078859 -393.942253)
			(xy 262.158141 -393.964879) (xy 262.234991 -393.994741) (xy 262.308749 -394.031583) (xy 262.378783 -394.075089)
			(xy 262.444493 -394.124886) (xy 262.475218 -394.152374) (xy 262.48245 -394.158461) (xy 262.500063 -394.165287)
			(xy 262.518953 -394.165287) (xy 262.536566 -394.158461) (xy 262.543798 -394.152374) (xy 262.574534 -394.124897)
			(xy 262.640236 -394.075089) (xy 262.710266 -394.031574) (xy 262.784021 -393.994725) (xy 262.86087 -393.96486)
			(xy 262.940153 -393.942234) (xy 263.021189 -393.927042) (xy 263.103284 -393.919413) (xy 263.144508 -393.918948)
			(xy 263.18635 -393.919404) (xy 263.269665 -393.927258) (xy 263.351874 -393.942906) (xy 263.432248 -393.966208)
			(xy 263.510078 -393.996959) (xy 263.584674 -394.034887) (xy 263.655376 -394.079656) (xy 263.721559 -394.130869)
			(xy 263.782638 -394.188075) (xy 263.838071 -394.250766) (xy 263.887369 -394.318389) (xy 263.930095 -394.390344)
			(xy 263.948418 -394.427964) (xy 263.981692 -394.42644) (xy 264.008347 -394.426817) (xy 264.061062 -394.434761)
			(xy 264.112004 -394.450474) (xy 264.160035 -394.473603) (xy 264.204083 -394.503633) (xy 264.243162 -394.539893)
			(xy 264.276401 -394.581572) (xy 264.303057 -394.62774) (xy 264.322533 -394.677365) (xy 264.334396 -394.729339)
			(xy 264.33838 -394.7825) (xy 264.336432 -394.8085) (xy 266.919443 -394.8085) (xy 266.923474 -394.723896)
			(xy 266.935527 -394.640059) (xy 266.955496 -394.557747) (xy 266.983198 -394.477706) (xy 267.018382 -394.40066)
			(xy 267.060731 -394.327308) (xy 267.109861 -394.258313) (xy 267.165326 -394.194301) (xy 267.226625 -394.13585)
			(xy 267.293203 -394.083491) (xy 267.364456 -394.037698) (xy 267.439739 -393.998885) (xy 267.51837 -393.967403)
			(xy 267.599638 -393.943538) (xy 267.682807 -393.927507) (xy 267.767122 -393.919453) (xy 267.809472 -393.918948)
			(xy 267.850695 -393.919444) (xy 267.932787 -393.927077) (xy 268.013822 -393.942269) (xy 268.093103 -393.964892)
			(xy 268.169953 -393.994751) (xy 268.243711 -394.03159) (xy 268.313746 -394.075093) (xy 268.379456 -394.124888)
			(xy 268.410182 -394.152374) (xy 268.417414 -394.158461) (xy 268.435027 -394.165287) (xy 268.453917 -394.165287)
			(xy 268.47153 -394.158461) (xy 268.478762 -394.152374) (xy 268.509471 -394.124866) (xy 268.575178 -394.07506)
			(xy 268.645212 -394.031548) (xy 268.718971 -393.994703) (xy 268.795824 -393.964842) (xy 268.87511 -393.942221)
			(xy 268.95615 -393.927033) (xy 269.038247 -393.91941) (xy 269.079472 -393.918948) (xy 269.121265 -393.919428)
			(xy 269.204483 -393.927269) (xy 269.286598 -393.942885) (xy 269.366885 -393.966137) (xy 269.444636 -393.996821)
			(xy 269.519164 -394.034666) (xy 269.589812 -394.079337) (xy 269.655956 -394.130441) (xy 269.717013 -394.187526)
			(xy 269.772444 -394.250089) (xy 269.821759 -394.317577) (xy 269.864524 -394.389396) (xy 269.882874 -394.426948)
			(xy 269.909949 -394.428731) (xy 269.963129 -394.439499) (xy 270.014058 -394.458212) (xy 270.061558 -394.484438)
			(xy 270.104527 -394.517569) (xy 270.141971 -394.556837) (xy 270.173021 -394.601333) (xy 270.19696 -394.650026)
			(xy 270.213231 -394.701787) (xy 270.221458 -394.755419) (xy 270.221964 -394.782548) (xy 270.221496 -394.8085)
			(xy 272.854328 -394.8085) (xy 272.858359 -394.723891) (xy 272.870414 -394.640048) (xy 272.890384 -394.557731)
			(xy 272.918089 -394.477686) (xy 272.953277 -394.400636) (xy 272.995631 -394.32728) (xy 273.044766 -394.258282)
			(xy 273.100237 -394.194267) (xy 273.161542 -394.135816) (xy 273.228125 -394.083456) (xy 273.299385 -394.037663)
			(xy 273.374675 -393.998851) (xy 273.453313 -393.967372) (xy 273.534587 -393.943511) (xy 273.617762 -393.927483)
			(xy 273.702084 -393.919434) (xy 273.744436 -393.918948) (xy 273.78566 -393.919404) (xy 273.867754 -393.927042)
			(xy 273.948789 -393.942241) (xy 274.028071 -393.964869) (xy 274.10492 -393.994734) (xy 274.178678 -394.031578)
			(xy 274.248712 -394.075086) (xy 274.314421 -394.124886) (xy 274.345146 -394.152374) (xy 274.352378 -394.158461)
			(xy 274.369991 -394.165287) (xy 274.388881 -394.165287) (xy 274.406494 -394.158461) (xy 274.413726 -394.152374)
			(xy 274.44445 -394.124884) (xy 274.510154 -394.075076) (xy 274.580186 -394.031562) (xy 274.653943 -393.994716)
			(xy 274.730794 -393.964852) (xy 274.810078 -393.942228) (xy 274.891116 -393.927038) (xy 274.973211 -393.919412)
			(xy 275.014436 -393.918948) (xy 275.056229 -393.919459) (xy 275.139445 -393.927297) (xy 275.221559 -393.942909)
			(xy 275.301846 -393.966158) (xy 275.379596 -393.996839) (xy 275.454125 -394.034681) (xy 275.524773 -394.079349)
			(xy 275.590918 -394.130451) (xy 275.651975 -394.187533) (xy 275.707406 -394.250094) (xy 275.756722 -394.31758)
			(xy 275.799488 -394.389397) (xy 275.817838 -394.426948) (xy 275.844911 -394.428763) (xy 275.898089 -394.439526)
			(xy 275.949019 -394.458234) (xy 275.996518 -394.484456) (xy 276.039488 -394.517583) (xy 276.076932 -394.556848)
			(xy 276.107984 -394.601341) (xy 276.131922 -394.650031) (xy 276.148194 -394.70179) (xy 276.156421 -394.75542)
			(xy 276.156928 -394.782548) (xy 276.156404 -394.808503) (xy 276.148874 -394.859865) (xy 276.133965 -394.909589)
			(xy 276.111994 -394.956621) (xy 276.083427 -394.999964) (xy 276.048869 -395.038699) (xy 276.009052 -395.072006)
			(xy 275.964821 -395.099179) (xy 275.917114 -395.11964) (xy 275.86694 -395.132958) (xy 275.841206 -395.13637)
			(xy 275.825747 -395.174161) (xy 275.788816 -395.246988) (xy 275.745365 -395.316123) (xy 275.695761 -395.380985)
			(xy 275.64042 -395.441027) (xy 275.579808 -395.495744) (xy 275.514437 -395.544676) (xy 275.444856 -395.587409)
			(xy 275.371651 -395.623585) (xy 275.295438 -395.652899) (xy 275.216859 -395.675104) (xy 275.136576 -395.690013)
			(xy 275.055264 -395.6975) (xy 275.014436 -395.697964) (xy 274.973213 -395.69746) (xy 274.891121 -395.689828)
			(xy 274.810087 -395.674636) (xy 274.730806 -395.652015) (xy 274.653956 -395.622157) (xy 274.580198 -395.585319)
			(xy 274.510163 -395.541817) (xy 274.444452 -395.492024) (xy 274.413726 -395.464538) (xy 274.406494 -395.458451)
			(xy 274.388881 -395.451625) (xy 274.369991 -395.451625) (xy 274.352378 -395.458451) (xy 274.345146 -395.464538)
			(xy 274.314435 -395.492044) (xy 274.248729 -395.54185) (xy 274.178695 -395.585362) (xy 274.104936 -395.622207)
			(xy 274.028083 -395.652068) (xy 273.948797 -395.67469) (xy 273.867758 -395.689878) (xy 273.785661 -395.697501)
			(xy 273.744436 -395.697964) (xy 273.702084 -395.697566) (xy 273.617762 -395.689517) (xy 273.534587 -395.673489)
			(xy 273.453313 -395.649628) (xy 273.374675 -395.618149) (xy 273.299385 -395.579337) (xy 273.228125 -395.533544)
			(xy 273.161542 -395.481184) (xy 273.100237 -395.422733) (xy 273.044766 -395.358718) (xy 272.995631 -395.28972)
			(xy 272.953277 -395.216364) (xy 272.918089 -395.139314) (xy 272.890384 -395.059269) (xy 272.870414 -394.976952)
			(xy 272.858359 -394.893109) (xy 272.854328 -394.8085) (xy 270.221496 -394.8085) (xy 270.221496 -394.808506)
			(xy 270.213964 -394.859873) (xy 270.199053 -394.909601) (xy 270.177077 -394.956636) (xy 270.148504 -394.999982)
			(xy 270.113939 -395.038718) (xy 270.074115 -395.072025) (xy 270.029876 -395.099194) (xy 269.98216 -395.119651)
			(xy 269.93198 -395.132962) (xy 269.906242 -395.13637) (xy 269.890753 -395.174148) (xy 269.853824 -395.246974)
			(xy 269.810375 -395.316109) (xy 269.760773 -395.38097) (xy 269.705435 -395.441012) (xy 269.644826 -395.49573)
			(xy 269.579457 -395.544662) (xy 269.509879 -395.587396) (xy 269.436676 -395.623574) (xy 269.360466 -395.652889)
			(xy 269.28189 -395.675096) (xy 269.201609 -395.690008) (xy 269.120299 -395.697499) (xy 269.079472 -395.697964)
			(xy 269.038248 -395.6975) (xy 268.956155 -395.689862) (xy 268.87512 -395.674665) (xy 268.795838 -395.652037)
			(xy 268.718989 -395.622174) (xy 268.645231 -395.585331) (xy 268.575197 -395.541824) (xy 268.509487 -395.492026)
			(xy 268.478762 -395.464538) (xy 268.47153 -395.458451) (xy 268.453917 -395.451625) (xy 268.435027 -395.451625)
			(xy 268.417414 -395.458451) (xy 268.410182 -395.464538) (xy 268.379456 -395.492026) (xy 268.313752 -395.541834)
			(xy 268.243721 -395.585348) (xy 268.169964 -395.622194) (xy 268.093113 -395.652058) (xy 268.013829 -395.674682)
			(xy 267.932792 -395.689873) (xy 267.850696 -395.6975) (xy 267.809472 -395.697964) (xy 267.767122 -395.697547)
			(xy 267.682807 -395.689493) (xy 267.599638 -395.673462) (xy 267.51837 -395.649597) (xy 267.439739 -395.618115)
			(xy 267.364456 -395.579302) (xy 267.293203 -395.533509) (xy 267.226625 -395.48115) (xy 267.165326 -395.422699)
			(xy 267.109861 -395.358687) (xy 267.060731 -395.289692) (xy 267.018382 -395.21634) (xy 266.983198 -395.139294)
			(xy 266.955496 -395.059253) (xy 266.935527 -394.976941) (xy 266.923474 -394.893104) (xy 266.919443 -394.8085)
			(xy 264.336432 -394.8085) (xy 264.334396 -394.835661) (xy 264.322533 -394.887635) (xy 264.303057 -394.93726)
			(xy 264.276401 -394.983428) (xy 264.243162 -395.025107) (xy 264.204083 -395.061367) (xy 264.160035 -395.091397)
			(xy 264.112004 -395.114526) (xy 264.061062 -395.130239) (xy 264.008347 -395.138183) (xy 263.981692 -395.138656)
			(xy 263.970516 -395.138402) (xy 263.954928 -395.17605) (xy 263.917915 -395.248648) (xy 263.874417 -395.317555)
			(xy 263.824797 -395.382194) (xy 263.769471 -395.442023) (xy 263.708905 -395.496539) (xy 263.643605 -395.545287)
			(xy 263.57412 -395.587856) (xy 263.501032 -395.623891) (xy 263.424953 -395.653088) (xy 263.346523 -395.675203)
			(xy 263.266399 -395.69005) (xy 263.185252 -395.697505) (xy 263.144508 -395.697964) (xy 263.103285 -395.697477)
			(xy 263.021192 -395.689843) (xy 262.940158 -395.674649) (xy 262.860876 -395.652025) (xy 262.784027 -395.622164)
			(xy 262.710269 -395.585324) (xy 262.640234 -395.54182) (xy 262.574524 -395.492025) (xy 262.543798 -395.464538)
			(xy 262.536566 -395.458451) (xy 262.518953 -395.451625) (xy 262.500063 -395.451625) (xy 262.48245 -395.458451)
			(xy 262.475218 -395.464538) (xy 262.444477 -395.492009) (xy 262.378775 -395.541818) (xy 262.308747 -395.585333)
			(xy 262.234992 -395.622182) (xy 262.158144 -395.652048) (xy 262.078861 -395.674675) (xy 261.997826 -395.689868)
			(xy 261.915732 -395.697498) (xy 261.874508 -395.697964) (xy 261.832156 -395.697564) (xy 261.747837 -395.689513)
			(xy 261.664664 -395.673484) (xy 261.583392 -395.649621) (xy 261.504756 -395.61814) (xy 261.429469 -395.579328)
			(xy 261.358212 -395.533534) (xy 261.29163 -395.481174) (xy 261.230327 -395.422723) (xy 261.174858 -395.358709)
			(xy 261.125725 -395.289712) (xy 261.083374 -395.216357) (xy 261.048186 -395.139308) (xy 261.020483 -395.059264)
			(xy 261.000513 -394.976948) (xy 260.988458 -394.893107) (xy 260.984428 -394.8085) (xy 258.421708 -394.8085)
			(xy 258.419673 -394.835652) (xy 258.407813 -394.887617) (xy 258.388341 -394.937235) (xy 258.361693 -394.983396)
			(xy 258.328463 -395.025071) (xy 258.289393 -395.061327) (xy 258.245356 -395.091357) (xy 258.197335 -395.114488)
			(xy 258.146403 -395.130204) (xy 258.093699 -395.138155) (xy 258.067048 -395.138656) (xy 258.03606 -395.137386)
			(xy 258.020546 -395.175113) (xy 257.983557 -395.247826) (xy 257.940067 -395.316846) (xy 257.89044 -395.381595)
			(xy 257.835094 -395.441529) (xy 257.774494 -395.496144) (xy 257.709147 -395.544982) (xy 257.639604 -395.587632)
			(xy 257.566448 -395.623736) (xy 257.490294 -395.65299) (xy 257.411782 -395.67515) (xy 257.331571 -395.690029)
			(xy 257.250334 -395.697502) (xy 257.209544 -395.697964) (xy 257.168321 -395.697455) (xy 257.08623 -395.689824)
			(xy 257.005196 -395.674633) (xy 256.925914 -395.652012) (xy 256.849065 -395.622155) (xy 256.775306 -395.585317)
			(xy 256.705271 -395.541816) (xy 256.63956 -395.492023) (xy 256.608834 -395.464538) (xy 256.601602 -395.458451)
			(xy 256.583989 -395.451625) (xy 256.565099 -395.451625) (xy 256.547486 -395.458451) (xy 256.540254 -395.464538)
			(xy 256.50954 -395.49204) (xy 256.443834 -395.541846) (xy 256.373801 -395.585359) (xy 256.300042 -395.622204)
			(xy 256.22319 -395.652066) (xy 256.143904 -395.674688) (xy 256.062865 -395.689877) (xy 255.980769 -395.697501)
			(xy 255.939544 -395.697964) (xy 255.897191 -395.697566) (xy 255.812869 -395.689518) (xy 255.729694 -395.673491)
			(xy 255.648419 -395.64963) (xy 255.56978 -395.618151) (xy 255.494489 -395.57934) (xy 255.423229 -395.533547)
			(xy 255.356645 -395.481187) (xy 255.295339 -395.422735) (xy 255.239868 -395.358721) (xy 255.190732 -395.289723)
			(xy 255.148379 -395.216366) (xy 255.11319 -395.139316) (xy 255.085484 -395.05927) (xy 255.065514 -394.976952)
			(xy 255.053459 -394.893109) (xy 255.049428 -394.8085) (xy 252.441992 -394.8085) (xy 252.441968 -394.809821)
			(xy 252.433657 -394.863731) (xy 252.417221 -394.915743) (xy 252.393046 -394.964639) (xy 252.361695 -395.009276)
			(xy 252.323904 -395.04861) (xy 252.280556 -395.081721) (xy 252.232666 -395.107832) (xy 252.181353 -395.126335)
			(xy 252.127819 -395.136795) (xy 252.100588 -395.138402) (xy 252.085024 -395.17606) (xy 252.048009 -395.248659)
			(xy 252.004509 -395.317566) (xy 251.954887 -395.382206) (xy 251.89956 -395.442034) (xy 251.838991 -395.496551)
			(xy 251.773689 -395.545298) (xy 251.704202 -395.587866) (xy 251.631111 -395.623899) (xy 251.555031 -395.653095)
			(xy 251.476599 -395.675208) (xy 251.396473 -395.690054) (xy 251.315325 -395.697507) (xy 251.27458 -395.697964)
			(xy 251.233356 -395.697495) (xy 251.151263 -395.689858) (xy 251.070228 -395.674661) (xy 250.990947 -395.652035)
			(xy 250.914097 -395.622172) (xy 250.840339 -395.58533) (xy 250.770305 -395.541823) (xy 250.704595 -395.492026)
			(xy 250.67387 -395.464538) (xy 250.666638 -395.458451) (xy 250.649025 -395.451625) (xy 250.630135 -395.451625)
			(xy 250.612522 -395.458451) (xy 250.60529 -395.464538) (xy 250.574561 -395.492023) (xy 250.508857 -395.54183)
			(xy 250.438827 -395.585344) (xy 250.36507 -395.622192) (xy 250.28822 -395.652056) (xy 250.208936 -395.67468)
			(xy 250.127899 -395.689872) (xy 250.045804 -395.697499) (xy 250.00458 -395.697964) (xy 249.96223 -395.697547)
			(xy 249.877914 -395.689494) (xy 249.794745 -395.673463) (xy 249.713476 -395.649599) (xy 249.634844 -395.618118)
			(xy 249.55956 -395.579305) (xy 249.488307 -395.533512) (xy 249.421729 -395.481153) (xy 249.360429 -395.422702)
			(xy 249.304963 -395.35869) (xy 249.255833 -395.289695) (xy 249.213483 -395.216342) (xy 249.178298 -395.139296)
			(xy 249.150596 -395.059254) (xy 249.130628 -394.976942) (xy 249.118574 -394.893104) (xy 249.114543 -394.8085)
			(xy 246.481601 -394.8085) (xy 246.481601 -394.808504) (xy 246.474071 -394.859867) (xy 246.459161 -394.909593)
			(xy 246.437189 -394.956626) (xy 246.40862 -394.999969) (xy 246.374059 -395.038705) (xy 246.334241 -395.072012)
			(xy 246.290007 -395.099183) (xy 246.242297 -395.119644) (xy 246.192121 -395.132959) (xy 246.166386 -395.13637)
			(xy 246.15086 -395.174132) (xy 246.113933 -395.246957) (xy 246.070488 -395.316091) (xy 246.020888 -395.380952)
			(xy 245.965553 -395.440994) (xy 245.904948 -395.495712) (xy 245.839582 -395.544645) (xy 245.770007 -395.587381)
			(xy 245.696808 -395.62356) (xy 245.620601 -395.652878) (xy 245.542028 -395.675088) (xy 245.461749 -395.690002)
			(xy 245.380442 -395.697497) (xy 245.339616 -395.697964) (xy 245.298393 -395.697472) (xy 245.216301 -395.689839)
			(xy 245.135266 -395.674645) (xy 245.055985 -395.652022) (xy 244.979135 -395.622162) (xy 244.905377 -395.585323)
			(xy 244.835342 -395.541819) (xy 244.769632 -395.492024) (xy 244.738906 -395.464538) (xy 244.731674 -395.458451)
			(xy 244.714061 -395.451625) (xy 244.695171 -395.451625) (xy 244.677558 -395.458451) (xy 244.670326 -395.464538)
			(xy 244.639624 -395.492053) (xy 244.573916 -395.541859) (xy 244.503881 -395.58537) (xy 244.43012 -395.622214)
			(xy 244.353266 -395.652074) (xy 244.273979 -395.674694) (xy 244.192939 -395.68988) (xy 244.110841 -395.697502)
			(xy 244.069616 -395.697964) (xy 244.027264 -395.697565) (xy 243.942944 -395.689514) (xy 243.859771 -395.673485)
			(xy 243.778498 -395.649623) (xy 243.699861 -395.618143) (xy 243.624573 -395.57933) (xy 243.553315 -395.533537)
			(xy 243.486733 -395.481177) (xy 243.42543 -395.422726) (xy 243.36996 -395.358711) (xy 243.320827 -395.289714)
			(xy 243.278475 -395.216359) (xy 243.243287 -395.13931) (xy 243.215583 -395.059265) (xy 243.195613 -394.976949)
			(xy 243.183558 -394.893108) (xy 243.179528 -394.8085) (xy 185.2549 -394.8085) (xy 185.2549 -396.90548)
			(xy 185.92546 -397.57604) (xy 185.92546 -399.82394) (xy 186.17438 -400.07286) (xy 192.69456 -400.07286)
			(xy 194.37604 -398.39138) (xy 196.558916 -398.39138) (xy 198.852536 -400.685) (xy 202.66914 -400.685)
			(xy 204.37602 -398.97812) (xy 207.30718 -398.97812) (xy 209.00898 -400.67992) (xy 213.25586 -400.67992)
			(xy 215.05418 -398.8816) (xy 217.932 -398.8816) (xy 219.73286 -400.68246) (xy 223.97466 -400.68246)
			(xy 225.61804 -399.03908) (xy 228.775514 -399.03908) (xy 230.423974 -400.68754) (xy 238.64824 -400.68754)
		)
		(stroke
			(width 0)
			(type solid)
		)
		(fill yes)
		(layer "In2.Cu")
		(net "P12V_AUX")
	)
	(gr_poly
		(pts
			(xy 315.87948 -57.11952) (xy 315.893615 -57.119103) (xy 315.920823 -57.111433) (xy 315.944883 -57.096593)
			(xy 315.963948 -57.075722) (xy 315.976555 -57.050421) (xy 315.981737 -57.022633) (xy 315.980826 -57.008522)
			(xy 315.979048 -56.972708) (xy 315.979533 -56.945455) (xy 315.987289 -56.891504) (xy 316.002643 -56.839206)
			(xy 316.025283 -56.789625) (xy 316.054748 -56.74377) (xy 316.090439 -56.702576) (xy 316.131629 -56.666879)
			(xy 316.177479 -56.637408) (xy 316.227057 -56.614761) (xy 316.279353 -56.5994) (xy 316.333303 -56.591637)
			(xy 316.360556 -56.5912) (xy 316.388104 -56.591688) (xy 316.442625 -56.599619) (xy 316.495439 -56.615309)
			(xy 316.545448 -56.638431) (xy 316.591611 -56.668504) (xy 316.63297 -56.704904) (xy 316.668664 -56.746873)
			(xy 316.697952 -56.793539) (xy 316.709552 -56.81853) (xy 316.715658 -56.831246) (xy 316.733663 -56.852948)
			(xy 316.756922 -56.86889) (xy 316.783657 -56.877854) (xy 316.811825 -56.879154) (xy 316.839273 -56.872692)
			(xy 316.863902 -56.858961) (xy 316.874144 -56.849264) (xy 316.907672 -56.815482) (xy 316.907672 -42.293286)
			(xy 316.907253 -42.2798) (xy 316.900182 -42.25377) (xy 316.88654 -42.230502) (xy 316.867278 -42.211621)
			(xy 316.843742 -42.198446) (xy 316.817576 -42.191898) (xy 316.790609 -42.192433) (xy 316.764724 -42.200015)
			(xy 316.752986 -42.206672) (xy 316.730342 -42.220083) (xy 316.682156 -42.241243) (xy 316.631524 -42.255594)
			(xy 316.579401 -42.262865) (xy 316.553088 -42.263314) (xy 316.533512 -42.263048) (xy 316.494572 -42.258975)
			(xy 316.475364 -42.255186) (xy 316.4618 -42.252806) (xy 316.434328 -42.254556) (xy 316.408321 -42.263578)
			(xy 316.385667 -42.279216) (xy 316.368011 -42.300336) (xy 316.356636 -42.325403) (xy 316.352366 -42.352597)
			(xy 316.355513 -42.379944) (xy 316.360302 -42.392854) (xy 316.369057 -42.415579) (xy 316.381378 -42.462695)
			(xy 316.387592 -42.510998) (xy 316.387988 -42.535348) (xy 316.387502 -42.562599) (xy 316.379746 -42.616547)
			(xy 316.364391 -42.668842) (xy 316.341749 -42.718419) (xy 316.312283 -42.764269) (xy 316.276592 -42.80546)
			(xy 316.235401 -42.841151) (xy 316.189551 -42.870617) (xy 316.139974 -42.893259) (xy 316.087679 -42.908614)
			(xy 316.033731 -42.91637) (xy 315.979229 -42.91637) (xy 315.925281 -42.908614) (xy 315.872986 -42.893259)
			(xy 315.823409 -42.870617) (xy 315.777559 -42.841151) (xy 315.736368 -42.80546) (xy 315.700677 -42.764269)
			(xy 315.671211 -42.718419) (xy 315.648569 -42.668842) (xy 315.633214 -42.616547) (xy 315.625458 -42.562599)
			(xy 315.624972 -42.535348) (xy 315.625045 -42.524274) (xy 315.626317 -42.502162) (xy 315.627512 -42.491152)
			(xy 315.628741 -42.475598) (xy 315.622805 -42.444983) (xy 315.607906 -42.417587) (xy 315.585433 -42.395965)
			(xy 315.557483 -42.382135) (xy 315.542168 -42.379138) (xy 315.515477 -42.374565) (xy 315.463652 -42.358868)
			(xy 315.414567 -42.335999) (xy 315.369209 -42.306418) (xy 315.328491 -42.27072) (xy 315.29323 -42.229622)
			(xy 315.264137 -42.183951) (xy 315.241794 -42.134624) (xy 315.226653 -42.082633) (xy 315.219016 -42.029024)
			(xy 315.218572 -42.001948) (xy 315.219058 -41.974697) (xy 315.226814 -41.920749) (xy 315.242169 -41.868454)
			(xy 315.264811 -41.818877) (xy 315.294277 -41.773027) (xy 315.329968 -41.731836) (xy 315.371159 -41.696145)
			(xy 315.417009 -41.666679) (xy 315.466586 -41.644037) (xy 315.518881 -41.628682) (xy 315.572829 -41.620926)
			(xy 315.627331 -41.620926) (xy 315.681279 -41.628682) (xy 315.733574 -41.644037) (xy 315.783151 -41.666679)
			(xy 315.829001 -41.696145) (xy 315.870192 -41.731836) (xy 315.905883 -41.773027) (xy 315.935349 -41.818877)
			(xy 315.957991 -41.868454) (xy 315.973346 -41.920749) (xy 315.981102 -41.974697) (xy 315.981588 -42.001948)
			(xy 315.981515 -42.013022) (xy 315.980244 -42.035134) (xy 315.979048 -42.046144) (xy 315.977819 -42.0617)
			(xy 315.983753 -42.09232) (xy 315.99865 -42.119722) (xy 316.021121 -42.141351) (xy 316.04907 -42.155193)
			(xy 316.064392 -42.158158) (xy 316.084204 -42.161968) (xy 316.097768 -42.164354) (xy 316.125242 -42.162611)
			(xy 316.151252 -42.153593) (xy 316.173908 -42.137955) (xy 316.191563 -42.116833) (xy 316.202935 -42.091762)
			(xy 316.207196 -42.064565) (xy 316.204038 -42.037218) (xy 316.199266 -42.0243) (xy 316.190506 -42.001576)
			(xy 316.178177 -41.95446) (xy 316.171954 -41.906157) (xy 316.17158 -41.881806) (xy 316.172065 -41.854554)
			(xy 316.179821 -41.800605) (xy 316.195176 -41.748309) (xy 316.217816 -41.69873) (xy 316.247282 -41.652878)
			(xy 316.282974 -41.611686) (xy 316.324164 -41.575993) (xy 316.370014 -41.546525) (xy 316.419592 -41.523882)
			(xy 316.471888 -41.508525) (xy 316.525836 -41.500767) (xy 316.553088 -41.500298) (xy 316.579404 -41.500735)
			(xy 316.631535 -41.507972) (xy 316.682172 -41.522322) (xy 316.730349 -41.543513) (xy 316.752986 -41.55694)
			(xy 316.764707 -41.563635) (xy 316.790604 -41.571219) (xy 316.817583 -41.571755) (xy 316.84376 -41.565203)
			(xy 316.867306 -41.552023) (xy 316.886577 -41.533135) (xy 316.900228 -41.509858) (xy 316.907303 -41.483818)
			(xy 316.907672 -41.470326) (xy 316.907672 -38.316916) (xy 315.754766 -37.163756) (xy 315.744422 -37.154066)
			(xy 315.719658 -37.140303) (xy 315.692067 -37.133871) (xy 315.663769 -37.135267) (xy 315.636944 -37.144382)
			(xy 315.613654 -37.160515) (xy 315.595693 -37.182425) (xy 315.589666 -37.195252) (xy 315.578204 -37.220522)
			(xy 315.549047 -37.267729) (xy 315.513357 -37.310214) (xy 315.471887 -37.347077) (xy 315.425512 -37.377541)
			(xy 315.375211 -37.400962) (xy 315.322048 -37.416847) (xy 315.267143 -37.42486) (xy 315.2394 -37.425376)
			(xy 315.212148 -37.424913) (xy 315.158199 -37.417155) (xy 315.105903 -37.401799) (xy 315.056325 -37.379156)
			(xy 315.010474 -37.349688) (xy 314.969284 -37.313994) (xy 314.933593 -37.272801) (xy 314.904128 -37.226947)
			(xy 314.88149 -37.177367) (xy 314.866138 -37.12507) (xy 314.858385 -37.07112) (xy 314.857892 -37.043868)
			(xy 314.858392 -37.016126) (xy 314.866429 -36.961228) (xy 314.88233 -36.908072) (xy 314.905759 -36.857778)
			(xy 314.936223 -36.811406) (xy 314.97308 -36.769933) (xy 315.015552 -36.734233) (xy 315.062746 -36.705058)
			(xy 315.088016 -36.693602) (xy 315.10083 -36.687546) (xy 315.122736 -36.669582) (xy 315.138868 -36.646294)
			(xy 315.147988 -36.619472) (xy 315.149395 -36.591177) (xy 315.142979 -36.563583) (xy 315.129236 -36.53881)
			(xy 315.119512 -36.528502) (xy 313.50839 -34.91738) (xy 313.497722 -34.91357) (xy 313.470274 -34.903239)
			(xy 313.418675 -34.875366) (xy 313.371947 -34.839927) (xy 313.331191 -34.797757) (xy 313.297366 -34.749848)
			(xy 313.271268 -34.697329) (xy 313.253512 -34.641435) (xy 313.244516 -34.583483) (xy 313.243976 -34.55416)
			(xy 313.244356 -34.530868) (xy 313.250088 -34.484638) (xy 313.255406 -34.461958) (xy 313.256676 -34.455862)
			(xy 313.256676 -25.978612) (xy 311.85866 -24.580342) (xy 304.853594 -24.580342) (xy 303.89957 -25.534366)
			(xy 303.89957 -27.6606) (xy 305.637182 -27.6606) (xy 305.641253 -27.604978) (xy 305.653379 -27.550541)
			(xy 305.673302 -27.49845) (xy 305.700598 -27.449815) (xy 305.734684 -27.405672) (xy 305.774833 -27.366963)
			(xy 305.820191 -27.334512) (xy 305.869791 -27.309011) (xy 305.922575 -27.291004) (xy 305.977418 -27.280874)
			(xy 306.033152 -27.278837) (xy 306.088589 -27.284937) (xy 306.142546 -27.299043) (xy 306.193875 -27.320855)
			(xy 306.241481 -27.349909) (xy 306.284349 -27.385584) (xy 306.321566 -27.427121) (xy 306.352339 -27.473634)
			(xy 306.376011 -27.524131) (xy 306.392079 -27.577538) (xy 306.400199 -27.632714) (xy 306.400708 -27.6606)
			(xy 306.400199 -27.688486) (xy 306.392079 -27.743662) (xy 306.376011 -27.797069) (xy 306.352339 -27.847566)
			(xy 306.321566 -27.894079) (xy 306.284349 -27.935616) (xy 306.241481 -27.971291) (xy 306.193875 -28.000345)
			(xy 306.142546 -28.022157) (xy 306.088589 -28.036263) (xy 306.033152 -28.042363) (xy 305.977418 -28.040326)
			(xy 305.922575 -28.030196) (xy 305.869791 -28.012189) (xy 305.820191 -27.986688) (xy 305.774833 -27.954237)
			(xy 305.734684 -27.915528) (xy 305.700598 -27.871385) (xy 305.673302 -27.82275) (xy 305.653379 -27.770659)
			(xy 305.641253 -27.716222) (xy 305.637182 -27.6606) (xy 303.89957 -27.6606) (xy 303.89957 -28.095448)
			(xy 304.376328 -28.572206) (xy 308.373526 -28.572206) (xy 308.388053 -28.571686) (xy 308.415931 -28.563497)
			(xy 308.440374 -28.547789) (xy 308.459404 -28.525833) (xy 308.471481 -28.499407) (xy 308.475628 -28.47065)
			(xy 308.471509 -28.441888) (xy 308.465982 -28.428442) (xy 308.455158 -28.40348) (xy 308.439888 -28.35126)
			(xy 308.432174 -28.297403) (xy 308.431692 -28.2702) (xy 308.432178 -28.242949) (xy 308.439934 -28.189001)
			(xy 308.455289 -28.136706) (xy 308.477931 -28.087129) (xy 308.507397 -28.041279) (xy 308.543088 -28.000088)
			(xy 308.584279 -27.964397) (xy 308.630129 -27.934931) (xy 308.679706 -27.912289) (xy 308.732001 -27.896934)
			(xy 308.785949 -27.889178) (xy 308.840451 -27.889178) (xy 308.894399 -27.896934) (xy 308.946694 -27.912289)
			(xy 308.996271 -27.934931) (xy 309.042121 -27.964397) (xy 309.083312 -28.000088) (xy 309.119003 -28.041279)
			(xy 309.148469 -28.087129) (xy 309.171111 -28.136706) (xy 309.186466 -28.189001) (xy 309.194222 -28.242949)
			(xy 309.194568 -28.262331) (xy 310.388025 -28.262331) (xy 310.388027 -28.207837) (xy 310.395785 -28.153898)
			(xy 310.411139 -28.101612) (xy 310.433778 -28.052043) (xy 310.463241 -28.0062) (xy 310.498928 -27.965017)
			(xy 310.540113 -27.929332) (xy 310.585957 -27.899871) (xy 310.635527 -27.877234) (xy 310.687813 -27.861881)
			(xy 310.741753 -27.854126) (xy 310.769 -27.85364) (xy 310.785466 -27.853794) (xy 310.818278 -27.856593)
			(xy 310.834532 -27.859228) (xy 310.848299 -27.86123) (xy 310.875968 -27.858388) (xy 310.901843 -27.848183)
			(xy 310.924003 -27.831373) (xy 310.940804 -27.809206) (xy 310.950998 -27.783327) (xy 310.953828 -27.755657)
			(xy 310.95188 -27.74188) (xy 310.949241 -27.725626) (xy 310.946443 -27.692814) (xy 310.946292 -27.676348)
			(xy 310.946704 -27.649091) (xy 310.954455 -27.595131) (xy 310.969807 -27.542823) (xy 310.992448 -27.493233)
			(xy 311.021915 -27.447369) (xy 311.05761 -27.406167) (xy 311.098805 -27.370463) (xy 311.144662 -27.340986)
			(xy 311.194248 -27.318335) (xy 311.246552 -27.302972) (xy 311.300511 -27.295209) (xy 311.355025 -27.295205)
			(xy 311.408985 -27.302959) (xy 311.461292 -27.318313) (xy 311.510881 -27.340955) (xy 311.556744 -27.370425)
			(xy 311.597945 -27.406121) (xy 311.633646 -27.447318) (xy 311.663122 -27.493176) (xy 311.68577 -27.542763)
			(xy 311.701131 -27.595068) (xy 311.708892 -27.649027) (xy 311.708894 -27.703541) (xy 311.701138 -27.757501)
			(xy 311.685781 -27.809807) (xy 311.663137 -27.859395) (xy 311.633666 -27.905256) (xy 311.597967 -27.946456)
			(xy 311.556769 -27.982156) (xy 311.510909 -28.011629) (xy 311.461322 -28.034276) (xy 311.409016 -28.049635)
			(xy 311.355057 -28.057393) (xy 311.3278 -28.057856) (xy 311.311334 -28.057702) (xy 311.278522 -28.054903)
			(xy 311.262268 -28.052268) (xy 311.2485 -28.050271) (xy 311.220832 -28.053113) (xy 311.194958 -28.063317)
			(xy 311.172798 -28.080126) (xy 311.155998 -28.102292) (xy 311.145804 -28.12817) (xy 311.142972 -28.15584)
			(xy 311.14492 -28.169616) (xy 311.147559 -28.18587) (xy 311.150357 -28.218682) (xy 311.150508 -28.235148)
			(xy 311.14997 -28.262395) (xy 311.142209 -28.316333) (xy 311.12685 -28.368618) (xy 311.104206 -28.418185)
			(xy 311.074739 -28.464026) (xy 311.061772 -28.478988) (xy 311.708798 -28.478988) (xy 311.712869 -28.423366)
			(xy 311.724995 -28.368929) (xy 311.744918 -28.316838) (xy 311.772214 -28.268203) (xy 311.8063 -28.22406)
			(xy 311.846449 -28.185351) (xy 311.891807 -28.1529) (xy 311.941407 -28.127399) (xy 311.994191 -28.109392)
			(xy 312.049034 -28.099262) (xy 312.104768 -28.097225) (xy 312.160205 -28.103325) (xy 312.214162 -28.117431)
			(xy 312.265491 -28.139243) (xy 312.313097 -28.168297) (xy 312.355965 -28.203972) (xy 312.393182 -28.245509)
			(xy 312.423955 -28.292022) (xy 312.447627 -28.342519) (xy 312.463695 -28.395926) (xy 312.471815 -28.451102)
			(xy 312.472324 -28.478988) (xy 312.471815 -28.506874) (xy 312.463695 -28.56205) (xy 312.447627 -28.615457)
			(xy 312.423955 -28.665954) (xy 312.393182 -28.712467) (xy 312.355965 -28.754004) (xy 312.313097 -28.789679)
			(xy 312.265491 -28.818733) (xy 312.214162 -28.840545) (xy 312.160205 -28.854651) (xy 312.104768 -28.860751)
			(xy 312.049034 -28.858714) (xy 311.994191 -28.848584) (xy 311.941407 -28.830577) (xy 311.891807 -28.805076)
			(xy 311.846449 -28.772625) (xy 311.8063 -28.733916) (xy 311.772214 -28.689773) (xy 311.744918 -28.641138)
			(xy 311.724995 -28.589047) (xy 311.712869 -28.53461) (xy 311.708798 -28.478988) (xy 311.061772 -28.478988)
			(xy 311.039049 -28.505206) (xy 310.997861 -28.540887) (xy 310.952015 -28.570345) (xy 310.902443 -28.592978)
			(xy 310.850155 -28.608326) (xy 310.796215 -28.616076) (xy 310.741721 -28.616072) (xy 310.687782 -28.608312)
			(xy 310.635497 -28.592955) (xy 310.585929 -28.570314) (xy 310.540087 -28.540849) (xy 310.498906 -28.50516)
			(xy 310.463222 -28.463974) (xy 310.433763 -28.418129) (xy 310.411128 -28.368558) (xy 310.395778 -28.316271)
			(xy 310.388025 -28.262331) (xy 309.194568 -28.262331) (xy 309.194708 -28.2702) (xy 309.194278 -28.296045)
			(xy 309.187297 -28.347261) (xy 309.173463 -28.397065) (xy 309.153029 -28.444545) (xy 309.126371 -28.48883)
			(xy 309.093975 -28.529108) (xy 309.056437 -28.564643) (xy 309.035704 -28.58008) (xy 309.024902 -28.588363)
			(xy 309.00777 -28.609504) (xy 308.996834 -28.634421) (xy 308.992874 -28.661342) (xy 308.996169 -28.688353)
			(xy 309.006487 -28.713532) (xy 309.023093 -28.735089) (xy 309.033672 -28.743656) (xy 309.053738 -28.75933)
			(xy 309.089938 -28.795139) (xy 309.121052 -28.835445) (xy 309.146526 -28.879533) (xy 309.156608 -28.902914)
			(xy 309.160418 -28.912312) (xy 309.171848 -28.923742) (xy 309.171848 -28.947618) (xy 309.173372 -28.953714)
			(xy 309.178943 -28.976938) (xy 309.184927 -29.024322) (xy 309.18531 -29.048202) (xy 309.184923 -29.072082)
			(xy 309.178937 -29.119465) (xy 309.173372 -29.14269) (xy 309.171848 -29.148786) (xy 309.171848 -31.7754)
			(xy 311.910982 -31.7754) (xy 311.915053 -31.719778) (xy 311.927179 -31.665341) (xy 311.947102 -31.61325)
			(xy 311.974398 -31.564615) (xy 312.008484 -31.520472) (xy 312.048633 -31.481763) (xy 312.093991 -31.449312)
			(xy 312.143591 -31.423811) (xy 312.196375 -31.405804) (xy 312.251218 -31.395674) (xy 312.306952 -31.393637)
			(xy 312.362389 -31.399737) (xy 312.416346 -31.413843) (xy 312.467675 -31.435655) (xy 312.515281 -31.464709)
			(xy 312.558149 -31.500384) (xy 312.595366 -31.541921) (xy 312.626139 -31.588434) (xy 312.649811 -31.638931)
			(xy 312.665879 -31.692338) (xy 312.673999 -31.747514) (xy 312.674508 -31.7754) (xy 312.673999 -31.803286)
			(xy 312.665879 -31.858462) (xy 312.649811 -31.911869) (xy 312.626139 -31.962366) (xy 312.595366 -32.008879)
			(xy 312.558149 -32.050416) (xy 312.515281 -32.086091) (xy 312.467675 -32.115145) (xy 312.416346 -32.136957)
			(xy 312.362389 -32.151063) (xy 312.306952 -32.157163) (xy 312.251218 -32.155126) (xy 312.196375 -32.144996)
			(xy 312.143591 -32.126989) (xy 312.093991 -32.101488) (xy 312.048633 -32.069037) (xy 312.008484 -32.030328)
			(xy 311.974398 -31.986185) (xy 311.947102 -31.93755) (xy 311.927179 -31.885459) (xy 311.915053 -31.831022)
			(xy 311.910982 -31.7754) (xy 309.171848 -31.7754) (xy 309.171848 -33.1978) (xy 310.285892 -33.1978)
			(xy 310.286368 -33.171422) (xy 310.29362 -33.119166) (xy 310.308001 -33.068407) (xy 310.329235 -33.020112)
			(xy 310.356918 -32.975202) (xy 310.390523 -32.934533) (xy 310.429409 -32.89888) (xy 310.472835 -32.868922)
			(xy 310.496204 -32.856678) (xy 310.508559 -32.849974) (xy 310.52928 -32.830995) (xy 310.544035 -32.807082)
			(xy 310.551704 -32.78005) (xy 310.551704 -32.75195) (xy 310.544035 -32.724918) (xy 310.52928 -32.701005)
			(xy 310.508559 -32.682026) (xy 310.496204 -32.675322) (xy 310.472835 -32.663078) (xy 310.42941 -32.633117)
			(xy 310.390524 -32.597462) (xy 310.356918 -32.556793) (xy 310.32923 -32.511885) (xy 310.30799 -32.463592)
			(xy 310.293601 -32.412834) (xy 310.286337 -32.360579) (xy 310.285892 -32.3342) (xy 310.286378 -32.306949)
			(xy 310.294134 -32.253001) (xy 310.309489 -32.200706) (xy 310.332131 -32.151129) (xy 310.361597 -32.105279)
			(xy 310.397288 -32.064088) (xy 310.438479 -32.028397) (xy 310.484329 -31.998931) (xy 310.533906 -31.976289)
			(xy 310.586201 -31.960934) (xy 310.640149 -31.953178) (xy 310.694651 -31.953178) (xy 310.748599 -31.960934)
			(xy 310.800894 -31.976289) (xy 310.850471 -31.998931) (xy 310.896321 -32.028397) (xy 310.937512 -32.064088)
			(xy 310.973203 -32.105279) (xy 311.002669 -32.151129) (xy 311.025311 -32.200706) (xy 311.040666 -32.253001)
			(xy 311.048422 -32.306949) (xy 311.048908 -32.3342) (xy 311.048432 -32.360578) (xy 311.04118 -32.412834)
			(xy 311.026799 -32.463593) (xy 311.005565 -32.511888) (xy 310.977882 -32.556798) (xy 310.944277 -32.597467)
			(xy 310.905391 -32.63312) (xy 310.861965 -32.663078) (xy 310.838596 -32.675322) (xy 310.826241 -32.682026)
			(xy 310.80552 -32.701005) (xy 310.790765 -32.724918) (xy 310.783096 -32.75195) (xy 310.783096 -32.78005)
			(xy 310.790765 -32.807082) (xy 310.80552 -32.830995) (xy 310.826241 -32.849974) (xy 310.838596 -32.856678)
			(xy 310.861965 -32.868922) (xy 310.90539 -32.898883) (xy 310.944276 -32.934538) (xy 310.977882 -32.975207)
			(xy 311.00557 -33.020115) (xy 311.02681 -33.068408) (xy 311.041199 -33.119166) (xy 311.048463 -33.171421)
			(xy 311.048908 -33.1978) (xy 311.048422 -33.225051) (xy 311.040666 -33.278999) (xy 311.025311 -33.331294)
			(xy 311.002669 -33.380871) (xy 310.973203 -33.426721) (xy 310.937512 -33.467912) (xy 310.896321 -33.503603)
			(xy 310.850471 -33.533069) (xy 310.800894 -33.555711) (xy 310.748599 -33.571066) (xy 310.694651 -33.578822)
			(xy 310.640149 -33.578822) (xy 310.586201 -33.571066) (xy 310.533906 -33.555711) (xy 310.484329 -33.533069)
			(xy 310.438479 -33.503603) (xy 310.397288 -33.467912) (xy 310.361597 -33.426721) (xy 310.332131 -33.380871)
			(xy 310.309489 -33.331294) (xy 310.294134 -33.278999) (xy 310.286378 -33.225051) (xy 310.285892 -33.1978)
			(xy 309.171848 -33.1978) (xy 309.171848 -35.476942) (xy 308.268116 -36.380674) (xy 308.268116 -36.806886)
			(xy 310.239662 -36.806886) (xy 310.243733 -36.751264) (xy 310.255859 -36.696827) (xy 310.275782 -36.644736)
			(xy 310.303078 -36.596101) (xy 310.337164 -36.551958) (xy 310.377313 -36.513249) (xy 310.422671 -36.480798)
			(xy 310.472271 -36.455297) (xy 310.525055 -36.43729) (xy 310.579898 -36.42716) (xy 310.635632 -36.425123)
			(xy 310.691069 -36.431223) (xy 310.745026 -36.445329) (xy 310.796355 -36.467141) (xy 310.843961 -36.496195)
			(xy 310.886829 -36.53187) (xy 310.924046 -36.573407) (xy 310.954819 -36.61992) (xy 310.978491 -36.670417)
			(xy 310.994559 -36.723824) (xy 311.002679 -36.779) (xy 311.003188 -36.806886) (xy 311.002942 -36.820348)
			(xy 313.077604 -36.820348) (xy 313.081675 -36.764726) (xy 313.093801 -36.710289) (xy 313.113724 -36.658198)
			(xy 313.14102 -36.609563) (xy 313.175106 -36.56542) (xy 313.215255 -36.526711) (xy 313.260613 -36.49426)
			(xy 313.310213 -36.468759) (xy 313.362997 -36.450752) (xy 313.41784 -36.440622) (xy 313.473574 -36.438585)
			(xy 313.529011 -36.444685) (xy 313.582968 -36.458791) (xy 313.634297 -36.480603) (xy 313.681903 -36.509657)
			(xy 313.724771 -36.545332) (xy 313.761988 -36.586869) (xy 313.792761 -36.633382) (xy 313.816433 -36.683879)
			(xy 313.832501 -36.737286) (xy 313.840621 -36.792462) (xy 313.84113 -36.820348) (xy 313.840621 -36.848234)
			(xy 313.832501 -36.90341) (xy 313.816433 -36.956817) (xy 313.792761 -37.007314) (xy 313.761988 -37.053827)
			(xy 313.724771 -37.095364) (xy 313.681903 -37.131039) (xy 313.634297 -37.160093) (xy 313.582968 -37.181905)
			(xy 313.529011 -37.196011) (xy 313.473574 -37.202111) (xy 313.41784 -37.200074) (xy 313.362997 -37.189944)
			(xy 313.310213 -37.171937) (xy 313.260613 -37.146436) (xy 313.215255 -37.113985) (xy 313.175106 -37.075276)
			(xy 313.14102 -37.031133) (xy 313.113724 -36.982498) (xy 313.093801 -36.930407) (xy 313.081675 -36.87597)
			(xy 313.077604 -36.820348) (xy 311.002942 -36.820348) (xy 311.002679 -36.834772) (xy 310.994559 -36.889948)
			(xy 310.978491 -36.943355) (xy 310.954819 -36.993852) (xy 310.924046 -37.040365) (xy 310.886829 -37.081902)
			(xy 310.843961 -37.117577) (xy 310.796355 -37.146631) (xy 310.745026 -37.168443) (xy 310.691069 -37.182549)
			(xy 310.635632 -37.188649) (xy 310.579898 -37.186612) (xy 310.525055 -37.176482) (xy 310.472271 -37.158475)
			(xy 310.422671 -37.132974) (xy 310.377313 -37.100523) (xy 310.337164 -37.061814) (xy 310.303078 -37.017671)
			(xy 310.275782 -36.969036) (xy 310.255859 -36.916945) (xy 310.243733 -36.862508) (xy 310.239662 -36.806886)
			(xy 308.268116 -36.806886) (xy 308.268116 -37.358066) (xy 308.268533 -37.371491) (xy 308.275545 -37.397409)
			(xy 308.289068 -37.420605) (xy 308.308167 -37.439477) (xy 308.331524 -37.452721) (xy 308.357525 -37.459422)
			(xy 308.384373 -37.459117) (xy 308.397402 -37.455856) (xy 308.422904 -37.44909) (xy 308.475162 -37.44183)
			(xy 308.501542 -37.441378) (xy 308.528792 -37.441867) (xy 308.582737 -37.449628) (xy 308.635029 -37.464988)
			(xy 308.684603 -37.487632) (xy 308.73045 -37.517101) (xy 308.771636 -37.552793) (xy 308.807325 -37.593984)
			(xy 308.836788 -37.639834) (xy 308.859427 -37.68941) (xy 308.874781 -37.741704) (xy 308.882536 -37.79565)
			(xy 308.882536 -37.822886) (xy 310.239662 -37.822886) (xy 310.243733 -37.767264) (xy 310.255859 -37.712827)
			(xy 310.275782 -37.660736) (xy 310.303078 -37.612101) (xy 310.337164 -37.567958) (xy 310.377313 -37.529249)
			(xy 310.422671 -37.496798) (xy 310.472271 -37.471297) (xy 310.525055 -37.45329) (xy 310.579898 -37.44316)
			(xy 310.635632 -37.441123) (xy 310.691069 -37.447223) (xy 310.745026 -37.461329) (xy 310.796355 -37.483141)
			(xy 310.843961 -37.512195) (xy 310.886829 -37.54787) (xy 310.924046 -37.589407) (xy 310.954819 -37.63592)
			(xy 310.978491 -37.686417) (xy 310.994559 -37.739824) (xy 311.002679 -37.795) (xy 311.003188 -37.822886)
			(xy 311.002679 -37.850772) (xy 310.994559 -37.905948) (xy 310.978491 -37.959355) (xy 310.954819 -38.009852)
			(xy 310.924046 -38.056365) (xy 310.886829 -38.097902) (xy 310.843961 -38.133577) (xy 310.796355 -38.162631)
			(xy 310.745026 -38.184443) (xy 310.691069 -38.198549) (xy 310.635632 -38.204649) (xy 310.579898 -38.202612)
			(xy 310.525055 -38.192482) (xy 310.472271 -38.174475) (xy 310.422671 -38.148974) (xy 310.377313 -38.116523)
			(xy 310.337164 -38.077814) (xy 310.303078 -38.033671) (xy 310.275782 -37.985036) (xy 310.255859 -37.932945)
			(xy 310.243733 -37.878508) (xy 310.239662 -37.822886) (xy 308.882536 -37.822886) (xy 308.882536 -37.85015)
			(xy 308.874781 -37.904096) (xy 308.859427 -37.95639) (xy 308.836788 -38.005966) (xy 308.807325 -38.051816)
			(xy 308.771636 -38.093007) (xy 308.73045 -38.128699) (xy 308.684603 -38.158168) (xy 308.635029 -38.180812)
			(xy 308.582737 -38.196172) (xy 308.528792 -38.203933) (xy 308.501542 -38.204394) (xy 308.475161 -38.203952)
			(xy 308.422901 -38.196692) (xy 308.397402 -38.189916) (xy 308.384367 -38.186649) (xy 308.357506 -38.18632)
			(xy 308.331489 -38.193009) (xy 308.308116 -38.206251) (xy 308.289006 -38.22513) (xy 308.275481 -38.24834)
			(xy 308.268476 -38.274274) (xy 308.268116 -38.287706) (xy 308.268116 -38.63213) (xy 308.268685 -38.647052)
			(xy 308.277397 -38.675601) (xy 308.293982 -38.700418) (xy 308.317026 -38.719389) (xy 308.344567 -38.730897)
			(xy 308.374258 -38.733962) (xy 308.38902 -38.731698) (xy 308.406942 -38.728462) (xy 308.4432 -38.725027)
			(xy 308.46141 -38.72484) (xy 308.488657 -38.725327) (xy 308.542597 -38.733084) (xy 308.594884 -38.748438)
			(xy 308.644454 -38.771076) (xy 308.690297 -38.800539) (xy 308.700255 -38.809168) (xy 311.045604 -38.809168)
			(xy 311.049675 -38.753546) (xy 311.061801 -38.699109) (xy 311.081724 -38.647018) (xy 311.10902 -38.598383)
			(xy 311.143106 -38.55424) (xy 311.183255 -38.515531) (xy 311.228613 -38.48308) (xy 311.278213 -38.457579)
			(xy 311.330997 -38.439572) (xy 311.38584 -38.429442) (xy 311.441574 -38.427405) (xy 311.497011 -38.433505)
			(xy 311.550968 -38.447611) (xy 311.602297 -38.469423) (xy 311.649903 -38.498477) (xy 311.692771 -38.534152)
			(xy 311.729988 -38.575689) (xy 311.760761 -38.622202) (xy 311.784433 -38.672699) (xy 311.800501 -38.726106)
			(xy 311.808621 -38.781282) (xy 311.80913 -38.809168) (xy 311.808621 -38.837054) (xy 311.800501 -38.89223)
			(xy 311.784433 -38.945637) (xy 311.760761 -38.996134) (xy 311.729988 -39.042647) (xy 311.692771 -39.084184)
			(xy 311.649903 -39.119859) (xy 311.602297 -39.148913) (xy 311.550968 -39.170725) (xy 311.497011 -39.184831)
			(xy 311.441574 -39.190931) (xy 311.38584 -39.188894) (xy 311.330997 -39.178764) (xy 311.278213 -39.160757)
			(xy 311.228613 -39.135256) (xy 311.183255 -39.102805) (xy 311.143106 -39.064096) (xy 311.10902 -39.019953)
			(xy 311.081724 -38.971318) (xy 311.061801 -38.919227) (xy 311.049675 -38.86479) (xy 311.045604 -38.809168)
			(xy 308.700255 -38.809168) (xy 308.731481 -38.836226) (xy 308.767167 -38.877411) (xy 308.796628 -38.923255)
			(xy 308.819266 -38.972825) (xy 308.834619 -39.025113) (xy 308.842374 -39.079053) (xy 308.842374 -39.133547)
			(xy 308.834619 -39.187487) (xy 308.819266 -39.239775) (xy 308.796628 -39.289345) (xy 308.767167 -39.335189)
			(xy 308.731481 -39.376374) (xy 308.690297 -39.412061) (xy 308.644454 -39.441524) (xy 308.594884 -39.464162)
			(xy 308.542597 -39.479516) (xy 308.488657 -39.487273) (xy 308.46141 -39.487856) (xy 308.443201 -39.487647)
			(xy 308.406945 -39.48421) (xy 308.38902 -39.480998) (xy 308.37426 -39.478672) (xy 308.34455 -39.481715)
			(xy 308.31699 -39.493223) (xy 308.293938 -39.512211) (xy 308.277365 -39.537057) (xy 308.268687 -39.565634)
			(xy 308.268116 -39.580566) (xy 308.268116 -39.878508) (xy 310.232042 -39.878508) (xy 310.236113 -39.822886)
			(xy 310.248239 -39.768449) (xy 310.268162 -39.716358) (xy 310.295458 -39.667723) (xy 310.329544 -39.62358)
			(xy 310.369693 -39.584871) (xy 310.415051 -39.55242) (xy 310.464651 -39.526919) (xy 310.517435 -39.508912)
			(xy 310.572278 -39.498782) (xy 310.628012 -39.496745) (xy 310.683449 -39.502845) (xy 310.737406 -39.516951)
			(xy 310.788735 -39.538763) (xy 310.836341 -39.567817) (xy 310.879209 -39.603492) (xy 310.916426 -39.645029)
			(xy 310.947199 -39.691542) (xy 310.970871 -39.742039) (xy 310.986939 -39.795446) (xy 310.995059 -39.850622)
			(xy 310.995568 -39.878508) (xy 310.995059 -39.906394) (xy 310.986939 -39.96157) (xy 310.970871 -40.014977)
			(xy 310.947199 -40.065474) (xy 310.916426 -40.111987) (xy 310.879209 -40.153524) (xy 310.836341 -40.189199)
			(xy 310.788735 -40.218253) (xy 310.737406 -40.240065) (xy 310.683449 -40.254171) (xy 310.628012 -40.260271)
			(xy 310.572278 -40.258234) (xy 310.517435 -40.248104) (xy 310.464651 -40.230097) (xy 310.415051 -40.204596)
			(xy 310.369693 -40.172145) (xy 310.329544 -40.133436) (xy 310.295458 -40.089293) (xy 310.268162 -40.040658)
			(xy 310.248239 -39.988567) (xy 310.236113 -39.93413) (xy 310.232042 -39.878508) (xy 308.268116 -39.878508)
			(xy 308.268116 -40.09644) (xy 308.85765 -40.685974) (xy 315.365382 -40.685974) (xy 315.369453 -40.630352)
			(xy 315.381579 -40.575915) (xy 315.401502 -40.523824) (xy 315.428798 -40.475189) (xy 315.462884 -40.431046)
			(xy 315.503033 -40.392337) (xy 315.548391 -40.359886) (xy 315.597991 -40.334385) (xy 315.650775 -40.316378)
			(xy 315.705618 -40.306248) (xy 315.761352 -40.304211) (xy 315.816789 -40.310311) (xy 315.870746 -40.324417)
			(xy 315.922075 -40.346229) (xy 315.969681 -40.375283) (xy 316.012549 -40.410958) (xy 316.049766 -40.452495)
			(xy 316.080539 -40.499008) (xy 316.104211 -40.549505) (xy 316.120279 -40.602912) (xy 316.128399 -40.658088)
			(xy 316.128908 -40.685974) (xy 316.128399 -40.71386) (xy 316.120279 -40.769036) (xy 316.104211 -40.822443)
			(xy 316.080539 -40.87294) (xy 316.049766 -40.919453) (xy 316.012549 -40.96099) (xy 315.969681 -40.996665)
			(xy 315.922075 -41.025719) (xy 315.870746 -41.047531) (xy 315.816789 -41.061637) (xy 315.761352 -41.067737)
			(xy 315.705618 -41.0657) (xy 315.650775 -41.05557) (xy 315.597991 -41.037563) (xy 315.548391 -41.012062)
			(xy 315.503033 -40.979611) (xy 315.462884 -40.940902) (xy 315.428798 -40.896759) (xy 315.401502 -40.848124)
			(xy 315.381579 -40.796033) (xy 315.369453 -40.741596) (xy 315.365382 -40.685974) (xy 308.85765 -40.685974)
			(xy 310.050942 -41.879266) (xy 310.050942 -43.109896) (xy 310.209438 -43.268392) (xy 310.278526 -43.199304)
			(xy 310.248046 -43.16349) (xy 310.230961 -43.142707) (xy 310.202194 -43.097245) (xy 310.180104 -43.048189)
			(xy 310.165132 -42.996514) (xy 310.157575 -42.943248) (xy 310.157114 -42.916348) (xy 310.157574 -42.889096)
			(xy 310.165324 -42.835147) (xy 310.180673 -42.782849) (xy 310.203308 -42.733269) (xy 310.23277 -42.687414)
			(xy 310.268457 -42.646219) (xy 310.309644 -42.610522) (xy 310.355492 -42.58105) (xy 310.405067 -42.558403)
			(xy 310.457361 -42.543042) (xy 310.511309 -42.53528) (xy 310.565812 -42.535274) (xy 310.619762 -42.543026)
			(xy 310.672059 -42.558376) (xy 310.721639 -42.581013) (xy 310.767493 -42.610475) (xy 310.808687 -42.646163)
			(xy 310.844383 -42.687351) (xy 310.873854 -42.733199) (xy 310.8965 -42.782775) (xy 310.911859 -42.83507)
			(xy 310.919621 -42.889018) (xy 310.919625 -42.943521) (xy 310.911872 -42.99747) (xy 310.896521 -43.049767)
			(xy 310.873883 -43.099347) (xy 310.84442 -43.1452) (xy 310.808731 -43.186393) (xy 310.767542 -43.222088)
			(xy 310.721693 -43.251558) (xy 310.672116 -43.274203) (xy 310.619822 -43.289561) (xy 310.565874 -43.297321)
			(xy 310.538622 -43.297856) (xy 310.527163 -43.297768) (xy 310.504286 -43.296373) (xy 310.492902 -43.295062)
			(xy 310.478938 -43.293819) (xy 310.451248 -43.29814) (xy 310.425772 -43.30982) (xy 310.404428 -43.327981)
			(xy 310.388819 -43.351257) (xy 310.38012 -43.377898) (xy 310.378985 -43.405901) (xy 310.385499 -43.433158)
			(xy 310.399172 -43.457621) (xy 310.408828 -43.467782) (xy 312.461148 -45.520102) (xy 312.461148 -46.122336)
			(xy 312.246432 -46.337052) (xy 314.546966 -46.337052) (xy 314.546966 -46.282548) (xy 314.554722 -46.228599)
			(xy 314.570078 -46.176303) (xy 314.592719 -46.126724) (xy 314.622186 -46.080873) (xy 314.657878 -46.039681)
			(xy 314.69907 -46.003989) (xy 314.744921 -45.974521) (xy 314.794499 -45.951879) (xy 314.846795 -45.936523)
			(xy 314.900744 -45.928766) (xy 314.927996 -45.92828) (xy 314.953915 -45.928692) (xy 315.005277 -45.935704)
			(xy 315.055215 -45.949612) (xy 315.102806 -45.970161) (xy 315.147174 -45.996971) (xy 315.187498 -46.029546)
			(xy 315.223035 -46.067287) (xy 315.253129 -46.109496) (xy 315.265562 -46.132242) (xy 315.272236 -46.143912)
			(xy 315.290508 -46.163611) (xy 315.313291 -46.177854) (xy 315.339003 -46.185655) (xy 315.365859 -46.18647)
			(xy 315.391997 -46.180244) (xy 315.415602 -46.167409) (xy 315.435036 -46.148855) (xy 315.442346 -46.137576)
			(xy 315.457264 -46.113895) (xy 315.492948 -46.070778) (xy 315.534546 -46.033334) (xy 315.581165 -46.002365)
			(xy 315.631807 -45.978536) (xy 315.685385 -45.962357) (xy 315.740752 -45.954175) (xy 315.768736 -45.95368)
			(xy 315.795985 -45.954193) (xy 315.849927 -45.961953) (xy 315.902215 -45.977311) (xy 315.951787 -45.999953)
			(xy 315.997631 -46.02942) (xy 316.038816 -46.06511) (xy 316.074502 -46.106298) (xy 316.103964 -46.152145)
			(xy 316.126602 -46.201718) (xy 316.141955 -46.254008) (xy 316.14971 -46.307951) (xy 316.14971 -46.362449)
			(xy 316.141955 -46.416392) (xy 316.126602 -46.468682) (xy 316.103964 -46.518255) (xy 316.074502 -46.564102)
			(xy 316.038816 -46.60529) (xy 315.997631 -46.64098) (xy 315.951787 -46.670447) (xy 315.902215 -46.693089)
			(xy 315.849927 -46.708447) (xy 315.795985 -46.716207) (xy 315.768736 -46.716696) (xy 315.742819 -46.716218)
			(xy 315.691462 -46.709212) (xy 315.641528 -46.69531) (xy 315.593938 -46.67477) (xy 315.549572 -46.64797)
			(xy 315.509246 -46.615404) (xy 315.473706 -46.577674) (xy 315.443607 -46.535476) (xy 315.43117 -46.512734)
			(xy 315.424593 -46.501006) (xy 315.406302 -46.481305) (xy 315.383501 -46.467064) (xy 315.357773 -46.459269)
			(xy 315.330902 -46.458462) (xy 315.304753 -46.464699) (xy 315.281138 -46.477546) (xy 315.261697 -46.496114)
			(xy 315.254386 -46.5074) (xy 315.239505 -46.531106) (xy 315.203816 -46.574224) (xy 315.162213 -46.611668)
			(xy 315.115587 -46.642634) (xy 315.064939 -46.666459) (xy 315.011354 -46.682632) (xy 314.955982 -46.690805)
			(xy 314.927996 -46.691296) (xy 314.900744 -46.690834) (xy 314.846795 -46.683077) (xy 314.794499 -46.667721)
			(xy 314.744921 -46.645079) (xy 314.69907 -46.615611) (xy 314.657878 -46.579919) (xy 314.622186 -46.538727)
			(xy 314.592719 -46.492876) (xy 314.570078 -46.443297) (xy 314.554722 -46.391001) (xy 314.546966 -46.337052)
			(xy 312.246432 -46.337052) (xy 311.218326 -47.365158) (xy 311.20804 -47.376188) (xy 311.193839 -47.402779)
			(xy 311.188014 -47.432357) (xy 311.191071 -47.462346) (xy 311.202745 -47.49014) (xy 311.222019 -47.513318)
			(xy 311.247218 -47.529864) (xy 311.276147 -47.53834) (xy 311.291224 -47.53864) (xy 311.295796 -47.53864)
			(xy 311.323046 -47.539103) (xy 311.37699 -47.546858) (xy 311.429282 -47.562212) (xy 311.478856 -47.584852)
			(xy 311.524704 -47.614316) (xy 311.565892 -47.650005) (xy 311.601582 -47.691193) (xy 311.631046 -47.73704)
			(xy 311.653686 -47.786614) (xy 311.669041 -47.838906) (xy 311.676797 -47.89285) (xy 311.676797 -47.94735)
			(xy 311.669041 -48.001294) (xy 311.653686 -48.053586) (xy 311.633426 -48.097948) (xy 313.617862 -48.097948)
			(xy 313.621933 -48.042326) (xy 313.634059 -47.987889) (xy 313.653982 -47.935798) (xy 313.681278 -47.887163)
			(xy 313.715364 -47.84302) (xy 313.755513 -47.804311) (xy 313.800871 -47.77186) (xy 313.850471 -47.746359)
			(xy 313.903255 -47.728352) (xy 313.958098 -47.718222) (xy 314.013832 -47.716185) (xy 314.069269 -47.722285)
			(xy 314.123226 -47.736391) (xy 314.174555 -47.758203) (xy 314.222161 -47.787257) (xy 314.265029 -47.822932)
			(xy 314.302246 -47.864469) (xy 314.333019 -47.910982) (xy 314.356691 -47.961479) (xy 314.372759 -48.014886)
			(xy 314.380879 -48.070062) (xy 314.381388 -48.097948) (xy 314.380879 -48.125834) (xy 314.372759 -48.18101)
			(xy 314.356691 -48.234417) (xy 314.333019 -48.284914) (xy 314.302246 -48.331427) (xy 314.265029 -48.372964)
			(xy 314.222161 -48.408639) (xy 314.174555 -48.437693) (xy 314.123226 -48.459505) (xy 314.069269 -48.473611)
			(xy 314.013832 -48.479711) (xy 313.958098 -48.477674) (xy 313.903255 -48.467544) (xy 313.850471 -48.449537)
			(xy 313.800871 -48.424036) (xy 313.755513 -48.391585) (xy 313.715364 -48.352876) (xy 313.681278 -48.308733)
			(xy 313.653982 -48.260098) (xy 313.634059 -48.208007) (xy 313.621933 -48.15357) (xy 313.617862 -48.097948)
			(xy 311.633426 -48.097948) (xy 311.631046 -48.10316) (xy 311.601582 -48.149007) (xy 311.565892 -48.190195)
			(xy 311.524704 -48.225884) (xy 311.478856 -48.255348) (xy 311.429282 -48.277988) (xy 311.37699 -48.293342)
			(xy 311.323046 -48.301097) (xy 311.295796 -48.301656) (xy 311.266961 -48.301129) (xy 311.209946 -48.292456)
			(xy 311.182258 -48.284384) (xy 311.167915 -48.280445) (xy 311.138188 -48.280135) (xy 311.109631 -48.288403)
			(xy 311.084666 -48.304546) (xy 311.06541 -48.327196) (xy 311.053495 -48.354433) (xy 311.049931 -48.383948)
			(xy 311.051956 -48.398684) (xy 311.054569 -48.414813) (xy 311.057366 -48.44737) (xy 311.057544 -48.463708)
			(xy 311.057129 -48.489054) (xy 311.050417 -48.5393) (xy 311.037112 -48.588216) (xy 311.017449 -48.634939)
			(xy 311.004966 -48.657002) (xy 311.004966 -49.963832) (xy 311.6326 -50.591466) (xy 312.044588 -50.591466)
			(xy 312.058502 -50.591025) (xy 312.085294 -50.583493) (xy 312.109059 -50.569013) (xy 312.128037 -50.548657)
			(xy 312.140818 -50.523936) (xy 312.146456 -50.496684) (xy 312.144533 -50.468921) (xy 312.13519 -50.442706)
			(xy 312.119121 -50.419985) (xy 312.108596 -50.410872) (xy 312.086954 -50.392664) (xy 312.048764 -50.35095)
			(xy 312.017152 -50.304054) (xy 311.992812 -50.253004) (xy 311.976277 -50.198919) (xy 311.96791 -50.142986)
			(xy 311.967372 -50.114708) (xy 311.967858 -50.087457) (xy 311.975614 -50.033509) (xy 311.990969 -49.981214)
			(xy 312.013611 -49.931637) (xy 312.043077 -49.885787) (xy 312.078768 -49.844596) (xy 312.119959 -49.808905)
			(xy 312.165809 -49.779439) (xy 312.215386 -49.756797) (xy 312.267681 -49.741442) (xy 312.321629 -49.733686)
			(xy 312.376131 -49.733686) (xy 312.430079 -49.741442) (xy 312.482374 -49.756797) (xy 312.531951 -49.779439)
			(xy 312.577801 -49.808905) (xy 312.618992 -49.844596) (xy 312.654683 -49.885787) (xy 312.684149 -49.931637)
			(xy 312.706791 -49.981214) (xy 312.722146 -50.033509) (xy 312.729902 -50.087457) (xy 312.730388 -50.114708)
			(xy 312.72988 -50.14299) (xy 312.721533 -50.198935) (xy 312.705008 -50.253031) (xy 312.680668 -50.304091)
			(xy 312.649048 -50.350992) (xy 312.610844 -50.392704) (xy 312.589164 -50.410872) (xy 312.57862 -50.419967)
			(xy 312.562527 -50.44268) (xy 312.553166 -50.468895) (xy 312.551234 -50.496664) (xy 312.556874 -50.523923)
			(xy 312.569667 -50.548645) (xy 312.588662 -50.568993) (xy 312.612447 -50.583454) (xy 312.639254 -50.590954)
			(xy 312.653172 -50.591466) (xy 313.239404 -50.591466) (xy 313.59475 -50.946812) (xy 313.605276 -50.956632)
			(xy 313.630488 -50.970498) (xy 313.658563 -50.976796) (xy 313.687282 -50.975029) (xy 313.714374 -50.965335)
			(xy 313.737695 -50.948482) (xy 313.746896 -50.937414) (xy 313.765073 -50.914865) (xy 313.807088 -50.875002)
			(xy 313.854649 -50.841953) (xy 313.906663 -50.816478) (xy 313.961931 -50.799165) (xy 314.019182 -50.79041)
			(xy 314.04814 -50.78984) (xy 314.07539 -50.790306) (xy 314.129334 -50.798068) (xy 314.181624 -50.813428)
			(xy 314.231196 -50.836073) (xy 314.277041 -50.865543) (xy 314.318225 -50.901238) (xy 314.35391 -50.94243)
			(xy 314.383369 -50.988281) (xy 314.406003 -51.037858) (xy 314.421351 -51.090152) (xy 314.4291 -51.144098)
			(xy 314.429648 -51.171348) (xy 314.429113 -51.200309) (xy 314.420359 -51.257566) (xy 314.403045 -51.31284)
			(xy 314.377568 -51.364859) (xy 314.344517 -51.412425) (xy 314.30465 -51.454444) (xy 314.282074 -51.472592)
			(xy 314.271025 -51.48182) (xy 314.254146 -51.505125) (xy 314.244435 -51.532212) (xy 314.242663 -51.560932)
			(xy 314.248971 -51.589007) (xy 314.262857 -51.61421) (xy 314.272676 -51.624738) (xy 314.871608 -52.22367)
			(xy 314.871608 -56.26608) (xy 315.725048 -57.11952)
		)
		(stroke
			(width 0)
			(type solid)
		)
		(fill yes)
		(layer "In2.Cu")
		(net "P3V3_AUX")
	)
	(gr_poly
		(pts
			(xy 465.316316 -395.996414) (xy 466.95868 -394.35405) (xy 466.95868 -379.016768) (xy 465.741258 -377.799346)
			(xy 463.151728 -377.799346) (xy 463.151728 -381.176784) (xy 463.152191 -381.19095) (xy 463.159973 -381.218193)
			(xy 463.174943 -381.242247) (xy 463.195947 -381.261262) (xy 463.221367 -381.273772) (xy 463.249247 -381.278814)
			(xy 463.277439 -381.275999) (xy 463.303772 -381.265545) (xy 463.315304 -381.257302) (xy 463.335424 -381.242242)
			(xy 463.378868 -381.216972) (xy 463.425254 -381.197624) (xy 463.473778 -381.184533) (xy 463.523601 -381.177926)
			(xy 463.54873 -381.177546) (xy 463.575983 -381.178034) (xy 463.629934 -381.185795) (xy 463.682232 -381.201154)
			(xy 463.690604 -381.204978) (xy 464.315048 -381.204978) (xy 464.315541 -381.17613) (xy 464.324227 -381.119091)
			(xy 464.341412 -381.064014) (xy 464.366703 -381.012157) (xy 464.399522 -380.964704) (xy 464.418934 -380.943358)
			(xy 464.429105 -380.931769) (xy 464.442652 -380.904088) (xy 464.447314 -380.873626) (xy 464.442667 -380.843161)
			(xy 464.429135 -380.815473) (xy 464.418934 -380.803912) (xy 464.399513 -380.782577) (xy 464.366716 -380.735113)
			(xy 464.341441 -380.683251) (xy 464.324264 -380.628174) (xy 464.315577 -380.571139) (xy 464.315048 -380.542292)
			(xy 464.31557 -380.515043) (xy 464.323327 -380.461098) (xy 464.338681 -380.408807) (xy 464.361319 -380.359233)
			(xy 464.390782 -380.313384) (xy 464.42647 -380.272195) (xy 464.467656 -380.236504) (xy 464.513501 -380.207037)
			(xy 464.563073 -380.184393) (xy 464.615363 -380.169034) (xy 464.669307 -380.161273) (xy 464.696556 -380.160784)
			(xy 464.725296 -380.161278) (xy 464.782124 -380.169908) (xy 464.837015 -380.186966) (xy 464.888727 -380.212064)
			(xy 464.936088 -380.244635) (xy 464.957414 -380.263908) (xy 464.968948 -380.27398) (xy 464.996494 -380.287322)
			(xy 465.026756 -380.291907) (xy 465.057018 -380.287322) (xy 465.084564 -380.27398) (xy 465.096098 -380.263908)
			(xy 465.117398 -380.244606) (xy 465.164768 -380.212045) (xy 465.216486 -380.186959) (xy 465.271383 -380.169916)
			(xy 465.328215 -380.161301) (xy 465.356956 -380.160784) (xy 465.384207 -380.161296) (xy 465.438156 -380.169047)
			(xy 465.490453 -380.184397) (xy 465.540032 -380.207034) (xy 465.585885 -380.236496) (xy 465.627078 -380.272185)
			(xy 465.662772 -380.313373) (xy 465.692241 -380.359222) (xy 465.714885 -380.408799) (xy 465.730242 -380.461093)
			(xy 465.738 -380.515041) (xy 465.738464 -380.542292) (xy 465.737949 -380.571139) (xy 465.729268 -380.628177)
			(xy 465.712088 -380.683254) (xy 465.686802 -380.735112) (xy 465.653988 -380.782565) (xy 465.634578 -380.803912)
			(xy 465.624387 -380.815468) (xy 465.610927 -380.843173) (xy 465.606307 -380.873626) (xy 465.610943 -380.904076)
			(xy 465.624416 -380.931774) (xy 465.634578 -380.943358) (xy 465.653987 -380.964704) (xy 465.686785 -381.012165)
			(xy 465.712063 -381.064025) (xy 465.729243 -381.119099) (xy 465.737933 -381.176132) (xy 465.738464 -381.204978)
			(xy 465.738024 -381.232232) (xy 465.730269 -381.286186) (xy 465.714913 -381.338487) (xy 465.69227 -381.38807)
			(xy 465.662801 -381.433926) (xy 465.627104 -381.47512) (xy 465.585908 -381.510814) (xy 465.540051 -381.540281)
			(xy 465.490467 -381.562921) (xy 465.438165 -381.578274) (xy 465.38421 -381.586026) (xy 465.356956 -381.586486)
			(xy 465.328217 -381.585966) (xy 465.271391 -381.577339) (xy 465.216501 -381.560287) (xy 465.164789 -381.535195)
			(xy 465.117426 -381.502631) (xy 465.096098 -381.483362) (xy 465.084564 -381.47329) (xy 465.057018 -381.459948)
			(xy 465.026756 -381.455363) (xy 464.996494 -381.459948) (xy 464.968948 -381.47329) (xy 464.957414 -381.483362)
			(xy 464.936105 -381.502654) (xy 464.888738 -381.535217) (xy 464.837022 -381.560305) (xy 464.782127 -381.577351)
			(xy 464.725296 -381.585968) (xy 464.696556 -381.586486) (xy 464.669303 -381.586063) (xy 464.615352 -381.5783)
			(xy 464.563054 -381.562938) (xy 464.513475 -381.54029) (xy 464.467624 -381.510817) (xy 464.426434 -381.475119)
			(xy 464.390743 -381.433923) (xy 464.361278 -381.388067) (xy 464.338639 -381.338484) (xy 464.323286 -381.286184)
			(xy 464.315532 -381.232231) (xy 464.315048 -381.204978) (xy 463.690604 -381.204978) (xy 463.731811 -381.2238)
			(xy 463.777663 -381.253271) (xy 463.818855 -381.288966) (xy 463.854547 -381.330161) (xy 463.884014 -381.376015)
			(xy 463.906656 -381.425597) (xy 463.922012 -381.477895) (xy 463.929768 -381.531847) (xy 463.929768 -381.586353)
			(xy 463.922012 -381.640305) (xy 463.906656 -381.692603) (xy 463.884014 -381.742185) (xy 463.854547 -381.788039)
			(xy 463.818855 -381.829234) (xy 463.777663 -381.864929) (xy 463.731811 -381.8944) (xy 463.682232 -381.917046)
			(xy 463.629934 -381.932405) (xy 463.575983 -381.940166) (xy 463.54873 -381.940562) (xy 463.51918 -381.940009)
			(xy 463.460786 -381.930893) (xy 463.404498 -381.912877) (xy 463.351665 -381.88639) (xy 463.303552 -381.852068)
			(xy 463.261311 -381.810732) (xy 463.243168 -381.7874) (xy 463.227928 -381.76708) (xy 463.151728 -381.76708)
			(xy 463.151728 -381.902208) (xy 463.151172 -381.931183) (xy 463.14207 -381.988414) (xy 463.124123 -382.043515)
			(xy 463.097774 -382.095128) (xy 463.063671 -382.141981) (xy 463.043524 -382.162812) (xy 462.837784 -382.368552)
			(xy 462.816935 -382.38868) (xy 462.770087 -382.422787) (xy 462.718478 -382.449142) (xy 462.663382 -382.467097)
			(xy 462.606154 -382.476208) (xy 462.57718 -382.476756) (xy 460.974694 -382.476756) (xy 460.93253 -382.51892)
			(xy 460.922032 -382.530168) (xy 460.907743 -382.5574) (xy 460.902208 -382.58765) (xy 460.905928 -382.618177)
			(xy 460.918566 -382.646213) (xy 460.938976 -382.669217) (xy 460.951834 -382.67767) (xy 460.975545 -382.692592)
			(xy 461.018723 -382.728287) (xy 461.05622 -382.76991) (xy 461.087233 -382.816565) (xy 461.111094 -382.867252)
			(xy 461.127291 -382.920882) (xy 461.135476 -382.976303) (xy 461.135984 -383.004314) (xy 461.135498 -383.031565)
			(xy 461.127742 -383.085513) (xy 461.112387 -383.137808) (xy 461.089745 -383.187385) (xy 461.060279 -383.233235)
			(xy 461.024588 -383.274426) (xy 460.983397 -383.310117) (xy 460.937547 -383.339583) (xy 460.88797 -383.362225)
			(xy 460.835675 -383.37758) (xy 460.781727 -383.385336) (xy 460.727225 -383.385336) (xy 460.673277 -383.37758)
			(xy 460.620982 -383.362225) (xy 460.571405 -383.339583) (xy 460.525555 -383.310117) (xy 460.484364 -383.274426)
			(xy 460.448673 -383.233235) (xy 460.419207 -383.187385) (xy 460.396565 -383.137808) (xy 460.38121 -383.085513)
			(xy 460.373454 -383.031565) (xy 460.372968 -383.004314) (xy 460.373303 -382.980697) (xy 460.379098 -382.933821)
			(xy 460.390638 -382.88802) (xy 460.398876 -382.865884) (xy 460.403606 -382.852561) (xy 460.406316 -382.824431)
			(xy 460.401211 -382.796635) (xy 460.388682 -382.771303) (xy 460.36969 -382.750376) (xy 460.345689 -382.735455)
			(xy 460.318518 -382.727686) (xy 460.304388 -382.7272) (xy 460.217774 -382.7272) (xy 460.211678 -382.728724)
			(xy 460.188999 -382.734048) (xy 460.142768 -382.739784) (xy 460.119476 -382.740154) (xy 460.092223 -382.739666)
			(xy 460.038271 -382.731906) (xy 459.985973 -382.716547) (xy 459.936393 -382.693902) (xy 459.89054 -382.664431)
			(xy 459.849347 -382.628736) (xy 459.813654 -382.587541) (xy 459.784187 -382.541686) (xy 459.761544 -382.492105)
			(xy 459.746189 -382.439806) (xy 459.738432 -382.385853) (xy 459.738432 -382.331347) (xy 459.746189 -382.277394)
			(xy 459.761544 -382.225095) (xy 459.784187 -382.175514) (xy 459.813654 -382.129659) (xy 459.849347 -382.088464)
			(xy 459.89054 -382.052769) (xy 459.936393 -382.023298) (xy 459.985973 -382.000653) (xy 460.038271 -381.985294)
			(xy 460.092223 -381.977534) (xy 460.119476 -381.977138) (xy 460.142767 -381.97752) (xy 460.188997 -381.983255)
			(xy 460.211678 -381.988568) (xy 460.217774 -381.990092) (xy 460.418688 -381.990092) (xy 460.561436 -381.847344)
			(xy 460.582285 -381.827217) (xy 460.629134 -381.793114) (xy 460.680743 -381.766761) (xy 460.73584 -381.74881)
			(xy 460.793067 -381.739701) (xy 460.82204 -381.73914) (xy 461.422496 -381.73914) (xy 461.437578 -381.738594)
			(xy 461.466425 -381.729783) (xy 461.49144 -381.712929) (xy 461.51044 -381.689502) (xy 461.521766 -381.661546)
			(xy 461.524431 -381.631501) (xy 461.518202 -381.601988) (xy 461.511396 -381.588518) (xy 461.496473 -381.560096)
			(xy 461.475309 -381.499495) (xy 461.464574 -381.436209) (xy 461.463898 -381.404114) (xy 461.464384 -381.376863)
			(xy 461.47214 -381.322915) (xy 461.487495 -381.27062) (xy 461.510137 -381.221043) (xy 461.539603 -381.175193)
			(xy 461.575294 -381.134002) (xy 461.616485 -381.098311) (xy 461.662335 -381.068845) (xy 461.711912 -381.046203)
			(xy 461.764207 -381.030848) (xy 461.818155 -381.023092) (xy 461.872657 -381.023092) (xy 461.926605 -381.030848)
			(xy 461.9789 -381.046203) (xy 462.028477 -381.068845) (xy 462.074327 -381.098311) (xy 462.115518 -381.134002)
			(xy 462.151209 -381.175193) (xy 462.180675 -381.221043) (xy 462.203317 -381.27062) (xy 462.218672 -381.322915)
			(xy 462.226428 -381.376863) (xy 462.226914 -381.404114) (xy 462.226254 -381.43621) (xy 462.215514 -381.499496)
			(xy 462.194339 -381.560095) (xy 462.179416 -381.588518) (xy 462.172625 -381.601984) (xy 462.166429 -381.631482)
			(xy 462.169113 -381.661505) (xy 462.180441 -381.689437) (xy 462.199429 -381.712847) (xy 462.224423 -381.729697)
			(xy 462.253245 -381.738518) (xy 462.268316 -381.73914) (xy 462.414112 -381.73914) (xy 462.414112 -377.799346)
			(xy 436.550308 -377.799346) (xy 435.823106 -378.526548) (xy 438.052462 -378.526548) (xy 438.056533 -378.470926)
			(xy 438.068659 -378.416489) (xy 438.088582 -378.364398) (xy 438.115878 -378.315763) (xy 438.149964 -378.27162)
			(xy 438.190113 -378.232911) (xy 438.235471 -378.20046) (xy 438.285071 -378.174959) (xy 438.337855 -378.156952)
			(xy 438.392698 -378.146822) (xy 438.448432 -378.144785) (xy 438.503869 -378.150885) (xy 438.557826 -378.164991)
			(xy 438.609155 -378.186803) (xy 438.656761 -378.215857) (xy 438.699629 -378.251532) (xy 438.736846 -378.293069)
			(xy 438.767619 -378.339582) (xy 438.791291 -378.390079) (xy 438.807359 -378.443486) (xy 438.815479 -378.498662)
			(xy 438.815988 -378.526548) (xy 438.815479 -378.554434) (xy 438.807359 -378.60961) (xy 438.791291 -378.663017)
			(xy 438.767619 -378.713514) (xy 438.736846 -378.760027) (xy 438.699629 -378.801564) (xy 438.656761 -378.837239)
			(xy 438.609155 -378.866293) (xy 438.557826 -378.888105) (xy 438.503869 -378.902211) (xy 438.448432 -378.908311)
			(xy 438.392698 -378.906274) (xy 438.337855 -378.896144) (xy 438.285071 -378.878137) (xy 438.235471 -378.852636)
			(xy 438.190113 -378.820185) (xy 438.149964 -378.781476) (xy 438.115878 -378.737333) (xy 438.088582 -378.688698)
			(xy 438.068659 -378.636607) (xy 438.056533 -378.58217) (xy 438.052462 -378.526548) (xy 435.823106 -378.526548)
			(xy 435.614826 -378.734828) (xy 435.589269 -378.759693) (xy 435.533506 -378.804138) (xy 435.473116 -378.842059)
			(xy 435.40886 -378.872977) (xy 435.341544 -378.896504) (xy 435.272018 -378.912344) (xy 435.201154 -378.920297)
			(xy 435.1655 -378.920756) (xy 434.127656 -378.920756) (xy 433.378992 -379.669548) (xy 460.297782 -379.669548)
			(xy 460.301853 -379.613926) (xy 460.313979 -379.559489) (xy 460.333902 -379.507398) (xy 460.361198 -379.458763)
			(xy 460.395284 -379.41462) (xy 460.435433 -379.375911) (xy 460.480791 -379.34346) (xy 460.530391 -379.317959)
			(xy 460.583175 -379.299952) (xy 460.638018 -379.289822) (xy 460.693752 -379.287785) (xy 460.749189 -379.293885)
			(xy 460.803146 -379.307991) (xy 460.854475 -379.329803) (xy 460.902081 -379.358857) (xy 460.944949 -379.394532)
			(xy 460.982166 -379.436069) (xy 461.012939 -379.482582) (xy 461.036611 -379.533079) (xy 461.052679 -379.586486)
			(xy 461.060799 -379.641662) (xy 461.061308 -379.669548) (xy 461.060799 -379.697434) (xy 461.052679 -379.75261)
			(xy 461.036611 -379.806017) (xy 461.012939 -379.856514) (xy 460.982166 -379.903027) (xy 460.944949 -379.944564)
			(xy 460.902081 -379.980239) (xy 460.854475 -380.009293) (xy 460.803146 -380.031105) (xy 460.749189 -380.045211)
			(xy 460.693752 -380.051311) (xy 460.638018 -380.049274) (xy 460.583175 -380.039144) (xy 460.530391 -380.021137)
			(xy 460.480791 -379.995636) (xy 460.435433 -379.963185) (xy 460.395284 -379.924476) (xy 460.361198 -379.880333)
			(xy 460.333902 -379.831698) (xy 460.313979 -379.779607) (xy 460.301853 -379.72517) (xy 460.297782 -379.669548)
			(xy 433.378992 -379.669548) (xy 432.996026 -380.05258) (xy 438.059828 -380.05258) (xy 438.063899 -379.996958)
			(xy 438.076025 -379.942521) (xy 438.095948 -379.89043) (xy 438.123244 -379.841795) (xy 438.15733 -379.797652)
			(xy 438.197479 -379.758943) (xy 438.242837 -379.726492) (xy 438.292437 -379.700991) (xy 438.345221 -379.682984)
			(xy 438.400064 -379.672854) (xy 438.455798 -379.670817) (xy 438.511235 -379.676917) (xy 438.565192 -379.691023)
			(xy 438.616521 -379.712835) (xy 438.664127 -379.741889) (xy 438.706995 -379.777564) (xy 438.744212 -379.819101)
			(xy 438.774985 -379.865614) (xy 438.798657 -379.916111) (xy 438.814725 -379.969518) (xy 438.822845 -380.024694)
			(xy 438.823354 -380.05258) (xy 438.822845 -380.080466) (xy 438.814725 -380.135642) (xy 438.798657 -380.189049)
			(xy 438.774985 -380.239546) (xy 438.744212 -380.286059) (xy 438.706995 -380.327596) (xy 438.664127 -380.363271)
			(xy 438.616521 -380.392325) (xy 438.565192 -380.414137) (xy 438.511235 -380.428243) (xy 438.455798 -380.434343)
			(xy 438.400064 -380.432306) (xy 438.345221 -380.422176) (xy 438.292437 -380.404169) (xy 438.242837 -380.378668)
			(xy 438.197479 -380.346217) (xy 438.15733 -380.307508) (xy 438.123244 -380.263365) (xy 438.095948 -380.21473)
			(xy 438.076025 -380.162639) (xy 438.063899 -380.108202) (xy 438.059828 -380.05258) (xy 432.996026 -380.05258)
			(xy 432.645058 -380.403608) (xy 432.645058 -380.807468) (xy 432.645509 -380.820935) (xy 432.652627 -380.846914)
			(xy 432.666297 -380.870124) (xy 432.685564 -380.888948) (xy 432.709086 -380.902072) (xy 432.735224 -380.908584)
			(xy 432.762155 -380.908027) (xy 432.788001 -380.900442) (xy 432.799744 -380.893828) (xy 432.822391 -380.880439)
			(xy 432.870583 -380.859333) (xy 432.921218 -380.845052) (xy 432.973336 -380.837866) (xy 432.999642 -380.83744)
			(xy 433.026888 -380.837929) (xy 433.080824 -380.845689) (xy 433.133107 -380.861046) (xy 433.182673 -380.883687)
			(xy 433.228512 -380.913151) (xy 433.269692 -380.948838) (xy 433.305375 -380.990021) (xy 433.334833 -381.035864)
			(xy 433.357468 -381.085432) (xy 433.37282 -381.137717) (xy 433.380574 -381.191654) (xy 433.380574 -381.246146)
			(xy 433.37282 -381.300083) (xy 433.357468 -381.352368) (xy 433.334833 -381.401936) (xy 433.305375 -381.447779)
			(xy 433.269692 -381.488962) (xy 433.228512 -381.524649) (xy 433.182673 -381.554113) (xy 433.133107 -381.576754)
			(xy 433.080824 -381.592111) (xy 433.026888 -381.599871) (xy 432.999642 -381.600456) (xy 432.973336 -381.600032)
			(xy 432.921219 -381.592841) (xy 432.870583 -381.578561) (xy 432.822388 -381.557463) (xy 432.799744 -381.544068)
			(xy 432.788042 -381.537389) (xy 432.762191 -381.529824) (xy 432.735261 -381.529284) (xy 432.709128 -381.535809)
			(xy 432.685612 -381.548943) (xy 432.666351 -381.567772) (xy 432.652686 -381.590983) (xy 432.64557 -381.616962)
			(xy 432.645058 -381.630428) (xy 432.645058 -382.524553) (xy 437.679785 -382.524553) (xy 437.679785 -382.470047)
			(xy 437.687543 -382.416096) (xy 437.7029 -382.363799) (xy 437.725544 -382.31422) (xy 437.755014 -382.268368)
			(xy 437.79071 -382.227177) (xy 437.831905 -382.191487) (xy 437.87776 -382.162022) (xy 437.927342 -382.139384)
			(xy 437.979641 -382.124033) (xy 438.033593 -382.116282) (xy 438.060846 -382.115822) (xy 438.090076 -382.11638)
			(xy 438.147851 -382.125317) (xy 438.203586 -382.142959) (xy 438.25598 -382.168894) (xy 438.303805 -382.202516)
			(xy 438.345945 -382.243038) (xy 438.364122 -382.265936) (xy 438.37256 -382.276333) (xy 438.393764 -382.29267)
			(xy 438.418483 -382.302943) (xy 438.445021 -382.306448) (xy 438.471559 -382.302943) (xy 438.496278 -382.29267)
			(xy 438.517482 -382.276333) (xy 438.52592 -382.265936) (xy 438.544107 -382.243043) (xy 438.586231 -382.2025)
			(xy 438.634051 -382.168863) (xy 438.686444 -382.14292) (xy 438.742184 -382.125279) (xy 438.799964 -382.116353)
			(xy 438.829196 -382.115822) (xy 438.856451 -382.116225) (xy 438.910407 -382.123982) (xy 438.962709 -382.139339)
			(xy 439.012294 -382.161983) (xy 439.058151 -382.191453) (xy 439.099348 -382.227149) (xy 439.135045 -382.268346)
			(xy 439.164515 -382.314203) (xy 439.171008 -382.32842) (xy 456.932282 -382.32842) (xy 456.936353 -382.272798)
			(xy 456.948479 -382.218361) (xy 456.968402 -382.16627) (xy 456.995698 -382.117635) (xy 457.029784 -382.073492)
			(xy 457.069933 -382.034783) (xy 457.115291 -382.002332) (xy 457.164891 -381.976831) (xy 457.217675 -381.958824)
			(xy 457.272518 -381.948694) (xy 457.328252 -381.946657) (xy 457.383689 -381.952757) (xy 457.437646 -381.966863)
			(xy 457.488975 -381.988675) (xy 457.536581 -382.017729) (xy 457.579449 -382.053404) (xy 457.616666 -382.094941)
			(xy 457.647439 -382.141454) (xy 457.671111 -382.191951) (xy 457.687179 -382.245358) (xy 457.695299 -382.300534)
			(xy 457.695808 -382.32842) (xy 457.695299 -382.356306) (xy 457.687179 -382.411482) (xy 457.678163 -382.44145)
			(xy 458.634082 -382.44145) (xy 458.638153 -382.385828) (xy 458.650279 -382.331391) (xy 458.670202 -382.2793)
			(xy 458.697498 -382.230665) (xy 458.731584 -382.186522) (xy 458.771733 -382.147813) (xy 458.817091 -382.115362)
			(xy 458.866691 -382.089861) (xy 458.919475 -382.071854) (xy 458.974318 -382.061724) (xy 459.030052 -382.059687)
			(xy 459.085489 -382.065787) (xy 459.139446 -382.079893) (xy 459.190775 -382.101705) (xy 459.238381 -382.130759)
			(xy 459.281249 -382.166434) (xy 459.318466 -382.207971) (xy 459.349239 -382.254484) (xy 459.372911 -382.304981)
			(xy 459.388979 -382.358388) (xy 459.397099 -382.413564) (xy 459.397608 -382.44145) (xy 459.397099 -382.469336)
			(xy 459.388979 -382.524512) (xy 459.372911 -382.577919) (xy 459.349239 -382.628416) (xy 459.318466 -382.674929)
			(xy 459.281249 -382.716466) (xy 459.238381 -382.752141) (xy 459.190775 -382.781195) (xy 459.139446 -382.803007)
			(xy 459.085489 -382.817113) (xy 459.030052 -382.823213) (xy 458.974318 -382.821176) (xy 458.919475 -382.811046)
			(xy 458.866691 -382.793039) (xy 458.817091 -382.767538) (xy 458.771733 -382.735087) (xy 458.731584 -382.696378)
			(xy 458.697498 -382.652235) (xy 458.670202 -382.6036) (xy 458.650279 -382.551509) (xy 458.638153 -382.497072)
			(xy 458.634082 -382.44145) (xy 457.678163 -382.44145) (xy 457.671111 -382.464889) (xy 457.647439 -382.515386)
			(xy 457.616666 -382.561899) (xy 457.579449 -382.603436) (xy 457.536581 -382.639111) (xy 457.488975 -382.668165)
			(xy 457.437646 -382.689977) (xy 457.383689 -382.704083) (xy 457.328252 -382.710183) (xy 457.272518 -382.708146)
			(xy 457.217675 -382.698016) (xy 457.164891 -382.680009) (xy 457.115291 -382.654508) (xy 457.069933 -382.622057)
			(xy 457.029784 -382.583348) (xy 456.995698 -382.539205) (xy 456.968402 -382.49057) (xy 456.948479 -382.438479)
			(xy 456.936353 -382.384042) (xy 456.932282 -382.32842) (xy 439.171008 -382.32842) (xy 439.18716 -382.363787)
			(xy 439.202517 -382.416089) (xy 439.210275 -382.470045) (xy 439.210275 -382.524555) (xy 439.202517 -382.578511)
			(xy 439.18716 -382.630813) (xy 439.164515 -382.680397) (xy 439.135045 -382.726254) (xy 439.099348 -382.767451)
			(xy 439.058151 -382.803147) (xy 439.012294 -382.832617) (xy 438.962709 -382.855261) (xy 438.910407 -382.870618)
			(xy 438.856451 -382.878375) (xy 438.829196 -382.878838) (xy 438.799966 -382.878266) (xy 438.742192 -382.869334)
			(xy 438.686456 -382.851696) (xy 438.634062 -382.825763) (xy 438.586236 -382.792143) (xy 438.544097 -382.751622)
			(xy 438.52592 -382.728724) (xy 438.517509 -382.718283) (xy 438.496323 -382.701865) (xy 438.471591 -382.691536)
			(xy 438.445021 -382.688012) (xy 438.418451 -382.691536) (xy 438.393719 -382.701865) (xy 438.372533 -382.718283)
			(xy 438.364122 -382.728724) (xy 438.345962 -382.751639) (xy 438.303829 -382.792173) (xy 438.256003 -382.825801)
			(xy 438.203604 -382.851735) (xy 438.14786 -382.869367) (xy 438.090079 -382.878283) (xy 438.060846 -382.878838)
			(xy 438.033593 -382.878318) (xy 437.979641 -382.870567) (xy 437.927342 -382.855216) (xy 437.87776 -382.832578)
			(xy 437.831905 -382.803113) (xy 437.79071 -382.767423) (xy 437.755014 -382.726232) (xy 437.725544 -382.68038)
			(xy 437.7029 -382.630801) (xy 437.687543 -382.578504) (xy 437.679785 -382.524553) (xy 432.645058 -382.524553)
			(xy 432.645058 -382.903853) (xy 442.76693 -382.903853) (xy 442.76693 -382.849347) (xy 442.774686 -382.795396)
			(xy 442.790041 -382.743098) (xy 442.812682 -382.693518) (xy 442.842148 -382.647664) (xy 442.87784 -382.606469)
			(xy 442.91903 -382.570773) (xy 442.964881 -382.541302) (xy 443.014459 -382.518656) (xy 443.066755 -382.503295)
			(xy 443.120705 -382.495533) (xy 443.147958 -382.495044) (xy 443.176875 -382.495576) (xy 443.234046 -382.5043)
			(xy 443.289245 -382.521554) (xy 443.341207 -382.546943) (xy 443.388742 -382.579885) (xy 443.430758 -382.619625)
			(xy 443.448948 -382.64211) (xy 443.458845 -382.653915) (xy 443.484169 -382.671434) (xy 443.513562 -382.68061)
			(xy 443.544354 -382.68061) (xy 443.573747 -382.671434) (xy 443.599071 -382.653915) (xy 443.608968 -382.64211)
			(xy 443.62718 -382.619644) (xy 443.669195 -382.579907) (xy 443.716725 -382.546966) (xy 443.768683 -382.521574)
			(xy 443.823877 -382.504314) (xy 443.881043 -382.495581) (xy 443.909958 -382.495044) (xy 443.937209 -382.4956)
			(xy 443.991158 -382.503351) (xy 444.043454 -382.518702) (xy 444.093034 -382.541339) (xy 444.138886 -382.570802)
			(xy 444.180079 -382.606492) (xy 444.215772 -382.64768) (xy 444.245241 -382.69353) (xy 444.267883 -382.743106)
			(xy 444.28324 -382.795401) (xy 444.290997 -382.849349) (xy 444.290997 -382.903851) (xy 444.28324 -382.957799)
			(xy 444.267883 -383.010094) (xy 444.245241 -383.05967) (xy 444.215772 -383.10552) (xy 444.180079 -383.146708)
			(xy 444.138886 -383.182398) (xy 444.093034 -383.211861) (xy 444.043454 -383.234498) (xy 443.991158 -383.249849)
			(xy 443.937209 -383.2576) (xy 443.909958 -383.25806) (xy 443.881042 -383.257515) (xy 443.823871 -383.248794)
			(xy 443.768672 -383.231542) (xy 443.71671 -383.206156) (xy 443.669176 -383.173216) (xy 443.627158 -383.133478)
			(xy 443.608968 -383.110994) (xy 443.599071 -383.099189) (xy 443.573747 -383.08167) (xy 443.544354 -383.072494)
			(xy 443.513562 -383.072494) (xy 443.484169 -383.08167) (xy 443.458845 -383.099189) (xy 443.448948 -383.110994)
			(xy 443.430728 -383.133453) (xy 443.388715 -383.17319) (xy 443.341186 -383.206132) (xy 443.28923 -383.231525)
			(xy 443.234038 -383.248786) (xy 443.176872 -383.257522) (xy 443.147958 -383.25806) (xy 443.120705 -383.257667)
			(xy 443.066755 -383.249905) (xy 443.014459 -383.234544) (xy 442.964881 -383.211898) (xy 442.91903 -383.182427)
			(xy 442.87784 -383.146731) (xy 442.842148 -383.105536) (xy 442.812682 -383.059682) (xy 442.790041 -383.010102)
			(xy 442.774686 -382.957804) (xy 442.76693 -382.903853) (xy 432.645058 -382.903853) (xy 432.645058 -384.569253)
			(xy 437.679785 -384.569253) (xy 437.679785 -384.514747) (xy 437.687543 -384.460796) (xy 437.7029 -384.408499)
			(xy 437.725544 -384.35892) (xy 437.755014 -384.313068) (xy 437.79071 -384.271877) (xy 437.831905 -384.236187)
			(xy 437.87776 -384.206722) (xy 437.927342 -384.184084) (xy 437.979641 -384.168733) (xy 438.033593 -384.160982)
			(xy 438.060846 -384.160522) (xy 438.090076 -384.16108) (xy 438.147851 -384.170017) (xy 438.203586 -384.187659)
			(xy 438.25598 -384.213594) (xy 438.303805 -384.247216) (xy 438.345945 -384.287738) (xy 438.364122 -384.310636)
			(xy 438.37256 -384.321033) (xy 438.393764 -384.33737) (xy 438.418483 -384.347643) (xy 438.445021 -384.351148)
			(xy 438.471559 -384.347643) (xy 438.496278 -384.33737) (xy 438.517482 -384.321033) (xy 438.52592 -384.310636)
			(xy 438.544107 -384.287743) (xy 438.586231 -384.2472) (xy 438.634051 -384.213563) (xy 438.686444 -384.18762)
			(xy 438.742184 -384.169979) (xy 438.799964 -384.161053) (xy 438.829196 -384.160522) (xy 438.856451 -384.160925)
			(xy 438.910407 -384.168682) (xy 438.962709 -384.184039) (xy 439.012294 -384.206683) (xy 439.058151 -384.236153)
			(xy 439.099348 -384.271849) (xy 439.135045 -384.313046) (xy 439.164515 -384.358903) (xy 439.18716 -384.408487)
			(xy 439.202517 -384.460789) (xy 439.210275 -384.514745) (xy 439.210275 -384.569255) (xy 439.202517 -384.623211)
			(xy 439.18716 -384.675513) (xy 439.164515 -384.725097) (xy 439.135045 -384.770954) (xy 439.099348 -384.812151)
			(xy 439.058151 -384.847847) (xy 439.012294 -384.877317) (xy 438.962709 -384.899961) (xy 438.910407 -384.915318)
			(xy 438.856451 -384.923075) (xy 438.829196 -384.923538) (xy 438.799966 -384.922966) (xy 438.742192 -384.914034)
			(xy 438.686456 -384.896396) (xy 438.634062 -384.870463) (xy 438.586236 -384.836843) (xy 438.544097 -384.796322)
			(xy 438.52592 -384.773424) (xy 438.517509 -384.762983) (xy 438.496323 -384.746565) (xy 438.471591 -384.736236)
			(xy 438.445021 -384.732712) (xy 438.418451 -384.736236) (xy 438.393719 -384.746565) (xy 438.372533 -384.762983)
			(xy 438.364122 -384.773424) (xy 438.345962 -384.796339) (xy 438.303829 -384.836873) (xy 438.256003 -384.870501)
			(xy 438.203604 -384.896435) (xy 438.14786 -384.914067) (xy 438.090079 -384.922983) (xy 438.060846 -384.923538)
			(xy 438.033593 -384.923018) (xy 437.979641 -384.915267) (xy 437.927342 -384.899916) (xy 437.87776 -384.877278)
			(xy 437.831905 -384.847813) (xy 437.79071 -384.812123) (xy 437.755014 -384.770932) (xy 437.725544 -384.72508)
			(xy 437.7029 -384.675501) (xy 437.687543 -384.623204) (xy 437.679785 -384.569253) (xy 432.645058 -384.569253)
			(xy 432.645058 -385.760468) (xy 432.645509 -385.773935) (xy 432.652627 -385.799914) (xy 432.666297 -385.823124)
			(xy 432.685564 -385.841948) (xy 432.709086 -385.855072) (xy 432.735224 -385.861584) (xy 432.762155 -385.861027)
			(xy 432.788001 -385.853442) (xy 432.799744 -385.846828) (xy 432.822391 -385.833439) (xy 432.870583 -385.812333)
			(xy 432.921218 -385.798052) (xy 432.973336 -385.790866) (xy 432.999642 -385.79044) (xy 433.026888 -385.790929)
			(xy 433.080824 -385.798689) (xy 433.133107 -385.814046) (xy 433.182673 -385.836687) (xy 433.228512 -385.866151)
			(xy 433.269692 -385.901838) (xy 433.305375 -385.943021) (xy 433.334833 -385.988864) (xy 433.357468 -386.038432)
			(xy 433.37282 -386.090717) (xy 433.380574 -386.144654) (xy 433.380574 -386.199146) (xy 433.37282 -386.253083)
			(xy 433.357468 -386.305368) (xy 433.337608 -386.348858) (xy 438.101609 -386.348858) (xy 438.101609 -386.294342)
			(xy 438.109368 -386.240381) (xy 438.124728 -386.188074) (xy 438.147376 -386.138485) (xy 438.176851 -386.092624)
			(xy 438.212554 -386.051425) (xy 438.253756 -386.015727) (xy 438.29962 -385.986257) (xy 438.349211 -385.963614)
			(xy 438.40152 -385.94826) (xy 438.455482 -385.940506) (xy 438.48274 -385.940046) (xy 438.511656 -385.94059)
			(xy 438.568827 -385.949311) (xy 438.624026 -385.966563) (xy 438.675988 -385.991949) (xy 438.723523 -386.024889)
			(xy 438.76554 -386.064628) (xy 438.78373 -386.087112) (xy 438.793627 -386.098917) (xy 438.818951 -386.116436)
			(xy 438.848344 -386.125612) (xy 438.879136 -386.125612) (xy 438.908529 -386.116436) (xy 438.933853 -386.098917)
			(xy 438.94375 -386.087112) (xy 438.960503 -386.066329) (xy 438.998857 -386.029199) (xy 439.042011 -385.997777)
			(xy 439.089125 -385.972678) (xy 439.139277 -385.954392) (xy 439.191488 -385.943275) (xy 439.24474 -385.939545)
			(xy 439.297992 -385.943275) (xy 439.350203 -385.954392) (xy 439.400355 -385.972678) (xy 439.447469 -385.997777)
			(xy 439.490623 -386.029199) (xy 439.528977 -386.066329) (xy 439.54573 -386.087112) (xy 439.555627 -386.098917)
			(xy 439.580951 -386.116436) (xy 439.610344 -386.125612) (xy 439.641136 -386.125612) (xy 439.670529 -386.116436)
			(xy 439.695853 -386.098917) (xy 439.70575 -386.087112) (xy 439.722503 -386.066329) (xy 439.760857 -386.029199)
			(xy 439.804011 -385.997777) (xy 439.851125 -385.972678) (xy 439.901277 -385.954392) (xy 439.953488 -385.943275)
			(xy 440.00674 -385.939545) (xy 440.059992 -385.943275) (xy 440.112203 -385.954392) (xy 440.162355 -385.972678)
			(xy 440.209469 -385.997777) (xy 440.252623 -386.029199) (xy 440.290977 -386.066329) (xy 440.30773 -386.087112)
			(xy 440.317627 -386.098917) (xy 440.342951 -386.116436) (xy 440.372344 -386.125612) (xy 440.403136 -386.125612)
			(xy 440.432529 -386.116436) (xy 440.457853 -386.098917) (xy 440.46775 -386.087112) (xy 440.485972 -386.064655)
			(xy 440.527985 -386.024918) (xy 440.575513 -385.991975) (xy 440.627469 -385.966582) (xy 440.682661 -385.94932)
			(xy 440.739826 -385.940585) (xy 440.76874 -385.940046) (xy 440.795986 -385.940627) (xy 440.849923 -385.948387)
			(xy 440.902206 -385.963744) (xy 440.951773 -385.986384) (xy 440.997612 -386.015848) (xy 441.038793 -386.051535)
			(xy 441.074476 -386.09272) (xy 441.103935 -386.138563) (xy 441.12657 -386.188131) (xy 441.141921 -386.240416)
			(xy 441.149676 -386.294354) (xy 441.149676 -386.348846) (xy 441.141921 -386.402784) (xy 441.12657 -386.455069)
			(xy 441.103935 -386.504637) (xy 441.074476 -386.55048) (xy 441.038793 -386.591665) (xy 440.997612 -386.627352)
			(xy 440.951773 -386.656816) (xy 440.902206 -386.679456) (xy 440.849923 -386.694813) (xy 440.795986 -386.702573)
			(xy 440.76874 -386.703062) (xy 440.739823 -386.702529) (xy 440.682652 -386.693805) (xy 440.627453 -386.676551)
			(xy 440.575491 -386.651162) (xy 440.527957 -386.618221) (xy 440.48594 -386.578481) (xy 440.46775 -386.555996)
			(xy 440.457853 -386.544191) (xy 440.432529 -386.526672) (xy 440.403136 -386.517496) (xy 440.372344 -386.517496)
			(xy 440.342951 -386.526672) (xy 440.317627 -386.544191) (xy 440.30773 -386.555996) (xy 440.290977 -386.576779)
			(xy 440.252623 -386.613909) (xy 440.209469 -386.645331) (xy 440.162355 -386.67043) (xy 440.112203 -386.688716)
			(xy 440.059992 -386.699833) (xy 440.00674 -386.703563) (xy 439.953488 -386.699833) (xy 439.901277 -386.688716)
			(xy 439.851125 -386.67043) (xy 439.804011 -386.645331) (xy 439.760857 -386.613909) (xy 439.722503 -386.576779)
			(xy 439.70575 -386.555996) (xy 439.695853 -386.544191) (xy 439.670529 -386.526672) (xy 439.641136 -386.517496)
			(xy 439.610344 -386.517496) (xy 439.580951 -386.526672) (xy 439.555627 -386.544191) (xy 439.54573 -386.555996)
			(xy 439.528977 -386.576779) (xy 439.490623 -386.613909) (xy 439.447469 -386.645331) (xy 439.400355 -386.67043)
			(xy 439.350203 -386.688716) (xy 439.297992 -386.699833) (xy 439.24474 -386.703563) (xy 439.191488 -386.699833)
			(xy 439.139277 -386.688716) (xy 439.089125 -386.67043) (xy 439.042011 -386.645331) (xy 438.998857 -386.613909)
			(xy 438.960503 -386.576779) (xy 438.94375 -386.555996) (xy 438.933853 -386.544191) (xy 438.908529 -386.526672)
			(xy 438.879136 -386.517496) (xy 438.848344 -386.517496) (xy 438.818951 -386.526672) (xy 438.793627 -386.544191)
			(xy 438.78373 -386.555996) (xy 438.765521 -386.578464) (xy 438.723505 -386.618201) (xy 438.675974 -386.651142)
			(xy 438.624016 -386.676533) (xy 438.568822 -386.693792) (xy 438.511655 -386.702525) (xy 438.48274 -386.703062)
			(xy 438.455482 -386.702694) (xy 438.40152 -386.69494) (xy 438.349211 -386.679586) (xy 438.29962 -386.656943)
			(xy 438.253756 -386.627473) (xy 438.212554 -386.591775) (xy 438.176851 -386.550576) (xy 438.147376 -386.504715)
			(xy 438.124728 -386.455126) (xy 438.109368 -386.402819) (xy 438.101609 -386.348858) (xy 433.337608 -386.348858)
			(xy 433.334833 -386.354936) (xy 433.305375 -386.400779) (xy 433.269692 -386.441962) (xy 433.228512 -386.477649)
			(xy 433.182673 -386.507113) (xy 433.133107 -386.529754) (xy 433.080824 -386.545111) (xy 433.026888 -386.552871)
			(xy 432.999642 -386.553456) (xy 432.973336 -386.553032) (xy 432.921219 -386.545841) (xy 432.870583 -386.531561)
			(xy 432.822388 -386.510463) (xy 432.799744 -386.497068) (xy 432.788042 -386.490389) (xy 432.762191 -386.482824)
			(xy 432.735261 -386.482284) (xy 432.709128 -386.488809) (xy 432.685612 -386.501943) (xy 432.666351 -386.520772)
			(xy 432.652686 -386.543983) (xy 432.64557 -386.569962) (xy 432.645058 -386.583428) (xy 432.645058 -387.371153)
			(xy 442.672159 -387.371153) (xy 442.672159 -387.316647) (xy 442.679917 -387.262695) (xy 442.695273 -387.210396)
			(xy 442.717917 -387.160816) (xy 442.747386 -387.114962) (xy 442.783081 -387.07377) (xy 442.824275 -387.038076)
			(xy 442.87013 -387.008609) (xy 442.919711 -386.985968) (xy 442.972011 -386.970613) (xy 443.025963 -386.962858)
			(xy 443.053216 -386.962396) (xy 443.082132 -386.962938) (xy 443.139304 -386.971657) (xy 443.194504 -386.988908)
			(xy 443.246467 -387.014295) (xy 443.294001 -387.047236) (xy 443.336017 -387.086977) (xy 443.354206 -387.109462)
			(xy 443.364103 -387.121267) (xy 443.389427 -387.138786) (xy 443.41882 -387.147962) (xy 443.449612 -387.147962)
			(xy 443.479005 -387.138786) (xy 443.504329 -387.121267) (xy 443.514226 -387.109462) (xy 443.532393 -387.086958)
			(xy 443.574419 -387.047226) (xy 443.621959 -387.01429) (xy 443.673925 -386.988906) (xy 443.729126 -386.971654)
			(xy 443.786299 -386.962929) (xy 443.815216 -386.962396) (xy 443.842467 -386.962875) (xy 443.896413 -386.970633)
			(xy 443.948707 -386.98599) (xy 443.998282 -387.008632) (xy 444.044131 -387.038099) (xy 444.08532 -387.073791)
			(xy 444.12101 -387.114981) (xy 444.150475 -387.160832) (xy 444.173116 -387.210408) (xy 444.18847 -387.262702)
			(xy 444.191125 -387.281166) (xy 455.690476 -387.281166) (xy 455.694547 -387.225544) (xy 455.706673 -387.171107)
			(xy 455.726596 -387.119016) (xy 455.753892 -387.070381) (xy 455.787978 -387.026238) (xy 455.828127 -386.987529)
			(xy 455.873485 -386.955078) (xy 455.923085 -386.929577) (xy 455.975869 -386.91157) (xy 456.030712 -386.90144)
			(xy 456.086446 -386.899403) (xy 456.141883 -386.905503) (xy 456.19584 -386.919609) (xy 456.247169 -386.941421)
			(xy 456.294775 -386.970475) (xy 456.337643 -387.00615) (xy 456.37486 -387.047687) (xy 456.405633 -387.0942)
			(xy 456.429305 -387.144697) (xy 456.445373 -387.198104) (xy 456.453493 -387.25328) (xy 456.454002 -387.281166)
			(xy 456.453493 -387.309052) (xy 456.445373 -387.364228) (xy 456.429305 -387.417635) (xy 456.405633 -387.468132)
			(xy 456.37486 -387.514645) (xy 456.337643 -387.556182) (xy 456.294775 -387.591857) (xy 456.247169 -387.620911)
			(xy 456.19584 -387.642723) (xy 456.141883 -387.656829) (xy 456.086446 -387.662929) (xy 456.030712 -387.660892)
			(xy 455.975869 -387.650762) (xy 455.923085 -387.632755) (xy 455.873485 -387.607254) (xy 455.828127 -387.574803)
			(xy 455.787978 -387.536094) (xy 455.753892 -387.491951) (xy 455.726596 -387.443316) (xy 455.706673 -387.391225)
			(xy 455.694547 -387.336788) (xy 455.690476 -387.281166) (xy 444.191125 -387.281166) (xy 444.196226 -387.316649)
			(xy 444.196226 -387.371151) (xy 444.18847 -387.425098) (xy 444.173116 -387.477392) (xy 444.150475 -387.526968)
			(xy 444.12101 -387.572819) (xy 444.08532 -387.614009) (xy 444.044131 -387.649701) (xy 443.998282 -387.679168)
			(xy 443.948707 -387.70181) (xy 443.896413 -387.717167) (xy 443.842467 -387.724925) (xy 443.815216 -387.725412)
			(xy 443.786298 -387.724916) (xy 443.729124 -387.716187) (xy 443.673923 -387.698927) (xy 443.621961 -387.673531)
			(xy 443.574428 -387.640582) (xy 443.532414 -387.600835) (xy 443.514226 -387.578346) (xy 443.504329 -387.566541)
			(xy 443.479005 -387.549022) (xy 443.449612 -387.539846) (xy 443.41882 -387.539846) (xy 443.389427 -387.549022)
			(xy 443.364103 -387.566541) (xy 443.354206 -387.578346) (xy 443.336023 -387.600836) (xy 443.294 -387.640569)
			(xy 443.246463 -387.673506) (xy 443.194501 -387.698893) (xy 443.139302 -387.716148) (xy 443.082132 -387.724877)
			(xy 443.053216 -387.725412) (xy 443.025963 -387.724942) (xy 442.972011 -387.717187) (xy 442.919711 -387.701832)
			(xy 442.87013 -387.679191) (xy 442.824275 -387.649724) (xy 442.783081 -387.61403) (xy 442.747386 -387.572838)
			(xy 442.717917 -387.526984) (xy 442.695273 -387.477404) (xy 442.679917 -387.425105) (xy 442.672159 -387.371153)
			(xy 432.645058 -387.371153) (xy 432.645058 -388.760253) (xy 438.101685 -388.760253) (xy 438.101685 -388.705747)
			(xy 438.109443 -388.651797) (xy 438.1248 -388.5995) (xy 438.147443 -388.549921) (xy 438.176913 -388.50407)
			(xy 438.212608 -388.46288) (xy 438.253802 -388.427189) (xy 438.299657 -388.397724) (xy 438.349238 -388.375086)
			(xy 438.401536 -388.359734) (xy 438.455487 -388.351983) (xy 438.48274 -388.351522) (xy 438.511656 -388.352075)
			(xy 438.568826 -388.360796) (xy 438.624024 -388.378046) (xy 438.675986 -388.403431) (xy 438.723521 -388.436369)
			(xy 438.765539 -388.476105) (xy 438.78373 -388.498588) (xy 438.793627 -388.510393) (xy 438.818951 -388.527912)
			(xy 438.848344 -388.537088) (xy 438.879136 -388.537088) (xy 438.908529 -388.527912) (xy 438.933853 -388.510393)
			(xy 438.94375 -388.498588) (xy 438.960503 -388.477805) (xy 438.998857 -388.440675) (xy 439.042011 -388.409253)
			(xy 439.089125 -388.384154) (xy 439.139277 -388.365868) (xy 439.191488 -388.354751) (xy 439.24474 -388.351021)
			(xy 439.297992 -388.354751) (xy 439.350203 -388.365868) (xy 439.400355 -388.384154) (xy 439.447469 -388.409253)
			(xy 439.490623 -388.440675) (xy 439.528977 -388.477805) (xy 439.54573 -388.498588) (xy 439.555627 -388.510393)
			(xy 439.580951 -388.527912) (xy 439.610344 -388.537088) (xy 439.641136 -388.537088) (xy 439.670529 -388.527912)
			(xy 439.695853 -388.510393) (xy 439.70575 -388.498588) (xy 439.722503 -388.477805) (xy 439.760857 -388.440675)
			(xy 439.804011 -388.409253) (xy 439.851125 -388.384154) (xy 439.901277 -388.365868) (xy 439.953488 -388.354751)
			(xy 440.00674 -388.351021) (xy 440.059992 -388.354751) (xy 440.112203 -388.365868) (xy 440.162355 -388.384154)
			(xy 440.209469 -388.409253) (xy 440.252623 -388.440675) (xy 440.290977 -388.477805) (xy 440.30773 -388.498588)
			(xy 440.317627 -388.510393) (xy 440.342951 -388.527912) (xy 440.372344 -388.537088) (xy 440.403136 -388.537088)
			(xy 440.432529 -388.527912) (xy 440.457853 -388.510393) (xy 440.46775 -388.498588) (xy 440.485966 -388.476126)
			(xy 440.527981 -388.43639) (xy 440.575511 -388.403449) (xy 440.627467 -388.378057) (xy 440.68266 -388.360796)
			(xy 440.739826 -388.352061) (xy 440.76874 -388.351522) (xy 440.795992 -388.351951) (xy 440.849939 -388.359712)
			(xy 440.902233 -388.375072) (xy 440.951809 -388.397717) (xy 440.997658 -388.427187) (xy 441.038847 -388.462881)
			(xy 441.074537 -388.504074) (xy 441.104002 -388.549926) (xy 441.126642 -388.599504) (xy 441.141996 -388.6518)
			(xy 441.149752 -388.705748) (xy 441.149752 -388.760252) (xy 441.141996 -388.8142) (xy 441.126642 -388.866496)
			(xy 441.104002 -388.916074) (xy 441.074537 -388.961926) (xy 441.038847 -389.003119) (xy 440.997658 -389.038813)
			(xy 440.951809 -389.068283) (xy 440.902233 -389.090928) (xy 440.849939 -389.106288) (xy 440.795992 -389.114049)
			(xy 440.76874 -389.114538) (xy 440.739823 -389.114015) (xy 440.682651 -389.10529) (xy 440.627451 -389.088035)
			(xy 440.575489 -389.062644) (xy 440.527955 -389.0297) (xy 440.485939 -388.989958) (xy 440.46775 -388.967472)
			(xy 440.457853 -388.955667) (xy 440.432529 -388.938148) (xy 440.403136 -388.928972) (xy 440.372344 -388.928972)
			(xy 440.342951 -388.938148) (xy 440.317627 -388.955667) (xy 440.30773 -388.967472) (xy 440.290977 -388.988255)
			(xy 440.252623 -389.025385) (xy 440.209469 -389.056807) (xy 440.162355 -389.081906) (xy 440.112203 -389.100192)
			(xy 440.059992 -389.111309) (xy 440.00674 -389.115039) (xy 439.953488 -389.111309) (xy 439.901277 -389.100192)
			(xy 439.851125 -389.081906) (xy 439.804011 -389.056807) (xy 439.760857 -389.025385) (xy 439.722503 -388.988255)
			(xy 439.70575 -388.967472) (xy 439.695853 -388.955667) (xy 439.670529 -388.938148) (xy 439.641136 -388.928972)
			(xy 439.610344 -388.928972) (xy 439.580951 -388.938148) (xy 439.555627 -388.955667) (xy 439.54573 -388.967472)
			(xy 439.528977 -388.988255) (xy 439.490623 -389.025385) (xy 439.447469 -389.056807) (xy 439.400355 -389.081906)
			(xy 439.350203 -389.100192) (xy 439.297992 -389.111309) (xy 439.24474 -389.115039) (xy 439.191488 -389.111309)
			(xy 439.139277 -389.100192) (xy 439.089125 -389.081906) (xy 439.042011 -389.056807) (xy 438.998857 -389.025385)
			(xy 438.960503 -388.988255) (xy 438.94375 -388.967472) (xy 438.933853 -388.955667) (xy 438.908529 -388.938148)
			(xy 438.879136 -388.928972) (xy 438.848344 -388.928972) (xy 438.818951 -388.938148) (xy 438.793627 -388.955667)
			(xy 438.78373 -388.967472) (xy 438.765515 -388.989935) (xy 438.723501 -389.029673) (xy 438.675971 -389.062615)
			(xy 438.624015 -389.088007) (xy 438.568821 -389.105268) (xy 438.511655 -389.114001) (xy 438.48274 -389.114538)
			(xy 438.455487 -389.114017) (xy 438.401536 -389.106266) (xy 438.349238 -389.090914) (xy 438.299657 -389.068276)
			(xy 438.253802 -389.038811) (xy 438.212608 -389.00312) (xy 438.176913 -388.96193) (xy 438.147443 -388.916079)
			(xy 438.1248 -388.8665) (xy 438.109443 -388.814203) (xy 438.101685 -388.760253) (xy 432.645058 -388.760253)
			(xy 432.645058 -391.094468) (xy 432.645509 -391.107935) (xy 432.652627 -391.133914) (xy 432.666297 -391.157124)
			(xy 432.685564 -391.175948) (xy 432.709086 -391.189072) (xy 432.735224 -391.195584) (xy 432.762155 -391.195027)
			(xy 432.788001 -391.187442) (xy 432.799744 -391.180828) (xy 432.822391 -391.167439) (xy 432.870583 -391.146333)
			(xy 432.921218 -391.132052) (xy 432.973336 -391.124866) (xy 432.999642 -391.12444) (xy 433.026888 -391.124929)
			(xy 433.080824 -391.132689) (xy 433.133107 -391.148046) (xy 433.182673 -391.170687) (xy 433.228512 -391.200151)
			(xy 433.269692 -391.235838) (xy 433.305375 -391.277021) (xy 433.334833 -391.322864) (xy 433.357468 -391.372432)
			(xy 433.37282 -391.424717) (xy 433.380574 -391.478654) (xy 433.380574 -391.533146) (xy 433.37282 -391.587083)
			(xy 433.357468 -391.639368) (xy 433.334833 -391.688936) (xy 433.305375 -391.734779) (xy 433.269692 -391.775962)
			(xy 433.228512 -391.811649) (xy 433.182673 -391.841113) (xy 433.133107 -391.863754) (xy 433.080824 -391.879111)
			(xy 433.026888 -391.886871) (xy 432.999642 -391.887456) (xy 432.973336 -391.887032) (xy 432.921219 -391.879841)
			(xy 432.870583 -391.865561) (xy 432.822388 -391.844463) (xy 432.799744 -391.831068) (xy 432.788042 -391.824389)
			(xy 432.762191 -391.816824) (xy 432.735261 -391.816284) (xy 432.709128 -391.822809) (xy 432.685612 -391.835943)
			(xy 432.666351 -391.854772) (xy 432.652686 -391.877983) (xy 432.64557 -391.903962) (xy 432.645058 -391.917428)
			(xy 432.645058 -393.67079) (xy 432.65979 -393.685776) (xy 434.970428 -395.996414) (xy 434.985414 -396.011146)
			(xy 465.30133 -396.011146)
		)
		(stroke
			(width 0)
			(type solid)
		)
		(fill yes)
		(layer "In2.Cu")
		(net "GND")
	)
	(gr_poly
		(pts
			(xy 185.42254 -33.978088) (xy 185.42254 -33.885124) (xy 185.422121 -33.875537) (xy 185.415058 -33.857711)
			(xy 185.401948 -33.843719) (xy 185.384618 -33.835514) (xy 185.365486 -33.834239) (xy 185.347221 -33.840074)
			(xy 185.339482 -33.845754) (xy 185.31897 -33.861962) (xy 185.274353 -33.889206) (xy 185.226432 -33.910102)
			(xy 185.176107 -33.924258) (xy 185.124321 -33.931408) (xy 185.098182 -33.93186) (xy 185.070931 -33.931395)
			(xy 185.016985 -33.923636) (xy 184.964692 -33.908278) (xy 184.915117 -33.885634) (xy 184.86927 -33.856165)
			(xy 184.828083 -33.82047) (xy 184.792396 -33.779277) (xy 184.762935 -33.733425) (xy 184.740299 -33.683846)
			(xy 184.72495 -33.631551) (xy 184.7172 -33.577603) (xy 184.716674 -33.550352) (xy 184.717093 -33.524032)
			(xy 184.724289 -33.471887) (xy 184.738592 -33.421229) (xy 184.759731 -33.373021) (xy 184.787303 -33.328181)
			(xy 184.820783 -33.287562) (xy 184.839864 -33.269428) (xy 184.849881 -33.259618) (xy 184.86457 -33.235749)
			(xy 184.8722 -33.208781) (xy 184.872191 -33.180754) (xy 184.864544 -33.153791) (xy 184.849839 -33.129932)
			(xy 184.839864 -33.120076) (xy 184.820804 -33.101926) (xy 184.78735 -33.061294) (xy 184.759794 -33.016452)
			(xy 184.738658 -32.96825) (xy 184.724343 -32.917602) (xy 184.717121 -32.865468) (xy 184.716674 -32.839152)
			(xy 184.717157 -32.811576) (xy 184.725093 -32.756999) (xy 184.740806 -32.704134) (xy 184.763969 -32.654083)
			(xy 184.794099 -32.607889) (xy 184.830568 -32.566517) (xy 184.851294 -32.548322) (xy 184.862185 -32.538424)
			(xy 184.878244 -32.513778) (xy 184.886617 -32.485577) (xy 184.886608 -32.456161) (xy 184.878218 -32.427966)
			(xy 184.862143 -32.403329) (xy 184.851294 -32.393382) (xy 184.830591 -32.375164) (xy 184.794131 -32.333791)
			(xy 184.764007 -32.2876) (xy 184.740844 -32.237554) (xy 184.725127 -32.184696) (xy 184.717182 -32.130125)
			(xy 184.716674 -32.102552) (xy 184.717177 -32.074464) (xy 184.725426 -32.018896) (xy 184.741739 -31.96514)
			(xy 184.765761 -31.914358) (xy 184.780936 -31.890716) (xy 184.80405 -31.855918) (xy 182.290466 -29.342334)
			(xy 182.280168 -29.332657) (xy 182.255505 -29.318882) (xy 182.228013 -29.312387) (xy 182.199794 -29.313671)
			(xy 182.173004 -29.322634) (xy 182.149694 -29.33859) (xy 182.140352 -29.349192) (xy 182.129637 -29.361803)
			(xy 182.106363 -29.38533) (xy 182.09387 -29.396182) (xy 182.082969 -29.406082) (xy 182.066888 -29.430737)
			(xy 182.058496 -29.458951) (xy 182.058487 -29.488387) (xy 182.066862 -29.516606) (xy 182.082927 -29.541271)
			(xy 182.09387 -29.551122) (xy 182.114575 -29.569339) (xy 182.151037 -29.610711) (xy 182.181164 -29.656901)
			(xy 182.204328 -29.706948) (xy 182.220047 -29.759807) (xy 182.227992 -29.814379) (xy 182.22849 -29.841952)
			(xy 182.22803 -29.869207) (xy 182.220278 -29.923162) (xy 182.204926 -29.975464) (xy 182.182286 -30.025049)
			(xy 182.152819 -30.070907) (xy 182.117125 -30.112104) (xy 182.075931 -30.147801) (xy 182.030076 -30.177272)
			(xy 181.980493 -30.199916) (xy 181.928191 -30.215272) (xy 181.874237 -30.223028) (xy 181.846982 -30.22346)
			(xy 181.819725 -30.222973) (xy 181.765765 -30.215213) (xy 181.713459 -30.199855) (xy 181.66387 -30.17721)
			(xy 181.618008 -30.14774) (xy 181.576805 -30.112044) (xy 181.541102 -30.070848) (xy 181.525926 -30.0482)
			(xy 181.517645 -30.036273) (xy 181.495709 -30.017269) (xy 181.469309 -30.005214) (xy 181.440582 -30.001084)
			(xy 181.411855 -30.005214) (xy 181.385455 -30.017269) (xy 181.363519 -30.036273) (xy 181.355238 -30.0482)
			(xy 181.340083 -30.070861) (xy 181.304368 -30.112046) (xy 181.263159 -30.147734) (xy 181.217293 -30.177198)
			(xy 181.167703 -30.19984) (xy 181.115397 -30.215199) (xy 181.061439 -30.222964) (xy 181.034182 -30.22346)
			(xy 181.006931 -30.222995) (xy 180.952985 -30.215236) (xy 180.900692 -30.199878) (xy 180.851117 -30.177234)
			(xy 180.80527 -30.147765) (xy 180.764083 -30.11207) (xy 180.728396 -30.070877) (xy 180.698935 -30.025025)
			(xy 180.676299 -29.975446) (xy 180.66095 -29.923151) (xy 180.6532 -29.869203) (xy 180.652674 -29.841952)
			(xy 180.653157 -29.814376) (xy 180.661093 -29.759799) (xy 180.676806 -29.706934) (xy 180.699969 -29.656883)
			(xy 180.730099 -29.610689) (xy 180.766568 -29.569317) (xy 180.787294 -29.551122) (xy 180.798185 -29.541224)
			(xy 180.814244 -29.516578) (xy 180.822617 -29.488377) (xy 180.822608 -29.458961) (xy 180.814218 -29.430766)
			(xy 180.798143 -29.406129) (xy 180.787294 -29.396182) (xy 180.766591 -29.377964) (xy 180.730131 -29.336591)
			(xy 180.700007 -29.2904) (xy 180.676844 -29.240354) (xy 180.661127 -29.187496) (xy 180.653182 -29.132925)
			(xy 180.652674 -29.105352) (xy 180.653163 -29.078103) (xy 180.660925 -29.024159) (xy 180.676284 -28.971869)
			(xy 180.698928 -28.922297) (xy 180.728395 -28.876451) (xy 180.764086 -28.835265) (xy 180.805275 -28.799577)
			(xy 180.851123 -28.770113) (xy 180.900697 -28.747474) (xy 180.952988 -28.732119) (xy 181.006932 -28.724361)
			(xy 181.034182 -28.723844) (xy 181.06144 -28.724329) (xy 181.115403 -28.732084) (xy 181.167713 -28.747439)
			(xy 181.217305 -28.770081) (xy 181.263171 -28.799549) (xy 181.304377 -28.835245) (xy 181.340085 -28.87644)
			(xy 181.355238 -28.899104) (xy 181.363519 -28.911031) (xy 181.385455 -28.930035) (xy 181.411855 -28.94209)
			(xy 181.440582 -28.94622) (xy 181.469309 -28.94209) (xy 181.495709 -28.930035) (xy 181.517645 -28.911031)
			(xy 181.525926 -28.899104) (xy 181.542197 -28.87481) (xy 181.580981 -28.831057) (xy 181.603142 -28.811982)
			(xy 181.613738 -28.802622) (xy 181.629738 -28.779327) (xy 181.63873 -28.752534) (xy 181.640023 -28.724303)
			(xy 181.633517 -28.696801) (xy 181.619712 -28.672142) (xy 181.61 -28.661868) (xy 179.009294 -26.061162)
			(xy 178.99884 -26.051434) (xy 178.973826 -26.037682) (xy 178.945985 -26.031388) (xy 178.917488 -26.033043)
			(xy 178.890562 -26.042517) (xy 178.867308 -26.059071) (xy 178.849543 -26.081413) (xy 178.843686 -26.094436)
			(xy 178.832139 -26.12106) (xy 178.802176 -26.170756) (xy 178.765033 -26.215342) (xy 178.721566 -26.253787)
			(xy 178.672777 -26.285207) (xy 178.619794 -26.308876) (xy 178.563837 -26.324247) (xy 178.535076 -26.328116)
			(xy 178.52146 -26.330194) (xy 178.495984 -26.34063) (xy 178.474218 -26.35749) (xy 178.457744 -26.379549)
			(xy 178.447758 -26.405205) (xy 178.444985 -26.432597) (xy 178.449625 -26.459735) (xy 178.455066 -26.472388)
			(xy 178.466556 -26.497929) (xy 178.482754 -26.55154) (xy 178.490923 -26.606945) (xy 178.491388 -26.634948)
			(xy 178.490902 -26.662199) (xy 178.483146 -26.716147) (xy 178.467791 -26.768442) (xy 178.445149 -26.818019)
			(xy 178.415683 -26.863869) (xy 178.379992 -26.90506) (xy 178.338801 -26.940751) (xy 178.292951 -26.970217)
			(xy 178.243374 -26.992859) (xy 178.191079 -27.008214) (xy 178.137131 -27.01597) (xy 178.082629 -27.01597)
			(xy 178.028681 -27.008214) (xy 177.976386 -26.992859) (xy 177.926809 -26.970217) (xy 177.880959 -26.940751)
			(xy 177.839768 -26.90506) (xy 177.804077 -26.863869) (xy 177.774611 -26.818019) (xy 177.751969 -26.768442)
			(xy 177.736614 -26.716147) (xy 177.728858 -26.662199) (xy 177.728372 -26.634948) (xy 177.72887 -26.606623)
			(xy 177.73721 -26.55059) (xy 177.753744 -26.496406) (xy 177.765456 -26.47061) (xy 177.771021 -26.457987)
			(xy 177.775883 -26.430844) (xy 177.773295 -26.403391) (xy 177.763446 -26.377635) (xy 177.747056 -26.35546)
			(xy 177.725324 -26.338486) (xy 177.699838 -26.327957) (xy 177.672464 -26.32464) (xy 177.658776 -26.326338)
			(xy 177.646076 -26.328116) (xy 177.63246 -26.330194) (xy 177.606984 -26.34063) (xy 177.585218 -26.35749)
			(xy 177.568744 -26.379549) (xy 177.558758 -26.405205) (xy 177.555985 -26.432597) (xy 177.560625 -26.459735)
			(xy 177.566066 -26.472388) (xy 177.577556 -26.497929) (xy 177.593754 -26.55154) (xy 177.601923 -26.606945)
			(xy 177.602388 -26.634948) (xy 177.601902 -26.662199) (xy 177.594146 -26.716147) (xy 177.578791 -26.768442)
			(xy 177.556149 -26.818019) (xy 177.526683 -26.863869) (xy 177.490992 -26.90506) (xy 177.449801 -26.940751)
			(xy 177.403951 -26.970217) (xy 177.354374 -26.992859) (xy 177.302079 -27.008214) (xy 177.248131 -27.01597)
			(xy 177.193629 -27.01597) (xy 177.139681 -27.008214) (xy 177.087386 -26.992859) (xy 177.037809 -26.970217)
			(xy 176.991959 -26.940751) (xy 176.950768 -26.90506) (xy 176.915077 -26.863869) (xy 176.885611 -26.818019)
			(xy 176.862969 -26.768442) (xy 176.847614 -26.716147) (xy 176.839858 -26.662199) (xy 176.839372 -26.634948)
			(xy 176.83987 -26.606623) (xy 176.84821 -26.55059) (xy 176.864744 -26.496406) (xy 176.876456 -26.47061)
			(xy 176.882021 -26.457987) (xy 176.886883 -26.430844) (xy 176.884295 -26.403391) (xy 176.874446 -26.377635)
			(xy 176.858056 -26.35546) (xy 176.836324 -26.338486) (xy 176.810838 -26.327957) (xy 176.783464 -26.32464)
			(xy 176.769776 -26.326338) (xy 176.757076 -26.328116) (xy 176.74346 -26.330194) (xy 176.717984 -26.34063)
			(xy 176.696218 -26.35749) (xy 176.679744 -26.379549) (xy 176.669758 -26.405205) (xy 176.666985 -26.432597)
			(xy 176.671625 -26.459735) (xy 176.677066 -26.472388) (xy 176.688556 -26.497929) (xy 176.704754 -26.55154)
			(xy 176.712923 -26.606945) (xy 176.713388 -26.634948) (xy 176.712902 -26.662199) (xy 176.705146 -26.716147)
			(xy 176.689791 -26.768442) (xy 176.667149 -26.818019) (xy 176.637683 -26.863869) (xy 176.601992 -26.90506)
			(xy 176.560801 -26.940751) (xy 176.514951 -26.970217) (xy 176.465374 -26.992859) (xy 176.413079 -27.008214)
			(xy 176.359131 -27.01597) (xy 176.304629 -27.01597) (xy 176.250681 -27.008214) (xy 176.198386 -26.992859)
			(xy 176.148809 -26.970217) (xy 176.102959 -26.940751) (xy 176.061768 -26.90506) (xy 176.026077 -26.863869)
			(xy 175.996611 -26.818019) (xy 175.973969 -26.768442) (xy 175.958614 -26.716147) (xy 175.950858 -26.662199)
			(xy 175.950372 -26.634948) (xy 175.950875 -26.607188) (xy 175.95893 -26.552256) (xy 175.974861 -26.499071)
			(xy 175.998333 -26.448757) (xy 176.028849 -26.402377) (xy 176.065766 -26.360909) (xy 176.108303 -26.32523)
			(xy 176.155562 -26.296092) (xy 176.206546 -26.274113) (xy 176.260176 -26.259755) (xy 176.287684 -26.25598)
			(xy 176.301293 -26.253895) (xy 176.326755 -26.243451) (xy 176.348506 -26.22659) (xy 176.364968 -26.204536)
			(xy 176.374947 -26.178888) (xy 176.377719 -26.151507) (xy 176.373083 -26.12438) (xy 176.367694 -26.111708)
			(xy 176.356205 -26.086167) (xy 176.340009 -26.032556) (xy 176.331842 -25.97715) (xy 176.331372 -25.949148)
			(xy 176.332006 -25.918508) (xy 176.341837 -25.858019) (xy 176.35093 -25.828752) (xy 176.354839 -25.815552)
			(xy 176.356229 -25.788067) (xy 176.350228 -25.761211) (xy 176.337272 -25.736932) (xy 176.318302 -25.716996)
			(xy 176.294696 -25.702851) (xy 176.26817 -25.695525) (xy 176.25441 -25.695148) (xy 174.643542 -25.695148)
			(xy 173.96206 -26.376376) (xy 173.94121 -26.396501) (xy 173.89436 -26.430603) (xy 173.842752 -26.456953)
			(xy 173.787655 -26.474903) (xy 173.730429 -26.48401) (xy 173.701456 -26.48458) (xy 173.47057 -26.48458)
			(xy 173.457274 -26.485015) (xy 173.431587 -26.491893) (xy 173.408548 -26.505172) (xy 173.389722 -26.523953)
			(xy 173.376387 -26.54696) (xy 173.369448 -26.572631) (xy 173.36897 -26.585926) (xy 173.368468 -26.613166)
			(xy 173.360685 -26.667087) (xy 173.34531 -26.719352) (xy 173.322656 -26.768899) (xy 173.293183 -26.814718)
			(xy 173.257491 -26.855878) (xy 173.216306 -26.891541) (xy 173.170467 -26.920983) (xy 173.120905 -26.943603)
			(xy 173.068629 -26.958942) (xy 173.014702 -26.966687) (xy 172.987462 -26.96718) (xy 172.961029 -26.966729)
			(xy 172.908668 -26.959431) (xy 172.857815 -26.944981) (xy 172.80944 -26.923654) (xy 172.764471 -26.895859)
			(xy 172.723765 -26.862126) (xy 172.688101 -26.8231) (xy 172.672756 -26.801572) (xy 172.663818 -26.78947)
			(xy 172.64034 -26.770682) (xy 172.612407 -26.759551) (xy 172.582442 -26.757041) (xy 172.553047 -26.763372)
			(xy 172.526772 -26.777994) (xy 172.505897 -26.799637) (xy 172.498512 -26.812748) (xy 172.486214 -26.835913)
			(xy 172.456218 -26.878936) (xy 172.420614 -26.917446) (xy 172.380072 -26.950719) (xy 172.335356 -26.978126)
			(xy 172.287308 -26.999153) (xy 172.236834 -27.013402) (xy 172.184883 -27.020605) (xy 172.15866 -27.021028)
			(xy 172.13141 -27.02054) (xy 172.077466 -27.012778) (xy 172.025175 -26.99742) (xy 171.975601 -26.974777)
			(xy 171.929754 -26.94531) (xy 171.888567 -26.909619) (xy 171.852878 -26.86843) (xy 171.823413 -26.822581)
			(xy 171.800773 -26.773007) (xy 171.785417 -26.720715) (xy 171.777659 -26.66677) (xy 171.777152 -26.63952)
			(xy 171.777211 -26.628957) (xy 171.778356 -26.607863) (xy 171.779438 -26.597356) (xy 171.780515 -26.583151)
			(xy 171.775679 -26.555089) (xy 171.763286 -26.529452) (xy 171.744298 -26.508231) (xy 171.720191 -26.493075)
			(xy 171.692837 -26.485162) (xy 171.6786 -26.48458) (xy 171.072302 -26.48458) (xy 170.59148 -26.965148)
			(xy 170.59148 -28.031948) (xy 170.743372 -28.031948) (xy 170.743858 -28.004697) (xy 170.751614 -27.950749)
			(xy 170.766969 -27.898454) (xy 170.789611 -27.848877) (xy 170.819077 -27.803027) (xy 170.854768 -27.761836)
			(xy 170.895959 -27.726145) (xy 170.941809 -27.696679) (xy 170.991386 -27.674037) (xy 171.043681 -27.658682)
			(xy 171.097629 -27.650926) (xy 171.152131 -27.650926) (xy 171.206079 -27.658682) (xy 171.258374 -27.674037)
			(xy 171.307951 -27.696679) (xy 171.353801 -27.726145) (xy 171.394992 -27.761836) (xy 171.430683 -27.803027)
			(xy 171.460149 -27.848877) (xy 171.482791 -27.898454) (xy 171.498146 -27.950749) (xy 171.505902 -28.004697)
			(xy 171.506388 -28.031948) (xy 171.505963 -28.058743) (xy 171.498451 -28.111804) (xy 171.483595 -28.163294)
			(xy 171.461687 -28.212202) (xy 171.433157 -28.257567) (xy 171.398566 -28.298498) (xy 171.37888 -28.316682)
			(xy 171.368525 -28.32644) (xy 171.3533 -28.350466) (xy 171.345303 -28.377762) (xy 171.345158 -28.406206)
			(xy 171.352875 -28.433583) (xy 171.367854 -28.457763) (xy 171.38893 -28.476865) (xy 171.401486 -28.48356)
			(xy 171.42512 -28.495655) (xy 171.469033 -28.525496) (xy 171.508381 -28.56114) (xy 171.542404 -28.601898)
			(xy 171.570445 -28.646981) (xy 171.591961 -28.695518) (xy 171.600337 -28.72486) (xy 174.124112 -28.72486)
			(xy 174.124575 -28.698208) (xy 174.132012 -28.645427) (xy 174.146724 -28.594193) (xy 174.168422 -28.545506)
			(xy 174.196685 -28.500313) (xy 174.230963 -28.459493) (xy 174.270589 -28.423841) (xy 174.31479 -28.39405)
			(xy 174.362708 -28.370701) (xy 174.413408 -28.354249) (xy 174.43958 -28.349194) (xy 174.453331 -28.346366)
			(xy 174.47862 -28.334198) (xy 174.499643 -28.315607) (xy 174.514814 -28.291997) (xy 174.522988 -28.265149)
			(xy 174.523549 -28.237091) (xy 174.516453 -28.209938) (xy 174.502236 -28.185742) (xy 174.492412 -28.175712)
			(xy 174.474221 -28.157679) (xy 174.442384 -28.117553) (xy 174.416201 -28.073528) (xy 174.396143 -28.026396)
			(xy 174.38257 -27.977005) (xy 174.375727 -27.926241) (xy 174.375318 -27.90063) (xy 174.375804 -27.873379)
			(xy 174.38356 -27.819431) (xy 174.398915 -27.767136) (xy 174.421557 -27.717559) (xy 174.451023 -27.671709)
			(xy 174.486714 -27.630518) (xy 174.527905 -27.594827) (xy 174.573755 -27.565361) (xy 174.623332 -27.542719)
			(xy 174.675627 -27.527364) (xy 174.729575 -27.519608) (xy 174.784077 -27.519608) (xy 174.838025 -27.527364)
			(xy 174.89032 -27.542719) (xy 174.939897 -27.565361) (xy 174.985747 -27.594827) (xy 175.026938 -27.630518)
			(xy 175.062629 -27.671709) (xy 175.092095 -27.717559) (xy 175.114737 -27.767136) (xy 175.130092 -27.819431)
			(xy 175.137848 -27.873379) (xy 175.138334 -27.90063) (xy 175.137803 -27.927278) (xy 175.130368 -27.980053)
			(xy 175.115661 -28.03128) (xy 175.093968 -28.079962) (xy 175.065711 -28.125152) (xy 175.031441 -28.165969)
			(xy 174.991824 -28.20162) (xy 174.947631 -28.231411) (xy 174.899722 -28.254761) (xy 174.84903 -28.271218)
			(xy 174.822866 -28.276296) (xy 174.809122 -28.279158) (xy 174.78383 -28.291316) (xy 174.762802 -28.3099)
			(xy 174.747628 -28.333506) (xy 174.739451 -28.360351) (xy 174.738891 -28.388408) (xy 174.745988 -28.415558)
			(xy 174.760208 -28.439751) (xy 174.770034 -28.449778) (xy 174.78821 -28.467826) (xy 174.820051 -28.507948)
			(xy 174.846237 -28.551969) (xy 174.866298 -28.599098) (xy 174.879873 -28.648488) (xy 174.886718 -28.699249)
			(xy 174.887128 -28.72486) (xy 174.886664 -28.751206) (xy 174.879435 -28.8034) (xy 174.865096 -28.854104)
			(xy 174.843918 -28.902353) (xy 174.816306 -28.947231) (xy 174.782782 -28.987884) (xy 174.763684 -29.006038)
			(xy 174.753683 -29.01594) (xy 174.738953 -29.039903) (xy 174.731317 -29.066975) (xy 174.731356 -29.095103)
			(xy 174.739065 -29.122154) (xy 174.753862 -29.146076) (xy 174.763938 -29.155898) (xy 174.783138 -29.17405)
			(xy 174.816857 -29.214727) (xy 174.841886 -29.255212) (xy 176.187862 -29.255212) (xy 176.188401 -29.227892)
			(xy 176.196736 -29.173892) (xy 176.213214 -29.121796) (xy 176.237447 -29.072824) (xy 176.268869 -29.028123)
			(xy 176.28743 -29.00807) (xy 176.297817 -28.996439) (xy 176.311645 -28.968509) (xy 176.316404 -28.937709)
			(xy 176.311651 -28.906908) (xy 176.297827 -28.878975) (xy 176.28743 -28.867354) (xy 176.268809 -28.847348)
			(xy 176.237352 -28.802654) (xy 176.213104 -28.753673) (xy 176.196635 -28.701559) (xy 176.188332 -28.64754)
			(xy 176.187862 -28.620212) (xy 176.18836 -28.593563) (xy 176.196303 -28.540859) (xy 176.212013 -28.489929)
			(xy 176.235139 -28.441908) (xy 176.265163 -28.397871) (xy 176.301415 -28.3588) (xy 176.343086 -28.325569)
			(xy 176.389244 -28.29892) (xy 176.438858 -28.279448) (xy 176.49082 -28.267588) (xy 176.54397 -28.263605)
			(xy 176.59712 -28.267588) (xy 176.649082 -28.279448) (xy 176.698696 -28.29892) (xy 176.744854 -28.325569)
			(xy 176.786525 -28.3588) (xy 176.822777 -28.397871) (xy 176.852801 -28.441908) (xy 176.875927 -28.489929)
			(xy 176.891637 -28.540859) (xy 176.89958 -28.593563) (xy 176.900078 -28.620212) (xy 176.89957 -28.647533)
			(xy 176.89123 -28.701536) (xy 176.874746 -28.753633) (xy 176.850505 -28.802604) (xy 176.819075 -28.847302)
			(xy 176.80051 -28.867354) (xy 176.790105 -28.878968) (xy 176.776287 -28.906905) (xy 176.771535 -28.937709)
			(xy 176.776292 -28.968511) (xy 176.790115 -28.996446) (xy 176.80051 -29.00807) (xy 176.819102 -29.028102)
			(xy 176.850561 -29.07279) (xy 176.874814 -29.121764) (xy 176.89129 -29.173872) (xy 176.899602 -29.227886)
			(xy 176.900078 -29.255212) (xy 177.087784 -29.255212) (xy 177.088317 -29.227892) (xy 177.096653 -29.173891)
			(xy 177.113131 -29.121795) (xy 177.137366 -29.072823) (xy 177.16879 -29.028123) (xy 177.187352 -29.00807)
			(xy 177.197737 -28.996438) (xy 177.211562 -28.968508) (xy 177.21632 -28.937709) (xy 177.211568 -28.906909)
			(xy 177.197747 -28.878976) (xy 177.187352 -28.867354) (xy 177.168734 -28.847345) (xy 177.137277 -28.802652)
			(xy 177.113027 -28.753672) (xy 177.096557 -28.701559) (xy 177.088254 -28.647539) (xy 177.087784 -28.620212)
			(xy 177.088282 -28.593563) (xy 177.096225 -28.540859) (xy 177.111935 -28.489929) (xy 177.135061 -28.441908)
			(xy 177.165085 -28.397871) (xy 177.201337 -28.3588) (xy 177.243008 -28.325569) (xy 177.289166 -28.29892)
			(xy 177.33878 -28.279448) (xy 177.390742 -28.267588) (xy 177.443892 -28.263605) (xy 177.497042 -28.267588)
			(xy 177.549004 -28.279448) (xy 177.598618 -28.29892) (xy 177.644776 -28.325569) (xy 177.686447 -28.3588)
			(xy 177.722699 -28.397871) (xy 177.752723 -28.441908) (xy 177.775849 -28.489929) (xy 177.791559 -28.540859)
			(xy 177.799502 -28.593563) (xy 177.8 -28.620212) (xy 177.799486 -28.647533) (xy 177.791146 -28.701535)
			(xy 177.774664 -28.753631) (xy 177.750424 -28.802603) (xy 177.718996 -28.847302) (xy 177.700432 -28.867354)
			(xy 177.690025 -28.878967) (xy 177.676204 -28.906904) (xy 177.671452 -28.937709) (xy 177.676209 -28.968512)
			(xy 177.690035 -28.996447) (xy 177.700432 -29.00807) (xy 177.719028 -29.028099) (xy 177.750485 -29.072788)
			(xy 177.774737 -29.121763) (xy 177.791213 -29.173871) (xy 177.799524 -29.227886) (xy 177.8 -29.255212)
			(xy 177.987706 -29.255212) (xy 177.988233 -29.227892) (xy 177.996569 -29.17389) (xy 178.013049 -29.121794)
			(xy 178.037285 -29.072822) (xy 178.068711 -29.028122) (xy 178.087274 -29.00807) (xy 178.097657 -28.996437)
			(xy 178.111479 -28.968507) (xy 178.116236 -28.937709) (xy 178.111485 -28.90691) (xy 178.097667 -28.878977)
			(xy 178.087274 -28.867354) (xy 178.068643 -28.847357) (xy 178.03719 -28.802659) (xy 178.012945 -28.753676)
			(xy 177.996477 -28.701561) (xy 177.988176 -28.64754) (xy 177.987706 -28.620212) (xy 177.988204 -28.593563)
			(xy 177.996147 -28.540859) (xy 178.011857 -28.489929) (xy 178.034983 -28.441908) (xy 178.065007 -28.397871)
			(xy 178.101259 -28.3588) (xy 178.14293 -28.325569) (xy 178.189088 -28.29892) (xy 178.238702 -28.279448)
			(xy 178.290664 -28.267588) (xy 178.343814 -28.263605) (xy 178.396964 -28.267588) (xy 178.448926 -28.279448)
			(xy 178.49854 -28.29892) (xy 178.544698 -28.325569) (xy 178.586369 -28.3588) (xy 178.622621 -28.397871)
			(xy 178.652645 -28.441908) (xy 178.675771 -28.489929) (xy 178.691481 -28.540859) (xy 178.699424 -28.593563)
			(xy 178.699922 -28.620212) (xy 178.699402 -28.647533) (xy 178.691063 -28.701534) (xy 178.674581 -28.75363)
			(xy 178.650344 -28.802602) (xy 178.618917 -28.847301) (xy 178.600354 -28.867354) (xy 178.589945 -28.878966)
			(xy 178.576121 -28.906903) (xy 178.571367 -28.937709) (xy 178.576126 -28.968513) (xy 178.589955 -28.996448)
			(xy 178.600354 -29.00807) (xy 178.618936 -29.028111) (xy 178.650399 -29.072795) (xy 178.674655 -29.121767)
			(xy 178.691133 -29.173873) (xy 178.699446 -29.227887) (xy 178.699922 -29.255212) (xy 178.887882 -29.255212)
			(xy 178.888415 -29.227892) (xy 178.896751 -29.173891) (xy 178.91323 -29.121795) (xy 178.937464 -29.072823)
			(xy 178.968888 -29.028123) (xy 178.98745 -29.00807) (xy 178.997835 -28.996438) (xy 179.011661 -28.968508)
			(xy 179.016419 -28.937709) (xy 179.011666 -28.906908) (xy 178.997845 -28.878976) (xy 178.98745 -28.867354)
			(xy 178.968832 -28.847345) (xy 178.937374 -28.802652) (xy 178.913125 -28.753672) (xy 178.896655 -28.701559)
			(xy 178.888352 -28.647539) (xy 178.887882 -28.620212) (xy 178.88838 -28.593563) (xy 178.896323 -28.540859)
			(xy 178.912033 -28.489929) (xy 178.935159 -28.441908) (xy 178.965183 -28.397871) (xy 179.001435 -28.3588)
			(xy 179.043106 -28.325569) (xy 179.089264 -28.29892) (xy 179.138878 -28.279448) (xy 179.19084 -28.267588)
			(xy 179.24399 -28.263605) (xy 179.29714 -28.267588) (xy 179.349102 -28.279448) (xy 179.398716 -28.29892)
			(xy 179.444874 -28.325569) (xy 179.486545 -28.3588) (xy 179.522797 -28.397871) (xy 179.552821 -28.441908)
			(xy 179.575947 -28.489929) (xy 179.591657 -28.540859) (xy 179.5996 -28.593563) (xy 179.600098 -28.620212)
			(xy 179.599585 -28.647533) (xy 179.591245 -28.701535) (xy 179.574762 -28.753632) (xy 179.550523 -28.802603)
			(xy 179.519094 -28.847302) (xy 179.50053 -28.867354) (xy 179.490123 -28.878967) (xy 179.476303 -28.906904)
			(xy 179.47155 -28.937709) (xy 179.476308 -28.968512) (xy 179.490133 -28.996447) (xy 179.50053 -29.00807)
			(xy 179.519125 -29.028099) (xy 179.550583 -29.072788) (xy 179.574835 -29.121763) (xy 179.591311 -29.173871)
			(xy 179.599622 -29.227886) (xy 179.600098 -29.255212) (xy 179.5996 -29.281861) (xy 179.591657 -29.334565)
			(xy 179.575947 -29.385495) (xy 179.552821 -29.433516) (xy 179.522797 -29.477553) (xy 179.486545 -29.516624)
			(xy 179.444874 -29.549855) (xy 179.398716 -29.576504) (xy 179.349102 -29.595976) (xy 179.29714 -29.607836)
			(xy 179.24399 -29.61182) (xy 179.19084 -29.607836) (xy 179.138878 -29.595976) (xy 179.089264 -29.576504)
			(xy 179.043106 -29.549855) (xy 179.001435 -29.516624) (xy 178.965183 -29.477553) (xy 178.935159 -29.433516)
			(xy 178.912033 -29.385495) (xy 178.896323 -29.334565) (xy 178.88838 -29.281861) (xy 178.887882 -29.255212)
			(xy 178.699922 -29.255212) (xy 178.699424 -29.281861) (xy 178.691481 -29.334565) (xy 178.675771 -29.385495)
			(xy 178.652645 -29.433516) (xy 178.622621 -29.477553) (xy 178.586369 -29.516624) (xy 178.544698 -29.549855)
			(xy 178.49854 -29.576504) (xy 178.448926 -29.595976) (xy 178.396964 -29.607836) (xy 178.343814 -29.61182)
			(xy 178.290664 -29.607836) (xy 178.238702 -29.595976) (xy 178.189088 -29.576504) (xy 178.14293 -29.549855)
			(xy 178.101259 -29.516624) (xy 178.065007 -29.477553) (xy 178.034983 -29.433516) (xy 178.011857 -29.385495)
			(xy 177.996147 -29.334565) (xy 177.988204 -29.281861) (xy 177.987706 -29.255212) (xy 177.8 -29.255212)
			(xy 177.799502 -29.281861) (xy 177.791559 -29.334565) (xy 177.775849 -29.385495) (xy 177.752723 -29.433516)
			(xy 177.722699 -29.477553) (xy 177.686447 -29.516624) (xy 177.644776 -29.549855) (xy 177.598618 -29.576504)
			(xy 177.549004 -29.595976) (xy 177.497042 -29.607836) (xy 177.443892 -29.61182) (xy 177.390742 -29.607836)
			(xy 177.33878 -29.595976) (xy 177.289166 -29.576504) (xy 177.243008 -29.549855) (xy 177.201337 -29.516624)
			(xy 177.165085 -29.477553) (xy 177.135061 -29.433516) (xy 177.111935 -29.385495) (xy 177.096225 -29.334565)
			(xy 177.088282 -29.281861) (xy 177.087784 -29.255212) (xy 176.900078 -29.255212) (xy 176.89958 -29.281861)
			(xy 176.891637 -29.334565) (xy 176.875927 -29.385495) (xy 176.852801 -29.433516) (xy 176.822777 -29.477553)
			(xy 176.786525 -29.516624) (xy 176.744854 -29.549855) (xy 176.698696 -29.576504) (xy 176.649082 -29.595976)
			(xy 176.59712 -29.607836) (xy 176.54397 -29.61182) (xy 176.49082 -29.607836) (xy 176.438858 -29.595976)
			(xy 176.389244 -29.576504) (xy 176.343086 -29.549855) (xy 176.301415 -29.516624) (xy 176.265163 -29.477553)
			(xy 176.235139 -29.433516) (xy 176.212013 -29.385495) (xy 176.196303 -29.334565) (xy 176.18836 -29.281861)
			(xy 176.187862 -29.255212) (xy 174.841886 -29.255212) (xy 174.844641 -29.259668) (xy 174.865959 -29.308012)
			(xy 174.880402 -29.358836) (xy 174.887694 -29.411166) (xy 174.888144 -29.437584) (xy 174.887658 -29.464835)
			(xy 174.879902 -29.518783) (xy 174.864547 -29.571078) (xy 174.841905 -29.620655) (xy 174.812439 -29.666505)
			(xy 174.776748 -29.707696) (xy 174.735557 -29.743387) (xy 174.689707 -29.772853) (xy 174.64013 -29.795495)
			(xy 174.587835 -29.81085) (xy 174.533887 -29.818606) (xy 174.479385 -29.818606) (xy 174.425437 -29.81085)
			(xy 174.373142 -29.795495) (xy 174.323565 -29.772853) (xy 174.277715 -29.743387) (xy 174.236524 -29.707696)
			(xy 174.200833 -29.666505) (xy 174.171367 -29.620655) (xy 174.148725 -29.571078) (xy 174.13337 -29.518783)
			(xy 174.125614 -29.464835) (xy 174.125128 -29.437584) (xy 174.125537 -29.411236) (xy 174.132774 -29.359038)
			(xy 174.147123 -29.308333) (xy 174.168311 -29.260084) (xy 174.195934 -29.215207) (xy 174.229468 -29.174558)
			(xy 174.248572 -29.156406) (xy 174.258625 -29.146554) (xy 174.273344 -29.122575) (xy 174.280968 -29.095492)
			(xy 174.280919 -29.067355) (xy 174.2732 -29.040298) (xy 174.258397 -29.016371) (xy 174.248318 -29.006546)
			(xy 174.229102 -28.98841) (xy 174.195382 -28.947731) (xy 174.167599 -28.902787) (xy 174.146283 -28.854439)
			(xy 174.131844 -28.803612) (xy 174.124558 -28.751279) (xy 174.124112 -28.72486) (xy 171.600337 -28.72486)
			(xy 171.606535 -28.746571) (xy 171.613886 -28.799152) (xy 171.614338 -28.825698) (xy 171.613852 -28.852949)
			(xy 171.606096 -28.906897) (xy 171.590741 -28.959192) (xy 171.568099 -29.008769) (xy 171.538633 -29.054619)
			(xy 171.502942 -29.09581) (xy 171.461751 -29.131501) (xy 171.415901 -29.160967) (xy 171.366324 -29.183609)
			(xy 171.314029 -29.198964) (xy 171.260081 -29.20672) (xy 171.205579 -29.20672) (xy 171.151631 -29.198964)
			(xy 171.099336 -29.183609) (xy 171.049759 -29.160967) (xy 171.003909 -29.131501) (xy 170.962718 -29.09581)
			(xy 170.927027 -29.054619) (xy 170.897561 -29.008769) (xy 170.874919 -28.959192) (xy 170.859564 -28.906897)
			(xy 170.851808 -28.852949) (xy 170.851322 -28.825698) (xy 170.851775 -28.798904) (xy 170.859281 -28.745844)
			(xy 170.874131 -28.694354) (xy 170.896034 -28.645446) (xy 170.924559 -28.600081) (xy 170.959146 -28.559149)
			(xy 170.97883 -28.540964) (xy 170.989132 -28.531154) (xy 171.004357 -28.507141) (xy 171.012357 -28.479857)
			(xy 171.012509 -28.451425) (xy 171.004802 -28.424057) (xy 170.989836 -28.399882) (xy 170.968774 -28.380782)
			(xy 170.956224 -28.374086) (xy 170.932611 -28.361952) (xy 170.888699 -28.332116) (xy 170.84935 -28.296478)
			(xy 170.815325 -28.255726) (xy 170.787282 -28.210649) (xy 170.765763 -28.162117) (xy 170.751184 -28.111069)
			(xy 170.743827 -28.058492) (xy 170.743372 -28.031948) (xy 170.59148 -28.031948) (xy 170.59148 -29.775756)
			(xy 171.211135 -29.775756) (xy 171.211135 -29.721244) (xy 171.218893 -29.667287) (xy 171.234252 -29.614983)
			(xy 171.256899 -29.565397) (xy 171.286372 -29.51954) (xy 171.322072 -29.478344) (xy 171.363272 -29.442648)
			(xy 171.409132 -29.41318) (xy 171.45872 -29.390538) (xy 171.511026 -29.375185) (xy 171.564984 -29.367432)
			(xy 171.59224 -29.366972) (xy 171.620347 -29.367487) (xy 171.675947 -29.375781) (xy 171.702984 -29.383482)
			(xy 171.716683 -29.387092) (xy 171.744997 -29.387472) (xy 171.772331 -29.380074) (xy 171.796588 -29.365464)
			(xy 171.815909 -29.344763) (xy 171.828814 -29.319557) (xy 171.832016 -29.305758) (xy 171.837518 -29.280075)
			(xy 171.854669 -29.230431) (xy 171.878468 -29.183608) (xy 171.908465 -29.140493) (xy 171.944093 -29.1019)
			(xy 171.984677 -29.068559) (xy 172.029452 -29.0411) (xy 172.077569 -29.020042) (xy 172.128121 -29.005784)
			(xy 172.18015 -28.998594) (xy 172.206412 -28.998164) (xy 172.233661 -28.998707) (xy 172.287603 -29.006464)
			(xy 172.339892 -29.021819) (xy 172.389464 -29.04446) (xy 172.43531 -29.073924) (xy 172.476496 -29.109613)
			(xy 172.512183 -29.1508) (xy 172.541646 -29.196646) (xy 172.564285 -29.246219) (xy 172.579638 -29.298509)
			(xy 172.587394 -29.352451) (xy 172.587394 -29.406949) (xy 172.579638 -29.460891) (xy 172.564285 -29.513181)
			(xy 172.541646 -29.562754) (xy 172.512183 -29.6086) (xy 172.476496 -29.649787) (xy 172.43531 -29.685476)
			(xy 172.389464 -29.71494) (xy 172.339892 -29.737581) (xy 172.287603 -29.752936) (xy 172.233661 -29.760693)
			(xy 172.206412 -29.76118) (xy 172.178305 -29.760652) (xy 172.122705 -29.752367) (xy 172.095668 -29.74467)
			(xy 172.081963 -29.741077) (xy 172.053649 -29.740684) (xy 172.026312 -29.748074) (xy 172.002053 -29.762682)
			(xy 171.982732 -29.783384) (xy 171.969833 -29.808593) (xy 171.966636 -29.822394) (xy 171.960443 -29.850915)
			(xy 171.940539 -29.905777) (xy 171.912514 -29.956969) (xy 171.877021 -30.003297) (xy 171.834887 -30.043679)
			(xy 171.787095 -30.077175) (xy 171.73476 -30.103003) (xy 171.679103 -30.120561) (xy 171.621421 -30.129438)
			(xy 171.59224 -30.129988) (xy 171.564984 -30.129568) (xy 171.511026 -30.121815) (xy 171.45872 -30.106462)
			(xy 171.409132 -30.08382) (xy 171.363272 -30.054352) (xy 171.322072 -30.018656) (xy 171.286372 -29.97746)
			(xy 171.256899 -29.931603) (xy 171.234252 -29.882017) (xy 171.218893 -29.829713) (xy 171.211135 -29.775756)
			(xy 170.59148 -29.775756) (xy 170.59148 -30.395672) (xy 171.824394 -30.395672) (xy 171.828465 -30.34005)
			(xy 171.840591 -30.285613) (xy 171.860514 -30.233522) (xy 171.88781 -30.184887) (xy 171.921896 -30.140744)
			(xy 171.962045 -30.102035) (xy 172.007403 -30.069584) (xy 172.057003 -30.044083) (xy 172.109787 -30.026076)
			(xy 172.16463 -30.015946) (xy 172.220364 -30.013909) (xy 172.275801 -30.020009) (xy 172.329758 -30.034115)
			(xy 172.381087 -30.055927) (xy 172.428693 -30.084981) (xy 172.471561 -30.120656) (xy 172.508778 -30.162193)
			(xy 172.539551 -30.208706) (xy 172.563223 -30.259203) (xy 172.579291 -30.31261) (xy 172.587411 -30.367786)
			(xy 172.58792 -30.395672) (xy 172.587411 -30.423558) (xy 172.579291 -30.478734) (xy 172.563223 -30.532141)
			(xy 172.539551 -30.582638) (xy 172.508778 -30.629151) (xy 172.471561 -30.670688) (xy 172.428693 -30.706363)
			(xy 172.381087 -30.735417) (xy 172.329758 -30.757229) (xy 172.275801 -30.771335) (xy 172.220364 -30.777435)
			(xy 172.16463 -30.775398) (xy 172.109787 -30.765268) (xy 172.057003 -30.747261) (xy 172.007403 -30.72176)
			(xy 171.962045 -30.689309) (xy 171.921896 -30.6506) (xy 171.88781 -30.606457) (xy 171.860514 -30.557822)
			(xy 171.840591 -30.505731) (xy 171.828465 -30.451294) (xy 171.824394 -30.395672) (xy 170.59148 -30.395672)
			(xy 170.59148 -30.851348) (xy 171.18638 -31.446248) (xy 176.813144 -31.446248) (xy 176.813145 -31.39174)
			(xy 176.820904 -31.337786) (xy 176.836262 -31.285486) (xy 176.858907 -31.235903) (xy 176.888378 -31.190049)
			(xy 176.924075 -31.148855) (xy 176.965271 -31.113161) (xy 177.011128 -31.083693) (xy 177.060712 -31.061052)
			(xy 177.113013 -31.045698) (xy 177.166968 -31.037943) (xy 177.221476 -31.037946) (xy 177.27543 -31.045707)
			(xy 177.327729 -31.061067) (xy 177.377311 -31.083715) (xy 177.423164 -31.113188) (xy 177.464356 -31.148886)
			(xy 177.500048 -31.190084) (xy 177.529514 -31.235942) (xy 177.552154 -31.285527) (xy 177.567506 -31.337829)
			(xy 177.575258 -31.391784) (xy 177.575718 -31.419038) (xy 177.575718 -31.428944) (xy 177.575825 -31.44294)
			(xy 177.582765 -31.470045) (xy 177.5968 -31.49425) (xy 177.616878 -31.513737) (xy 177.64149 -31.527045)
			(xy 177.66879 -31.533174) (xy 177.696728 -31.531664) (xy 177.723209 -31.522629) (xy 177.734976 -31.51505)
			(xy 177.759047 -31.498984) (xy 177.811029 -31.473548) (xy 177.866258 -31.45626) (xy 177.923464 -31.447515)
			(xy 177.9524 -31.446978) (xy 177.979653 -31.447455) (xy 178.033604 -31.455212) (xy 178.085903 -31.470569)
			(xy 178.135483 -31.493212) (xy 178.181336 -31.52268) (xy 178.222529 -31.558374) (xy 178.258223 -31.599567)
			(xy 178.287691 -31.645421) (xy 178.310333 -31.695002) (xy 178.325689 -31.7473) (xy 178.333445 -31.801252)
			(xy 178.333444 -31.855758) (xy 178.325687 -31.909709) (xy 178.312618 -31.954216) (xy 179.198014 -31.954216)
			(xy 179.202085 -31.898594) (xy 179.214211 -31.844157) (xy 179.234134 -31.792066) (xy 179.26143 -31.743431)
			(xy 179.295516 -31.699288) (xy 179.335665 -31.660579) (xy 179.381023 -31.628128) (xy 179.430623 -31.602627)
			(xy 179.483407 -31.58462) (xy 179.53825 -31.57449) (xy 179.593984 -31.572453) (xy 179.649421 -31.578553)
			(xy 179.703378 -31.592659) (xy 179.754707 -31.614471) (xy 179.802313 -31.643525) (xy 179.806794 -31.647254)
			(xy 182.48193 -31.647254) (xy 182.48193 -31.592746) (xy 182.489687 -31.538793) (xy 182.505043 -31.486493)
			(xy 182.527686 -31.436911) (xy 182.557154 -31.391056) (xy 182.592848 -31.349861) (xy 182.634041 -31.314165)
			(xy 182.679895 -31.284694) (xy 182.729476 -31.262049) (xy 182.781776 -31.246691) (xy 182.835728 -31.238931)
			(xy 182.862982 -31.238444) (xy 182.890239 -31.238938) (xy 182.944198 -31.246703) (xy 182.996504 -31.262062)
			(xy 183.046093 -31.284705) (xy 183.091959 -31.314169) (xy 183.133168 -31.349857) (xy 183.168883 -31.391043)
			(xy 183.184038 -31.413704) (xy 183.192319 -31.425631) (xy 183.214255 -31.444635) (xy 183.240655 -31.45669)
			(xy 183.269382 -31.46082) (xy 183.298109 -31.45669) (xy 183.324509 -31.444635) (xy 183.346445 -31.425631)
			(xy 183.354726 -31.413704) (xy 183.369903 -31.391057) (xy 183.405606 -31.349861) (xy 183.446808 -31.314165)
			(xy 183.49267 -31.284694) (xy 183.542259 -31.262049) (xy 183.594565 -31.246691) (xy 183.648525 -31.238931)
			(xy 183.675782 -31.238444) (xy 183.703032 -31.239002) (xy 183.756978 -31.246756) (xy 183.809272 -31.262108)
			(xy 183.858848 -31.284747) (xy 183.904698 -31.314211) (xy 183.945887 -31.3499) (xy 183.981578 -31.391088)
			(xy 184.011044 -31.436936) (xy 184.033685 -31.486511) (xy 184.04904 -31.538804) (xy 184.056797 -31.59275)
			(xy 184.056797 -31.64725) (xy 184.04904 -31.701196) (xy 184.033685 -31.753489) (xy 184.011044 -31.803064)
			(xy 183.981578 -31.848912) (xy 183.945887 -31.8901) (xy 183.904698 -31.925789) (xy 183.858848 -31.955253)
			(xy 183.809272 -31.977892) (xy 183.756978 -31.993244) (xy 183.703032 -32.000998) (xy 183.675782 -32.00146)
			(xy 183.648524 -32.000991) (xy 183.594564 -31.993222) (xy 183.542258 -31.977858) (xy 183.492668 -31.955211)
			(xy 183.446803 -31.925743) (xy 183.405595 -31.890051) (xy 183.369881 -31.848862) (xy 183.354726 -31.8262)
			(xy 183.346445 -31.814273) (xy 183.324509 -31.795269) (xy 183.298109 -31.783214) (xy 183.269382 -31.779084)
			(xy 183.240655 -31.783214) (xy 183.214255 -31.795269) (xy 183.192319 -31.814273) (xy 183.184038 -31.8262)
			(xy 183.168886 -31.848864) (xy 183.133178 -31.89006) (xy 183.091972 -31.925755) (xy 183.046106 -31.955224)
			(xy 182.996513 -31.977866) (xy 182.944203 -31.99322) (xy 182.890241 -32.000975) (xy 182.862982 -32.00146)
			(xy 182.835728 -32.001069) (xy 182.781776 -31.993309) (xy 182.729476 -31.977951) (xy 182.679895 -31.955306)
			(xy 182.634041 -31.925835) (xy 182.592848 -31.890139) (xy 182.557154 -31.848944) (xy 182.527686 -31.803089)
			(xy 182.505043 -31.753507) (xy 182.489687 -31.701207) (xy 182.48193 -31.647254) (xy 179.806794 -31.647254)
			(xy 179.845181 -31.6792) (xy 179.882398 -31.720737) (xy 179.913171 -31.76725) (xy 179.936843 -31.817747)
			(xy 179.952911 -31.871154) (xy 179.961031 -31.92633) (xy 179.96154 -31.954216) (xy 179.961031 -31.982102)
			(xy 179.952911 -32.037278) (xy 179.936843 -32.090685) (xy 179.913171 -32.141182) (xy 179.882398 -32.187695)
			(xy 179.845181 -32.229232) (xy 179.802313 -32.264907) (xy 179.754707 -32.293961) (xy 179.703378 -32.315773)
			(xy 179.649421 -32.329879) (xy 179.593984 -32.335979) (xy 179.53825 -32.333942) (xy 179.483407 -32.323812)
			(xy 179.430623 -32.305805) (xy 179.381023 -32.280304) (xy 179.335665 -32.247853) (xy 179.295516 -32.209144)
			(xy 179.26143 -32.165001) (xy 179.234134 -32.116366) (xy 179.214211 -32.064275) (xy 179.202085 -32.009838)
			(xy 179.198014 -31.954216) (xy 178.312618 -31.954216) (xy 178.31033 -31.962007) (xy 178.287686 -32.011587)
			(xy 178.258217 -32.05744) (xy 178.222523 -32.098632) (xy 178.181329 -32.134326) (xy 178.135475 -32.163793)
			(xy 178.085894 -32.186435) (xy 178.033595 -32.20179) (xy 177.979644 -32.209545) (xy 177.925138 -32.209544)
			(xy 177.871186 -32.201786) (xy 177.818889 -32.186428) (xy 177.769309 -32.163784) (xy 177.723456 -32.134314)
			(xy 177.682264 -32.098619) (xy 177.646572 -32.057425) (xy 177.617105 -32.011571) (xy 177.594464 -31.961989)
			(xy 177.579109 -31.909691) (xy 177.571354 -31.855739) (xy 177.570892 -31.828486) (xy 177.570892 -31.81858)
			(xy 177.570823 -31.804585) (xy 177.563868 -31.777484) (xy 177.549822 -31.753286) (xy 177.52974 -31.733805)
			(xy 177.505126 -31.7205) (xy 177.477827 -31.714371) (xy 177.449888 -31.715875) (xy 177.423405 -31.724901)
			(xy 177.411634 -31.732474) (xy 177.387554 -31.748527) (xy 177.335576 -31.773968) (xy 177.28035 -31.791261)
			(xy 177.223145 -31.800008) (xy 177.19421 -31.800546) (xy 177.166956 -31.800056) (xy 177.113002 -31.7923)
			(xy 177.060701 -31.776944) (xy 177.011118 -31.754301) (xy 176.965262 -31.724832) (xy 176.924066 -31.689136)
			(xy 176.888371 -31.647942) (xy 176.858901 -31.602086) (xy 176.836258 -31.552503) (xy 176.820901 -31.500202)
			(xy 176.813144 -31.446248) (xy 171.18638 -31.446248) (xy 172.275754 -32.535622) (xy 180.552342 -32.535622)
			(xy 180.556413 -32.48) (xy 180.568539 -32.425563) (xy 180.588462 -32.373472) (xy 180.615758 -32.324837)
			(xy 180.649844 -32.280694) (xy 180.689993 -32.241985) (xy 180.735351 -32.209534) (xy 180.784951 -32.184033)
			(xy 180.837735 -32.166026) (xy 180.892578 -32.155896) (xy 180.948312 -32.153859) (xy 181.003749 -32.159959)
			(xy 181.057706 -32.174065) (xy 181.109035 -32.195877) (xy 181.156641 -32.224931) (xy 181.199509 -32.260606)
			(xy 181.236726 -32.302143) (xy 181.267499 -32.348656) (xy 181.291171 -32.399153) (xy 181.307239 -32.45256)
			(xy 181.315359 -32.507736) (xy 181.315868 -32.535622) (xy 181.315359 -32.563508) (xy 181.307239 -32.618684)
			(xy 181.291171 -32.672091) (xy 181.267499 -32.722588) (xy 181.236726 -32.769101) (xy 181.199509 -32.810638)
			(xy 181.156641 -32.846313) (xy 181.109035 -32.875367) (xy 181.057706 -32.897179) (xy 181.003749 -32.911285)
			(xy 180.948312 -32.917385) (xy 180.892578 -32.915348) (xy 180.837735 -32.905218) (xy 180.784951 -32.887211)
			(xy 180.735351 -32.86171) (xy 180.689993 -32.829259) (xy 180.649844 -32.79055) (xy 180.615758 -32.746407)
			(xy 180.588462 -32.697772) (xy 180.568539 -32.645681) (xy 180.556413 -32.591244) (xy 180.552342 -32.535622)
			(xy 172.275754 -32.535622) (xy 174.079786 -34.339654) (xy 181.84693 -34.339654) (xy 181.84693 -34.285146)
			(xy 181.854687 -34.231193) (xy 181.870043 -34.178893) (xy 181.892686 -34.129311) (xy 181.922154 -34.083456)
			(xy 181.957848 -34.042261) (xy 181.999041 -34.006565) (xy 182.044895 -33.977094) (xy 182.094476 -33.954449)
			(xy 182.146776 -33.939091) (xy 182.200728 -33.931331) (xy 182.227982 -33.930844) (xy 182.256899 -33.931359)
			(xy 182.314071 -33.940086) (xy 182.369271 -33.957344) (xy 182.421233 -33.982736) (xy 182.468767 -34.015681)
			(xy 182.510783 -34.055424) (xy 182.528972 -34.07791) (xy 182.538869 -34.089715) (xy 182.564193 -34.107234)
			(xy 182.593586 -34.11641) (xy 182.624378 -34.11641) (xy 182.653771 -34.107234) (xy 182.679095 -34.089715)
			(xy 182.688992 -34.07791) (xy 182.70719 -34.055432) (xy 182.749208 -34.015696) (xy 182.796741 -33.982756)
			(xy 182.848701 -33.957367) (xy 182.903898 -33.94011) (xy 182.961066 -33.931379) (xy 182.989982 -33.930844)
			(xy 183.017232 -33.931402) (xy 183.071178 -33.939156) (xy 183.123472 -33.954508) (xy 183.173048 -33.977147)
			(xy 183.218898 -34.006611) (xy 183.260087 -34.0423) (xy 183.295778 -34.083488) (xy 183.325244 -34.129336)
			(xy 183.347885 -34.178911) (xy 183.36324 -34.231204) (xy 183.370997 -34.28515) (xy 183.370997 -34.33965)
			(xy 183.36324 -34.393596) (xy 183.347885 -34.445889) (xy 183.325244 -34.495464) (xy 183.295778 -34.541312)
			(xy 183.260087 -34.5825) (xy 183.218898 -34.618189) (xy 183.173048 -34.647653) (xy 183.123472 -34.670292)
			(xy 183.071178 -34.685644) (xy 183.017232 -34.693398) (xy 182.989982 -34.69386) (xy 182.961067 -34.693298)
			(xy 182.903897 -34.68458) (xy 182.848698 -34.667332) (xy 182.796736 -34.641948) (xy 182.749201 -34.609012)
			(xy 182.707183 -34.569277) (xy 182.688992 -34.546794) (xy 182.679095 -34.534989) (xy 182.653771 -34.51747)
			(xy 182.624378 -34.508294) (xy 182.593586 -34.508294) (xy 182.564193 -34.51747) (xy 182.538869 -34.534989)
			(xy 182.528972 -34.546794) (xy 182.510795 -34.56929) (xy 182.468773 -34.609024) (xy 182.421235 -34.641962)
			(xy 182.369271 -34.667348) (xy 182.314071 -34.684602) (xy 182.256899 -34.693327) (xy 182.227982 -34.69386)
			(xy 182.200728 -34.693469) (xy 182.146776 -34.685709) (xy 182.094476 -34.670351) (xy 182.044895 -34.647706)
			(xy 181.999041 -34.618235) (xy 181.957848 -34.582539) (xy 181.922154 -34.541344) (xy 181.892686 -34.495489)
			(xy 181.870043 -34.445907) (xy 181.854687 -34.393607) (xy 181.84693 -34.339654) (xy 174.079786 -34.339654)
			(xy 174.75708 -35.016948) (xy 184.38368 -35.016948)
		)
		(stroke
			(width 0)
			(type solid)
		)
		(fill yes)
		(layer "In2.Cu")
		(net "GND")
	)
	(gr_poly
		(pts
			(xy 254.918972 -58.2422) (xy 254.918972 -57.953148) (xy 254.919526 -57.923166) (xy 254.928903 -57.863941)
			(xy 254.947434 -57.806914) (xy 254.974662 -57.753489) (xy 255.009916 -57.704984) (xy 255.030732 -57.6834)
			(xy 255.528572 -57.18556) (xy 255.550188 -57.164783) (xy 255.598695 -57.12955) (xy 255.652114 -57.102335)
			(xy 255.709131 -57.083806) (xy 255.768344 -57.07442) (xy 255.79832 -57.0738) (xy 256.427732 -57.0738)
			(xy 257.28168 -56.220106) (xy 257.281426 -56.19877) (xy 257.281172 -56.194452) (xy 257.281172 -51.726084)
			(xy 257.280683 -51.711754) (xy 257.272721 -51.684222) (xy 257.257426 -51.659984) (xy 257.236003 -51.640946)
			(xy 257.210136 -51.628605) (xy 257.18186 -51.623932) (xy 257.153398 -51.627295) (xy 257.126989 -51.638428)
			(xy 257.115564 -51.64709) (xy 257.095097 -51.663147) (xy 257.050637 -51.690151) (xy 257.002917 -51.710858)
			(xy 256.952824 -51.724885) (xy 256.90129 -51.731969) (xy 256.87528 -51.732434) (xy 256.848028 -51.731947)
			(xy 256.794079 -51.724187) (xy 256.741783 -51.70883) (xy 256.692205 -51.686186) (xy 256.646354 -51.656717)
			(xy 256.605163 -51.621023) (xy 256.569471 -51.57983) (xy 256.540005 -51.533978) (xy 256.517363 -51.484399)
			(xy 256.502008 -51.432102) (xy 256.494252 -51.378152) (xy 256.494252 -51.323648) (xy 256.502008 -51.269698)
			(xy 256.517363 -51.217401) (xy 256.540005 -51.167822) (xy 256.569471 -51.12197) (xy 256.605163 -51.080777)
			(xy 256.646354 -51.045083) (xy 256.692205 -51.015614) (xy 256.741783 -50.99297) (xy 256.794079 -50.977613)
			(xy 256.848028 -50.969853) (xy 256.87528 -50.969418) (xy 256.901289 -50.969877) (xy 256.95282 -50.976978)
			(xy 257.002911 -50.99101) (xy 257.050632 -51.011712) (xy 257.0951 -51.038703) (xy 257.115564 -51.054762)
			(xy 257.127008 -51.063414) (xy 257.153424 -51.074577) (xy 257.1819 -51.077961) (xy 257.210196 -51.073299)
			(xy 257.236082 -51.060958) (xy 257.25752 -51.041911) (xy 257.272821 -51.017657) (xy 257.28078 -50.990107)
			(xy 257.281172 -50.975768) (xy 257.281172 -48.734218) (xy 256.568448 -48.021494) (xy 256.558 -48.011713)
			(xy 256.532965 -47.997871) (xy 256.505072 -47.991522) (xy 256.476512 -47.993167) (xy 256.449532 -48.002675)
			(xy 256.426252 -48.0193) (xy 256.408501 -48.041734) (xy 256.402586 -48.054768) (xy 256.394301 -48.07417)
			(xy 256.373327 -48.110775) (xy 256.347676 -48.14427) (xy 256.33299 -48.159416) (xy 255.085088 -49.407318)
			(xy 255.085088 -50.366422) (xy 255.680462 -50.366422) (xy 255.684533 -50.3108) (xy 255.696659 -50.256363)
			(xy 255.716582 -50.204272) (xy 255.743878 -50.155637) (xy 255.777964 -50.111494) (xy 255.818113 -50.072785)
			(xy 255.863471 -50.040334) (xy 255.913071 -50.014833) (xy 255.965855 -49.996826) (xy 256.020698 -49.986696)
			(xy 256.076432 -49.984659) (xy 256.131869 -49.990759) (xy 256.185826 -50.004865) (xy 256.237155 -50.026677)
			(xy 256.284761 -50.055731) (xy 256.327629 -50.091406) (xy 256.364846 -50.132943) (xy 256.395619 -50.179456)
			(xy 256.419291 -50.229953) (xy 256.435359 -50.28336) (xy 256.443479 -50.338536) (xy 256.443988 -50.366422)
			(xy 256.443479 -50.394308) (xy 256.435359 -50.449484) (xy 256.419291 -50.502891) (xy 256.395619 -50.553388)
			(xy 256.364846 -50.599901) (xy 256.327629 -50.641438) (xy 256.284761 -50.677113) (xy 256.237155 -50.706167)
			(xy 256.185826 -50.727979) (xy 256.131869 -50.742085) (xy 256.076432 -50.748185) (xy 256.020698 -50.746148)
			(xy 255.965855 -50.736018) (xy 255.913071 -50.718011) (xy 255.863471 -50.69251) (xy 255.818113 -50.660059)
			(xy 255.777964 -50.62135) (xy 255.743878 -50.577207) (xy 255.716582 -50.528572) (xy 255.696659 -50.476481)
			(xy 255.684533 -50.422044) (xy 255.680462 -50.366422) (xy 255.085088 -50.366422) (xy 255.085088 -52.939696)
			(xy 256.159252 -52.939696) (xy 256.163323 -52.884074) (xy 256.175449 -52.829637) (xy 256.195372 -52.777546)
			(xy 256.222668 -52.728911) (xy 256.256754 -52.684768) (xy 256.296903 -52.646059) (xy 256.342261 -52.613608)
			(xy 256.391861 -52.588107) (xy 256.444645 -52.5701) (xy 256.499488 -52.55997) (xy 256.555222 -52.557933)
			(xy 256.610659 -52.564033) (xy 256.664616 -52.578139) (xy 256.715945 -52.599951) (xy 256.763551 -52.629005)
			(xy 256.806419 -52.66468) (xy 256.843636 -52.706217) (xy 256.874409 -52.75273) (xy 256.898081 -52.803227)
			(xy 256.914149 -52.856634) (xy 256.922269 -52.91181) (xy 256.922778 -52.939696) (xy 256.922269 -52.967582)
			(xy 256.914149 -53.022758) (xy 256.898081 -53.076165) (xy 256.874409 -53.126662) (xy 256.843636 -53.173175)
			(xy 256.806419 -53.214712) (xy 256.763551 -53.250387) (xy 256.715945 -53.279441) (xy 256.664616 -53.301253)
			(xy 256.610659 -53.315359) (xy 256.555222 -53.321459) (xy 256.499488 -53.319422) (xy 256.444645 -53.309292)
			(xy 256.391861 -53.291285) (xy 256.342261 -53.265784) (xy 256.296903 -53.233333) (xy 256.256754 -53.194624)
			(xy 256.222668 -53.150481) (xy 256.195372 -53.101846) (xy 256.175449 -53.049755) (xy 256.163323 -52.995318)
			(xy 256.159252 -52.939696) (xy 255.085088 -52.939696) (xy 255.085088 -53.14823) (xy 255.08458 -53.165248)
			(xy 255.084318 -53.178965) (xy 255.090246 -53.205741) (xy 255.103091 -53.229972) (xy 255.121926 -53.249906)
			(xy 255.145389 -53.264103) (xy 255.171787 -53.271539) (xy 255.199211 -53.271675) (xy 255.225681 -53.264501)
			(xy 255.237742 -53.257958) (xy 255.259941 -53.245274) (xy 255.307009 -53.225306) (xy 255.356321 -53.211804)
			(xy 255.406996 -53.20501) (xy 255.43256 -53.204618) (xy 255.459811 -53.205078) (xy 255.51376 -53.212829)
			(xy 255.566056 -53.228179) (xy 255.615635 -53.250815) (xy 255.661489 -53.280277) (xy 255.702682 -53.315964)
			(xy 255.738378 -53.357151) (xy 255.767849 -53.402998) (xy 255.790495 -53.452573) (xy 255.805855 -53.504867)
			(xy 255.813616 -53.558814) (xy 255.813621 -53.613316) (xy 255.80587 -53.667264) (xy 255.790519 -53.71956)
			(xy 255.767883 -53.76914) (xy 255.73842 -53.814992) (xy 255.702732 -53.856186) (xy 255.661545 -53.891881)
			(xy 255.615698 -53.921351) (xy 255.566122 -53.943996) (xy 255.513829 -53.959356) (xy 255.459882 -53.967117)
			(xy 255.405379 -53.967121) (xy 255.351431 -53.959369) (xy 255.299135 -53.944018) (xy 255.249556 -53.92138)
			(xy 255.203704 -53.891918) (xy 255.162511 -53.856229) (xy 255.126816 -53.815042) (xy 255.097347 -53.769193)
			(xy 255.074702 -53.719618) (xy 255.059343 -53.667324) (xy 255.051583 -53.613377) (xy 255.051052 -53.586126)
			(xy 255.051677 -53.555231) (xy 255.061681 -53.494254) (xy 255.081368 -53.435682) (xy 255.095248 -53.408072)
			(xy 255.099918 -53.398372) (xy 255.101476 -53.376919) (xy 255.09413 -53.356703) (xy 255.079163 -53.341255)
			(xy 255.05919 -53.333274) (xy 255.037699 -53.334152) (xy 255.018443 -53.343738) (xy 255.011174 -53.351684)
			(xy 254.99187 -53.37302) (xy 254.536194 -53.828696) (xy 254.519518 -53.844781) (xy 254.482351 -53.872441)
			(xy 254.441564 -53.894416) (xy 254.398019 -53.910241) (xy 254.375412 -53.91531) (xy 254.3511 -53.931846)
			(xy 254.298465 -53.958042) (xy 254.242435 -53.97586) (xy 254.184337 -53.984879) (xy 254.15494 -53.985414)
			(xy 254.127685 -53.984953) (xy 254.073729 -53.977201) (xy 254.021425 -53.961848) (xy 253.971839 -53.939208)
			(xy 253.92598 -53.90974) (xy 253.884782 -53.874046) (xy 253.849084 -53.832852) (xy 253.819612 -53.786996)
			(xy 253.796966 -53.737412) (xy 253.781608 -53.68511) (xy 253.773849 -53.631155) (xy 253.773849 -53.576645)
			(xy 253.781608 -53.52269) (xy 253.796966 -53.470388) (xy 253.819612 -53.420804) (xy 253.849084 -53.374948)
			(xy 253.884782 -53.333754) (xy 253.92598 -53.29806) (xy 253.971839 -53.268592) (xy 254.021425 -53.245952)
			(xy 254.073729 -53.230599) (xy 254.127685 -53.222847) (xy 254.15494 -53.222398) (xy 254.168834 -53.222534)
			(xy 254.196547 -53.224567) (xy 254.210312 -53.226462) (xy 254.235712 -53.230272) (xy 254.449072 -53.016658)
			(xy 254.449072 -51.941984) (xy 254.448606 -51.92783) (xy 254.440829 -51.900612) (xy 254.425876 -51.876576)
			(xy 254.404898 -51.857569) (xy 254.379508 -51.845053) (xy 254.351656 -51.839991) (xy 254.323486 -51.84277)
			(xy 254.310134 -51.847496) (xy 254.289199 -51.855417) (xy 254.245852 -51.86658) (xy 254.20145 -51.872242)
			(xy 254.17907 -51.872642) (xy 254.151743 -51.872171) (xy 254.097724 -51.863866) (xy 254.045612 -51.847394)
			(xy 253.996633 -51.823145) (xy 253.951941 -51.791687) (xy 253.931928 -51.773074) (xy 253.920306 -51.762677)
			(xy 253.892372 -51.748853) (xy 253.86157 -51.744097) (xy 253.830768 -51.748853) (xy 253.802834 -51.762677)
			(xy 253.791212 -51.773074) (xy 253.771161 -51.791638) (xy 253.726462 -51.823066) (xy 253.67749 -51.847304)
			(xy 253.625393 -51.863783) (xy 253.571391 -51.872119) (xy 253.54407 -51.872642) (xy 253.51742 -51.872142)
			(xy 253.464715 -51.864194) (xy 253.413783 -51.84848) (xy 253.365762 -51.825351) (xy 253.321724 -51.795323)
			(xy 253.282654 -51.759067) (xy 253.249423 -51.717394) (xy 253.222773 -51.671233) (xy 253.203301 -51.621616)
			(xy 253.191441 -51.569652) (xy 253.187458 -51.5165) (xy 253.191441 -51.463348) (xy 253.203301 -51.411384)
			(xy 253.222773 -51.361767) (xy 253.249423 -51.315606) (xy 253.282654 -51.273933) (xy 253.321724 -51.237677)
			(xy 253.365762 -51.207649) (xy 253.413783 -51.18452) (xy 253.464715 -51.168806) (xy 253.51742 -51.160858)
			(xy 253.54407 -51.160426) (xy 253.571396 -51.1609) (xy 253.625412 -51.16921) (xy 253.677521 -51.185685)
			(xy 253.726497 -51.209936) (xy 253.771187 -51.241394) (xy 253.791212 -51.259994) (xy 253.802834 -51.270391)
			(xy 253.830768 -51.284215) (xy 253.86157 -51.288971) (xy 253.892372 -51.284215) (xy 253.920306 -51.270391)
			(xy 253.931928 -51.259994) (xy 253.951979 -51.241428) (xy 253.996677 -51.209995) (xy 254.045648 -51.185751)
			(xy 254.097745 -51.169265) (xy 254.151748 -51.160921) (xy 254.17907 -51.160426) (xy 254.201453 -51.160778)
			(xy 254.245861 -51.166431) (xy 254.289206 -51.177626) (xy 254.310134 -51.185572) (xy 254.323472 -51.190349)
			(xy 254.351655 -51.193131) (xy 254.379518 -51.188066) (xy 254.404919 -51.175543) (xy 254.425903 -51.156526)
			(xy 254.440858 -51.132476) (xy 254.448631 -51.105244) (xy 254.449072 -51.091084) (xy 254.449072 -51.042062)
			(xy 254.448603 -51.02791) (xy 254.440822 -51.000698) (xy 254.425869 -50.976667) (xy 254.404893 -50.957665)
			(xy 254.379505 -50.945152) (xy 254.351658 -50.940091) (xy 254.323491 -50.942869) (xy 254.310134 -50.947574)
			(xy 254.289199 -50.955496) (xy 254.245852 -50.966659) (xy 254.20145 -50.972321) (xy 254.17907 -50.97272)
			(xy 254.151743 -50.972249) (xy 254.097725 -50.963943) (xy 254.045613 -50.947471) (xy 253.996635 -50.92322)
			(xy 253.951944 -50.891762) (xy 253.931928 -50.873152) (xy 253.920306 -50.862755) (xy 253.892372 -50.848931)
			(xy 253.86157 -50.844175) (xy 253.830768 -50.848931) (xy 253.802834 -50.862755) (xy 253.791212 -50.873152)
			(xy 253.771159 -50.891713) (xy 253.726458 -50.923134) (xy 253.677486 -50.947366) (xy 253.62539 -50.963842)
			(xy 253.57139 -50.972175) (xy 253.54407 -50.97272) (xy 253.517421 -50.97222) (xy 253.46472 -50.964273)
			(xy 253.413791 -50.948559) (xy 253.365773 -50.925432) (xy 253.321738 -50.895406) (xy 253.28267 -50.859152)
			(xy 253.249441 -50.817481) (xy 253.222793 -50.771324) (xy 253.203322 -50.72171) (xy 253.191463 -50.669749)
			(xy 253.18748 -50.6166) (xy 253.191463 -50.563451) (xy 253.203322 -50.51149) (xy 253.222793 -50.461876)
			(xy 253.249441 -50.415719) (xy 253.28267 -50.374048) (xy 253.321738 -50.337794) (xy 253.365773 -50.307768)
			(xy 253.413791 -50.284641) (xy 253.46472 -50.268927) (xy 253.517421 -50.26098) (xy 253.54407 -50.260504)
			(xy 253.571396 -50.260978) (xy 253.625413 -50.269288) (xy 253.677523 -50.285761) (xy 253.726499 -50.310012)
			(xy 253.77119 -50.341469) (xy 253.791212 -50.360072) (xy 253.802834 -50.370469) (xy 253.830768 -50.384293)
			(xy 253.86157 -50.389049) (xy 253.892372 -50.384293) (xy 253.920306 -50.370469) (xy 253.931928 -50.360072)
			(xy 253.95198 -50.341507) (xy 253.996678 -50.310076) (xy 254.045649 -50.285834) (xy 254.097746 -50.269348)
			(xy 254.151749 -50.261005) (xy 254.17907 -50.260504) (xy 254.201453 -50.260856) (xy 254.245862 -50.266508)
			(xy 254.289206 -50.277703) (xy 254.310134 -50.28565) (xy 254.323471 -50.290427) (xy 254.351652 -50.29321)
			(xy 254.379514 -50.288145) (xy 254.404913 -50.275622) (xy 254.425895 -50.256604) (xy 254.440845 -50.232553)
			(xy 254.448613 -50.205321) (xy 254.449072 -50.191162) (xy 254.449072 -50.14214) (xy 254.448613 -50.127981)
			(xy 254.440845 -50.100748) (xy 254.425895 -50.076698) (xy 254.404913 -50.057679) (xy 254.379514 -50.045155)
			(xy 254.351652 -50.04009) (xy 254.323471 -50.042874) (xy 254.310134 -50.047652) (xy 254.289199 -50.055573)
			(xy 254.245852 -50.066734) (xy 254.20145 -50.072394) (xy 254.17907 -50.072798) (xy 254.151742 -50.072327)
			(xy 254.097723 -50.064023) (xy 254.045609 -50.047554) (xy 253.996628 -50.023307) (xy 253.951932 -49.991853)
			(xy 253.931928 -49.97323) (xy 253.920306 -49.962833) (xy 253.892372 -49.949009) (xy 253.86157 -49.944253)
			(xy 253.830768 -49.949009) (xy 253.802834 -49.962833) (xy 253.791212 -49.97323) (xy 253.771159 -49.991792)
			(xy 253.726459 -50.023215) (xy 253.677487 -50.047449) (xy 253.625391 -50.063925) (xy 253.57139 -50.072259)
			(xy 253.54407 -50.072798) (xy 253.517423 -50.072298) (xy 253.464724 -50.064351) (xy 253.413799 -50.048639)
			(xy 253.365784 -50.025512) (xy 253.321752 -49.995488) (xy 253.282686 -49.959237) (xy 253.249459 -49.917569)
			(xy 253.222813 -49.871414) (xy 253.203343 -49.821803) (xy 253.191485 -49.769845) (xy 253.187502 -49.7167)
			(xy 253.191485 -49.663555) (xy 253.203343 -49.611597) (xy 253.222813 -49.561986) (xy 253.249459 -49.515831)
			(xy 253.282686 -49.474163) (xy 253.321752 -49.437912) (xy 253.365784 -49.407888) (xy 253.413799 -49.384761)
			(xy 253.464724 -49.369049) (xy 253.517423 -49.361102) (xy 253.54407 -49.360582) (xy 253.571396 -49.361056)
			(xy 253.625411 -49.369367) (xy 253.677518 -49.385844) (xy 253.726492 -49.410098) (xy 253.771178 -49.44156)
			(xy 253.791212 -49.46015) (xy 253.802834 -49.470547) (xy 253.830768 -49.484371) (xy 253.86157 -49.489127)
			(xy 253.892372 -49.484371) (xy 253.920306 -49.470547) (xy 253.931928 -49.46015) (xy 253.95198 -49.441586)
			(xy 253.996679 -49.410157) (xy 254.04565 -49.385916) (xy 254.097747 -49.369432) (xy 254.151749 -49.361089)
			(xy 254.17907 -49.360582) (xy 254.201453 -49.360933) (xy 254.245862 -49.366586) (xy 254.289207 -49.377779)
			(xy 254.310134 -49.385728) (xy 254.323475 -49.390503) (xy 254.351661 -49.393283) (xy 254.379528 -49.388218)
			(xy 254.404933 -49.375696) (xy 254.425925 -49.356681) (xy 254.440889 -49.332634) (xy 254.448676 -49.305402)
			(xy 254.449072 -49.29124) (xy 254.449072 -49.275746) (xy 254.450342 -49.249838) (xy 254.451083 -49.235056)
			(xy 254.445007 -49.206101) (xy 254.430876 -49.18011) (xy 254.409878 -49.159269) (xy 254.383781 -49.145332)
			(xy 254.354783 -49.139473) (xy 254.325322 -49.142184) (xy 254.311404 -49.147222) (xy 254.290284 -49.155281)
			(xy 254.246519 -49.166602) (xy 254.201673 -49.172294) (xy 254.17907 -49.172622) (xy 254.151743 -49.172151)
			(xy 254.097725 -49.163845) (xy 254.045613 -49.147373) (xy 253.996635 -49.123123) (xy 253.951944 -49.091664)
			(xy 253.931928 -49.073054) (xy 253.920306 -49.062657) (xy 253.892372 -49.048833) (xy 253.86157 -49.044077)
			(xy 253.830768 -49.048833) (xy 253.802834 -49.062657) (xy 253.791212 -49.073054) (xy 253.771159 -49.091615)
			(xy 253.726458 -49.123036) (xy 253.677486 -49.147268) (xy 253.62539 -49.163743) (xy 253.57139 -49.172076)
			(xy 253.54407 -49.172622) (xy 253.517421 -49.172122) (xy 253.464719 -49.164175) (xy 253.41379 -49.148461)
			(xy 253.365772 -49.125333) (xy 253.321737 -49.095307) (xy 253.282668 -49.059054) (xy 253.249439 -49.017383)
			(xy 253.222791 -48.971225) (xy 253.203321 -48.921611) (xy 253.191461 -48.869649) (xy 253.187478 -48.8165)
			(xy 253.191461 -48.763351) (xy 253.203321 -48.711389) (xy 253.222791 -48.661775) (xy 253.249439 -48.615617)
			(xy 253.282668 -48.573946) (xy 253.321737 -48.537693) (xy 253.365772 -48.507667) (xy 253.41379 -48.484539)
			(xy 253.464719 -48.468825) (xy 253.517421 -48.460878) (xy 253.54407 -48.460406) (xy 253.571396 -48.46088)
			(xy 253.625413 -48.46919) (xy 253.677522 -48.485663) (xy 253.726499 -48.509914) (xy 253.77119 -48.541371)
			(xy 253.791212 -48.559974) (xy 253.802834 -48.570371) (xy 253.830768 -48.584195) (xy 253.86157 -48.588951)
			(xy 253.892372 -48.584195) (xy 253.920306 -48.570371) (xy 253.931928 -48.559974) (xy 253.95198 -48.541409)
			(xy 253.996678 -48.509977) (xy 254.045649 -48.485735) (xy 254.097746 -48.46925) (xy 254.151749 -48.460907)
			(xy 254.17907 -48.460406) (xy 254.206915 -48.460942) (xy 254.261926 -48.469606) (xy 254.314918 -48.486729)
			(xy 254.364598 -48.511892) (xy 254.409755 -48.544483) (xy 254.449289 -48.583705) (xy 254.482234 -48.628604)
			(xy 254.507789 -48.678084) (xy 254.525329 -48.730939) (xy 254.534428 -48.78588) (xy 254.535178 -48.81372)
			(xy 254.535811 -48.828668) (xy 254.544679 -48.857229) (xy 254.561442 -48.881994) (xy 254.584661 -48.90084)
			(xy 254.612345 -48.912151) (xy 254.642118 -48.914954) (xy 254.671427 -48.909011) (xy 254.697756 -48.89483)
			(xy 254.70866 -48.884586) (xy 255.790192 -47.803054) (xy 255.790192 -47.536608) (xy 255.789682 -47.521343)
			(xy 255.780678 -47.492172) (xy 255.763469 -47.466956) (xy 255.739587 -47.447939) (xy 255.711157 -47.436814)
			(xy 255.68071 -47.434571) (xy 255.665732 -47.437548) (xy 255.644568 -47.442157) (xy 255.601538 -47.447125)
			(xy 255.57988 -47.447454) (xy 255.552626 -47.446967) (xy 255.498674 -47.439207) (xy 255.446376 -47.423848)
			(xy 255.396795 -47.401203) (xy 255.350942 -47.371733) (xy 255.309749 -47.336037) (xy 255.274055 -47.294842)
			(xy 255.244587 -47.248987) (xy 255.221945 -47.199406) (xy 255.206589 -47.147106) (xy 255.198832 -47.093154)
			(xy 255.198832 -47.038646) (xy 255.206589 -46.984694) (xy 255.221945 -46.932394) (xy 255.244587 -46.882813)
			(xy 255.274055 -46.836958) (xy 255.309749 -46.795763) (xy 255.350942 -46.760067) (xy 255.396795 -46.730597)
			(xy 255.446376 -46.707952) (xy 255.498674 -46.692593) (xy 255.552626 -46.684833) (xy 255.57988 -46.684438)
			(xy 255.601538 -46.684769) (xy 255.644569 -46.689731) (xy 255.665732 -46.694344) (xy 255.680718 -46.697281)
			(xy 255.711163 -46.695063) (xy 255.739594 -46.683952) (xy 255.763474 -46.664939) (xy 255.780673 -46.639721)
			(xy 255.789656 -46.610547) (xy 255.790192 -46.595284) (xy 255.790192 -46.156118) (xy 255.214628 -45.5803)
			(xy 254.33528 -45.5803) (xy 254.310302 -45.579856) (xy 254.260957 -45.572077) (xy 254.213438 -45.556666)
			(xy 254.16892 -45.534004) (xy 254.128499 -45.504651) (xy 254.11049 -45.487336) (xy 253.67869 -45.055536)
			(xy 253.661338 -45.03755) (xy 253.631942 -44.997136) (xy 253.609238 -44.952617) (xy 253.593786 -44.905092)
			(xy 253.585968 -44.855733) (xy 253.585472 -44.830746) (xy 253.585472 -42.676318) (xy 251.99721 -41.088056)
			(xy 251.979856 -41.070071) (xy 251.950455 -41.029658) (xy 251.927747 -40.98514) (xy 251.912291 -40.937614)
			(xy 251.904469 -40.888254) (xy 251.903992 -40.863266) (xy 251.903992 -39.163752) (xy 251.78004 -39.0398)
			(xy 251.748036 -39.054786) (xy 251.722733 -39.066006) (xy 251.669697 -39.081839) (xy 251.614929 -39.089837)
			(xy 251.587254 -39.090346) (xy 251.560002 -39.089857) (xy 251.506054 -39.082094) (xy 251.45376 -39.066734)
			(xy 251.404183 -39.044088) (xy 251.358334 -39.014617) (xy 251.317145 -38.978922) (xy 251.281455 -38.937729)
			(xy 251.25199 -38.891876) (xy 251.22935 -38.842297) (xy 251.213996 -38.790001) (xy 251.20624 -38.736052)
			(xy 251.20624 -38.681548) (xy 251.213996 -38.627599) (xy 251.22935 -38.575303) (xy 251.25199 -38.525724)
			(xy 251.281455 -38.479871) (xy 251.317145 -38.438678) (xy 251.358334 -38.402983) (xy 251.404183 -38.373512)
			(xy 251.45376 -38.350866) (xy 251.506054 -38.335506) (xy 251.560002 -38.327743) (xy 251.587254 -38.32733)
			(xy 251.613455 -38.327768) (xy 251.665361 -38.334952) (xy 251.715795 -38.349176) (xy 251.763806 -38.370174)
			(xy 251.78639 -38.383464) (xy 251.798582 -38.391084) (xy 251.898658 -38.391084) (xy 251.923638 -38.391523)
			(xy 251.972989 -38.399294) (xy 252.020514 -38.414697) (xy 252.06504 -38.437352) (xy 252.105469 -38.466701)
			(xy 252.123448 -38.484048) (xy 252.385068 -38.745668) (xy 252.396277 -38.756172) (xy 252.423432 -38.770502)
			(xy 252.453618 -38.776118) (xy 252.48411 -38.772512) (xy 252.512153 -38.760009) (xy 252.524006 -38.75024)
			(xy 252.541024 -38.73627) (xy 252.548569 -38.729811) (xy 252.558439 -38.7126) (xy 252.56103 -38.69293)
			(xy 252.555954 -38.67375) (xy 252.543972 -38.657936) (xy 252.53569 -38.65245) (xy 252.51164 -38.637629)
			(xy 252.467794 -38.602008) (xy 252.429685 -38.560308) (xy 252.398146 -38.513441) (xy 252.373867 -38.462433)
			(xy 252.357381 -38.408401) (xy 252.349048 -38.352528) (xy 252.348492 -38.324282) (xy 252.348978 -38.297031)
			(xy 252.356734 -38.243083) (xy 252.372089 -38.190788) (xy 252.394731 -38.141211) (xy 252.424197 -38.095361)
			(xy 252.459888 -38.05417) (xy 252.501079 -38.018479) (xy 252.546929 -37.989013) (xy 252.596506 -37.966371)
			(xy 252.648801 -37.951016) (xy 252.702749 -37.94326) (xy 252.757251 -37.94326) (xy 252.811199 -37.951016)
			(xy 252.863494 -37.966371) (xy 252.913071 -37.989013) (xy 252.958921 -38.018479) (xy 253.000112 -38.05417)
			(xy 253.035803 -38.095361) (xy 253.065269 -38.141211) (xy 253.087911 -38.190788) (xy 253.103266 -38.243083)
			(xy 253.111022 -38.297031) (xy 253.111508 -38.324282) (xy 253.998982 -38.324282) (xy 254.003053 -38.26866)
			(xy 254.015179 -38.214223) (xy 254.035102 -38.162132) (xy 254.062398 -38.113497) (xy 254.096484 -38.069354)
			(xy 254.136633 -38.030645) (xy 254.181991 -37.998194) (xy 254.231591 -37.972693) (xy 254.284375 -37.954686)
			(xy 254.339218 -37.944556) (xy 254.394952 -37.942519) (xy 254.450389 -37.948619) (xy 254.504346 -37.962725)
			(xy 254.555675 -37.984537) (xy 254.603281 -38.013591) (xy 254.646149 -38.049266) (xy 254.683366 -38.090803)
			(xy 254.714139 -38.137316) (xy 254.737811 -38.187813) (xy 254.753879 -38.24122) (xy 254.761999 -38.296396)
			(xy 254.762508 -38.324282) (xy 254.762207 -38.340792) (xy 255.682748 -38.340792) (xy 255.686819 -38.28517)
			(xy 255.698945 -38.230733) (xy 255.718868 -38.178642) (xy 255.746164 -38.130007) (xy 255.78025 -38.085864)
			(xy 255.820399 -38.047155) (xy 255.865757 -38.014704) (xy 255.915357 -37.989203) (xy 255.968141 -37.971196)
			(xy 256.022984 -37.961066) (xy 256.078718 -37.959029) (xy 256.134155 -37.965129) (xy 256.188112 -37.979235)
			(xy 256.239441 -38.001047) (xy 256.287047 -38.030101) (xy 256.329915 -38.065776) (xy 256.367132 -38.107313)
			(xy 256.397905 -38.153826) (xy 256.421577 -38.204323) (xy 256.437645 -38.25773) (xy 256.445765 -38.312906)
			(xy 256.446274 -38.340792) (xy 256.445765 -38.368678) (xy 256.437645 -38.423854) (xy 256.421577 -38.477261)
			(xy 256.397905 -38.527758) (xy 256.367132 -38.574271) (xy 256.329915 -38.615808) (xy 256.287047 -38.651483)
			(xy 256.239441 -38.680537) (xy 256.188112 -38.702349) (xy 256.134155 -38.716455) (xy 256.078718 -38.722555)
			(xy 256.022984 -38.720518) (xy 255.968141 -38.710388) (xy 255.915357 -38.692381) (xy 255.865757 -38.66688)
			(xy 255.820399 -38.634429) (xy 255.78025 -38.59572) (xy 255.746164 -38.551577) (xy 255.718868 -38.502942)
			(xy 255.698945 -38.450851) (xy 255.686819 -38.396414) (xy 255.682748 -38.340792) (xy 254.762207 -38.340792)
			(xy 254.761999 -38.352168) (xy 254.753879 -38.407344) (xy 254.737811 -38.460751) (xy 254.714139 -38.511248)
			(xy 254.683366 -38.557761) (xy 254.646149 -38.599298) (xy 254.603281 -38.634973) (xy 254.555675 -38.664027)
			(xy 254.504346 -38.685839) (xy 254.450389 -38.699945) (xy 254.394952 -38.706045) (xy 254.339218 -38.704008)
			(xy 254.284375 -38.693878) (xy 254.231591 -38.675871) (xy 254.181991 -38.65037) (xy 254.136633 -38.617919)
			(xy 254.096484 -38.57921) (xy 254.062398 -38.535067) (xy 254.035102 -38.486432) (xy 254.015179 -38.434341)
			(xy 254.003053 -38.379904) (xy 253.998982 -38.324282) (xy 253.111508 -38.324282) (xy 253.110967 -38.353579)
			(xy 253.102001 -38.411482) (xy 253.084291 -38.467335) (xy 253.058254 -38.519826) (xy 253.024502 -38.567721)
			(xy 253.004574 -38.589204) (xy 252.995086 -38.599661) (xy 252.981753 -38.624538) (xy 252.975734 -38.652114)
			(xy 252.977492 -38.680284) (xy 252.98689 -38.706898) (xy 253.003211 -38.729925) (xy 253.013972 -38.739064)
			(xy 253.035903 -38.757283) (xy 253.074634 -38.799121) (xy 253.10671 -38.846256) (xy 253.131417 -38.897637)
			(xy 253.148205 -38.952123) (xy 253.1567 -39.0085) (xy 253.157228 -39.037006) (xy 253.156742 -39.064257)
			(xy 253.148985 -39.118206) (xy 253.133629 -39.170501) (xy 253.110988 -39.220079) (xy 253.081522 -39.26593)
			(xy 253.045831 -39.307121) (xy 253.004641 -39.342814) (xy 252.958791 -39.372281) (xy 252.909214 -39.394924)
			(xy 252.856919 -39.410282) (xy 252.802971 -39.418041) (xy 252.77572 -39.418514) (xy 252.748876 -39.418059)
			(xy 252.695717 -39.410541) (xy 252.669802 -39.403528) (xy 252.656754 -39.40019) (xy 252.629834 -39.39974)
			(xy 252.603732 -39.406339) (xy 252.58026 -39.41953) (xy 252.561051 -39.438395) (xy 252.547439 -39.461624)
			(xy 252.540369 -39.487603) (xy 252.540008 -39.501064) (xy 252.540008 -40.029384) (xy 256.867406 -40.029384)
			(xy 256.867892 -40.002133) (xy 256.875648 -39.948185) (xy 256.891003 -39.89589) (xy 256.913645 -39.846313)
			(xy 256.943111 -39.800463) (xy 256.978802 -39.759272) (xy 257.019993 -39.723581) (xy 257.065843 -39.694115)
			(xy 257.11542 -39.671473) (xy 257.167715 -39.656118) (xy 257.221663 -39.648362) (xy 257.276165 -39.648362)
			(xy 257.330113 -39.656118) (xy 257.382408 -39.671473) (xy 257.431985 -39.694115) (xy 257.477835 -39.723581)
			(xy 257.519026 -39.759272) (xy 257.554717 -39.800463) (xy 257.584183 -39.846313) (xy 257.606825 -39.89589)
			(xy 257.62218 -39.948185) (xy 257.629936 -40.002133) (xy 257.630422 -40.029384) (xy 257.629974 -40.057446)
			(xy 257.621759 -40.112964) (xy 257.605505 -40.166682) (xy 257.581561 -40.217441) (xy 257.550444 -40.264148)
			(xy 257.512824 -40.305795) (xy 257.491484 -40.324024) (xy 257.480468 -40.33383) (xy 257.464043 -40.358305)
			(xy 257.45529 -40.386452) (xy 257.454936 -40.415925) (xy 257.463013 -40.444273) (xy 257.478846 -40.469136)
			(xy 257.501119 -40.488443) (xy 257.514344 -40.494966) (xy 257.539118 -40.506662) (xy 257.585352 -40.536048)
			(xy 257.626909 -40.571744) (xy 257.662934 -40.613016) (xy 257.692686 -40.659015) (xy 257.715555 -40.708796)
			(xy 257.73107 -40.761336) (xy 257.738912 -40.815555) (xy 257.739388 -40.842946) (xy 257.738902 -40.870197)
			(xy 257.731146 -40.924145) (xy 257.715791 -40.97644) (xy 257.693149 -41.026017) (xy 257.663683 -41.071867)
			(xy 257.627992 -41.113058) (xy 257.586801 -41.148749) (xy 257.540951 -41.178215) (xy 257.491374 -41.200857)
			(xy 257.439079 -41.216212) (xy 257.385131 -41.223968) (xy 257.330629 -41.223968) (xy 257.276681 -41.216212)
			(xy 257.224386 -41.200857) (xy 257.174809 -41.178215) (xy 257.128959 -41.148749) (xy 257.087768 -41.113058)
			(xy 257.052077 -41.071867) (xy 257.022611 -41.026017) (xy 256.999969 -40.97644) (xy 256.984614 -40.924145)
			(xy 256.976858 -40.870197) (xy 256.976372 -40.842946) (xy 256.976843 -40.814885) (xy 256.985053 -40.759368)
			(xy 257.001303 -40.705651) (xy 257.025242 -40.654891) (xy 257.056355 -40.608184) (xy 257.093971 -40.566535)
			(xy 257.11531 -40.548306) (xy 257.126405 -40.538582) (xy 257.14283 -40.514086) (xy 257.151577 -40.48592)
			(xy 257.15192 -40.456429) (xy 257.143829 -40.428068) (xy 257.127977 -40.403197) (xy 257.105685 -40.383887)
			(xy 257.09245 -40.377364) (xy 257.067647 -40.365726) (xy 257.021412 -40.336332) (xy 256.979855 -40.300628)
			(xy 256.943832 -40.259348) (xy 256.914082 -40.21334) (xy 256.891219 -40.163551) (xy 256.875711 -40.111003)
			(xy 256.867878 -40.056778) (xy 256.867406 -40.029384) (xy 252.540008 -40.029384) (xy 252.540008 -40.731694)
			(xy 252.65126 -40.842946) (xy 254.308862 -40.842946) (xy 254.312933 -40.787324) (xy 254.325059 -40.732887)
			(xy 254.344982 -40.680796) (xy 254.372278 -40.632161) (xy 254.406364 -40.588018) (xy 254.446513 -40.549309)
			(xy 254.491871 -40.516858) (xy 254.541471 -40.491357) (xy 254.594255 -40.47335) (xy 254.649098 -40.46322)
			(xy 254.704832 -40.461183) (xy 254.760269 -40.467283) (xy 254.814226 -40.481389) (xy 254.865555 -40.503201)
			(xy 254.913161 -40.532255) (xy 254.956029 -40.56793) (xy 254.993246 -40.609467) (xy 255.024019 -40.65598)
			(xy 255.047691 -40.706477) (xy 255.063759 -40.759884) (xy 255.071879 -40.81506) (xy 255.072388 -40.842946)
			(xy 255.197862 -40.842946) (xy 255.201933 -40.787324) (xy 255.214059 -40.732887) (xy 255.233982 -40.680796)
			(xy 255.261278 -40.632161) (xy 255.295364 -40.588018) (xy 255.335513 -40.549309) (xy 255.380871 -40.516858)
			(xy 255.430471 -40.491357) (xy 255.483255 -40.47335) (xy 255.538098 -40.46322) (xy 255.593832 -40.461183)
			(xy 255.649269 -40.467283) (xy 255.703226 -40.481389) (xy 255.754555 -40.503201) (xy 255.802161 -40.532255)
			(xy 255.845029 -40.56793) (xy 255.882246 -40.609467) (xy 255.913019 -40.65598) (xy 255.936691 -40.706477)
			(xy 255.952759 -40.759884) (xy 255.960879 -40.81506) (xy 255.961388 -40.842946) (xy 256.086862 -40.842946)
			(xy 256.090933 -40.787324) (xy 256.103059 -40.732887) (xy 256.122982 -40.680796) (xy 256.150278 -40.632161)
			(xy 256.184364 -40.588018) (xy 256.224513 -40.549309) (xy 256.269871 -40.516858) (xy 256.319471 -40.491357)
			(xy 256.372255 -40.47335) (xy 256.427098 -40.46322) (xy 256.482832 -40.461183) (xy 256.538269 -40.467283)
			(xy 256.592226 -40.481389) (xy 256.643555 -40.503201) (xy 256.691161 -40.532255) (xy 256.734029 -40.56793)
			(xy 256.771246 -40.609467) (xy 256.802019 -40.65598) (xy 256.825691 -40.706477) (xy 256.841759 -40.759884)
			(xy 256.849879 -40.81506) (xy 256.850388 -40.842946) (xy 256.849879 -40.870832) (xy 256.841759 -40.926008)
			(xy 256.825691 -40.979415) (xy 256.802019 -41.029912) (xy 256.771246 -41.076425) (xy 256.734029 -41.117962)
			(xy 256.691161 -41.153637) (xy 256.643555 -41.182691) (xy 256.592226 -41.204503) (xy 256.538269 -41.218609)
			(xy 256.482832 -41.224709) (xy 256.427098 -41.222672) (xy 256.372255 -41.212542) (xy 256.319471 -41.194535)
			(xy 256.269871 -41.169034) (xy 256.224513 -41.136583) (xy 256.184364 -41.097874) (xy 256.150278 -41.053731)
			(xy 256.122982 -41.005096) (xy 256.103059 -40.953005) (xy 256.090933 -40.898568) (xy 256.086862 -40.842946)
			(xy 255.961388 -40.842946) (xy 255.960879 -40.870832) (xy 255.952759 -40.926008) (xy 255.936691 -40.979415)
			(xy 255.913019 -41.029912) (xy 255.882246 -41.076425) (xy 255.845029 -41.117962) (xy 255.802161 -41.153637)
			(xy 255.754555 -41.182691) (xy 255.703226 -41.204503) (xy 255.649269 -41.218609) (xy 255.593832 -41.224709)
			(xy 255.538098 -41.222672) (xy 255.483255 -41.212542) (xy 255.430471 -41.194535) (xy 255.380871 -41.169034)
			(xy 255.335513 -41.136583) (xy 255.295364 -41.097874) (xy 255.261278 -41.053731) (xy 255.233982 -41.005096)
			(xy 255.214059 -40.953005) (xy 255.201933 -40.898568) (xy 255.197862 -40.842946) (xy 255.072388 -40.842946)
			(xy 255.071879 -40.870832) (xy 255.063759 -40.926008) (xy 255.047691 -40.979415) (xy 255.024019 -41.029912)
			(xy 254.993246 -41.076425) (xy 254.956029 -41.117962) (xy 254.913161 -41.153637) (xy 254.865555 -41.182691)
			(xy 254.814226 -41.204503) (xy 254.760269 -41.218609) (xy 254.704832 -41.224709) (xy 254.649098 -41.222672)
			(xy 254.594255 -41.212542) (xy 254.541471 -41.194535) (xy 254.491871 -41.169034) (xy 254.446513 -41.136583)
			(xy 254.406364 -41.097874) (xy 254.372278 -41.053731) (xy 254.344982 -41.005096) (xy 254.325059 -40.953005)
			(xy 254.312933 -40.898568) (xy 254.308862 -40.842946) (xy 252.65126 -40.842946) (xy 253.754128 -41.945814)
			(xy 253.764791 -41.95575) (xy 253.790409 -41.969626) (xy 253.8189 -41.975713) (xy 253.847952 -41.973518)
			(xy 253.875205 -41.963218) (xy 253.898447 -41.94565) (xy 253.91579 -41.92224) (xy 253.92126 -41.90873)
			(xy 253.931762 -41.881559) (xy 253.959818 -41.830511) (xy 253.995309 -41.784322) (xy 254.03741 -41.744066)
			(xy 254.085142 -41.710679) (xy 254.137396 -41.684937) (xy 254.192955 -41.667439) (xy 254.250529 -41.658591)
			(xy 254.279654 -41.658032) (xy 254.306908 -41.658492) (xy 254.360862 -41.666244) (xy 254.413163 -41.681597)
			(xy 254.462746 -41.704237) (xy 254.508602 -41.733704) (xy 254.549797 -41.769399) (xy 254.585492 -41.810593)
			(xy 254.61496 -41.856449) (xy 254.637601 -41.906032) (xy 254.652955 -41.958332) (xy 254.660707 -42.012286)
			(xy 254.661162 -42.03954) (xy 254.660652 -42.06784) (xy 254.652297 -42.12382) (xy 254.635762 -42.177952)
			(xy 254.611411 -42.229046) (xy 254.579777 -42.27598) (xy 254.541555 -42.317726) (xy 254.497584 -42.353365)
			(xy 254.448829 -42.382116) (xy 254.396362 -42.403347) (xy 254.341333 -42.416592) (xy 254.313182 -42.419524)
			(xy 254.297629 -42.421496) (xy 254.268729 -42.433608) (xy 254.244844 -42.45389) (xy 254.228209 -42.480445)
			(xy 254.220381 -42.510786) (xy 254.220726 -42.526458) (xy 254.221488 -42.544746) (xy 254.221488 -44.699174)
			(xy 254.466852 -44.944792) (xy 255.222502 -44.944792) (xy 255.237503 -44.94426) (xy 255.266215 -44.935552)
			(xy 255.291164 -44.918888) (xy 255.310202 -44.8957) (xy 255.321693 -44.867984) (xy 255.324646 -44.838127)
			(xy 255.318807 -44.808698) (xy 255.304678 -44.78223) (xy 255.294384 -44.77131) (xy 255.240028 -44.7167)
			(xy 254.952754 -44.7167) (xy 254.929185 -44.731777) (xy 254.878564 -44.755607) (xy 254.825004 -44.771783)
			(xy 254.769655 -44.779958) (xy 254.74168 -44.780454) (xy 254.714426 -44.779967) (xy 254.660474 -44.772207)
			(xy 254.608176 -44.756848) (xy 254.558595 -44.734203) (xy 254.512742 -44.704733) (xy 254.471549 -44.669037)
			(xy 254.435855 -44.627842) (xy 254.406387 -44.581987) (xy 254.383745 -44.532406) (xy 254.368389 -44.480106)
			(xy 254.360632 -44.426154) (xy 254.360632 -44.371646) (xy 254.368389 -44.317694) (xy 254.383745 -44.265394)
			(xy 254.406387 -44.215813) (xy 254.435855 -44.169958) (xy 254.471549 -44.128763) (xy 254.512742 -44.093067)
			(xy 254.558595 -44.063597) (xy 254.608176 -44.040952) (xy 254.660474 -44.025593) (xy 254.714426 -44.017833)
			(xy 254.74168 -44.017438) (xy 254.769655 -44.017928) (xy 254.825005 -44.026103) (xy 254.878566 -44.042279)
			(xy 254.929188 -44.066109) (xy 254.952754 -44.081192) (xy 255.3716 -44.081192) (xy 255.396578 -44.081634)
			(xy 255.445926 -44.089411) (xy 255.493446 -44.104819) (xy 255.537968 -44.127478) (xy 255.578391 -44.15683)
			(xy 255.59639 -44.174156) (xy 256.076982 -44.654748) (xy 257.251224 -44.654748) (xy 257.251224 -44.600252)
			(xy 257.25898 -44.546311) (xy 257.274333 -44.494023) (xy 257.296971 -44.444451) (xy 257.326434 -44.398606)
			(xy 257.362121 -44.357421) (xy 257.403306 -44.321734) (xy 257.449151 -44.292271) (xy 257.498723 -44.269633)
			(xy 257.551011 -44.25428) (xy 257.604952 -44.246524) (xy 257.6322 -44.246038) (xy 257.659775 -44.24649)
			(xy 257.714349 -44.254444) (xy 257.76721 -44.270171) (xy 257.817256 -44.293343) (xy 257.863445 -44.323479)
			(xy 257.904815 -44.359949) (xy 257.92303 -44.380658) (xy 257.932928 -44.391556) (xy 257.957578 -44.407631)
			(xy 257.985786 -44.416015) (xy 258.015214 -44.416015) (xy 258.043422 -44.407631) (xy 258.068072 -44.391556)
			(xy 258.07797 -44.380658) (xy 258.096184 -44.35995) (xy 258.137553 -44.323481) (xy 258.183743 -44.29335)
			(xy 258.23379 -44.270184) (xy 258.286652 -44.254466) (xy 258.341226 -44.246525) (xy 258.3688 -44.246038)
			(xy 258.395097 -44.246493) (xy 258.447194 -44.253711) (xy 258.497804 -44.268023) (xy 258.545965 -44.289158)
			(xy 258.590763 -44.316715) (xy 258.631346 -44.350169) (xy 258.64947 -44.369228) (xy 258.658799 -44.378871)
			(xy 258.681467 -44.393214) (xy 258.70709 -44.401152) (xy 258.733897 -44.402136) (xy 258.760033 -44.396096)
			(xy 258.783691 -44.383452) (xy 258.793742 -44.374562) (xy 258.815073 -44.355295) (xy 258.862433 -44.322728)
			(xy 258.914144 -44.297634) (xy 258.969034 -44.280582) (xy 259.025861 -44.271959) (xy 259.0546 -44.271438)
			(xy 259.082175 -44.27189) (xy 259.136749 -44.279844) (xy 259.18961 -44.295571) (xy 259.239656 -44.318743)
			(xy 259.285845 -44.348879) (xy 259.327215 -44.385349) (xy 259.34543 -44.406058) (xy 259.355328 -44.416956)
			(xy 259.379978 -44.433031) (xy 259.408186 -44.441415) (xy 259.437614 -44.441415) (xy 259.465822 -44.433031)
			(xy 259.490472 -44.416956) (xy 259.50037 -44.406058) (xy 259.518584 -44.38535) (xy 259.559953 -44.348881)
			(xy 259.606143 -44.31875) (xy 259.65619 -44.295584) (xy 259.709052 -44.279866) (xy 259.763626 -44.271925)
			(xy 259.7912 -44.271438) (xy 259.818455 -44.271832) (xy 259.872409 -44.279589) (xy 259.92471 -44.294946)
			(xy 259.974293 -44.31759) (xy 260.020149 -44.34706) (xy 260.061344 -44.382756) (xy 260.09704 -44.423951)
			(xy 260.12651 -44.469807) (xy 260.149154 -44.51939) (xy 260.164511 -44.571691) (xy 260.172268 -44.625645)
			(xy 260.172268 -44.680155) (xy 260.164511 -44.734109) (xy 260.149154 -44.78641) (xy 260.12651 -44.835993)
			(xy 260.09704 -44.881849) (xy 260.061344 -44.923044) (xy 260.020149 -44.95874) (xy 259.974293 -44.98821)
			(xy 259.92471 -45.010854) (xy 259.872409 -45.026211) (xy 259.818455 -45.033968) (xy 259.7912 -45.034454)
			(xy 259.763625 -45.034004) (xy 259.70905 -45.026051) (xy 259.65619 -45.010324) (xy 259.606143 -44.987151)
			(xy 259.559954 -44.957015) (xy 259.518585 -44.920543) (xy 259.50037 -44.899834) (xy 259.490472 -44.888936)
			(xy 259.465822 -44.872861) (xy 259.437614 -44.864477) (xy 259.408186 -44.864477) (xy 259.379978 -44.872861)
			(xy 259.355328 -44.888936) (xy 259.34543 -44.899834) (xy 259.327214 -44.920541) (xy 259.285846 -44.95701)
			(xy 259.239656 -44.987142) (xy 259.189609 -45.010308) (xy 259.136748 -45.026026) (xy 259.082174 -45.033967)
			(xy 259.0546 -45.034454) (xy 259.028303 -45.034002) (xy 258.976205 -45.026784) (xy 258.925596 -45.012471)
			(xy 258.877435 -44.991335) (xy 258.832637 -44.963778) (xy 258.792054 -44.930324) (xy 258.77393 -44.911264)
			(xy 258.764602 -44.901618) (xy 258.741937 -44.887261) (xy 258.716312 -44.879316) (xy 258.689501 -44.878332)
			(xy 258.663362 -44.884377) (xy 258.639706 -44.897033) (xy 258.629658 -44.90593) (xy 258.608326 -44.925195)
			(xy 258.560966 -44.957764) (xy 258.509256 -44.982858) (xy 258.454366 -44.999909) (xy 258.397539 -45.008533)
			(xy 258.3688 -45.009054) (xy 258.341225 -45.008604) (xy 258.28665 -45.000651) (xy 258.23379 -44.984924)
			(xy 258.183743 -44.961751) (xy 258.137554 -44.931615) (xy 258.096185 -44.895143) (xy 258.07797 -44.874434)
			(xy 258.068072 -44.863536) (xy 258.043422 -44.847461) (xy 258.015214 -44.839077) (xy 257.985786 -44.839077)
			(xy 257.957578 -44.847461) (xy 257.932928 -44.863536) (xy 257.92303 -44.874434) (xy 257.904814 -44.895141)
			(xy 257.863446 -44.93161) (xy 257.817256 -44.961742) (xy 257.767209 -44.984908) (xy 257.714348 -45.000626)
			(xy 257.659774 -45.008567) (xy 257.6322 -45.009054) (xy 257.604952 -45.008476) (xy 257.551011 -45.00072)
			(xy 257.498723 -44.985367) (xy 257.449151 -44.962729) (xy 257.403306 -44.933266) (xy 257.362121 -44.897579)
			(xy 257.326434 -44.856394) (xy 257.296971 -44.810549) (xy 257.274333 -44.760977) (xy 257.25898 -44.708689)
			(xy 257.251224 -44.654748) (xy 256.076982 -44.654748) (xy 256.71399 -45.291756) (xy 256.731343 -45.309741)
			(xy 256.760742 -45.350154) (xy 256.783449 -45.394673) (xy 256.798903 -45.442199) (xy 256.806723 -45.491558)
			(xy 256.807208 -45.516546) (xy 256.807208 -46.603412) (xy 256.807634 -46.61695) (xy 256.814756 -46.643073)
			(xy 256.828497 -46.666404) (xy 256.847888 -46.685302) (xy 256.871566 -46.698436) (xy 256.897864 -46.704882)
			(xy 256.924931 -46.704187) (xy 256.938018 -46.700694) (xy 256.964876 -46.693093) (xy 257.020092 -46.68493)
			(xy 257.048 -46.684438) (xy 257.075574 -46.684925) (xy 257.130148 -46.692866) (xy 257.18301 -46.708584)
			(xy 257.233057 -46.73175) (xy 257.279247 -46.761881) (xy 257.320616 -46.79835) (xy 257.33883 -46.819058)
			(xy 257.348728 -46.829956) (xy 257.373378 -46.846031) (xy 257.401586 -46.854415) (xy 257.431014 -46.854415)
			(xy 257.459222 -46.846031) (xy 257.483872 -46.829956) (xy 257.49377 -46.819058) (xy 257.511985 -46.798352)
			(xy 257.553356 -46.761887) (xy 257.599546 -46.73176) (xy 257.649593 -46.708597) (xy 257.702454 -46.692881)
			(xy 257.757026 -46.684941) (xy 257.812174 -46.684941) (xy 257.866746 -46.692881) (xy 257.919607 -46.708597)
			(xy 257.969654 -46.73176) (xy 258.015844 -46.761887) (xy 258.057215 -46.798352) (xy 258.07543 -46.819058)
			(xy 258.085328 -46.829956) (xy 258.109978 -46.846031) (xy 258.138186 -46.854415) (xy 258.167614 -46.854415)
			(xy 258.195822 -46.846031) (xy 258.220472 -46.829956) (xy 258.23037 -46.819058) (xy 258.248585 -46.798349)
			(xy 258.289955 -46.761879) (xy 258.336144 -46.731743) (xy 258.38619 -46.708571) (xy 258.439051 -46.692844)
			(xy 258.493625 -46.68489) (xy 258.5212 -46.684438) (xy 258.548448 -46.684924) (xy 258.602389 -46.69268)
			(xy 258.654677 -46.708033) (xy 258.704249 -46.730671) (xy 258.750094 -46.760134) (xy 258.791279 -46.795821)
			(xy 258.826966 -46.837006) (xy 258.856429 -46.882851) (xy 258.879067 -46.932423) (xy 258.89442 -46.984711)
			(xy 258.902176 -47.038652) (xy 258.902176 -47.093148) (xy 258.89442 -47.147089) (xy 258.879067 -47.199377)
			(xy 258.856429 -47.248949) (xy 258.826966 -47.294794) (xy 258.791279 -47.335979) (xy 258.750094 -47.371666)
			(xy 258.704249 -47.401129) (xy 258.654677 -47.423767) (xy 258.602389 -47.43912) (xy 258.548448 -47.446876)
			(xy 258.5212 -47.447454) (xy 258.493626 -47.446967) (xy 258.439052 -47.439026) (xy 258.386191 -47.423308)
			(xy 258.336144 -47.400142) (xy 258.289954 -47.37001) (xy 258.248586 -47.333541) (xy 258.23037 -47.312834)
			(xy 258.220472 -47.301936) (xy 258.195822 -47.285861) (xy 258.167614 -47.277477) (xy 258.138186 -47.277477)
			(xy 258.109978 -47.285861) (xy 258.085328 -47.301936) (xy 258.07543 -47.312834) (xy 258.057215 -47.33354)
			(xy 258.015844 -47.370005) (xy 257.969654 -47.400132) (xy 257.919607 -47.423295) (xy 257.866746 -47.439011)
			(xy 257.812174 -47.446951) (xy 257.757026 -47.446951) (xy 257.702454 -47.439011) (xy 257.649593 -47.423295)
			(xy 257.599546 -47.400132) (xy 257.553356 -47.370005) (xy 257.511985 -47.33354) (xy 257.49377 -47.312834)
			(xy 257.483872 -47.301936) (xy 257.459222 -47.285861) (xy 257.431014 -47.277477) (xy 257.401586 -47.277477)
			(xy 257.373378 -47.285861) (xy 257.348728 -47.301936) (xy 257.33883 -47.312834) (xy 257.321376 -47.332705)
			(xy 257.281907 -47.36791) (xy 257.237948 -47.397316) (xy 257.190343 -47.420358) (xy 257.140007 -47.436592)
			(xy 257.11404 -47.441612) (xy 257.100449 -47.444474) (xy 257.075408 -47.456461) (xy 257.054522 -47.474751)
			(xy 257.039335 -47.497992) (xy 257.030971 -47.524464) (xy 257.030048 -47.552212) (xy 257.036635 -47.579181)
			(xy 257.050244 -47.60338) (xy 257.059684 -47.61357) (xy 257.82397 -48.377856) (xy 257.832548 -48.386746)
			(xy 258.861812 -48.386746) (xy 258.865883 -48.331124) (xy 258.878009 -48.276687) (xy 258.897932 -48.224596)
			(xy 258.925228 -48.175961) (xy 258.959314 -48.131818) (xy 258.999463 -48.093109) (xy 259.044821 -48.060658)
			(xy 259.094421 -48.035157) (xy 259.147205 -48.01715) (xy 259.202048 -48.00702) (xy 259.257782 -48.004983)
			(xy 259.313219 -48.011083) (xy 259.367176 -48.025189) (xy 259.418505 -48.047001) (xy 259.466111 -48.076055)
			(xy 259.508979 -48.11173) (xy 259.546196 -48.153267) (xy 259.576969 -48.19978) (xy 259.600641 -48.250277)
			(xy 259.616709 -48.303684) (xy 259.624829 -48.35886) (xy 259.625338 -48.386746) (xy 259.624829 -48.414632)
			(xy 259.616709 -48.469808) (xy 259.600641 -48.523215) (xy 259.576969 -48.573712) (xy 259.546196 -48.620225)
			(xy 259.508979 -48.661762) (xy 259.466111 -48.697437) (xy 259.418505 -48.726491) (xy 259.367176 -48.748303)
			(xy 259.313219 -48.762409) (xy 259.257782 -48.768509) (xy 259.202048 -48.766472) (xy 259.147205 -48.756342)
			(xy 259.094421 -48.738335) (xy 259.044821 -48.712834) (xy 258.999463 -48.680383) (xy 258.959314 -48.641674)
			(xy 258.925228 -48.597531) (xy 258.897932 -48.548896) (xy 258.878009 -48.496805) (xy 258.865883 -48.442368)
			(xy 258.861812 -48.386746) (xy 257.832548 -48.386746) (xy 257.841324 -48.395841) (xy 257.870725 -48.436253)
			(xy 257.893433 -48.480772) (xy 257.908888 -48.528298) (xy 257.916709 -48.577658) (xy 257.917188 -48.602646)
			(xy 257.917188 -55.339488) (xy 257.917704 -55.354472) (xy 257.926374 -55.383158) (xy 257.943 -55.40809)
			(xy 257.966149 -55.42712) (xy 257.993826 -55.438609) (xy 258.023648 -55.441566) (xy 258.053042 -55.435736)
			(xy 258.079478 -55.421622) (xy 258.090416 -55.41137) (xy 258.40182 -55.099966) (xy 258.40182 -54.106826)
			(xy 258.81076 -53.697886) (xy 260.31952 -53.697886) (xy 261.16788 -52.849526) (xy 261.16788 -38.125146)
			(xy 260.32968 -37.286946) (xy 251.37618 -37.286946) (xy 250.89612 -37.767006) (xy 250.89612 -38.854126)
			(xy 251.24918 -39.207186) (xy 251.24918 -43.489118) (xy 251.249607 -43.502651) (xy 251.256731 -43.528763)
			(xy 251.270471 -43.552082) (xy 251.289861 -43.570966) (xy 251.313535 -43.584085) (xy 251.339826 -43.590516)
			(xy 251.366882 -43.589805) (xy 251.37999 -43.5864) (xy 251.406679 -43.578948) (xy 251.461505 -43.570921)
			(xy 251.48921 -43.570398) (xy 251.51646 -43.570884) (xy 251.570406 -43.578642) (xy 251.622699 -43.593998)
			(xy 251.672274 -43.616639) (xy 251.718123 -43.646105) (xy 251.759311 -43.681796) (xy 251.795001 -43.722986)
			(xy 251.824466 -43.768835) (xy 251.847106 -43.81841) (xy 251.851996 -43.835066) (xy 252.707392 -43.835066)
			(xy 252.711463 -43.779444) (xy 252.723589 -43.725007) (xy 252.743512 -43.672916) (xy 252.770808 -43.624281)
			(xy 252.804894 -43.580138) (xy 252.845043 -43.541429) (xy 252.890401 -43.508978) (xy 252.940001 -43.483477)
			(xy 252.992785 -43.46547) (xy 253.047628 -43.45534) (xy 253.103362 -43.453303) (xy 253.158799 -43.459403)
			(xy 253.212756 -43.473509) (xy 253.264085 -43.495321) (xy 253.311691 -43.524375) (xy 253.354559 -43.56005)
			(xy 253.391776 -43.601587) (xy 253.422549 -43.6481) (xy 253.446221 -43.698597) (xy 253.462289 -43.752004)
			(xy 253.470409 -43.80718) (xy 253.470918 -43.835066) (xy 253.470409 -43.862952) (xy 253.462289 -43.918128)
			(xy 253.446221 -43.971535) (xy 253.422549 -44.022032) (xy 253.391776 -44.068545) (xy 253.354559 -44.110082)
			(xy 253.311691 -44.145757) (xy 253.264085 -44.174811) (xy 253.212756 -44.196623) (xy 253.158799 -44.210729)
			(xy 253.103362 -44.216829) (xy 253.047628 -44.214792) (xy 252.992785 -44.204662) (xy 252.940001 -44.186655)
			(xy 252.890401 -44.161154) (xy 252.845043 -44.128703) (xy 252.804894 -44.089994) (xy 252.770808 -44.045851)
			(xy 252.743512 -43.997216) (xy 252.723589 -43.945125) (xy 252.711463 -43.890688) (xy 252.707392 -43.835066)
			(xy 251.851996 -43.835066) (xy 251.86246 -43.870704) (xy 251.870216 -43.92465) (xy 251.870216 -43.97915)
			(xy 251.86246 -44.033096) (xy 251.847106 -44.08539) (xy 251.824466 -44.134965) (xy 251.795001 -44.180814)
			(xy 251.759311 -44.222004) (xy 251.718123 -44.257695) (xy 251.672274 -44.287161) (xy 251.622699 -44.309802)
			(xy 251.570406 -44.325158) (xy 251.51646 -44.332916) (xy 251.48921 -44.333414) (xy 251.461503 -44.33292)
			(xy 251.406674 -44.324888) (xy 251.37999 -44.317412) (xy 251.366905 -44.313929) (xy 251.339845 -44.31324)
			(xy 251.313556 -44.319689) (xy 251.289887 -44.332823) (xy 251.270504 -44.351718) (xy 251.25677 -44.375044)
			(xy 251.249652 -44.40116) (xy 251.24918 -44.414694) (xy 251.24918 -45.447966) (xy 252.11786 -46.316646)
			(xy 252.11786 -47.065946) (xy 253.419862 -47.065946) (xy 253.423933 -47.010324) (xy 253.436059 -46.955887)
			(xy 253.455982 -46.903796) (xy 253.483278 -46.855161) (xy 253.517364 -46.811018) (xy 253.557513 -46.772309)
			(xy 253.602871 -46.739858) (xy 253.652471 -46.714357) (xy 253.705255 -46.69635) (xy 253.760098 -46.68622)
			(xy 253.815832 -46.684183) (xy 253.871269 -46.690283) (xy 253.925226 -46.704389) (xy 253.976555 -46.726201)
			(xy 254.024161 -46.755255) (xy 254.067029 -46.79093) (xy 254.104246 -46.832467) (xy 254.135019 -46.87898)
			(xy 254.158691 -46.929477) (xy 254.174759 -46.982884) (xy 254.182879 -47.03806) (xy 254.183388 -47.065946)
			(xy 254.308862 -47.065946) (xy 254.312933 -47.010324) (xy 254.325059 -46.955887) (xy 254.344982 -46.903796)
			(xy 254.372278 -46.855161) (xy 254.406364 -46.811018) (xy 254.446513 -46.772309) (xy 254.491871 -46.739858)
			(xy 254.541471 -46.714357) (xy 254.594255 -46.69635) (xy 254.649098 -46.68622) (xy 254.704832 -46.684183)
			(xy 254.760269 -46.690283) (xy 254.814226 -46.704389) (xy 254.865555 -46.726201) (xy 254.913161 -46.755255)
			(xy 254.956029 -46.79093) (xy 254.993246 -46.832467) (xy 255.024019 -46.87898) (xy 255.047691 -46.929477)
			(xy 255.063759 -46.982884) (xy 255.071879 -47.03806) (xy 255.072388 -47.065946) (xy 255.071879 -47.093832)
			(xy 255.063759 -47.149008) (xy 255.047691 -47.202415) (xy 255.024019 -47.252912) (xy 254.993246 -47.299425)
			(xy 254.956029 -47.340962) (xy 254.913161 -47.376637) (xy 254.865555 -47.405691) (xy 254.814226 -47.427503)
			(xy 254.760269 -47.441609) (xy 254.704832 -47.447709) (xy 254.649098 -47.445672) (xy 254.594255 -47.435542)
			(xy 254.541471 -47.417535) (xy 254.491871 -47.392034) (xy 254.446513 -47.359583) (xy 254.406364 -47.320874)
			(xy 254.372278 -47.276731) (xy 254.344982 -47.228096) (xy 254.325059 -47.176005) (xy 254.312933 -47.121568)
			(xy 254.308862 -47.065946) (xy 254.183388 -47.065946) (xy 254.182879 -47.093832) (xy 254.174759 -47.149008)
			(xy 254.158691 -47.202415) (xy 254.135019 -47.252912) (xy 254.104246 -47.299425) (xy 254.067029 -47.340962)
			(xy 254.024161 -47.376637) (xy 253.976555 -47.405691) (xy 253.925226 -47.427503) (xy 253.871269 -47.441609)
			(xy 253.815832 -47.447709) (xy 253.760098 -47.445672) (xy 253.705255 -47.435542) (xy 253.652471 -47.417535)
			(xy 253.602871 -47.392034) (xy 253.557513 -47.359583) (xy 253.517364 -47.320874) (xy 253.483278 -47.276731)
			(xy 253.455982 -47.228096) (xy 253.436059 -47.176005) (xy 253.423933 -47.121568) (xy 253.419862 -47.065946)
			(xy 252.11786 -47.065946) (xy 252.11786 -51.975766) (xy 251.7648 -52.328826) (xy 244.43436 -52.328826)
			(xy 244.04828 -52.714906) (xy 244.04828 -53.660294) (xy 244.08892 -53.668676) (xy 244.115435 -53.67454)
			(xy 244.166421 -53.693224) (xy 244.213979 -53.719433) (xy 244.257006 -53.752561) (xy 244.294503 -53.791838)
			(xy 244.3256 -53.836353) (xy 244.349578 -53.885074) (xy 244.365879 -53.936872) (xy 244.374126 -53.990544)
			(xy 244.374127 -54.044845) (xy 244.365882 -54.098518) (xy 244.349582 -54.150316) (xy 244.325606 -54.199038)
			(xy 244.29451 -54.243554) (xy 244.257014 -54.282832) (xy 244.213988 -54.315961) (xy 244.166431 -54.342172)
			(xy 244.115446 -54.360857) (xy 244.08892 -54.366668) (xy 244.04828 -54.37505) (xy 244.04828 -55.022242)
			(xy 248.993912 -55.022242) (xy 248.997983 -54.96662) (xy 249.010109 -54.912183) (xy 249.030032 -54.860092)
			(xy 249.057328 -54.811457) (xy 249.091414 -54.767314) (xy 249.131563 -54.728605) (xy 249.176921 -54.696154)
			(xy 249.226521 -54.670653) (xy 249.279305 -54.652646) (xy 249.334148 -54.642516) (xy 249.389882 -54.640479)
			(xy 249.445319 -54.646579) (xy 249.499276 -54.660685) (xy 249.550605 -54.682497) (xy 249.598211 -54.711551)
			(xy 249.641079 -54.747226) (xy 249.678296 -54.788763) (xy 249.709069 -54.835276) (xy 249.732741 -54.885773)
			(xy 249.748809 -54.93918) (xy 249.756929 -54.994356) (xy 249.757438 -55.022242) (xy 249.756929 -55.050128)
			(xy 249.753557 -55.073042) (xy 251.127512 -55.073042) (xy 251.131583 -55.01742) (xy 251.143709 -54.962983)
			(xy 251.163632 -54.910892) (xy 251.190928 -54.862257) (xy 251.225014 -54.818114) (xy 251.265163 -54.779405)
			(xy 251.310521 -54.746954) (xy 251.360121 -54.721453) (xy 251.412905 -54.703446) (xy 251.467748 -54.693316)
			(xy 251.523482 -54.691279) (xy 251.578919 -54.697379) (xy 251.632876 -54.711485) (xy 251.684205 -54.733297)
			(xy 251.731811 -54.762351) (xy 251.774679 -54.798026) (xy 251.811896 -54.839563) (xy 251.842669 -54.886076)
			(xy 251.866341 -54.936573) (xy 251.882409 -54.98998) (xy 251.890529 -55.045156) (xy 251.891038 -55.073042)
			(xy 251.890529 -55.100928) (xy 251.882409 -55.156104) (xy 251.866341 -55.209511) (xy 251.842669 -55.260008)
			(xy 251.811896 -55.306521) (xy 251.774679 -55.348058) (xy 251.731811 -55.383733) (xy 251.684205 -55.412787)
			(xy 251.632876 -55.434599) (xy 251.578919 -55.448705) (xy 251.523482 -55.454805) (xy 251.467748 -55.452768)
			(xy 251.412905 -55.442638) (xy 251.360121 -55.424631) (xy 251.310521 -55.39913) (xy 251.265163 -55.366679)
			(xy 251.225014 -55.32797) (xy 251.190928 -55.283827) (xy 251.163632 -55.235192) (xy 251.143709 -55.183101)
			(xy 251.131583 -55.128664) (xy 251.127512 -55.073042) (xy 249.753557 -55.073042) (xy 249.748809 -55.105304)
			(xy 249.732741 -55.158711) (xy 249.709069 -55.209208) (xy 249.678296 -55.255721) (xy 249.641079 -55.297258)
			(xy 249.598211 -55.332933) (xy 249.550605 -55.361987) (xy 249.499276 -55.383799) (xy 249.445319 -55.397905)
			(xy 249.389882 -55.404005) (xy 249.334148 -55.401968) (xy 249.279305 -55.391838) (xy 249.226521 -55.373831)
			(xy 249.176921 -55.34833) (xy 249.131563 -55.315879) (xy 249.091414 -55.27717) (xy 249.057328 -55.233027)
			(xy 249.030032 -55.184392) (xy 249.010109 -55.132301) (xy 248.997983 -55.077864) (xy 248.993912 -55.022242)
			(xy 244.04828 -55.022242) (xy 244.04828 -55.27675) (xy 247.18518 -58.413396) (xy 252.682502 -58.413396)
			(xy 253.922276 -57.173876) (xy 253.922276 -55.854092) (xy 253.922762 -55.826859) (xy 253.930513 -55.772947)
			(xy 253.945858 -55.720687) (xy 253.968484 -55.671143) (xy 253.997931 -55.625323) (xy 254.033598 -55.58416)
			(xy 254.074761 -55.548493) (xy 254.120581 -55.519046) (xy 254.170125 -55.49642) (xy 254.222385 -55.481075)
			(xy 254.276297 -55.473324) (xy 254.330763 -55.473324) (xy 254.384675 -55.481075) (xy 254.436935 -55.49642)
			(xy 254.486479 -55.519046) (xy 254.532299 -55.548493) (xy 254.573462 -55.58416) (xy 254.609129 -55.625323)
			(xy 254.638576 -55.671143) (xy 254.661202 -55.720687) (xy 254.676547 -55.772947) (xy 254.684298 -55.826859)
			(xy 254.684784 -55.854092) (xy 254.684784 -57.331864) (xy 254.684216 -57.361833) (xy 254.674881 -57.421039)
			(xy 254.656405 -57.478057) (xy 254.62924 -57.531486) (xy 254.594057 -57.58001) (xy 254.573278 -57.601612)
			(xy 253.445772 -58.728864) (xy 253.435546 -58.739842) (xy 253.421411 -58.766289) (xy 253.415563 -58.7957)
			(xy 253.418507 -58.825543) (xy 253.429989 -58.853244) (xy 253.44902 -58.876419) (xy 253.47396 -58.893069)
			(xy 253.50266 -58.901761) (xy 253.517654 -58.902346) (xy 254.25908 -58.902346)
		)
		(stroke
			(width 0)
			(type solid)
		)
		(fill yes)
		(layer "In2.Cu")
		(net "GND")
	)
	(gr_poly
		(pts
			(xy 446.239392 -32.671766) (xy 446.238122 -32.66567) (xy 446.232798 -32.642991) (xy 446.227062 -32.59676)
			(xy 446.226692 -32.573468) (xy 446.227178 -32.546217) (xy 446.234934 -32.492269) (xy 446.250289 -32.439974)
			(xy 446.272931 -32.390397) (xy 446.302397 -32.344547) (xy 446.338088 -32.303356) (xy 446.379279 -32.267665)
			(xy 446.425129 -32.238199) (xy 446.474706 -32.215557) (xy 446.527001 -32.200202) (xy 446.580949 -32.192446)
			(xy 446.635451 -32.192446) (xy 446.689399 -32.200202) (xy 446.741694 -32.215557) (xy 446.791271 -32.238199)
			(xy 446.837121 -32.267665) (xy 446.878312 -32.303356) (xy 446.914003 -32.344547) (xy 446.943469 -32.390397)
			(xy 446.966111 -32.439974) (xy 446.981466 -32.492269) (xy 446.989222 -32.546217) (xy 446.989708 -32.573468)
			(xy 446.989326 -32.59676) (xy 446.983591 -32.642989) (xy 446.978278 -32.66567) (xy 446.977008 -32.671766)
			(xy 446.977008 -35.016948) (xy 449.25488 -35.016948) (xy 450.39788 -33.873948) (xy 450.39788 -28.412948)
			(xy 449.6816 -27.696668) (xy 449.64604 -27.727656) (xy 449.6435 -27.729688) (xy 449.632597 -27.739587)
			(xy 449.616514 -27.764241) (xy 449.60812 -27.792455) (xy 449.608112 -27.821891) (xy 449.616491 -27.85011)
			(xy 449.632561 -27.874772) (xy 449.6435 -27.884628) (xy 449.664203 -27.902846) (xy 449.700662 -27.944219)
			(xy 449.730786 -27.99041) (xy 449.753947 -28.040456) (xy 449.769663 -28.093315) (xy 449.777607 -28.147885)
			(xy 449.77812 -28.175458) (xy 449.7777 -28.201778) (xy 449.770503 -28.253921) (xy 449.756199 -28.304579)
			(xy 449.735059 -28.352786) (xy 449.707486 -28.397625) (xy 449.674005 -28.438242) (xy 449.65493 -28.456382)
			(xy 449.644901 -28.466193) (xy 449.630188 -28.490068) (xy 449.622538 -28.517049) (xy 449.622531 -28.545094)
			(xy 449.630165 -28.572079) (xy 449.644865 -28.595963) (xy 449.65493 -28.605734) (xy 449.67399 -28.623884)
			(xy 449.707443 -28.664516) (xy 449.734999 -28.709358) (xy 449.756133 -28.75756) (xy 449.770447 -28.808208)
			(xy 449.777668 -28.860342) (xy 449.77812 -28.886658) (xy 449.777634 -28.913909) (xy 449.769878 -28.967857)
			(xy 449.754523 -29.020152) (xy 449.731881 -29.069729) (xy 449.702415 -29.115579) (xy 449.666724 -29.15677)
			(xy 449.625533 -29.192461) (xy 449.579683 -29.221927) (xy 449.530106 -29.244569) (xy 449.477811 -29.259924)
			(xy 449.423863 -29.26768) (xy 449.369361 -29.26768) (xy 449.315413 -29.259924) (xy 449.263118 -29.244569)
			(xy 449.213541 -29.221927) (xy 449.167691 -29.192461) (xy 449.1265 -29.15677) (xy 449.090809 -29.115579)
			(xy 449.061343 -29.069729) (xy 449.038701 -29.020152) (xy 449.023346 -28.967857) (xy 449.01559 -28.913909)
			(xy 449.015104 -28.886658) (xy 449.015522 -28.860337) (xy 449.022717 -28.808191) (xy 449.037017 -28.757531)
			(xy 449.058153 -28.70932) (xy 449.085721 -28.664475) (xy 449.119197 -28.623851) (xy 449.138294 -28.605734)
			(xy 449.148309 -28.595922) (xy 449.162996 -28.572053) (xy 449.170624 -28.545085) (xy 449.170616 -28.517059)
			(xy 449.162973 -28.490095) (xy 449.148272 -28.466234) (xy 449.138294 -28.456382) (xy 449.119232 -28.438233)
			(xy 449.085775 -28.397602) (xy 449.058216 -28.35276) (xy 449.037078 -28.304558) (xy 449.022761 -28.25391)
			(xy 449.015537 -28.201775) (xy 449.015104 -28.175458) (xy 449.015587 -28.147882) (xy 449.023522 -28.093305)
			(xy 449.039235 -28.04044) (xy 449.062399 -27.99039) (xy 449.092531 -27.944197) (xy 449.129001 -27.902826)
			(xy 449.149724 -27.884628) (xy 449.160613 -27.874728) (xy 449.176669 -27.850081) (xy 449.18504 -27.821881)
			(xy 449.185032 -27.792465) (xy 449.176646 -27.76427) (xy 449.160576 -27.739631) (xy 449.149724 -27.729688)
			(xy 449.129019 -27.711471) (xy 449.092556 -27.670099) (xy 449.062428 -27.623909) (xy 449.039263 -27.573863)
			(xy 449.023544 -27.521003) (xy 449.015597 -27.466432) (xy 449.015104 -27.438858) (xy 449.015593 -27.411668)
			(xy 449.023321 -27.357839) (xy 449.038601 -27.30565) (xy 449.061125 -27.256153) (xy 449.090436 -27.210348)
			(xy 449.107814 -27.18943) (xy 449.138802 -27.15387) (xy 447.34988 -25.364948) (xy 447.34988 -23.342092)
			(xy 447.349378 -23.327226) (xy 447.340835 -23.298749) (xy 447.324446 -23.273942) (xy 447.301603 -23.254912)
			(xy 447.274244 -23.243274) (xy 447.244692 -23.240014) (xy 447.229992 -23.24227) (xy 447.212993 -23.24514)
			(xy 447.178651 -23.248196) (xy 447.161412 -23.248366) (xy 447.13416 -23.247903) (xy 447.08021 -23.240148)
			(xy 447.027913 -23.224792) (xy 446.978334 -23.20215) (xy 446.932482 -23.172681) (xy 446.891292 -23.136987)
			(xy 446.855601 -23.095794) (xy 446.826136 -23.04994) (xy 446.803497 -23.000359) (xy 446.788146 -22.948061)
			(xy 446.780394 -22.89411) (xy 446.779904 -22.866858) (xy 446.780432 -22.838412) (xy 446.788885 -22.782151)
			(xy 446.805598 -22.727768) (xy 446.830199 -22.67647) (xy 446.862143 -22.629393) (xy 446.900724 -22.58758)
			(xy 446.945084 -22.551958) (xy 446.969388 -22.537166) (xy 446.981277 -22.529674) (xy 447.000725 -22.509404)
			(xy 447.013926 -22.484608) (xy 447.019883 -22.457156) (xy 447.018146 -22.429119) (xy 447.008847 -22.402611)
			(xy 447.001138 -22.390862) (xy 446.987421 -22.37066) (xy 446.965692 -22.326932) (xy 446.950908 -22.280394)
			(xy 446.943418 -22.232143) (xy 446.942972 -22.207728) (xy 446.942972 -18.830036) (xy 446.942516 -18.815911)
			(xy 446.934777 -18.788743) (xy 446.919883 -18.76474) (xy 446.898976 -18.745743) (xy 446.87366 -18.733209)
			(xy 446.845877 -18.7281) (xy 446.817758 -18.730808) (xy 446.79146 -18.741125) (xy 446.779904 -18.749264)
			(xy 446.759853 -18.764086) (xy 446.716635 -18.788956) (xy 446.670547 -18.807985) (xy 446.622373 -18.82085)
			(xy 446.572933 -18.827332) (xy 446.548002 -18.82775) (xy 446.520746 -18.827287) (xy 446.466789 -18.81953)
			(xy 446.414485 -18.804172) (xy 446.364899 -18.781527) (xy 446.319041 -18.752056) (xy 446.277843 -18.716358)
			(xy 446.242145 -18.675161) (xy 446.212674 -18.629303) (xy 446.190029 -18.579717) (xy 446.174671 -18.527413)
			(xy 446.166913 -18.473456) (xy 446.166913 -18.418944) (xy 446.174671 -18.364987) (xy 446.190029 -18.312683)
			(xy 446.212674 -18.263097) (xy 446.242145 -18.217239) (xy 446.277843 -18.176042) (xy 446.319041 -18.140344)
			(xy 446.364899 -18.110873) (xy 446.414485 -18.088228) (xy 446.466789 -18.07287) (xy 446.520746 -18.065113)
			(xy 446.548002 -18.064734) (xy 446.572934 -18.065138) (xy 446.622374 -18.071627) (xy 446.670549 -18.084494)
			(xy 446.71664 -18.103521) (xy 446.759863 -18.128384) (xy 446.779904 -18.14322) (xy 446.791427 -18.151401)
			(xy 446.817738 -18.16168) (xy 446.845858 -18.164361) (xy 446.873637 -18.159238) (xy 446.898952 -18.146704)
			(xy 446.919866 -18.127717) (xy 446.934781 -18.103728) (xy 446.942556 -18.076571) (xy 446.942972 -18.062448)
			(xy 446.942972 -16.934688) (xy 446.943484 -16.909704) (xy 446.951335 -16.860356) (xy 446.966795 -16.81284)
			(xy 446.989485 -16.76832) (xy 447.018849 -16.72789) (xy 447.03619 -16.709898) (xy 447.24701 -16.499078)
			(xy 446.96888 -16.220948) (xy 444.17488 -16.220948) (xy 442.4426 -17.953228) (xy 442.433383 -17.963031)
			(xy 442.419992 -17.986359) (xy 442.413156 -18.012374) (xy 442.413348 -18.039271) (xy 442.420555 -18.065186)
			(xy 442.434277 -18.088321) (xy 442.443616 -18.098008) (xy 442.461595 -18.116039) (xy 442.4931 -18.156042)
			(xy 442.519004 -18.19988) (xy 442.538844 -18.246775) (xy 442.55227 -18.295893) (xy 442.559042 -18.34636)
			(xy 442.55944 -18.37182) (xy 442.558967 -18.399189) (xy 442.551139 -18.453365) (xy 442.535648 -18.505866)
			(xy 442.512811 -18.555613) (xy 442.483098 -18.601585) (xy 442.46546 -18.622518) (xy 442.456229 -18.633846)
			(xy 442.444062 -18.660403) (xy 442.439896 -18.689315) (xy 442.444071 -18.718226) (xy 442.456246 -18.744779)
			(xy 442.46546 -18.756122) (xy 442.483102 -18.777053) (xy 442.512829 -18.823019) (xy 442.535672 -18.872766)
			(xy 442.551161 -18.92527) (xy 442.558977 -18.979449) (xy 442.55944 -19.00682) (xy 442.558954 -19.034071)
			(xy 442.551198 -19.088019) (xy 442.535843 -19.140314) (xy 442.513201 -19.189891) (xy 442.483735 -19.235741)
			(xy 442.448044 -19.276932) (xy 442.406853 -19.312623) (xy 442.361003 -19.342089) (xy 442.311426 -19.364731)
			(xy 442.259131 -19.380086) (xy 442.205183 -19.387842) (xy 442.150681 -19.387842) (xy 442.096733 -19.380086)
			(xy 442.044438 -19.364731) (xy 441.994861 -19.342089) (xy 441.949011 -19.312623) (xy 441.90782 -19.276932)
			(xy 441.872129 -19.235741) (xy 441.842663 -19.189891) (xy 441.820021 -19.140314) (xy 441.804666 -19.088019)
			(xy 441.79691 -19.034071) (xy 441.796424 -19.00682) (xy 441.796901 -18.979452) (xy 441.804736 -18.92528)
			(xy 441.820233 -18.872783) (xy 441.843073 -18.823041) (xy 441.872789 -18.777073) (xy 441.890404 -18.756122)
			(xy 441.899643 -18.744795) (xy 441.911826 -18.718235) (xy 441.916003 -18.689315) (xy 441.911834 -18.660394)
			(xy 441.89966 -18.633831) (xy 441.890404 -18.622518) (xy 441.874402 -18.60296) (xy 441.87237 -18.600166)
			(xy 441.834016 -18.561812) (xy 441.063888 -19.332194) (xy 441.063888 -19.640804) (xy 441.063332 -19.669779)
			(xy 441.05423 -19.727009) (xy 441.036282 -19.782109) (xy 441.009931 -19.833721) (xy 440.975826 -19.880573)
			(xy 440.955684 -19.901408) (xy 439.945351 -20.91182) (xy 441.796424 -20.91182) (xy 441.796896 -20.88445)
			(xy 441.804711 -20.830271) (xy 441.820199 -20.777768) (xy 441.843039 -20.728021) (xy 441.872763 -20.682054)
			(xy 441.890404 -20.661122) (xy 441.899621 -20.64978) (xy 441.911801 -20.623228) (xy 441.915977 -20.594315)
			(xy 441.911809 -20.565401) (xy 441.899638 -20.538845) (xy 441.890404 -20.527518) (xy 441.872761 -20.506589)
			(xy 441.843049 -20.460616) (xy 441.820214 -20.410867) (xy 441.804724 -20.358366) (xy 441.796897 -20.304189)
			(xy 441.796424 -20.27682) (xy 441.79691 -20.249569) (xy 441.804666 -20.195621) (xy 441.820021 -20.143326)
			(xy 441.842663 -20.093749) (xy 441.872129 -20.047899) (xy 441.90782 -20.006708) (xy 441.949011 -19.971017)
			(xy 441.994861 -19.941551) (xy 442.044438 -19.918909) (xy 442.096733 -19.903554) (xy 442.150681 -19.895798)
			(xy 442.205183 -19.895798) (xy 442.259131 -19.903554) (xy 442.311426 -19.918909) (xy 442.361003 -19.941551)
			(xy 442.406853 -19.971017) (xy 442.448044 -20.006708) (xy 442.483735 -20.047899) (xy 442.513201 -20.093749)
			(xy 442.535843 -20.143326) (xy 442.551198 -20.195621) (xy 442.558954 -20.249569) (xy 442.55944 -20.27682)
			(xy 442.559 -20.304191) (xy 442.551178 -20.358372) (xy 442.535684 -20.410876) (xy 442.512836 -20.460623)
			(xy 442.483105 -20.506588) (xy 442.46546 -20.527518) (xy 442.456207 -20.538832) (xy 442.444037 -20.565395)
			(xy 442.43987 -20.594315) (xy 442.444046 -20.623234) (xy 442.456224 -20.649793) (xy 442.46546 -20.661122)
			(xy 442.48307 -20.682078) (xy 442.512787 -20.728043) (xy 442.53563 -20.777785) (xy 442.551127 -20.830281)
			(xy 442.558963 -20.884452) (xy 442.55944 -20.91182) (xy 442.558954 -20.939071) (xy 442.551198 -20.993019)
			(xy 442.535843 -21.045314) (xy 442.513201 -21.094891) (xy 442.483735 -21.140741) (xy 442.448044 -21.181932)
			(xy 442.406853 -21.217623) (xy 442.361003 -21.247089) (xy 442.311426 -21.269731) (xy 442.259131 -21.285086)
			(xy 442.205183 -21.292842) (xy 442.150681 -21.292842) (xy 442.096733 -21.285086) (xy 442.044438 -21.269731)
			(xy 441.994861 -21.247089) (xy 441.949011 -21.217623) (xy 441.90782 -21.181932) (xy 441.872129 -21.140741)
			(xy 441.842663 -21.094891) (xy 441.820021 -21.045314) (xy 441.804666 -20.993019) (xy 441.79691 -20.939071)
			(xy 441.796424 -20.91182) (xy 439.945351 -20.91182) (xy 437.714136 -23.14321) (xy 437.704677 -23.153307)
			(xy 437.691069 -23.177383) (xy 437.684424 -23.204228) (xy 437.685231 -23.231872) (xy 437.69343 -23.258284)
			(xy 437.70842 -23.281525) (xy 437.729098 -23.299888) (xy 437.753948 -23.312025) (xy 437.767476 -23.314914)
			(xy 437.793393 -23.3202) (xy 437.843555 -23.336982) (xy 437.890914 -23.360538) (xy 437.934561 -23.390417)
			(xy 437.973656 -23.426045) (xy 438.00745 -23.466736) (xy 438.035292 -23.511709) (xy 438.056648 -23.560101)
			(xy 438.071106 -23.61098) (xy 438.078391 -23.663371) (xy 438.07888 -23.689818) (xy 438.078415 -23.717069)
			(xy 438.070656 -23.771017) (xy 438.055298 -23.823311) (xy 438.032654 -23.872887) (xy 438.003185 -23.918736)
			(xy 437.967491 -23.959924) (xy 437.926299 -23.995613) (xy 437.880447 -24.025077) (xy 437.830868 -24.047714)
			(xy 437.778572 -24.063066) (xy 437.724623 -24.070819) (xy 437.697372 -24.071326) (xy 437.670931 -24.070866)
			(xy 437.618557 -24.063543) (xy 437.567697 -24.049055) (xy 437.519326 -24.02768) (xy 437.474372 -23.999828)
			(xy 437.433697 -23.966032) (xy 437.39808 -23.926942) (xy 437.368205 -23.883306) (xy 437.344644 -23.835961)
			(xy 437.32785 -23.785816) (xy 437.322468 -23.759922) (xy 437.319479 -23.746429) (xy 437.307317 -23.721626)
			(xy 437.288955 -23.700988) (xy 437.265736 -23.686023) (xy 437.239356 -23.677824) (xy 437.211744 -23.676992)
			(xy 437.184919 -23.683586) (xy 437.16084 -23.697126) (xy 437.150764 -23.706582) (xy 435.033928 -25.823418)
			(xy 437.264554 -25.823418) (xy 437.268625 -25.767796) (xy 437.280751 -25.713359) (xy 437.300674 -25.661268)
			(xy 437.32797 -25.612633) (xy 437.362056 -25.56849) (xy 437.402205 -25.529781) (xy 437.447563 -25.49733)
			(xy 437.497163 -25.471829) (xy 437.549947 -25.453822) (xy 437.60479 -25.443692) (xy 437.660524 -25.441655)
			(xy 437.715961 -25.447755) (xy 437.769918 -25.461861) (xy 437.821247 -25.483673) (xy 437.868853 -25.512727)
			(xy 437.911721 -25.548402) (xy 437.948938 -25.589939) (xy 437.979711 -25.636452) (xy 438.003383 -25.686949)
			(xy 438.019451 -25.740356) (xy 438.027571 -25.795532) (xy 438.02808 -25.823418) (xy 438.027571 -25.851304)
			(xy 438.024386 -25.872948) (xy 440.745372 -25.872948) (xy 440.745911 -25.846179) (xy 440.753416 -25.793169)
			(xy 440.768258 -25.74173) (xy 440.790146 -25.69287) (xy 440.818649 -25.647549) (xy 440.853207 -25.606658)
			(xy 440.893142 -25.571) (xy 440.937671 -25.541275) (xy 440.985917 -25.518066) (xy 441.036934 -25.501829)
			(xy 441.08972 -25.492884) (xy 441.116466 -25.491694) (xy 441.130171 -25.490836) (xy 441.156404 -25.482755)
			(xy 441.179535 -25.467978) (xy 441.197895 -25.447573) (xy 441.210156 -25.423014) (xy 441.215431 -25.396077)
			(xy 441.21334 -25.368708) (xy 441.204034 -25.342885) (xy 441.196476 -25.33142) (xy 441.179919 -25.307123)
			(xy 441.153727 -25.254482) (xy 441.135917 -25.198448) (xy 441.12691 -25.140346) (xy 441.126372 -25.110948)
			(xy 441.126858 -25.083697) (xy 441.134614 -25.029749) (xy 441.149969 -24.977454) (xy 441.172611 -24.927877)
			(xy 441.202077 -24.882027) (xy 441.237768 -24.840836) (xy 441.278959 -24.805145) (xy 441.324809 -24.775679)
			(xy 441.374386 -24.753037) (xy 441.426681 -24.737682) (xy 441.480629 -24.729926) (xy 441.535131 -24.729926)
			(xy 441.589079 -24.737682) (xy 441.641374 -24.753037) (xy 441.690951 -24.775679) (xy 441.736801 -24.805145)
			(xy 441.777992 -24.840836) (xy 441.813683 -24.882027) (xy 441.843149 -24.927877) (xy 441.865791 -24.977454)
			(xy 441.881146 -25.029749) (xy 441.888902 -25.083697) (xy 441.889388 -25.110948) (xy 441.888884 -25.137719)
			(xy 441.881378 -25.190731) (xy 441.866535 -25.242174) (xy 441.844645 -25.291037) (xy 441.816139 -25.336359)
			(xy 441.781577 -25.377251) (xy 441.741637 -25.412909) (xy 441.697104 -25.442634) (xy 441.648854 -25.465841)
			(xy 441.597832 -25.482074) (xy 441.545042 -25.491014) (xy 441.518294 -25.492202) (xy 441.504588 -25.49304)
			(xy 441.478358 -25.501129) (xy 441.45523 -25.515911) (xy 441.436873 -25.536319) (xy 441.424614 -25.560878)
			(xy 441.419339 -25.587815) (xy 441.421427 -25.615185) (xy 441.430729 -25.64101) (xy 441.438284 -25.652476)
			(xy 441.454835 -25.676778) (xy 441.481029 -25.729416) (xy 441.498841 -25.785449) (xy 441.50785 -25.84355)
			(xy 441.508388 -25.872948) (xy 441.634372 -25.872948) (xy 441.634911 -25.846179) (xy 441.642416 -25.793169)
			(xy 441.657258 -25.74173) (xy 441.679146 -25.69287) (xy 441.707649 -25.647549) (xy 441.742207 -25.606658)
			(xy 441.782142 -25.571) (xy 441.826671 -25.541275) (xy 441.874917 -25.518066) (xy 441.925934 -25.501829)
			(xy 441.97872 -25.492884) (xy 442.005466 -25.491694) (xy 442.019171 -25.490836) (xy 442.045404 -25.482755)
			(xy 442.068535 -25.467978) (xy 442.086895 -25.447573) (xy 442.099156 -25.423014) (xy 442.104431 -25.396077)
			(xy 442.10234 -25.368708) (xy 442.093034 -25.342885) (xy 442.085476 -25.33142) (xy 442.068919 -25.307123)
			(xy 442.042727 -25.254482) (xy 442.024917 -25.198448) (xy 442.01591 -25.140346) (xy 442.015372 -25.110948)
			(xy 442.015858 -25.083697) (xy 442.023614 -25.029749) (xy 442.038969 -24.977454) (xy 442.061611 -24.927877)
			(xy 442.091077 -24.882027) (xy 442.126768 -24.840836) (xy 442.167959 -24.805145) (xy 442.213809 -24.775679)
			(xy 442.263386 -24.753037) (xy 442.315681 -24.737682) (xy 442.369629 -24.729926) (xy 442.424131 -24.729926)
			(xy 442.478079 -24.737682) (xy 442.530374 -24.753037) (xy 442.579951 -24.775679) (xy 442.625801 -24.805145)
			(xy 442.666992 -24.840836) (xy 442.702683 -24.882027) (xy 442.732149 -24.927877) (xy 442.754791 -24.977454)
			(xy 442.770146 -25.029749) (xy 442.777902 -25.083697) (xy 442.778388 -25.110948) (xy 442.777884 -25.137719)
			(xy 442.770378 -25.190731) (xy 442.755535 -25.242174) (xy 442.733645 -25.291037) (xy 442.705139 -25.336359)
			(xy 442.670577 -25.377251) (xy 442.630637 -25.412909) (xy 442.586104 -25.442634) (xy 442.537854 -25.465841)
			(xy 442.486832 -25.482074) (xy 442.434042 -25.491014) (xy 442.407294 -25.492202) (xy 442.393588 -25.49304)
			(xy 442.367358 -25.501129) (xy 442.34423 -25.515911) (xy 442.325873 -25.536319) (xy 442.313614 -25.560878)
			(xy 442.308339 -25.587815) (xy 442.310427 -25.615185) (xy 442.319729 -25.64101) (xy 442.327284 -25.652476)
			(xy 442.343835 -25.676778) (xy 442.370029 -25.729416) (xy 442.387841 -25.785449) (xy 442.39685 -25.84355)
			(xy 442.397388 -25.872948) (xy 442.523372 -25.872948) (xy 442.523911 -25.846179) (xy 442.531416 -25.793169)
			(xy 442.546258 -25.74173) (xy 442.568146 -25.69287) (xy 442.596649 -25.647549) (xy 442.631207 -25.606658)
			(xy 442.671142 -25.571) (xy 442.715671 -25.541275) (xy 442.763917 -25.518066) (xy 442.814934 -25.501829)
			(xy 442.86772 -25.492884) (xy 442.894466 -25.491694) (xy 442.908171 -25.490836) (xy 442.934404 -25.482755)
			(xy 442.957535 -25.467978) (xy 442.975895 -25.447573) (xy 442.988156 -25.423014) (xy 442.993431 -25.396077)
			(xy 442.99134 -25.368708) (xy 442.982034 -25.342885) (xy 442.974476 -25.33142) (xy 442.957919 -25.307123)
			(xy 442.931727 -25.254482) (xy 442.913917 -25.198448) (xy 442.90491 -25.140346) (xy 442.904372 -25.110948)
			(xy 442.904858 -25.083697) (xy 442.912614 -25.029749) (xy 442.927969 -24.977454) (xy 442.950611 -24.927877)
			(xy 442.980077 -24.882027) (xy 443.015768 -24.840836) (xy 443.056959 -24.805145) (xy 443.102809 -24.775679)
			(xy 443.152386 -24.753037) (xy 443.204681 -24.737682) (xy 443.258629 -24.729926) (xy 443.313131 -24.729926)
			(xy 443.313284 -24.729948) (xy 443.792862 -24.729948) (xy 443.796933 -24.674326) (xy 443.809059 -24.619889)
			(xy 443.828982 -24.567798) (xy 443.856278 -24.519163) (xy 443.890364 -24.47502) (xy 443.930513 -24.436311)
			(xy 443.975871 -24.40386) (xy 444.025471 -24.378359) (xy 444.078255 -24.360352) (xy 444.133098 -24.350222)
			(xy 444.188832 -24.348185) (xy 444.244269 -24.354285) (xy 444.298226 -24.368391) (xy 444.349555 -24.390203)
			(xy 444.397161 -24.419257) (xy 444.440029 -24.454932) (xy 444.477246 -24.496469) (xy 444.508019 -24.542982)
			(xy 444.531691 -24.593479) (xy 444.547759 -24.646886) (xy 444.555879 -24.702062) (xy 444.556388 -24.729948)
			(xy 444.555879 -24.757834) (xy 444.547759 -24.81301) (xy 444.531691 -24.866417) (xy 444.508019 -24.916914)
			(xy 444.477246 -24.963427) (xy 444.440029 -25.004964) (xy 444.397161 -25.040639) (xy 444.349555 -25.069693)
			(xy 444.298226 -25.091505) (xy 444.244269 -25.105611) (xy 444.188832 -25.111711) (xy 444.133098 -25.109674)
			(xy 444.078255 -25.099544) (xy 444.025471 -25.081537) (xy 443.975871 -25.056036) (xy 443.930513 -25.023585)
			(xy 443.890364 -24.984876) (xy 443.856278 -24.940733) (xy 443.828982 -24.892098) (xy 443.809059 -24.840007)
			(xy 443.796933 -24.78557) (xy 443.792862 -24.729948) (xy 443.313284 -24.729948) (xy 443.367079 -24.737682)
			(xy 443.419374 -24.753037) (xy 443.468951 -24.775679) (xy 443.514801 -24.805145) (xy 443.555992 -24.840836)
			(xy 443.591683 -24.882027) (xy 443.621149 -24.927877) (xy 443.643791 -24.977454) (xy 443.659146 -25.029749)
			(xy 443.666902 -25.083697) (xy 443.667388 -25.110948) (xy 443.666884 -25.137719) (xy 443.659378 -25.190731)
			(xy 443.644535 -25.242174) (xy 443.622645 -25.291037) (xy 443.594139 -25.336359) (xy 443.559577 -25.377251)
			(xy 443.519637 -25.412909) (xy 443.475104 -25.442634) (xy 443.426854 -25.465841) (xy 443.375832 -25.482074)
			(xy 443.323042 -25.491014) (xy 443.296294 -25.492202) (xy 443.282588 -25.49304) (xy 443.256358 -25.501129)
			(xy 443.23323 -25.515911) (xy 443.214873 -25.536319) (xy 443.202614 -25.560878) (xy 443.197339 -25.587815)
			(xy 443.199427 -25.615185) (xy 443.208729 -25.64101) (xy 443.216284 -25.652476) (xy 443.232835 -25.676778)
			(xy 443.259029 -25.729416) (xy 443.276841 -25.785449) (xy 443.28585 -25.84355) (xy 443.286388 -25.872948)
			(xy 443.285902 -25.900199) (xy 443.278146 -25.954147) (xy 443.262791 -26.006442) (xy 443.240149 -26.056019)
			(xy 443.210683 -26.101869) (xy 443.174992 -26.14306) (xy 443.133801 -26.178751) (xy 443.087951 -26.208217)
			(xy 443.038374 -26.230859) (xy 442.986079 -26.246214) (xy 442.932131 -26.25397) (xy 442.877629 -26.25397)
			(xy 442.823681 -26.246214) (xy 442.771386 -26.230859) (xy 442.721809 -26.208217) (xy 442.675959 -26.178751)
			(xy 442.634768 -26.14306) (xy 442.599077 -26.101869) (xy 442.569611 -26.056019) (xy 442.546969 -26.006442)
			(xy 442.531614 -25.954147) (xy 442.523858 -25.900199) (xy 442.523372 -25.872948) (xy 442.397388 -25.872948)
			(xy 442.396902 -25.900199) (xy 442.389146 -25.954147) (xy 442.373791 -26.006442) (xy 442.351149 -26.056019)
			(xy 442.321683 -26.101869) (xy 442.285992 -26.14306) (xy 442.244801 -26.178751) (xy 442.198951 -26.208217)
			(xy 442.149374 -26.230859) (xy 442.097079 -26.246214) (xy 442.043131 -26.25397) (xy 441.988629 -26.25397)
			(xy 441.934681 -26.246214) (xy 441.882386 -26.230859) (xy 441.832809 -26.208217) (xy 441.786959 -26.178751)
			(xy 441.745768 -26.14306) (xy 441.710077 -26.101869) (xy 441.680611 -26.056019) (xy 441.657969 -26.006442)
			(xy 441.642614 -25.954147) (xy 441.634858 -25.900199) (xy 441.634372 -25.872948) (xy 441.508388 -25.872948)
			(xy 441.507902 -25.900199) (xy 441.500146 -25.954147) (xy 441.484791 -26.006442) (xy 441.462149 -26.056019)
			(xy 441.432683 -26.101869) (xy 441.396992 -26.14306) (xy 441.355801 -26.178751) (xy 441.309951 -26.208217)
			(xy 441.260374 -26.230859) (xy 441.208079 -26.246214) (xy 441.154131 -26.25397) (xy 441.099629 -26.25397)
			(xy 441.045681 -26.246214) (xy 440.993386 -26.230859) (xy 440.943809 -26.208217) (xy 440.897959 -26.178751)
			(xy 440.856768 -26.14306) (xy 440.821077 -26.101869) (xy 440.791611 -26.056019) (xy 440.768969 -26.006442)
			(xy 440.753614 -25.954147) (xy 440.745858 -25.900199) (xy 440.745372 -25.872948) (xy 438.024386 -25.872948)
			(xy 438.019451 -25.90648) (xy 438.003383 -25.959887) (xy 437.979711 -26.010384) (xy 437.948938 -26.056897)
			(xy 437.911721 -26.098434) (xy 437.868853 -26.134109) (xy 437.821247 -26.163163) (xy 437.769918 -26.184975)
			(xy 437.715961 -26.199081) (xy 437.660524 -26.205181) (xy 437.60479 -26.203144) (xy 437.549947 -26.193014)
			(xy 437.497163 -26.175007) (xy 437.447563 -26.149506) (xy 437.402205 -26.117055) (xy 437.362056 -26.078346)
			(xy 437.32797 -26.034203) (xy 437.300674 -25.985568) (xy 437.280751 -25.933477) (xy 437.268625 -25.87904)
			(xy 437.264554 -25.823418) (xy 435.033928 -25.823418) (xy 434.90388 -25.953466) (xy 434.90388 -26.983556)
			(xy 446.780313 -26.983556) (xy 446.780313 -26.929044) (xy 446.788071 -26.875086) (xy 446.803429 -26.822781)
			(xy 446.826075 -26.773195) (xy 446.855548 -26.727336) (xy 446.891247 -26.686138) (xy 446.932445 -26.650441)
			(xy 446.978305 -26.62097) (xy 447.027892 -26.598325) (xy 447.080197 -26.582969) (xy 447.134156 -26.575212)
			(xy 447.161412 -26.57475) (xy 447.18867 -26.575219) (xy 447.24263 -26.582987) (xy 447.294937 -26.598351)
			(xy 447.344526 -26.620998) (xy 447.390392 -26.650466) (xy 447.4316 -26.686158) (xy 447.467313 -26.727348)
			(xy 447.482468 -26.75001) (xy 447.490749 -26.761937) (xy 447.512685 -26.780941) (xy 447.539085 -26.792996)
			(xy 447.567812 -26.797126) (xy 447.596539 -26.792996) (xy 447.622939 -26.780941) (xy 447.644875 -26.761937)
			(xy 447.653156 -26.75001) (xy 447.668315 -26.727351) (xy 447.704021 -26.686155) (xy 447.745226 -26.650459)
			(xy 447.791091 -26.620989) (xy 447.840683 -26.598347) (xy 447.892992 -26.582991) (xy 447.946954 -26.575235)
			(xy 447.974212 -26.57475) (xy 448.00146 -26.575321) (xy 448.0554 -26.583078) (xy 448.107688 -26.598432)
			(xy 448.157258 -26.621072) (xy 448.203102 -26.650535) (xy 448.244286 -26.686223) (xy 448.279972 -26.727408)
			(xy 448.309434 -26.773253) (xy 448.332072 -26.822824) (xy 448.347425 -26.875112) (xy 448.35518 -26.929052)
			(xy 448.35518 -26.983548) (xy 448.347425 -27.037488) (xy 448.332072 -27.089776) (xy 448.309434 -27.139347)
			(xy 448.279972 -27.185192) (xy 448.244286 -27.226377) (xy 448.203102 -27.262065) (xy 448.157258 -27.291528)
			(xy 448.107688 -27.314168) (xy 448.0554 -27.329522) (xy 448.00146 -27.337279) (xy 447.974212 -27.337766)
			(xy 447.946955 -27.337272) (xy 447.892997 -27.329506) (xy 447.840691 -27.314147) (xy 447.791101 -27.291504)
			(xy 447.745236 -27.26204) (xy 447.704027 -27.226352) (xy 447.668312 -27.185166) (xy 447.653156 -27.162506)
			(xy 447.644875 -27.150579) (xy 447.622939 -27.131575) (xy 447.596539 -27.11952) (xy 447.567812 -27.11539)
			(xy 447.539085 -27.11952) (xy 447.512685 -27.131575) (xy 447.490749 -27.150579) (xy 447.482468 -27.162506)
			(xy 447.467298 -27.185158) (xy 447.431593 -27.226353) (xy 447.39039 -27.262049) (xy 447.344527 -27.291519)
			(xy 447.294937 -27.314163) (xy 447.24263 -27.329521) (xy 447.18867 -27.337279) (xy 447.161412 -27.337766)
			(xy 447.134156 -27.337388) (xy 447.080197 -27.329631) (xy 447.027892 -27.314275) (xy 446.978305 -27.29163)
			(xy 446.932445 -27.262159) (xy 446.891247 -27.226462) (xy 446.855548 -27.185264) (xy 446.826075 -27.139405)
			(xy 446.803429 -27.089819) (xy 446.788071 -27.037514) (xy 446.780313 -26.983556) (xy 434.90388 -26.983556)
			(xy 434.90388 -27.930602) (xy 434.904324 -27.944369) (xy 434.911669 -27.970903) (xy 434.925851 -27.994503)
			(xy 434.945832 -28.013444) (xy 434.970155 -28.026344) (xy 434.997044 -28.032262) (xy 435.010814 -28.031948)
			(xy 435.03088 -28.03144) (xy 435.05813 -28.031902) (xy 435.112077 -28.039656) (xy 435.16437 -28.055008)
			(xy 435.213947 -28.077646) (xy 435.259797 -28.10711) (xy 435.300986 -28.142799) (xy 435.336678 -28.183987)
			(xy 435.366144 -28.229836) (xy 435.388785 -28.279411) (xy 435.40414 -28.331704) (xy 435.411897 -28.38565)
			(xy 435.411897 -28.44015) (xy 435.40414 -28.494096) (xy 435.388785 -28.546389) (xy 435.366144 -28.595964)
			(xy 435.352356 -28.617418) (xy 436.483504 -28.617418) (xy 436.487575 -28.561796) (xy 436.499701 -28.507359)
			(xy 436.519624 -28.455268) (xy 436.54692 -28.406633) (xy 436.581006 -28.36249) (xy 436.621155 -28.323781)
			(xy 436.666513 -28.29133) (xy 436.716113 -28.265829) (xy 436.768897 -28.247822) (xy 436.82374 -28.237692)
			(xy 436.879474 -28.235655) (xy 436.934911 -28.241755) (xy 436.988868 -28.255861) (xy 437.040197 -28.277673)
			(xy 437.087803 -28.306727) (xy 437.130671 -28.342402) (xy 437.167888 -28.383939) (xy 437.198661 -28.430452)
			(xy 437.222333 -28.480949) (xy 437.238401 -28.534356) (xy 437.246521 -28.589532) (xy 437.24703 -28.617418)
			(xy 437.246521 -28.645304) (xy 437.242102 -28.67533) (xy 438.783728 -28.67533) (xy 438.787799 -28.619708)
			(xy 438.799925 -28.565271) (xy 438.819848 -28.51318) (xy 438.847144 -28.464545) (xy 438.88123 -28.420402)
			(xy 438.921379 -28.381693) (xy 438.966737 -28.349242) (xy 439.016337 -28.323741) (xy 439.069121 -28.305734)
			(xy 439.123964 -28.295604) (xy 439.179698 -28.293567) (xy 439.235135 -28.299667) (xy 439.289092 -28.313773)
			(xy 439.340421 -28.335585) (xy 439.388027 -28.364639) (xy 439.430895 -28.400314) (xy 439.468112 -28.441851)
			(xy 439.498885 -28.488364) (xy 439.501039 -28.492958) (xy 440.846972 -28.492958) (xy 440.847475 -28.465637)
			(xy 440.855819 -28.411635) (xy 440.872304 -28.359538) (xy 440.896546 -28.310567) (xy 440.927975 -28.265868)
			(xy 440.94654 -28.245816) (xy 440.956979 -28.234228) (xy 440.970801 -28.206283) (xy 440.975549 -28.17547)
			(xy 440.970782 -28.144659) (xy 440.956944 -28.116722) (xy 440.94654 -28.1051) (xy 440.927942 -28.085073)
			(xy 440.896482 -28.040385) (xy 440.872229 -27.991409) (xy 440.855754 -27.9393) (xy 440.847445 -27.885284)
			(xy 440.846972 -27.857958) (xy 440.84747 -27.831309) (xy 440.855413 -27.778605) (xy 440.871123 -27.727675)
			(xy 440.894249 -27.679654) (xy 440.924273 -27.635617) (xy 440.960525 -27.596546) (xy 441.002196 -27.563315)
			(xy 441.048354 -27.536666) (xy 441.097968 -27.517194) (xy 441.14993 -27.505334) (xy 441.20308 -27.501351)
			(xy 441.25623 -27.505334) (xy 441.308192 -27.517194) (xy 441.357806 -27.536666) (xy 441.403964 -27.563315)
			(xy 441.445635 -27.596546) (xy 441.481887 -27.635617) (xy 441.511911 -27.679654) (xy 441.535037 -27.727675)
			(xy 441.550747 -27.778605) (xy 441.55869 -27.831309) (xy 441.559188 -27.857958) (xy 441.558644 -27.885278)
			(xy 441.550312 -27.939278) (xy 441.533837 -27.991375) (xy 441.509604 -28.040347) (xy 441.478182 -28.085047)
			(xy 441.45962 -28.1051) (xy 441.449267 -28.116757) (xy 441.435442 -28.144679) (xy 441.43068 -28.17547)
			(xy 441.435424 -28.206263) (xy 441.449232 -28.234193) (xy 441.45962 -28.245816) (xy 441.478236 -28.265827)
			(xy 441.509691 -28.310521) (xy 441.533939 -28.3595) (xy 441.55041 -28.411612) (xy 441.558716 -28.465631)
			(xy 441.559188 -28.492958) (xy 441.746894 -28.492958) (xy 441.747391 -28.465636) (xy 441.755735 -28.411634)
			(xy 441.772222 -28.359537) (xy 441.796465 -28.310566) (xy 441.827896 -28.265868) (xy 441.846462 -28.245816)
			(xy 441.856899 -28.234227) (xy 441.870718 -28.206282) (xy 441.875465 -28.17547) (xy 441.8707 -28.14466)
			(xy 441.856864 -28.116723) (xy 441.846462 -28.1051) (xy 441.827868 -28.08507) (xy 441.796407 -28.040383)
			(xy 441.772153 -27.991408) (xy 441.755677 -27.9393) (xy 441.747368 -27.885284) (xy 441.746894 -27.857958)
			(xy 441.747392 -27.831309) (xy 441.755335 -27.778605) (xy 441.771045 -27.727675) (xy 441.794171 -27.679654)
			(xy 441.824195 -27.635617) (xy 441.860447 -27.596546) (xy 441.902118 -27.563315) (xy 441.948276 -27.536666)
			(xy 441.99789 -27.517194) (xy 442.049852 -27.505334) (xy 442.103002 -27.501351) (xy 442.156152 -27.505334)
			(xy 442.208114 -27.517194) (xy 442.257728 -27.536666) (xy 442.303886 -27.563315) (xy 442.345557 -27.596546)
			(xy 442.381809 -27.635617) (xy 442.411833 -27.679654) (xy 442.434959 -27.727675) (xy 442.450669 -27.778605)
			(xy 442.458612 -27.831309) (xy 442.45911 -27.857958) (xy 442.45856 -27.885278) (xy 442.450229 -27.939278)
			(xy 442.433754 -27.991374) (xy 442.409523 -28.040346) (xy 442.378102 -28.085047) (xy 442.359542 -28.1051)
			(xy 442.349187 -28.116756) (xy 442.335359 -28.144678) (xy 442.330596 -28.17547) (xy 442.335341 -28.206264)
			(xy 442.349152 -28.234194) (xy 442.359542 -28.245816) (xy 442.378144 -28.265839) (xy 442.409604 -28.310528)
			(xy 442.433857 -28.359504) (xy 442.450331 -28.411614) (xy 442.458638 -28.465631) (xy 442.45911 -28.492958)
			(xy 442.646816 -28.492958) (xy 442.647307 -28.465636) (xy 442.655652 -28.411633) (xy 442.672139 -28.359536)
			(xy 442.696384 -28.310565) (xy 442.727817 -28.265867) (xy 442.746384 -28.245816) (xy 442.756819 -28.234226)
			(xy 442.770635 -28.206281) (xy 442.775381 -28.17547) (xy 442.770617 -28.144661) (xy 442.756784 -28.116724)
			(xy 442.746384 -28.1051) (xy 442.727777 -28.085082) (xy 442.69632 -28.04039) (xy 442.67207 -27.991412)
			(xy 442.655597 -27.939302) (xy 442.647289 -27.885285) (xy 442.646816 -27.857958) (xy 442.647314 -27.831309)
			(xy 442.655257 -27.778605) (xy 442.670967 -27.727675) (xy 442.694093 -27.679654) (xy 442.724117 -27.635617)
			(xy 442.760369 -27.596546) (xy 442.80204 -27.563315) (xy 442.848198 -27.536666) (xy 442.897812 -27.517194)
			(xy 442.949774 -27.505334) (xy 443.002924 -27.501351) (xy 443.056074 -27.505334) (xy 443.108036 -27.517194)
			(xy 443.15765 -27.536666) (xy 443.203808 -27.563315) (xy 443.245479 -27.596546) (xy 443.281731 -27.635617)
			(xy 443.311755 -27.679654) (xy 443.334881 -27.727675) (xy 443.350591 -27.778605) (xy 443.358534 -27.831309)
			(xy 443.359032 -27.857958) (xy 443.358476 -27.885277) (xy 443.350145 -27.939277) (xy 443.333672 -27.991373)
			(xy 443.309442 -28.040345) (xy 443.278023 -28.085046) (xy 443.259464 -28.1051) (xy 443.249107 -28.116755)
			(xy 443.235276 -28.144677) (xy 443.230512 -28.17547) (xy 443.235258 -28.206265) (xy 443.249072 -28.234195)
			(xy 443.259464 -28.245816) (xy 443.27807 -28.265836) (xy 443.309529 -28.310526) (xy 443.33378 -28.359503)
			(xy 443.350253 -28.411614) (xy 443.35856 -28.465631) (xy 443.359032 -28.492958) (xy 443.546992 -28.492958)
			(xy 443.547489 -28.465636) (xy 443.555834 -28.411634) (xy 443.57232 -28.359537) (xy 443.596563 -28.310566)
			(xy 443.627995 -28.265868) (xy 443.64656 -28.245816) (xy 443.656998 -28.234228) (xy 443.670816 -28.206282)
			(xy 443.675564 -28.17547) (xy 443.670798 -28.14466) (xy 443.656963 -28.116723) (xy 443.64656 -28.1051)
			(xy 443.627966 -28.08507) (xy 443.596504 -28.040383) (xy 443.57225 -27.991408) (xy 443.555775 -27.9393)
			(xy 443.547466 -27.885284) (xy 443.546992 -27.857958) (xy 443.54749 -27.831309) (xy 443.555433 -27.778605)
			(xy 443.571143 -27.727675) (xy 443.594269 -27.679654) (xy 443.624293 -27.635617) (xy 443.660545 -27.596546)
			(xy 443.702216 -27.563315) (xy 443.748374 -27.536666) (xy 443.797988 -27.517194) (xy 443.84995 -27.505334)
			(xy 443.9031 -27.501351) (xy 443.95625 -27.505334) (xy 444.008212 -27.517194) (xy 444.057826 -27.536666)
			(xy 444.103984 -27.563315) (xy 444.145655 -27.596546) (xy 444.181907 -27.635617) (xy 444.211931 -27.679654)
			(xy 444.235057 -27.727675) (xy 444.250767 -27.778605) (xy 444.25871 -27.831309) (xy 444.259208 -27.857958)
			(xy 444.258659 -27.885278) (xy 444.250327 -27.939278) (xy 444.233853 -27.991374) (xy 444.209621 -28.040346)
			(xy 444.178201 -28.085047) (xy 444.15964 -28.1051) (xy 444.149285 -28.116756) (xy 444.135458 -28.144678)
			(xy 444.130695 -28.17547) (xy 444.134607 -28.200858) (xy 445.636904 -28.200858) (xy 445.637401 -28.172118)
			(xy 445.64603 -28.11529) (xy 445.663086 -28.060398) (xy 445.688184 -28.008687) (xy 445.720755 -27.961326)
			(xy 445.740028 -27.94) (xy 445.750145 -27.928501) (xy 445.763488 -27.900943) (xy 445.768067 -27.870669)
			(xy 445.76347 -27.840398) (xy 445.75011 -27.812849) (xy 445.740028 -27.801316) (xy 445.720736 -27.780008)
			(xy 445.688173 -27.73264) (xy 445.663085 -27.680924) (xy 445.646039 -27.626029) (xy 445.637422 -27.569198)
			(xy 445.636904 -27.540458) (xy 445.63739 -27.513207) (xy 445.645146 -27.459259) (xy 445.660501 -27.406964)
			(xy 445.683143 -27.357387) (xy 445.712609 -27.311537) (xy 445.7483 -27.270346) (xy 445.789491 -27.234655)
			(xy 445.835341 -27.205189) (xy 445.884918 -27.182547) (xy 445.937213 -27.167192) (xy 445.991161 -27.159436)
			(xy 446.045663 -27.159436) (xy 446.099611 -27.167192) (xy 446.151906 -27.182547) (xy 446.201483 -27.205189)
			(xy 446.247333 -27.234655) (xy 446.288524 -27.270346) (xy 446.324215 -27.311537) (xy 446.353681 -27.357387)
			(xy 446.376323 -27.406964) (xy 446.391678 -27.459259) (xy 446.399434 -27.513207) (xy 446.39992 -27.540458)
			(xy 446.399426 -27.569198) (xy 446.390795 -27.626026) (xy 446.373738 -27.680917) (xy 446.34864 -27.732628)
			(xy 446.316069 -27.77999) (xy 446.296796 -27.801316) (xy 446.286768 -27.812884) (xy 446.273426 -27.840419)
			(xy 446.268835 -27.870669) (xy 446.273408 -27.900922) (xy 446.286733 -27.928465) (xy 446.296796 -27.94)
			(xy 446.316083 -27.961313) (xy 446.348649 -28.008678) (xy 446.37374 -28.060393) (xy 446.390786 -28.115287)
			(xy 446.399403 -28.172118) (xy 446.39992 -28.200858) (xy 446.399434 -28.228109) (xy 446.391678 -28.282057)
			(xy 446.376323 -28.334352) (xy 446.353681 -28.383929) (xy 446.324215 -28.429779) (xy 446.288524 -28.47097)
			(xy 446.247333 -28.506661) (xy 446.201483 -28.536127) (xy 446.151906 -28.558769) (xy 446.099611 -28.574124)
			(xy 446.045663 -28.58188) (xy 445.991161 -28.58188) (xy 445.937213 -28.574124) (xy 445.884918 -28.558769)
			(xy 445.835341 -28.536127) (xy 445.789491 -28.506661) (xy 445.7483 -28.47097) (xy 445.712609 -28.429779)
			(xy 445.683143 -28.383929) (xy 445.660501 -28.334352) (xy 445.645146 -28.282057) (xy 445.63739 -28.228109)
			(xy 445.636904 -28.200858) (xy 444.134607 -28.200858) (xy 444.13544 -28.206264) (xy 444.14925 -28.234194)
			(xy 444.15964 -28.245816) (xy 444.178242 -28.265839) (xy 444.209702 -28.310528) (xy 444.233955 -28.359504)
			(xy 444.250428 -28.411614) (xy 444.258736 -28.465631) (xy 444.259208 -28.492958) (xy 444.25871 -28.519607)
			(xy 444.250767 -28.572311) (xy 444.235057 -28.623241) (xy 444.211931 -28.671262) (xy 444.181907 -28.715299)
			(xy 444.145655 -28.75437) (xy 444.103984 -28.787601) (xy 444.057826 -28.81425) (xy 444.008212 -28.833722)
			(xy 443.95625 -28.845582) (xy 443.9031 -28.849566) (xy 443.84995 -28.845582) (xy 443.797988 -28.833722)
			(xy 443.748374 -28.81425) (xy 443.702216 -28.787601) (xy 443.660545 -28.75437) (xy 443.624293 -28.715299)
			(xy 443.594269 -28.671262) (xy 443.571143 -28.623241) (xy 443.555433 -28.572311) (xy 443.54749 -28.519607)
			(xy 443.546992 -28.492958) (xy 443.359032 -28.492958) (xy 443.358534 -28.519607) (xy 443.350591 -28.572311)
			(xy 443.334881 -28.623241) (xy 443.311755 -28.671262) (xy 443.281731 -28.715299) (xy 443.245479 -28.75437)
			(xy 443.203808 -28.787601) (xy 443.15765 -28.81425) (xy 443.108036 -28.833722) (xy 443.056074 -28.845582)
			(xy 443.002924 -28.849566) (xy 442.949774 -28.845582) (xy 442.897812 -28.833722) (xy 442.848198 -28.81425)
			(xy 442.80204 -28.787601) (xy 442.760369 -28.75437) (xy 442.724117 -28.715299) (xy 442.694093 -28.671262)
			(xy 442.670967 -28.623241) (xy 442.655257 -28.572311) (xy 442.647314 -28.519607) (xy 442.646816 -28.492958)
			(xy 442.45911 -28.492958) (xy 442.458612 -28.519607) (xy 442.450669 -28.572311) (xy 442.434959 -28.623241)
			(xy 442.411833 -28.671262) (xy 442.381809 -28.715299) (xy 442.345557 -28.75437) (xy 442.303886 -28.787601)
			(xy 442.257728 -28.81425) (xy 442.208114 -28.833722) (xy 442.156152 -28.845582) (xy 442.103002 -28.849566)
			(xy 442.049852 -28.845582) (xy 441.99789 -28.833722) (xy 441.948276 -28.81425) (xy 441.902118 -28.787601)
			(xy 441.860447 -28.75437) (xy 441.824195 -28.715299) (xy 441.794171 -28.671262) (xy 441.771045 -28.623241)
			(xy 441.755335 -28.572311) (xy 441.747392 -28.519607) (xy 441.746894 -28.492958) (xy 441.559188 -28.492958)
			(xy 441.55869 -28.519607) (xy 441.550747 -28.572311) (xy 441.535037 -28.623241) (xy 441.511911 -28.671262)
			(xy 441.481887 -28.715299) (xy 441.445635 -28.75437) (xy 441.403964 -28.787601) (xy 441.357806 -28.81425)
			(xy 441.308192 -28.833722) (xy 441.25623 -28.845582) (xy 441.20308 -28.849566) (xy 441.14993 -28.845582)
			(xy 441.097968 -28.833722) (xy 441.048354 -28.81425) (xy 441.002196 -28.787601) (xy 440.960525 -28.75437)
			(xy 440.924273 -28.715299) (xy 440.894249 -28.671262) (xy 440.871123 -28.623241) (xy 440.855413 -28.572311)
			(xy 440.84747 -28.519607) (xy 440.846972 -28.492958) (xy 439.501039 -28.492958) (xy 439.522557 -28.538861)
			(xy 439.538625 -28.592268) (xy 439.546745 -28.647444) (xy 439.547254 -28.67533) (xy 439.546745 -28.703216)
			(xy 439.538625 -28.758392) (xy 439.522557 -28.811799) (xy 439.498885 -28.862296) (xy 439.468112 -28.908809)
			(xy 439.430895 -28.950346) (xy 439.388027 -28.986021) (xy 439.340421 -29.015075) (xy 439.289092 -29.036887)
			(xy 439.235135 -29.050993) (xy 439.179698 -29.057093) (xy 439.123964 -29.055056) (xy 439.069121 -29.044926)
			(xy 439.016337 -29.026919) (xy 438.966737 -29.001418) (xy 438.921379 -28.968967) (xy 438.88123 -28.930258)
			(xy 438.847144 -28.886115) (xy 438.819848 -28.83748) (xy 438.799925 -28.785389) (xy 438.787799 -28.730952)
			(xy 438.783728 -28.67533) (xy 437.242102 -28.67533) (xy 437.238401 -28.70048) (xy 437.222333 -28.753887)
			(xy 437.198661 -28.804384) (xy 437.167888 -28.850897) (xy 437.130671 -28.892434) (xy 437.087803 -28.928109)
			(xy 437.040197 -28.957163) (xy 436.988868 -28.978975) (xy 436.934911 -28.993081) (xy 436.879474 -28.999181)
			(xy 436.82374 -28.997144) (xy 436.768897 -28.987014) (xy 436.716113 -28.969007) (xy 436.666513 -28.943506)
			(xy 436.621155 -28.911055) (xy 436.581006 -28.872346) (xy 436.54692 -28.828203) (xy 436.519624 -28.779568)
			(xy 436.499701 -28.727477) (xy 436.487575 -28.67304) (xy 436.483504 -28.617418) (xy 435.352356 -28.617418)
			(xy 435.336678 -28.641813) (xy 435.300986 -28.683001) (xy 435.259797 -28.71869) (xy 435.213947 -28.748154)
			(xy 435.16437 -28.770792) (xy 435.112077 -28.786144) (xy 435.05813 -28.793898) (xy 435.03088 -28.794456)
			(xy 435.010814 -28.793948) (xy 434.997049 -28.793681) (xy 434.97018 -28.79963) (xy 434.945874 -28.812535)
			(xy 434.925894 -28.831459) (xy 434.911689 -28.855029) (xy 434.90429 -28.881535) (xy 434.90388 -28.895294)
			(xy 434.90388 -29.454602) (xy 434.904411 -29.470064) (xy 434.913644 -29.499576) (xy 434.931293 -29.524968)
			(xy 434.955736 -29.543908) (xy 434.98473 -29.554658) (xy 435.000146 -29.555948) (xy 435.029053 -29.558009)
			(xy 435.085798 -29.569772) (xy 435.140111 -29.589983) (xy 435.190742 -29.618176) (xy 435.210385 -29.633418)
			(xy 436.483504 -29.633418) (xy 436.487575 -29.577796) (xy 436.499701 -29.523359) (xy 436.519624 -29.471268)
			(xy 436.54692 -29.422633) (xy 436.581006 -29.37849) (xy 436.621155 -29.339781) (xy 436.666513 -29.30733)
			(xy 436.716113 -29.281829) (xy 436.768897 -29.263822) (xy 436.82374 -29.253692) (xy 436.879474 -29.251655)
			(xy 436.934911 -29.257755) (xy 436.988868 -29.271861) (xy 437.040197 -29.293673) (xy 437.087803 -29.322727)
			(xy 437.130671 -29.358402) (xy 437.167888 -29.399939) (xy 437.198661 -29.446452) (xy 437.222333 -29.496949)
			(xy 437.238401 -29.550356) (xy 437.246521 -29.605532) (xy 437.24703 -29.633418) (xy 437.246521 -29.661304)
			(xy 437.238401 -29.71648) (xy 437.222333 -29.769887) (xy 437.198661 -29.820384) (xy 437.167888 -29.866897)
			(xy 437.130671 -29.908434) (xy 437.087803 -29.944109) (xy 437.040197 -29.973163) (xy 436.988868 -29.994975)
			(xy 436.948502 -30.005528) (xy 438.804302 -30.005528) (xy 438.808373 -29.949906) (xy 438.820499 -29.895469)
			(xy 438.840422 -29.843378) (xy 438.867718 -29.794743) (xy 438.901804 -29.7506) (xy 438.941953 -29.711891)
			(xy 438.987311 -29.67944) (xy 439.036911 -29.653939) (xy 439.089695 -29.635932) (xy 439.144538 -29.625802)
			(xy 439.200272 -29.623765) (xy 439.255709 -29.629865) (xy 439.309666 -29.643971) (xy 439.360995 -29.665783)
			(xy 439.377664 -29.675956) (xy 446.145313 -29.675956) (xy 446.145313 -29.621444) (xy 446.153071 -29.567486)
			(xy 446.168429 -29.515181) (xy 446.191075 -29.465595) (xy 446.220548 -29.419736) (xy 446.256247 -29.378538)
			(xy 446.297445 -29.342841) (xy 446.343305 -29.31337) (xy 446.392892 -29.290725) (xy 446.445197 -29.275369)
			(xy 446.499156 -29.267612) (xy 446.526412 -29.26715) (xy 446.555327 -29.267713) (xy 446.612497 -29.27643)
			(xy 446.667696 -29.293678) (xy 446.719659 -29.319061) (xy 446.767193 -29.351998) (xy 446.809211 -29.391733)
			(xy 446.827402 -29.414216) (xy 446.837299 -29.426021) (xy 446.862623 -29.44354) (xy 446.892016 -29.452716)
			(xy 446.922808 -29.452716) (xy 446.952201 -29.44354) (xy 446.977525 -29.426021) (xy 446.987422 -29.414216)
			(xy 447.005605 -29.391725) (xy 447.047626 -29.35199) (xy 447.095162 -29.319051) (xy 447.147125 -29.293664)
			(xy 447.202324 -29.27641) (xy 447.259495 -29.267683) (xy 447.288412 -29.26715) (xy 447.31566 -29.267721)
			(xy 447.3696 -29.275478) (xy 447.421888 -29.290832) (xy 447.471458 -29.313472) (xy 447.517302 -29.342935)
			(xy 447.558486 -29.378623) (xy 447.594172 -29.419808) (xy 447.623634 -29.465653) (xy 447.646272 -29.515224)
			(xy 447.661625 -29.567512) (xy 447.66938 -29.621452) (xy 447.66938 -29.675948) (xy 447.661625 -29.729888)
			(xy 447.646272 -29.782176) (xy 447.623634 -29.831747) (xy 447.594172 -29.877592) (xy 447.558486 -29.918777)
			(xy 447.517302 -29.954465) (xy 447.471458 -29.983928) (xy 447.421888 -30.006568) (xy 447.3696 -30.021922)
			(xy 447.31566 -30.029679) (xy 447.288412 -30.030166) (xy 447.259495 -30.029652) (xy 447.202323 -30.020924)
			(xy 447.147123 -30.003666) (xy 447.095161 -29.978273) (xy 447.047628 -29.945329) (xy 447.005612 -29.905586)
			(xy 446.987422 -29.8831) (xy 446.977525 -29.871295) (xy 446.952201 -29.853776) (xy 446.922808 -29.8446)
			(xy 446.892016 -29.8446) (xy 446.862623 -29.853776) (xy 446.837299 -29.871295) (xy 446.827402 -29.8831)
			(xy 446.80921 -29.905583) (xy 446.76719 -29.945318) (xy 446.719656 -29.978257) (xy 446.667695 -30.003645)
			(xy 446.612497 -30.020902) (xy 446.555328 -30.029631) (xy 446.526412 -30.030166) (xy 446.499156 -30.029788)
			(xy 446.445197 -30.022031) (xy 446.392892 -30.006675) (xy 446.343305 -29.98403) (xy 446.297445 -29.954559)
			(xy 446.256247 -29.918862) (xy 446.220548 -29.877664) (xy 446.191075 -29.831805) (xy 446.168429 -29.782219)
			(xy 446.153071 -29.729914) (xy 446.145313 -29.675956) (xy 439.377664 -29.675956) (xy 439.408601 -29.694837)
			(xy 439.451469 -29.730512) (xy 439.488686 -29.772049) (xy 439.519459 -29.818562) (xy 439.543131 -29.869059)
			(xy 439.559199 -29.922466) (xy 439.567319 -29.977642) (xy 439.567828 -30.005528) (xy 439.567319 -30.033414)
			(xy 439.559199 -30.08859) (xy 439.543131 -30.141997) (xy 439.519459 -30.192494) (xy 439.488686 -30.239007)
			(xy 439.451469 -30.280544) (xy 439.408601 -30.316219) (xy 439.360995 -30.345273) (xy 439.309666 -30.367085)
			(xy 439.255709 -30.381191) (xy 439.200272 -30.387291) (xy 439.144538 -30.385254) (xy 439.089695 -30.375124)
			(xy 439.036911 -30.357117) (xy 438.987311 -30.331616) (xy 438.941953 -30.299165) (xy 438.901804 -30.260456)
			(xy 438.867718 -30.216313) (xy 438.840422 -30.167678) (xy 438.820499 -30.115587) (xy 438.808373 -30.06115)
			(xy 438.804302 -30.005528) (xy 436.948502 -30.005528) (xy 436.934911 -30.009081) (xy 436.879474 -30.015181)
			(xy 436.82374 -30.013144) (xy 436.768897 -30.003014) (xy 436.716113 -29.985007) (xy 436.666513 -29.959506)
			(xy 436.621155 -29.927055) (xy 436.581006 -29.888346) (xy 436.54692 -29.844203) (xy 436.519624 -29.795568)
			(xy 436.499701 -29.743477) (xy 436.487575 -29.68904) (xy 436.483504 -29.633418) (xy 435.210385 -29.633418)
			(xy 435.236527 -29.653703) (xy 435.276411 -29.695746) (xy 435.309477 -29.743339) (xy 435.334964 -29.795384)
			(xy 435.352286 -29.850686) (xy 435.361044 -29.907972) (xy 435.361588 -29.936948) (xy 435.361061 -29.965448)
			(xy 435.352581 -30.021815) (xy 435.335802 -30.07629) (xy 435.311098 -30.127659) (xy 435.27902 -30.174777)
			(xy 435.240284 -30.216593) (xy 435.195753 -30.252175) (xy 435.171342 -30.266894) (xy 434.90388 -30.53461)
			(xy 434.90388 -30.706568) (xy 441.506862 -30.706568) (xy 441.510933 -30.650946) (xy 441.523059 -30.596509)
			(xy 441.542982 -30.544418) (xy 441.570278 -30.495783) (xy 441.604364 -30.45164) (xy 441.644513 -30.412931)
			(xy 441.689871 -30.38048) (xy 441.739471 -30.354979) (xy 441.792255 -30.336972) (xy 441.847098 -30.326842)
			(xy 441.902832 -30.324805) (xy 441.958269 -30.330905) (xy 442.012226 -30.345011) (xy 442.063555 -30.366823)
			(xy 442.111161 -30.395877) (xy 442.154029 -30.431552) (xy 442.191066 -30.472888) (xy 444.326262 -30.472888)
			(xy 444.330333 -30.417266) (xy 444.342459 -30.362829) (xy 444.362382 -30.310738) (xy 444.389678 -30.262103)
			(xy 444.423764 -30.21796) (xy 444.463913 -30.179251) (xy 444.509271 -30.1468) (xy 444.558871 -30.121299)
			(xy 444.611655 -30.103292) (xy 444.666498 -30.093162) (xy 444.722232 -30.091125) (xy 444.777669 -30.097225)
			(xy 444.831626 -30.111331) (xy 444.882955 -30.133143) (xy 444.930561 -30.162197) (xy 444.973429 -30.197872)
			(xy 445.010646 -30.239409) (xy 445.041419 -30.285922) (xy 445.065091 -30.336419) (xy 445.081159 -30.389826)
			(xy 445.089279 -30.445002) (xy 445.089788 -30.472888) (xy 445.089279 -30.500774) (xy 445.081159 -30.55595)
			(xy 445.065091 -30.609357) (xy 445.041419 -30.659854) (xy 445.010646 -30.706367) (xy 444.973429 -30.747904)
			(xy 444.930561 -30.783579) (xy 444.882955 -30.812633) (xy 444.831626 -30.834445) (xy 444.777669 -30.848551)
			(xy 444.722232 -30.854651) (xy 444.666498 -30.852614) (xy 444.611655 -30.842484) (xy 444.558871 -30.824477)
			(xy 444.509271 -30.798976) (xy 444.463913 -30.766525) (xy 444.423764 -30.727816) (xy 444.389678 -30.683673)
			(xy 444.362382 -30.635038) (xy 444.342459 -30.582947) (xy 444.330333 -30.52851) (xy 444.326262 -30.472888)
			(xy 442.191066 -30.472888) (xy 442.191246 -30.473089) (xy 442.222019 -30.519602) (xy 442.245691 -30.570099)
			(xy 442.261759 -30.623506) (xy 442.269879 -30.678682) (xy 442.270388 -30.706568) (xy 442.269879 -30.734454)
			(xy 442.261759 -30.78963) (xy 442.245691 -30.843037) (xy 442.222019 -30.893534) (xy 442.191246 -30.940047)
			(xy 442.154029 -30.981584) (xy 442.111161 -31.017259) (xy 442.063555 -31.046313) (xy 442.012226 -31.068125)
			(xy 441.958269 -31.082231) (xy 441.902832 -31.088331) (xy 441.847098 -31.086294) (xy 441.792255 -31.076164)
			(xy 441.739471 -31.058157) (xy 441.689871 -31.032656) (xy 441.644513 -31.000205) (xy 441.604364 -30.961496)
			(xy 441.570278 -30.917353) (xy 441.542982 -30.868718) (xy 441.523059 -30.816627) (xy 441.510933 -30.76219)
			(xy 441.506862 -30.706568) (xy 434.90388 -30.706568) (xy 434.90388 -31.229808) (xy 442.850522 -31.229808)
			(xy 442.854593 -31.174186) (xy 442.866719 -31.119749) (xy 442.886642 -31.067658) (xy 442.913938 -31.019023)
			(xy 442.948024 -30.97488) (xy 442.988173 -30.936171) (xy 443.033531 -30.90372) (xy 443.083131 -30.878219)
			(xy 443.135915 -30.860212) (xy 443.190758 -30.850082) (xy 443.246492 -30.848045) (xy 443.301929 -30.854145)
			(xy 443.355886 -30.868251) (xy 443.407215 -30.890063) (xy 443.454821 -30.919117) (xy 443.497689 -30.954792)
			(xy 443.534906 -30.996329) (xy 443.565679 -31.042842) (xy 443.589351 -31.093339) (xy 443.605419 -31.146746)
			(xy 443.613539 -31.201922) (xy 443.614048 -31.229808) (xy 443.613539 -31.257694) (xy 443.605419 -31.31287)
			(xy 443.589351 -31.366277) (xy 443.565679 -31.416774) (xy 443.534906 -31.463287) (xy 443.497689 -31.504824)
			(xy 443.454821 -31.540499) (xy 443.407215 -31.569553) (xy 443.355886 -31.591365) (xy 443.301929 -31.605471)
			(xy 443.246492 -31.611571) (xy 443.190758 -31.609534) (xy 443.135915 -31.599404) (xy 443.083131 -31.581397)
			(xy 443.033531 -31.555896) (xy 442.988173 -31.523445) (xy 442.948024 -31.484736) (xy 442.913938 -31.440593)
			(xy 442.886642 -31.391958) (xy 442.866719 -31.339867) (xy 442.854593 -31.28543) (xy 442.850522 -31.229808)
			(xy 434.90388 -31.229808) (xy 434.90388 -32.800544) (xy 434.904357 -32.815118) (xy 434.912598 -32.843078)
			(xy 434.928398 -32.867574) (xy 434.95047 -32.886612) (xy 434.97702 -32.898645) (xy 435.005887 -32.902693)
			(xy 435.034722 -32.898427) (xy 435.048152 -32.892746) (xy 435.073346 -32.881615) (xy 435.126134 -32.8659)
			(xy 435.180633 -32.857936) (xy 435.208172 -32.85744) (xy 435.235425 -32.857901) (xy 435.289376 -32.865655)
			(xy 435.341675 -32.88101) (xy 435.391255 -32.903651) (xy 435.437109 -32.933119) (xy 435.478301 -32.968814)
			(xy 435.513993 -33.010007) (xy 435.543458 -33.055862) (xy 435.566097 -33.105444) (xy 435.581449 -33.157743)
			(xy 435.5892 -33.211695) (xy 435.58968 -33.238948) (xy 435.589201 -33.266379) (xy 435.581339 -33.320676)
			(xy 435.565784 -33.373288) (xy 435.542857 -33.42313) (xy 435.513029 -33.469176) (xy 435.476915 -33.510477)
			(xy 435.435261 -33.546182) (xy 435.388923 -33.575555) (xy 435.338857 -33.59799) (xy 435.286095 -33.613027)
			(xy 435.258972 -33.617154) (xy 435.245032 -33.619503) (xy 435.219136 -33.630816) (xy 435.197329 -33.648789)
			(xy 435.181279 -33.672047) (xy 435.172212 -33.698812) (xy 435.170823 -33.727037) (xy 435.177218 -33.754563)
			(xy 435.190906 -33.779285) (xy 435.200552 -33.78962) (xy 435.69636 -34.285428) (xy 435.707082 -34.295487)
			(xy 435.732902 -34.309519) (xy 435.761651 -34.31561) (xy 435.790943 -34.313253) (xy 435.818348 -34.302644)
			(xy 435.841592 -34.284664) (xy 435.858747 -34.260804) (xy 435.864 -34.247074) (xy 435.87305 -34.222511)
			(xy 435.89693 -34.175927) (xy 435.926956 -34.133047) (xy 435.962564 -34.094677) (xy 436.003085 -34.061537)
			(xy 436.047759 -34.03425) (xy 436.095744 -34.013329) (xy 436.146139 -33.999168) (xy 436.197998 -33.992032)
			(xy 436.224172 -33.99155) (xy 436.251426 -33.992034) (xy 436.305379 -33.999787) (xy 436.357679 -34.015139)
			(xy 436.407263 -34.037778) (xy 436.45312 -34.067243) (xy 436.494317 -34.102934) (xy 436.530015 -34.144124)
			(xy 436.559488 -34.189976) (xy 436.582136 -34.239555) (xy 436.597498 -34.291853) (xy 436.605261 -34.345804)
			(xy 436.60568 -34.373058) (xy 436.858154 -34.373058) (xy 436.862225 -34.317436) (xy 436.874351 -34.262999)
			(xy 436.894274 -34.210908) (xy 436.92157 -34.162273) (xy 436.955656 -34.11813) (xy 436.995805 -34.079421)
			(xy 437.041163 -34.04697) (xy 437.090763 -34.021469) (xy 437.143547 -34.003462) (xy 437.19839 -33.993332)
			(xy 437.254124 -33.991295) (xy 437.309561 -33.997395) (xy 437.363518 -34.011501) (xy 437.414847 -34.033313)
			(xy 437.462453 -34.062367) (xy 437.505321 -34.098042) (xy 437.542538 -34.139579) (xy 437.573311 -34.186092)
			(xy 437.596983 -34.236589) (xy 437.613051 -34.289996) (xy 437.621171 -34.345172) (xy 437.62168 -34.373058)
			(xy 437.621171 -34.400944) (xy 437.613051 -34.45612) (xy 437.596983 -34.509527) (xy 437.573311 -34.560024)
			(xy 437.542538 -34.606537) (xy 437.505321 -34.648074) (xy 437.462453 -34.683749) (xy 437.414847 -34.712803)
			(xy 437.363518 -34.734615) (xy 437.309561 -34.748721) (xy 437.254124 -34.754821) (xy 437.19839 -34.752784)
			(xy 437.143547 -34.742654) (xy 437.090763 -34.724647) (xy 437.041163 -34.699146) (xy 436.995805 -34.666695)
			(xy 436.955656 -34.627986) (xy 436.92157 -34.583843) (xy 436.894274 -34.535208) (xy 436.874351 -34.483117)
			(xy 436.862225 -34.42868) (xy 436.858154 -34.373058) (xy 436.60568 -34.373058) (xy 436.605245 -34.399231)
			(xy 436.598083 -34.451085) (xy 436.583903 -34.501474) (xy 436.562969 -34.549452) (xy 436.535676 -34.59412)
			(xy 436.502534 -34.634638) (xy 436.464166 -34.670247) (xy 436.421291 -34.700279) (xy 436.374715 -34.72417)
			(xy 436.350156 -34.73323) (xy 436.336485 -34.738554) (xy 436.312725 -34.755746) (xy 436.294825 -34.778977)
			(xy 436.284258 -34.806334) (xy 436.281896 -34.835566) (xy 436.287931 -34.864265) (xy 436.301867 -34.89007)
			(xy 436.311802 -34.90087) (xy 436.42788 -35.016948) (xy 446.239392 -35.016948)
		)
		(stroke
			(width 0)
			(type solid)
		)
		(fill yes)
		(layer "In2.Cu")
		(net "GND")
	)
	(gr_poly
		(pts
			(xy 354.422202 -58.011314) (xy 354.431546 -58.001377) (xy 354.445057 -57.977695) (xy 354.451804 -57.951277)
			(xy 354.451304 -57.924017) (xy 354.443592 -57.897865) (xy 354.42922 -57.874694) (xy 354.409219 -57.856165)
			(xy 354.39731 -57.849516) (xy 354.377502 -57.83877) (xy 354.340322 -57.813301) (xy 354.323142 -57.798716)
			(xy 354.311814 -57.78948) (xy 354.285257 -57.777304) (xy 354.25634 -57.773131) (xy 354.227423 -57.777304)
			(xy 354.200866 -57.78948) (xy 354.189538 -57.798716) (xy 354.168605 -57.816354) (xy 354.122637 -57.846071)
			(xy 354.072889 -57.868905) (xy 354.020387 -57.884386) (xy 353.966209 -57.892196) (xy 353.93884 -57.892696)
			(xy 353.911586 -57.892235) (xy 353.857633 -57.884483) (xy 353.805332 -57.869131) (xy 353.755748 -57.846492)
			(xy 353.709891 -57.817026) (xy 353.668695 -57.781333) (xy 353.632998 -57.740141) (xy 353.603527 -57.694287)
			(xy 353.580883 -57.644706) (xy 353.565525 -57.592407) (xy 353.557767 -57.538454) (xy 353.557767 -57.483946)
			(xy 353.565525 -57.429993) (xy 353.580883 -57.377694) (xy 353.603527 -57.328113) (xy 353.632998 -57.282259)
			(xy 353.668695 -57.241067) (xy 353.709891 -57.205374) (xy 353.755748 -57.175908) (xy 353.805332 -57.153269)
			(xy 353.857633 -57.137917) (xy 353.911586 -57.130165) (xy 353.93884 -57.12968) (xy 353.966209 -57.130154)
			(xy 354.020385 -57.137983) (xy 354.072886 -57.153473) (xy 354.122634 -57.176308) (xy 354.168608 -57.206019)
			(xy 354.189538 -57.22366) (xy 354.200866 -57.232896) (xy 354.227423 -57.245072) (xy 354.25634 -57.249245)
			(xy 354.285257 -57.245072) (xy 354.311814 -57.232896) (xy 354.323142 -57.22366) (xy 354.344073 -57.206018)
			(xy 354.390039 -57.176292) (xy 354.439786 -57.153451) (xy 354.49229 -57.137964) (xy 354.54647 -57.13015)
			(xy 354.57384 -57.12968) (xy 354.599841 -57.130116) (xy 354.651363 -57.137169) (xy 354.70145 -57.151153)
			(xy 354.749173 -57.17181) (xy 354.79365 -57.198755) (xy 354.834056 -57.231491) (xy 354.869642 -57.26941)
			(xy 354.89975 -57.31181) (xy 354.912168 -57.334658) (xy 354.918874 -57.346505) (xy 354.937434 -57.366405)
			(xy 354.960589 -57.380701) (xy 354.986696 -57.388376) (xy 355.013904 -57.388887) (xy 355.040281 -57.382196)
			(xy 355.063956 -57.36878) (xy 355.073966 -57.35955) (xy 356.416864 -56.016652) (xy 356.408736 -55.98795)
			(xy 356.402076 -55.962626) (xy 356.394939 -55.910753) (xy 356.394512 -55.884572) (xy 356.395058 -55.855444)
			(xy 356.403907 -55.797863) (xy 356.421409 -55.742298) (xy 356.447159 -55.690042) (xy 356.480556 -55.642309)
			(xy 356.520823 -55.60021) (xy 356.54361 -55.582058) (xy 356.557691 -55.539861) (xy 356.592424 -55.457957)
			(xy 356.634375 -55.379505) (xy 356.683205 -55.30514) (xy 356.738519 -55.235462) (xy 356.799869 -55.171037)
			(xy 356.866761 -55.112384) (xy 356.938651 -55.059978) (xy 357.014959 -55.014243) (xy 357.095068 -54.97555)
			(xy 357.178329 -54.94421) (xy 357.264069 -54.920478) (xy 357.351595 -54.904546) (xy 357.440198 -54.896542)
			(xy 357.48468 -54.896004) (xy 357.514398 -54.896512) (xy 357.536242 -54.897274) (xy 357.578406 -54.85511)
			(xy 360.403902 -54.85511) (xy 361.232958 -54.026054) (xy 361.232958 -47.914814) (xy 360.772202 -47.454058)
			(xy 356.042976 -47.454058) (xy 355.674422 -47.085504) (xy 355.674422 -46.471332) (xy 354.81006 -45.60697)
			(xy 349.6564 -45.60697) (xy 349.244158 -45.194728) (xy 348.892114 -45.194728) (xy 348.865704 -45.194292)
			(xy 348.813383 -45.187044) (xy 348.762555 -45.17267) (xy 348.73819 -45.16247) (xy 348.728538 -45.158152)
			(xy 348.220538 -45.158152) (xy 348.21495 -45.159422) (xy 348.193737 -45.164148) (xy 348.150575 -45.169242)
			(xy 348.128844 -45.169582) (xy 348.107112 -45.169264) (xy 348.063946 -45.164175) (xy 348.042738 -45.159422)
			(xy 348.03715 -45.158152) (xy 345.574366 -45.158152) (xy 345.559253 -45.158708) (xy 345.530352 -45.167566)
			(xy 345.505311 -45.184497) (xy 345.486323 -45.208016) (xy 345.475052 -45.236063) (xy 345.472484 -45.266181)
			(xy 345.475052 -45.281088) (xy 345.47848 -45.298154) (xy 345.482167 -45.33277) (xy 345.482418 -45.350176)
			(xy 345.481908 -45.376163) (xy 345.473778 -45.427498) (xy 345.457717 -45.476928) (xy 345.434121 -45.523238)
			(xy 345.403571 -45.565286) (xy 345.36682 -45.602037) (xy 345.324772 -45.632587) (xy 345.278462 -45.656183)
			(xy 345.229032 -45.672244) (xy 345.177697 -45.680374) (xy 345.125723 -45.680374) (xy 345.074388 -45.672244)
			(xy 345.024958 -45.656183) (xy 344.978648 -45.632587) (xy 344.9366 -45.602037) (xy 344.899849 -45.565286)
			(xy 344.869299 -45.523238) (xy 344.845703 -45.476928) (xy 344.829642 -45.427498) (xy 344.821512 -45.376163)
			(xy 344.821002 -45.350176) (xy 344.821717 -45.318805) (xy 344.833482 -45.257178) (xy 344.84437 -45.227748)
			(xy 344.84818 -45.218604) (xy 344.84818 -45.158152) (xy 344.69705 -45.158152) (xy 344.691462 -45.202602)
			(xy 344.687794 -45.227479) (xy 344.673913 -45.275808) (xy 344.65288 -45.32148) (xy 344.625178 -45.363444)
			(xy 344.591445 -45.400733) (xy 344.552459 -45.432488) (xy 344.509116 -45.457979) (xy 344.462415 -45.476618)
			(xy 344.413432 -45.487975) (xy 344.363294 -45.491791) (xy 344.313156 -45.487975) (xy 344.264173 -45.476618)
			(xy 344.217472 -45.457979) (xy 344.174129 -45.432488) (xy 344.135143 -45.400733) (xy 344.10141 -45.363444)
			(xy 344.073708 -45.32148) (xy 344.052675 -45.275808) (xy 344.038794 -45.227479) (xy 344.035126 -45.202602)
			(xy 344.029538 -45.158152) (xy 343.06891 -45.158152) (xy 343.063322 -45.202602) (xy 343.059654 -45.227479)
			(xy 343.045773 -45.275808) (xy 343.02474 -45.32148) (xy 342.997038 -45.363444) (xy 342.963305 -45.400733)
			(xy 342.924319 -45.432488) (xy 342.880976 -45.457979) (xy 342.834275 -45.476618) (xy 342.785292 -45.487975)
			(xy 342.735154 -45.491791) (xy 342.685016 -45.487975) (xy 342.636033 -45.476618) (xy 342.589332 -45.457979)
			(xy 342.545989 -45.432488) (xy 342.507003 -45.400733) (xy 342.47327 -45.363444) (xy 342.445568 -45.32148)
			(xy 342.424535 -45.275808) (xy 342.410654 -45.227479) (xy 342.406986 -45.202602) (xy 342.401398 -45.158152)
			(xy 341.439754 -45.158152) (xy 341.434166 -45.202602) (xy 341.430531 -45.227505) (xy 341.416704 -45.275895)
			(xy 341.395708 -45.321632) (xy 341.368026 -45.36366) (xy 341.334297 -45.401011) (xy 341.2953 -45.432822)
			(xy 341.251934 -45.458358) (xy 341.205201 -45.477032) (xy 341.156179 -45.488411) (xy 341.105998 -45.492234)
			(xy 341.055817 -45.488411) (xy 341.006795 -45.477032) (xy 340.960062 -45.458358) (xy 340.916696 -45.432822)
			(xy 340.877699 -45.401011) (xy 340.84397 -45.36366) (xy 340.816288 -45.321632) (xy 340.795292 -45.275895)
			(xy 340.781465 -45.227505) (xy 340.77783 -45.202602) (xy 340.772242 -45.158152) (xy 340.378288 -45.158152)
			(xy 340.281768 -45.254672) (xy 340.329266 -45.301916) (xy 340.345268 -45.30471) (xy 340.370653 -45.309468)
			(xy 340.419641 -45.325817) (xy 340.465492 -45.349582) (xy 340.507092 -45.380185) (xy 340.54343 -45.416881)
			(xy 340.573623 -45.45878) (xy 340.596936 -45.504863) (xy 340.612803 -45.554009) (xy 340.620839 -45.605024)
			(xy 340.621366 -45.630846) (xy 340.620852 -45.65683) (xy 340.620852 -45.656833) (xy 341.5886 -45.656833)
			(xy 341.5886 -45.604859) (xy 341.59673 -45.553524) (xy 341.612791 -45.504094) (xy 341.636387 -45.457784)
			(xy 341.666937 -45.415736) (xy 341.703688 -45.378985) (xy 341.745736 -45.348435) (xy 341.792046 -45.324839)
			(xy 341.841476 -45.308778) (xy 341.892811 -45.300648) (xy 341.944785 -45.300648) (xy 341.99612 -45.308778)
			(xy 342.04555 -45.324839) (xy 342.09186 -45.348435) (xy 342.133908 -45.378985) (xy 342.170659 -45.415736)
			(xy 342.201209 -45.457784) (xy 342.224805 -45.504094) (xy 342.240866 -45.553524) (xy 342.248996 -45.604859)
			(xy 342.249506 -45.630846) (xy 342.249001 -45.656579) (xy 343.21928 -45.656579) (xy 343.21928 -45.604605)
			(xy 343.22741 -45.55327) (xy 343.243471 -45.50384) (xy 343.267067 -45.45753) (xy 343.297617 -45.415482)
			(xy 343.334368 -45.378731) (xy 343.376416 -45.348181) (xy 343.422726 -45.324585) (xy 343.472156 -45.308524)
			(xy 343.523491 -45.300394) (xy 343.575465 -45.300394) (xy 343.6268 -45.308524) (xy 343.67623 -45.324585)
			(xy 343.72254 -45.348181) (xy 343.764588 -45.378731) (xy 343.801339 -45.415482) (xy 343.831889 -45.45753)
			(xy 343.855485 -45.50384) (xy 343.871546 -45.55327) (xy 343.879676 -45.604605) (xy 343.880186 -45.630592)
			(xy 343.879676 -45.656579) (xy 343.871546 -45.707914) (xy 343.855485 -45.757344) (xy 343.831889 -45.803654)
			(xy 343.801339 -45.845702) (xy 343.764588 -45.882453) (xy 343.72254 -45.913003) (xy 343.67623 -45.936599)
			(xy 343.6268 -45.95266) (xy 343.575465 -45.96079) (xy 343.523491 -45.96079) (xy 343.472156 -45.95266)
			(xy 343.422726 -45.936599) (xy 343.376416 -45.913003) (xy 343.334368 -45.882453) (xy 343.297617 -45.845702)
			(xy 343.267067 -45.803654) (xy 343.243471 -45.757344) (xy 343.22741 -45.707914) (xy 343.21928 -45.656579)
			(xy 342.249001 -45.656579) (xy 342.248996 -45.656833) (xy 342.240866 -45.708168) (xy 342.224805 -45.757598)
			(xy 342.201209 -45.803908) (xy 342.170659 -45.845956) (xy 342.133908 -45.882707) (xy 342.09186 -45.913257)
			(xy 342.04555 -45.936853) (xy 341.99612 -45.952914) (xy 341.944785 -45.961044) (xy 341.892811 -45.961044)
			(xy 341.841476 -45.952914) (xy 341.792046 -45.936853) (xy 341.745736 -45.913257) (xy 341.703688 -45.882707)
			(xy 341.666937 -45.845956) (xy 341.636387 -45.803908) (xy 341.612791 -45.757598) (xy 341.59673 -45.708168)
			(xy 341.5886 -45.656833) (xy 340.620852 -45.656833) (xy 340.612716 -45.708156) (xy 340.59665 -45.757578)
			(xy 340.573051 -45.803878) (xy 340.5425 -45.845916) (xy 340.505749 -45.882657) (xy 340.463702 -45.913198)
			(xy 340.417396 -45.936784) (xy 340.36797 -45.952837) (xy 340.316642 -45.960959) (xy 340.290658 -45.961554)
			(xy 340.267075 -45.961177) (xy 340.220385 -45.954508) (xy 340.175121 -45.941255) (xy 340.153498 -45.931836)
			(xy 340.140059 -45.926271) (xy 340.111281 -45.92214) (xy 340.082505 -45.926282) (xy 340.05606 -45.938362)
			(xy 340.03409 -45.957402) (xy 340.018372 -45.98186) (xy 340.01018 -46.009756) (xy 340.009734 -46.024292)
			(xy 340.009734 -46.126733) (xy 340.7758 -46.126733) (xy 340.7758 -46.074759) (xy 340.78393 -46.023424)
			(xy 340.799991 -45.973994) (xy 340.823587 -45.927684) (xy 340.854137 -45.885636) (xy 340.890888 -45.848885)
			(xy 340.932936 -45.818335) (xy 340.979246 -45.794739) (xy 341.028676 -45.778678) (xy 341.080011 -45.770548)
			(xy 341.131985 -45.770548) (xy 341.18332 -45.778678) (xy 341.23275 -45.794739) (xy 341.27906 -45.818335)
			(xy 341.321108 -45.848885) (xy 341.357859 -45.885636) (xy 341.388409 -45.927684) (xy 341.412005 -45.973994)
			(xy 341.428066 -46.023424) (xy 341.436196 -46.074759) (xy 341.436706 -46.100746) (xy 341.436201 -46.126479)
			(xy 342.404956 -46.126479) (xy 342.404956 -46.074505) (xy 342.413086 -46.02317) (xy 342.429147 -45.97374)
			(xy 342.452743 -45.92743) (xy 342.483293 -45.885382) (xy 342.520044 -45.848631) (xy 342.562092 -45.818081)
			(xy 342.608402 -45.794485) (xy 342.657832 -45.778424) (xy 342.709167 -45.770294) (xy 342.761141 -45.770294)
			(xy 342.812476 -45.778424) (xy 342.861906 -45.794485) (xy 342.908216 -45.818081) (xy 342.950264 -45.848631)
			(xy 342.987015 -45.885382) (xy 343.017565 -45.92743) (xy 343.041161 -45.97374) (xy 343.057222 -46.02317)
			(xy 343.065352 -46.074505) (xy 343.065862 -46.100492) (xy 343.065352 -46.126479) (xy 344.033096 -46.126479)
			(xy 344.033096 -46.074505) (xy 344.041226 -46.02317) (xy 344.057287 -45.97374) (xy 344.080883 -45.92743)
			(xy 344.111433 -45.885382) (xy 344.148184 -45.848631) (xy 344.190232 -45.818081) (xy 344.236542 -45.794485)
			(xy 344.285972 -45.778424) (xy 344.337307 -45.770294) (xy 344.389281 -45.770294) (xy 344.440616 -45.778424)
			(xy 344.490046 -45.794485) (xy 344.536356 -45.818081) (xy 344.578404 -45.848631) (xy 344.615155 -45.885382)
			(xy 344.645705 -45.92743) (xy 344.669301 -45.97374) (xy 344.685362 -46.02317) (xy 344.693492 -46.074505)
			(xy 344.694002 -46.100492) (xy 344.693492 -46.126479) (xy 344.685362 -46.177814) (xy 344.669301 -46.227244)
			(xy 344.645705 -46.273554) (xy 344.615155 -46.315602) (xy 344.578404 -46.352353) (xy 344.544587 -46.376923)
			(xy 344.821512 -46.376923) (xy 344.821512 -46.324949) (xy 344.829642 -46.273614) (xy 344.845703 -46.224184)
			(xy 344.869299 -46.177874) (xy 344.899849 -46.135826) (xy 344.9366 -46.099075) (xy 344.978648 -46.068525)
			(xy 345.024958 -46.044929) (xy 345.074388 -46.028868) (xy 345.125723 -46.020738) (xy 345.177697 -46.020738)
			(xy 345.229032 -46.028868) (xy 345.278462 -46.044929) (xy 345.324772 -46.068525) (xy 345.36682 -46.099075)
			(xy 345.403571 -46.135826) (xy 345.434121 -46.177874) (xy 345.457717 -46.224184) (xy 345.473778 -46.273614)
			(xy 345.481908 -46.324949) (xy 345.482418 -46.350936) (xy 345.481908 -46.376923) (xy 345.473778 -46.428258)
			(xy 345.457717 -46.477688) (xy 345.434121 -46.523998) (xy 345.403571 -46.566046) (xy 345.36682 -46.602797)
			(xy 345.324772 -46.633347) (xy 345.278462 -46.656943) (xy 345.229032 -46.673004) (xy 345.177697 -46.681134)
			(xy 345.125723 -46.681134) (xy 345.074388 -46.673004) (xy 345.024958 -46.656943) (xy 344.978648 -46.633347)
			(xy 344.9366 -46.602797) (xy 344.899849 -46.566046) (xy 344.869299 -46.523998) (xy 344.845703 -46.477688)
			(xy 344.829642 -46.428258) (xy 344.821512 -46.376923) (xy 344.544587 -46.376923) (xy 344.536356 -46.382903)
			(xy 344.490046 -46.406499) (xy 344.440616 -46.42256) (xy 344.389281 -46.43069) (xy 344.337307 -46.43069)
			(xy 344.285972 -46.42256) (xy 344.236542 -46.406499) (xy 344.190232 -46.382903) (xy 344.148184 -46.352353)
			(xy 344.111433 -46.315602) (xy 344.080883 -46.273554) (xy 344.057287 -46.227244) (xy 344.041226 -46.177814)
			(xy 344.033096 -46.126479) (xy 343.065352 -46.126479) (xy 343.057222 -46.177814) (xy 343.041161 -46.227244)
			(xy 343.017565 -46.273554) (xy 342.987015 -46.315602) (xy 342.950264 -46.352353) (xy 342.908216 -46.382903)
			(xy 342.861906 -46.406499) (xy 342.812476 -46.42256) (xy 342.761141 -46.43069) (xy 342.709167 -46.43069)
			(xy 342.657832 -46.42256) (xy 342.608402 -46.406499) (xy 342.562092 -46.382903) (xy 342.520044 -46.352353)
			(xy 342.483293 -46.315602) (xy 342.452743 -46.273554) (xy 342.429147 -46.227244) (xy 342.413086 -46.177814)
			(xy 342.404956 -46.126479) (xy 341.436201 -46.126479) (xy 341.436196 -46.126733) (xy 341.428066 -46.178068)
			(xy 341.412005 -46.227498) (xy 341.388409 -46.273808) (xy 341.357859 -46.315856) (xy 341.321108 -46.352607)
			(xy 341.27906 -46.383157) (xy 341.23275 -46.406753) (xy 341.18332 -46.422814) (xy 341.131985 -46.430944)
			(xy 341.080011 -46.430944) (xy 341.028676 -46.422814) (xy 340.979246 -46.406753) (xy 340.932936 -46.383157)
			(xy 340.890888 -46.352607) (xy 340.854137 -46.315856) (xy 340.823587 -46.273808) (xy 340.799991 -46.227498)
			(xy 340.78393 -46.178068) (xy 340.7758 -46.126733) (xy 340.009734 -46.126733) (xy 340.009734 -46.1772)
			(xy 340.01025 -46.191735) (xy 340.018436 -46.219628) (xy 340.034144 -46.244088) (xy 340.056105 -46.263135)
			(xy 340.082539 -46.275228) (xy 340.11131 -46.279388) (xy 340.140088 -46.275279) (xy 340.153498 -46.269656)
			(xy 340.175136 -46.260279) (xy 340.220399 -46.247049) (xy 340.26708 -46.240363) (xy 340.290658 -46.239938)
			(xy 340.316646 -46.240418) (xy 340.367982 -46.248543) (xy 340.417416 -46.264599) (xy 340.463728 -46.288191)
			(xy 340.50578 -46.318739) (xy 340.542534 -46.355488) (xy 340.573087 -46.397536) (xy 340.596685 -46.443846)
			(xy 340.612747 -46.493277) (xy 340.620879 -46.544612) (xy 340.620879 -46.596588) (xy 340.620872 -46.596633)
			(xy 341.5886 -46.596633) (xy 341.5886 -46.544659) (xy 341.59673 -46.493324) (xy 341.612791 -46.443894)
			(xy 341.636387 -46.397584) (xy 341.666937 -46.355536) (xy 341.703688 -46.318785) (xy 341.745736 -46.288235)
			(xy 341.792046 -46.264639) (xy 341.841476 -46.248578) (xy 341.892811 -46.240448) (xy 341.944785 -46.240448)
			(xy 341.99612 -46.248578) (xy 342.04555 -46.264639) (xy 342.09186 -46.288235) (xy 342.133908 -46.318785)
			(xy 342.170659 -46.355536) (xy 342.201209 -46.397584) (xy 342.224805 -46.443894) (xy 342.240866 -46.493324)
			(xy 342.248996 -46.544659) (xy 342.249506 -46.570646) (xy 342.249001 -46.596379) (xy 343.21928 -46.596379)
			(xy 343.21928 -46.544405) (xy 343.22741 -46.49307) (xy 343.243471 -46.44364) (xy 343.267067 -46.39733)
			(xy 343.297617 -46.355282) (xy 343.334368 -46.318531) (xy 343.376416 -46.287981) (xy 343.422726 -46.264385)
			(xy 343.472156 -46.248324) (xy 343.523491 -46.240194) (xy 343.575465 -46.240194) (xy 343.6268 -46.248324)
			(xy 343.67623 -46.264385) (xy 343.72254 -46.287981) (xy 343.764588 -46.318531) (xy 343.801339 -46.355282)
			(xy 343.831889 -46.39733) (xy 343.855485 -46.44364) (xy 343.871546 -46.49307) (xy 343.879676 -46.544405)
			(xy 343.880186 -46.570392) (xy 343.879676 -46.596379) (xy 343.871546 -46.647714) (xy 343.855485 -46.697144)
			(xy 343.831889 -46.743454) (xy 343.801339 -46.785502) (xy 343.764588 -46.822253) (xy 343.72254 -46.852803)
			(xy 343.67623 -46.876399) (xy 343.6268 -46.89246) (xy 343.575465 -46.90059) (xy 343.523491 -46.90059)
			(xy 343.472156 -46.89246) (xy 343.422726 -46.876399) (xy 343.376416 -46.852803) (xy 343.334368 -46.822253)
			(xy 343.297617 -46.785502) (xy 343.267067 -46.743454) (xy 343.243471 -46.697144) (xy 343.22741 -46.647714)
			(xy 343.21928 -46.596379) (xy 342.249001 -46.596379) (xy 342.248996 -46.596633) (xy 342.240866 -46.647968)
			(xy 342.224805 -46.697398) (xy 342.201209 -46.743708) (xy 342.170659 -46.785756) (xy 342.133908 -46.822507)
			(xy 342.09186 -46.853057) (xy 342.04555 -46.876653) (xy 341.99612 -46.892714) (xy 341.944785 -46.900844)
			(xy 341.892811 -46.900844) (xy 341.841476 -46.892714) (xy 341.792046 -46.876653) (xy 341.745736 -46.853057)
			(xy 341.703688 -46.822507) (xy 341.666937 -46.785756) (xy 341.636387 -46.743708) (xy 341.612791 -46.697398)
			(xy 341.59673 -46.647968) (xy 341.5886 -46.596633) (xy 340.620872 -46.596633) (xy 340.612747 -46.647923)
			(xy 340.596685 -46.697354) (xy 340.573087 -46.743664) (xy 340.542534 -46.785712) (xy 340.50578 -46.822461)
			(xy 340.463728 -46.853009) (xy 340.417416 -46.876601) (xy 340.367982 -46.892657) (xy 340.316646 -46.900782)
			(xy 340.290658 -46.901354) (xy 340.267075 -46.900977) (xy 340.220385 -46.894308) (xy 340.175121 -46.881055)
			(xy 340.153498 -46.871636) (xy 340.140059 -46.866071) (xy 340.111281 -46.86194) (xy 340.082505 -46.866082)
			(xy 340.05606 -46.878162) (xy 340.03409 -46.897202) (xy 340.018372 -46.92166) (xy 340.01018 -46.949556)
			(xy 340.009734 -46.964092) (xy 340.009734 -47.066533) (xy 340.7758 -47.066533) (xy 340.7758 -47.014559)
			(xy 340.78393 -46.963224) (xy 340.799991 -46.913794) (xy 340.823587 -46.867484) (xy 340.854137 -46.825436)
			(xy 340.890888 -46.788685) (xy 340.932936 -46.758135) (xy 340.979246 -46.734539) (xy 341.028676 -46.718478)
			(xy 341.080011 -46.710348) (xy 341.131985 -46.710348) (xy 341.18332 -46.718478) (xy 341.23275 -46.734539)
			(xy 341.27906 -46.758135) (xy 341.321108 -46.788685) (xy 341.357859 -46.825436) (xy 341.388409 -46.867484)
			(xy 341.412005 -46.913794) (xy 341.428066 -46.963224) (xy 341.436196 -47.014559) (xy 341.436706 -47.040546)
			(xy 341.436201 -47.066279) (xy 342.404956 -47.066279) (xy 342.404956 -47.014305) (xy 342.413086 -46.96297)
			(xy 342.429147 -46.91354) (xy 342.452743 -46.86723) (xy 342.483293 -46.825182) (xy 342.520044 -46.788431)
			(xy 342.562092 -46.757881) (xy 342.608402 -46.734285) (xy 342.657832 -46.718224) (xy 342.709167 -46.710094)
			(xy 342.761141 -46.710094) (xy 342.812476 -46.718224) (xy 342.861906 -46.734285) (xy 342.908216 -46.757881)
			(xy 342.950264 -46.788431) (xy 342.987015 -46.825182) (xy 343.017565 -46.86723) (xy 343.041161 -46.91354)
			(xy 343.057222 -46.96297) (xy 343.065352 -47.014305) (xy 343.065862 -47.040292) (xy 343.065352 -47.066279)
			(xy 344.033096 -47.066279) (xy 344.033096 -47.014305) (xy 344.041226 -46.96297) (xy 344.057287 -46.91354)
			(xy 344.080883 -46.86723) (xy 344.111433 -46.825182) (xy 344.148184 -46.788431) (xy 344.190232 -46.757881)
			(xy 344.236542 -46.734285) (xy 344.285972 -46.718224) (xy 344.337307 -46.710094) (xy 344.389281 -46.710094)
			(xy 344.440616 -46.718224) (xy 344.490046 -46.734285) (xy 344.536356 -46.757881) (xy 344.578404 -46.788431)
			(xy 344.615155 -46.825182) (xy 344.645705 -46.86723) (xy 344.669301 -46.91354) (xy 344.685362 -46.96297)
			(xy 344.693492 -47.014305) (xy 344.694002 -47.040292) (xy 344.693492 -47.066279) (xy 344.685362 -47.117614)
			(xy 344.669301 -47.167044) (xy 344.645705 -47.213354) (xy 344.615155 -47.255402) (xy 344.578404 -47.292153)
			(xy 344.536356 -47.322703) (xy 344.490046 -47.346299) (xy 344.440616 -47.36236) (xy 344.389281 -47.37049)
			(xy 344.337307 -47.37049) (xy 344.285972 -47.36236) (xy 344.236542 -47.346299) (xy 344.190232 -47.322703)
			(xy 344.148184 -47.292153) (xy 344.111433 -47.255402) (xy 344.080883 -47.213354) (xy 344.057287 -47.167044)
			(xy 344.041226 -47.117614) (xy 344.033096 -47.066279) (xy 343.065352 -47.066279) (xy 343.057222 -47.117614)
			(xy 343.041161 -47.167044) (xy 343.017565 -47.213354) (xy 342.987015 -47.255402) (xy 342.950264 -47.292153)
			(xy 342.908216 -47.322703) (xy 342.861906 -47.346299) (xy 342.812476 -47.36236) (xy 342.761141 -47.37049)
			(xy 342.709167 -47.37049) (xy 342.657832 -47.36236) (xy 342.608402 -47.346299) (xy 342.562092 -47.322703)
			(xy 342.520044 -47.292153) (xy 342.483293 -47.255402) (xy 342.452743 -47.213354) (xy 342.429147 -47.167044)
			(xy 342.413086 -47.117614) (xy 342.404956 -47.066279) (xy 341.436201 -47.066279) (xy 341.436196 -47.066533)
			(xy 341.428066 -47.117868) (xy 341.412005 -47.167298) (xy 341.388409 -47.213608) (xy 341.357859 -47.255656)
			(xy 341.321108 -47.292407) (xy 341.27906 -47.322957) (xy 341.23275 -47.346553) (xy 341.18332 -47.362614)
			(xy 341.131985 -47.370744) (xy 341.080011 -47.370744) (xy 341.028676 -47.362614) (xy 340.979246 -47.346553)
			(xy 340.932936 -47.322957) (xy 340.890888 -47.292407) (xy 340.854137 -47.255656) (xy 340.823587 -47.213608)
			(xy 340.799991 -47.167298) (xy 340.78393 -47.117868) (xy 340.7758 -47.066533) (xy 340.009734 -47.066533)
			(xy 340.009734 -47.117) (xy 340.01025 -47.131535) (xy 340.018436 -47.159428) (xy 340.034144 -47.183888)
			(xy 340.056105 -47.202935) (xy 340.082539 -47.215028) (xy 340.11131 -47.219188) (xy 340.140088 -47.215079)
			(xy 340.153498 -47.209456) (xy 340.175136 -47.200079) (xy 340.220399 -47.186849) (xy 340.26708 -47.180163)
			(xy 340.290658 -47.179738) (xy 340.316646 -47.180218) (xy 340.367982 -47.188343) (xy 340.417416 -47.204399)
			(xy 340.463728 -47.227991) (xy 340.50578 -47.258539) (xy 340.542534 -47.295288) (xy 340.573087 -47.337336)
			(xy 340.596685 -47.383646) (xy 340.612747 -47.433077) (xy 340.620879 -47.484412) (xy 340.620879 -47.536388)
			(xy 340.620872 -47.536433) (xy 341.5886 -47.536433) (xy 341.5886 -47.484459) (xy 341.59673 -47.433124)
			(xy 341.612791 -47.383694) (xy 341.636387 -47.337384) (xy 341.666937 -47.295336) (xy 341.703688 -47.258585)
			(xy 341.745736 -47.228035) (xy 341.792046 -47.204439) (xy 341.841476 -47.188378) (xy 341.892811 -47.180248)
			(xy 341.944785 -47.180248) (xy 341.99612 -47.188378) (xy 342.04555 -47.204439) (xy 342.09186 -47.228035)
			(xy 342.133908 -47.258585) (xy 342.170659 -47.295336) (xy 342.201209 -47.337384) (xy 342.224805 -47.383694)
			(xy 342.240866 -47.433124) (xy 342.248996 -47.484459) (xy 342.249506 -47.510446) (xy 342.249001 -47.536179)
			(xy 343.217756 -47.536179) (xy 343.217756 -47.484205) (xy 343.225886 -47.43287) (xy 343.241947 -47.38344)
			(xy 343.265543 -47.33713) (xy 343.296093 -47.295082) (xy 343.332844 -47.258331) (xy 343.374892 -47.227781)
			(xy 343.421202 -47.204185) (xy 343.470632 -47.188124) (xy 343.521967 -47.179994) (xy 343.573941 -47.179994)
			(xy 343.625276 -47.188124) (xy 343.674706 -47.204185) (xy 343.721016 -47.227781) (xy 343.763064 -47.258331)
			(xy 343.799815 -47.295082) (xy 343.830365 -47.33713) (xy 343.853961 -47.38344) (xy 343.870022 -47.43287)
			(xy 343.877843 -47.482252) (xy 347.709754 -47.482252) (xy 347.71373 -47.427926) (xy 347.725573 -47.374757)
			(xy 347.745032 -47.32388) (xy 347.771692 -47.276378) (xy 347.804983 -47.233264) (xy 347.844197 -47.195457)
			(xy 347.888499 -47.163762) (xy 347.936942 -47.138856) (xy 347.988496 -47.121268) (xy 348.042062 -47.111374)
			(xy 348.096497 -47.109384) (xy 348.150642 -47.115342) (xy 348.203342 -47.12912) (xy 348.253475 -47.150424)
			(xy 348.299971 -47.1788) (xy 348.341841 -47.213644) (xy 348.37819 -47.254213) (xy 348.408246 -47.299642)
			(xy 348.431367 -47.348963) (xy 348.44706 -47.401125) (xy 348.454991 -47.455016) (xy 348.455488 -47.482252)
			(xy 348.454991 -47.509488) (xy 348.44706 -47.563379) (xy 348.431367 -47.615541) (xy 348.408246 -47.664862)
			(xy 348.37819 -47.710291) (xy 348.341841 -47.75086) (xy 348.299971 -47.785704) (xy 348.253475 -47.81408)
			(xy 348.203342 -47.835384) (xy 348.150642 -47.849162) (xy 348.096497 -47.85512) (xy 348.042062 -47.85313)
			(xy 347.988496 -47.843236) (xy 347.936942 -47.825648) (xy 347.888499 -47.800742) (xy 347.844197 -47.769047)
			(xy 347.804983 -47.73124) (xy 347.771692 -47.688126) (xy 347.745032 -47.640624) (xy 347.725573 -47.589747)
			(xy 347.71373 -47.536578) (xy 347.709754 -47.482252) (xy 343.877843 -47.482252) (xy 343.878152 -47.484205)
			(xy 343.878662 -47.510192) (xy 343.878152 -47.536179) (xy 343.870022 -47.587514) (xy 343.853961 -47.636944)
			(xy 343.830365 -47.683254) (xy 343.799815 -47.725302) (xy 343.763064 -47.762053) (xy 343.721016 -47.792603)
			(xy 343.674706 -47.816199) (xy 343.625276 -47.83226) (xy 343.573941 -47.84039) (xy 343.521967 -47.84039)
			(xy 343.470632 -47.83226) (xy 343.421202 -47.816199) (xy 343.374892 -47.792603) (xy 343.332844 -47.762053)
			(xy 343.296093 -47.725302) (xy 343.265543 -47.683254) (xy 343.241947 -47.636944) (xy 343.225886 -47.587514)
			(xy 343.217756 -47.536179) (xy 342.249001 -47.536179) (xy 342.248996 -47.536433) (xy 342.240866 -47.587768)
			(xy 342.224805 -47.637198) (xy 342.201209 -47.683508) (xy 342.170659 -47.725556) (xy 342.133908 -47.762307)
			(xy 342.09186 -47.792857) (xy 342.04555 -47.816453) (xy 341.99612 -47.832514) (xy 341.944785 -47.840644)
			(xy 341.892811 -47.840644) (xy 341.841476 -47.832514) (xy 341.792046 -47.816453) (xy 341.745736 -47.792857)
			(xy 341.703688 -47.762307) (xy 341.666937 -47.725556) (xy 341.636387 -47.683508) (xy 341.612791 -47.637198)
			(xy 341.59673 -47.587768) (xy 341.5886 -47.536433) (xy 340.620872 -47.536433) (xy 340.612747 -47.587723)
			(xy 340.596685 -47.637154) (xy 340.573087 -47.683464) (xy 340.542534 -47.725512) (xy 340.50578 -47.762261)
			(xy 340.463728 -47.792809) (xy 340.417416 -47.816401) (xy 340.367982 -47.832457) (xy 340.316646 -47.840582)
			(xy 340.290658 -47.841154) (xy 340.267075 -47.840777) (xy 340.220385 -47.834108) (xy 340.175121 -47.820855)
			(xy 340.153498 -47.811436) (xy 340.140059 -47.805871) (xy 340.111281 -47.80174) (xy 340.082505 -47.805882)
			(xy 340.05606 -47.817962) (xy 340.03409 -47.837002) (xy 340.018372 -47.86146) (xy 340.01018 -47.889356)
			(xy 340.009734 -47.903892) (xy 340.009734 -48.006333) (xy 340.7758 -48.006333) (xy 340.7758 -47.954359)
			(xy 340.78393 -47.903024) (xy 340.799991 -47.853594) (xy 340.823587 -47.807284) (xy 340.854137 -47.765236)
			(xy 340.890888 -47.728485) (xy 340.932936 -47.697935) (xy 340.979246 -47.674339) (xy 341.028676 -47.658278)
			(xy 341.080011 -47.650148) (xy 341.131985 -47.650148) (xy 341.18332 -47.658278) (xy 341.23275 -47.674339)
			(xy 341.27906 -47.697935) (xy 341.321108 -47.728485) (xy 341.357859 -47.765236) (xy 341.388409 -47.807284)
			(xy 341.412005 -47.853594) (xy 341.428066 -47.903024) (xy 341.436196 -47.954359) (xy 341.436706 -47.980346)
			(xy 341.436201 -48.006079) (xy 342.403432 -48.006079) (xy 342.403432 -47.954105) (xy 342.411562 -47.90277)
			(xy 342.427623 -47.85334) (xy 342.451219 -47.80703) (xy 342.481769 -47.764982) (xy 342.51852 -47.728231)
			(xy 342.560568 -47.697681) (xy 342.606878 -47.674085) (xy 342.656308 -47.658024) (xy 342.707643 -47.649894)
			(xy 342.759617 -47.649894) (xy 342.810952 -47.658024) (xy 342.860382 -47.674085) (xy 342.906692 -47.697681)
			(xy 342.94874 -47.728231) (xy 342.985491 -47.764982) (xy 343.016041 -47.80703) (xy 343.039637 -47.85334)
			(xy 343.055698 -47.90277) (xy 343.063828 -47.954105) (xy 343.064338 -47.980092) (xy 343.063828 -48.006079)
			(xy 343.055698 -48.057414) (xy 343.039637 -48.106844) (xy 343.016041 -48.153154) (xy 342.985491 -48.195202)
			(xy 342.94874 -48.231953) (xy 342.906692 -48.262503) (xy 342.860382 -48.286099) (xy 342.810952 -48.30216)
			(xy 342.759617 -48.31029) (xy 342.707643 -48.31029) (xy 342.656308 -48.30216) (xy 342.606878 -48.286099)
			(xy 342.560568 -48.262503) (xy 342.51852 -48.231953) (xy 342.481769 -48.195202) (xy 342.451219 -48.153154)
			(xy 342.427623 -48.106844) (xy 342.411562 -48.057414) (xy 342.403432 -48.006079) (xy 341.436201 -48.006079)
			(xy 341.436196 -48.006333) (xy 341.428066 -48.057668) (xy 341.412005 -48.107098) (xy 341.388409 -48.153408)
			(xy 341.357859 -48.195456) (xy 341.321108 -48.232207) (xy 341.27906 -48.262757) (xy 341.23275 -48.286353)
			(xy 341.18332 -48.302414) (xy 341.131985 -48.310544) (xy 341.080011 -48.310544) (xy 341.028676 -48.302414)
			(xy 340.979246 -48.286353) (xy 340.932936 -48.262757) (xy 340.890888 -48.232207) (xy 340.854137 -48.195456)
			(xy 340.823587 -48.153408) (xy 340.799991 -48.107098) (xy 340.78393 -48.057668) (xy 340.7758 -48.006333)
			(xy 340.009734 -48.006333) (xy 340.009734 -48.0568) (xy 340.01025 -48.071335) (xy 340.018436 -48.099228)
			(xy 340.034144 -48.123688) (xy 340.056105 -48.142735) (xy 340.082539 -48.154828) (xy 340.11131 -48.158988)
			(xy 340.140088 -48.154879) (xy 340.153498 -48.149256) (xy 340.175136 -48.139879) (xy 340.220399 -48.126649)
			(xy 340.26708 -48.119963) (xy 340.290658 -48.119538) (xy 340.316646 -48.120018) (xy 340.367982 -48.128143)
			(xy 340.417416 -48.144199) (xy 340.463728 -48.167791) (xy 340.50578 -48.198339) (xy 340.542534 -48.235088)
			(xy 340.573087 -48.277136) (xy 340.596685 -48.323446) (xy 340.612747 -48.372877) (xy 340.620879 -48.424212)
			(xy 340.620879 -48.476188) (xy 340.620872 -48.476233) (xy 341.5886 -48.476233) (xy 341.5886 -48.424259)
			(xy 341.59673 -48.372924) (xy 341.612791 -48.323494) (xy 341.636387 -48.277184) (xy 341.666937 -48.235136)
			(xy 341.703688 -48.198385) (xy 341.745736 -48.167835) (xy 341.792046 -48.144239) (xy 341.841476 -48.128178)
			(xy 341.892811 -48.120048) (xy 341.944785 -48.120048) (xy 341.99612 -48.128178) (xy 342.04555 -48.144239)
			(xy 342.09186 -48.167835) (xy 342.133908 -48.198385) (xy 342.170659 -48.235136) (xy 342.201209 -48.277184)
			(xy 342.224805 -48.323494) (xy 342.240866 -48.372924) (xy 342.248996 -48.424259) (xy 342.249506 -48.450246)
			(xy 342.248996 -48.476233) (xy 342.240866 -48.527568) (xy 342.224805 -48.576998) (xy 342.201209 -48.623308)
			(xy 342.170659 -48.665356) (xy 342.133908 -48.702107) (xy 342.09186 -48.732657) (xy 342.04555 -48.756253)
			(xy 341.99612 -48.772314) (xy 341.944785 -48.780444) (xy 341.892811 -48.780444) (xy 341.841476 -48.772314)
			(xy 341.792046 -48.756253) (xy 341.745736 -48.732657) (xy 341.703688 -48.702107) (xy 341.666937 -48.665356)
			(xy 341.636387 -48.623308) (xy 341.612791 -48.576998) (xy 341.59673 -48.527568) (xy 341.5886 -48.476233)
			(xy 340.620872 -48.476233) (xy 340.612747 -48.527523) (xy 340.596685 -48.576954) (xy 340.573087 -48.623264)
			(xy 340.542534 -48.665312) (xy 340.50578 -48.702061) (xy 340.463728 -48.732609) (xy 340.417416 -48.756201)
			(xy 340.367982 -48.772257) (xy 340.316646 -48.780382) (xy 340.290658 -48.780954) (xy 340.267075 -48.780577)
			(xy 340.220385 -48.773908) (xy 340.175121 -48.760655) (xy 340.153498 -48.751236) (xy 340.140059 -48.745671)
			(xy 340.111281 -48.74154) (xy 340.082505 -48.745682) (xy 340.05606 -48.757762) (xy 340.03409 -48.776802)
			(xy 340.018372 -48.80126) (xy 340.01018 -48.829156) (xy 340.009734 -48.843692) (xy 340.009734 -49.27346)
			(xy 339.948774 -49.33442) (xy 339.939353 -49.344461) (xy 339.925768 -49.368395) (xy 339.919064 -49.395088)
			(xy 339.91957 -49.416033) (xy 341.5886 -49.416033) (xy 341.5886 -49.364059) (xy 341.59673 -49.312724)
			(xy 341.612791 -49.263294) (xy 341.636387 -49.216984) (xy 341.666937 -49.174936) (xy 341.703688 -49.138185)
			(xy 341.745736 -49.107635) (xy 341.792046 -49.084039) (xy 341.841476 -49.067978) (xy 341.892811 -49.059848)
			(xy 341.944785 -49.059848) (xy 341.99612 -49.067978) (xy 342.04555 -49.084039) (xy 342.09186 -49.107635)
			(xy 342.133908 -49.138185) (xy 342.170659 -49.174936) (xy 342.201209 -49.216984) (xy 342.224805 -49.263294)
			(xy 342.240866 -49.312724) (xy 342.248996 -49.364059) (xy 342.249506 -49.390046) (xy 342.248996 -49.416033)
			(xy 342.240866 -49.467368) (xy 342.224805 -49.516798) (xy 342.201209 -49.563108) (xy 342.170659 -49.605156)
			(xy 342.133908 -49.641907) (xy 342.09186 -49.672457) (xy 342.04555 -49.696053) (xy 341.99612 -49.712114)
			(xy 341.944785 -49.720244) (xy 341.892811 -49.720244) (xy 341.841476 -49.712114) (xy 341.792046 -49.696053)
			(xy 341.745736 -49.672457) (xy 341.703688 -49.641907) (xy 341.666937 -49.605156) (xy 341.636387 -49.563108)
			(xy 341.612791 -49.516798) (xy 341.59673 -49.467368) (xy 341.5886 -49.416033) (xy 339.91957 -49.416033)
			(xy 339.919729 -49.422601) (xy 339.927713 -49.448939) (xy 339.942438 -49.47219) (xy 339.962836 -49.490666)
			(xy 339.974936 -49.497234) (xy 339.998096 -49.509388) (xy 340.040592 -49.539877) (xy 340.07776 -49.576673)
			(xy 340.108675 -49.61886) (xy 340.132566 -49.665386) (xy 340.148838 -49.715092) (xy 340.157085 -49.766739)
			(xy 340.157562 -49.79289) (xy 340.15708 -49.818878) (xy 340.148949 -49.870216) (xy 340.132887 -49.919648)
			(xy 340.109289 -49.96596) (xy 340.078737 -50.008009) (xy 340.041981 -50.04476) (xy 339.999929 -50.075308)
			(xy 339.953615 -50.098901) (xy 339.90418 -50.114958) (xy 339.852843 -50.123082) (xy 339.826854 -50.123598)
			(xy 339.801593 -50.123101) (xy 339.751664 -50.115382) (xy 339.703489 -50.100159) (xy 339.658189 -50.077788)
			(xy 339.616817 -50.048789) (xy 339.598254 -50.03165) (xy 339.587168 -50.021728) (xy 339.560689 -50.008192)
			(xy 339.531434 -50.002851) (xy 339.50188 -50.006157) (xy 339.474529 -50.017831) (xy 339.451696 -50.036884)
			(xy 339.435314 -50.061702) (xy 339.426769 -50.090187) (xy 339.426296 -50.105056) (xy 339.426296 -50.355833)
			(xy 341.59114 -50.355833) (xy 341.59114 -50.303859) (xy 341.59927 -50.252524) (xy 341.615331 -50.203094)
			(xy 341.638927 -50.156784) (xy 341.669477 -50.114736) (xy 341.706228 -50.077985) (xy 341.748276 -50.047435)
			(xy 341.794586 -50.023839) (xy 341.844016 -50.007778) (xy 341.895351 -49.999648) (xy 341.947325 -49.999648)
			(xy 341.99866 -50.007778) (xy 342.04809 -50.023839) (xy 342.0944 -50.047435) (xy 342.136448 -50.077985)
			(xy 342.173199 -50.114736) (xy 342.203749 -50.156784) (xy 342.227345 -50.203094) (xy 342.243406 -50.252524)
			(xy 342.251536 -50.303859) (xy 342.252046 -50.329846) (xy 342.251536 -50.355833) (xy 342.243406 -50.407168)
			(xy 342.227345 -50.456598) (xy 342.203749 -50.502908) (xy 342.173199 -50.544956) (xy 342.136448 -50.581707)
			(xy 342.0944 -50.612257) (xy 342.04809 -50.635853) (xy 341.99866 -50.651914) (xy 341.947325 -50.660044)
			(xy 341.895351 -50.660044) (xy 341.844016 -50.651914) (xy 341.794586 -50.635853) (xy 341.748276 -50.612257)
			(xy 341.706228 -50.581707) (xy 341.669477 -50.544956) (xy 341.638927 -50.502908) (xy 341.615331 -50.456598)
			(xy 341.59927 -50.407168) (xy 341.59114 -50.355833) (xy 339.426296 -50.355833) (xy 339.426296 -50.862484)
			(xy 339.426717 -50.876643) (xy 339.434415 -50.903892) (xy 339.449305 -50.927977) (xy 339.470242 -50.947041)
			(xy 339.495612 -50.959616) (xy 339.523461 -50.964734) (xy 339.551644 -50.962001) (xy 339.56498 -50.957226)
			(xy 339.593998 -50.946573) (xy 339.654726 -50.935073) (xy 339.68563 -50.934366) (xy 339.711618 -50.934878)
			(xy 339.762953 -50.943013) (xy 339.812383 -50.959078) (xy 339.858692 -50.982677) (xy 339.900739 -51.01323)
			(xy 339.93749 -51.049984) (xy 339.968039 -51.092034) (xy 339.991634 -51.138345) (xy 340.007694 -51.187777)
			(xy 340.015824 -51.239112) (xy 340.015825 -51.291088) (xy 340.015105 -51.295633) (xy 341.59114 -51.295633)
			(xy 341.59114 -51.243659) (xy 341.59927 -51.192324) (xy 341.615331 -51.142894) (xy 341.638927 -51.096584)
			(xy 341.669477 -51.054536) (xy 341.706228 -51.017785) (xy 341.748276 -50.987235) (xy 341.794586 -50.963639)
			(xy 341.844016 -50.947578) (xy 341.895351 -50.939448) (xy 341.947325 -50.939448) (xy 341.99866 -50.947578)
			(xy 342.04809 -50.963639) (xy 342.0944 -50.987235) (xy 342.136448 -51.017785) (xy 342.173199 -51.054536)
			(xy 342.203749 -51.096584) (xy 342.227345 -51.142894) (xy 342.243406 -51.192324) (xy 342.251536 -51.243659)
			(xy 342.252046 -51.269646) (xy 342.251536 -51.295633) (xy 342.243406 -51.346968) (xy 342.227345 -51.396398)
			(xy 342.203749 -51.442708) (xy 342.173199 -51.484756) (xy 342.136448 -51.521507) (xy 342.0944 -51.552057)
			(xy 342.04809 -51.575653) (xy 341.99866 -51.591714) (xy 341.947325 -51.599844) (xy 341.895351 -51.599844)
			(xy 341.844016 -51.591714) (xy 341.794586 -51.575653) (xy 341.748276 -51.552057) (xy 341.706228 -51.521507)
			(xy 341.669477 -51.484756) (xy 341.638927 -51.442708) (xy 341.615331 -51.396398) (xy 341.59927 -51.346968)
			(xy 341.59114 -51.295633) (xy 340.015105 -51.295633) (xy 340.007694 -51.342423) (xy 339.991634 -51.391855)
			(xy 339.968039 -51.438166) (xy 339.93749 -51.480216) (xy 339.900739 -51.51697) (xy 339.858692 -51.547523)
			(xy 339.812383 -51.571122) (xy 339.762953 -51.587187) (xy 339.711618 -51.595322) (xy 339.68563 -51.595782)
			(xy 339.654729 -51.595062) (xy 339.594006 -51.58355) (xy 339.56498 -51.572922) (xy 339.551639 -51.568188)
			(xy 339.523473 -51.565486) (xy 339.495646 -51.570618) (xy 339.470296 -51.58319) (xy 339.44937 -51.602236)
			(xy 339.434474 -51.626293) (xy 339.426753 -51.653515) (xy 339.426296 -51.667664) (xy 339.426296 -51.730148)
			(xy 339.656674 -51.960526) (xy 340.043516 -51.960526) (xy 340.062318 -51.941987) (xy 340.104721 -51.910527)
			(xy 340.151584 -51.886205) (xy 340.201716 -51.869638) (xy 340.253845 -51.861249) (xy 340.306643 -51.861249)
			(xy 340.358772 -51.869638) (xy 340.408904 -51.886205) (xy 340.455767 -51.910527) (xy 340.49817 -51.941987)
			(xy 340.516972 -51.960526) (xy 342.036654 -51.960526) (xy 342.706198 -51.290982) (xy 342.715432 -51.281187)
			(xy 342.728852 -51.257862) (xy 342.735705 -51.231839) (xy 342.735515 -51.20493) (xy 342.728294 -51.179006)
			(xy 342.714545 -51.155874) (xy 342.695225 -51.137141) (xy 342.671679 -51.124113) (xy 342.6587 -51.120548)
			(xy 342.635078 -51.11428) (xy 342.58986 -51.095742) (xy 342.54786 -51.070754) (xy 342.509994 -51.039859)
			(xy 342.477084 -51.00373) (xy 342.449847 -50.963152) (xy 342.428876 -50.91901) (xy 342.414627 -50.872262)
			(xy 342.40741 -50.823927) (xy 342.406986 -50.799492) (xy 342.407527 -50.772056) (xy 342.416588 -50.717938)
			(xy 342.434459 -50.666059) (xy 342.46065 -50.617842) (xy 342.494442 -50.574611) (xy 342.534908 -50.537552)
			(xy 342.580937 -50.507682) (xy 342.605868 -50.496216) (xy 342.599011 -50.4549) (xy 342.591631 -50.37147)
			(xy 342.591136 -50.329592) (xy 342.591605 -50.287974) (xy 342.598856 -50.205053) (xy 342.605614 -50.163984)
			(xy 342.583554 -50.154118) (xy 342.542318 -50.128927) (xy 342.505186 -50.098002) (xy 342.472951 -50.062003)
			(xy 342.446299 -50.021695) (xy 342.425797 -49.977937) (xy 342.411882 -49.931661) (xy 342.40485 -49.883853)
			(xy 342.404446 -49.859692) (xy 342.404956 -49.833704) (xy 342.413087 -49.782368) (xy 342.429148 -49.732935)
			(xy 342.452744 -49.686624) (xy 342.483293 -49.644573) (xy 342.520044 -49.607818) (xy 342.562091 -49.577264)
			(xy 342.6084 -49.553663) (xy 342.657831 -49.537596) (xy 342.709166 -49.529459) (xy 342.735154 -49.528984)
			(xy 342.746878 -49.529091) (xy 342.770267 -49.530745) (xy 342.78189 -49.532286) (xy 342.79656 -49.533901)
			(xy 342.825746 -49.529597) (xy 342.852487 -49.517136) (xy 342.874554 -49.497556) (xy 342.890109 -49.472488)
			(xy 342.894412 -49.458372) (xy 342.912176 -49.395824) (xy 342.95694 -49.273737) (xy 342.98382 -49.214532)
			(xy 342.988646 -49.204372) (xy 342.988646 -48.827944) (xy 343.240614 -48.575976) (xy 343.231724 -48.546766)
			(xy 343.224968 -48.523145) (xy 343.217704 -48.474556) (xy 343.217246 -48.449992) (xy 343.217756 -48.424004)
			(xy 343.225887 -48.372668) (xy 343.241948 -48.323235) (xy 343.265544 -48.276924) (xy 343.296093 -48.234873)
			(xy 343.332844 -48.198118) (xy 343.374891 -48.167564) (xy 343.4212 -48.143963) (xy 343.470631 -48.127896)
			(xy 343.521966 -48.119759) (xy 343.547954 -48.119284) (xy 343.57215 -48.119709) (xy 343.620024 -48.126766)
			(xy 343.666359 -48.140723) (xy 343.710167 -48.161282) (xy 343.750512 -48.188003) (xy 343.786534 -48.220317)
			(xy 343.817464 -48.257533) (xy 343.842642 -48.298859) (xy 343.8525 -48.32096) (xy 343.865708 -48.351948)
			(xy 344.061034 -48.351948) (xy 344.07602 -48.3362) (xy 344.096848 -48.31461) (xy 344.100658 -48.3108)
			(xy 344.163396 -48.248316) (xy 344.127836 -48.212248) (xy 344.110095 -48.193574) (xy 344.080038 -48.151746)
			(xy 344.056839 -48.10576) (xy 344.041059 -48.05673) (xy 344.03308 -48.005845) (xy 344.032586 -47.980092)
			(xy 344.033096 -47.954105) (xy 344.041228 -47.902771) (xy 344.057289 -47.853341) (xy 344.080885 -47.807033)
			(xy 344.111435 -47.764985) (xy 344.148186 -47.728234) (xy 344.190234 -47.697684) (xy 344.236543 -47.674088)
			(xy 344.285973 -47.658027) (xy 344.337307 -47.649896) (xy 344.363294 -47.649384) (xy 344.390725 -47.649922)
			(xy 344.444836 -47.658969) (xy 344.496714 -47.676816) (xy 344.544938 -47.702975) (xy 344.588187 -47.736728)
			(xy 344.607134 -47.756572) (xy 344.617527 -47.767177) (xy 344.643011 -47.782386) (xy 344.671795 -47.789617)
			(xy 344.701442 -47.78826) (xy 344.729444 -47.778427) (xy 344.753432 -47.760952) (xy 344.762836 -47.74946)
			(xy 344.778583 -47.729525) (xy 344.815156 -47.694269) (xy 344.856688 -47.665017) (xy 344.902203 -47.642456)
			(xy 344.950631 -47.627116) (xy 345.000834 -47.619358) (xy 345.026234 -47.618904) (xy 345.051384 -47.619376)
			(xy 345.101103 -47.626999) (xy 345.149095 -47.642064) (xy 345.194251 -47.664222) (xy 345.235531 -47.692964)
			(xy 345.271983 -47.727625) (xy 345.302764 -47.767407) (xy 345.327166 -47.811392) (xy 345.336368 -47.834804)
			(xy 345.34214 -47.848967) (xy 345.36072 -47.873245) (xy 345.385641 -47.890953) (xy 345.41468 -47.90051)
			(xy 345.445246 -47.901065) (xy 345.460066 -47.897288) (xy 345.505041 -47.884718) (xy 345.596756 -47.86711)
			(xy 345.689723 -47.858235) (xy 345.736418 -47.857664) (xy 345.912694 -47.857664) (xy 345.955835 -47.858121)
			(xy 346.04179 -47.865642) (xy 346.126761 -47.880626) (xy 346.210104 -47.90296) (xy 346.291182 -47.932473)
			(xy 346.369379 -47.968941) (xy 346.444099 -48.012087) (xy 346.514774 -48.061582) (xy 346.580866 -48.117048)
			(xy 346.611702 -48.147224) (xy 346.816172 -48.351948) (xy 346.842588 -48.351948) (xy 348.285816 -49.795176)
			(xy 348.285816 -49.938686) (xy 348.289118 -49.947322) (xy 348.304648 -49.989493) (xy 348.328898 -50.076034)
			(xy 348.345184 -50.164421) (xy 348.347653 -50.1914) (xy 349.536449 -50.1914) (xy 349.540618 -50.135781)
			(xy 349.55303 -50.081405) (xy 349.573408 -50.029486) (xy 349.601297 -49.981185) (xy 349.636074 -49.93758)
			(xy 349.676961 -49.899646) (xy 349.723047 -49.86823) (xy 349.7733 -49.844033) (xy 349.826598 -49.827598)
			(xy 349.881751 -49.81929) (xy 349.909638 -49.818798) (xy 349.938744 -49.81938) (xy 349.996248 -49.828424)
			(xy 350.051646 -49.846301) (xy 350.103589 -49.872576) (xy 350.150815 -49.906609) (xy 350.192172 -49.947573)
			(xy 350.209866 -49.97069) (xy 350.218187 -49.981236) (xy 350.239154 -49.998008) (xy 350.263772 -50.008724)
			(xy 350.290334 -50.012642) (xy 350.316998 -50.009489) (xy 350.341914 -49.999485) (xy 350.363355 -49.983323)
			(xy 350.371918 -49.972976) (xy 350.390112 -49.950506) (xy 350.432143 -49.910809) (xy 350.479685 -49.877911)
			(xy 350.531648 -49.852566) (xy 350.586841 -49.835356) (xy 350.644 -49.826675) (xy 350.672908 -49.826164)
			(xy 351.536508 -49.826164) (xy 351.563139 -49.826604) (xy 351.615884 -49.834007) (xy 351.667089 -49.848668)
			(xy 351.715759 -49.870303) (xy 351.76095 -49.898493) (xy 351.801785 -49.932688) (xy 351.819972 -49.952148)
			(xy 351.829758 -49.962222) (xy 351.853536 -49.97714) (xy 351.880479 -49.98502) (xy 351.908549 -49.985266)
			(xy 351.935625 -49.97786) (xy 351.959662 -49.963361) (xy 351.969578 -49.953418) (xy 351.987309 -49.935118)
			(xy 352.026836 -49.902966) (xy 352.070371 -49.876492) (xy 352.117105 -49.856191) (xy 352.166167 -49.842439)
			(xy 352.216644 -49.835493) (xy 352.24212 -49.835054) (xy 352.268437 -49.835511) (xy 352.320553 -49.842879)
			(xy 352.371113 -49.857507) (xy 352.419112 -49.879104) (xy 352.463594 -49.907241) (xy 352.483928 -49.923954)
			(xy 352.49535 -49.933018) (xy 352.521967 -49.944891) (xy 352.550852 -49.948775) (xy 352.57966 -49.944354)
			(xy 352.606051 -49.931987) (xy 352.617278 -49.922684) (xy 352.638344 -49.904586) (xy 352.684755 -49.874081)
			(xy 352.735095 -49.850622) (xy 352.788303 -49.834704) (xy 352.843255 -49.826661) (xy 352.871024 -49.826164)
			(xy 353.734624 -49.826164) (xy 353.764955 -49.826701) (xy 353.824855 -49.836271) (xy 353.882488 -49.855197)
			(xy 353.936399 -49.883004) (xy 353.985233 -49.91899) (xy 354.006912 -49.94021) (xy 354.01656 -49.949417)
			(xy 354.039498 -49.962997) (xy 354.065169 -49.970177) (xy 354.091823 -49.970467) (xy 354.117645 -49.963849)
			(xy 354.140873 -49.950773) (xy 354.150676 -49.941734) (xy 354.171697 -49.921866) (xy 354.218728 -49.888201)
			(xy 354.270401 -49.862218) (xy 354.325472 -49.844542) (xy 354.382615 -49.835599) (xy 354.411534 -49.835054)
			(xy 354.44074 -49.835611) (xy 354.498434 -49.844739) (xy 354.553995 -49.862767) (xy 354.606058 -49.889251)
			(xy 354.653346 -49.923542) (xy 354.674424 -49.943766) (xy 354.684288 -49.952921) (xy 354.707654 -49.966249)
			(xy 354.73369 -49.973009) (xy 354.760589 -49.972733) (xy 354.786481 -49.965439) (xy 354.809568 -49.951634)
			(xy 354.819204 -49.942242) (xy 354.837263 -49.92422) (xy 354.877329 -49.892635) (xy 354.921246 -49.86667)
			(xy 354.968231 -49.846788) (xy 355.017447 -49.833342) (xy 355.068014 -49.826575) (xy 355.093524 -49.826164)
			(xy 355.957124 -49.826164) (xy 355.987455 -49.826701) (xy 356.047355 -49.836271) (xy 356.104988 -49.855197)
			(xy 356.158899 -49.883004) (xy 356.207733 -49.91899) (xy 356.229412 -49.94021) (xy 356.23906 -49.949417)
			(xy 356.261998 -49.962997) (xy 356.287669 -49.970177) (xy 356.314323 -49.970467) (xy 356.340145 -49.963849)
			(xy 356.363373 -49.950773) (xy 356.373176 -49.941734) (xy 356.394197 -49.921866) (xy 356.441228 -49.888201)
			(xy 356.492901 -49.862218) (xy 356.547972 -49.844542) (xy 356.605115 -49.835599) (xy 356.634034 -49.835054)
			(xy 356.663674 -49.83559) (xy 356.722202 -49.845) (xy 356.778501 -49.863561) (xy 356.83115 -49.890805)
			(xy 356.878819 -49.926043) (xy 356.899972 -49.946814) (xy 356.909833 -49.956231) (xy 356.933408 -49.969912)
			(xy 356.959759 -49.976881) (xy 356.987014 -49.976643) (xy 357.01324 -49.969214) (xy 357.036571 -49.955122)
			(xy 357.046276 -49.945544) (xy 357.064362 -49.927022) (xy 357.104682 -49.894553) (xy 357.149026 -49.86784)
			(xy 357.196577 -49.847375) (xy 357.246461 -49.833535) (xy 357.297759 -49.826574) (xy 357.323644 -49.826164)
			(xy 358.187244 -49.826164) (xy 358.217573 -49.826751) (xy 358.277471 -49.836309) (xy 358.335103 -49.855224)
			(xy 358.389015 -49.883019) (xy 358.437851 -49.918995) (xy 358.459532 -49.94021) (xy 358.469162 -49.949437)
			(xy 358.492105 -49.963016) (xy 358.517781 -49.970193) (xy 358.544439 -49.97048) (xy 358.570263 -49.963857)
			(xy 358.593493 -49.950776) (xy 358.603296 -49.941734) (xy 358.624308 -49.921856) (xy 358.671342 -49.888193)
			(xy 358.723017 -49.862212) (xy 358.77809 -49.844538) (xy 358.835234 -49.835598) (xy 358.864154 -49.835054)
			(xy 358.892041 -49.835602) (xy 358.947193 -49.843909) (xy 359.00049 -49.860343) (xy 359.050742 -49.884538)
			(xy 359.096827 -49.915953) (xy 359.137715 -49.953886) (xy 359.172491 -49.997489) (xy 359.20038 -50.04579)
			(xy 359.220758 -50.097707) (xy 359.23317 -50.152082) (xy 359.237338 -50.2077) (xy 359.23317 -50.263318)
			(xy 359.220758 -50.317693) (xy 359.20038 -50.36961) (xy 359.172491 -50.417911) (xy 359.137715 -50.461514)
			(xy 359.096827 -50.499447) (xy 359.050742 -50.530862) (xy 359.00049 -50.555057) (xy 358.947193 -50.571491)
			(xy 358.892041 -50.579798) (xy 358.864154 -50.58029) (xy 358.835235 -50.579771) (xy 358.778094 -50.57081)
			(xy 358.723025 -50.553124) (xy 358.671351 -50.52714) (xy 358.624314 -50.493482) (xy 358.603296 -50.47361)
			(xy 358.593488 -50.464577) (xy 358.570258 -50.451504) (xy 358.544437 -50.444885) (xy 358.517783 -50.445172)
			(xy 358.49211 -50.452345) (xy 358.469168 -50.465916) (xy 358.459532 -50.475134) (xy 358.43784 -50.496339)
			(xy 358.389012 -50.532327) (xy 358.335103 -50.560132) (xy 358.277472 -50.579054) (xy 358.217573 -50.588615)
			(xy 358.187244 -50.58918) (xy 357.323644 -50.58918) (xy 357.297762 -50.58876) (xy 357.246473 -50.581772)
			(xy 357.196598 -50.567919) (xy 357.149052 -50.547453) (xy 357.104708 -50.520752) (xy 357.064377 -50.488304)
			(xy 357.046276 -50.4698) (xy 357.03658 -50.460195) (xy 357.013265 -50.44603) (xy 356.987026 -50.43856)
			(xy 356.959746 -50.43832) (xy 356.933381 -50.445329) (xy 356.90982 -50.459082) (xy 356.899972 -50.46853)
			(xy 356.878834 -50.489315) (xy 356.831164 -50.524553) (xy 356.778511 -50.551789) (xy 356.722206 -50.570334)
			(xy 356.663674 -50.579721) (xy 356.634034 -50.58029) (xy 356.605117 -50.579722) (xy 356.547978 -50.570772)
			(xy 356.49291 -50.553098) (xy 356.441235 -50.527125) (xy 356.394195 -50.493477) (xy 356.373176 -50.47361)
			(xy 356.363385 -50.464557) (xy 356.34015 -50.451485) (xy 356.314325 -50.444869) (xy 356.287667 -50.44516)
			(xy 356.261992 -50.452337) (xy 356.239048 -50.465913) (xy 356.229412 -50.475134) (xy 356.207729 -50.496348)
			(xy 356.158898 -50.532335) (xy 356.104987 -50.560139) (xy 356.047354 -50.579058) (xy 355.987454 -50.588617)
			(xy 355.957124 -50.58918) (xy 355.093524 -50.58918) (xy 355.068012 -50.588805) (xy 355.017437 -50.582045)
			(xy 354.968216 -50.568602) (xy 354.921226 -50.548716) (xy 354.877307 -50.522743) (xy 354.837244 -50.491147)
			(xy 354.819204 -50.473102) (xy 354.809599 -50.463673) (xy 354.786498 -50.449868) (xy 354.760595 -50.442574)
			(xy 354.733685 -50.442298) (xy 354.707637 -50.449058) (xy 354.684258 -50.462385) (xy 354.674424 -50.471578)
			(xy 354.653326 -50.491776) (xy 354.606028 -50.526038) (xy 354.553967 -50.552509) (xy 354.498417 -50.570543)
			(xy 354.440735 -50.579697) (xy 354.411534 -50.58029) (xy 354.382617 -50.579722) (xy 354.325478 -50.570772)
			(xy 354.27041 -50.553098) (xy 354.218735 -50.527125) (xy 354.171695 -50.493477) (xy 354.150676 -50.47361)
			(xy 354.140885 -50.464557) (xy 354.11765 -50.451485) (xy 354.091825 -50.444869) (xy 354.065167 -50.44516)
			(xy 354.039492 -50.452337) (xy 354.016548 -50.465913) (xy 354.006912 -50.475134) (xy 353.985229 -50.496348)
			(xy 353.936398 -50.532335) (xy 353.882487 -50.560139) (xy 353.824854 -50.579058) (xy 353.764954 -50.588617)
			(xy 353.734624 -50.58918) (xy 352.871024 -50.58918) (xy 352.843255 -50.588697) (xy 352.788303 -50.580652)
			(xy 352.735097 -50.564727) (xy 352.68476 -50.54126) (xy 352.638356 -50.510745) (xy 352.617278 -50.49266)
			(xy 352.606084 -50.483296) (xy 352.579687 -50.470871) (xy 352.550853 -50.466428) (xy 352.52194 -50.470331)
			(xy 352.495316 -50.482261) (xy 352.483928 -50.49139) (xy 352.463601 -50.508114) (xy 352.419119 -50.536255)
			(xy 352.371119 -50.557857) (xy 352.320557 -50.572487) (xy 352.268439 -50.579856) (xy 352.24212 -50.58029)
			(xy 352.21664 -50.579879) (xy 352.166153 -50.572952) (xy 352.11708 -50.55921) (xy 352.070338 -50.538911)
			(xy 352.026797 -50.512432) (xy 351.98727 -50.480267) (xy 351.969578 -50.461926) (xy 351.959712 -50.451914)
			(xy 351.935666 -50.43737) (xy 351.908564 -50.42994) (xy 351.880463 -50.430187) (xy 351.853495 -50.438092)
			(xy 351.829708 -50.453055) (xy 351.819972 -50.463196) (xy 351.801799 -50.482673) (xy 351.760977 -50.516892)
			(xy 351.715787 -50.545095) (xy 351.667111 -50.566732) (xy 351.615897 -50.581381) (xy 351.563142 -50.588757)
			(xy 351.536508 -50.58918) (xy 350.672908 -50.58918) (xy 350.646971 -50.588759) (xy 350.595574 -50.581731)
			(xy 350.545604 -50.567803) (xy 350.497982 -50.547232) (xy 350.453587 -50.520398) (xy 350.413238 -50.487796)
			(xy 350.377678 -50.450026) (xy 350.362266 -50.42916) (xy 350.354124 -50.418476) (xy 350.333371 -50.401436)
			(xy 350.308895 -50.390394) (xy 350.282386 -50.386113) (xy 350.255678 -50.388889) (xy 350.230617 -50.398531)
			(xy 350.208934 -50.414371) (xy 350.200214 -50.424588) (xy 350.182421 -50.44594) (xy 350.141593 -50.483648)
			(xy 350.095615 -50.514872) (xy 350.045509 -50.538919) (xy 349.992387 -50.555255) (xy 349.937427 -50.563517)
			(xy 349.909638 -50.564034) (xy 349.881751 -50.56351) (xy 349.826598 -50.555202) (xy 349.7733 -50.538767)
			(xy 349.723047 -50.51457) (xy 349.676961 -50.483154) (xy 349.636074 -50.44522) (xy 349.601297 -50.401615)
			(xy 349.573408 -50.353314) (xy 349.55303 -50.301395) (xy 349.540618 -50.247019) (xy 349.536449 -50.1914)
			(xy 348.347653 -50.1914) (xy 348.353373 -50.253921) (xy 348.353888 -50.298858) (xy 348.353888 -52.939188)
			(xy 348.944182 -52.939188) (xy 348.948253 -52.883566) (xy 348.960379 -52.829129) (xy 348.980302 -52.777038)
			(xy 349.007598 -52.728403) (xy 349.041684 -52.68426) (xy 349.081833 -52.645551) (xy 349.127191 -52.6131)
			(xy 349.176791 -52.587599) (xy 349.229575 -52.569592) (xy 349.284418 -52.559462) (xy 349.340152 -52.557425)
			(xy 349.395589 -52.563525) (xy 349.449546 -52.577631) (xy 349.500875 -52.599443) (xy 349.548481 -52.628497)
			(xy 349.591349 -52.664172) (xy 349.628566 -52.705709) (xy 349.659339 -52.752222) (xy 349.683011 -52.802719)
			(xy 349.699079 -52.856126) (xy 349.707199 -52.911302) (xy 349.707708 -52.939188) (xy 349.707199 -52.967074)
			(xy 349.699079 -53.02225) (xy 349.683011 -53.075657) (xy 349.659339 -53.126154) (xy 349.628566 -53.172667)
			(xy 349.591349 -53.214204) (xy 349.548481 -53.249879) (xy 349.500875 -53.278933) (xy 349.449546 -53.300745)
			(xy 349.395589 -53.314851) (xy 349.340152 -53.320951) (xy 349.284418 -53.318914) (xy 349.229575 -53.308784)
			(xy 349.176791 -53.290777) (xy 349.127191 -53.265276) (xy 349.081833 -53.232825) (xy 349.041684 -53.194116)
			(xy 349.007598 -53.149973) (xy 348.980302 -53.101338) (xy 348.960379 -53.049247) (xy 348.948253 -52.99481)
			(xy 348.944182 -52.939188) (xy 348.353888 -52.939188) (xy 348.353888 -57.112408) (xy 348.430596 -57.49671)
			(xy 348.437708 -57.505854) (xy 348.45568 -57.530398) (xy 348.484242 -57.584102) (xy 348.503712 -57.64173)
			(xy 348.513571 -57.701754) (xy 348.514162 -57.732168) (xy 348.513757 -57.756195) (xy 348.507518 -57.803844)
			(xy 348.501716 -57.827164) (xy 348.498922 -57.838594) (xy 348.610174 -58.396378) (xy 348.859348 -58.645552)
			(xy 353.787964 -58.645552)
		)
		(stroke
			(width 0)
			(type solid)
		)
		(fill yes)
		(layer "In2.Cu")
		(net "P1V8_PCH_PLL_AUX")
	)
	(gr_poly
		(pts
			(xy 280.52268 -77.993748) (xy 280.52268 -73.19518) (xy 280.77414 -72.94372) (xy 280.77414 -63.36538)
			(xy 280.126186 -62.717426) (xy 278.818594 -62.717426) (xy 278.600916 -62.499748) (xy 275.811488 -62.499748)
			(xy 275.796031 -62.500281) (xy 275.766529 -62.509518) (xy 275.741151 -62.52717) (xy 275.722227 -62.551614)
			(xy 275.711497 -62.580606) (xy 275.710142 -62.596014) (xy 275.708083 -62.624923) (xy 275.696324 -62.681671)
			(xy 275.676115 -62.735987) (xy 275.647923 -62.786622) (xy 275.612397 -62.832409) (xy 275.570353 -62.872296)
			(xy 275.522759 -62.905364) (xy 275.470712 -62.930853) (xy 275.415407 -62.948175) (xy 275.358119 -62.956933)
			(xy 275.329142 -62.957456) (xy 275.300228 -62.956918) (xy 275.243062 -62.948182) (xy 275.18787 -62.930921)
			(xy 275.135915 -62.905528) (xy 275.088386 -62.872586) (xy 275.046373 -62.832848) (xy 275.028152 -62.81039)
			(xy 275.018255 -62.798585) (xy 274.992931 -62.781066) (xy 274.963538 -62.77189) (xy 274.932746 -62.77189)
			(xy 274.903353 -62.781066) (xy 274.878029 -62.798585) (xy 274.868132 -62.81039) (xy 274.851379 -62.831173)
			(xy 274.813025 -62.868303) (xy 274.769871 -62.899725) (xy 274.722757 -62.924824) (xy 274.672605 -62.94311)
			(xy 274.620394 -62.954227) (xy 274.567142 -62.957957) (xy 274.51389 -62.954227) (xy 274.461679 -62.94311)
			(xy 274.411527 -62.924824) (xy 274.364413 -62.899725) (xy 274.321259 -62.868303) (xy 274.282905 -62.831173)
			(xy 274.266152 -62.81039) (xy 274.256255 -62.798585) (xy 274.230931 -62.781066) (xy 274.201538 -62.77189)
			(xy 274.170746 -62.77189) (xy 274.141353 -62.781066) (xy 274.116029 -62.798585) (xy 274.106132 -62.81039)
			(xy 274.087942 -62.832874) (xy 274.045925 -62.872613) (xy 273.99839 -62.905553) (xy 273.946428 -62.930939)
			(xy 273.891229 -62.948191) (xy 273.834058 -62.956913) (xy 273.805142 -62.957456) (xy 273.776169 -62.956913)
			(xy 273.71889 -62.948142) (xy 273.663596 -62.930812) (xy 273.611559 -62.905319) (xy 273.563974 -62.872251)
			(xy 273.521937 -62.832368) (xy 273.486414 -62.786588) (xy 273.458222 -62.735962) (xy 273.438008 -62.681655)
			(xy 273.426239 -62.624917) (xy 273.424142 -62.596014) (xy 273.422785 -62.580613) (xy 273.41201 -62.551651)
			(xy 273.39308 -62.527226) (xy 273.367721 -62.509567) (xy 273.338246 -62.500285) (xy 273.322796 -62.499748)
			(xy 264.358882 -62.499748) (xy 262.938504 -63.920313) (xy 278.713942 -63.920313) (xy 278.713942 -63.835591)
			(xy 278.721995 -63.751254) (xy 278.738029 -63.668064) (xy 278.761897 -63.586774) (xy 278.793385 -63.508122)
			(xy 278.832207 -63.432819) (xy 278.87801 -63.361547) (xy 278.930381 -63.294951) (xy 278.988846 -63.233636)
			(xy 279.052874 -63.178155) (xy 279.121886 -63.129012) (xy 279.195256 -63.086652) (xy 279.272321 -63.051457)
			(xy 279.352383 -63.023748) (xy 279.434716 -63.003774) (xy 279.518575 -62.991717) (xy 279.6032 -62.987686)
			(xy 279.687825 -62.991717) (xy 279.771684 -63.003774) (xy 279.854017 -63.023748) (xy 279.934079 -63.051457)
			(xy 280.011144 -63.086652) (xy 280.084514 -63.129012) (xy 280.153526 -63.178155) (xy 280.217554 -63.233636)
			(xy 280.276019 -63.294951) (xy 280.32839 -63.361547) (xy 280.374193 -63.432819) (xy 280.413015 -63.508122)
			(xy 280.444503 -63.586774) (xy 280.468371 -63.668064) (xy 280.484405 -63.751254) (xy 280.492458 -63.835591)
			(xy 280.492962 -63.877952) (xy 280.492458 -63.920313) (xy 280.484405 -64.00465) (xy 280.468371 -64.08784)
			(xy 280.444503 -64.16913) (xy 280.413015 -64.247782) (xy 280.374193 -64.323085) (xy 280.32839 -64.394357)
			(xy 280.276019 -64.460953) (xy 280.217554 -64.522268) (xy 280.153526 -64.577749) (xy 280.084514 -64.626892)
			(xy 280.011144 -64.669252) (xy 279.934079 -64.704447) (xy 279.854017 -64.732156) (xy 279.771684 -64.75213)
			(xy 279.687825 -64.764187) (xy 279.6032 -64.768219) (xy 279.518575 -64.764187) (xy 279.434716 -64.75213)
			(xy 279.352383 -64.732156) (xy 279.272321 -64.704447) (xy 279.195256 -64.669252) (xy 279.121886 -64.626892)
			(xy 279.052874 -64.577749) (xy 278.988846 -64.522268) (xy 278.930381 -64.460953) (xy 278.87801 -64.394357)
			(xy 278.832207 -64.323085) (xy 278.793385 -64.247782) (xy 278.761897 -64.16913) (xy 278.738029 -64.08784)
			(xy 278.721995 -64.00465) (xy 278.713942 -63.920313) (xy 262.938504 -63.920313) (xy 262.433816 -64.425068)
			(xy 262.433816 -66.3448) (xy 263.172954 -66.3448) (xy 263.177025 -66.289178) (xy 263.189151 -66.234741)
			(xy 263.209074 -66.18265) (xy 263.23637 -66.134015) (xy 263.270456 -66.089872) (xy 263.310605 -66.051163)
			(xy 263.355963 -66.018712) (xy 263.405563 -65.993211) (xy 263.458347 -65.975204) (xy 263.51319 -65.965074)
			(xy 263.568924 -65.963037) (xy 263.624361 -65.969137) (xy 263.678318 -65.983243) (xy 263.729647 -66.005055)
			(xy 263.777253 -66.034109) (xy 263.820121 -66.069784) (xy 263.857338 -66.111321) (xy 263.888111 -66.157834)
			(xy 263.911783 -66.208331) (xy 263.927851 -66.261738) (xy 263.930708 -66.281153) (xy 273.401246 -66.281153)
			(xy 273.401246 -66.226647) (xy 273.409003 -66.172697) (xy 273.424358 -66.120399) (xy 273.447 -66.070819)
			(xy 273.476467 -66.024965) (xy 273.512159 -65.983772) (xy 273.553351 -65.948078) (xy 273.599203 -65.918608)
			(xy 273.648782 -65.895964) (xy 273.701079 -65.880606) (xy 273.755029 -65.872847) (xy 273.782282 -65.87236)
			(xy 273.8112 -65.872868) (xy 273.868372 -65.881596) (xy 273.923572 -65.898855) (xy 273.975534 -65.924248)
			(xy 274.023068 -65.957194) (xy 274.065083 -65.996939) (xy 274.083272 -66.019426) (xy 274.093169 -66.031231)
			(xy 274.118493 -66.04875) (xy 274.147886 -66.057926) (xy 274.178678 -66.057926) (xy 274.208071 -66.04875)
			(xy 274.233395 -66.031231) (xy 274.243292 -66.019426) (xy 274.260045 -65.998643) (xy 274.298399 -65.961513)
			(xy 274.341553 -65.930091) (xy 274.388667 -65.904992) (xy 274.438819 -65.886706) (xy 274.49103 -65.875589)
			(xy 274.544282 -65.871859) (xy 274.597534 -65.875589) (xy 274.649745 -65.886706) (xy 274.699897 -65.904992)
			(xy 274.747011 -65.930091) (xy 274.790165 -65.961513) (xy 274.828519 -65.998643) (xy 274.845272 -66.019426)
			(xy 274.855169 -66.031231) (xy 274.880493 -66.04875) (xy 274.909886 -66.057926) (xy 274.940678 -66.057926)
			(xy 274.970071 -66.04875) (xy 274.995395 -66.031231) (xy 275.005292 -66.019426) (xy 275.023494 -65.996952)
			(xy 275.065511 -65.957215) (xy 275.113043 -65.924274) (xy 275.165002 -65.898884) (xy 275.220198 -65.881626)
			(xy 275.277367 -65.872896) (xy 275.306282 -65.87236) (xy 275.333533 -65.872886) (xy 275.368752 -65.877948)
			(xy 278.687535 -65.877948) (xy 278.691558 -65.792204) (xy 278.703593 -65.707213) (xy 278.723534 -65.623723)
			(xy 278.751205 -65.542466) (xy 278.786364 -65.464158) (xy 278.828701 -65.389487) (xy 278.877844 -65.319108)
			(xy 278.933362 -65.25364) (xy 278.994766 -65.193659) (xy 279.061518 -65.139691) (xy 279.133029 -65.092211)
			(xy 279.208673 -65.051636) (xy 279.287784 -65.018323) (xy 279.369666 -64.992564) (xy 279.453601 -64.974586)
			(xy 279.538851 -64.964546) (xy 279.624666 -64.962534) (xy 279.710292 -64.968567) (xy 279.794977 -64.982591)
			(xy 279.877977 -65.004483) (xy 279.958562 -65.034052) (xy 280.036025 -65.071036) (xy 280.109683 -65.115112)
			(xy 280.178891 -65.165892) (xy 280.243039 -65.222929) (xy 280.301565 -65.285723) (xy 280.353953 -65.353721)
			(xy 280.399743 -65.426326) (xy 280.438534 -65.5029) (xy 280.469983 -65.58277) (xy 280.493816 -65.665234)
			(xy 280.509821 -65.749567) (xy 280.517859 -65.835029) (xy 280.518362 -65.877948) (xy 280.517859 -65.920867)
			(xy 280.509821 -66.006329) (xy 280.493816 -66.090662) (xy 280.469983 -66.173126) (xy 280.438534 -66.252996)
			(xy 280.399743 -66.32957) (xy 280.353953 -66.402175) (xy 280.301565 -66.470173) (xy 280.243039 -66.532967)
			(xy 280.178891 -66.590004) (xy 280.109683 -66.640784) (xy 280.036025 -66.68486) (xy 279.958562 -66.721844)
			(xy 279.877977 -66.751413) (xy 279.794977 -66.773305) (xy 279.710292 -66.787329) (xy 279.624666 -66.793362)
			(xy 279.538851 -66.79135) (xy 279.453601 -66.78131) (xy 279.369666 -66.763332) (xy 279.287784 -66.737573)
			(xy 279.208673 -66.70426) (xy 279.133029 -66.663685) (xy 279.061518 -66.616205) (xy 278.994766 -66.562237)
			(xy 278.933362 -66.502256) (xy 278.877844 -66.436788) (xy 278.828701 -66.366409) (xy 278.786364 -66.291738)
			(xy 278.751205 -66.21343) (xy 278.723534 -66.132173) (xy 278.703593 -66.048683) (xy 278.691558 -65.963692)
			(xy 278.687535 -65.877948) (xy 275.368752 -65.877948) (xy 275.387482 -65.88064) (xy 275.439777 -65.895993)
			(xy 275.489356 -65.918633) (xy 275.535207 -65.948098) (xy 275.576399 -65.983789) (xy 275.612091 -66.024978)
			(xy 275.641558 -66.070829) (xy 275.6642 -66.120406) (xy 275.679556 -66.172701) (xy 275.687313 -66.226649)
			(xy 275.687313 -66.281151) (xy 275.679556 -66.335099) (xy 275.6642 -66.387394) (xy 275.641558 -66.436971)
			(xy 275.612091 -66.482822) (xy 275.576399 -66.524011) (xy 275.535207 -66.559702) (xy 275.489356 -66.589167)
			(xy 275.439777 -66.611807) (xy 275.387482 -66.62716) (xy 275.333533 -66.634914) (xy 275.306282 -66.635376)
			(xy 275.277367 -66.634808) (xy 275.220197 -66.626091) (xy 275.164999 -66.608843) (xy 275.113037 -66.583461)
			(xy 275.065502 -66.550526) (xy 275.023483 -66.510792) (xy 275.005292 -66.48831) (xy 274.995395 -66.476505)
			(xy 274.970071 -66.458986) (xy 274.940678 -66.44981) (xy 274.909886 -66.44981) (xy 274.880493 -66.458986)
			(xy 274.855169 -66.476505) (xy 274.845272 -66.48831) (xy 274.828519 -66.509093) (xy 274.790165 -66.546223)
			(xy 274.747011 -66.577645) (xy 274.699897 -66.602744) (xy 274.649745 -66.62103) (xy 274.597534 -66.632147)
			(xy 274.544282 -66.635877) (xy 274.49103 -66.632147) (xy 274.438819 -66.62103) (xy 274.388667 -66.602744)
			(xy 274.341553 -66.577645) (xy 274.298399 -66.546223) (xy 274.260045 -66.509093) (xy 274.243292 -66.48831)
			(xy 274.233395 -66.476505) (xy 274.208071 -66.458986) (xy 274.178678 -66.44981) (xy 274.147886 -66.44981)
			(xy 274.118493 -66.458986) (xy 274.093169 -66.476505) (xy 274.083272 -66.48831) (xy 274.065099 -66.510809)
			(xy 274.023075 -66.550543) (xy 273.975537 -66.58348) (xy 273.923572 -66.608865) (xy 273.868371 -66.626118)
			(xy 273.811199 -66.634843) (xy 273.782282 -66.635376) (xy 273.755029 -66.634953) (xy 273.701079 -66.627194)
			(xy 273.648782 -66.611836) (xy 273.599203 -66.589192) (xy 273.553351 -66.559722) (xy 273.512159 -66.524028)
			(xy 273.476467 -66.482835) (xy 273.447 -66.436981) (xy 273.424358 -66.387401) (xy 273.409003 -66.335103)
			(xy 273.401246 -66.281153) (xy 263.930708 -66.281153) (xy 263.935971 -66.316914) (xy 263.93648 -66.3448)
			(xy 263.935971 -66.372686) (xy 263.927851 -66.427862) (xy 263.911783 -66.481269) (xy 263.888111 -66.531766)
			(xy 263.857338 -66.578279) (xy 263.820121 -66.619816) (xy 263.777253 -66.655491) (xy 263.729647 -66.684545)
			(xy 263.678318 -66.706357) (xy 263.624361 -66.720463) (xy 263.568924 -66.726563) (xy 263.51319 -66.724526)
			(xy 263.458347 -66.714396) (xy 263.405563 -66.696389) (xy 263.355963 -66.670888) (xy 263.310605 -66.638437)
			(xy 263.270456 -66.599728) (xy 263.23637 -66.555585) (xy 263.209074 -66.50695) (xy 263.189151 -66.454859)
			(xy 263.177025 -66.400422) (xy 263.172954 -66.3448) (xy 262.433816 -66.3448) (xy 262.433816 -67.08902)
			(xy 262.433562 -67.101974) (xy 262.433562 -67.247008) (xy 262.3312 -67.34937) (xy 262.312658 -67.367912)
			(xy 262.259318 -67.421252) (xy 273.131024 -67.421252) (xy 273.135095 -67.36563) (xy 273.147221 -67.311193)
			(xy 273.167144 -67.259102) (xy 273.19444 -67.210467) (xy 273.228526 -67.166324) (xy 273.268675 -67.127615)
			(xy 273.314033 -67.095164) (xy 273.363633 -67.069663) (xy 273.416417 -67.051656) (xy 273.47126 -67.041526)
			(xy 273.526994 -67.039489) (xy 273.582431 -67.045589) (xy 273.636388 -67.059695) (xy 273.687717 -67.081507)
			(xy 273.735323 -67.110561) (xy 273.778191 -67.146236) (xy 273.815408 -67.187773) (xy 273.846181 -67.234286)
			(xy 273.869853 -67.284783) (xy 273.885921 -67.33819) (xy 273.894041 -67.393366) (xy 273.89455 -67.421252)
			(xy 274.020024 -67.421252) (xy 274.024095 -67.36563) (xy 274.036221 -67.311193) (xy 274.056144 -67.259102)
			(xy 274.08344 -67.210467) (xy 274.117526 -67.166324) (xy 274.157675 -67.127615) (xy 274.203033 -67.095164)
			(xy 274.252633 -67.069663) (xy 274.305417 -67.051656) (xy 274.36026 -67.041526) (xy 274.415994 -67.039489)
			(xy 274.471431 -67.045589) (xy 274.525388 -67.059695) (xy 274.576717 -67.081507) (xy 274.624323 -67.110561)
			(xy 274.667191 -67.146236) (xy 274.704408 -67.187773) (xy 274.735181 -67.234286) (xy 274.758853 -67.284783)
			(xy 274.774921 -67.33819) (xy 274.783041 -67.393366) (xy 274.78355 -67.421252) (xy 274.909024 -67.421252)
			(xy 274.913095 -67.36563) (xy 274.925221 -67.311193) (xy 274.945144 -67.259102) (xy 274.97244 -67.210467)
			(xy 275.006526 -67.166324) (xy 275.046675 -67.127615) (xy 275.092033 -67.095164) (xy 275.141633 -67.069663)
			(xy 275.194417 -67.051656) (xy 275.24926 -67.041526) (xy 275.304994 -67.039489) (xy 275.360431 -67.045589)
			(xy 275.414388 -67.059695) (xy 275.465717 -67.081507) (xy 275.513323 -67.110561) (xy 275.556191 -67.146236)
			(xy 275.593408 -67.187773) (xy 275.624181 -67.234286) (xy 275.647853 -67.284783) (xy 275.663921 -67.33819)
			(xy 275.672041 -67.393366) (xy 275.67255 -67.421252) (xy 275.672041 -67.449138) (xy 275.663921 -67.504314)
			(xy 275.647853 -67.557721) (xy 275.624181 -67.608218) (xy 275.593408 -67.654731) (xy 275.556191 -67.696268)
			(xy 275.513323 -67.731943) (xy 275.465717 -67.760997) (xy 275.414388 -67.782809) (xy 275.360431 -67.796915)
			(xy 275.304994 -67.803015) (xy 275.24926 -67.800978) (xy 275.194417 -67.790848) (xy 275.141633 -67.772841)
			(xy 275.092033 -67.74734) (xy 275.046675 -67.714889) (xy 275.006526 -67.67618) (xy 274.97244 -67.632037)
			(xy 274.945144 -67.583402) (xy 274.925221 -67.531311) (xy 274.913095 -67.476874) (xy 274.909024 -67.421252)
			(xy 274.78355 -67.421252) (xy 274.783041 -67.449138) (xy 274.774921 -67.504314) (xy 274.758853 -67.557721)
			(xy 274.735181 -67.608218) (xy 274.704408 -67.654731) (xy 274.667191 -67.696268) (xy 274.624323 -67.731943)
			(xy 274.576717 -67.760997) (xy 274.525388 -67.782809) (xy 274.471431 -67.796915) (xy 274.415994 -67.803015)
			(xy 274.36026 -67.800978) (xy 274.305417 -67.790848) (xy 274.252633 -67.772841) (xy 274.203033 -67.74734)
			(xy 274.157675 -67.714889) (xy 274.117526 -67.67618) (xy 274.08344 -67.632037) (xy 274.056144 -67.583402)
			(xy 274.036221 -67.531311) (xy 274.024095 -67.476874) (xy 274.020024 -67.421252) (xy 273.89455 -67.421252)
			(xy 273.894041 -67.449138) (xy 273.885921 -67.504314) (xy 273.869853 -67.557721) (xy 273.846181 -67.608218)
			(xy 273.815408 -67.654731) (xy 273.778191 -67.696268) (xy 273.735323 -67.731943) (xy 273.687717 -67.760997)
			(xy 273.636388 -67.782809) (xy 273.582431 -67.796915) (xy 273.526994 -67.803015) (xy 273.47126 -67.800978)
			(xy 273.416417 -67.790848) (xy 273.363633 -67.772841) (xy 273.314033 -67.74734) (xy 273.268675 -67.714889)
			(xy 273.228526 -67.67618) (xy 273.19444 -67.632037) (xy 273.167144 -67.583402) (xy 273.147221 -67.531311)
			(xy 273.135095 -67.476874) (xy 273.131024 -67.421252) (xy 262.259318 -67.421252) (xy 262.210296 -67.470274)
			(xy 262.065262 -67.470274) (xy 262.052308 -67.470528) (xy 262.039354 -67.470274) (xy 261.89432 -67.470274)
			(xy 261.791958 -67.367912) (xy 261.773416 -67.34937) (xy 261.671054 -67.247008) (xy 261.671054 -67.101974)
			(xy 261.6708 -67.08902) (xy 261.6708 -64.26708) (xy 261.671054 -64.254126) (xy 261.671054 -64.109092)
			(xy 261.773416 -64.006984) (xy 261.773924 -64.006222) (xy 261.78256 -63.997332) (xy 263.106916 -62.67323)
			(xy 263.117142 -62.662253) (xy 263.131277 -62.635808) (xy 263.137124 -62.606398) (xy 263.13418 -62.576558)
			(xy 263.122697 -62.548858) (xy 263.103666 -62.525686) (xy 263.078726 -62.509038) (xy 263.050027 -62.50035)
			(xy 263.035034 -62.499748) (xy 256.304288 -62.499748) (xy 256.304288 -64.607948) (xy 256.303773 -64.63293)
			(xy 256.295917 -64.682275) (xy 256.280451 -64.729786) (xy 256.257755 -64.7743) (xy 256.228387 -64.814724)
			(xy 256.21107 -64.832738) (xy 252.61189 -68.431918) (xy 252.593905 -68.449273) (xy 252.554074 -68.478252)
			(xy 273.901646 -68.478252) (xy 273.901646 -68.423748) (xy 273.909402 -68.369799) (xy 273.924756 -68.317503)
			(xy 273.947397 -68.267924) (xy 273.976862 -68.222072) (xy 274.012552 -68.180879) (xy 274.053741 -68.145185)
			(xy 274.099591 -68.115715) (xy 274.149168 -68.09307) (xy 274.201462 -68.07771) (xy 274.25541 -68.069948)
			(xy 274.282662 -68.06946) (xy 274.311579 -68.069983) (xy 274.368751 -68.078708) (xy 274.423951 -68.095963)
			(xy 274.475913 -68.121354) (xy 274.523447 -68.154298) (xy 274.565463 -68.19404) (xy 274.583652 -68.216526)
			(xy 274.593549 -68.228331) (xy 274.618873 -68.24585) (xy 274.648266 -68.255026) (xy 274.679058 -68.255026)
			(xy 274.708451 -68.24585) (xy 274.733775 -68.228331) (xy 274.743672 -68.216526) (xy 274.761885 -68.194061)
			(xy 274.8039 -68.154324) (xy 274.85143 -68.121382) (xy 274.903387 -68.09599) (xy 274.958581 -68.07873)
			(xy 275.015747 -68.069997) (xy 275.044662 -68.06946) (xy 275.071914 -68.069985) (xy 275.125865 -68.077737)
			(xy 275.178163 -68.093088) (xy 275.227744 -68.115726) (xy 275.273598 -68.145191) (xy 275.314791 -68.180882)
			(xy 275.350486 -68.222072) (xy 275.379955 -68.267923) (xy 275.402599 -68.317501) (xy 275.417955 -68.369798)
			(xy 275.425713 -68.423748) (xy 275.425713 -68.478252) (xy 275.417955 -68.532202) (xy 275.402599 -68.584499)
			(xy 275.379955 -68.634077) (xy 275.350486 -68.679928) (xy 275.314791 -68.721118) (xy 275.273598 -68.756809)
			(xy 275.227744 -68.786274) (xy 275.178163 -68.808912) (xy 275.125865 -68.824263) (xy 275.071914 -68.832015)
			(xy 275.044662 -68.832476) (xy 275.015746 -68.831922) (xy 274.958576 -68.823202) (xy 274.903378 -68.805952)
			(xy 274.851416 -68.780567) (xy 274.803881 -68.747629) (xy 274.761863 -68.707893) (xy 274.743672 -68.68541)
			(xy 274.733775 -68.673605) (xy 274.708451 -68.656086) (xy 274.679058 -68.64691) (xy 274.648266 -68.64691)
			(xy 274.618873 -68.656086) (xy 274.593549 -68.673605) (xy 274.583652 -68.68541) (xy 274.565434 -68.707871)
			(xy 274.52342 -68.747607) (xy 274.47589 -68.780548) (xy 274.423934 -68.80594) (xy 274.368742 -68.823202)
			(xy 274.311576 -68.831937) (xy 274.282662 -68.832476) (xy 274.25541 -68.832052) (xy 274.201462 -68.82429)
			(xy 274.149168 -68.80893) (xy 274.099591 -68.786285) (xy 274.053741 -68.756815) (xy 274.012552 -68.721121)
			(xy 273.976862 -68.679928) (xy 273.947397 -68.634076) (xy 273.924756 -68.584497) (xy 273.909402 -68.532201)
			(xy 273.901646 -68.478252) (xy 252.554074 -68.478252) (xy 252.553493 -68.478675) (xy 252.508974 -68.501386)
			(xy 252.461449 -68.516846) (xy 252.412088 -68.524672) (xy 252.3871 -68.525136) (xy 249.504454 -68.525136)
			(xy 249.480932 -68.540152) (xy 249.430424 -68.563884) (xy 249.376997 -68.579997) (xy 249.32179 -68.588147)
			(xy 249.293888 -68.588636) (xy 249.29338 -68.588636) (xy 249.266128 -68.588149) (xy 249.212178 -68.580389)
			(xy 249.159882 -68.565031) (xy 249.110304 -68.542387) (xy 249.064452 -68.512918) (xy 249.023262 -68.477224)
			(xy 248.98757 -68.436032) (xy 248.958103 -68.390179) (xy 248.935462 -68.340599) (xy 248.920106 -68.288302)
			(xy 248.91235 -68.234352) (xy 248.91235 -68.179848) (xy 248.920106 -68.125898) (xy 248.935462 -68.073601)
			(xy 248.958103 -68.024021) (xy 248.98757 -67.978168) (xy 249.023262 -67.936976) (xy 249.064452 -67.901282)
			(xy 249.110304 -67.871813) (xy 249.159882 -67.849169) (xy 249.212178 -67.833811) (xy 249.266128 -67.826051)
			(xy 249.29338 -67.82562) (xy 249.293888 -67.82562) (xy 249.321787 -67.82615) (xy 249.376985 -67.834312)
			(xy 249.430408 -67.85042) (xy 249.480918 -67.874131) (xy 249.504454 -67.88912) (xy 252.255528 -67.88912)
			(xy 255.668272 -64.476376) (xy 255.668272 -62.499748) (xy 253.14148 -62.499748) (xy 246.61368 -69.027548)
			(xy 246.61368 -69.562748) (xy 272.770626 -69.562748) (xy 272.770626 -69.508252) (xy 272.778382 -69.454311)
			(xy 272.793735 -69.402023) (xy 272.816373 -69.352452) (xy 272.845836 -69.306608) (xy 272.881523 -69.265423)
			(xy 272.922708 -69.229736) (xy 272.968552 -69.200273) (xy 273.018123 -69.177635) (xy 273.070411 -69.162282)
			(xy 273.124352 -69.154526) (xy 273.1516 -69.15404) (xy 273.180518 -69.154543) (xy 273.23769 -69.163273)
			(xy 273.29289 -69.180533) (xy 273.344852 -69.205928) (xy 273.392385 -69.238875) (xy 273.434401 -69.278619)
			(xy 273.45259 -69.301106) (xy 273.462487 -69.312911) (xy 273.487811 -69.33043) (xy 273.517204 -69.339606)
			(xy 273.547996 -69.339606) (xy 273.577389 -69.33043) (xy 273.602713 -69.312911) (xy 273.61261 -69.301106)
			(xy 273.629363 -69.280323) (xy 273.667717 -69.243193) (xy 273.710871 -69.211771) (xy 273.757985 -69.186672)
			(xy 273.808137 -69.168386) (xy 273.860348 -69.157269) (xy 273.9136 -69.153539) (xy 273.966852 -69.157269)
			(xy 274.019063 -69.168386) (xy 274.069215 -69.186672) (xy 274.116329 -69.211771) (xy 274.159483 -69.243193)
			(xy 274.197837 -69.280323) (xy 274.21459 -69.301106) (xy 274.224487 -69.312911) (xy 274.249811 -69.33043)
			(xy 274.279204 -69.339606) (xy 274.309996 -69.339606) (xy 274.339389 -69.33043) (xy 274.364713 -69.312911)
			(xy 274.37461 -69.301106) (xy 274.391363 -69.280323) (xy 274.429717 -69.243193) (xy 274.472871 -69.211771)
			(xy 274.519985 -69.186672) (xy 274.570137 -69.168386) (xy 274.622348 -69.157269) (xy 274.6756 -69.153539)
			(xy 274.728852 -69.157269) (xy 274.781063 -69.168386) (xy 274.831215 -69.186672) (xy 274.878329 -69.211771)
			(xy 274.921483 -69.243193) (xy 274.959837 -69.280323) (xy 274.97659 -69.301106) (xy 274.986487 -69.312911)
			(xy 275.011811 -69.33043) (xy 275.041204 -69.339606) (xy 275.071996 -69.339606) (xy 275.101389 -69.33043)
			(xy 275.126713 -69.312911) (xy 275.13661 -69.301106) (xy 275.153363 -69.280323) (xy 275.191717 -69.243193)
			(xy 275.234871 -69.211771) (xy 275.281985 -69.186672) (xy 275.332137 -69.168386) (xy 275.384348 -69.157269)
			(xy 275.4376 -69.153539) (xy 275.490852 -69.157269) (xy 275.543063 -69.168386) (xy 275.593215 -69.186672)
			(xy 275.640329 -69.211771) (xy 275.683483 -69.243193) (xy 275.721837 -69.280323) (xy 275.73859 -69.301106)
			(xy 275.748487 -69.312911) (xy 275.773811 -69.33043) (xy 275.803204 -69.339606) (xy 275.833996 -69.339606)
			(xy 275.863389 -69.33043) (xy 275.888713 -69.312911) (xy 275.89861 -69.301106) (xy 275.916797 -69.278619)
			(xy 275.958817 -69.238884) (xy 276.006353 -69.205945) (xy 276.058315 -69.180557) (xy 276.113514 -69.163302)
			(xy 276.170684 -69.154574) (xy 276.1996 -69.15404) (xy 276.226855 -69.15443) (xy 276.280809 -69.162187)
			(xy 276.333111 -69.177544) (xy 276.382694 -69.200188) (xy 276.42855 -69.229658) (xy 276.469746 -69.265354)
			(xy 276.505442 -69.30655) (xy 276.534912 -69.352406) (xy 276.557556 -69.401989) (xy 276.572913 -69.454291)
			(xy 276.58067 -69.508245) (xy 276.58067 -69.562755) (xy 276.572913 -69.616709) (xy 276.557556 -69.669011)
			(xy 276.534912 -69.718594) (xy 276.505442 -69.76445) (xy 276.469746 -69.805646) (xy 276.42855 -69.841342)
			(xy 276.382694 -69.870812) (xy 276.333111 -69.893456) (xy 276.280809 -69.908813) (xy 276.226855 -69.91657)
			(xy 276.1996 -69.917056) (xy 276.170682 -69.916554) (xy 276.11351 -69.907824) (xy 276.05831 -69.890564)
			(xy 276.006348 -69.865169) (xy 275.958814 -69.832222) (xy 275.916799 -69.792477) (xy 275.89861 -69.76999)
			(xy 275.888713 -69.758185) (xy 275.863389 -69.740666) (xy 275.833996 -69.73149) (xy 275.803204 -69.73149)
			(xy 275.773811 -69.740666) (xy 275.748487 -69.758185) (xy 275.73859 -69.76999) (xy 275.721837 -69.790773)
			(xy 275.683483 -69.827903) (xy 275.640329 -69.859325) (xy 275.593215 -69.884424) (xy 275.543063 -69.90271)
			(xy 275.490852 -69.913827) (xy 275.4376 -69.917557) (xy 275.384348 -69.913827) (xy 275.332137 -69.90271)
			(xy 275.281985 -69.884424) (xy 275.234871 -69.859325) (xy 275.191717 -69.827903) (xy 275.153363 -69.790773)
			(xy 275.13661 -69.76999) (xy 275.126713 -69.758185) (xy 275.101389 -69.740666) (xy 275.071996 -69.73149)
			(xy 275.041204 -69.73149) (xy 275.011811 -69.740666) (xy 274.986487 -69.758185) (xy 274.97659 -69.76999)
			(xy 274.959837 -69.790773) (xy 274.921483 -69.827903) (xy 274.878329 -69.859325) (xy 274.831215 -69.884424)
			(xy 274.781063 -69.90271) (xy 274.728852 -69.913827) (xy 274.6756 -69.917557) (xy 274.622348 -69.913827)
			(xy 274.570137 -69.90271) (xy 274.519985 -69.884424) (xy 274.472871 -69.859325) (xy 274.429717 -69.827903)
			(xy 274.391363 -69.790773) (xy 274.37461 -69.76999) (xy 274.364713 -69.758185) (xy 274.339389 -69.740666)
			(xy 274.309996 -69.73149) (xy 274.279204 -69.73149) (xy 274.249811 -69.740666) (xy 274.224487 -69.758185)
			(xy 274.21459 -69.76999) (xy 274.197837 -69.790773) (xy 274.159483 -69.827903) (xy 274.116329 -69.859325)
			(xy 274.069215 -69.884424) (xy 274.019063 -69.90271) (xy 273.966852 -69.913827) (xy 273.9136 -69.917557)
			(xy 273.860348 -69.913827) (xy 273.808137 -69.90271) (xy 273.757985 -69.884424) (xy 273.710871 -69.859325)
			(xy 273.667717 -69.827903) (xy 273.629363 -69.790773) (xy 273.61261 -69.76999) (xy 273.602713 -69.758185)
			(xy 273.577389 -69.740666) (xy 273.547996 -69.73149) (xy 273.517204 -69.73149) (xy 273.487811 -69.740666)
			(xy 273.462487 -69.758185) (xy 273.45259 -69.76999) (xy 273.434402 -69.792476) (xy 273.392382 -69.832212)
			(xy 273.344847 -69.865151) (xy 273.292885 -69.890539) (xy 273.237686 -69.907794) (xy 273.180516 -69.916522)
			(xy 273.1516 -69.917056) (xy 273.124352 -69.916474) (xy 273.070411 -69.908718) (xy 273.018123 -69.893365)
			(xy 272.968552 -69.870727) (xy 272.922708 -69.841264) (xy 272.881523 -69.805577) (xy 272.845836 -69.764392)
			(xy 272.816373 -69.718548) (xy 272.793735 -69.668977) (xy 272.778382 -69.616689) (xy 272.770626 -69.562748)
			(xy 246.61368 -69.562748) (xy 246.61368 -71.652384) (xy 247.39854 -71.652384) (xy 247.398982 -71.625711)
			(xy 247.406426 -71.572887) (xy 247.421154 -71.521615) (xy 247.442878 -71.472893) (xy 247.471175 -71.42767)
			(xy 247.505494 -71.386829) (xy 247.525032 -71.368666) (xy 247.535357 -71.35882) (xy 247.550505 -71.334654)
			(xy 247.558383 -71.307243) (xy 247.558378 -71.278722) (xy 247.550491 -71.251314) (xy 247.535335 -71.227153)
			(xy 247.525032 -71.217282) (xy 247.505486 -71.199126) (xy 247.471158 -71.15829) (xy 247.442856 -71.113068)
			(xy 247.421133 -71.064343) (xy 247.406413 -71.013066) (xy 247.398983 -70.960238) (xy 247.39854 -70.933564)
			(xy 247.398922 -70.906308) (xy 247.406685 -70.852352) (xy 247.422048 -70.800049) (xy 247.444698 -70.750466)
			(xy 247.474174 -70.70461) (xy 247.509876 -70.663417) (xy 247.551078 -70.627724) (xy 247.59694 -70.598258)
			(xy 247.646528 -70.575618) (xy 247.698834 -70.560267) (xy 247.752792 -70.552516) (xy 247.780048 -70.552056)
			(xy 247.806286 -70.552464) (xy 247.858265 -70.559667) (xy 247.908765 -70.57393) (xy 247.956831 -70.594984)
			(xy 248.001557 -70.622431) (xy 248.042096 -70.655752) (xy 248.06021 -70.674738) (xy 248.067739 -70.68211)
			(xy 248.087024 -70.690541) (xy 248.108072 -70.690541) (xy 248.127357 -70.68211) (xy 248.134886 -70.674738)
			(xy 248.160032 -70.649846) (xy 248.170378 -70.64002) (xy 248.185524 -70.615848) (xy 248.1934 -70.588432)
			(xy 248.193392 -70.559907) (xy 248.185499 -70.532495) (xy 248.170338 -70.508333) (xy 248.160032 -70.498462)
			(xy 248.140476 -70.480316) (xy 248.106149 -70.439478) (xy 248.077849 -70.394254) (xy 248.056128 -70.345527)
			(xy 248.04141 -70.294248) (xy 248.033982 -70.241419) (xy 248.03354 -70.214744) (xy 248.034026 -70.187493)
			(xy 248.041782 -70.133545) (xy 248.057137 -70.08125) (xy 248.079779 -70.031673) (xy 248.109245 -69.985823)
			(xy 248.144936 -69.944632) (xy 248.186127 -69.908941) (xy 248.231977 -69.879475) (xy 248.281554 -69.856833)
			(xy 248.333849 -69.841478) (xy 248.387797 -69.833722) (xy 248.442299 -69.833722) (xy 248.496247 -69.841478)
			(xy 248.548542 -69.856833) (xy 248.598119 -69.879475) (xy 248.643969 -69.908941) (xy 248.68516 -69.944632)
			(xy 248.720851 -69.985823) (xy 248.750317 -70.031673) (xy 248.772959 -70.08125) (xy 248.776266 -70.092513)
			(xy 278.688542 -70.092513) (xy 278.688542 -70.007791) (xy 278.696595 -69.923454) (xy 278.712629 -69.840264)
			(xy 278.736497 -69.758974) (xy 278.767985 -69.680322) (xy 278.806807 -69.605019) (xy 278.85261 -69.533747)
			(xy 278.904981 -69.467151) (xy 278.963446 -69.405836) (xy 279.027474 -69.350355) (xy 279.096486 -69.301212)
			(xy 279.169856 -69.258852) (xy 279.246921 -69.223657) (xy 279.326983 -69.195948) (xy 279.409316 -69.175974)
			(xy 279.493175 -69.163917) (xy 279.5778 -69.159886) (xy 279.662425 -69.163917) (xy 279.746284 -69.175974)
			(xy 279.828617 -69.195948) (xy 279.908679 -69.223657) (xy 279.985744 -69.258852) (xy 280.059114 -69.301212)
			(xy 280.128126 -69.350355) (xy 280.192154 -69.405836) (xy 280.250619 -69.467151) (xy 280.30299 -69.533747)
			(xy 280.348793 -69.605019) (xy 280.387615 -69.680322) (xy 280.419103 -69.758974) (xy 280.442971 -69.840264)
			(xy 280.459005 -69.923454) (xy 280.467058 -70.007791) (xy 280.467562 -70.050152) (xy 280.467058 -70.092513)
			(xy 280.459005 -70.17685) (xy 280.442971 -70.26004) (xy 280.419103 -70.34133) (xy 280.387615 -70.419982)
			(xy 280.348793 -70.495285) (xy 280.30299 -70.566557) (xy 280.250619 -70.633153) (xy 280.192154 -70.694468)
			(xy 280.128126 -70.749949) (xy 280.059114 -70.799092) (xy 279.985744 -70.841452) (xy 279.908679 -70.876647)
			(xy 279.828617 -70.904356) (xy 279.746284 -70.92433) (xy 279.662425 -70.936387) (xy 279.5778 -70.940419)
			(xy 279.493175 -70.936387) (xy 279.409316 -70.92433) (xy 279.326983 -70.904356) (xy 279.246921 -70.876647)
			(xy 279.169856 -70.841452) (xy 279.096486 -70.799092) (xy 279.027474 -70.749949) (xy 278.963446 -70.694468)
			(xy 278.904981 -70.633153) (xy 278.85261 -70.566557) (xy 278.806807 -70.495285) (xy 278.767985 -70.419982)
			(xy 278.736497 -70.34133) (xy 278.712629 -70.26004) (xy 278.696595 -70.17685) (xy 278.688542 -70.092513)
			(xy 248.776266 -70.092513) (xy 248.788314 -70.133545) (xy 248.79607 -70.187493) (xy 248.796556 -70.214744)
			(xy 248.796067 -70.241415) (xy 248.788632 -70.294237) (xy 248.773914 -70.345509) (xy 248.752199 -70.394231)
			(xy 248.72391 -70.439455) (xy 248.689599 -70.480298) (xy 248.670064 -70.498462) (xy 248.659811 -70.508377)
			(xy 248.644661 -70.532524) (xy 248.636774 -70.559917) (xy 248.636765 -70.588422) (xy 248.644635 -70.61582)
			(xy 248.659771 -70.639975) (xy 248.670064 -70.649846) (xy 248.689565 -70.668046) (xy 248.72388 -70.708882)
			(xy 248.752172 -70.7541) (xy 248.773889 -70.802819) (xy 248.788608 -70.854087) (xy 248.796041 -70.906906)
			(xy 248.796045 -70.960246) (xy 248.788618 -71.013066) (xy 248.773905 -71.064336) (xy 248.752194 -71.113057)
			(xy 248.723908 -71.158279) (xy 248.689599 -71.199119) (xy 248.670064 -71.217282) (xy 248.659791 -71.227178)
			(xy 248.644642 -71.25133) (xy 248.636757 -71.278728) (xy 248.636752 -71.307238) (xy 248.644627 -71.334638)
			(xy 248.659769 -71.358795) (xy 248.670064 -71.368666) (xy 248.689584 -71.386849) (xy 248.723915 -71.427679)
			(xy 248.75222 -71.472895) (xy 248.773947 -71.521615) (xy 248.788673 -71.572887) (xy 248.796109 -71.625712)
			(xy 248.796556 -71.652384) (xy 248.796094 -71.679035) (xy 248.788674 -71.731818) (xy 248.773975 -71.783053)
			(xy 248.763536 -71.807578) (xy 248.757906 -71.821707) (xy 248.754301 -71.85189) (xy 248.759721 -71.8818)
			(xy 248.773687 -71.9088) (xy 248.794967 -71.930506) (xy 248.821683 -71.945005) (xy 248.85148 -71.951017)
			(xy 248.86666 -71.950072) (xy 248.90476 -71.94804) (xy 248.932014 -71.948493) (xy 248.985968 -71.956245)
			(xy 249.038269 -71.971599) (xy 249.087852 -71.99424) (xy 249.133708 -72.023708) (xy 249.16422 -72.050148)
			(xy 278.662135 -72.050148) (xy 278.666158 -71.964404) (xy 278.678193 -71.879413) (xy 278.698134 -71.795923)
			(xy 278.725805 -71.714666) (xy 278.760964 -71.636358) (xy 278.803301 -71.561687) (xy 278.852444 -71.491308)
			(xy 278.907962 -71.42584) (xy 278.969366 -71.365859) (xy 279.036118 -71.311891) (xy 279.107629 -71.264411)
			(xy 279.183273 -71.223836) (xy 279.262384 -71.190523) (xy 279.344266 -71.164764) (xy 279.428201 -71.146786)
			(xy 279.513451 -71.136746) (xy 279.599266 -71.134734) (xy 279.684892 -71.140767) (xy 279.769577 -71.154791)
			(xy 279.852577 -71.176683) (xy 279.933162 -71.206252) (xy 280.010625 -71.243236) (xy 280.084283 -71.287312)
			(xy 280.153491 -71.338092) (xy 280.217639 -71.395129) (xy 280.276165 -71.457923) (xy 280.328553 -71.525921)
			(xy 280.374343 -71.598526) (xy 280.413134 -71.6751) (xy 280.444583 -71.75497) (xy 280.468416 -71.837434)
			(xy 280.484421 -71.921767) (xy 280.492459 -72.007229) (xy 280.492962 -72.050148) (xy 280.492459 -72.093067)
			(xy 280.484421 -72.178529) (xy 280.468416 -72.262862) (xy 280.444583 -72.345326) (xy 280.413134 -72.425196)
			(xy 280.374343 -72.50177) (xy 280.328553 -72.574375) (xy 280.276165 -72.642373) (xy 280.217639 -72.705167)
			(xy 280.153491 -72.762204) (xy 280.084283 -72.812984) (xy 280.010625 -72.85706) (xy 279.933162 -72.894044)
			(xy 279.852577 -72.923613) (xy 279.769577 -72.945505) (xy 279.684892 -72.959529) (xy 279.599266 -72.965562)
			(xy 279.513451 -72.96355) (xy 279.428201 -72.95351) (xy 279.344266 -72.935532) (xy 279.262384 -72.909773)
			(xy 279.183273 -72.87646) (xy 279.107629 -72.835885) (xy 279.036118 -72.788405) (xy 278.969366 -72.734437)
			(xy 278.907962 -72.674456) (xy 278.852444 -72.608988) (xy 278.803301 -72.538609) (xy 278.760964 -72.463938)
			(xy 278.725805 -72.38563) (xy 278.698134 -72.304373) (xy 278.678193 -72.220883) (xy 278.666158 -72.135892)
			(xy 278.662135 -72.050148) (xy 249.16422 -72.050148) (xy 249.174902 -72.059404) (xy 249.210596 -72.100599)
			(xy 249.240064 -72.146455) (xy 249.262704 -72.196039) (xy 249.278056 -72.24834) (xy 249.285808 -72.302294)
			(xy 249.286268 -72.329548) (xy 249.285779 -72.356918) (xy 249.277968 -72.411096) (xy 249.262485 -72.463599)
			(xy 249.239648 -72.513346) (xy 249.209927 -72.559314) (xy 249.192288 -72.580246) (xy 249.183006 -72.591539)
			(xy 249.170836 -72.61811) (xy 249.166673 -72.647036) (xy 249.170856 -72.67596) (xy 249.183045 -72.702522)
			(xy 249.192288 -72.71385) (xy 249.209975 -72.734745) (xy 249.239697 -72.78072) (xy 249.262538 -72.830472)
			(xy 249.27803 -72.88298) (xy 249.285854 -72.937163) (xy 249.285849 -72.991909) (xy 249.278015 -73.046091)
			(xy 249.262513 -73.098596) (xy 249.239662 -73.148344) (xy 249.209931 -73.194313) (xy 249.192288 -73.215246)
			(xy 249.183006 -73.226539) (xy 249.170836 -73.25311) (xy 249.166673 -73.282036) (xy 249.170856 -73.31096)
			(xy 249.183045 -73.337522) (xy 249.192288 -73.34885) (xy 249.209975 -73.369745) (xy 249.239697 -73.41572)
			(xy 249.262538 -73.465472) (xy 249.27803 -73.51798) (xy 249.285854 -73.572163) (xy 249.28585 -73.620122)
			(xy 252.28245 -73.620122) (xy 252.286523 -73.564463) (xy 252.298658 -73.50999) (xy 252.318594 -73.457864)
			(xy 252.345908 -73.409196) (xy 252.380016 -73.365024) (xy 252.420193 -73.326289) (xy 252.465581 -73.293817)
			(xy 252.515213 -73.268299) (xy 252.568033 -73.25028) (xy 252.622912 -73.240143) (xy 252.678683 -73.238105)
			(xy 252.734157 -73.244208) (xy 252.78815 -73.258324) (xy 252.839513 -73.280151) (xy 252.887151 -73.309224)
			(xy 252.930047 -73.344923) (xy 252.967289 -73.386487) (xy 252.998083 -73.433031) (xy 253.021771 -73.483562)
			(xy 253.037201 -73.53485) (xy 272.927578 -73.53485) (xy 272.927578 -73.48035) (xy 272.935333 -73.426405)
			(xy 272.950687 -73.374112) (xy 272.973326 -73.324537) (xy 273.00279 -73.278688) (xy 273.038478 -73.237498)
			(xy 273.079665 -73.201807) (xy 273.125512 -73.17234) (xy 273.175086 -73.149697) (xy 273.227377 -73.134339)
			(xy 273.281322 -73.12658) (xy 273.308572 -73.126092) (xy 273.33749 -73.126595) (xy 273.394663 -73.135323)
			(xy 273.449864 -73.152581) (xy 273.501827 -73.177975) (xy 273.54936 -73.210923) (xy 273.591374 -73.25067)
			(xy 273.609562 -73.273158) (xy 273.619459 -73.284963) (xy 273.644783 -73.302482) (xy 273.674176 -73.311658)
			(xy 273.704968 -73.311658) (xy 273.734361 -73.302482) (xy 273.759685 -73.284963) (xy 273.769582 -73.273158)
			(xy 273.786335 -73.252375) (xy 273.824689 -73.215245) (xy 273.867843 -73.183823) (xy 273.914957 -73.158724)
			(xy 273.965109 -73.140438) (xy 274.01732 -73.129321) (xy 274.070572 -73.125591) (xy 274.123824 -73.129321)
			(xy 274.176035 -73.140438) (xy 274.226187 -73.158724) (xy 274.273301 -73.183823) (xy 274.316455 -73.215245)
			(xy 274.354809 -73.252375) (xy 274.371562 -73.273158) (xy 274.381459 -73.284963) (xy 274.406783 -73.302482)
			(xy 274.436176 -73.311658) (xy 274.466968 -73.311658) (xy 274.496361 -73.302482) (xy 274.521685 -73.284963)
			(xy 274.531582 -73.273158) (xy 274.548335 -73.252375) (xy 274.586689 -73.215245) (xy 274.629843 -73.183823)
			(xy 274.676957 -73.158724) (xy 274.727109 -73.140438) (xy 274.77932 -73.129321) (xy 274.832572 -73.125591)
			(xy 274.885824 -73.129321) (xy 274.938035 -73.140438) (xy 274.988187 -73.158724) (xy 275.035301 -73.183823)
			(xy 275.078455 -73.215245) (xy 275.116809 -73.252375) (xy 275.133562 -73.273158) (xy 275.143459 -73.284963)
			(xy 275.168783 -73.302482) (xy 275.198176 -73.311658) (xy 275.228968 -73.311658) (xy 275.258361 -73.302482)
			(xy 275.283685 -73.284963) (xy 275.293582 -73.273158) (xy 275.310335 -73.252375) (xy 275.348689 -73.215245)
			(xy 275.391843 -73.183823) (xy 275.438957 -73.158724) (xy 275.489109 -73.140438) (xy 275.54132 -73.129321)
			(xy 275.594572 -73.125591) (xy 275.647824 -73.129321) (xy 275.700035 -73.140438) (xy 275.750187 -73.158724)
			(xy 275.797301 -73.183823) (xy 275.840455 -73.215245) (xy 275.878809 -73.252375) (xy 275.895562 -73.273158)
			(xy 275.905459 -73.284963) (xy 275.930783 -73.302482) (xy 275.960176 -73.311658) (xy 275.990968 -73.311658)
			(xy 276.020361 -73.302482) (xy 276.045685 -73.284963) (xy 276.055582 -73.273158) (xy 276.073773 -73.250674)
			(xy 276.115794 -73.210941) (xy 276.163329 -73.178003) (xy 276.21529 -73.152615) (xy 276.270487 -73.135359)
			(xy 276.327656 -73.126628) (xy 276.356572 -73.126092) (xy 276.383826 -73.126553) (xy 276.43778 -73.134307)
			(xy 276.490081 -73.149661) (xy 276.539665 -73.172302) (xy 276.585522 -73.201769) (xy 276.626718 -73.237463)
			(xy 276.662414 -73.278656) (xy 276.691885 -73.32451) (xy 276.714529 -73.374092) (xy 276.729887 -73.426392)
			(xy 276.737645 -73.480346) (xy 276.737645 -73.534854) (xy 276.729887 -73.588808) (xy 276.714529 -73.641108)
			(xy 276.691885 -73.69069) (xy 276.662414 -73.736544) (xy 276.626718 -73.777737) (xy 276.585522 -73.813431)
			(xy 276.539665 -73.842898) (xy 276.490081 -73.865539) (xy 276.43778 -73.880893) (xy 276.383826 -73.888647)
			(xy 276.356572 -73.889108) (xy 276.327655 -73.888573) (xy 276.270483 -73.879852) (xy 276.215283 -73.8626)
			(xy 276.163321 -73.837212) (xy 276.115787 -73.804269) (xy 276.073771 -73.764528) (xy 276.055582 -73.742042)
			(xy 276.045685 -73.730237) (xy 276.020361 -73.712718) (xy 275.990968 -73.703542) (xy 275.960176 -73.703542)
			(xy 275.930783 -73.712718) (xy 275.905459 -73.730237) (xy 275.895562 -73.742042) (xy 275.878809 -73.762825)
			(xy 275.840455 -73.799955) (xy 275.797301 -73.831377) (xy 275.750187 -73.856476) (xy 275.700035 -73.874762)
			(xy 275.647824 -73.885879) (xy 275.594572 -73.889609) (xy 275.54132 -73.885879) (xy 275.489109 -73.874762)
			(xy 275.438957 -73.856476) (xy 275.391843 -73.831377) (xy 275.348689 -73.799955) (xy 275.310335 -73.762825)
			(xy 275.293582 -73.742042) (xy 275.283685 -73.730237) (xy 275.258361 -73.712718) (xy 275.228968 -73.703542)
			(xy 275.198176 -73.703542) (xy 275.168783 -73.712718) (xy 275.143459 -73.730237) (xy 275.133562 -73.742042)
			(xy 275.116809 -73.762825) (xy 275.078455 -73.799955) (xy 275.035301 -73.831377) (xy 274.988187 -73.856476)
			(xy 274.938035 -73.874762) (xy 274.885824 -73.885879) (xy 274.832572 -73.889609) (xy 274.77932 -73.885879)
			(xy 274.727109 -73.874762) (xy 274.676957 -73.856476) (xy 274.629843 -73.831377) (xy 274.586689 -73.799955)
			(xy 274.548335 -73.762825) (xy 274.531582 -73.742042) (xy 274.521685 -73.730237) (xy 274.496361 -73.712718)
			(xy 274.466968 -73.703542) (xy 274.436176 -73.703542) (xy 274.406783 -73.712718) (xy 274.381459 -73.730237)
			(xy 274.371562 -73.742042) (xy 274.354809 -73.762825) (xy 274.316455 -73.799955) (xy 274.273301 -73.831377)
			(xy 274.226187 -73.856476) (xy 274.176035 -73.874762) (xy 274.123824 -73.885879) (xy 274.070572 -73.889609)
			(xy 274.01732 -73.885879) (xy 273.965109 -73.874762) (xy 273.914957 -73.856476) (xy 273.867843 -73.831377)
			(xy 273.824689 -73.799955) (xy 273.786335 -73.762825) (xy 273.769582 -73.742042) (xy 273.759685 -73.730237)
			(xy 273.734361 -73.712718) (xy 273.704968 -73.703542) (xy 273.674176 -73.703542) (xy 273.644783 -73.712718)
			(xy 273.619459 -73.730237) (xy 273.609562 -73.742042) (xy 273.591403 -73.764552) (xy 273.549375 -73.804284)
			(xy 273.501833 -73.837219) (xy 273.449866 -73.862602) (xy 273.394663 -73.879853) (xy 273.33749 -73.888576)
			(xy 273.308572 -73.889108) (xy 273.281322 -73.88862) (xy 273.227377 -73.880861) (xy 273.175086 -73.865503)
			(xy 273.125512 -73.84286) (xy 273.079665 -73.813393) (xy 273.038478 -73.777702) (xy 273.00279 -73.736512)
			(xy 272.973326 -73.690663) (xy 272.950687 -73.641088) (xy 272.935333 -73.588795) (xy 272.927578 -73.53485)
			(xy 253.037201 -73.53485) (xy 253.037849 -73.537004) (xy 253.045975 -73.592218) (xy 253.046484 -73.620122)
			(xy 253.045975 -73.648026) (xy 253.037849 -73.70324) (xy 253.021771 -73.756682) (xy 252.998083 -73.807213)
			(xy 252.967289 -73.853757) (xy 252.930047 -73.895321) (xy 252.887151 -73.93102) (xy 252.839513 -73.960093)
			(xy 252.78815 -73.98192) (xy 252.734157 -73.996036) (xy 252.678683 -74.002139) (xy 252.622912 -74.000101)
			(xy 252.568033 -73.989964) (xy 252.515213 -73.971945) (xy 252.465581 -73.946427) (xy 252.420193 -73.913955)
			(xy 252.380016 -73.87522) (xy 252.345908 -73.831048) (xy 252.318594 -73.78238) (xy 252.298658 -73.730254)
			(xy 252.286523 -73.675781) (xy 252.28245 -73.620122) (xy 249.28585 -73.620122) (xy 249.285849 -73.626909)
			(xy 249.278015 -73.681091) (xy 249.262513 -73.733596) (xy 249.239662 -73.783344) (xy 249.209931 -73.829313)
			(xy 249.192288 -73.850246) (xy 249.183006 -73.861539) (xy 249.170836 -73.88811) (xy 249.166673 -73.917036)
			(xy 249.170856 -73.94596) (xy 249.183045 -73.972522) (xy 249.192288 -73.98385) (xy 249.209915 -74.004792)
			(xy 249.239629 -74.050762) (xy 249.261619 -74.098658) (xy 260.18693 -74.098658) (xy 260.191001 -74.043036)
			(xy 260.203127 -73.988599) (xy 260.22305 -73.936508) (xy 260.250346 -73.887873) (xy 260.284432 -73.84373)
			(xy 260.324581 -73.805021) (xy 260.369939 -73.77257) (xy 260.419539 -73.747069) (xy 260.472323 -73.729062)
			(xy 260.527166 -73.718932) (xy 260.5829 -73.716895) (xy 260.638337 -73.722995) (xy 260.692294 -73.737101)
			(xy 260.743623 -73.758913) (xy 260.791229 -73.787967) (xy 260.834097 -73.823642) (xy 260.871314 -73.865179)
			(xy 260.902087 -73.911692) (xy 260.925759 -73.962189) (xy 260.932964 -73.986136) (xy 261.8265 -73.986136)
			(xy 261.830571 -73.930514) (xy 261.842697 -73.876077) (xy 261.86262 -73.823986) (xy 261.889916 -73.775351)
			(xy 261.924002 -73.731208) (xy 261.964151 -73.692499) (xy 262.009509 -73.660048) (xy 262.059109 -73.634547)
			(xy 262.111893 -73.61654) (xy 262.166736 -73.60641) (xy 262.22247 -73.604373) (xy 262.277907 -73.610473)
			(xy 262.331864 -73.624579) (xy 262.383193 -73.646391) (xy 262.430799 -73.675445) (xy 262.473667 -73.71112)
			(xy 262.510884 -73.752657) (xy 262.541657 -73.79917) (xy 262.565329 -73.849667) (xy 262.581397 -73.903074)
			(xy 262.589517 -73.95825) (xy 262.590026 -73.986136) (xy 262.589517 -74.014022) (xy 262.581397 -74.069198)
			(xy 262.565329 -74.122605) (xy 262.541657 -74.173102) (xy 262.510884 -74.219615) (xy 262.473667 -74.261152)
			(xy 262.430799 -74.296827) (xy 262.383193 -74.325881) (xy 262.331864 -74.347693) (xy 262.277907 -74.361799)
			(xy 262.22247 -74.367899) (xy 262.166736 -74.365862) (xy 262.111893 -74.355732) (xy 262.059109 -74.337725)
			(xy 262.009509 -74.312224) (xy 261.964151 -74.279773) (xy 261.924002 -74.241064) (xy 261.889916 -74.196921)
			(xy 261.86262 -74.148286) (xy 261.842697 -74.096195) (xy 261.830571 -74.041758) (xy 261.8265 -73.986136)
			(xy 260.932964 -73.986136) (xy 260.941827 -74.015596) (xy 260.949947 -74.070772) (xy 260.950456 -74.098658)
			(xy 260.949947 -74.126544) (xy 260.941827 -74.18172) (xy 260.925759 -74.235127) (xy 260.902087 -74.285624)
			(xy 260.871314 -74.332137) (xy 260.834097 -74.373674) (xy 260.791229 -74.409349) (xy 260.743623 -74.438403)
			(xy 260.692294 -74.460215) (xy 260.638337 -74.474321) (xy 260.5829 -74.480421) (xy 260.527166 -74.478384)
			(xy 260.472323 -74.468254) (xy 260.419539 -74.450247) (xy 260.369939 -74.424746) (xy 260.324581 -74.392295)
			(xy 260.284432 -74.353586) (xy 260.250346 -74.309443) (xy 260.22305 -74.260808) (xy 260.203127 -74.208717)
			(xy 260.191001 -74.15428) (xy 260.18693 -74.098658) (xy 249.261619 -74.098658) (xy 249.262468 -74.100507)
			(xy 249.277961 -74.153005) (xy 249.285793 -74.207179) (xy 249.286268 -74.234548) (xy 249.285867 -74.261802)
			(xy 249.278103 -74.315755) (xy 249.262739 -74.368054) (xy 249.24009 -74.417634) (xy 249.210615 -74.463486)
			(xy 249.174914 -74.504677) (xy 249.133715 -74.540368) (xy 249.087857 -74.569832) (xy 249.038271 -74.59247)
			(xy 248.985969 -74.607821) (xy 248.932014 -74.615573) (xy 248.90476 -74.616056) (xy 248.893495 -74.616003)
			(xy 248.871001 -74.614732) (xy 248.859802 -74.613516) (xy 248.846201 -74.612398) (xy 248.819238 -74.616521)
			(xy 248.79433 -74.627641) (xy 248.773259 -74.644963) (xy 248.757532 -74.667249) (xy 248.748272 -74.692906)
			(xy 248.746141 -74.7201) (xy 248.751293 -74.746886) (xy 248.752552 -74.74966) (xy 258.981954 -74.74966)
			(xy 258.986025 -74.694038) (xy 258.998151 -74.639601) (xy 259.018074 -74.58751) (xy 259.04537 -74.538875)
			(xy 259.079456 -74.494732) (xy 259.119605 -74.456023) (xy 259.164963 -74.423572) (xy 259.214563 -74.398071)
			(xy 259.267347 -74.380064) (xy 259.32219 -74.369934) (xy 259.377924 -74.367897) (xy 259.433361 -74.373997)
			(xy 259.487318 -74.388103) (xy 259.538647 -74.409915) (xy 259.586253 -74.438969) (xy 259.629121 -74.474644)
			(xy 259.666338 -74.516181) (xy 259.697111 -74.562694) (xy 259.720783 -74.613191) (xy 259.736851 -74.666598)
			(xy 259.744971 -74.721774) (xy 259.74548 -74.74966) (xy 259.744971 -74.777546) (xy 259.736851 -74.832722)
			(xy 259.720783 -74.886129) (xy 259.697111 -74.936626) (xy 259.666338 -74.983139) (xy 259.629121 -75.024676)
			(xy 259.586253 -75.060351) (xy 259.538647 -75.089405) (xy 259.487318 -75.111217) (xy 259.433361 -75.125323)
			(xy 259.377924 -75.131423) (xy 259.32219 -75.129386) (xy 259.267347 -75.119256) (xy 259.214563 -75.101249)
			(xy 259.164963 -75.075748) (xy 259.119605 -75.043297) (xy 259.079456 -75.004588) (xy 259.04537 -74.960445)
			(xy 259.018074 -74.91181) (xy 258.998151 -74.859719) (xy 258.986025 -74.805282) (xy 258.981954 -74.74966)
			(xy 248.752552 -74.74966) (xy 248.756932 -74.759312) (xy 248.769388 -74.785711) (xy 248.787005 -74.841359)
			(xy 248.795961 -74.899038) (xy 248.796556 -74.928222) (xy 248.796556 -74.928984) (xy 248.796007 -74.956233)
			(xy 248.788254 -75.010176) (xy 248.772903 -75.062466) (xy 248.750268 -75.11204) (xy 248.720807 -75.157888)
			(xy 248.685123 -75.199077) (xy 248.643939 -75.234769) (xy 248.598096 -75.264237) (xy 248.548526 -75.286881)
			(xy 248.496238 -75.30224) (xy 248.442297 -75.310002) (xy 248.415048 -75.310492) (xy 248.387679 -75.31)
			(xy 248.333501 -75.302189) (xy 248.280998 -75.286706) (xy 248.23125 -75.26387) (xy 248.185283 -75.234151)
			(xy 248.16435 -75.216512) (xy 248.153022 -75.207276) (xy 248.126465 -75.1951) (xy 248.097548 -75.190927)
			(xy 248.068631 -75.1951) (xy 248.042074 -75.207276) (xy 248.030746 -75.216512) (xy 248.009809 -75.234145)
			(xy 247.963837 -75.263857) (xy 247.914091 -75.286694) (xy 247.861592 -75.302187) (xy 247.807417 -75.310017)
			(xy 247.780048 -75.310492) (xy 247.752792 -75.310064) (xy 247.698833 -75.302313) (xy 247.646527 -75.28696)
			(xy 247.596939 -75.264319) (xy 247.551078 -75.234851) (xy 247.509878 -75.199156) (xy 247.474177 -75.15796)
			(xy 247.444704 -75.112103) (xy 247.422057 -75.062518) (xy 247.406698 -75.010214) (xy 247.398939 -74.956256)
			(xy 247.398939 -74.901744) (xy 247.406698 -74.847786) (xy 247.422057 -74.795482) (xy 247.444704 -74.745897)
			(xy 247.474177 -74.70004) (xy 247.509878 -74.658844) (xy 247.551078 -74.623149) (xy 247.596939 -74.593681)
			(xy 247.646527 -74.57104) (xy 247.698833 -74.555687) (xy 247.752792 -74.547936) (xy 247.780048 -74.547476)
			(xy 247.807418 -74.547954) (xy 247.861597 -74.555766) (xy 247.914101 -74.571251) (xy 247.963848 -74.594091)
			(xy 248.009815 -74.623815) (xy 248.030746 -74.641456) (xy 248.042074 -74.650692) (xy 248.068631 -74.662868)
			(xy 248.097548 -74.667041) (xy 248.126465 -74.662868) (xy 248.153022 -74.650692) (xy 248.16435 -74.641456)
			(xy 248.185284 -74.62382) (xy 248.231257 -74.594109) (xy 248.281004 -74.571273) (xy 248.333504 -74.555781)
			(xy 248.387679 -74.547951) (xy 248.415048 -74.547476) (xy 248.426313 -74.547528) (xy 248.448807 -74.5488)
			(xy 248.460006 -74.550016) (xy 248.473603 -74.551239) (xy 248.500583 -74.547112) (xy 248.525505 -74.535982)
			(xy 248.546585 -74.518644) (xy 248.562316 -74.496339) (xy 248.571573 -74.470663) (xy 248.573693 -74.443451)
			(xy 248.568525 -74.416651) (xy 248.562876 -74.40422) (xy 248.550432 -74.377816) (xy 248.532811 -74.32217)
			(xy 248.52385 -74.264494) (xy 248.523252 -74.23531) (xy 248.523252 -74.234548) (xy 248.523734 -74.207178)
			(xy 248.531546 -74.152999) (xy 248.54703 -74.100496) (xy 248.569869 -74.050749) (xy 248.599591 -74.004782)
			(xy 248.617232 -73.98385) (xy 248.62642 -73.972487) (xy 248.638599 -73.945942) (xy 248.642779 -73.917036)
			(xy 248.63862 -73.888128) (xy 248.62646 -73.861574) (xy 248.617232 -73.850246) (xy 248.599638 -73.829275)
			(xy 248.569911 -73.783314) (xy 248.547063 -73.733574) (xy 248.531562 -73.681078) (xy 248.523729 -73.626905)
			(xy 248.523724 -73.572168) (xy 248.531547 -73.517993) (xy 248.547037 -73.465494) (xy 248.569876 -73.415749)
			(xy 248.599595 -73.369783) (xy 248.617232 -73.34885) (xy 248.62642 -73.337487) (xy 248.638599 -73.310942)
			(xy 248.642779 -73.282036) (xy 248.63862 -73.253128) (xy 248.62646 -73.226574) (xy 248.617232 -73.215246)
			(xy 248.599638 -73.194275) (xy 248.569911 -73.148314) (xy 248.547063 -73.098574) (xy 248.531562 -73.046078)
			(xy 248.523729 -72.991905) (xy 248.523724 -72.937168) (xy 248.531547 -72.882993) (xy 248.547037 -72.830494)
			(xy 248.569876 -72.780749) (xy 248.599595 -72.734783) (xy 248.617232 -72.71385) (xy 248.62642 -72.702487)
			(xy 248.638599 -72.675942) (xy 248.642779 -72.647036) (xy 248.63862 -72.618128) (xy 248.62646 -72.591574)
			(xy 248.617232 -72.580246) (xy 248.599606 -72.559303) (xy 248.569891 -72.513334) (xy 248.547052 -72.463589)
			(xy 248.531558 -72.411091) (xy 248.523727 -72.356917) (xy 248.523252 -72.329548) (xy 248.52369 -72.302896)
			(xy 248.53112 -72.250113) (xy 248.545828 -72.198878) (xy 248.556272 -72.174354) (xy 248.561856 -72.160208)
			(xy 248.565466 -72.130032) (xy 248.560054 -72.100128) (xy 248.546096 -72.073132) (xy 248.524823 -72.051428)
			(xy 248.498114 -72.036929) (xy 248.468324 -72.030916) (xy 248.453148 -72.03186) (xy 248.415048 -72.033892)
			(xy 248.387679 -72.0334) (xy 248.333501 -72.025589) (xy 248.280998 -72.010106) (xy 248.23125 -71.98727)
			(xy 248.185283 -71.957551) (xy 248.16435 -71.939912) (xy 248.153022 -71.930676) (xy 248.126465 -71.9185)
			(xy 248.097548 -71.914327) (xy 248.068631 -71.9185) (xy 248.042074 -71.930676) (xy 248.030746 -71.939912)
			(xy 248.009809 -71.957545) (xy 247.963837 -71.987257) (xy 247.914091 -72.010094) (xy 247.861592 -72.025587)
			(xy 247.807417 -72.033417) (xy 247.780048 -72.033892) (xy 247.752796 -72.0334) (xy 247.698845 -72.025649)
			(xy 247.646547 -72.010298) (xy 247.596966 -71.98766) (xy 247.551111 -71.958196) (xy 247.509918 -71.922505)
			(xy 247.474223 -71.881314) (xy 247.444755 -71.835463) (xy 247.422113 -71.785883) (xy 247.406758 -71.733586)
			(xy 247.399002 -71.679636) (xy 247.39854 -71.652384) (xy 246.61368 -71.652384) (xy 246.61368 -75.377548)
			(xy 247.042288 -75.806156) (xy 274.987923 -75.806156) (xy 274.987923 -75.751644) (xy 274.995681 -75.697687)
			(xy 275.011039 -75.645383) (xy 275.033685 -75.595797) (xy 275.063158 -75.549939) (xy 275.098857 -75.508742)
			(xy 275.140055 -75.473046) (xy 275.185915 -75.443576) (xy 275.235502 -75.420932) (xy 275.287806 -75.405577)
			(xy 275.341764 -75.397822) (xy 275.36902 -75.39736) (xy 275.396391 -75.3978) (xy 275.450572 -75.405622)
			(xy 275.503076 -75.421116) (xy 275.552823 -75.443964) (xy 275.598788 -75.473695) (xy 275.619718 -75.49134)
			(xy 275.631046 -75.500576) (xy 275.657603 -75.512752) (xy 275.68652 -75.516925) (xy 275.715437 -75.512752)
			(xy 275.741994 -75.500576) (xy 275.753322 -75.49134) (xy 275.774255 -75.473699) (xy 275.820223 -75.443975)
			(xy 275.869969 -75.421129) (xy 275.922471 -75.405633) (xy 275.976649 -75.397804) (xy 276.031391 -75.397804)
			(xy 276.085569 -75.405633) (xy 276.138071 -75.421129) (xy 276.187817 -75.443975) (xy 276.233785 -75.473699)
			(xy 276.254718 -75.49134) (xy 276.266046 -75.500576) (xy 276.292603 -75.512752) (xy 276.32152 -75.516925)
			(xy 276.350437 -75.512752) (xy 276.376994 -75.500576) (xy 276.388322 -75.49134) (xy 276.409255 -75.473699)
			(xy 276.455223 -75.443975) (xy 276.504969 -75.421129) (xy 276.557471 -75.405633) (xy 276.611649 -75.397804)
			(xy 276.666391 -75.397804) (xy 276.720569 -75.405633) (xy 276.773071 -75.421129) (xy 276.822817 -75.443975)
			(xy 276.868785 -75.473699) (xy 276.889718 -75.49134) (xy 276.901046 -75.500576) (xy 276.927603 -75.512752)
			(xy 276.95652 -75.516925) (xy 276.985437 -75.512752) (xy 277.011994 -75.500576) (xy 277.023322 -75.49134)
			(xy 277.044255 -75.473699) (xy 277.090223 -75.443975) (xy 277.139969 -75.421129) (xy 277.192471 -75.405633)
			(xy 277.246649 -75.397804) (xy 277.301391 -75.397804) (xy 277.355569 -75.405633) (xy 277.408071 -75.421129)
			(xy 277.457817 -75.443975) (xy 277.503785 -75.473699) (xy 277.524718 -75.49134) (xy 277.536046 -75.500576)
			(xy 277.562603 -75.512752) (xy 277.59152 -75.516925) (xy 277.620437 -75.512752) (xy 277.646994 -75.500576)
			(xy 277.658322 -75.49134) (xy 277.679278 -75.47373) (xy 277.725243 -75.444013) (xy 277.774985 -75.42117)
			(xy 277.827481 -75.405673) (xy 277.881652 -75.397837) (xy 277.90902 -75.39736) (xy 277.936268 -75.397912)
			(xy 277.990209 -75.40567) (xy 278.042497 -75.421025) (xy 278.092067 -75.443666) (xy 278.137911 -75.47313)
			(xy 278.179096 -75.508818) (xy 278.214782 -75.550005) (xy 278.244244 -75.59585) (xy 278.266882 -75.645422)
			(xy 278.282235 -75.697711) (xy 278.28999 -75.751652) (xy 278.28999 -75.806148) (xy 278.282235 -75.860089)
			(xy 278.266882 -75.912378) (xy 278.244244 -75.96195) (xy 278.214782 -76.007795) (xy 278.179096 -76.048982)
			(xy 278.137911 -76.08467) (xy 278.092067 -76.114134) (xy 278.042497 -76.136775) (xy 277.990209 -76.15213)
			(xy 277.936268 -76.159888) (xy 277.90902 -76.160376) (xy 277.88165 -76.159904) (xy 277.827471 -76.152089)
			(xy 277.774968 -76.136601) (xy 277.725221 -76.113761) (xy 277.679254 -76.084037) (xy 277.658322 -76.066396)
			(xy 277.646994 -76.05716) (xy 277.620437 -76.044984) (xy 277.59152 -76.040811) (xy 277.562603 -76.044984)
			(xy 277.536046 -76.05716) (xy 277.524718 -76.066396) (xy 277.503785 -76.084037) (xy 277.457817 -76.113761)
			(xy 277.408071 -76.136607) (xy 277.355569 -76.152103) (xy 277.301391 -76.159932) (xy 277.246649 -76.159932)
			(xy 277.192471 -76.152103) (xy 277.139969 -76.136607) (xy 277.090223 -76.113761) (xy 277.044255 -76.084037)
			(xy 277.023322 -76.066396) (xy 277.011994 -76.05716) (xy 276.985437 -76.044984) (xy 276.95652 -76.040811)
			(xy 276.927603 -76.044984) (xy 276.901046 -76.05716) (xy 276.889718 -76.066396) (xy 276.868785 -76.084037)
			(xy 276.822817 -76.113761) (xy 276.773071 -76.136607) (xy 276.720569 -76.152103) (xy 276.666391 -76.159932)
			(xy 276.611649 -76.159932) (xy 276.557471 -76.152103) (xy 276.504969 -76.136607) (xy 276.455223 -76.113761)
			(xy 276.409255 -76.084037) (xy 276.388322 -76.066396) (xy 276.376994 -76.05716) (xy 276.350437 -76.044984)
			(xy 276.32152 -76.040811) (xy 276.292603 -76.044984) (xy 276.266046 -76.05716) (xy 276.254718 -76.066396)
			(xy 276.233785 -76.084037) (xy 276.187817 -76.113761) (xy 276.138071 -76.136607) (xy 276.085569 -76.152103)
			(xy 276.031391 -76.159932) (xy 275.976649 -76.159932) (xy 275.922471 -76.152103) (xy 275.869969 -76.136607)
			(xy 275.820223 -76.113761) (xy 275.774255 -76.084037) (xy 275.753322 -76.066396) (xy 275.741994 -76.05716)
			(xy 275.715437 -76.044984) (xy 275.68652 -76.040811) (xy 275.657603 -76.044984) (xy 275.631046 -76.05716)
			(xy 275.619718 -76.066396) (xy 275.598789 -76.084039) (xy 275.552816 -76.113751) (xy 275.503067 -76.136586)
			(xy 275.450566 -76.152076) (xy 275.396389 -76.159903) (xy 275.36902 -76.160376) (xy 275.341764 -76.159978)
			(xy 275.287806 -76.152223) (xy 275.235502 -76.136868) (xy 275.185915 -76.114224) (xy 275.140055 -76.084754)
			(xy 275.098857 -76.049058) (xy 275.063158 -76.007861) (xy 275.033685 -75.962003) (xy 275.011039 -75.912417)
			(xy 274.995681 -75.860113) (xy 274.987923 -75.806156) (xy 247.042288 -75.806156) (xy 248.16308 -76.926948)
			(xy 257.560062 -76.926948) (xy 257.564133 -76.871326) (xy 257.576259 -76.816889) (xy 257.596182 -76.764798)
			(xy 257.623478 -76.716163) (xy 257.657564 -76.67202) (xy 257.697713 -76.633311) (xy 257.743071 -76.60086)
			(xy 257.792671 -76.575359) (xy 257.845455 -76.557352) (xy 257.900298 -76.547222) (xy 257.956032 -76.545185)
			(xy 258.011469 -76.551285) (xy 258.065426 -76.565391) (xy 258.116755 -76.587203) (xy 258.164361 -76.616257)
			(xy 258.207229 -76.651932) (xy 258.244446 -76.693469) (xy 258.275219 -76.739982) (xy 258.298891 -76.790479)
			(xy 258.314959 -76.843886) (xy 258.323079 -76.899062) (xy 258.323588 -76.926948) (xy 258.323079 -76.954834)
			(xy 258.314959 -77.01001) (xy 258.298891 -77.063417) (xy 258.275219 -77.113914) (xy 258.244446 -77.160427)
			(xy 258.207229 -77.201964) (xy 258.164361 -77.237639) (xy 258.116755 -77.266693) (xy 258.065426 -77.288505)
			(xy 258.011469 -77.302611) (xy 257.956032 -77.308711) (xy 257.900298 -77.306674) (xy 257.845455 -77.296544)
			(xy 257.792671 -77.278537) (xy 257.743071 -77.253036) (xy 257.697713 -77.220585) (xy 257.657564 -77.181876)
			(xy 257.623478 -77.137733) (xy 257.596182 -77.089098) (xy 257.576259 -77.037007) (xy 257.564133 -76.98257)
			(xy 257.560062 -76.926948) (xy 248.16308 -76.926948) (xy 249.313954 -78.077822) (xy 262.833104 -78.077822)
			(xy 262.833509 -78.051441) (xy 262.840772 -77.999182) (xy 262.855163 -77.948421) (xy 262.876408 -77.900125)
			(xy 262.904101 -77.855216) (xy 262.937715 -77.814548) (xy 262.97661 -77.778897) (xy 263.020043 -77.748942)
			(xy 263.043416 -77.7367) (xy 263.05576 -77.72997) (xy 263.076497 -77.711003) (xy 263.091265 -77.687094)
			(xy 263.098943 -77.660061) (xy 263.098945 -77.631959) (xy 263.091273 -77.604924) (xy 263.076509 -77.581012)
			(xy 263.055777 -77.562042) (xy 263.043416 -77.555344) (xy 263.020059 -77.543078) (xy 262.976634 -77.513121)
			(xy 262.937747 -77.477469) (xy 262.90414 -77.436803) (xy 262.876451 -77.391898) (xy 262.855209 -77.343608)
			(xy 262.840817 -77.292853) (xy 262.833551 -77.2406) (xy 262.833104 -77.214222) (xy 262.83359 -77.186971)
			(xy 262.841346 -77.133023) (xy 262.856701 -77.080728) (xy 262.879343 -77.031151) (xy 262.908809 -76.985301)
			(xy 262.9445 -76.94411) (xy 262.985691 -76.908419) (xy 263.031541 -76.878953) (xy 263.081118 -76.856311)
			(xy 263.133413 -76.840956) (xy 263.187361 -76.8332) (xy 263.241863 -76.8332) (xy 263.295811 -76.840956)
			(xy 263.348106 -76.856311) (xy 263.397683 -76.878953) (xy 263.443533 -76.908419) (xy 263.484724 -76.94411)
			(xy 263.520415 -76.985301) (xy 263.549881 -77.031151) (xy 263.572523 -77.080728) (xy 263.587878 -77.133023)
			(xy 263.595634 -77.186971) (xy 263.59612 -77.214222) (xy 263.595656 -77.240601) (xy 263.588401 -77.292857)
			(xy 263.574018 -77.343616) (xy 263.552782 -77.39191) (xy 263.525097 -77.43682) (xy 263.491491 -77.477489)
			(xy 263.452604 -77.513142) (xy 263.409177 -77.5431) (xy 263.385808 -77.555344) (xy 263.373433 -77.562015)
			(xy 263.352707 -77.580998) (xy 263.337949 -77.604918) (xy 263.330281 -77.631957) (xy 263.330283 -77.660063)
			(xy 263.337957 -77.6871) (xy 263.352719 -77.711017) (xy 263.373449 -77.729996) (xy 263.385808 -77.7367)
			(xy 263.409189 -77.748922) (xy 263.452614 -77.778887) (xy 263.491499 -77.814545) (xy 263.525104 -77.855217)
			(xy 263.55279 -77.900129) (xy 263.574029 -77.948425) (xy 263.588415 -77.999185) (xy 263.595676 -78.051442)
			(xy 263.59612 -78.077822) (xy 263.595634 -78.105073) (xy 263.587878 -78.159021) (xy 263.572523 -78.211316)
			(xy 263.549881 -78.260893) (xy 263.520415 -78.306743) (xy 263.484724 -78.347934) (xy 263.443533 -78.383625)
			(xy 263.397683 -78.413091) (xy 263.348106 -78.435733) (xy 263.295811 -78.451088) (xy 263.241863 -78.458844)
			(xy 263.187361 -78.458844) (xy 263.133413 -78.451088) (xy 263.081118 -78.435733) (xy 263.031541 -78.413091)
			(xy 262.985691 -78.383625) (xy 262.9445 -78.347934) (xy 262.908809 -78.306743) (xy 262.879343 -78.260893)
			(xy 262.856701 -78.211316) (xy 262.841346 -78.159021) (xy 262.83359 -78.105073) (xy 262.833104 -78.077822)
			(xy 249.313954 -78.077822) (xy 250.21413 -78.977998) (xy 258.880862 -78.977998) (xy 258.884933 -78.922376)
			(xy 258.897059 -78.867939) (xy 258.916982 -78.815848) (xy 258.944278 -78.767213) (xy 258.978364 -78.72307)
			(xy 259.018513 -78.684361) (xy 259.063871 -78.65191) (xy 259.113471 -78.626409) (xy 259.166255 -78.608402)
			(xy 259.221098 -78.598272) (xy 259.276832 -78.596235) (xy 259.332269 -78.602335) (xy 259.386226 -78.616441)
			(xy 259.437555 -78.638253) (xy 259.485161 -78.667307) (xy 259.528029 -78.702982) (xy 259.565246 -78.744519)
			(xy 259.596019 -78.791032) (xy 259.619691 -78.841529) (xy 259.635759 -78.894936) (xy 259.643879 -78.950112)
			(xy 259.644388 -78.977998) (xy 259.643879 -79.005884) (xy 259.635759 -79.06106) (xy 259.619691 -79.114467)
			(xy 259.596019 -79.164964) (xy 259.565246 -79.211477) (xy 259.528029 -79.253014) (xy 259.485161 -79.288689)
			(xy 259.437555 -79.317743) (xy 259.386226 -79.339555) (xy 259.332269 -79.353661) (xy 259.276832 -79.359761)
			(xy 259.221098 -79.357724) (xy 259.166255 -79.347594) (xy 259.113471 -79.329587) (xy 259.063871 -79.304086)
			(xy 259.018513 -79.271635) (xy 258.978364 -79.232926) (xy 258.944278 -79.188783) (xy 258.916982 -79.140148)
			(xy 258.897059 -79.088057) (xy 258.884933 -79.03362) (xy 258.880862 -78.977998) (xy 250.21413 -78.977998)
			(xy 250.77928 -79.543148) (xy 278.97328 -79.543148)
		)
		(stroke
			(width 0)
			(type solid)
		)
		(fill yes)
		(layer "In2.Cu")
		(net "GND")
	)
	(gr_poly
		(pts
			(xy 164.537644 -321.8434) (xy 164.553259 -321.842829) (xy 164.583032 -321.833396) (xy 164.608573 -321.815423)
			(xy 164.627503 -321.790584) (xy 164.638061 -321.761191) (xy 164.639244 -321.74561) (xy 164.640737 -321.718311)
			(xy 164.651052 -321.664624) (xy 164.669452 -321.613144) (xy 164.695504 -321.565081) (xy 164.728596 -321.521564)
			(xy 164.76795 -321.483617) (xy 164.812642 -321.45213) (xy 164.861621 -321.427844) (xy 164.913736 -321.411329)
			(xy 164.967763 -321.402973) (xy 165.022433 -321.402973) (xy 165.07646 -321.411329) (xy 165.128575 -321.427844)
			(xy 165.177554 -321.45213) (xy 165.222246 -321.483617) (xy 165.2616 -321.521564) (xy 165.294692 -321.565081)
			(xy 165.320744 -321.613144) (xy 165.339144 -321.664624) (xy 165.349459 -321.718311) (xy 165.350952 -321.74561)
			(xy 165.352092 -321.761204) (xy 165.362623 -321.790628) (xy 165.381557 -321.815491) (xy 165.407122 -321.833465)
			(xy 165.436925 -321.842869) (xy 165.452552 -321.8434) (xy 184.109106 -321.8434) (xy 184.124132 -321.842875)
			(xy 184.152888 -321.834151) (xy 184.177857 -321.817432) (xy 184.196876 -321.794166) (xy 184.208296 -321.766371)
			(xy 184.211128 -321.736454) (xy 184.205125 -321.70701) (xy 184.190808 -321.680589) (xy 184.18048 -321.669664)
			(xy 184.160875 -321.649461) (xy 184.127644 -321.604023) (xy 184.101967 -321.553927) (xy 184.084482 -321.500418)
			(xy 184.075623 -321.444826) (xy 184.07507 -321.41668) (xy 184.075568 -321.390031) (xy 184.083511 -321.337327)
			(xy 184.099221 -321.286397) (xy 184.122347 -321.238376) (xy 184.152371 -321.194339) (xy 184.188623 -321.155268)
			(xy 184.230294 -321.122037) (xy 184.276452 -321.095388) (xy 184.326066 -321.075916) (xy 184.378028 -321.064056)
			(xy 184.431178 -321.060073) (xy 184.484328 -321.064056) (xy 184.53629 -321.075916) (xy 184.585904 -321.095388)
			(xy 184.632062 -321.122037) (xy 184.673733 -321.155268) (xy 184.709985 -321.194339) (xy 184.740009 -321.238376)
			(xy 184.763135 -321.286397) (xy 184.778845 -321.337327) (xy 184.786788 -321.390031) (xy 184.787286 -321.41668)
			(xy 184.786755 -321.444828) (xy 184.777903 -321.500424) (xy 184.760415 -321.553935) (xy 184.734728 -321.604028)
			(xy 184.70148 -321.649458) (xy 184.681876 -321.669664) (xy 184.671596 -321.68061) (xy 184.657344 -321.707025)
			(xy 184.651383 -321.736441) (xy 184.654229 -321.766321) (xy 184.665636 -321.794083) (xy 184.684618 -321.817332)
			(xy 184.709538 -321.834062) (xy 184.738244 -321.842827) (xy 184.75325 -321.8434) (xy 187.560966 -321.8434)
			(xy 187.575985 -321.842867) (xy 187.604725 -321.834134) (xy 187.629678 -321.817413) (xy 187.648684 -321.794153)
			(xy 187.660097 -321.766369) (xy 187.662928 -321.736465) (xy 187.656933 -321.707032) (xy 187.64263 -321.680618)
			(xy 187.63234 -321.669664) (xy 187.612732 -321.649463) (xy 187.579496 -321.604026) (xy 187.553814 -321.55393)
			(xy 187.536326 -321.500421) (xy 187.527465 -321.444827) (xy 187.52693 -321.41668) (xy 187.527428 -321.390031)
			(xy 187.535371 -321.337327) (xy 187.551081 -321.286397) (xy 187.574207 -321.238376) (xy 187.604231 -321.194339)
			(xy 187.640483 -321.155268) (xy 187.682154 -321.122037) (xy 187.728312 -321.095388) (xy 187.777926 -321.075916)
			(xy 187.829888 -321.064056) (xy 187.883038 -321.060073) (xy 187.936188 -321.064056) (xy 187.98815 -321.075916)
			(xy 188.037764 -321.095388) (xy 188.083922 -321.122037) (xy 188.125593 -321.155268) (xy 188.161845 -321.194339)
			(xy 188.191869 -321.238376) (xy 188.214995 -321.286397) (xy 188.230705 -321.337327) (xy 188.238648 -321.390031)
			(xy 188.239146 -321.41668) (xy 188.238615 -321.444828) (xy 188.229764 -321.500425) (xy 188.212279 -321.553938)
			(xy 188.186594 -321.604034) (xy 188.153351 -321.649468) (xy 188.133736 -321.669664) (xy 188.123451 -321.680606)
			(xy 188.109191 -321.707017) (xy 188.103226 -321.736433) (xy 188.106071 -321.766313) (xy 188.11748 -321.794075)
			(xy 188.136467 -321.81732) (xy 188.161393 -321.834041) (xy 188.190103 -321.842793) (xy 188.20511 -321.8434)
			(xy 191.650366 -321.8434) (xy 191.665385 -321.842867) (xy 191.694125 -321.834134) (xy 191.719078 -321.817413)
			(xy 191.738084 -321.794153) (xy 191.749497 -321.766369) (xy 191.752328 -321.736465) (xy 191.746333 -321.707032)
			(xy 191.73203 -321.680618) (xy 191.72174 -321.669664) (xy 191.702132 -321.649463) (xy 191.668896 -321.604026)
			(xy 191.643214 -321.55393) (xy 191.625726 -321.500421) (xy 191.616865 -321.444827) (xy 191.61633 -321.41668)
			(xy 191.616828 -321.390031) (xy 191.624771 -321.337327) (xy 191.640481 -321.286397) (xy 191.663607 -321.238376)
			(xy 191.693631 -321.194339) (xy 191.729883 -321.155268) (xy 191.771554 -321.122037) (xy 191.817712 -321.095388)
			(xy 191.867326 -321.075916) (xy 191.919288 -321.064056) (xy 191.972438 -321.060073) (xy 192.025588 -321.064056)
			(xy 192.07755 -321.075916) (xy 192.127164 -321.095388) (xy 192.173322 -321.122037) (xy 192.214993 -321.155268)
			(xy 192.251245 -321.194339) (xy 192.281269 -321.238376) (xy 192.304395 -321.286397) (xy 192.320105 -321.337327)
			(xy 192.328048 -321.390031) (xy 192.328546 -321.41668) (xy 192.328015 -321.444828) (xy 192.319164 -321.500425)
			(xy 192.301679 -321.553938) (xy 192.275994 -321.604034) (xy 192.242751 -321.649468) (xy 192.223136 -321.669664)
			(xy 192.212851 -321.680606) (xy 192.198591 -321.707017) (xy 192.192626 -321.736433) (xy 192.195471 -321.766313)
			(xy 192.20688 -321.794075) (xy 192.225867 -321.81732) (xy 192.250793 -321.834041) (xy 192.279503 -321.842793)
			(xy 192.29451 -321.8434) (xy 195.105274 -321.8434) (xy 195.120292 -321.842866) (xy 195.14903 -321.834131)
			(xy 195.173981 -321.817411) (xy 195.192985 -321.794152) (xy 195.204397 -321.766368) (xy 195.207228 -321.736466)
			(xy 195.201234 -321.707035) (xy 195.186933 -321.680622) (xy 195.176648 -321.669664) (xy 195.157039 -321.649463)
			(xy 195.123803 -321.604027) (xy 195.098121 -321.553931) (xy 195.080632 -321.500421) (xy 195.071771 -321.444828)
			(xy 195.071238 -321.41668) (xy 195.071736 -321.390031) (xy 195.079679 -321.337327) (xy 195.095389 -321.286397)
			(xy 195.118515 -321.238376) (xy 195.148539 -321.194339) (xy 195.184791 -321.155268) (xy 195.226462 -321.122037)
			(xy 195.27262 -321.095388) (xy 195.322234 -321.075916) (xy 195.374196 -321.064056) (xy 195.427346 -321.060073)
			(xy 195.480496 -321.064056) (xy 195.532458 -321.075916) (xy 195.582072 -321.095388) (xy 195.62823 -321.122037)
			(xy 195.669901 -321.155268) (xy 195.706153 -321.194339) (xy 195.736177 -321.238376) (xy 195.759303 -321.286397)
			(xy 195.775013 -321.337327) (xy 195.782956 -321.390031) (xy 195.783454 -321.41668) (xy 195.782923 -321.444829)
			(xy 195.774072 -321.500425) (xy 195.756587 -321.553938) (xy 195.730903 -321.604035) (xy 195.69766 -321.649469)
			(xy 195.678044 -321.669664) (xy 195.667759 -321.680606) (xy 195.653498 -321.707016) (xy 195.647532 -321.736432)
			(xy 195.650376 -321.766312) (xy 195.661785 -321.794073) (xy 195.680774 -321.817318) (xy 195.7057 -321.834038)
			(xy 195.734411 -321.842789) (xy 195.749418 -321.8434) (xy 199.205342 -321.8434) (xy 199.220364 -321.84287)
			(xy 199.24911 -321.834141) (xy 199.27407 -321.817421) (xy 199.293081 -321.794159) (xy 199.304497 -321.766369)
			(xy 199.307328 -321.736461) (xy 199.30133 -321.707023) (xy 199.287021 -321.680607) (xy 199.276716 -321.669664)
			(xy 199.257109 -321.649462) (xy 199.223875 -321.604025) (xy 199.198195 -321.553929) (xy 199.180708 -321.50042)
			(xy 199.171848 -321.444827) (xy 199.171306 -321.41668) (xy 199.171804 -321.390031) (xy 199.179747 -321.337327)
			(xy 199.195457 -321.286397) (xy 199.218583 -321.238376) (xy 199.248607 -321.194339) (xy 199.284859 -321.155268)
			(xy 199.32653 -321.122037) (xy 199.372688 -321.095388) (xy 199.422302 -321.075916) (xy 199.474264 -321.064056)
			(xy 199.527414 -321.060073) (xy 199.580564 -321.064056) (xy 199.632526 -321.075916) (xy 199.68214 -321.095388)
			(xy 199.728298 -321.122037) (xy 199.769969 -321.155268) (xy 199.806221 -321.194339) (xy 199.836245 -321.238376)
			(xy 199.859371 -321.286397) (xy 199.875081 -321.337327) (xy 199.883024 -321.390031) (xy 199.883522 -321.41668)
			(xy 199.882991 -321.444828) (xy 199.874139 -321.500425) (xy 199.856653 -321.553937) (xy 199.830968 -321.604032)
			(xy 199.797722 -321.649464) (xy 199.778112 -321.669664) (xy 199.767829 -321.680608) (xy 199.753572 -321.70702)
			(xy 199.747609 -321.736436) (xy 199.750454 -321.766316) (xy 199.761862 -321.794078) (xy 199.780847 -321.817325)
			(xy 199.805771 -321.834049) (xy 199.834479 -321.842807) (xy 199.849486 -321.8434) (xy 202.649074 -321.8434)
			(xy 202.664092 -321.842866) (xy 202.69283 -321.834131) (xy 202.717781 -321.817411) (xy 202.736785 -321.794152)
			(xy 202.748197 -321.766368) (xy 202.751028 -321.736466) (xy 202.745034 -321.707035) (xy 202.730733 -321.680622)
			(xy 202.720448 -321.669664) (xy 202.700839 -321.649463) (xy 202.667603 -321.604027) (xy 202.641921 -321.553931)
			(xy 202.624432 -321.500421) (xy 202.615571 -321.444828) (xy 202.615038 -321.41668) (xy 202.615536 -321.390031)
			(xy 202.623479 -321.337327) (xy 202.639189 -321.286397) (xy 202.662315 -321.238376) (xy 202.692339 -321.194339)
			(xy 202.728591 -321.155268) (xy 202.770262 -321.122037) (xy 202.81642 -321.095388) (xy 202.866034 -321.075916)
			(xy 202.917996 -321.064056) (xy 202.971146 -321.060073) (xy 203.024296 -321.064056) (xy 203.076258 -321.075916)
			(xy 203.125872 -321.095388) (xy 203.17203 -321.122037) (xy 203.213701 -321.155268) (xy 203.249953 -321.194339)
			(xy 203.279977 -321.238376) (xy 203.303103 -321.286397) (xy 203.318813 -321.337327) (xy 203.326756 -321.390031)
			(xy 203.327254 -321.41668) (xy 203.326723 -321.444829) (xy 203.317872 -321.500425) (xy 203.300387 -321.553938)
			(xy 203.274703 -321.604035) (xy 203.24146 -321.649469) (xy 203.221844 -321.669664) (xy 203.211559 -321.680606)
			(xy 203.197298 -321.707016) (xy 203.191332 -321.736432) (xy 203.194176 -321.766312) (xy 203.205585 -321.794073)
			(xy 203.224574 -321.817318) (xy 203.2495 -321.834038) (xy 203.278211 -321.842789) (xy 203.293218 -321.8434)
			(xy 206.749142 -321.8434) (xy 206.764164 -321.84287) (xy 206.79291 -321.834141) (xy 206.81787 -321.817421)
			(xy 206.836881 -321.794159) (xy 206.848297 -321.766369) (xy 206.851128 -321.736461) (xy 206.84513 -321.707023)
			(xy 206.830821 -321.680607) (xy 206.820516 -321.669664) (xy 206.800909 -321.649462) (xy 206.767675 -321.604025)
			(xy 206.741995 -321.553929) (xy 206.724508 -321.50042) (xy 206.715648 -321.444827) (xy 206.715106 -321.41668)
			(xy 206.715604 -321.390031) (xy 206.723547 -321.337327) (xy 206.739257 -321.286397) (xy 206.762383 -321.238376)
			(xy 206.792407 -321.194339) (xy 206.828659 -321.155268) (xy 206.87033 -321.122037) (xy 206.916488 -321.095388)
			(xy 206.966102 -321.075916) (xy 207.018064 -321.064056) (xy 207.071214 -321.060073) (xy 207.124364 -321.064056)
			(xy 207.176326 -321.075916) (xy 207.22594 -321.095388) (xy 207.272098 -321.122037) (xy 207.313769 -321.155268)
			(xy 207.350021 -321.194339) (xy 207.380045 -321.238376) (xy 207.403171 -321.286397) (xy 207.418881 -321.337327)
			(xy 207.426824 -321.390031) (xy 207.427322 -321.41668) (xy 207.426791 -321.444828) (xy 207.417939 -321.500425)
			(xy 207.400453 -321.553937) (xy 207.374768 -321.604032) (xy 207.341522 -321.649464) (xy 207.321912 -321.669664)
			(xy 207.311629 -321.680608) (xy 207.297372 -321.70702) (xy 207.291409 -321.736436) (xy 207.294254 -321.766316)
			(xy 207.305662 -321.794078) (xy 207.324647 -321.817325) (xy 207.349571 -321.834049) (xy 207.378279 -321.842807)
			(xy 207.393286 -321.8434) (xy 210.192874 -321.8434) (xy 210.207892 -321.842866) (xy 210.23663 -321.834131)
			(xy 210.261581 -321.817411) (xy 210.280585 -321.794152) (xy 210.291997 -321.766368) (xy 210.294828 -321.736466)
			(xy 210.288834 -321.707035) (xy 210.274533 -321.680622) (xy 210.264248 -321.669664) (xy 210.244639 -321.649463)
			(xy 210.211403 -321.604027) (xy 210.185721 -321.553931) (xy 210.168232 -321.500421) (xy 210.159371 -321.444828)
			(xy 210.158838 -321.41668) (xy 210.159336 -321.390031) (xy 210.167279 -321.337327) (xy 210.182989 -321.286397)
			(xy 210.206115 -321.238376) (xy 210.236139 -321.194339) (xy 210.272391 -321.155268) (xy 210.314062 -321.122037)
			(xy 210.36022 -321.095388) (xy 210.409834 -321.075916) (xy 210.461796 -321.064056) (xy 210.514946 -321.060073)
			(xy 210.568096 -321.064056) (xy 210.620058 -321.075916) (xy 210.669672 -321.095388) (xy 210.71583 -321.122037)
			(xy 210.757501 -321.155268) (xy 210.793753 -321.194339) (xy 210.823777 -321.238376) (xy 210.846903 -321.286397)
			(xy 210.862613 -321.337327) (xy 210.870556 -321.390031) (xy 210.871054 -321.41668) (xy 210.870523 -321.444829)
			(xy 210.861672 -321.500425) (xy 210.844187 -321.553938) (xy 210.818503 -321.604035) (xy 210.78526 -321.649469)
			(xy 210.765644 -321.669664) (xy 210.755359 -321.680606) (xy 210.741098 -321.707016) (xy 210.735132 -321.736432)
			(xy 210.737976 -321.766312) (xy 210.749385 -321.794073) (xy 210.768374 -321.817318) (xy 210.7933 -321.834038)
			(xy 210.822011 -321.842789) (xy 210.837018 -321.8434) (xy 210.9724 -321.8434) (xy 211.3788 -321.437)
			(xy 211.3788 -319.3542) (xy 211.0486 -319.024) (xy 207.390746 -319.024) (xy 207.378636 -319.047519)
			(xy 207.348517 -319.091006) (xy 207.312296 -319.129559) (xy 207.270771 -319.16233) (xy 207.224856 -319.188598)
			(xy 207.175559 -319.207785) (xy 207.123967 -319.219469) (xy 207.071214 -319.223392) (xy 207.018461 -319.219469)
			(xy 206.966869 -319.207785) (xy 206.917572 -319.188598) (xy 206.871657 -319.16233) (xy 206.830132 -319.129559)
			(xy 206.793911 -319.091006) (xy 206.763792 -319.047519) (xy 206.751682 -319.024) (xy 205.56982 -319.024)
			(xy 205.554881 -319.024536) (xy 205.526288 -319.033201) (xy 205.501424 -319.049768) (xy 205.482415 -319.072819)
			(xy 205.470887 -319.100383) (xy 205.467825 -319.130104) (xy 205.473492 -319.159439) (xy 205.487403 -319.185881)
			(xy 205.49743 -319.196974) (xy 205.516491 -319.21707) (xy 205.548782 -319.262067) (xy 205.573711 -319.311525)
			(xy 205.590675 -319.364248) (xy 205.599264 -319.418963) (xy 205.599792 -319.446656) (xy 205.599294 -319.473305)
			(xy 205.591351 -319.526009) (xy 205.575641 -319.576939) (xy 205.552515 -319.62496) (xy 205.522491 -319.668997)
			(xy 205.486239 -319.708068) (xy 205.444568 -319.741299) (xy 205.44109 -319.743307) (xy 206.00415 -319.743307)
			(xy 206.00415 -319.690009) (xy 206.012093 -319.637305) (xy 206.027803 -319.586375) (xy 206.050929 -319.538354)
			(xy 206.080953 -319.494317) (xy 206.117205 -319.455246) (xy 206.158876 -319.422015) (xy 206.205034 -319.395366)
			(xy 206.254648 -319.375894) (xy 206.30661 -319.364034) (xy 206.35976 -319.360051) (xy 206.41291 -319.364034)
			(xy 206.464872 -319.375894) (xy 206.514486 -319.395366) (xy 206.560644 -319.422015) (xy 206.602315 -319.455246)
			(xy 206.638567 -319.494317) (xy 206.668591 -319.538354) (xy 206.691717 -319.586375) (xy 206.707427 -319.637305)
			(xy 206.71537 -319.690009) (xy 206.715868 -319.716658) (xy 206.71537 -319.743307) (xy 206.707427 -319.796011)
			(xy 206.691717 -319.846941) (xy 206.668591 -319.894962) (xy 206.638567 -319.938999) (xy 206.602315 -319.97807)
			(xy 206.560644 -320.011301) (xy 206.514486 -320.03795) (xy 206.464872 -320.057422) (xy 206.41291 -320.069282)
			(xy 206.35976 -320.073266) (xy 206.30661 -320.069282) (xy 206.254648 -320.057422) (xy 206.205034 -320.03795)
			(xy 206.158876 -320.011301) (xy 206.117205 -319.97807) (xy 206.080953 -319.938999) (xy 206.050929 -319.894962)
			(xy 206.027803 -319.846941) (xy 206.012093 -319.796011) (xy 206.00415 -319.743307) (xy 205.44109 -319.743307)
			(xy 205.39841 -319.767948) (xy 205.348796 -319.78742) (xy 205.296834 -319.79928) (xy 205.243684 -319.803264)
			(xy 205.190534 -319.79928) (xy 205.138572 -319.78742) (xy 205.088958 -319.767948) (xy 205.0428 -319.741299)
			(xy 205.001129 -319.708068) (xy 204.964877 -319.668997) (xy 204.934853 -319.62496) (xy 204.911727 -319.576939)
			(xy 204.896017 -319.526009) (xy 204.888074 -319.473305) (xy 204.887576 -319.446656) (xy 204.888127 -319.418967)
			(xy 204.896743 -319.364263) (xy 204.913713 -319.311548) (xy 204.938631 -319.262092) (xy 204.970895 -319.217083)
			(xy 204.989938 -319.196974) (xy 205.000068 -319.185958) (xy 205.014012 -319.159495) (xy 205.019696 -319.130127)
			(xy 205.016633 -319.100372) (xy 205.005087 -319.072779) (xy 204.986045 -319.04971) (xy 204.96114 -319.033143)
			(xy 204.932504 -319.024497) (xy 204.917548 -319.024) (xy 199.846946 -319.024) (xy 199.834836 -319.047519)
			(xy 199.804717 -319.091006) (xy 199.768496 -319.129559) (xy 199.726971 -319.16233) (xy 199.681056 -319.188598)
			(xy 199.631759 -319.207785) (xy 199.580167 -319.219469) (xy 199.527414 -319.223392) (xy 199.474661 -319.219469)
			(xy 199.423069 -319.207785) (xy 199.373772 -319.188598) (xy 199.327857 -319.16233) (xy 199.286332 -319.129559)
			(xy 199.250111 -319.091006) (xy 199.219992 -319.047519) (xy 199.207882 -319.024) (xy 198.101458 -319.024)
			(xy 198.086401 -319.024548) (xy 198.057598 -319.033339) (xy 198.032608 -319.050145) (xy 198.013604 -319.073506)
			(xy 198.002235 -319.101392) (xy 197.99949 -319.131382) (xy 198.005606 -319.160869) (xy 198.012304 -319.174368)
			(xy 198.026038 -319.200701) (xy 198.045507 -319.256805) (xy 198.05539 -319.315363) (xy 198.055992 -319.345056)
			(xy 198.055494 -319.371705) (xy 198.047551 -319.424409) (xy 198.031841 -319.475339) (xy 198.008715 -319.52336)
			(xy 197.978691 -319.567397) (xy 197.942439 -319.606468) (xy 197.900768 -319.639699) (xy 197.85461 -319.666348)
			(xy 197.804996 -319.68582) (xy 197.753034 -319.69768) (xy 197.699884 -319.701664) (xy 197.646734 -319.69768)
			(xy 197.594772 -319.68582) (xy 197.545158 -319.666348) (xy 197.499 -319.639699) (xy 197.457329 -319.606468)
			(xy 197.421077 -319.567397) (xy 197.391053 -319.52336) (xy 197.367927 -319.475339) (xy 197.352217 -319.424409)
			(xy 197.344274 -319.371705) (xy 197.343776 -319.345056) (xy 197.344397 -319.315366) (xy 197.354294 -319.256815)
			(xy 197.373759 -319.200714) (xy 197.387464 -319.174368) (xy 197.394217 -319.16089) (xy 197.400339 -319.131389)
			(xy 197.397593 -319.101384) (xy 197.386217 -319.073484) (xy 197.3672 -319.050113) (xy 197.342195 -319.033303)
			(xy 197.313375 -319.024514) (xy 197.29831 -319.024) (xy 194.95897 -319.024) (xy 194.950588 -319.06464)
			(xy 194.944706 -319.091137) (xy 194.925995 -319.142084) (xy 194.899768 -319.189602) (xy 194.866633 -319.232588)
			(xy 194.827358 -319.270048) (xy 194.782854 -319.301114) (xy 194.73415 -319.325066) (xy 194.682375 -319.341349)
			(xy 194.628729 -319.349586) (xy 194.574455 -319.349586) (xy 194.520809 -319.341349) (xy 194.469034 -319.325066)
			(xy 194.42033 -319.301114) (xy 194.375826 -319.270048) (xy 194.336551 -319.232588) (xy 194.303416 -319.189602)
			(xy 194.277189 -319.142084) (xy 194.258478 -319.091137) (xy 194.252596 -319.06464) (xy 194.244214 -319.024)
			(xy 192.315592 -319.024) (xy 192.303482 -319.047519) (xy 192.273363 -319.091006) (xy 192.237142 -319.129559)
			(xy 192.195617 -319.16233) (xy 192.149702 -319.188598) (xy 192.100405 -319.207785) (xy 192.048813 -319.219469)
			(xy 191.99606 -319.223392) (xy 191.943307 -319.219469) (xy 191.891715 -319.207785) (xy 191.842418 -319.188598)
			(xy 191.796503 -319.16233) (xy 191.754978 -319.129559) (xy 191.718757 -319.091006) (xy 191.688638 -319.047519)
			(xy 191.676528 -319.024) (xy 190.498476 -319.024) (xy 190.484764 -319.024478) (xy 190.458343 -319.031839)
			(xy 190.434836 -319.045968) (xy 190.41594 -319.065846) (xy 190.403017 -319.090037) (xy 190.397003 -319.116796)
			(xy 190.398329 -319.14419) (xy 190.40221 -319.15735) (xy 190.41055 -319.184467) (xy 190.419481 -319.24049)
			(xy 190.41999 -319.268856) (xy 190.419492 -319.295505) (xy 190.411549 -319.348209) (xy 190.395839 -319.399139)
			(xy 190.372713 -319.44716) (xy 190.342689 -319.491197) (xy 190.306437 -319.530268) (xy 190.264766 -319.563499)
			(xy 190.218608 -319.590148) (xy 190.168994 -319.60962) (xy 190.117032 -319.62148) (xy 190.063882 -319.625464)
			(xy 190.010732 -319.62148) (xy 189.95877 -319.60962) (xy 189.909156 -319.590148) (xy 189.862998 -319.563499)
			(xy 189.821327 -319.530268) (xy 189.785075 -319.491197) (xy 189.755051 -319.44716) (xy 189.731925 -319.399139)
			(xy 189.716215 -319.348209) (xy 189.708272 -319.295505) (xy 189.707774 -319.268856) (xy 189.708304 -319.240492)
			(xy 189.717233 -319.184471) (xy 189.725554 -319.15735) (xy 189.729413 -319.144184) (xy 189.730738 -319.11679)
			(xy 189.724724 -319.090032) (xy 189.711806 -319.06584) (xy 189.692916 -319.045958) (xy 189.669415 -319.03182)
			(xy 189.643 -319.024446) (xy 189.629288 -319.024) (xy 184.759346 -319.024) (xy 184.747236 -319.047519)
			(xy 184.717117 -319.091006) (xy 184.680896 -319.129559) (xy 184.639371 -319.16233) (xy 184.593456 -319.188598)
			(xy 184.544159 -319.207785) (xy 184.492567 -319.219469) (xy 184.439814 -319.223392) (xy 184.387061 -319.219469)
			(xy 184.335469 -319.207785) (xy 184.286172 -319.188598) (xy 184.240257 -319.16233) (xy 184.198732 -319.129559)
			(xy 184.162511 -319.091006) (xy 184.132392 -319.047519) (xy 184.120282 -319.024) (xy 183.063134 -319.024)
			(xy 183.048973 -319.024459) (xy 183.021738 -319.032229) (xy 182.997684 -319.04718) (xy 182.978662 -319.068162)
			(xy 182.966133 -319.093562) (xy 182.961063 -319.121426) (xy 182.96384 -319.149611) (xy 182.968646 -319.162938)
			(xy 182.976582 -319.183913) (xy 182.987757 -319.227345) (xy 182.993411 -319.271833) (xy 182.993792 -319.294256)
			(xy 182.993294 -319.320905) (xy 182.985351 -319.373609) (xy 182.969641 -319.424539) (xy 182.946515 -319.47256)
			(xy 182.916491 -319.516597) (xy 182.880239 -319.555668) (xy 182.838568 -319.588899) (xy 182.79241 -319.615548)
			(xy 182.742796 -319.63502) (xy 182.690834 -319.64688) (xy 182.637684 -319.650864) (xy 182.584534 -319.64688)
			(xy 182.532572 -319.63502) (xy 182.482958 -319.615548) (xy 182.4368 -319.588899) (xy 182.395129 -319.555668)
			(xy 182.358877 -319.516597) (xy 182.328853 -319.47256) (xy 182.305727 -319.424539) (xy 182.290017 -319.373609)
			(xy 182.282074 -319.320905) (xy 182.281576 -319.294256) (xy 182.281909 -319.271829) (xy 182.287543 -319.227331)
			(xy 182.298739 -319.183898) (xy 182.306722 -319.162938) (xy 182.311493 -319.1496) (xy 182.314266 -319.121419)
			(xy 182.309197 -319.09356) (xy 182.296675 -319.068163) (xy 182.277662 -319.047179) (xy 182.253618 -319.032221)
			(xy 182.226392 -319.024439) (xy 182.212234 -319.024) (xy 179.905152 -319.024) (xy 179.891036 -319.02441)
			(xy 179.86386 -319.032052) (xy 179.839819 -319.046848) (xy 179.820753 -319.067667) (xy 179.808122 -319.092913)
			(xy 179.802893 -319.120654) (xy 179.803806 -319.134744) (xy 179.80533 -319.167002) (xy 179.804832 -319.193651)
			(xy 179.796889 -319.246355) (xy 179.781179 -319.297285) (xy 179.758053 -319.345306) (xy 179.728029 -319.389343)
			(xy 179.691777 -319.428414) (xy 179.650106 -319.461645) (xy 179.603948 -319.488294) (xy 179.554334 -319.507766)
			(xy 179.502372 -319.519626) (xy 179.449222 -319.52361) (xy 179.396072 -319.519626) (xy 179.34411 -319.507766)
			(xy 179.294496 -319.488294) (xy 179.248338 -319.461645) (xy 179.206667 -319.428414) (xy 179.170415 -319.389343)
			(xy 179.140391 -319.345306) (xy 179.117265 -319.297285) (xy 179.101555 -319.246355) (xy 179.093612 -319.193651)
			(xy 179.093114 -319.167002) (xy 179.094638 -319.134744) (xy 179.095439 -319.120664) (xy 179.090178 -319.092968)
			(xy 179.077548 -319.067764) (xy 179.05851 -319.046972) (xy 179.034514 -319.032174) (xy 179.007388 -319.024498)
			(xy 178.993292 -319.024) (xy 177.215546 -319.024) (xy 177.203436 -319.047519) (xy 177.173317 -319.091006)
			(xy 177.137096 -319.129559) (xy 177.095571 -319.16233) (xy 177.049656 -319.188598) (xy 177.000359 -319.207785)
			(xy 176.948767 -319.219469) (xy 176.896014 -319.223392) (xy 176.843261 -319.219469) (xy 176.791669 -319.207785)
			(xy 176.742372 -319.188598) (xy 176.696457 -319.16233) (xy 176.654932 -319.129559) (xy 176.618711 -319.091006)
			(xy 176.588592 -319.047519) (xy 176.576482 -319.024) (xy 175.419258 -319.024) (xy 175.405548 -319.02448)
			(xy 175.379131 -319.031844) (xy 175.355629 -319.045974) (xy 175.336736 -319.065851) (xy 175.323816 -319.09004)
			(xy 175.317803 -319.116795) (xy 175.319129 -319.144186) (xy 175.322992 -319.15735) (xy 175.33133 -319.184468)
			(xy 175.340259 -319.24049) (xy 175.340772 -319.268856) (xy 175.340274 -319.295505) (xy 175.332331 -319.348209)
			(xy 175.316621 -319.399139) (xy 175.293495 -319.44716) (xy 175.263471 -319.491197) (xy 175.227219 -319.530268)
			(xy 175.185548 -319.563499) (xy 175.13939 -319.590148) (xy 175.089776 -319.60962) (xy 175.037814 -319.62148)
			(xy 174.984664 -319.625464) (xy 174.931514 -319.62148) (xy 174.879552 -319.60962) (xy 174.829938 -319.590148)
			(xy 174.78378 -319.563499) (xy 174.742109 -319.530268) (xy 174.705857 -319.491197) (xy 174.675833 -319.44716)
			(xy 174.652707 -319.399139) (xy 174.636997 -319.348209) (xy 174.629054 -319.295505) (xy 174.628556 -319.268856)
			(xy 174.629086 -319.240492) (xy 174.638014 -319.184471) (xy 174.646336 -319.15735) (xy 174.650195 -319.144185)
			(xy 174.65152 -319.116793) (xy 174.645507 -319.090036) (xy 174.632588 -319.065845) (xy 174.613697 -319.045965)
			(xy 174.590196 -319.031831) (xy 174.563781 -319.024461) (xy 174.55007 -319.024) (xy 169.671746 -319.024)
			(xy 169.659636 -319.047519) (xy 169.629517 -319.091006) (xy 169.593296 -319.129559) (xy 169.551771 -319.16233)
			(xy 169.505856 -319.188598) (xy 169.456559 -319.207785) (xy 169.404967 -319.219469) (xy 169.352214 -319.223392)
			(xy 169.299461 -319.219469) (xy 169.247869 -319.207785) (xy 169.198572 -319.188598) (xy 169.152657 -319.16233)
			(xy 169.111132 -319.129559) (xy 169.074911 -319.091006) (xy 169.044792 -319.047519) (xy 169.032682 -319.024)
			(xy 167.85082 -319.024) (xy 167.835881 -319.024536) (xy 167.807288 -319.033201) (xy 167.782424 -319.049768)
			(xy 167.763415 -319.072819) (xy 167.751887 -319.100383) (xy 167.748825 -319.130104) (xy 167.754492 -319.159439)
			(xy 167.768403 -319.185881) (xy 167.77843 -319.196974) (xy 167.797491 -319.21707) (xy 167.829782 -319.262067)
			(xy 167.854711 -319.311525) (xy 167.871675 -319.364248) (xy 167.880264 -319.418963) (xy 167.880792 -319.446656)
			(xy 167.880294 -319.473305) (xy 167.872351 -319.526009) (xy 167.856641 -319.576939) (xy 167.833515 -319.62496)
			(xy 167.803491 -319.668997) (xy 167.767239 -319.708068) (xy 167.725568 -319.741299) (xy 167.67941 -319.767948)
			(xy 167.629796 -319.78742) (xy 167.577834 -319.79928) (xy 167.524684 -319.803264) (xy 167.471534 -319.79928)
			(xy 167.419572 -319.78742) (xy 167.369958 -319.767948) (xy 167.3238 -319.741299) (xy 167.282129 -319.708068)
			(xy 167.245877 -319.668997) (xy 167.215853 -319.62496) (xy 167.192727 -319.576939) (xy 167.177017 -319.526009)
			(xy 167.169074 -319.473305) (xy 167.168576 -319.446656) (xy 167.169127 -319.418967) (xy 167.177743 -319.364263)
			(xy 167.194713 -319.311548) (xy 167.219631 -319.262092) (xy 167.251895 -319.217083) (xy 167.270938 -319.196974)
			(xy 167.281068 -319.185958) (xy 167.295012 -319.159495) (xy 167.300696 -319.130127) (xy 167.297633 -319.100372)
			(xy 167.286087 -319.072779) (xy 167.267045 -319.04971) (xy 167.24214 -319.033143) (xy 167.213504 -319.024497)
			(xy 167.198548 -319.024) (xy 160.263078 -319.024) (xy 160.250968 -319.047519) (xy 160.220849 -319.091006)
			(xy 160.184628 -319.129559) (xy 160.143103 -319.16233) (xy 160.097188 -319.188598) (xy 160.047891 -319.207785)
			(xy 159.996299 -319.219469) (xy 159.943546 -319.223392) (xy 159.890793 -319.219469) (xy 159.839201 -319.207785)
			(xy 159.789904 -319.188598) (xy 159.743989 -319.16233) (xy 159.702464 -319.129559) (xy 159.666243 -319.091006)
			(xy 159.636124 -319.047519) (xy 159.624014 -319.024) (xy 159.5374 -319.024) (xy 159.0294 -319.532)
			(xy 159.0294 -319.7045) (xy 160.733434 -319.7045) (xy 160.737418 -319.651342) (xy 160.74928 -319.59937)
			(xy 160.768755 -319.549748) (xy 160.795409 -319.503582) (xy 160.828646 -319.461905) (xy 160.867723 -319.425647)
			(xy 160.911768 -319.395618) (xy 160.959797 -319.372488) (xy 161.010736 -319.356776) (xy 161.063448 -319.348831)
			(xy 161.090102 -319.348358) (xy 161.117532 -319.348869) (xy 161.171746 -319.357265) (xy 161.224032 -319.373872)
			(xy 161.273153 -319.3983) (xy 161.317949 -319.429969) (xy 161.338006 -319.448688) (xy 161.348894 -319.458555)
			(xy 161.374938 -319.472133) (xy 161.40377 -319.47773) (xy 161.433002 -319.474884) (xy 161.460213 -319.46383)
			(xy 161.483148 -319.445483) (xy 161.49193 -319.433702) (xy 161.508721 -319.410554) (xy 161.548474 -319.369449)
			(xy 161.594284 -319.335224) (xy 161.644974 -319.308759) (xy 161.699242 -319.290733) (xy 161.755692 -319.281609)
			(xy 161.784284 -319.281048) (xy 161.812264 -319.281656) (xy 161.867537 -319.290407) (xy 161.92076 -319.307696)
			(xy 161.970623 -319.333099) (xy 162.015899 -319.365988) (xy 162.055473 -319.405555) (xy 162.08837 -319.450826)
			(xy 162.113781 -319.500685) (xy 162.131079 -319.553905) (xy 162.13984 -319.609176) (xy 162.140392 -319.637156)
			(xy 162.1399 -319.664593) (xy 162.131468 -319.718815) (xy 162.114828 -319.771104) (xy 162.090372 -319.820227)
			(xy 162.058678 -319.865022) (xy 162.020495 -319.904432) (xy 161.998914 -319.921382) (xy 161.987053 -319.931001)
			(xy 161.969233 -319.955782) (xy 161.959524 -319.98472) (xy 161.958792 -320.015235) (xy 161.967103 -320.044606)
			(xy 161.983716 -320.070212) (xy 161.995104 -320.080386) (xy 162.014738 -320.097394) (xy 162.049329 -320.136147)
			(xy 162.077926 -320.179512) (xy 162.099921 -320.22657) (xy 162.113822 -320.272897) (xy 164.15765 -320.272897)
			(xy 164.15765 -320.219599) (xy 164.165593 -320.166895) (xy 164.181303 -320.115965) (xy 164.204429 -320.067944)
			(xy 164.234453 -320.023907) (xy 164.270705 -319.984836) (xy 164.312376 -319.951605) (xy 164.358534 -319.924956)
			(xy 164.408148 -319.905484) (xy 164.46011 -319.893624) (xy 164.51326 -319.889641) (xy 164.56641 -319.893624)
			(xy 164.618372 -319.905484) (xy 164.667887 -319.924917) (xy 168.46041 -319.924917) (xy 168.46041 -319.871619)
			(xy 168.468353 -319.818915) (xy 168.484063 -319.767985) (xy 168.507189 -319.719964) (xy 168.537213 -319.675927)
			(xy 168.573465 -319.636856) (xy 168.615136 -319.603625) (xy 168.661294 -319.576976) (xy 168.710908 -319.557504)
			(xy 168.76287 -319.545644) (xy 168.81602 -319.541661) (xy 168.86917 -319.545644) (xy 168.886086 -319.549505)
			(xy 171.360074 -319.549505) (xy 171.360074 -319.496207) (xy 171.368017 -319.443503) (xy 171.383727 -319.392573)
			(xy 171.406853 -319.344552) (xy 171.436877 -319.300515) (xy 171.473129 -319.261444) (xy 171.5148 -319.228213)
			(xy 171.560958 -319.201564) (xy 171.610572 -319.182092) (xy 171.662534 -319.170232) (xy 171.715684 -319.166249)
			(xy 171.768834 -319.170232) (xy 171.820796 -319.182092) (xy 171.87041 -319.201564) (xy 171.916568 -319.228213)
			(xy 171.958239 -319.261444) (xy 171.994491 -319.300515) (xy 172.024515 -319.344552) (xy 172.047641 -319.392573)
			(xy 172.063351 -319.443503) (xy 172.071294 -319.496207) (xy 172.071792 -319.522856) (xy 172.071294 -319.549505)
			(xy 172.063351 -319.602209) (xy 172.047641 -319.653139) (xy 172.024515 -319.70116) (xy 171.99578 -319.743307)
			(xy 183.46419 -319.743307) (xy 183.46419 -319.690009) (xy 183.472133 -319.637305) (xy 183.487843 -319.586375)
			(xy 183.510969 -319.538354) (xy 183.540993 -319.494317) (xy 183.577245 -319.455246) (xy 183.618916 -319.422015)
			(xy 183.665074 -319.395366) (xy 183.714688 -319.375894) (xy 183.76665 -319.364034) (xy 183.8198 -319.360051)
			(xy 183.87295 -319.364034) (xy 183.924912 -319.375894) (xy 183.974526 -319.395366) (xy 184.020684 -319.422015)
			(xy 184.062355 -319.455246) (xy 184.098607 -319.494317) (xy 184.128631 -319.538354) (xy 184.151757 -319.586375)
			(xy 184.167467 -319.637305) (xy 184.17541 -319.690009) (xy 184.175908 -319.716658) (xy 184.17541 -319.743307)
			(xy 184.167467 -319.796011) (xy 184.151757 -319.846941) (xy 184.128631 -319.894962) (xy 184.12033 -319.907137)
			(xy 198.55941 -319.907137) (xy 198.55941 -319.853839) (xy 198.567353 -319.801135) (xy 198.583063 -319.750205)
			(xy 198.606189 -319.702184) (xy 198.636213 -319.658147) (xy 198.672465 -319.619076) (xy 198.714136 -319.585845)
			(xy 198.760294 -319.559196) (xy 198.809908 -319.539724) (xy 198.86187 -319.527864) (xy 198.91502 -319.523881)
			(xy 198.96817 -319.527864) (xy 199.020132 -319.539724) (xy 199.069746 -319.559196) (xy 199.115904 -319.585845)
			(xy 199.157575 -319.619076) (xy 199.193827 -319.658147) (xy 199.223851 -319.702184) (xy 199.246977 -319.750205)
			(xy 199.262687 -319.801135) (xy 199.27063 -319.853839) (xy 199.271128 -319.880488) (xy 199.27063 -319.907137)
			(xy 199.262687 -319.959841) (xy 199.246977 -320.010771) (xy 199.223851 -320.058792) (xy 199.193827 -320.102829)
			(xy 199.157575 -320.1419) (xy 199.115904 -320.175131) (xy 199.069746 -320.20178) (xy 199.020132 -320.221252)
			(xy 198.96817 -320.233112) (xy 198.91502 -320.237096) (xy 198.86187 -320.233112) (xy 198.809908 -320.221252)
			(xy 198.760294 -320.20178) (xy 198.714136 -320.175131) (xy 198.672465 -320.1419) (xy 198.636213 -320.102829)
			(xy 198.606189 -320.058792) (xy 198.583063 -320.010771) (xy 198.567353 -319.959841) (xy 198.55941 -319.907137)
			(xy 184.12033 -319.907137) (xy 184.098607 -319.938999) (xy 184.062355 -319.97807) (xy 184.020684 -320.011301)
			(xy 183.974526 -320.03795) (xy 183.924912 -320.057422) (xy 183.87295 -320.069282) (xy 183.8198 -320.073266)
			(xy 183.76665 -320.069282) (xy 183.714688 -320.057422) (xy 183.665074 -320.03795) (xy 183.618916 -320.011301)
			(xy 183.577245 -319.97807) (xy 183.540993 -319.938999) (xy 183.510969 -319.894962) (xy 183.487843 -319.846941)
			(xy 183.472133 -319.796011) (xy 183.46419 -319.743307) (xy 171.99578 -319.743307) (xy 171.994491 -319.745197)
			(xy 171.958239 -319.784268) (xy 171.916568 -319.817499) (xy 171.87041 -319.844148) (xy 171.820796 -319.86362)
			(xy 171.768834 -319.87548) (xy 171.715684 -319.879464) (xy 171.662534 -319.87548) (xy 171.610572 -319.86362)
			(xy 171.560958 -319.844148) (xy 171.5148 -319.817499) (xy 171.473129 -319.784268) (xy 171.436877 -319.745197)
			(xy 171.406853 -319.70116) (xy 171.383727 -319.653139) (xy 171.368017 -319.602209) (xy 171.360074 -319.549505)
			(xy 168.886086 -319.549505) (xy 168.921132 -319.557504) (xy 168.970746 -319.576976) (xy 169.016904 -319.603625)
			(xy 169.058575 -319.636856) (xy 169.094827 -319.675927) (xy 169.124851 -319.719964) (xy 169.147977 -319.767985)
			(xy 169.163687 -319.818915) (xy 169.17163 -319.871619) (xy 169.172128 -319.898268) (xy 169.17163 -319.924917)
			(xy 169.163687 -319.977621) (xy 169.147977 -320.028551) (xy 169.124851 -320.076572) (xy 169.094827 -320.120609)
			(xy 169.058575 -320.15968) (xy 169.016904 -320.192911) (xy 168.970746 -320.21956) (xy 168.921132 -320.239032)
			(xy 168.86917 -320.250892) (xy 168.81602 -320.254876) (xy 168.76287 -320.250892) (xy 168.710908 -320.239032)
			(xy 168.661294 -320.21956) (xy 168.615136 -320.192911) (xy 168.573465 -320.15968) (xy 168.537213 -320.120609)
			(xy 168.507189 -320.076572) (xy 168.484063 -320.028551) (xy 168.468353 -319.977621) (xy 168.46041 -319.924917)
			(xy 164.667887 -319.924917) (xy 164.667986 -319.924956) (xy 164.714144 -319.951605) (xy 164.755815 -319.984836)
			(xy 164.792067 -320.023907) (xy 164.822091 -320.067944) (xy 164.845217 -320.115965) (xy 164.860927 -320.166895)
			(xy 164.86887 -320.219599) (xy 164.869368 -320.246248) (xy 164.86887 -320.272897) (xy 164.860927 -320.325601)
			(xy 164.845217 -320.376531) (xy 164.822091 -320.424552) (xy 164.792067 -320.468589) (xy 164.755815 -320.50766)
			(xy 164.714144 -320.540891) (xy 164.667986 -320.56754) (xy 164.618372 -320.587012) (xy 164.56641 -320.598872)
			(xy 164.51326 -320.602856) (xy 164.46011 -320.598872) (xy 164.408148 -320.587012) (xy 164.358534 -320.56754)
			(xy 164.312376 -320.540891) (xy 164.270705 -320.50766) (xy 164.234453 -320.468589) (xy 164.204429 -320.424552)
			(xy 164.181303 -320.376531) (xy 164.165593 -320.325601) (xy 164.15765 -320.272897) (xy 162.113822 -320.272897)
			(xy 162.11485 -320.276323) (xy 162.122395 -320.327718) (xy 162.122866 -320.35369) (xy 162.122368 -320.380339)
			(xy 162.114425 -320.433043) (xy 162.098715 -320.483973) (xy 162.075589 -320.531994) (xy 162.045565 -320.576031)
			(xy 162.009313 -320.615102) (xy 161.967642 -320.648333) (xy 161.921484 -320.674982) (xy 161.87187 -320.694454)
			(xy 161.819908 -320.706314) (xy 161.766758 -320.710298) (xy 161.713608 -320.706314) (xy 161.661646 -320.694454)
			(xy 161.612032 -320.674982) (xy 161.565874 -320.648333) (xy 161.524203 -320.615102) (xy 161.487951 -320.576031)
			(xy 161.457927 -320.531994) (xy 161.434801 -320.483973) (xy 161.419091 -320.433043) (xy 161.411148 -320.380339)
			(xy 161.41065 -320.35369) (xy 161.411198 -320.326256) (xy 161.419621 -320.272037) (xy 161.436252 -320.21975)
			(xy 161.460697 -320.170627) (xy 161.49238 -320.12583) (xy 161.530552 -320.086416) (xy 161.552128 -320.069464)
			(xy 161.563948 -320.059796) (xy 161.581779 -320.035031) (xy 161.591498 -320.006104) (xy 161.592238 -319.975596)
			(xy 161.583933 -319.946231) (xy 161.567324 -319.92063) (xy 161.555938 -319.91046) (xy 161.53638 -319.892934)
			(xy 161.525495 -319.883068) (xy 161.499449 -319.869503) (xy 161.470619 -319.863912) (xy 161.44139 -319.86676)
			(xy 161.414181 -319.877808) (xy 161.391242 -319.896145) (xy 161.382456 -319.90792) (xy 161.365619 -319.931033)
			(xy 161.325874 -319.972138) (xy 161.280073 -320.006366) (xy 161.229393 -320.032837) (xy 161.175134 -320.050871)
			(xy 161.118691 -320.060006) (xy 161.090102 -320.060574) (xy 161.063448 -320.060169) (xy 161.010736 -320.052224)
			(xy 160.959797 -320.036512) (xy 160.911768 -320.013382) (xy 160.867723 -319.983353) (xy 160.828646 -319.947095)
			(xy 160.795409 -319.905418) (xy 160.768755 -319.859252) (xy 160.74928 -319.80963) (xy 160.737418 -319.757658)
			(xy 160.733434 -319.7045) (xy 159.0294 -319.7045) (xy 159.0294 -320.762376) (xy 159.830008 -321.322954)
			(xy 159.842582 -321.331089) (xy 159.871037 -321.34038) (xy 159.900964 -321.341031) (xy 159.929796 -321.332986)
			(xy 159.955062 -321.316935) (xy 159.974596 -321.294253) (xy 159.986723 -321.266886) (xy 159.989012 -321.252088)
			(xy 159.992479 -321.227224) (xy 160.005499 -321.178739) (xy 160.025201 -321.132564) (xy 160.051195 -321.089615)
			(xy 160.082965 -321.050743) (xy 160.119881 -321.016721) (xy 160.16121 -320.988222) (xy 160.206133 -320.965812)
			(xy 160.229804 -320.957448) (xy 160.243124 -320.952557) (xy 160.266567 -320.936593) (xy 160.284706 -320.914789)
			(xy 160.29614 -320.888833) (xy 160.299982 -320.860732) (xy 160.295937 -320.832659) (xy 160.284317 -320.806786)
			(xy 160.275524 -320.79565) (xy 160.259877 -320.77632) (xy 160.233528 -320.734143) (xy 160.213302 -320.688711)
			(xy 160.199591 -320.640907) (xy 160.192661 -320.591661) (xy 160.192212 -320.566796) (xy 160.19271 -320.540147)
			(xy 160.200653 -320.487443) (xy 160.216363 -320.436513) (xy 160.239489 -320.388492) (xy 160.269513 -320.344455)
			(xy 160.305765 -320.305384) (xy 160.347436 -320.272153) (xy 160.393594 -320.245504) (xy 160.443208 -320.226032)
			(xy 160.49517 -320.214172) (xy 160.54832 -320.210189) (xy 160.60147 -320.214172) (xy 160.653432 -320.226032)
			(xy 160.703046 -320.245504) (xy 160.749204 -320.272153) (xy 160.790875 -320.305384) (xy 160.827127 -320.344455)
			(xy 160.857151 -320.388492) (xy 160.880277 -320.436513) (xy 160.895987 -320.487443) (xy 160.90393 -320.540147)
			(xy 160.904428 -320.566796) (xy 160.903894 -320.594603) (xy 160.895252 -320.649541) (xy 160.878178 -320.702469)
			(xy 160.853086 -320.7521) (xy 160.820585 -320.797229) (xy 160.781467 -320.836759) (xy 160.73668 -320.86973)
			(xy 160.687315 -320.89534) (xy 160.661096 -320.904616) (xy 160.647772 -320.909506) (xy 160.624321 -320.925472)
			(xy 160.606173 -320.947278) (xy 160.600021 -320.961237) (xy 167.63999 -320.961237) (xy 167.63999 -320.907939)
			(xy 167.647933 -320.855235) (xy 167.663643 -320.804305) (xy 167.686769 -320.756284) (xy 167.716793 -320.712247)
			(xy 167.753045 -320.673176) (xy 167.794716 -320.639945) (xy 167.840874 -320.613296) (xy 167.890488 -320.593824)
			(xy 167.94245 -320.581964) (xy 167.9956 -320.577981) (xy 168.04875 -320.581964) (xy 168.100712 -320.593824)
			(xy 168.150326 -320.613296) (xy 168.196484 -320.639945) (xy 168.238155 -320.673176) (xy 168.274407 -320.712247)
			(xy 168.304431 -320.756284) (xy 168.327557 -320.804305) (xy 168.343267 -320.855235) (xy 168.35121 -320.907939)
			(xy 168.351708 -320.934588) (xy 168.35121 -320.961237) (xy 168.343267 -321.013941) (xy 168.327557 -321.064871)
			(xy 168.304431 -321.112892) (xy 168.274407 -321.156929) (xy 168.258701 -321.173856) (xy 168.971976 -321.173856)
			(xy 168.97251 -321.146594) (xy 168.98082 -321.092708) (xy 168.997254 -321.04072) (xy 169.021427 -320.991848)
			(xy 169.052773 -320.947237) (xy 169.07129 -320.927222) (xy 169.081209 -320.916226) (xy 169.09478 -320.88992)
			(xy 169.100227 -320.860826) (xy 169.097091 -320.831392) (xy 169.085637 -320.804098) (xy 169.076624 -320.792348)
			(xy 169.061457 -320.773185) (xy 169.035972 -320.731484) (xy 169.016427 -320.68669) (xy 169.00319 -320.639645)
			(xy 168.996509 -320.591232) (xy 168.996106 -320.566796) (xy 168.996604 -320.540147) (xy 169.004547 -320.487443)
			(xy 169.020257 -320.436513) (xy 169.043383 -320.388492) (xy 169.073407 -320.344455) (xy 169.109659 -320.305384)
			(xy 169.15133 -320.272153) (xy 169.197488 -320.245504) (xy 169.247102 -320.226032) (xy 169.299064 -320.214172)
			(xy 169.352214 -320.210189) (xy 169.405364 -320.214172) (xy 169.457326 -320.226032) (xy 169.50694 -320.245504)
			(xy 169.553098 -320.272153) (xy 169.594769 -320.305384) (xy 169.631021 -320.344455) (xy 169.661045 -320.388492)
			(xy 169.684171 -320.436513) (xy 169.699881 -320.487443) (xy 169.707824 -320.540147) (xy 169.708322 -320.566796)
			(xy 169.707831 -320.593445) (xy 171.85131 -320.593445) (xy 171.85131 -320.540147) (xy 171.859253 -320.487443)
			(xy 171.874963 -320.436513) (xy 171.898089 -320.388492) (xy 171.928113 -320.344455) (xy 171.964365 -320.305384)
			(xy 172.006036 -320.272153) (xy 172.052194 -320.245504) (xy 172.101808 -320.226032) (xy 172.15377 -320.214172)
			(xy 172.20692 -320.210189) (xy 172.26007 -320.214172) (xy 172.312032 -320.226032) (xy 172.361646 -320.245504)
			(xy 172.407804 -320.272153) (xy 172.449475 -320.305384) (xy 172.485727 -320.344455) (xy 172.515751 -320.388492)
			(xy 172.534608 -320.427649) (xy 175.944883 -320.427649) (xy 175.950365 -320.373766) (xy 175.963943 -320.321333)
			(xy 175.985305 -320.271562) (xy 176.013958 -320.2256) (xy 176.04924 -320.184506) (xy 176.090338 -320.149229)
			(xy 176.136305 -320.120583) (xy 176.186079 -320.099228) (xy 176.238513 -320.085656) (xy 176.292397 -320.080182)
			(xy 176.346489 -320.08293) (xy 176.399542 -320.093838) (xy 176.45033 -320.112653) (xy 176.497684 -320.138943)
			(xy 176.54051 -320.172101) (xy 176.577821 -320.211361) (xy 176.608757 -320.255819) (xy 176.632604 -320.304449)
			(xy 176.648811 -320.356129) (xy 176.657006 -320.409667) (xy 176.657508 -320.436748) (xy 176.657214 -320.457191)
			(xy 176.6525 -320.497805) (xy 176.64811 -320.517774) (xy 176.64542 -320.531376) (xy 176.646629 -320.559064)
			(xy 176.649155 -320.5668) (xy 178.755764 -320.5668) (xy 178.759748 -320.513644) (xy 178.771609 -320.461676)
			(xy 178.791084 -320.412057) (xy 178.817737 -320.365894) (xy 178.850973 -320.32422) (xy 178.890049 -320.287964)
			(xy 178.934092 -320.257938) (xy 178.982119 -320.234812) (xy 179.033056 -320.219102) (xy 179.085766 -320.21116)
			(xy 179.112418 -320.210688) (xy 179.140505 -320.211212) (xy 179.195981 -320.220047) (xy 179.249383 -320.237479)
			(xy 179.299386 -320.263077) (xy 179.344753 -320.296206) (xy 179.384357 -320.336044) (xy 179.401216 -320.358516)
			(xy 179.409643 -320.369387) (xy 179.43112 -320.386554) (xy 179.456394 -320.397377) (xy 179.483639 -320.401074)
			(xy 179.510884 -320.397377) (xy 179.536158 -320.386554) (xy 179.557635 -320.369387) (xy 179.566062 -320.358516)
			(xy 179.582909 -320.336033) (xy 179.622506 -320.296183) (xy 179.667872 -320.263048) (xy 179.71788 -320.237451)
			(xy 179.771289 -320.220029) (xy 179.826771 -320.211213) (xy 179.85486 -320.210688) (xy 179.881513 -320.211166)
			(xy 179.934224 -320.219106) (xy 179.985162 -320.234813) (xy 180.033191 -320.257938) (xy 180.077236 -320.287963)
			(xy 180.116314 -320.324217) (xy 180.149551 -320.365892) (xy 180.176206 -320.412055) (xy 180.195682 -320.461675)
			(xy 180.207544 -320.513644) (xy 180.211528 -320.5668) (xy 180.209531 -320.593445) (xy 184.084204 -320.593445)
			(xy 184.084204 -320.540147) (xy 184.092147 -320.487443) (xy 184.107857 -320.436513) (xy 184.130983 -320.388492)
			(xy 184.161007 -320.344455) (xy 184.197259 -320.305384) (xy 184.23893 -320.272153) (xy 184.285088 -320.245504)
			(xy 184.334702 -320.226032) (xy 184.386664 -320.214172) (xy 184.439814 -320.210189) (xy 184.492964 -320.214172)
			(xy 184.544926 -320.226032) (xy 184.59454 -320.245504) (xy 184.640698 -320.272153) (xy 184.682369 -320.305384)
			(xy 184.718621 -320.344455) (xy 184.748645 -320.388492) (xy 184.771771 -320.436513) (xy 184.787481 -320.487443)
			(xy 184.795424 -320.540147) (xy 184.795922 -320.566796) (xy 184.795424 -320.593445) (xy 186.98971 -320.593445)
			(xy 186.98971 -320.540147) (xy 186.997653 -320.487443) (xy 187.013363 -320.436513) (xy 187.036489 -320.388492)
			(xy 187.066513 -320.344455) (xy 187.102765 -320.305384) (xy 187.144436 -320.272153) (xy 187.190594 -320.245504)
			(xy 187.240208 -320.226032) (xy 187.29217 -320.214172) (xy 187.34532 -320.210189) (xy 187.39847 -320.214172)
			(xy 187.450432 -320.226032) (xy 187.500046 -320.245504) (xy 187.546204 -320.272153) (xy 187.587875 -320.305384)
			(xy 187.624127 -320.344455) (xy 187.650679 -320.3834) (xy 190.905401 -320.3834) (xy 190.909383 -320.330252)
			(xy 190.921243 -320.27829) (xy 190.940715 -320.228677) (xy 190.967364 -320.18252) (xy 191.000594 -320.140851)
			(xy 191.039664 -320.104599) (xy 191.0837 -320.074576) (xy 191.13172 -320.051451) (xy 191.182649 -320.035741)
			(xy 191.235351 -320.027798) (xy 191.262 -320.0273) (xy 191.28869 -320.027759) (xy 191.341473 -320.035726)
			(xy 191.392475 -320.051483) (xy 191.440554 -320.074674) (xy 191.484633 -320.104783) (xy 191.523724 -320.141133)
			(xy 191.556952 -320.18291) (xy 191.583572 -320.229179) (xy 191.593724 -320.253868) (xy 191.599213 -320.266562)
			(xy 191.615757 -320.288704) (xy 191.637635 -320.305595) (xy 191.663243 -320.315997) (xy 191.690702 -320.319148)
			(xy 191.718 -320.314816) (xy 191.743135 -320.303318) (xy 191.753998 -320.294762) (xy 191.773344 -320.278968)
			(xy 191.81563 -320.252395) (xy 191.861211 -320.231986) (xy 191.909196 -320.21814) (xy 191.958643 -320.211128)
			(xy 191.983614 -320.210688) (xy 192.010262 -320.211195) (xy 192.062963 -320.21914) (xy 192.113892 -320.234851)
			(xy 192.16191 -320.257977) (xy 192.205945 -320.288001) (xy 192.245013 -320.324253) (xy 192.278243 -320.365923)
			(xy 192.30489 -320.412079) (xy 192.324361 -320.461692) (xy 192.336221 -320.513652) (xy 192.340204 -320.5668)
			(xy 192.338207 -320.593445) (xy 194.48271 -320.593445) (xy 194.48271 -320.540147) (xy 194.490653 -320.487443)
			(xy 194.506363 -320.436513) (xy 194.529489 -320.388492) (xy 194.559513 -320.344455) (xy 194.595765 -320.305384)
			(xy 194.637436 -320.272153) (xy 194.683594 -320.245504) (xy 194.733208 -320.226032) (xy 194.78517 -320.214172)
			(xy 194.83832 -320.210189) (xy 194.89147 -320.214172) (xy 194.943432 -320.226032) (xy 194.993046 -320.245504)
			(xy 195.039204 -320.272153) (xy 195.080875 -320.305384) (xy 195.117127 -320.344455) (xy 195.147151 -320.388492)
			(xy 195.170277 -320.436513) (xy 195.185987 -320.487443) (xy 195.19393 -320.540147) (xy 195.194428 -320.566796)
			(xy 195.19393 -320.593445) (xy 199.171804 -320.593445) (xy 199.171804 -320.540147) (xy 199.179747 -320.487443)
			(xy 199.195457 -320.436513) (xy 199.218583 -320.388492) (xy 199.248607 -320.344455) (xy 199.284859 -320.305384)
			(xy 199.32653 -320.272153) (xy 199.372688 -320.245504) (xy 199.422302 -320.226032) (xy 199.474264 -320.214172)
			(xy 199.527414 -320.210189) (xy 199.580564 -320.214172) (xy 199.632526 -320.226032) (xy 199.68214 -320.245504)
			(xy 199.728298 -320.272153) (xy 199.769969 -320.305384) (xy 199.806221 -320.344455) (xy 199.836245 -320.388492)
			(xy 199.859371 -320.436513) (xy 199.875081 -320.487443) (xy 199.883024 -320.540147) (xy 199.883522 -320.566796)
			(xy 199.883024 -320.593445) (xy 202.05191 -320.593445) (xy 202.05191 -320.540147) (xy 202.059853 -320.487443)
			(xy 202.075563 -320.436513) (xy 202.098689 -320.388492) (xy 202.128713 -320.344455) (xy 202.164965 -320.305384)
			(xy 202.206636 -320.272153) (xy 202.252794 -320.245504) (xy 202.302408 -320.226032) (xy 202.35437 -320.214172)
			(xy 202.40752 -320.210189) (xy 202.46067 -320.214172) (xy 202.512632 -320.226032) (xy 202.562246 -320.245504)
			(xy 202.608404 -320.272153) (xy 202.650075 -320.305384) (xy 202.686327 -320.344455) (xy 202.716351 -320.388492)
			(xy 202.739477 -320.436513) (xy 202.755187 -320.487443) (xy 202.76313 -320.540147) (xy 202.763628 -320.566796)
			(xy 202.76313 -320.593445) (xy 206.715604 -320.593445) (xy 206.715604 -320.540147) (xy 206.723547 -320.487443)
			(xy 206.739257 -320.436513) (xy 206.762383 -320.388492) (xy 206.792407 -320.344455) (xy 206.828659 -320.305384)
			(xy 206.87033 -320.272153) (xy 206.916488 -320.245504) (xy 206.966102 -320.226032) (xy 207.018064 -320.214172)
			(xy 207.071214 -320.210189) (xy 207.124364 -320.214172) (xy 207.176326 -320.226032) (xy 207.22594 -320.245504)
			(xy 207.272098 -320.272153) (xy 207.313769 -320.305384) (xy 207.350021 -320.344455) (xy 207.380045 -320.388492)
			(xy 207.403171 -320.436513) (xy 207.418881 -320.487443) (xy 207.426824 -320.540147) (xy 207.427322 -320.566796)
			(xy 207.426824 -320.593445) (xy 209.63889 -320.593445) (xy 209.63889 -320.540147) (xy 209.646833 -320.487443)
			(xy 209.662543 -320.436513) (xy 209.685669 -320.388492) (xy 209.715693 -320.344455) (xy 209.751945 -320.305384)
			(xy 209.793616 -320.272153) (xy 209.839774 -320.245504) (xy 209.889388 -320.226032) (xy 209.94135 -320.214172)
			(xy 209.9945 -320.210189) (xy 210.04765 -320.214172) (xy 210.099612 -320.226032) (xy 210.149226 -320.245504)
			(xy 210.195384 -320.272153) (xy 210.237055 -320.305384) (xy 210.273307 -320.344455) (xy 210.303331 -320.388492)
			(xy 210.326457 -320.436513) (xy 210.342167 -320.487443) (xy 210.35011 -320.540147) (xy 210.350608 -320.566796)
			(xy 210.35011 -320.593445) (xy 210.342167 -320.646149) (xy 210.326457 -320.697079) (xy 210.303331 -320.7451)
			(xy 210.273307 -320.789137) (xy 210.237055 -320.828208) (xy 210.195384 -320.861439) (xy 210.149226 -320.888088)
			(xy 210.099612 -320.90756) (xy 210.04765 -320.91942) (xy 209.9945 -320.923404) (xy 209.94135 -320.91942)
			(xy 209.889388 -320.90756) (xy 209.839774 -320.888088) (xy 209.793616 -320.861439) (xy 209.751945 -320.828208)
			(xy 209.715693 -320.789137) (xy 209.685669 -320.7451) (xy 209.662543 -320.697079) (xy 209.646833 -320.646149)
			(xy 209.63889 -320.593445) (xy 207.426824 -320.593445) (xy 207.418881 -320.646149) (xy 207.403171 -320.697079)
			(xy 207.380045 -320.7451) (xy 207.350021 -320.789137) (xy 207.313769 -320.828208) (xy 207.272098 -320.861439)
			(xy 207.22594 -320.888088) (xy 207.176326 -320.90756) (xy 207.124364 -320.91942) (xy 207.071214 -320.923404)
			(xy 207.018064 -320.91942) (xy 206.966102 -320.90756) (xy 206.916488 -320.888088) (xy 206.87033 -320.861439)
			(xy 206.828659 -320.828208) (xy 206.792407 -320.789137) (xy 206.762383 -320.7451) (xy 206.739257 -320.697079)
			(xy 206.723547 -320.646149) (xy 206.715604 -320.593445) (xy 202.76313 -320.593445) (xy 202.755187 -320.646149)
			(xy 202.739477 -320.697079) (xy 202.716351 -320.7451) (xy 202.686327 -320.789137) (xy 202.650075 -320.828208)
			(xy 202.608404 -320.861439) (xy 202.562246 -320.888088) (xy 202.512632 -320.90756) (xy 202.46067 -320.91942)
			(xy 202.40752 -320.923404) (xy 202.35437 -320.91942) (xy 202.302408 -320.90756) (xy 202.252794 -320.888088)
			(xy 202.206636 -320.861439) (xy 202.164965 -320.828208) (xy 202.128713 -320.789137) (xy 202.098689 -320.7451)
			(xy 202.075563 -320.697079) (xy 202.059853 -320.646149) (xy 202.05191 -320.593445) (xy 199.883024 -320.593445)
			(xy 199.875081 -320.646149) (xy 199.859371 -320.697079) (xy 199.836245 -320.7451) (xy 199.806221 -320.789137)
			(xy 199.769969 -320.828208) (xy 199.728298 -320.861439) (xy 199.68214 -320.888088) (xy 199.632526 -320.90756)
			(xy 199.580564 -320.91942) (xy 199.527414 -320.923404) (xy 199.474264 -320.91942) (xy 199.422302 -320.90756)
			(xy 199.372688 -320.888088) (xy 199.32653 -320.861439) (xy 199.284859 -320.828208) (xy 199.248607 -320.789137)
			(xy 199.218583 -320.7451) (xy 199.195457 -320.697079) (xy 199.179747 -320.646149) (xy 199.171804 -320.593445)
			(xy 195.19393 -320.593445) (xy 195.185987 -320.646149) (xy 195.170277 -320.697079) (xy 195.147151 -320.7451)
			(xy 195.117127 -320.789137) (xy 195.080875 -320.828208) (xy 195.039204 -320.861439) (xy 194.993046 -320.888088)
			(xy 194.943432 -320.90756) (xy 194.89147 -320.91942) (xy 194.83832 -320.923404) (xy 194.78517 -320.91942)
			(xy 194.733208 -320.90756) (xy 194.683594 -320.888088) (xy 194.637436 -320.861439) (xy 194.595765 -320.828208)
			(xy 194.559513 -320.789137) (xy 194.529489 -320.7451) (xy 194.506363 -320.697079) (xy 194.490653 -320.646149)
			(xy 194.48271 -320.593445) (xy 192.338207 -320.593445) (xy 192.336221 -320.619948) (xy 192.324361 -320.671908)
			(xy 192.30489 -320.721521) (xy 192.278243 -320.767677) (xy 192.245013 -320.809347) (xy 192.205945 -320.845599)
			(xy 192.16191 -320.875623) (xy 192.113892 -320.898749) (xy 192.062963 -320.91446) (xy 192.010262 -320.922405)
			(xy 191.983614 -320.922904) (xy 191.956924 -320.92243) (xy 191.904143 -320.914465) (xy 191.853141 -320.898711)
			(xy 191.805062 -320.875521) (xy 191.760983 -320.845415) (xy 191.721892 -320.809067) (xy 191.688663 -320.767291)
			(xy 191.662042 -320.721024) (xy 191.65189 -320.696336) (xy 191.646381 -320.683652) (xy 191.62984 -320.661511)
			(xy 191.607966 -320.64462) (xy 191.582363 -320.634216) (xy 191.554906 -320.631064) (xy 191.527611 -320.635394)
			(xy 191.502478 -320.646888) (xy 191.491616 -320.655442) (xy 191.472266 -320.67123) (xy 191.429981 -320.697804)
			(xy 191.3844 -320.718214) (xy 191.336417 -320.732062) (xy 191.28697 -320.739075) (xy 191.262 -320.739516)
			(xy 191.235351 -320.739002) (xy 191.182649 -320.731059) (xy 191.13172 -320.715349) (xy 191.0837 -320.692224)
			(xy 191.039664 -320.662201) (xy 191.000594 -320.625949) (xy 190.967364 -320.58428) (xy 190.940715 -320.538123)
			(xy 190.921243 -320.48851) (xy 190.909383 -320.436548) (xy 190.905401 -320.3834) (xy 187.650679 -320.3834)
			(xy 187.654151 -320.388492) (xy 187.677277 -320.436513) (xy 187.692987 -320.487443) (xy 187.70093 -320.540147)
			(xy 187.701428 -320.566796) (xy 187.70093 -320.593445) (xy 187.692987 -320.646149) (xy 187.677277 -320.697079)
			(xy 187.654151 -320.7451) (xy 187.624127 -320.789137) (xy 187.587875 -320.828208) (xy 187.546204 -320.861439)
			(xy 187.500046 -320.888088) (xy 187.450432 -320.90756) (xy 187.39847 -320.91942) (xy 187.34532 -320.923404)
			(xy 187.29217 -320.91942) (xy 187.240208 -320.90756) (xy 187.190594 -320.888088) (xy 187.144436 -320.861439)
			(xy 187.102765 -320.828208) (xy 187.066513 -320.789137) (xy 187.036489 -320.7451) (xy 187.013363 -320.697079)
			(xy 186.997653 -320.646149) (xy 186.98971 -320.593445) (xy 184.795424 -320.593445) (xy 184.787481 -320.646149)
			(xy 184.771771 -320.697079) (xy 184.748645 -320.7451) (xy 184.718621 -320.789137) (xy 184.682369 -320.828208)
			(xy 184.640698 -320.861439) (xy 184.59454 -320.888088) (xy 184.544926 -320.90756) (xy 184.492964 -320.91942)
			(xy 184.439814 -320.923404) (xy 184.386664 -320.91942) (xy 184.334702 -320.90756) (xy 184.285088 -320.888088)
			(xy 184.23893 -320.861439) (xy 184.197259 -320.828208) (xy 184.161007 -320.789137) (xy 184.130983 -320.7451)
			(xy 184.107857 -320.697079) (xy 184.092147 -320.646149) (xy 184.084204 -320.593445) (xy 180.209531 -320.593445)
			(xy 180.207544 -320.619956) (xy 180.195682 -320.671925) (xy 180.176206 -320.721545) (xy 180.149551 -320.767708)
			(xy 180.116314 -320.809383) (xy 180.077236 -320.845637) (xy 180.033191 -320.875662) (xy 179.985162 -320.898787)
			(xy 179.934224 -320.914494) (xy 179.881513 -320.922434) (xy 179.85486 -320.922904) (xy 179.826772 -320.922399)
			(xy 179.771295 -320.913561) (xy 179.717893 -320.896125) (xy 179.667889 -320.870523) (xy 179.622523 -320.837391)
			(xy 179.58292 -320.797549) (xy 179.566062 -320.775076) (xy 179.557662 -320.764161) (xy 179.536206 -320.746911)
			(xy 179.510917 -320.736031) (xy 179.483639 -320.732314) (xy 179.456361 -320.736031) (xy 179.431072 -320.746911)
			(xy 179.409616 -320.764161) (xy 179.401216 -320.775076) (xy 179.38438 -320.797567) (xy 179.344781 -320.837418)
			(xy 179.299413 -320.870552) (xy 179.249402 -320.896147) (xy 179.195992 -320.913568) (xy 179.140508 -320.922381)
			(xy 179.112418 -320.922904) (xy 179.085766 -320.92244) (xy 179.033056 -320.914498) (xy 178.982119 -320.898788)
			(xy 178.934092 -320.875662) (xy 178.890049 -320.845636) (xy 178.850973 -320.80938) (xy 178.817737 -320.767706)
			(xy 178.791084 -320.721543) (xy 178.771609 -320.671924) (xy 178.759748 -320.619956) (xy 178.755764 -320.5668)
			(xy 176.649155 -320.5668) (xy 176.655233 -320.58541) (xy 176.670598 -320.608477) (xy 176.691594 -320.626567)
			(xy 176.716679 -320.638353) (xy 176.744008 -320.642966) (xy 176.757838 -320.64198) (xy 176.795684 -320.639948)
			(xy 176.822766 -320.640481) (xy 176.876307 -320.64868) (xy 176.927988 -320.664894) (xy 176.976618 -320.688746)
			(xy 177.021075 -320.719688) (xy 177.060334 -320.757005) (xy 177.093489 -320.799836) (xy 177.119776 -320.847195)
			(xy 177.138587 -320.897988) (xy 177.149491 -320.951044) (xy 177.152233 -321.005139) (xy 177.146753 -321.059026)
			(xy 177.133175 -321.111461) (xy 177.111814 -321.161236) (xy 177.083161 -321.207202) (xy 177.047878 -321.248298)
			(xy 177.006779 -321.283578) (xy 176.960811 -321.312227) (xy 176.912771 -321.332839) (xy 179.978548 -321.332839)
			(xy 179.978548 -321.279541) (xy 179.986491 -321.226837) (xy 180.002201 -321.175907) (xy 180.025327 -321.127886)
			(xy 180.055351 -321.083849) (xy 180.091603 -321.044778) (xy 180.133274 -321.011547) (xy 180.179432 -320.984898)
			(xy 180.229046 -320.965426) (xy 180.281008 -320.953566) (xy 180.334158 -320.949583) (xy 180.387308 -320.953566)
			(xy 180.43927 -320.965426) (xy 180.488884 -320.984898) (xy 180.535042 -321.011547) (xy 180.576713 -321.044778)
			(xy 180.612965 -321.083849) (xy 180.642989 -321.127886) (xy 180.666115 -321.175907) (xy 180.681825 -321.226837)
			(xy 180.689768 -321.279541) (xy 180.690266 -321.30619) (xy 180.689768 -321.332839) (xy 180.681825 -321.385543)
			(xy 180.666115 -321.436473) (xy 180.642989 -321.484494) (xy 180.612965 -321.528531) (xy 180.576713 -321.567602)
			(xy 180.535042 -321.600833) (xy 180.488884 -321.627482) (xy 180.43927 -321.646954) (xy 180.387308 -321.658814)
			(xy 180.334158 -321.662798) (xy 180.281008 -321.658814) (xy 180.229046 -321.646954) (xy 180.179432 -321.627482)
			(xy 180.133274 -321.600833) (xy 180.091603 -321.567602) (xy 180.055351 -321.528531) (xy 180.025327 -321.484494)
			(xy 180.002201 -321.436473) (xy 179.986491 -321.385543) (xy 179.978548 -321.332839) (xy 176.912771 -321.332839)
			(xy 176.911035 -321.333584) (xy 176.858598 -321.347158) (xy 176.804711 -321.352634) (xy 176.750616 -321.349887)
			(xy 176.697561 -321.33898) (xy 176.646769 -321.320164) (xy 176.599413 -321.293874) (xy 176.556584 -321.260715)
			(xy 176.51927 -321.221453) (xy 176.488332 -321.176994) (xy 176.464483 -321.128362) (xy 176.448274 -321.07668)
			(xy 176.440078 -321.023138) (xy 176.439576 -320.996056) (xy 176.439871 -320.975613) (xy 176.444584 -320.934999)
			(xy 176.448974 -320.91503) (xy 176.451677 -320.90143) (xy 176.450469 -320.873738) (xy 176.441865 -320.84739)
			(xy 176.426498 -320.824321) (xy 176.405498 -320.80623) (xy 176.380409 -320.794446) (xy 176.353078 -320.789836)
			(xy 176.339246 -320.790824) (xy 176.3014 -320.792856) (xy 176.274319 -320.792302) (xy 176.220782 -320.7841)
			(xy 176.169104 -320.767886) (xy 176.120477 -320.744033) (xy 176.076024 -320.713091) (xy 176.036768 -320.675774)
			(xy 176.003617 -320.632944) (xy 175.977333 -320.585587) (xy 175.958524 -320.534795) (xy 175.947624 -320.481742)
			(xy 175.944883 -320.427649) (xy 172.534608 -320.427649) (xy 172.538877 -320.436513) (xy 172.554587 -320.487443)
			(xy 172.56253 -320.540147) (xy 172.563028 -320.566796) (xy 172.56253 -320.593445) (xy 172.554587 -320.646149)
			(xy 172.538877 -320.697079) (xy 172.515751 -320.7451) (xy 172.485727 -320.789137) (xy 172.449475 -320.828208)
			(xy 172.407804 -320.861439) (xy 172.361646 -320.888088) (xy 172.312032 -320.90756) (xy 172.26007 -320.91942)
			(xy 172.20692 -320.923404) (xy 172.15377 -320.91942) (xy 172.101808 -320.90756) (xy 172.052194 -320.888088)
			(xy 172.006036 -320.861439) (xy 171.964365 -320.828208) (xy 171.928113 -320.789137) (xy 171.898089 -320.7451)
			(xy 171.874963 -320.697079) (xy 171.859253 -320.646149) (xy 171.85131 -320.593445) (xy 169.707831 -320.593445)
			(xy 169.70782 -320.594059) (xy 169.699503 -320.647947) (xy 169.683061 -320.699935) (xy 169.658881 -320.748806)
			(xy 169.627528 -320.793416) (xy 169.609008 -320.81343) (xy 169.599135 -320.824464) (xy 169.58556 -320.850756)
			(xy 169.580104 -320.87984) (xy 169.583228 -320.909265) (xy 169.594668 -320.936554) (xy 169.603674 -320.948304)
			(xy 169.618819 -320.967484) (xy 169.644307 -321.009181) (xy 169.663856 -321.05397) (xy 169.677099 -321.101011)
			(xy 169.683786 -321.149421) (xy 169.684192 -321.173856) (xy 169.683694 -321.200505) (xy 169.675751 -321.253209)
			(xy 169.660041 -321.304139) (xy 169.648788 -321.327505) (xy 172.376074 -321.327505) (xy 172.376074 -321.274207)
			(xy 172.384017 -321.221503) (xy 172.399727 -321.170573) (xy 172.422853 -321.122552) (xy 172.452877 -321.078515)
			(xy 172.489129 -321.039444) (xy 172.5308 -321.006213) (xy 172.576958 -320.979564) (xy 172.626572 -320.960092)
			(xy 172.678534 -320.948232) (xy 172.731684 -320.944249) (xy 172.784834 -320.948232) (xy 172.836796 -320.960092)
			(xy 172.88641 -320.979564) (xy 172.932568 -321.006213) (xy 172.974239 -321.039444) (xy 173.010491 -321.078515)
			(xy 173.040515 -321.122552) (xy 173.063641 -321.170573) (xy 173.079351 -321.221503) (xy 173.087294 -321.274207)
			(xy 173.087792 -321.300856) (xy 173.087294 -321.327505) (xy 173.079351 -321.380209) (xy 173.063641 -321.431139)
			(xy 173.040515 -321.47916) (xy 173.010491 -321.523197) (xy 172.974239 -321.562268) (xy 172.932568 -321.595499)
			(xy 172.88641 -321.622148) (xy 172.836796 -321.64162) (xy 172.784834 -321.65348) (xy 172.731684 -321.657464)
			(xy 172.678534 -321.65348) (xy 172.626572 -321.64162) (xy 172.576958 -321.622148) (xy 172.5308 -321.595499)
			(xy 172.489129 -321.562268) (xy 172.452877 -321.523197) (xy 172.422853 -321.47916) (xy 172.399727 -321.431139)
			(xy 172.384017 -321.380209) (xy 172.376074 -321.327505) (xy 169.648788 -321.327505) (xy 169.636915 -321.35216)
			(xy 169.606891 -321.396197) (xy 169.570639 -321.435268) (xy 169.528968 -321.468499) (xy 169.48281 -321.495148)
			(xy 169.433196 -321.51462) (xy 169.381234 -321.52648) (xy 169.328084 -321.530464) (xy 169.274934 -321.52648)
			(xy 169.222972 -321.51462) (xy 169.173358 -321.495148) (xy 169.1272 -321.468499) (xy 169.085529 -321.435268)
			(xy 169.049277 -321.396197) (xy 169.019253 -321.35216) (xy 168.996127 -321.304139) (xy 168.980417 -321.253209)
			(xy 168.972474 -321.200505) (xy 168.971976 -321.173856) (xy 168.258701 -321.173856) (xy 168.238155 -321.196)
			(xy 168.196484 -321.229231) (xy 168.150326 -321.25588) (xy 168.100712 -321.275352) (xy 168.04875 -321.287212)
			(xy 167.9956 -321.291196) (xy 167.94245 -321.287212) (xy 167.890488 -321.275352) (xy 167.840874 -321.25588)
			(xy 167.794716 -321.229231) (xy 167.753045 -321.196) (xy 167.716793 -321.156929) (xy 167.686769 -321.112892)
			(xy 167.663643 -321.064871) (xy 167.647933 -321.013941) (xy 167.63999 -320.961237) (xy 160.600021 -320.961237)
			(xy 160.594732 -320.973239) (xy 160.590883 -321.001346) (xy 160.594923 -321.029427) (xy 160.60654 -321.05531)
			(xy 160.615376 -321.066414) (xy 160.631025 -321.085743) (xy 160.657378 -321.12792) (xy 160.677609 -321.173351)
			(xy 160.691325 -321.221155) (xy 160.698259 -321.270402) (xy 160.698688 -321.295268) (xy 160.698162 -321.323255)
			(xy 160.689391 -321.378538) (xy 160.672077 -321.431768) (xy 160.646646 -321.481632) (xy 160.613725 -321.526902)
			(xy 160.574124 -321.566461) (xy 160.528821 -321.599336) (xy 160.504124 -321.612514) (xy 160.491041 -321.619803)
			(xy 160.469483 -321.640569) (xy 160.454856 -321.666686) (xy 160.448411 -321.695917) (xy 160.450699 -321.725763)
			(xy 160.461526 -321.75367) (xy 160.479964 -321.777251) (xy 160.491932 -321.78625) (xy 160.573466 -321.8434)
		)
		(stroke
			(width 0)
			(type solid)
		)
		(fill yes)
		(layer "In2.Cu")
		(net "P3V3_AUX")
	)
	(gr_poly
		(pts
			(xy 61.608716 -197.53199) (xy 61.624166 -197.531458) (xy 61.653657 -197.522232) (xy 61.679032 -197.504599)
			(xy 61.697965 -197.480179) (xy 61.708719 -197.45121) (xy 61.710306 -197.420351) (xy 61.707014 -197.405244)
			(xy 61.706252 -197.402196) (xy 61.701386 -197.381261) (xy 61.696163 -197.338597) (xy 61.695838 -197.317106)
			(xy 61.695838 -197.313804) (xy 61.696534 -197.287291) (xy 61.70481 -197.234907) (xy 61.720764 -197.184329)
			(xy 61.744042 -197.136676) (xy 61.77413 -197.093002) (xy 61.810362 -197.054274) (xy 61.851937 -197.021347)
			(xy 61.897936 -196.99495) (xy 61.94734 -196.975666) (xy 61.999058 -196.963923) (xy 62.051946 -196.95998)
			(xy 62.104834 -196.963923) (xy 62.156552 -196.975666) (xy 62.205956 -196.99495) (xy 62.251955 -197.021347)
			(xy 62.29353 -197.054274) (xy 62.329762 -197.093002) (xy 62.35985 -197.136676) (xy 62.383128 -197.184329)
			(xy 62.399082 -197.234907) (xy 62.407358 -197.287291) (xy 62.408054 -197.313804) (xy 62.408054 -197.316852)
			(xy 62.407711 -197.338405) (xy 62.402492 -197.381194) (xy 62.39764 -197.402196) (xy 62.396878 -197.405244)
			(xy 62.393595 -197.420335) (xy 62.395258 -197.45116) (xy 62.406041 -197.480085) (xy 62.424962 -197.504476)
			(xy 62.450299 -197.522112) (xy 62.479742 -197.531386) (xy 62.495176 -197.53199) (xy 64.296036 -197.53199)
			(xy 64.296036 -197.112382) (xy 64.296535 -197.102226) (xy 64.304312 -197.083463) (xy 64.318677 -197.069103)
			(xy 64.337442 -197.061331) (xy 64.347598 -197.06082) (xy 65.747138 -197.06082) (xy 65.757292 -197.061321)
			(xy 65.776051 -197.069102) (xy 65.790409 -197.083465) (xy 65.798183 -197.102228) (xy 65.7987 -197.112382)
			(xy 65.7987 -197.53199) (xy 69.551804 -197.53199) (xy 69.566783 -197.531417) (xy 69.595431 -197.522648)
			(xy 69.62031 -197.505953) (xy 69.639282 -197.482765) (xy 69.650719 -197.455073) (xy 69.65364 -197.425255)
			(xy 69.647795 -197.39587) (xy 69.633684 -197.369441) (xy 69.623432 -197.358508) (xy 68.916042 -196.651118)
			(xy 68.898683 -196.633135) (xy 68.869271 -196.592725) (xy 68.846552 -196.548207) (xy 68.831085 -196.500681)
			(xy 68.823253 -196.451318) (xy 68.822824 -196.426328) (xy 68.822824 -195.413884) (xy 68.807891 -195.39046)
			(xy 68.784234 -195.340202) (xy 68.768122 -195.287042) (xy 68.759896 -195.232106) (xy 68.759324 -195.204334)
			(xy 68.759324 -195.203064) (xy 68.759881 -195.173204) (xy 68.769142 -195.114207) (xy 68.787478 -195.057372)
			(xy 68.814442 -195.004086) (xy 68.83146 -194.979544) (xy 68.840195 -194.967599) (xy 68.851027 -194.940075)
			(xy 68.853525 -194.910602) (xy 68.847478 -194.881648) (xy 68.833393 -194.855637) (xy 68.812451 -194.834749)
			(xy 68.786404 -194.820732) (xy 68.772024 -194.817238) (xy 68.743693 -194.81087) (xy 68.689235 -194.790716)
			(xy 68.638458 -194.76255) (xy 68.59253 -194.72702) (xy 68.552511 -194.684946) (xy 68.519324 -194.637298)
			(xy 68.493734 -194.585174) (xy 68.476331 -194.529777) (xy 68.467517 -194.472383) (xy 68.46697 -194.44335)
			(xy 68.467403 -194.417125) (xy 68.474582 -194.365168) (xy 68.488813 -194.314686) (xy 68.509827 -194.266629)
			(xy 68.537227 -194.221905) (xy 68.570497 -194.181357) (xy 68.609009 -194.14575) (xy 68.630292 -194.130422)
			(xy 68.640674 -194.121994) (xy 68.656988 -194.100817) (xy 68.667249 -194.076132) (xy 68.670754 -194.049631)
			(xy 68.667265 -194.023127) (xy 68.657018 -193.998436) (xy 68.640717 -193.977249) (xy 68.630292 -193.968878)
			(xy 68.609034 -193.95352) (xy 68.570535 -193.91791) (xy 68.537275 -193.877363) (xy 68.50988 -193.832644)
			(xy 68.488868 -193.784594) (xy 68.474633 -193.73412) (xy 68.467445 -193.682172) (xy 68.46697 -193.65595)
			(xy 68.467456 -193.628699) (xy 68.475212 -193.574751) (xy 68.490567 -193.522456) (xy 68.513209 -193.472879)
			(xy 68.542675 -193.427029) (xy 68.578366 -193.385838) (xy 68.619557 -193.350147) (xy 68.665407 -193.320681)
			(xy 68.714984 -193.298039) (xy 68.767279 -193.282684) (xy 68.821227 -193.274928) (xy 68.875729 -193.274928)
			(xy 68.929677 -193.282684) (xy 68.981972 -193.298039) (xy 69.031549 -193.320681) (xy 69.077399 -193.350147)
			(xy 69.11859 -193.385838) (xy 69.154281 -193.427029) (xy 69.183747 -193.472879) (xy 69.206389 -193.522456)
			(xy 69.221744 -193.574751) (xy 69.2295 -193.628699) (xy 69.229986 -193.65595) (xy 69.229553 -193.682175)
			(xy 69.222373 -193.73413) (xy 69.208141 -193.784612) (xy 69.187125 -193.832667) (xy 69.159723 -193.877388)
			(xy 69.126451 -193.917934) (xy 69.087937 -193.953537) (xy 69.066664 -193.968878) (xy 69.056299 -193.977308)
			(xy 69.040018 -193.99848) (xy 69.029784 -194.02315) (xy 69.026299 -194.04963) (xy 69.0298 -194.076109)
			(xy 69.040048 -194.100773) (xy 69.056342 -194.121935) (xy 69.066664 -194.130422) (xy 69.087924 -194.145779)
			(xy 69.126427 -194.181387) (xy 69.159691 -194.221933) (xy 69.187089 -194.266652) (xy 69.208104 -194.314702)
			(xy 69.222341 -194.365178) (xy 69.22953 -194.417128) (xy 69.229986 -194.44335) (xy 69.229909 -194.456088)
			(xy 69.228259 -194.48151) (xy 69.226684 -194.49415) (xy 69.221913 -194.525114) (xy 69.203578 -194.585018)
			(xy 69.175687 -194.641114) (xy 69.15785 -194.66687) (xy 69.148983 -194.678933) (xy 69.138027 -194.70678)
			(xy 69.135623 -194.736608) (xy 69.141978 -194.76585) (xy 69.156545 -194.791989) (xy 69.178071 -194.812776)
			(xy 69.204703 -194.826422) (xy 69.219318 -194.829684) (xy 69.247524 -194.836139) (xy 69.301715 -194.856417)
			(xy 69.352223 -194.884645) (xy 69.397889 -194.920176) (xy 69.437666 -194.962195) (xy 69.470642 -195.009739)
			(xy 69.496061 -195.061717) (xy 69.51334 -195.116938) (xy 69.522082 -195.174134) (xy 69.522594 -195.203064)
			(xy 69.52234 -195.20916) (xy 69.521427 -195.23632) (xy 69.51286 -195.289982) (xy 69.496763 -195.341885)
			(xy 69.473461 -195.390978) (xy 69.45884 -195.413884) (xy 69.45884 -196.294756) (xy 70.176136 -197.012052)
			(xy 73.095358 -197.012052) (xy 73.233788 -196.873876) (xy 73.233788 -193.43624) (xy 73.210237 -193.422726)
			(xy 73.166868 -193.390056) (xy 73.128572 -193.351565) (xy 73.096123 -193.30803) (xy 73.070178 -193.260333)
			(xy 73.05126 -193.209438) (xy 73.039754 -193.156374) (xy 73.035891 -193.102214) (xy 73.03975 -193.048055)
			(xy 73.051252 -192.99499) (xy 73.070166 -192.944093) (xy 73.096107 -192.896394) (xy 73.128553 -192.852857)
			(xy 73.166846 -192.814363) (xy 73.210213 -192.78169) (xy 73.233788 -192.76822) (xy 73.233788 -192.236598)
			(xy 73.233276 -192.222112) (xy 73.22513 -192.194308) (xy 73.209496 -192.169916) (xy 73.187635 -192.150903)
			(xy 73.161311 -192.138802) (xy 73.132646 -192.134591) (xy 73.118218 -192.136014) (xy 73.101843 -192.138733)
			(xy 73.068776 -192.141658) (xy 73.052178 -192.141856) (xy 73.024927 -192.141369) (xy 72.970979 -192.13361)
			(xy 72.918684 -192.118253) (xy 72.869106 -192.095612) (xy 72.823255 -192.066146) (xy 72.782064 -192.030455)
			(xy 72.74637 -191.989266) (xy 72.716901 -191.943417) (xy 72.694256 -191.893841) (xy 72.678896 -191.841547)
			(xy 72.671133 -191.787599) (xy 72.67067 -191.760348) (xy 72.670416 -191.760348) (xy 72.670895 -191.732831)
			(xy 72.678799 -191.678367) (xy 72.694448 -191.625605) (xy 72.717519 -191.575639) (xy 72.732138 -191.552322)
			(xy 72.740181 -191.540783) (xy 72.750202 -191.514513) (xy 72.752679 -191.486506) (xy 72.747424 -191.458885)
			(xy 72.734834 -191.433745) (xy 72.715865 -191.412991) (xy 72.691954 -191.398199) (xy 72.664916 -191.390488)
			(xy 72.650858 -191.390016) (xy 70.8533 -191.390016) (xy 70.816808 -191.38924) (xy 70.744815 -191.377241)
			(xy 70.710044 -191.36614) (xy 70.678132 -191.354591) (xy 70.61797 -191.323194) (xy 70.563282 -191.283012)
			(xy 70.538848 -191.25946) (xy 70.055232 -190.775844) (xy 70.031688 -190.751405) (xy 69.99153 -190.696705)
			(xy 69.960133 -190.636547) (xy 69.948552 -190.604648) (xy 69.937452 -190.569877) (xy 69.925455 -190.497884)
			(xy 69.924676 -190.461392) (xy 69.924676 -190.093092) (xy 69.924188 -190.07939) (xy 69.916814 -190.052993)
			(xy 69.902681 -190.02951) (xy 69.882808 -190.010635) (xy 69.858628 -189.99773) (xy 69.831887 -189.991725)
			(xy 69.804511 -189.993053) (xy 69.791326 -189.996826) (xy 69.785992 -189.998604) (xy 69.7565 -190.007872)
			(xy 69.695489 -190.017825) (xy 69.66458 -190.018416) (xy 69.66077 -190.018416) (xy 69.633457 -190.017675)
			(xy 69.579458 -190.00934) (xy 69.5272 -189.99339) (xy 69.477751 -189.970151) (xy 69.432121 -189.940097)
			(xy 69.391244 -189.903842) (xy 69.373242 -189.883288) (xy 69.362287 -189.872404) (xy 69.335409 -189.857224)
			(xy 69.305228 -189.85075) (xy 69.274489 -189.85357) (xy 69.245989 -189.865427) (xy 69.233796 -189.874906)
			(xy 69.212683 -189.89322) (xy 69.166107 -189.924112) (xy 69.115524 -189.947882) (xy 69.062015 -189.96402)
			(xy 69.006725 -189.972182) (xy 68.97878 -189.972696) (xy 68.951531 -189.972208) (xy 68.897587 -189.96445)
			(xy 68.845296 -189.949093) (xy 68.795723 -189.926452) (xy 68.749877 -189.896986) (xy 68.70869 -189.861296)
			(xy 68.673002 -189.820107) (xy 68.643538 -189.774259) (xy 68.6209 -189.724685) (xy 68.605546 -189.672394)
			(xy 68.59779 -189.618449) (xy 68.59779 -189.563951) (xy 68.605546 -189.510006) (xy 68.6209 -189.457715)
			(xy 68.643538 -189.408141) (xy 68.673002 -189.362293) (xy 68.70869 -189.321104) (xy 68.749877 -189.285414)
			(xy 68.795723 -189.255948) (xy 68.845296 -189.233307) (xy 68.897587 -189.21795) (xy 68.951531 -189.210192)
			(xy 68.97878 -189.20968) (xy 69.006414 -189.210176) (xy 69.061102 -189.218157) (xy 69.114068 -189.233943)
			(xy 69.164203 -189.257201) (xy 69.21046 -189.287447) (xy 69.251872 -189.324048) (xy 69.270118 -189.344808)
			(xy 69.281073 -189.355699) (xy 69.307954 -189.37089) (xy 69.338142 -189.377375) (xy 69.368889 -189.374563)
			(xy 69.3974 -189.36271) (xy 69.409564 -189.35319) (xy 69.430676 -189.334874) (xy 69.477251 -189.303977)
			(xy 69.527834 -189.280203) (xy 69.581343 -189.264059) (xy 69.636634 -189.255891) (xy 69.66458 -189.2554)
			(xy 69.69231 -189.255908) (xy 69.747184 -189.26395) (xy 69.80032 -189.279838) (xy 69.850602 -189.30324)
			(xy 69.896973 -189.333663) (xy 69.918072 -189.351666) (xy 69.929955 -189.361153) (xy 69.957798 -189.373332)
			(xy 69.987991 -189.37679) (xy 70.017867 -189.371221) (xy 70.044786 -189.357117) (xy 70.055994 -189.34684)
			(xy 70.079302 -189.324485) (xy 70.131202 -189.28605) (xy 70.188106 -189.255511) (xy 70.248823 -189.233505)
			(xy 70.31208 -189.220496) (xy 70.344284 -189.218062) (xy 70.363842 -189.217046) (xy 70.413372 -189.166754)
			(xy 70.413372 -188.617098) (xy 69.588888 -187.79236) (xy 69.56534 -187.767923) (xy 69.525176 -187.713225)
			(xy 69.493773 -187.653069) (xy 69.482208 -187.621164) (xy 69.471108 -187.586393) (xy 69.459109 -187.5144)
			(xy 69.458332 -187.477908) (xy 69.458481 -187.464793) (xy 69.460136 -187.438614) (xy 69.461634 -187.425584)
			(xy 69.463652 -187.409403) (xy 69.469756 -187.377367) (xy 69.473826 -187.361576) (xy 69.476423 -187.346352)
			(xy 69.47337 -187.315633) (xy 69.461298 -187.287222) (xy 69.441304 -187.263701) (xy 69.415208 -187.247211)
			(xy 69.385382 -187.23925) (xy 69.36994 -187.239402) (xy 69.353684 -187.239656) (xy 69.326427 -187.239192)
			(xy 69.272469 -187.231431) (xy 69.220164 -187.216071) (xy 69.170578 -187.193422) (xy 69.12472 -187.163948)
			(xy 69.083523 -187.128247) (xy 69.047827 -187.087046) (xy 69.018357 -187.041185) (xy 68.995714 -186.991596)
			(xy 68.98036 -186.939289) (xy 68.972605 -186.88533) (xy 68.972609 -186.830817) (xy 68.980371 -186.776858)
			(xy 68.995733 -186.724554) (xy 69.018383 -186.674969) (xy 69.047859 -186.629111) (xy 69.083561 -186.587916)
			(xy 69.124763 -186.55222) (xy 69.170625 -186.522752) (xy 69.220214 -186.500111) (xy 69.272521 -186.484757)
			(xy 69.32648 -186.477004) (xy 69.380994 -186.47701) (xy 69.434952 -186.484773) (xy 69.487256 -186.500137)
			(xy 69.536841 -186.522788) (xy 69.582697 -186.552265) (xy 69.623892 -186.587968) (xy 69.659586 -186.629171)
			(xy 69.689053 -186.675034) (xy 69.711693 -186.724624) (xy 69.727045 -186.776931) (xy 69.734796 -186.830891)
			(xy 69.735192 -186.858148) (xy 69.735004 -186.874359) (xy 69.732209 -186.906662) (xy 69.729604 -186.922664)
			(xy 69.728194 -186.935978) (xy 69.731595 -186.962525) (xy 69.741785 -186.987274) (xy 69.75806 -187.00852)
			(xy 69.779303 -187.024802) (xy 69.804049 -187.034998) (xy 69.830595 -187.038406) (xy 69.843904 -187.036964)
			(xy 69.861176 -187.034932) (xy 69.90334 -187.0329) (xy 69.908674 -187.033154) (xy 69.923651 -187.031946)
			(xy 69.951969 -187.021945) (xy 69.976164 -187.004153) (xy 69.994152 -186.980104) (xy 70.004384 -186.951869)
			(xy 70.005978 -186.921879) (xy 70.002908 -186.90717) (xy 69.996044 -186.881489) (xy 69.988652 -186.828847)
			(xy 69.988176 -186.802268) (xy 69.988664 -186.775018) (xy 69.996424 -186.721073) (xy 70.011782 -186.668781)
			(xy 70.034425 -186.619207) (xy 70.063891 -186.573359) (xy 70.099583 -186.532171) (xy 70.140772 -186.496482)
			(xy 70.186621 -186.467017) (xy 70.236196 -186.444376) (xy 70.288488 -186.429021) (xy 70.342434 -186.421263)
			(xy 70.369684 -186.42076) (xy 70.396729 -186.42123) (xy 70.450278 -186.428867) (xy 70.502211 -186.44399)
			(xy 70.551488 -186.466297) (xy 70.59712 -186.495339) (xy 70.638194 -186.530535) (xy 70.673884 -186.571179)
			(xy 70.703477 -186.616457) (xy 70.726379 -186.66546) (xy 70.74213 -186.717206) (xy 70.750415 -186.770658)
			(xy 70.751192 -186.797696) (xy 70.751192 -186.801252) (xy 70.750861 -186.826366) (xy 70.744407 -186.876176)
			(xy 70.731473 -186.924708) (xy 70.722236 -186.948064) (xy 70.720712 -186.95162) (xy 70.720458 -186.952382)
			(xy 70.714935 -186.96663) (xy 70.711771 -186.997011) (xy 70.717715 -187.026972) (xy 70.732237 -187.053844)
			(xy 70.754042 -187.075234) (xy 70.78119 -187.089235) (xy 70.79615 -187.092336) (xy 70.821703 -187.096287)
			(xy 70.871503 -187.110196) (xy 70.918966 -187.13071) (xy 70.96322 -187.157452) (xy 70.983602 -187.173362)
			(xy 70.995343 -187.181827) (xy 71.02226 -187.19243) (xy 71.051072 -187.195047) (xy 71.07946 -187.189469)
			(xy 71.105139 -187.176143) (xy 71.115936 -187.166504) (xy 71.13755 -187.145723) (xy 71.186055 -187.110481)
			(xy 71.239473 -187.083258) (xy 71.296491 -187.064721) (xy 71.355706 -187.055328) (xy 71.385684 -187.054744)
			(xy 71.412941 -187.055206) (xy 71.466901 -187.062962) (xy 71.519207 -187.078319) (xy 71.568795 -187.100963)
			(xy 71.614656 -187.130434) (xy 71.655856 -187.166133) (xy 71.691556 -187.207331) (xy 71.721029 -187.253191)
			(xy 71.743676 -187.302778) (xy 71.759035 -187.355084) (xy 71.766793 -187.409043) (xy 71.766793 -187.442856)
			(xy 72.019666 -187.442856) (xy 72.023737 -187.387234) (xy 72.035863 -187.332797) (xy 72.055786 -187.280706)
			(xy 72.083082 -187.232071) (xy 72.117168 -187.187928) (xy 72.157317 -187.149219) (xy 72.202675 -187.116768)
			(xy 72.252275 -187.091267) (xy 72.305059 -187.07326) (xy 72.359902 -187.06313) (xy 72.415636 -187.061093)
			(xy 72.471073 -187.067193) (xy 72.52503 -187.081299) (xy 72.576359 -187.103111) (xy 72.623965 -187.132165)
			(xy 72.666833 -187.16784) (xy 72.70405 -187.209377) (xy 72.734823 -187.25589) (xy 72.758495 -187.306387)
			(xy 72.774563 -187.359794) (xy 72.782683 -187.41497) (xy 72.783192 -187.442856) (xy 72.782683 -187.470742)
			(xy 72.774563 -187.525918) (xy 72.758495 -187.579325) (xy 72.734823 -187.629822) (xy 72.70405 -187.676335)
			(xy 72.666833 -187.717872) (xy 72.623965 -187.753547) (xy 72.576359 -187.782601) (xy 72.52503 -187.804413)
			(xy 72.471073 -187.818519) (xy 72.415636 -187.824619) (xy 72.359902 -187.822582) (xy 72.305059 -187.812452)
			(xy 72.252275 -187.794445) (xy 72.202675 -187.768944) (xy 72.157317 -187.736493) (xy 72.117168 -187.697784)
			(xy 72.083082 -187.653641) (xy 72.055786 -187.605006) (xy 72.035863 -187.552915) (xy 72.023737 -187.498478)
			(xy 72.019666 -187.442856) (xy 71.766793 -187.442856) (xy 71.766793 -187.463557) (xy 71.759035 -187.517516)
			(xy 71.743676 -187.569822) (xy 71.721029 -187.619409) (xy 71.691556 -187.665269) (xy 71.655856 -187.706467)
			(xy 71.614656 -187.742166) (xy 71.568795 -187.771637) (xy 71.519207 -187.794281) (xy 71.466901 -187.809638)
			(xy 71.412941 -187.817394) (xy 71.385684 -187.81776) (xy 71.359778 -187.817325) (xy 71.308444 -187.810308)
			(xy 71.258532 -187.796405) (xy 71.210962 -187.775873) (xy 71.16661 -187.74909) (xy 71.146162 -187.733178)
			(xy 71.134423 -187.724715) (xy 71.107509 -187.714118) (xy 71.078702 -187.711508) (xy 71.050321 -187.717095)
			(xy 71.024653 -187.730429) (xy 71.013828 -187.740036) (xy 71.006005 -187.747742) (xy 70.989611 -187.762354)
			(xy 70.981062 -187.769246) (xy 70.970493 -187.778609) (xy 70.95453 -187.801888) (xy 70.945542 -187.828644)
			(xy 70.944216 -187.856839) (xy 70.950651 -187.884321) (xy 70.964357 -187.908995) (xy 70.97395 -187.91936)
			(xy 70.974966 -187.920376) (xy 71.172832 -188.118496) (xy 71.196381 -188.142932) (xy 71.236548 -188.197628)
			(xy 71.267956 -188.257784) (xy 71.279512 -188.289692) (xy 71.290615 -188.324463) (xy 71.30262 -188.396456)
			(xy 71.303388 -188.432948) (xy 71.303388 -188.870336) (xy 71.30391 -188.885315) (xy 71.312588 -188.913988)
			(xy 71.329215 -188.938907) (xy 71.352359 -188.957927) (xy 71.380028 -188.969409) (xy 71.409839 -188.972366)
			(xy 71.439225 -188.966542) (xy 71.465654 -188.952439) (xy 71.476616 -188.942218) (xy 71.478648 -188.940186)
			(xy 71.906892 -188.512196) (xy 71.931327 -188.488646) (xy 71.986022 -188.448475) (xy 72.046177 -188.417065)
			(xy 72.078088 -188.405516) (xy 72.112859 -188.394412) (xy 72.184851 -188.382406) (xy 72.221344 -188.38164)
			(xy 73.233788 -188.38164) (xy 73.233788 -187.555378) (xy 73.47585 -187.313316) (xy 73.485696 -187.302688)
			(xy 73.499524 -187.277244) (xy 73.505653 -187.248941) (xy 73.50359 -187.220056) (xy 73.493501 -187.192912)
			(xy 73.476197 -187.169692) (xy 73.45307 -187.152263) (xy 73.42598 -187.142028) (xy 73.411588 -187.140342)
			(xy 73.383188 -187.137635) (xy 73.327591 -187.124859) (xy 73.274516 -187.103946) (xy 73.225148 -187.075362)
			(xy 73.180586 -187.039744) (xy 73.141826 -186.997888) (xy 73.109732 -186.950726) (xy 73.085019 -186.89931)
			(xy 73.068239 -186.844787) (xy 73.059766 -186.788373) (xy 73.05929 -186.75985) (xy 73.05975 -186.732595)
			(xy 73.067501 -186.678638) (xy 73.082853 -186.626334) (xy 73.105492 -186.576748) (xy 73.134959 -186.530888)
			(xy 73.170653 -186.489689) (xy 73.211847 -186.45399) (xy 73.257702 -186.424517) (xy 73.307286 -186.401871)
			(xy 73.359587 -186.386512) (xy 73.413543 -186.378754) (xy 73.440798 -186.378342) (xy 73.469267 -186.378869)
			(xy 73.525572 -186.387327) (xy 73.579997 -186.404056) (xy 73.631331 -186.428686) (xy 73.678438 -186.460668)
			(xy 73.72027 -186.499293) (xy 73.7559 -186.543705) (xy 73.784536 -186.592917) (xy 73.805544 -186.645837)
			(xy 73.818457 -186.701291) (xy 73.82129 -186.729624) (xy 73.822696 -186.744132) (xy 73.832706 -186.771495)
			(xy 73.850036 -186.794916) (xy 73.873277 -186.812489) (xy 73.900535 -186.82278) (xy 73.92959 -186.824954)
			(xy 73.958076 -186.818831) (xy 73.983672 -186.804912) (xy 73.994264 -186.794902) (xy 79.56169 -181.227476)
			(xy 79.56169 -167.458898) (xy 72.92848 -160.825688) (xy 72.3773 -160.825688) (xy 71.1962 -162.006788)
			(xy 68.83146 -162.006788) (xy 68.44284 -161.618168) (xy 61.539628 -161.618168) (xy 61.435488 -161.722308)
			(xy 61.425694 -161.732862) (xy 61.411897 -161.758119) (xy 61.405688 -161.786221) (xy 61.40756 -161.814939)
			(xy 61.417363 -161.841998) (xy 61.434321 -161.865251) (xy 61.445394 -161.874454) (xy 61.468059 -161.892638)
			(xy 61.508136 -161.934711) (xy 61.541367 -161.982376) (xy 61.56698 -162.034532) (xy 61.584385 -162.08997)
			(xy 61.593176 -162.147407) (xy 61.59373 -162.17646) (xy 61.593243 -162.203997) (xy 61.58532 -162.258498)
			(xy 61.569647 -162.311294) (xy 61.54655 -162.36129) (xy 61.516507 -162.407448) (xy 61.480143 -162.44881)
			(xy 61.438213 -162.484516) (xy 61.391586 -162.513826) (xy 61.341232 -162.536132) (xy 61.314838 -162.543998)
			(xy 61.300952 -162.549124) (xy 61.276712 -162.566087) (xy 61.258359 -162.589293) (xy 61.247437 -162.616789)
			(xy 61.244865 -162.646263) (xy 61.25086 -162.675235) (xy 61.264916 -162.701269) (xy 61.27496 -162.712146)
			(xy 61.341508 -162.778694) (xy 61.341508 -164.634926) (xy 69.007995 -164.634926) (xy 69.012017 -164.549206)
			(xy 69.024048 -164.464238) (xy 69.043984 -164.380771) (xy 69.071647 -164.299537) (xy 69.106796 -164.221251)
			(xy 69.149122 -164.1466) (xy 69.198251 -164.076241) (xy 69.253754 -164.010791) (xy 69.315141 -163.950827)
			(xy 69.381874 -163.896874) (xy 69.453366 -163.849407) (xy 69.528988 -163.808843) (xy 69.608077 -163.775539)
			(xy 69.689937 -163.749787) (xy 69.773848 -163.731814) (xy 69.859074 -163.721778) (xy 69.944866 -163.719766)
			(xy 70.030468 -163.725797) (xy 70.11513 -163.739817) (xy 70.198107 -163.761703) (xy 70.27867 -163.791264)
			(xy 70.35611 -163.828238) (xy 70.429749 -163.872302) (xy 70.498937 -163.923068) (xy 70.563068 -163.980089)
			(xy 70.621577 -164.042865) (xy 70.67395 -164.110845) (xy 70.719728 -164.18343) (xy 70.758508 -164.259982)
			(xy 70.789949 -164.33983) (xy 70.813775 -164.422271) (xy 70.829776 -164.506581) (xy 70.837811 -164.592019)
			(xy 70.838314 -164.634926) (xy 70.837811 -164.677833) (xy 70.829776 -164.763271) (xy 70.813775 -164.847581)
			(xy 70.789949 -164.930022) (xy 70.758508 -165.00987) (xy 70.719728 -165.086422) (xy 70.67395 -165.159007)
			(xy 70.621577 -165.226987) (xy 70.563068 -165.289763) (xy 70.498937 -165.346784) (xy 70.429749 -165.39755)
			(xy 70.35611 -165.441614) (xy 70.27867 -165.478588) (xy 70.198107 -165.508149) (xy 70.11513 -165.530035)
			(xy 70.030468 -165.544055) (xy 69.944866 -165.550086) (xy 69.859074 -165.548074) (xy 69.773848 -165.538038)
			(xy 69.689937 -165.520065) (xy 69.608077 -165.494313) (xy 69.528988 -165.461009) (xy 69.453366 -165.420445)
			(xy 69.381874 -165.372978) (xy 69.315141 -165.319025) (xy 69.253754 -165.259061) (xy 69.198251 -165.193611)
			(xy 69.149122 -165.123252) (xy 69.106796 -165.048601) (xy 69.071647 -164.970315) (xy 69.043984 -164.889081)
			(xy 69.024048 -164.805614) (xy 69.012017 -164.720646) (xy 69.007995 -164.634926) (xy 61.341508 -164.634926)
			(xy 61.341508 -166.67727) (xy 69.034402 -166.67727) (xy 69.034402 -166.592574) (xy 69.042453 -166.50826)
			(xy 69.058482 -166.425094) (xy 69.082343 -166.343827) (xy 69.113822 -166.265197) (xy 69.152633 -166.189916)
			(xy 69.198423 -166.118664) (xy 69.250779 -166.052088) (xy 69.309227 -165.99079) (xy 69.373237 -165.935325)
			(xy 69.442229 -165.886196) (xy 69.515579 -165.843847) (xy 69.592622 -165.808663) (xy 69.672661 -165.780961)
			(xy 69.75497 -165.760993) (xy 69.838805 -165.74894) (xy 69.923406 -165.74491) (xy 70.008007 -165.74894)
			(xy 70.091842 -165.760993) (xy 70.174151 -165.780961) (xy 70.25419 -165.808663) (xy 70.331233 -165.843847)
			(xy 70.404583 -165.886196) (xy 70.473575 -165.935325) (xy 70.537585 -165.99079) (xy 70.596033 -166.052088)
			(xy 70.648389 -166.118664) (xy 70.694179 -166.189916) (xy 70.73299 -166.265197) (xy 70.764469 -166.343827)
			(xy 70.78833 -166.425094) (xy 70.804359 -166.50826) (xy 70.81241 -166.592574) (xy 70.812914 -166.634922)
			(xy 70.81241 -166.67727) (xy 70.804359 -166.761584) (xy 70.78833 -166.84475) (xy 70.764469 -166.926017)
			(xy 70.73299 -167.004647) (xy 70.694179 -167.079928) (xy 70.648389 -167.15118) (xy 70.596033 -167.217756)
			(xy 70.537585 -167.279054) (xy 70.473575 -167.334519) (xy 70.404583 -167.383648) (xy 70.331233 -167.425997)
			(xy 70.25419 -167.461181) (xy 70.174151 -167.488883) (xy 70.091842 -167.508851) (xy 70.008007 -167.520904)
			(xy 69.923406 -167.524935) (xy 69.838805 -167.520904) (xy 69.75497 -167.508851) (xy 69.672661 -167.488883)
			(xy 69.592622 -167.461181) (xy 69.515579 -167.425997) (xy 69.442229 -167.383648) (xy 69.373237 -167.334519)
			(xy 69.309227 -167.279054) (xy 69.250779 -167.217756) (xy 69.198423 -167.15118) (xy 69.152633 -167.079928)
			(xy 69.113822 -167.004647) (xy 69.082343 -166.926017) (xy 69.058482 -166.84475) (xy 69.042453 -166.761584)
			(xy 69.034402 -166.67727) (xy 61.341508 -166.67727) (xy 61.341508 -170.19651) (xy 61.653674 -170.508676)
			(xy 66.777108 -170.508676) (xy 67.5767 -171.308268) (xy 67.5767 -171.812388) (xy 67.755004 -171.812388)
			(xy 67.755004 -171.727692) (xy 67.763055 -171.643378) (xy 67.779084 -171.560212) (xy 67.802945 -171.478945)
			(xy 67.834424 -171.400315) (xy 67.873235 -171.325034) (xy 67.919025 -171.253782) (xy 67.971381 -171.187206)
			(xy 68.029829 -171.125908) (xy 68.093839 -171.070443) (xy 68.162831 -171.021314) (xy 68.236181 -170.978965)
			(xy 68.313224 -170.943781) (xy 68.393263 -170.916079) (xy 68.475572 -170.896111) (xy 68.559407 -170.884058)
			(xy 68.644008 -170.880028) (xy 68.728609 -170.884058) (xy 68.812444 -170.896111) (xy 68.894753 -170.916079)
			(xy 68.974792 -170.943781) (xy 69.051835 -170.978965) (xy 69.125185 -171.021314) (xy 69.194177 -171.070443)
			(xy 69.258187 -171.125908) (xy 69.316635 -171.187206) (xy 69.368991 -171.253782) (xy 69.414781 -171.325034)
			(xy 69.453592 -171.400315) (xy 69.485071 -171.478945) (xy 69.508932 -171.560212) (xy 69.524961 -171.643378)
			(xy 69.533012 -171.727692) (xy 69.533516 -171.77004) (xy 69.728593 -171.77004) (xy 69.732615 -171.68432)
			(xy 69.744646 -171.599352) (xy 69.764582 -171.515885) (xy 69.792245 -171.434651) (xy 69.827394 -171.356365)
			(xy 69.86972 -171.281714) (xy 69.918849 -171.211355) (xy 69.974352 -171.145905) (xy 70.035739 -171.085941)
			(xy 70.102472 -171.031988) (xy 70.173964 -170.984521) (xy 70.249586 -170.943957) (xy 70.328675 -170.910653)
			(xy 70.410535 -170.884901) (xy 70.494446 -170.866928) (xy 70.579672 -170.856892) (xy 70.665464 -170.85488)
			(xy 70.751066 -170.860911) (xy 70.835728 -170.874931) (xy 70.918705 -170.896817) (xy 70.999268 -170.926378)
			(xy 71.076708 -170.963352) (xy 71.150347 -171.007416) (xy 71.219535 -171.058182) (xy 71.283666 -171.115203)
			(xy 71.342175 -171.177979) (xy 71.394548 -171.245959) (xy 71.440326 -171.318544) (xy 71.479106 -171.395096)
			(xy 71.510547 -171.474944) (xy 71.534373 -171.557385) (xy 71.550374 -171.641695) (xy 71.558409 -171.727133)
			(xy 71.558912 -171.77004) (xy 71.558409 -171.812947) (xy 71.550374 -171.898385) (xy 71.534373 -171.982695)
			(xy 71.510547 -172.065136) (xy 71.479106 -172.144984) (xy 71.440326 -172.221536) (xy 71.394548 -172.294121)
			(xy 71.342175 -172.362101) (xy 71.283666 -172.424877) (xy 71.219535 -172.481898) (xy 71.150347 -172.532664)
			(xy 71.102999 -172.560996) (xy 74.79233 -172.560996) (xy 74.796401 -172.505374) (xy 74.808527 -172.450937)
			(xy 74.82845 -172.398846) (xy 74.855746 -172.350211) (xy 74.889832 -172.306068) (xy 74.929981 -172.267359)
			(xy 74.975339 -172.234908) (xy 75.024939 -172.209407) (xy 75.077723 -172.1914) (xy 75.132566 -172.18127)
			(xy 75.1883 -172.179233) (xy 75.243737 -172.185333) (xy 75.297694 -172.199439) (xy 75.349023 -172.221251)
			(xy 75.396629 -172.250305) (xy 75.439497 -172.28598) (xy 75.476714 -172.327517) (xy 75.507487 -172.37403)
			(xy 75.531159 -172.424527) (xy 75.547227 -172.477934) (xy 75.555347 -172.53311) (xy 75.555856 -172.560996)
			(xy 75.555347 -172.588882) (xy 75.547227 -172.644058) (xy 75.531159 -172.697465) (xy 75.507487 -172.747962)
			(xy 75.476714 -172.794475) (xy 75.439497 -172.836012) (xy 75.396629 -172.871687) (xy 75.349023 -172.900741)
			(xy 75.297694 -172.922553) (xy 75.243737 -172.936659) (xy 75.1883 -172.942759) (xy 75.132566 -172.940722)
			(xy 75.077723 -172.930592) (xy 75.024939 -172.912585) (xy 74.975339 -172.887084) (xy 74.929981 -172.854633)
			(xy 74.889832 -172.815924) (xy 74.855746 -172.771781) (xy 74.82845 -172.723146) (xy 74.808527 -172.671055)
			(xy 74.796401 -172.616618) (xy 74.79233 -172.560996) (xy 71.102999 -172.560996) (xy 71.076708 -172.576728)
			(xy 70.999268 -172.613702) (xy 70.918705 -172.643263) (xy 70.835728 -172.665149) (xy 70.751066 -172.679169)
			(xy 70.665464 -172.6852) (xy 70.579672 -172.683188) (xy 70.494446 -172.673152) (xy 70.410535 -172.655179)
			(xy 70.328675 -172.629427) (xy 70.249586 -172.596123) (xy 70.173964 -172.555559) (xy 70.102472 -172.508092)
			(xy 70.035739 -172.454139) (xy 69.974352 -172.394175) (xy 69.918849 -172.328725) (xy 69.86972 -172.258366)
			(xy 69.827394 -172.183715) (xy 69.792245 -172.105429) (xy 69.764582 -172.024195) (xy 69.744646 -171.940728)
			(xy 69.732615 -171.85576) (xy 69.728593 -171.77004) (xy 69.533516 -171.77004) (xy 69.533012 -171.812388)
			(xy 69.524961 -171.896702) (xy 69.508932 -171.979868) (xy 69.485071 -172.061135) (xy 69.453592 -172.139765)
			(xy 69.414781 -172.215046) (xy 69.368991 -172.286298) (xy 69.316635 -172.352874) (xy 69.258187 -172.414172)
			(xy 69.194177 -172.469637) (xy 69.125185 -172.518766) (xy 69.051835 -172.561115) (xy 68.974792 -172.596299)
			(xy 68.894753 -172.624001) (xy 68.812444 -172.643969) (xy 68.728609 -172.656022) (xy 68.644008 -172.660053)
			(xy 68.559407 -172.656022) (xy 68.475572 -172.643969) (xy 68.393263 -172.624001) (xy 68.313224 -172.596299)
			(xy 68.236181 -172.561115) (xy 68.162831 -172.518766) (xy 68.093839 -172.469637) (xy 68.029829 -172.414172)
			(xy 67.971381 -172.352874) (xy 67.919025 -172.286298) (xy 67.873235 -172.215046) (xy 67.834424 -172.139765)
			(xy 67.802945 -172.061135) (xy 67.779084 -171.979868) (xy 67.763055 -171.896702) (xy 67.755004 -171.812388)
			(xy 67.5767 -171.812388) (xy 67.5767 -173.060868) (xy 68.517516 -174.001684) (xy 74.085958 -174.001684)
			(xy 74.086447 -173.963039) (xy 74.094267 -173.886145) (xy 74.109825 -173.810437) (xy 74.132963 -173.736691)
			(xy 74.163443 -173.665664) (xy 74.200952 -173.598086) (xy 74.245106 -173.534648) (xy 74.295451 -173.476004)
			(xy 74.35147 -173.422753) (xy 74.412589 -173.375443) (xy 74.478182 -173.334559) (xy 74.547573 -173.300521)
			(xy 74.620053 -173.273678) (xy 74.694876 -173.254305) (xy 74.771275 -173.242601) (xy 74.848466 -173.238686)
			(xy 74.925657 -173.242601) (xy 75.002056 -173.254305) (xy 75.076879 -173.273678) (xy 75.149359 -173.300521)
			(xy 75.21875 -173.334559) (xy 75.284343 -173.375443) (xy 75.345462 -173.422753) (xy 75.401481 -173.476004)
			(xy 75.451826 -173.534648) (xy 75.49598 -173.598086) (xy 75.533489 -173.665664) (xy 75.563969 -173.736691)
			(xy 75.587107 -173.810437) (xy 75.602665 -173.886145) (xy 75.610485 -173.963039) (xy 75.610974 -174.001684)
			(xy 75.610466 -174.041827) (xy 75.602041 -174.121668) (xy 75.585273 -174.200183) (xy 75.560346 -174.2765)
			(xy 75.527537 -174.349776) (xy 75.487209 -174.419197) (xy 75.439809 -174.483997) (xy 75.385862 -174.543456)
			(xy 75.325966 -174.596917) (xy 75.260782 -174.643787) (xy 75.226164 -174.664116) (xy 75.218447 -174.668897)
			(xy 75.206768 -174.682781) (xy 75.200661 -174.699864) (xy 75.200889 -174.718005) (xy 75.203812 -174.7266)
			(xy 75.212092 -174.748773) (xy 75.223721 -174.794653) (xy 75.2296 -174.841619) (xy 75.229974 -174.865284)
			(xy 75.229488 -174.892535) (xy 75.221732 -174.946483) (xy 75.206377 -174.998778) (xy 75.183735 -175.048355)
			(xy 75.154269 -175.094205) (xy 75.118578 -175.135396) (xy 75.077387 -175.171087) (xy 75.031537 -175.200553)
			(xy 74.98196 -175.223195) (xy 74.929665 -175.23855) (xy 74.875717 -175.246306) (xy 74.821215 -175.246306)
			(xy 74.767267 -175.23855) (xy 74.714972 -175.223195) (xy 74.665395 -175.200553) (xy 74.619545 -175.171087)
			(xy 74.578354 -175.135396) (xy 74.542663 -175.094205) (xy 74.513197 -175.048355) (xy 74.490555 -174.998778)
			(xy 74.4752 -174.946483) (xy 74.467444 -174.892535) (xy 74.466958 -174.865284) (xy 74.467305 -174.841617)
			(xy 74.473177 -174.794648) (xy 74.484829 -174.74877) (xy 74.49312 -174.7266) (xy 74.496022 -174.718006)
			(xy 74.496217 -174.69988) (xy 74.49011 -174.682812) (xy 74.47846 -174.668924) (xy 74.470768 -174.664116)
			(xy 74.436131 -174.64382) (xy 74.370958 -174.596936) (xy 74.31107 -174.543466) (xy 74.257131 -174.484)
			(xy 74.209737 -174.419196) (xy 74.169414 -174.349772) (xy 74.136606 -174.276497) (xy 74.111678 -174.20018)
			(xy 74.094905 -174.121667) (xy 74.086473 -174.041826) (xy 74.085958 -174.001684) (xy 68.517516 -174.001684)
			(xy 70.0532 -175.537368) (xy 70.0532 -175.538638) (xy 72.724008 -175.538638) (xy 72.728079 -175.483016)
			(xy 72.740205 -175.428579) (xy 72.760128 -175.376488) (xy 72.787424 -175.327853) (xy 72.82151 -175.28371)
			(xy 72.861659 -175.245001) (xy 72.907017 -175.21255) (xy 72.956617 -175.187049) (xy 73.009401 -175.169042)
			(xy 73.064244 -175.158912) (xy 73.119978 -175.156875) (xy 73.175415 -175.162975) (xy 73.229372 -175.177081)
			(xy 73.280701 -175.198893) (xy 73.328307 -175.227947) (xy 73.371175 -175.263622) (xy 73.408392 -175.305159)
			(xy 73.439165 -175.351672) (xy 73.462837 -175.402169) (xy 73.478905 -175.455576) (xy 73.487025 -175.510752)
			(xy 73.487534 -175.538638) (xy 73.487025 -175.566524) (xy 73.478905 -175.6217) (xy 73.462837 -175.675107)
			(xy 73.439165 -175.725604) (xy 73.408392 -175.772117) (xy 73.371175 -175.813654) (xy 73.328307 -175.849329)
			(xy 73.280701 -175.878383) (xy 73.229372 -175.900195) (xy 73.175415 -175.914301) (xy 73.119978 -175.920401)
			(xy 73.064244 -175.918364) (xy 73.009401 -175.908234) (xy 72.956617 -175.890227) (xy 72.907017 -175.864726)
			(xy 72.861659 -175.832275) (xy 72.82151 -175.793566) (xy 72.787424 -175.749423) (xy 72.760128 -175.700788)
			(xy 72.740205 -175.648697) (xy 72.728079 -175.59426) (xy 72.724008 -175.538638) (xy 70.0532 -175.538638)
			(xy 70.0532 -177.014124) (xy 70.053721 -177.029022) (xy 70.062324 -177.057549) (xy 70.078792 -177.082381)
			(xy 70.101723 -177.101406) (xy 70.129168 -177.113007) (xy 70.158792 -177.116196) (xy 70.188078 -177.110703)
			(xy 70.201536 -177.104294) (xy 70.242245 -177.082456) (xy 70.327199 -177.046151) (xy 70.415381 -177.018601)
			(xy 70.505893 -177.000086) (xy 70.597811 -176.990797) (xy 70.644004 -176.990248) (xy 70.686282 -176.990736)
			(xy 70.770478 -176.998539) (xy 70.853594 -177.014076) (xy 70.934922 -177.037216) (xy 71.013768 -177.067762)
			(xy 71.08946 -177.105452) (xy 71.161351 -177.149965) (xy 71.228828 -177.200922) (xy 71.291316 -177.257887)
			(xy 71.348281 -177.320375) (xy 71.399237 -177.387853) (xy 71.44375 -177.459744) (xy 71.48144 -177.535435)
			(xy 71.511985 -177.614282) (xy 71.535125 -177.69561) (xy 71.550662 -177.778726) (xy 71.558464 -177.862922)
			(xy 71.558464 -177.947478) (xy 71.550662 -178.031674) (xy 71.535125 -178.11479) (xy 71.511985 -178.196118)
			(xy 71.48144 -178.274965) (xy 71.44375 -178.350656) (xy 71.399237 -178.422547) (xy 71.348281 -178.490025)
			(xy 71.291316 -178.552513) (xy 71.228828 -178.609478) (xy 71.161351 -178.660435) (xy 71.08946 -178.704948)
			(xy 71.013768 -178.742638) (xy 70.934922 -178.773184) (xy 70.853594 -178.796324) (xy 70.770478 -178.811861)
			(xy 70.686282 -178.819664) (xy 70.644004 -178.820064) (xy 70.600138 -178.819548) (xy 70.512808 -178.811151)
			(xy 70.426683 -178.794435) (xy 70.342553 -178.769553) (xy 70.261191 -178.736733) (xy 70.183344 -178.696276)
			(xy 70.109726 -178.648554) (xy 70.075044 -178.62169) (xy 70.039738 -178.593496) (xy 69.522086 -179.111148)
			(xy 73.684382 -179.111148) (xy 73.688453 -179.055526) (xy 73.700579 -179.001089) (xy 73.720502 -178.948998)
			(xy 73.747798 -178.900363) (xy 73.781884 -178.85622) (xy 73.822033 -178.817511) (xy 73.867391 -178.78506)
			(xy 73.916991 -178.759559) (xy 73.969775 -178.741552) (xy 74.024618 -178.731422) (xy 74.080352 -178.729385)
			(xy 74.135789 -178.735485) (xy 74.189746 -178.749591) (xy 74.241075 -178.771403) (xy 74.288681 -178.800457)
			(xy 74.331549 -178.836132) (xy 74.368766 -178.877669) (xy 74.399539 -178.924182) (xy 74.423211 -178.974679)
			(xy 74.439279 -179.028086) (xy 74.447399 -179.083262) (xy 74.447908 -179.111148) (xy 74.447399 -179.139034)
			(xy 74.439279 -179.19421) (xy 74.423211 -179.247617) (xy 74.399539 -179.298114) (xy 74.368766 -179.344627)
			(xy 74.331549 -179.386164) (xy 74.288681 -179.421839) (xy 74.241075 -179.450893) (xy 74.189746 -179.472705)
			(xy 74.135789 -179.486811) (xy 74.080352 -179.492911) (xy 74.024618 -179.490874) (xy 73.969775 -179.480744)
			(xy 73.916991 -179.462737) (xy 73.867391 -179.437236) (xy 73.822033 -179.404785) (xy 73.781884 -179.366076)
			(xy 73.747798 -179.321933) (xy 73.720502 -179.273298) (xy 73.700579 -179.221207) (xy 73.688453 -179.16677)
			(xy 73.684382 -179.111148) (xy 69.522086 -179.111148) (xy 66.822066 -181.811168) (xy 68.096382 -181.811168)
			(xy 68.100453 -181.755546) (xy 68.112579 -181.701109) (xy 68.132502 -181.649018) (xy 68.159798 -181.600383)
			(xy 68.193884 -181.55624) (xy 68.234033 -181.517531) (xy 68.279391 -181.48508) (xy 68.328991 -181.459579)
			(xy 68.381775 -181.441572) (xy 68.436618 -181.431442) (xy 68.492352 -181.429405) (xy 68.547789 -181.435505)
			(xy 68.601746 -181.449611) (xy 68.653075 -181.471423) (xy 68.700681 -181.500477) (xy 68.743549 -181.536152)
			(xy 68.780766 -181.577689) (xy 68.811539 -181.624202) (xy 68.835211 -181.674699) (xy 68.851279 -181.728106)
			(xy 68.859399 -181.783282) (xy 68.859908 -181.811168) (xy 68.859399 -181.839054) (xy 68.855167 -181.86781)
			(xy 71.82688 -181.86781) (xy 71.830951 -181.812188) (xy 71.843077 -181.757751) (xy 71.863 -181.70566)
			(xy 71.890296 -181.657025) (xy 71.924382 -181.612882) (xy 71.964531 -181.574173) (xy 72.009889 -181.541722)
			(xy 72.059489 -181.516221) (xy 72.112273 -181.498214) (xy 72.167116 -181.488084) (xy 72.22285 -181.486047)
			(xy 72.278287 -181.492147) (xy 72.332244 -181.506253) (xy 72.383573 -181.528065) (xy 72.431179 -181.557119)
			(xy 72.474047 -181.592794) (xy 72.511264 -181.634331) (xy 72.542037 -181.680844) (xy 72.556455 -181.7116)
			(xy 75.379324 -181.7116) (xy 75.383395 -181.655978) (xy 75.395521 -181.601541) (xy 75.415444 -181.54945)
			(xy 75.44274 -181.500815) (xy 75.476826 -181.456672) (xy 75.516975 -181.417963) (xy 75.562333 -181.385512)
			(xy 75.611933 -181.360011) (xy 75.664717 -181.342004) (xy 75.71956 -181.331874) (xy 75.775294 -181.329837)
			(xy 75.830731 -181.335937) (xy 75.884688 -181.350043) (xy 75.936017 -181.371855) (xy 75.983623 -181.400909)
			(xy 76.026491 -181.436584) (xy 76.063708 -181.478121) (xy 76.094481 -181.524634) (xy 76.118153 -181.575131)
			(xy 76.134221 -181.628538) (xy 76.142341 -181.683714) (xy 76.14285 -181.7116) (xy 76.142341 -181.739486)
			(xy 76.134221 -181.794662) (xy 76.118153 -181.848069) (xy 76.094481 -181.898566) (xy 76.063708 -181.945079)
			(xy 76.026491 -181.986616) (xy 75.983623 -182.022291) (xy 75.936017 -182.051345) (xy 75.884688 -182.073157)
			(xy 75.830731 -182.087263) (xy 75.775294 -182.093363) (xy 75.71956 -182.091326) (xy 75.664717 -182.081196)
			(xy 75.611933 -182.063189) (xy 75.562333 -182.037688) (xy 75.516975 -182.005237) (xy 75.476826 -181.966528)
			(xy 75.44274 -181.922385) (xy 75.415444 -181.87375) (xy 75.395521 -181.821659) (xy 75.383395 -181.767222)
			(xy 75.379324 -181.7116) (xy 72.556455 -181.7116) (xy 72.565709 -181.731341) (xy 72.581777 -181.784748)
			(xy 72.589897 -181.839924) (xy 72.590406 -181.86781) (xy 72.589897 -181.895696) (xy 72.581777 -181.950872)
			(xy 72.565709 -182.004279) (xy 72.542037 -182.054776) (xy 72.511264 -182.101289) (xy 72.474047 -182.142826)
			(xy 72.431179 -182.178501) (xy 72.383573 -182.207555) (xy 72.332244 -182.229367) (xy 72.278287 -182.243473)
			(xy 72.22285 -182.249573) (xy 72.167116 -182.247536) (xy 72.112273 -182.237406) (xy 72.059489 -182.219399)
			(xy 72.009889 -182.193898) (xy 71.964531 -182.161447) (xy 71.924382 -182.122738) (xy 71.890296 -182.078595)
			(xy 71.863 -182.02996) (xy 71.843077 -181.977869) (xy 71.830951 -181.923432) (xy 71.82688 -181.86781)
			(xy 68.855167 -181.86781) (xy 68.851279 -181.89423) (xy 68.835211 -181.947637) (xy 68.811539 -181.998134)
			(xy 68.780766 -182.044647) (xy 68.743549 -182.086184) (xy 68.700681 -182.121859) (xy 68.653075 -182.150913)
			(xy 68.601746 -182.172725) (xy 68.547789 -182.186831) (xy 68.492352 -182.192931) (xy 68.436618 -182.190894)
			(xy 68.381775 -182.180764) (xy 68.328991 -182.162757) (xy 68.279391 -182.137256) (xy 68.234033 -182.104805)
			(xy 68.193884 -182.066096) (xy 68.159798 -182.021953) (xy 68.132502 -181.973318) (xy 68.112579 -181.921227)
			(xy 68.100453 -181.86679) (xy 68.096382 -181.811168) (xy 66.822066 -181.811168) (xy 66.143886 -182.489348)
			(xy 66.143886 -183.197246) (xy 75.07808 -183.197246) (xy 75.082151 -183.141624) (xy 75.094277 -183.087187)
			(xy 75.1142 -183.035096) (xy 75.141496 -182.986461) (xy 75.175582 -182.942318) (xy 75.215731 -182.903609)
			(xy 75.261089 -182.871158) (xy 75.310689 -182.845657) (xy 75.363473 -182.82765) (xy 75.418316 -182.81752)
			(xy 75.47405 -182.815483) (xy 75.529487 -182.821583) (xy 75.583444 -182.835689) (xy 75.634773 -182.857501)
			(xy 75.682379 -182.886555) (xy 75.725247 -182.92223) (xy 75.762464 -182.963767) (xy 75.793237 -183.01028)
			(xy 75.816909 -183.060777) (xy 75.832977 -183.114184) (xy 75.841097 -183.16936) (xy 75.841606 -183.197246)
			(xy 75.841097 -183.225132) (xy 75.832977 -183.280308) (xy 75.816909 -183.333715) (xy 75.793237 -183.384212)
			(xy 75.762464 -183.430725) (xy 75.725247 -183.472262) (xy 75.682379 -183.507937) (xy 75.634773 -183.536991)
			(xy 75.583444 -183.558803) (xy 75.529487 -183.572909) (xy 75.47405 -183.579009) (xy 75.418316 -183.576972)
			(xy 75.363473 -183.566842) (xy 75.310689 -183.548835) (xy 75.261089 -183.523334) (xy 75.215731 -183.490883)
			(xy 75.175582 -183.452174) (xy 75.141496 -183.408031) (xy 75.1142 -183.359396) (xy 75.094277 -183.307305)
			(xy 75.082151 -183.252868) (xy 75.07808 -183.197246) (xy 66.143886 -183.197246) (xy 66.143886 -184.470548)
			(xy 66.673982 -184.470548) (xy 66.678053 -184.414926) (xy 66.690179 -184.360489) (xy 66.710102 -184.308398)
			(xy 66.737398 -184.259763) (xy 66.771484 -184.21562) (xy 66.811633 -184.176911) (xy 66.856991 -184.14446)
			(xy 66.906591 -184.118959) (xy 66.959375 -184.100952) (xy 67.014218 -184.090822) (xy 67.069952 -184.088785)
			(xy 67.125389 -184.094885) (xy 67.179346 -184.108991) (xy 67.230675 -184.130803) (xy 67.278281 -184.159857)
			(xy 67.321149 -184.195532) (xy 67.358366 -184.237069) (xy 67.389139 -184.283582) (xy 67.412811 -184.334079)
			(xy 67.428879 -184.387486) (xy 67.436999 -184.442662) (xy 67.437508 -184.470548) (xy 67.436999 -184.498434)
			(xy 67.428879 -184.55361) (xy 67.412811 -184.607017) (xy 67.389139 -184.657514) (xy 67.358366 -184.704027)
			(xy 67.339979 -184.724548) (xy 68.223382 -184.724548) (xy 68.227453 -184.668926) (xy 68.239579 -184.614489)
			(xy 68.259502 -184.562398) (xy 68.286798 -184.513763) (xy 68.320884 -184.46962) (xy 68.361033 -184.430911)
			(xy 68.406391 -184.39846) (xy 68.455991 -184.372959) (xy 68.508775 -184.354952) (xy 68.563618 -184.344822)
			(xy 68.619352 -184.342785) (xy 68.674789 -184.348885) (xy 68.728746 -184.362991) (xy 68.780075 -184.384803)
			(xy 68.827681 -184.413857) (xy 68.870549 -184.449532) (xy 68.907766 -184.491069) (xy 68.938539 -184.537582)
			(xy 68.962211 -184.588079) (xy 68.978279 -184.641486) (xy 68.986399 -184.696662) (xy 68.986908 -184.724548)
			(xy 68.98686 -184.727154) (xy 69.277665 -184.727154) (xy 69.277665 -184.672646) (xy 69.285423 -184.618693)
			(xy 69.300781 -184.566394) (xy 69.323425 -184.516812) (xy 69.352896 -184.470959) (xy 69.388593 -184.429766)
			(xy 69.429789 -184.394073) (xy 69.475646 -184.364607) (xy 69.525229 -184.341967) (xy 69.57753 -184.326615)
			(xy 69.631484 -184.318863) (xy 69.658738 -184.318402) (xy 69.690451 -184.319061) (xy 69.752999 -184.329582)
			(xy 69.812953 -184.350279) (xy 69.84111 -184.364884) (xy 69.853841 -184.371276) (xy 69.881619 -184.377528)
			(xy 69.910043 -184.375855) (xy 69.936896 -184.366388) (xy 69.960084 -184.349865) (xy 69.9778 -184.327575)
			(xy 69.988661 -184.301255) (xy 69.990716 -184.28716) (xy 69.994415 -184.259584) (xy 70.008628 -184.205795)
			(xy 70.030505 -184.154641) (xy 70.05958 -184.107209) (xy 70.095239 -184.064504) (xy 70.136723 -184.027432)
			(xy 70.183153 -183.996781) (xy 70.233543 -183.9732) (xy 70.286825 -183.95719) (xy 70.341867 -183.949091)
			(xy 70.369684 -183.948578) (xy 70.397567 -183.949055) (xy 70.452738 -183.957185) (xy 70.506137 -183.97326)
			(xy 70.556628 -183.996936) (xy 70.603134 -184.027711) (xy 70.644665 -184.064927) (xy 70.680336 -184.107793)
			(xy 70.709387 -184.155395) (xy 70.7312 -184.206719) (xy 70.738746 -184.233566) (xy 70.742686 -184.246982)
			(xy 70.756884 -184.271063) (xy 70.777076 -184.290397) (xy 70.801751 -184.303536) (xy 70.829063 -184.309498)
			(xy 70.856969 -184.307837) (xy 70.870318 -184.30367) (xy 70.900508 -184.29394) (xy 70.963065 -184.283472)
			(xy 70.994778 -184.282842) (xy 71.022035 -184.283203) (xy 71.075996 -184.290959) (xy 71.128303 -184.306315)
			(xy 71.177893 -184.328959) (xy 71.223755 -184.358431) (xy 71.264955 -184.394129) (xy 71.300656 -184.435328)
			(xy 71.33013 -184.481188) (xy 71.352777 -184.530776) (xy 71.368136 -184.583083) (xy 71.375895 -184.637043)
			(xy 71.375895 -184.691557) (xy 71.368136 -184.745517) (xy 71.352777 -184.797824) (xy 71.33013 -184.847412)
			(xy 71.300656 -184.893272) (xy 71.264955 -184.934471) (xy 71.223755 -184.970169) (xy 71.177893 -184.999641)
			(xy 71.128303 -185.022285) (xy 71.086075 -185.034682) (xy 71.588882 -185.034682) (xy 71.592953 -184.97906)
			(xy 71.605079 -184.924623) (xy 71.625002 -184.872532) (xy 71.652298 -184.823897) (xy 71.686384 -184.779754)
			(xy 71.726533 -184.741045) (xy 71.771891 -184.708594) (xy 71.821491 -184.683093) (xy 71.874275 -184.665086)
			(xy 71.929118 -184.654956) (xy 71.984852 -184.652919) (xy 72.040289 -184.659019) (xy 72.094246 -184.673125)
			(xy 72.145575 -184.694937) (xy 72.193181 -184.723991) (xy 72.236049 -184.759666) (xy 72.273266 -184.801203)
			(xy 72.304039 -184.847716) (xy 72.327711 -184.898213) (xy 72.328955 -184.902348) (xy 72.724262 -184.902348)
			(xy 72.728333 -184.846726) (xy 72.740459 -184.792289) (xy 72.760382 -184.740198) (xy 72.787678 -184.691563)
			(xy 72.821764 -184.64742) (xy 72.861913 -184.608711) (xy 72.907271 -184.57626) (xy 72.956871 -184.550759)
			(xy 73.009655 -184.532752) (xy 73.064498 -184.522622) (xy 73.120232 -184.520585) (xy 73.175669 -184.526685)
			(xy 73.229626 -184.540791) (xy 73.280955 -184.562603) (xy 73.328561 -184.591657) (xy 73.371429 -184.627332)
			(xy 73.408646 -184.668869) (xy 73.439419 -184.715382) (xy 73.463091 -184.765879) (xy 73.479159 -184.819286)
			(xy 73.487279 -184.874462) (xy 73.487788 -184.902348) (xy 73.487279 -184.930234) (xy 73.479159 -184.98541)
			(xy 73.463091 -185.038817) (xy 73.439419 -185.089314) (xy 73.408646 -185.135827) (xy 73.371429 -185.177364)
			(xy 73.328561 -185.213039) (xy 73.280955 -185.242093) (xy 73.229626 -185.263905) (xy 73.175669 -185.278011)
			(xy 73.120232 -185.284111) (xy 73.064498 -185.282074) (xy 73.009655 -185.271944) (xy 72.956871 -185.253937)
			(xy 72.907271 -185.228436) (xy 72.861913 -185.195985) (xy 72.821764 -185.157276) (xy 72.787678 -185.113133)
			(xy 72.760382 -185.064498) (xy 72.740459 -185.012407) (xy 72.728333 -184.95797) (xy 72.724262 -184.902348)
			(xy 72.328955 -184.902348) (xy 72.343779 -184.95162) (xy 72.351899 -185.006796) (xy 72.352408 -185.034682)
			(xy 72.351899 -185.062568) (xy 72.343779 -185.117744) (xy 72.327711 -185.171151) (xy 72.304039 -185.221648)
			(xy 72.273266 -185.268161) (xy 72.236049 -185.309698) (xy 72.193181 -185.345373) (xy 72.145575 -185.374427)
			(xy 72.094246 -185.396239) (xy 72.040289 -185.410345) (xy 71.984852 -185.416445) (xy 71.929118 -185.414408)
			(xy 71.874275 -185.404278) (xy 71.821491 -185.386271) (xy 71.771891 -185.36077) (xy 71.726533 -185.328319)
			(xy 71.686384 -185.28961) (xy 71.652298 -185.245467) (xy 71.625002 -185.196832) (xy 71.605079 -185.144741)
			(xy 71.592953 -185.090304) (xy 71.588882 -185.034682) (xy 71.086075 -185.034682) (xy 71.075996 -185.037641)
			(xy 71.022035 -185.045397) (xy 70.994778 -185.045858) (xy 70.966898 -185.045298) (xy 70.911732 -185.037178)
			(xy 70.858336 -185.021113) (xy 70.807847 -184.997447) (xy 70.761342 -184.966683) (xy 70.71981 -184.929477)
			(xy 70.684137 -184.886621) (xy 70.655082 -184.839028) (xy 70.633265 -184.787713) (xy 70.625716 -184.76087)
			(xy 70.621683 -184.747485) (xy 70.607504 -184.72341) (xy 70.587332 -184.704077) (xy 70.562676 -184.690932)
			(xy 70.535381 -184.684961) (xy 70.507488 -184.686608) (xy 70.494144 -184.690766) (xy 70.463956 -184.700504)
			(xy 70.401398 -184.710967) (xy 70.369684 -184.711594) (xy 70.337972 -184.710926) (xy 70.275424 -184.700409)
			(xy 70.215469 -184.679715) (xy 70.187312 -184.665112) (xy 70.174567 -184.65875) (xy 70.146794 -184.652495)
			(xy 70.118374 -184.654163) (xy 70.091525 -184.663625) (xy 70.068338 -184.680143) (xy 70.050623 -184.702428)
			(xy 70.039761 -184.728743) (xy 70.037706 -184.742836) (xy 70.03416 -184.770435) (xy 70.01993 -184.824232)
			(xy 69.998036 -184.87539) (xy 69.968943 -184.922825) (xy 69.933266 -184.96553) (xy 69.891765 -185.002599)
			(xy 69.845318 -185.033246) (xy 69.794912 -185.05682) (xy 69.741616 -185.072822) (xy 69.686561 -185.080911)
			(xy 69.658738 -185.081418) (xy 69.631484 -185.080937) (xy 69.57753 -185.073185) (xy 69.525229 -185.057833)
			(xy 69.475646 -185.035193) (xy 69.429789 -185.005727) (xy 69.388593 -184.970034) (xy 69.352896 -184.928841)
			(xy 69.323425 -184.882988) (xy 69.300781 -184.833406) (xy 69.285423 -184.781107) (xy 69.277665 -184.727154)
			(xy 68.98686 -184.727154) (xy 68.986399 -184.752434) (xy 68.978279 -184.80761) (xy 68.962211 -184.861017)
			(xy 68.938539 -184.911514) (xy 68.907766 -184.958027) (xy 68.870549 -184.999564) (xy 68.827681 -185.035239)
			(xy 68.780075 -185.064293) (xy 68.728746 -185.086105) (xy 68.674789 -185.100211) (xy 68.619352 -185.106311)
			(xy 68.563618 -185.104274) (xy 68.508775 -185.094144) (xy 68.455991 -185.076137) (xy 68.406391 -185.050636)
			(xy 68.361033 -185.018185) (xy 68.320884 -184.979476) (xy 68.286798 -184.935333) (xy 68.259502 -184.886698)
			(xy 68.239579 -184.834607) (xy 68.227453 -184.78017) (xy 68.223382 -184.724548) (xy 67.339979 -184.724548)
			(xy 67.321149 -184.745564) (xy 67.278281 -184.781239) (xy 67.230675 -184.810293) (xy 67.179346 -184.832105)
			(xy 67.125389 -184.846211) (xy 67.069952 -184.852311) (xy 67.014218 -184.850274) (xy 66.959375 -184.840144)
			(xy 66.906591 -184.822137) (xy 66.856991 -184.796636) (xy 66.811633 -184.764185) (xy 66.771484 -184.725476)
			(xy 66.737398 -184.681333) (xy 66.710102 -184.632698) (xy 66.690179 -184.580607) (xy 66.678053 -184.52617)
			(xy 66.673982 -184.470548) (xy 66.143886 -184.470548) (xy 66.143886 -185.664348) (xy 67.359782 -185.664348)
			(xy 67.363853 -185.608726) (xy 67.375979 -185.554289) (xy 67.395902 -185.502198) (xy 67.423198 -185.453563)
			(xy 67.457284 -185.40942) (xy 67.497433 -185.370711) (xy 67.542791 -185.33826) (xy 67.592391 -185.312759)
			(xy 67.645175 -185.294752) (xy 67.700018 -185.284622) (xy 67.755752 -185.282585) (xy 67.811189 -185.288685)
			(xy 67.865146 -185.302791) (xy 67.916475 -185.324603) (xy 67.964081 -185.353657) (xy 68.006949 -185.389332)
			(xy 68.044166 -185.430869) (xy 68.074939 -185.477382) (xy 68.098611 -185.527879) (xy 68.114679 -185.581286)
			(xy 68.122799 -185.636462) (xy 68.123308 -185.664348) (xy 68.122799 -185.692234) (xy 68.114679 -185.74741)
			(xy 68.098611 -185.800817) (xy 68.074939 -185.851314) (xy 68.044166 -185.897827) (xy 68.006949 -185.939364)
			(xy 67.964081 -185.975039) (xy 67.916475 -186.004093) (xy 67.865146 -186.025905) (xy 67.811189 -186.040011)
			(xy 67.755752 -186.046111) (xy 67.700018 -186.044074) (xy 67.645175 -186.033944) (xy 67.592391 -186.015937)
			(xy 67.542791 -185.990436) (xy 67.497433 -185.957985) (xy 67.457284 -185.919276) (xy 67.423198 -185.875133)
			(xy 67.395902 -185.826498) (xy 67.375979 -185.774407) (xy 67.363853 -185.71997) (xy 67.359782 -185.664348)
			(xy 66.143886 -185.664348) (xy 66.143886 -186.070748) (xy 71.844914 -186.070748) (xy 71.848985 -186.015126)
			(xy 71.861111 -185.960689) (xy 71.881034 -185.908598) (xy 71.90833 -185.859963) (xy 71.942416 -185.81582)
			(xy 71.982565 -185.777111) (xy 72.027923 -185.74466) (xy 72.077523 -185.719159) (xy 72.130307 -185.701152)
			(xy 72.18515 -185.691022) (xy 72.240884 -185.688985) (xy 72.296321 -185.695085) (xy 72.350278 -185.709191)
			(xy 72.401607 -185.731003) (xy 72.449213 -185.760057) (xy 72.492081 -185.795732) (xy 72.529298 -185.837269)
			(xy 72.560071 -185.883782) (xy 72.583743 -185.934279) (xy 72.599811 -185.987686) (xy 72.607931 -186.042862)
			(xy 72.60844 -186.070748) (xy 72.607931 -186.098634) (xy 72.599811 -186.15381) (xy 72.583743 -186.207217)
			(xy 72.560071 -186.257714) (xy 72.529298 -186.304227) (xy 72.492081 -186.345764) (xy 72.449213 -186.381439)
			(xy 72.401607 -186.410493) (xy 72.350278 -186.432305) (xy 72.296321 -186.446411) (xy 72.240884 -186.452511)
			(xy 72.18515 -186.450474) (xy 72.130307 -186.440344) (xy 72.077523 -186.422337) (xy 72.027923 -186.396836)
			(xy 71.982565 -186.364385) (xy 71.942416 -186.325676) (xy 71.90833 -186.281533) (xy 71.881034 -186.232898)
			(xy 71.861111 -186.180807) (xy 71.848985 -186.12637) (xy 71.844914 -186.070748) (xy 66.143886 -186.070748)
			(xy 66.143886 -187.486642) (xy 67.775104 -187.486642) (xy 67.775105 -187.432146) (xy 67.782861 -187.378203)
			(xy 67.798215 -187.325914) (xy 67.820854 -187.276342) (xy 67.850317 -187.230496) (xy 67.886004 -187.18931)
			(xy 67.92719 -187.153622) (xy 67.973035 -187.124157) (xy 68.022607 -187.101518) (xy 68.074896 -187.086163)
			(xy 68.128838 -187.078405) (xy 68.183334 -187.078403) (xy 68.237277 -187.086157) (xy 68.289567 -187.101508)
			(xy 68.33914 -187.124144) (xy 68.384988 -187.153605) (xy 68.426176 -187.18929) (xy 68.461866 -187.230474)
			(xy 68.491333 -187.276317) (xy 68.513975 -187.325888) (xy 68.529333 -187.378176) (xy 68.537093 -187.432118)
			(xy 68.537582 -187.459366) (xy 68.537474 -187.473388) (xy 68.53544 -187.501356) (xy 68.533518 -187.515246)
			(xy 68.531778 -187.530214) (xy 68.536199 -187.560008) (xy 68.549127 -187.587212) (xy 68.569435 -187.609456)
			(xy 68.595354 -187.624801) (xy 68.624624 -187.631909) (xy 68.63969 -187.631578) (xy 68.661788 -187.63107)
			(xy 68.689042 -187.631542) (xy 68.742996 -187.639298) (xy 68.795297 -187.654653) (xy 68.84488 -187.677296)
			(xy 68.890736 -187.706764) (xy 68.931932 -187.742459) (xy 68.967628 -187.783653) (xy 68.997098 -187.829509)
			(xy 69.019742 -187.879091) (xy 69.035099 -187.931391) (xy 69.042857 -187.985345) (xy 69.042857 -188.039854)
			(xy 69.0351 -188.093807) (xy 69.019743 -188.146108) (xy 68.997099 -188.19569) (xy 68.967629 -188.241546)
			(xy 68.931933 -188.28274) (xy 68.890738 -188.318435) (xy 68.844882 -188.347904) (xy 68.795298 -188.370546)
			(xy 68.742997 -188.385902) (xy 68.689044 -188.393658) (xy 68.634535 -188.393656) (xy 68.580582 -188.385897)
			(xy 68.528282 -188.370539) (xy 68.4787 -188.347893) (xy 68.432845 -188.318422) (xy 68.391652 -188.282725)
			(xy 68.355958 -188.241528) (xy 68.326491 -188.195672) (xy 68.30385 -188.146088) (xy 68.288496 -188.093786)
			(xy 68.280741 -188.039832) (xy 68.28028 -188.012578) (xy 68.280383 -187.998556) (xy 68.28242 -187.970587)
			(xy 68.284344 -187.956698) (xy 68.28608 -187.941728) (xy 68.281669 -187.91193) (xy 68.268745 -187.884721)
			(xy 68.248435 -187.862474) (xy 68.222513 -187.847131) (xy 68.193239 -187.84003) (xy 68.178172 -187.840366)
			(xy 68.156074 -187.840874) (xy 68.128826 -187.840394) (xy 68.074884 -187.832635) (xy 68.022595 -187.817278)
			(xy 67.973024 -187.794637) (xy 67.92718 -187.765171) (xy 67.885996 -187.729482) (xy 67.85031 -187.688294)
			(xy 67.820848 -187.642447) (xy 67.798211 -187.592875) (xy 67.782858 -187.540585) (xy 67.775104 -187.486642)
			(xy 66.143886 -187.486642) (xy 66.143886 -189.330838) (xy 65.600834 -189.87389) (xy 67.18122 -189.87389)
			(xy 67.185291 -189.818268) (xy 67.197417 -189.763831) (xy 67.21734 -189.71174) (xy 67.244636 -189.663105)
			(xy 67.278722 -189.618962) (xy 67.318871 -189.580253) (xy 67.364229 -189.547802) (xy 67.413829 -189.522301)
			(xy 67.466613 -189.504294) (xy 67.521456 -189.494164) (xy 67.57719 -189.492127) (xy 67.632627 -189.498227)
			(xy 67.686584 -189.512333) (xy 67.737913 -189.534145) (xy 67.785519 -189.563199) (xy 67.828387 -189.598874)
			(xy 67.865604 -189.640411) (xy 67.896377 -189.686924) (xy 67.920049 -189.737421) (xy 67.936117 -189.790828)
			(xy 67.944237 -189.846004) (xy 67.944746 -189.87389) (xy 67.944237 -189.901776) (xy 67.936117 -189.956952)
			(xy 67.920049 -190.010359) (xy 67.896377 -190.060856) (xy 67.865604 -190.107369) (xy 67.828387 -190.148906)
			(xy 67.785519 -190.184581) (xy 67.737913 -190.213635) (xy 67.686584 -190.235447) (xy 67.632627 -190.249553)
			(xy 67.57719 -190.255653) (xy 67.521456 -190.253616) (xy 67.466613 -190.243486) (xy 67.413829 -190.225479)
			(xy 67.364229 -190.199978) (xy 67.318871 -190.167527) (xy 67.278722 -190.128818) (xy 67.244636 -190.084675)
			(xy 67.21734 -190.03604) (xy 67.197417 -189.983949) (xy 67.185291 -189.929512) (xy 67.18122 -189.87389)
			(xy 65.600834 -189.87389) (xy 62.987936 -192.486788) (xy 65.533522 -192.486788) (xy 65.537593 -192.431166)
			(xy 65.549719 -192.376729) (xy 65.569642 -192.324638) (xy 65.596938 -192.276003) (xy 65.631024 -192.23186)
			(xy 65.671173 -192.193151) (xy 65.716531 -192.1607) (xy 65.766131 -192.135199) (xy 65.818915 -192.117192)
			(xy 65.873758 -192.107062) (xy 65.929492 -192.105025) (xy 65.984929 -192.111125) (xy 66.038886 -192.125231)
			(xy 66.090215 -192.147043) (xy 66.137821 -192.176097) (xy 66.180689 -192.211772) (xy 66.217906 -192.253309)
			(xy 66.248679 -192.299822) (xy 66.272351 -192.350319) (xy 66.288419 -192.403726) (xy 66.296539 -192.458902)
			(xy 66.297048 -192.486788) (xy 66.296539 -192.514674) (xy 66.288419 -192.56985) (xy 66.272351 -192.623257)
			(xy 66.248679 -192.673754) (xy 66.217906 -192.720267) (xy 66.180689 -192.761804) (xy 66.137821 -192.797479)
			(xy 66.090215 -192.826533) (xy 66.038886 -192.848345) (xy 65.984929 -192.862451) (xy 65.929492 -192.868551)
			(xy 65.873758 -192.866514) (xy 65.818915 -192.856384) (xy 65.766131 -192.838377) (xy 65.716531 -192.812876)
			(xy 65.671173 -192.780425) (xy 65.631024 -192.741716) (xy 65.596938 -192.697573) (xy 65.569642 -192.648938)
			(xy 65.549719 -192.596847) (xy 65.537593 -192.54241) (xy 65.533522 -192.486788) (xy 62.987936 -192.486788)
			(xy 62.854078 -192.620646) (xy 61.19495 -192.620646) (xy 61.180218 -192.635378) (xy 60.520326 -192.635378)
			(xy 60.02147 -193.134234) (xy 60.02147 -194.475354) (xy 60.042685 -194.490837) (xy 60.080751 -194.52702)
			(xy 60.11309 -194.568402) (xy 60.139001 -194.614085) (xy 60.157921 -194.663078) (xy 60.16944 -194.714319)
			(xy 60.173308 -194.766695) (xy 60.171341 -194.793341) (xy 63.586604 -194.793341) (xy 63.586604 -194.740043)
			(xy 63.594547 -194.687339) (xy 63.610257 -194.636409) (xy 63.633383 -194.588388) (xy 63.663407 -194.544351)
			(xy 63.699659 -194.50528) (xy 63.74133 -194.472049) (xy 63.787488 -194.4454) (xy 63.837102 -194.425928)
			(xy 63.889064 -194.414068) (xy 63.942214 -194.410085) (xy 63.995364 -194.414068) (xy 64.047326 -194.425928)
			(xy 64.09694 -194.4454) (xy 64.143098 -194.472049) (xy 64.184769 -194.50528) (xy 64.221021 -194.544351)
			(xy 64.251045 -194.588388) (xy 64.274171 -194.636409) (xy 64.289881 -194.687339) (xy 64.297824 -194.740043)
			(xy 64.298322 -194.766692) (xy 64.297824 -194.793341) (xy 65.796404 -194.793341) (xy 65.796404 -194.740043)
			(xy 65.804347 -194.687339) (xy 65.820057 -194.636409) (xy 65.843183 -194.588388) (xy 65.873207 -194.544351)
			(xy 65.909459 -194.50528) (xy 65.95113 -194.472049) (xy 65.997288 -194.4454) (xy 66.046902 -194.425928)
			(xy 66.098864 -194.414068) (xy 66.152014 -194.410085) (xy 66.205164 -194.414068) (xy 66.257126 -194.425928)
			(xy 66.30674 -194.4454) (xy 66.352898 -194.472049) (xy 66.394569 -194.50528) (xy 66.430821 -194.544351)
			(xy 66.460845 -194.588388) (xy 66.483971 -194.636409) (xy 66.499681 -194.687339) (xy 66.507624 -194.740043)
			(xy 66.508122 -194.766692) (xy 66.507624 -194.793341) (xy 66.499681 -194.846045) (xy 66.483971 -194.896975)
			(xy 66.460845 -194.944996) (xy 66.430821 -194.989033) (xy 66.394569 -195.028104) (xy 66.352898 -195.061335)
			(xy 66.30674 -195.087984) (xy 66.257126 -195.107456) (xy 66.205164 -195.119316) (xy 66.152014 -195.1233)
			(xy 66.098864 -195.119316) (xy 66.046902 -195.107456) (xy 65.997288 -195.087984) (xy 65.95113 -195.061335)
			(xy 65.909459 -195.028104) (xy 65.873207 -194.989033) (xy 65.843183 -194.944996) (xy 65.820057 -194.896975)
			(xy 65.804347 -194.846045) (xy 65.796404 -194.793341) (xy 64.297824 -194.793341) (xy 64.289881 -194.846045)
			(xy 64.274171 -194.896975) (xy 64.251045 -194.944996) (xy 64.221021 -194.989033) (xy 64.184769 -195.028104)
			(xy 64.143098 -195.061335) (xy 64.09694 -195.087984) (xy 64.047326 -195.107456) (xy 63.995364 -195.119316)
			(xy 63.942214 -195.1233) (xy 63.889064 -195.119316) (xy 63.837102 -195.107456) (xy 63.787488 -195.087984)
			(xy 63.74133 -195.061335) (xy 63.699659 -195.028104) (xy 63.663407 -194.989033) (xy 63.633383 -194.944996)
			(xy 63.610257 -194.896975) (xy 63.594547 -194.846045) (xy 63.586604 -194.793341) (xy 60.171341 -194.793341)
			(xy 60.169441 -194.819072) (xy 60.157924 -194.870313) (xy 60.139005 -194.919307) (xy 60.113095 -194.96499)
			(xy 60.080757 -195.006373) (xy 60.042692 -195.042557) (xy 60.02147 -195.05803) (xy 60.02147 -195.308982)
			(xy 60.044149 -195.322772) (xy 60.085524 -195.356018) (xy 60.121506 -195.395036) (xy 60.151298 -195.438962)
			(xy 60.17424 -195.486824) (xy 60.189823 -195.537561) (xy 60.197703 -195.59005) (xy 60.197705 -195.643126)
			(xy 60.19769 -195.643225) (xy 61.696336 -195.643225) (xy 61.696336 -195.589927) (xy 61.704279 -195.537223)
			(xy 61.719989 -195.486293) (xy 61.743115 -195.438272) (xy 61.773139 -195.394235) (xy 61.809391 -195.355164)
			(xy 61.851062 -195.321933) (xy 61.89722 -195.295284) (xy 61.946834 -195.275812) (xy 61.998796 -195.263952)
			(xy 62.051946 -195.259969) (xy 62.105096 -195.263952) (xy 62.157058 -195.275812) (xy 62.206672 -195.295284)
			(xy 62.25283 -195.321933) (xy 62.294501 -195.355164) (xy 62.330753 -195.394235) (xy 62.360777 -195.438272)
			(xy 62.383903 -195.486293) (xy 62.399613 -195.537223) (xy 62.407556 -195.589927) (xy 62.408054 -195.616576)
			(xy 62.407556 -195.643225) (xy 62.399613 -195.695929) (xy 62.383903 -195.746859) (xy 62.360777 -195.79488)
			(xy 62.342591 -195.821554) (xy 64.296036 -195.821554) (xy 64.296036 -195.412614) (xy 64.296475 -195.402444)
			(xy 64.304255 -195.383649) (xy 64.318636 -195.369264) (xy 64.337428 -195.361478) (xy 64.347598 -195.361052)
			(xy 65.747138 -195.361052) (xy 65.7573 -195.361503) (xy 65.776073 -195.369292) (xy 65.790437 -195.383671)
			(xy 65.798208 -195.402452) (xy 65.7987 -195.412614) (xy 65.7987 -195.821554) (xy 65.798199 -195.831718)
			(xy 65.790437 -195.850504) (xy 65.776075 -195.864889) (xy 65.757301 -195.872683) (xy 65.747138 -195.873116)
			(xy 64.347598 -195.873116) (xy 64.337421 -195.872737) (xy 64.318617 -195.864942) (xy 64.304231 -195.850543)
			(xy 64.296454 -195.831732) (xy 64.296036 -195.821554) (xy 62.342591 -195.821554) (xy 62.330753 -195.838917)
			(xy 62.294501 -195.877988) (xy 62.25283 -195.911219) (xy 62.206672 -195.937868) (xy 62.157058 -195.95734)
			(xy 62.105096 -195.9692) (xy 62.051946 -195.973184) (xy 61.998796 -195.9692) (xy 61.946834 -195.95734)
			(xy 61.89722 -195.937868) (xy 61.851062 -195.911219) (xy 61.809391 -195.877988) (xy 61.773139 -195.838917)
			(xy 61.743115 -195.79488) (xy 61.719989 -195.746859) (xy 61.704279 -195.695929) (xy 61.696336 -195.643225)
			(xy 60.19769 -195.643225) (xy 60.189828 -195.695615) (xy 60.174248 -195.746353) (xy 60.15131 -195.794217)
			(xy 60.121521 -195.838145) (xy 60.085542 -195.877166) (xy 60.044169 -195.910414) (xy 60.02147 -195.92417)
			(xy 60.02147 -196.671438) (xy 60.195968 -196.671438) (xy 60.195968 -196.262498) (xy 60.196363 -196.252323)
			(xy 60.204154 -196.233522) (xy 60.218549 -196.219136) (xy 60.237354 -196.211357) (xy 60.24753 -196.210936)
			(xy 61.64707 -196.210936) (xy 61.657239 -196.211389) (xy 61.676033 -196.219163) (xy 61.690419 -196.23354)
			(xy 61.698205 -196.252329) (xy 61.698632 -196.262498) (xy 61.698632 -196.493363) (xy 63.586604 -196.493363)
			(xy 63.586604 -196.440065) (xy 63.594547 -196.387361) (xy 63.610257 -196.336431) (xy 63.633383 -196.28841)
			(xy 63.663407 -196.244373) (xy 63.699659 -196.205302) (xy 63.74133 -196.172071) (xy 63.787488 -196.145422)
			(xy 63.837102 -196.12595) (xy 63.889064 -196.11409) (xy 63.942214 -196.110107) (xy 63.995364 -196.11409)
			(xy 64.047326 -196.12595) (xy 64.09694 -196.145422) (xy 64.143098 -196.172071) (xy 64.184769 -196.205302)
			(xy 64.221021 -196.244373) (xy 64.251045 -196.28841) (xy 64.274171 -196.336431) (xy 64.289881 -196.387361)
			(xy 64.297824 -196.440065) (xy 64.298322 -196.466714) (xy 64.297824 -196.493363) (xy 65.796404 -196.493363)
			(xy 65.796404 -196.440065) (xy 65.804347 -196.387361) (xy 65.820057 -196.336431) (xy 65.843183 -196.28841)
			(xy 65.873207 -196.244373) (xy 65.909459 -196.205302) (xy 65.95113 -196.172071) (xy 65.997288 -196.145422)
			(xy 66.046902 -196.12595) (xy 66.098864 -196.11409) (xy 66.152014 -196.110107) (xy 66.205164 -196.11409)
			(xy 66.257126 -196.12595) (xy 66.30674 -196.145422) (xy 66.352898 -196.172071) (xy 66.394569 -196.205302)
			(xy 66.430821 -196.244373) (xy 66.460845 -196.28841) (xy 66.483971 -196.336431) (xy 66.499681 -196.387361)
			(xy 66.507624 -196.440065) (xy 66.508122 -196.466714) (xy 66.507624 -196.493363) (xy 66.499681 -196.546067)
			(xy 66.483971 -196.596997) (xy 66.460845 -196.645018) (xy 66.430821 -196.689055) (xy 66.394569 -196.728126)
			(xy 66.352898 -196.761357) (xy 66.30674 -196.788006) (xy 66.257126 -196.807478) (xy 66.205164 -196.819338)
			(xy 66.152014 -196.823322) (xy 66.098864 -196.819338) (xy 66.046902 -196.807478) (xy 65.997288 -196.788006)
			(xy 65.95113 -196.761357) (xy 65.909459 -196.728126) (xy 65.873207 -196.689055) (xy 65.843183 -196.645018)
			(xy 65.820057 -196.596997) (xy 65.804347 -196.546067) (xy 65.796404 -196.493363) (xy 64.297824 -196.493363)
			(xy 64.289881 -196.546067) (xy 64.274171 -196.596997) (xy 64.251045 -196.645018) (xy 64.221021 -196.689055)
			(xy 64.184769 -196.728126) (xy 64.143098 -196.761357) (xy 64.09694 -196.788006) (xy 64.047326 -196.807478)
			(xy 63.995364 -196.819338) (xy 63.942214 -196.823322) (xy 63.889064 -196.819338) (xy 63.837102 -196.807478)
			(xy 63.787488 -196.788006) (xy 63.74133 -196.761357) (xy 63.699659 -196.728126) (xy 63.663407 -196.689055)
			(xy 63.633383 -196.645018) (xy 63.610257 -196.596997) (xy 63.594547 -196.546067) (xy 63.586604 -196.493363)
			(xy 61.698632 -196.493363) (xy 61.698632 -196.671438) (xy 61.698197 -196.681602) (xy 61.690404 -196.700378)
			(xy 61.676021 -196.714743) (xy 61.657235 -196.72251) (xy 61.64707 -196.723) (xy 60.24753 -196.723)
			(xy 60.237379 -196.722443) (xy 60.218617 -196.714686) (xy 60.204252 -196.70034) (xy 60.19647 -196.681589)
			(xy 60.195968 -196.671438) (xy 60.02147 -196.671438) (xy 60.02147 -197.009004) (xy 60.045706 -197.023781)
			(xy 60.089583 -197.05979) (xy 60.127204 -197.102293) (xy 60.157619 -197.150217) (xy 60.18006 -197.202354)
			(xy 60.193962 -197.257386) (xy 60.196984 -197.28561) (xy 60.198508 -197.304152) (xy 60.426346 -197.53199)
		)
		(stroke
			(width 0)
			(type solid)
		)
		(fill yes)
		(layer "In2.Cu")
		(net "PVCCD_HV_CPU1")
	)
	(gr_poly
		(pts
			(xy 443.337188 -79.168752) (xy 443.337747 -79.139779) (xy 443.346855 -79.082551) (xy 443.364807 -79.027454)
			(xy 443.391161 -78.975846) (xy 443.425267 -78.928999) (xy 443.445392 -78.908148) (xy 444.6778 -77.675486)
			(xy 444.681102 -77.670152) (xy 444.695994 -77.646364) (xy 444.731658 -77.603033) (xy 444.773283 -77.565392)
			(xy 444.819972 -77.534253) (xy 444.870718 -77.510288) (xy 444.924427 -77.494013) (xy 444.97994 -77.485779)
			(xy 445.008 -77.48524) (xy 445.035252 -77.485703) (xy 445.0892 -77.493461) (xy 445.141495 -77.508817)
			(xy 445.191072 -77.53146) (xy 445.236922 -77.560929) (xy 445.278111 -77.596623) (xy 445.3138 -77.637817)
			(xy 445.343263 -77.68367) (xy 445.3659 -77.73325) (xy 445.38125 -77.785547) (xy 445.389 -77.839496)
			(xy 445.389508 -77.866748) (xy 445.388981 -77.895249) (xy 445.380501 -77.951616) (xy 445.363723 -78.006092)
			(xy 445.33902 -78.057462) (xy 445.306943 -78.104581) (xy 445.268207 -78.146399) (xy 445.223677 -78.181982)
			(xy 445.199262 -78.196694) (xy 444.476033 -78.920086) (xy 447.149726 -78.920086) (xy 447.153797 -78.864464)
			(xy 447.165923 -78.810027) (xy 447.185846 -78.757936) (xy 447.213142 -78.709301) (xy 447.247228 -78.665158)
			(xy 447.287377 -78.626449) (xy 447.332735 -78.593998) (xy 447.382335 -78.568497) (xy 447.435119 -78.55049)
			(xy 447.489962 -78.54036) (xy 447.545696 -78.538323) (xy 447.601133 -78.544423) (xy 447.65509 -78.558529)
			(xy 447.706419 -78.580341) (xy 447.754025 -78.609395) (xy 447.796893 -78.64507) (xy 447.83411 -78.686607)
			(xy 447.864883 -78.73312) (xy 447.888555 -78.783617) (xy 447.904623 -78.837024) (xy 447.908212 -78.861412)
			(xy 449.002402 -78.861412) (xy 449.006473 -78.80579) (xy 449.018599 -78.751353) (xy 449.038522 -78.699262)
			(xy 449.065818 -78.650627) (xy 449.099904 -78.606484) (xy 449.140053 -78.567775) (xy 449.185411 -78.535324)
			(xy 449.235011 -78.509823) (xy 449.287795 -78.491816) (xy 449.342638 -78.481686) (xy 449.398372 -78.479649)
			(xy 449.453809 -78.485749) (xy 449.507766 -78.499855) (xy 449.559095 -78.521667) (xy 449.606701 -78.550721)
			(xy 449.649569 -78.586396) (xy 449.686786 -78.627933) (xy 449.717559 -78.674446) (xy 449.741231 -78.724943)
			(xy 449.757299 -78.77835) (xy 449.765419 -78.833526) (xy 449.765928 -78.861412) (xy 449.765419 -78.889298)
			(xy 449.757299 -78.944474) (xy 449.741231 -78.997881) (xy 449.717559 -79.048378) (xy 449.686786 -79.094891)
			(xy 449.649569 -79.136428) (xy 449.606701 -79.172103) (xy 449.559095 -79.201157) (xy 449.507766 -79.222969)
			(xy 449.453809 -79.237075) (xy 449.398372 -79.243175) (xy 449.342638 -79.241138) (xy 449.287795 -79.231008)
			(xy 449.235011 -79.213001) (xy 449.185411 -79.1875) (xy 449.140053 -79.155049) (xy 449.099904 -79.11634)
			(xy 449.065818 -79.072197) (xy 449.038522 -79.023562) (xy 449.018599 -78.971471) (xy 449.006473 -78.917034)
			(xy 449.002402 -78.861412) (xy 447.908212 -78.861412) (xy 447.912743 -78.8922) (xy 447.913252 -78.920086)
			(xy 447.912743 -78.947972) (xy 447.904623 -79.003148) (xy 447.888555 -79.056555) (xy 447.864883 -79.107052)
			(xy 447.83411 -79.153565) (xy 447.796893 -79.195102) (xy 447.754025 -79.230777) (xy 447.706419 -79.259831)
			(xy 447.65509 -79.281643) (xy 447.601133 -79.295749) (xy 447.545696 -79.301849) (xy 447.489962 -79.299812)
			(xy 447.435119 -79.289682) (xy 447.382335 -79.271675) (xy 447.332735 -79.246174) (xy 447.287377 -79.213723)
			(xy 447.247228 -79.175014) (xy 447.213142 -79.130871) (xy 447.185846 -79.082236) (xy 447.165923 -79.030145)
			(xy 447.153797 -78.975708) (xy 447.149726 -78.920086) (xy 444.476033 -78.920086) (xy 444.074804 -79.321406)
			(xy 444.074804 -80.127348) (xy 466.17128 -80.127348) (xy 468.495126 -77.803248) (xy 468.495126 -54.770274)
			(xy 460.8322 -47.107348) (xy 451.909434 -47.107348) (xy 451.887335 -47.120712) (xy 451.84019 -47.141797)
			(xy 451.790561 -47.156088) (xy 451.739423 -47.163304) (xy 451.7136 -47.163736) (xy 442.843666 -47.163736)
			(xy 441.534873 -48.472344) (xy 445.193418 -48.472344) (xy 445.197489 -48.416722) (xy 445.209615 -48.362285)
			(xy 445.229538 -48.310194) (xy 445.256834 -48.261559) (xy 445.29092 -48.217416) (xy 445.331069 -48.178707)
			(xy 445.376427 -48.146256) (xy 445.426027 -48.120755) (xy 445.478811 -48.102748) (xy 445.533654 -48.092618)
			(xy 445.589388 -48.090581) (xy 445.644825 -48.096681) (xy 445.698782 -48.110787) (xy 445.750111 -48.132599)
			(xy 445.797717 -48.161653) (xy 445.840585 -48.197328) (xy 445.877802 -48.238865) (xy 445.908575 -48.285378)
			(xy 445.932247 -48.335875) (xy 445.948315 -48.389282) (xy 445.956435 -48.444458) (xy 445.956944 -48.472344)
			(xy 445.956435 -48.50023) (xy 445.948315 -48.555406) (xy 445.932247 -48.608813) (xy 445.908575 -48.65931)
			(xy 445.877802 -48.705823) (xy 445.840585 -48.74736) (xy 445.797717 -48.783035) (xy 445.750111 -48.812089)
			(xy 445.698782 -48.833901) (xy 445.644825 -48.848007) (xy 445.589388 -48.854107) (xy 445.533654 -48.85207)
			(xy 445.478811 -48.84194) (xy 445.426027 -48.823933) (xy 445.376427 -48.798432) (xy 445.331069 -48.765981)
			(xy 445.29092 -48.727272) (xy 445.256834 -48.683129) (xy 445.229538 -48.634494) (xy 445.209615 -48.582403)
			(xy 445.197489 -48.527966) (xy 445.193418 -48.472344) (xy 441.534873 -48.472344) (xy 441.0456 -48.961548)
			(xy 441.0456 -49.476406) (xy 448.662047 -49.476406) (xy 448.666083 -49.392959) (xy 448.678155 -49.310291)
			(xy 448.698148 -49.229174) (xy 448.725877 -49.150365) (xy 448.761083 -49.0746) (xy 448.803437 -49.002587)
			(xy 448.852543 -48.934998) (xy 448.907944 -48.872464) (xy 448.969121 -48.815569) (xy 449.035504 -48.764843)
			(xy 449.106472 -48.720762) (xy 449.181364 -48.683736) (xy 449.25948 -48.65411) (xy 449.34009 -48.632162)
			(xy 449.422442 -48.618097) (xy 449.505768 -48.612045) (xy 449.589288 -48.614064) (xy 449.672224 -48.624134)
			(xy 449.7538 -48.642162) (xy 449.833256 -48.667979) (xy 449.909849 -48.701344) (xy 449.982865 -48.741945)
			(xy 450.051621 -48.789404) (xy 450.115475 -48.843277) (xy 450.173832 -48.903062) (xy 450.226147 -48.968199)
			(xy 450.27193 -49.038082) (xy 450.310755 -49.112057) (xy 450.34226 -49.189434) (xy 450.366149 -49.269491)
			(xy 450.3822 -49.351479) (xy 450.390263 -49.434634) (xy 450.390768 -49.476406) (xy 456.170287 -49.476406)
			(xy 456.174323 -49.392959) (xy 456.186395 -49.310291) (xy 456.206388 -49.229174) (xy 456.234117 -49.150365)
			(xy 456.269323 -49.0746) (xy 456.311677 -49.002587) (xy 456.360783 -48.934998) (xy 456.416184 -48.872464)
			(xy 456.477361 -48.815569) (xy 456.543744 -48.764843) (xy 456.614712 -48.720762) (xy 456.689604 -48.683736)
			(xy 456.76772 -48.65411) (xy 456.84833 -48.632162) (xy 456.930682 -48.618097) (xy 457.014008 -48.612045)
			(xy 457.097528 -48.614064) (xy 457.180464 -48.624134) (xy 457.26204 -48.642162) (xy 457.341496 -48.667979)
			(xy 457.418089 -48.701344) (xy 457.491105 -48.741945) (xy 457.559861 -48.789404) (xy 457.623715 -48.843277)
			(xy 457.682072 -48.903062) (xy 457.734387 -48.968199) (xy 457.78017 -49.038082) (xy 457.818995 -49.112057)
			(xy 457.8505 -49.189434) (xy 457.874389 -49.269491) (xy 457.89044 -49.351479) (xy 457.898503 -49.434634)
			(xy 457.899008 -49.476406) (xy 457.898503 -49.518178) (xy 457.89044 -49.601333) (xy 457.874389 -49.683321)
			(xy 457.8505 -49.763378) (xy 457.818995 -49.840755) (xy 457.78017 -49.91473) (xy 457.734387 -49.984613)
			(xy 457.682072 -50.04975) (xy 457.623715 -50.109535) (xy 457.559861 -50.163408) (xy 457.491105 -50.210867)
			(xy 457.418089 -50.251468) (xy 457.341496 -50.284833) (xy 457.26204 -50.31065) (xy 457.180464 -50.328678)
			(xy 457.097528 -50.338748) (xy 457.014008 -50.340767) (xy 456.930682 -50.334715) (xy 456.84833 -50.32065)
			(xy 456.76772 -50.298702) (xy 456.689604 -50.269076) (xy 456.614712 -50.23205) (xy 456.543744 -50.187969)
			(xy 456.477361 -50.137243) (xy 456.416184 -50.080348) (xy 456.360783 -50.017814) (xy 456.311677 -49.950225)
			(xy 456.269323 -49.878212) (xy 456.234117 -49.802447) (xy 456.206388 -49.723638) (xy 456.186395 -49.642521)
			(xy 456.174323 -49.559853) (xy 456.170287 -49.476406) (xy 450.390768 -49.476406) (xy 450.390263 -49.518178)
			(xy 450.3822 -49.601333) (xy 450.366149 -49.683321) (xy 450.34226 -49.763378) (xy 450.310755 -49.840755)
			(xy 450.27193 -49.91473) (xy 450.226147 -49.984613) (xy 450.173832 -50.04975) (xy 450.115475 -50.109535)
			(xy 450.051621 -50.163408) (xy 449.982865 -50.210867) (xy 449.909849 -50.251468) (xy 449.833256 -50.284833)
			(xy 449.7538 -50.31065) (xy 449.672224 -50.328678) (xy 449.589288 -50.338748) (xy 449.505768 -50.340767)
			(xy 449.422442 -50.334715) (xy 449.34009 -50.32065) (xy 449.25948 -50.298702) (xy 449.181364 -50.269076)
			(xy 449.106472 -50.23205) (xy 449.035504 -50.187969) (xy 448.969121 -50.137243) (xy 448.907944 -50.080348)
			(xy 448.852543 -50.017814) (xy 448.803437 -49.950225) (xy 448.761083 -49.878212) (xy 448.725877 -49.802447)
			(xy 448.698148 -49.723638) (xy 448.678155 -49.642521) (xy 448.666083 -49.559853) (xy 448.662047 -49.476406)
			(xy 441.0456 -49.476406) (xy 441.0456 -52.018876) (xy 448.637656 -52.018876) (xy 448.637656 -51.93418)
			(xy 448.645707 -51.849866) (xy 448.661736 -51.7667) (xy 448.685597 -51.685433) (xy 448.717076 -51.606803)
			(xy 448.755887 -51.531522) (xy 448.801677 -51.46027) (xy 448.854033 -51.393694) (xy 448.912481 -51.332396)
			(xy 448.976491 -51.276931) (xy 449.045483 -51.227802) (xy 449.118833 -51.185453) (xy 449.195876 -51.150269)
			(xy 449.275915 -51.122567) (xy 449.358224 -51.102599) (xy 449.442059 -51.090546) (xy 449.52666 -51.086516)
			(xy 449.611261 -51.090546) (xy 449.695096 -51.102599) (xy 449.777405 -51.122567) (xy 449.857444 -51.150269)
			(xy 449.934487 -51.185453) (xy 450.007837 -51.227802) (xy 450.076829 -51.276931) (xy 450.140839 -51.332396)
			(xy 450.199287 -51.393694) (xy 450.251643 -51.46027) (xy 450.297433 -51.531522) (xy 450.336244 -51.606803)
			(xy 450.367723 -51.685433) (xy 450.391584 -51.7667) (xy 450.407613 -51.849866) (xy 450.415664 -51.93418)
			(xy 450.416168 -51.976528) (xy 450.415664 -52.018876) (xy 456.145896 -52.018876) (xy 456.145896 -51.93418)
			(xy 456.153947 -51.849866) (xy 456.169976 -51.7667) (xy 456.193837 -51.685433) (xy 456.225316 -51.606803)
			(xy 456.264127 -51.531522) (xy 456.309917 -51.46027) (xy 456.362273 -51.393694) (xy 456.420721 -51.332396)
			(xy 456.484731 -51.276931) (xy 456.553723 -51.227802) (xy 456.627073 -51.185453) (xy 456.704116 -51.150269)
			(xy 456.784155 -51.122567) (xy 456.866464 -51.102599) (xy 456.950299 -51.090546) (xy 457.0349 -51.086516)
			(xy 457.119501 -51.090546) (xy 457.203336 -51.102599) (xy 457.285645 -51.122567) (xy 457.365684 -51.150269)
			(xy 457.442727 -51.185453) (xy 457.516077 -51.227802) (xy 457.585069 -51.276931) (xy 457.649079 -51.332396)
			(xy 457.707527 -51.393694) (xy 457.759883 -51.46027) (xy 457.805673 -51.531522) (xy 457.844484 -51.606803)
			(xy 457.875963 -51.685433) (xy 457.899824 -51.7667) (xy 457.915853 -51.849866) (xy 457.923904 -51.93418)
			(xy 457.924408 -51.976528) (xy 457.923904 -52.018876) (xy 457.915853 -52.10319) (xy 457.899824 -52.186356)
			(xy 457.875963 -52.267623) (xy 457.844484 -52.346253) (xy 457.805673 -52.421534) (xy 457.759883 -52.492786)
			(xy 457.707527 -52.559362) (xy 457.649079 -52.62066) (xy 457.585069 -52.676125) (xy 457.516077 -52.725254)
			(xy 457.442727 -52.767603) (xy 457.365684 -52.802787) (xy 457.285645 -52.830489) (xy 457.203336 -52.850457)
			(xy 457.119501 -52.86251) (xy 457.0349 -52.866541) (xy 456.950299 -52.86251) (xy 456.866464 -52.850457)
			(xy 456.784155 -52.830489) (xy 456.704116 -52.802787) (xy 456.627073 -52.767603) (xy 456.553723 -52.725254)
			(xy 456.484731 -52.676125) (xy 456.420721 -52.62066) (xy 456.362273 -52.559362) (xy 456.309917 -52.492786)
			(xy 456.264127 -52.421534) (xy 456.225316 -52.346253) (xy 456.193837 -52.267623) (xy 456.169976 -52.186356)
			(xy 456.153947 -52.10319) (xy 456.145896 -52.018876) (xy 450.415664 -52.018876) (xy 450.407613 -52.10319)
			(xy 450.391584 -52.186356) (xy 450.367723 -52.267623) (xy 450.336244 -52.346253) (xy 450.297433 -52.421534)
			(xy 450.251643 -52.492786) (xy 450.199287 -52.559362) (xy 450.140839 -52.62066) (xy 450.076829 -52.676125)
			(xy 450.007837 -52.725254) (xy 449.934487 -52.767603) (xy 449.857444 -52.802787) (xy 449.777405 -52.830489)
			(xy 449.695096 -52.850457) (xy 449.611261 -52.86251) (xy 449.52666 -52.866541) (xy 449.442059 -52.86251)
			(xy 449.358224 -52.850457) (xy 449.275915 -52.830489) (xy 449.195876 -52.802787) (xy 449.118833 -52.767603)
			(xy 449.045483 -52.725254) (xy 448.976491 -52.676125) (xy 448.912481 -52.62066) (xy 448.854033 -52.559362)
			(xy 448.801677 -52.492786) (xy 448.755887 -52.421534) (xy 448.717076 -52.346253) (xy 448.685597 -52.267623)
			(xy 448.661736 -52.186356) (xy 448.645707 -52.10319) (xy 448.637656 -52.018876) (xy 441.0456 -52.018876)
			(xy 441.0456 -52.517548) (xy 444.575182 -52.517548) (xy 444.579253 -52.461926) (xy 444.591379 -52.407489)
			(xy 444.611302 -52.355398) (xy 444.638598 -52.306763) (xy 444.672684 -52.26262) (xy 444.712833 -52.223911)
			(xy 444.758191 -52.19146) (xy 444.807791 -52.165959) (xy 444.860575 -52.147952) (xy 444.915418 -52.137822)
			(xy 444.971152 -52.135785) (xy 445.026589 -52.141885) (xy 445.080546 -52.155991) (xy 445.131875 -52.177803)
			(xy 445.179481 -52.206857) (xy 445.222349 -52.242532) (xy 445.259566 -52.284069) (xy 445.290339 -52.330582)
			(xy 445.314011 -52.381079) (xy 445.330079 -52.434486) (xy 445.338199 -52.489662) (xy 445.338708 -52.517548)
			(xy 445.338199 -52.545434) (xy 445.330079 -52.60061) (xy 445.314011 -52.654017) (xy 445.290339 -52.704514)
			(xy 445.259566 -52.751027) (xy 445.222349 -52.792564) (xy 445.179481 -52.828239) (xy 445.131875 -52.857293)
			(xy 445.080546 -52.879105) (xy 445.026589 -52.893211) (xy 444.971152 -52.899311) (xy 444.915418 -52.897274)
			(xy 444.860575 -52.887144) (xy 444.807791 -52.869137) (xy 444.758191 -52.843636) (xy 444.712833 -52.811185)
			(xy 444.672684 -52.772476) (xy 444.638598 -52.728333) (xy 444.611302 -52.679698) (xy 444.591379 -52.627607)
			(xy 444.579253 -52.57317) (xy 444.575182 -52.517548) (xy 441.0456 -52.517548) (xy 441.0456 -52.627276)
			(xy 441.046099 -52.641412) (xy 441.053926 -52.668582) (xy 441.068903 -52.692564) (xy 441.089882 -52.71152)
			(xy 441.115255 -52.723998) (xy 441.143076 -52.72904) (xy 441.171214 -52.726259) (xy 441.184538 -52.72151)
			(xy 441.206972 -52.713035) (xy 441.253434 -52.701149) (xy 441.301021 -52.695191) (xy 441.325 -52.69484)
			(xy 441.353916 -52.695374) (xy 441.411086 -52.704102) (xy 441.466285 -52.721357) (xy 441.518247 -52.746745)
			(xy 441.565783 -52.779684) (xy 441.607803 -52.819419) (xy 441.62599 -52.841906) (xy 441.635887 -52.853711)
			(xy 441.661211 -52.87123) (xy 441.690604 -52.880406) (xy 441.721396 -52.880406) (xy 441.750789 -52.87123)
			(xy 441.776113 -52.853711) (xy 441.78601 -52.841906) (xy 441.804199 -52.819419) (xy 441.846215 -52.779675)
			(xy 441.893748 -52.746728) (xy 441.94571 -52.721333) (xy 442.00091 -52.704073) (xy 442.058082 -52.695343)
			(xy 442.087 -52.69484) (xy 442.114252 -52.695303) (xy 442.1682 -52.703061) (xy 442.220495 -52.718417)
			(xy 442.270072 -52.74106) (xy 442.315922 -52.770529) (xy 442.357111 -52.806223) (xy 442.3928 -52.847417)
			(xy 442.422263 -52.89327) (xy 442.4449 -52.94285) (xy 442.46025 -52.995147) (xy 442.468 -53.049096)
			(xy 442.468508 -53.076348) (xy 442.46797 -53.105263) (xy 442.464352 -53.128948) (xy 442.747426 -53.128948)
			(xy 442.747426 -53.074452) (xy 442.755182 -53.020511) (xy 442.770535 -52.968223) (xy 442.793173 -52.918652)
			(xy 442.822636 -52.872808) (xy 442.858323 -52.831623) (xy 442.899508 -52.795936) (xy 442.945352 -52.766473)
			(xy 442.994923 -52.743835) (xy 443.047211 -52.728482) (xy 443.101152 -52.720726) (xy 443.1284 -52.72024)
			(xy 443.157318 -52.720743) (xy 443.21449 -52.729473) (xy 443.26969 -52.746733) (xy 443.321652 -52.772128)
			(xy 443.369185 -52.805075) (xy 443.411201 -52.844819) (xy 443.42939 -52.867306) (xy 443.439287 -52.879111)
			(xy 443.464611 -52.89663) (xy 443.494004 -52.905806) (xy 443.524796 -52.905806) (xy 443.554189 -52.89663)
			(xy 443.579513 -52.879111) (xy 443.58941 -52.867306) (xy 443.607597 -52.844819) (xy 443.649617 -52.805084)
			(xy 443.697153 -52.772145) (xy 443.749115 -52.746757) (xy 443.804314 -52.729502) (xy 443.861484 -52.720774)
			(xy 443.8904 -52.72024) (xy 443.917655 -52.72063) (xy 443.971609 -52.728387) (xy 444.023911 -52.743744)
			(xy 444.073494 -52.766388) (xy 444.11935 -52.795858) (xy 444.160546 -52.831554) (xy 444.196242 -52.87275)
			(xy 444.225712 -52.918606) (xy 444.248356 -52.968189) (xy 444.263713 -53.020491) (xy 444.27147 -53.074445)
			(xy 444.27147 -53.128955) (xy 444.263713 -53.182909) (xy 444.248356 -53.235211) (xy 444.225712 -53.284794)
			(xy 444.196242 -53.33065) (xy 444.160546 -53.371846) (xy 444.11935 -53.407542) (xy 444.073494 -53.437012)
			(xy 444.023911 -53.459656) (xy 443.971609 -53.475013) (xy 443.917655 -53.48277) (xy 443.8904 -53.483256)
			(xy 443.861482 -53.482754) (xy 443.80431 -53.474024) (xy 443.74911 -53.456764) (xy 443.697148 -53.431369)
			(xy 443.649614 -53.398422) (xy 443.607599 -53.358677) (xy 443.58941 -53.33619) (xy 443.579513 -53.324385)
			(xy 443.554189 -53.306866) (xy 443.524796 -53.29769) (xy 443.494004 -53.29769) (xy 443.464611 -53.306866)
			(xy 443.439287 -53.324385) (xy 443.42939 -53.33619) (xy 443.411202 -53.358676) (xy 443.369182 -53.398412)
			(xy 443.321647 -53.431351) (xy 443.269685 -53.456739) (xy 443.214486 -53.473994) (xy 443.157316 -53.482722)
			(xy 443.1284 -53.483256) (xy 443.101152 -53.482674) (xy 443.047211 -53.474918) (xy 442.994923 -53.459565)
			(xy 442.945352 -53.436927) (xy 442.899508 -53.407464) (xy 442.858323 -53.371777) (xy 442.822636 -53.330592)
			(xy 442.793173 -53.284748) (xy 442.770535 -53.235177) (xy 442.755182 -53.182889) (xy 442.747426 -53.128948)
			(xy 442.464352 -53.128948) (xy 442.459237 -53.16243) (xy 442.441978 -53.217625) (xy 442.416589 -53.269584)
			(xy 442.38365 -53.317117) (xy 442.343916 -53.359136) (xy 442.321442 -53.377338) (xy 442.309641 -53.387234)
			(xy 442.292132 -53.412552) (xy 442.282966 -53.441938) (xy 442.282975 -53.472721) (xy 442.292159 -53.502102)
			(xy 442.309682 -53.52741) (xy 442.321442 -53.537358) (xy 442.342221 -53.554112) (xy 442.379345 -53.592464)
			(xy 442.41076 -53.635617) (xy 442.435853 -53.682727) (xy 442.454133 -53.732876) (xy 442.465245 -53.785083)
			(xy 442.46897 -53.83833) (xy 442.465236 -53.891575) (xy 442.454117 -53.943781) (xy 442.435828 -53.993927)
			(xy 442.410728 -54.041033) (xy 442.379307 -54.084181) (xy 442.342177 -54.122528) (xy 442.321442 -54.139338)
			(xy 442.309641 -54.149234) (xy 442.292132 -54.174552) (xy 442.282966 -54.203938) (xy 442.282975 -54.234721)
			(xy 442.292159 -54.264102) (xy 442.309682 -54.28941) (xy 442.321442 -54.299358) (xy 442.342221 -54.316112)
			(xy 442.379345 -54.354464) (xy 442.391928 -54.371748) (xy 447.038982 -54.371748) (xy 447.043053 -54.316126)
			(xy 447.055179 -54.261689) (xy 447.075102 -54.209598) (xy 447.102398 -54.160963) (xy 447.136484 -54.11682)
			(xy 447.176633 -54.078111) (xy 447.221991 -54.04566) (xy 447.271591 -54.020159) (xy 447.324375 -54.002152)
			(xy 447.379218 -53.992022) (xy 447.434952 -53.989985) (xy 447.490389 -53.996085) (xy 447.544346 -54.010191)
			(xy 447.595675 -54.032003) (xy 447.643281 -54.061057) (xy 447.686149 -54.096732) (xy 447.723366 -54.138269)
			(xy 447.754139 -54.184782) (xy 447.777811 -54.235279) (xy 447.793879 -54.288686) (xy 447.801999 -54.343862)
			(xy 447.802508 -54.371748) (xy 447.927982 -54.371748) (xy 447.932053 -54.316126) (xy 447.944179 -54.261689)
			(xy 447.964102 -54.209598) (xy 447.991398 -54.160963) (xy 448.025484 -54.11682) (xy 448.065633 -54.078111)
			(xy 448.110991 -54.04566) (xy 448.160591 -54.020159) (xy 448.213375 -54.002152) (xy 448.268218 -53.992022)
			(xy 448.323952 -53.989985) (xy 448.379389 -53.996085) (xy 448.433346 -54.010191) (xy 448.484675 -54.032003)
			(xy 448.532281 -54.061057) (xy 448.575149 -54.096732) (xy 448.612366 -54.138269) (xy 448.643139 -54.184782)
			(xy 448.666811 -54.235279) (xy 448.682879 -54.288686) (xy 448.690999 -54.343862) (xy 448.691508 -54.371748)
			(xy 448.816982 -54.371748) (xy 448.821053 -54.316126) (xy 448.833179 -54.261689) (xy 448.853102 -54.209598)
			(xy 448.880398 -54.160963) (xy 448.914484 -54.11682) (xy 448.954633 -54.078111) (xy 448.999991 -54.04566)
			(xy 449.049591 -54.020159) (xy 449.102375 -54.002152) (xy 449.157218 -53.992022) (xy 449.212952 -53.989985)
			(xy 449.268389 -53.996085) (xy 449.322346 -54.010191) (xy 449.373675 -54.032003) (xy 449.421281 -54.061057)
			(xy 449.464149 -54.096732) (xy 449.501366 -54.138269) (xy 449.532139 -54.184782) (xy 449.555811 -54.235279)
			(xy 449.571879 -54.288686) (xy 449.579999 -54.343862) (xy 449.580508 -54.371748) (xy 449.705982 -54.371748)
			(xy 449.710053 -54.316126) (xy 449.722179 -54.261689) (xy 449.742102 -54.209598) (xy 449.769398 -54.160963)
			(xy 449.803484 -54.11682) (xy 449.843633 -54.078111) (xy 449.888991 -54.04566) (xy 449.938591 -54.020159)
			(xy 449.991375 -54.002152) (xy 450.046218 -53.992022) (xy 450.101952 -53.989985) (xy 450.157389 -53.996085)
			(xy 450.211346 -54.010191) (xy 450.262675 -54.032003) (xy 450.310281 -54.061057) (xy 450.353149 -54.096732)
			(xy 450.390366 -54.138269) (xy 450.421139 -54.184782) (xy 450.444811 -54.235279) (xy 450.460879 -54.288686)
			(xy 450.468999 -54.343862) (xy 450.469508 -54.371748) (xy 450.468999 -54.399634) (xy 450.460879 -54.45481)
			(xy 450.444811 -54.508217) (xy 450.421139 -54.558714) (xy 450.390366 -54.605227) (xy 450.353149 -54.646764)
			(xy 450.310281 -54.682439) (xy 450.262675 -54.711493) (xy 450.211346 -54.733305) (xy 450.157389 -54.747411)
			(xy 450.101952 -54.753511) (xy 450.046218 -54.751474) (xy 449.991375 -54.741344) (xy 449.938591 -54.723337)
			(xy 449.888991 -54.697836) (xy 449.843633 -54.665385) (xy 449.803484 -54.626676) (xy 449.769398 -54.582533)
			(xy 449.742102 -54.533898) (xy 449.722179 -54.481807) (xy 449.710053 -54.42737) (xy 449.705982 -54.371748)
			(xy 449.580508 -54.371748) (xy 449.579999 -54.399634) (xy 449.571879 -54.45481) (xy 449.555811 -54.508217)
			(xy 449.532139 -54.558714) (xy 449.501366 -54.605227) (xy 449.464149 -54.646764) (xy 449.421281 -54.682439)
			(xy 449.373675 -54.711493) (xy 449.322346 -54.733305) (xy 449.268389 -54.747411) (xy 449.212952 -54.753511)
			(xy 449.157218 -54.751474) (xy 449.102375 -54.741344) (xy 449.049591 -54.723337) (xy 448.999991 -54.697836)
			(xy 448.954633 -54.665385) (xy 448.914484 -54.626676) (xy 448.880398 -54.582533) (xy 448.853102 -54.533898)
			(xy 448.833179 -54.481807) (xy 448.821053 -54.42737) (xy 448.816982 -54.371748) (xy 448.691508 -54.371748)
			(xy 448.690999 -54.399634) (xy 448.682879 -54.45481) (xy 448.666811 -54.508217) (xy 448.643139 -54.558714)
			(xy 448.612366 -54.605227) (xy 448.575149 -54.646764) (xy 448.532281 -54.682439) (xy 448.484675 -54.711493)
			(xy 448.433346 -54.733305) (xy 448.379389 -54.747411) (xy 448.323952 -54.753511) (xy 448.268218 -54.751474)
			(xy 448.213375 -54.741344) (xy 448.160591 -54.723337) (xy 448.110991 -54.697836) (xy 448.065633 -54.665385)
			(xy 448.025484 -54.626676) (xy 447.991398 -54.582533) (xy 447.964102 -54.533898) (xy 447.944179 -54.481807)
			(xy 447.932053 -54.42737) (xy 447.927982 -54.371748) (xy 447.802508 -54.371748) (xy 447.801999 -54.399634)
			(xy 447.793879 -54.45481) (xy 447.777811 -54.508217) (xy 447.754139 -54.558714) (xy 447.723366 -54.605227)
			(xy 447.686149 -54.646764) (xy 447.643281 -54.682439) (xy 447.595675 -54.711493) (xy 447.544346 -54.733305)
			(xy 447.490389 -54.747411) (xy 447.434952 -54.753511) (xy 447.379218 -54.751474) (xy 447.324375 -54.741344)
			(xy 447.271591 -54.723337) (xy 447.221991 -54.697836) (xy 447.176633 -54.665385) (xy 447.136484 -54.626676)
			(xy 447.102398 -54.582533) (xy 447.075102 -54.533898) (xy 447.055179 -54.481807) (xy 447.043053 -54.42737)
			(xy 447.038982 -54.371748) (xy 442.391928 -54.371748) (xy 442.41076 -54.397617) (xy 442.435853 -54.444727)
			(xy 442.454133 -54.494876) (xy 442.465245 -54.547083) (xy 442.46897 -54.60033) (xy 442.465236 -54.653575)
			(xy 442.454117 -54.705781) (xy 442.435828 -54.755927) (xy 442.410728 -54.803033) (xy 442.379307 -54.846181)
			(xy 442.342177 -54.884528) (xy 442.321442 -54.901338) (xy 442.309641 -54.911234) (xy 442.292132 -54.936552)
			(xy 442.282966 -54.965938) (xy 442.282975 -54.996721) (xy 442.292159 -55.026102) (xy 442.309682 -55.05141)
			(xy 442.321442 -55.061358) (xy 442.342221 -55.078112) (xy 442.379345 -55.116464) (xy 442.41076 -55.159617)
			(xy 442.435853 -55.206727) (xy 442.454133 -55.256876) (xy 442.465245 -55.309083) (xy 442.46897 -55.36233)
			(xy 442.465236 -55.415575) (xy 442.454117 -55.467781) (xy 442.435828 -55.517927) (xy 442.410728 -55.565033)
			(xy 442.379307 -55.608181) (xy 442.342177 -55.646528) (xy 442.321442 -55.663338) (xy 442.309641 -55.673234)
			(xy 442.292132 -55.698552) (xy 442.282966 -55.727938) (xy 442.282975 -55.758721) (xy 442.292159 -55.788102)
			(xy 442.309682 -55.81341) (xy 442.321442 -55.823358) (xy 442.342221 -55.840112) (xy 442.379345 -55.878464)
			(xy 442.41076 -55.921617) (xy 442.435853 -55.968727) (xy 442.454133 -56.018876) (xy 442.465245 -56.071083)
			(xy 442.46897 -56.12433) (xy 442.465236 -56.177575) (xy 442.454117 -56.229781) (xy 442.435828 -56.279927)
			(xy 442.410728 -56.327033) (xy 442.379307 -56.370181) (xy 442.342177 -56.408528) (xy 442.321442 -56.425338)
			(xy 442.309641 -56.435234) (xy 442.292132 -56.460552) (xy 442.282966 -56.489938) (xy 442.282975 -56.520721)
			(xy 442.292159 -56.550102) (xy 442.309682 -56.57541) (xy 442.321442 -56.585358) (xy 442.342221 -56.602112)
			(xy 442.379345 -56.640464) (xy 442.41076 -56.683617) (xy 442.435853 -56.730727) (xy 442.454133 -56.780876)
			(xy 442.465245 -56.833083) (xy 442.46897 -56.88633) (xy 442.465236 -56.939575) (xy 442.454117 -56.991781)
			(xy 442.435828 -57.041927) (xy 442.410728 -57.089033) (xy 442.379307 -57.132181) (xy 442.342177 -57.170528)
			(xy 442.321442 -57.187338) (xy 442.309641 -57.197234) (xy 442.292132 -57.222552) (xy 442.282966 -57.251938)
			(xy 442.282975 -57.282721) (xy 442.292159 -57.312102) (xy 442.309682 -57.33741) (xy 442.321442 -57.347358)
			(xy 442.343929 -57.365547) (xy 442.383673 -57.407562) (xy 442.416618 -57.455095) (xy 442.44201 -57.507058)
			(xy 442.459266 -57.562258) (xy 442.463333 -57.588912) (xy 444.646304 -57.588912) (xy 444.646776 -57.561542)
			(xy 444.654592 -57.507363) (xy 444.67008 -57.45486) (xy 444.69292 -57.405113) (xy 444.722643 -57.359146)
			(xy 444.740284 -57.338214) (xy 444.749511 -57.326879) (xy 444.761691 -57.300324) (xy 444.765867 -57.271409)
			(xy 444.761696 -57.242493) (xy 444.74952 -57.215937) (xy 444.740284 -57.20461) (xy 444.722657 -57.183667)
			(xy 444.692935 -57.1377) (xy 444.670091 -57.087955) (xy 444.654596 -57.035455) (xy 444.646767 -56.981279)
			(xy 444.646766 -56.926539) (xy 444.654592 -56.872363) (xy 444.670085 -56.819862) (xy 444.692926 -56.770116)
			(xy 444.722646 -56.724148) (xy 444.740284 -56.703214) (xy 444.749511 -56.691879) (xy 444.761691 -56.665324)
			(xy 444.765867 -56.636409) (xy 444.761696 -56.607493) (xy 444.74952 -56.580937) (xy 444.740284 -56.56961)
			(xy 444.722657 -56.548667) (xy 444.692935 -56.5027) (xy 444.670091 -56.452955) (xy 444.654596 -56.400455)
			(xy 444.646767 -56.346279) (xy 444.646766 -56.291539) (xy 444.654592 -56.237363) (xy 444.670085 -56.184862)
			(xy 444.692926 -56.135116) (xy 444.722646 -56.089148) (xy 444.740284 -56.068214) (xy 444.749511 -56.056879)
			(xy 444.761691 -56.030324) (xy 444.765867 -56.001409) (xy 444.761696 -55.972493) (xy 444.74952 -55.945937)
			(xy 444.740284 -55.93461) (xy 444.722657 -55.913667) (xy 444.692935 -55.8677) (xy 444.670091 -55.817955)
			(xy 444.654596 -55.765455) (xy 444.646767 -55.711279) (xy 444.646766 -55.656539) (xy 444.654592 -55.602363)
			(xy 444.670085 -55.549862) (xy 444.692926 -55.500116) (xy 444.722646 -55.454148) (xy 444.740284 -55.433214)
			(xy 444.749511 -55.421879) (xy 444.761691 -55.395324) (xy 444.765867 -55.366409) (xy 444.761696 -55.337493)
			(xy 444.74952 -55.310937) (xy 444.740284 -55.29961) (xy 444.722634 -55.278687) (xy 444.692924 -55.232711)
			(xy 444.670091 -55.182962) (xy 444.654602 -55.130459) (xy 444.646777 -55.076282) (xy 444.646304 -55.048912)
			(xy 444.646767 -55.021659) (xy 444.654522 -54.967707) (xy 444.669877 -54.915409) (xy 444.692519 -54.865828)
			(xy 444.721987 -54.819974) (xy 444.757681 -54.778781) (xy 444.798874 -54.743087) (xy 444.844728 -54.713619)
			(xy 444.894309 -54.690977) (xy 444.946607 -54.675622) (xy 445.000559 -54.667867) (xy 445.027812 -54.667404)
			(xy 445.054483 -54.66783) (xy 445.107306 -54.67525) (xy 445.158579 -54.689958) (xy 445.207304 -54.711667)
			(xy 445.252528 -54.739952) (xy 445.29337 -54.774263) (xy 445.329032 -54.81393) (xy 445.344296 -54.835806)
			(xy 445.35343 -54.848302) (xy 445.377599 -54.867612) (xy 445.406436 -54.87881) (xy 445.437302 -54.88087)
			(xy 445.467372 -54.873605) (xy 445.493892 -54.857678) (xy 445.50457 -54.846474) (xy 445.522735 -54.826673)
			(xy 445.563685 -54.791879) (xy 445.609115 -54.76318) (xy 445.658124 -54.741143) (xy 445.709741 -54.726205)
			(xy 445.762944 -54.718663) (xy 445.789812 -54.718204) (xy 445.817064 -54.718667) (xy 445.871013 -54.726425)
			(xy 445.923309 -54.741782) (xy 445.972887 -54.764426) (xy 446.018738 -54.793894) (xy 446.059929 -54.829588)
			(xy 446.09562 -54.870781) (xy 446.125086 -54.916634) (xy 446.147726 -54.966213) (xy 446.16308 -55.01851)
			(xy 446.170835 -55.07246) (xy 446.17132 -55.099712) (xy 446.17088 -55.127083) (xy 446.163059 -55.181264)
			(xy 446.147565 -55.233769) (xy 446.124717 -55.283515) (xy 446.094985 -55.32948) (xy 446.07734 -55.35041)
			(xy 446.068088 -55.361727) (xy 446.055908 -55.388288) (xy 446.051735 -55.417209) (xy 446.055913 -55.44613)
			(xy 446.068098 -55.472688) (xy 446.07734 -55.484014) (xy 446.094994 -55.504937) (xy 446.124721 -55.550905)
			(xy 446.147567 -55.600653) (xy 446.163064 -55.653157) (xy 446.170892 -55.707337) (xy 446.170891 -55.762081)
			(xy 446.16306 -55.816261) (xy 446.147561 -55.868764) (xy 446.124712 -55.918511) (xy 446.094983 -55.964478)
			(xy 446.07734 -55.98541) (xy 446.068088 -55.996727) (xy 446.055908 -56.023288) (xy 446.051735 -56.052209)
			(xy 446.055913 -56.08113) (xy 446.068098 -56.107688) (xy 446.07734 -56.119014) (xy 446.094994 -56.139937)
			(xy 446.124721 -56.185905) (xy 446.147567 -56.235653) (xy 446.163064 -56.288157) (xy 446.170892 -56.342337)
			(xy 446.170891 -56.369712) (xy 451.428104 -56.369712) (xy 451.428576 -56.342342) (xy 451.436392 -56.288163)
			(xy 451.45188 -56.23566) (xy 451.47472 -56.185913) (xy 451.504443 -56.139946) (xy 451.522084 -56.119014)
			(xy 451.531311 -56.107679) (xy 451.543491 -56.081124) (xy 451.547667 -56.052209) (xy 451.543496 -56.023293)
			(xy 451.53132 -55.996737) (xy 451.522084 -55.98541) (xy 451.504457 -55.964467) (xy 451.474735 -55.9185)
			(xy 451.451891 -55.868755) (xy 451.436396 -55.816255) (xy 451.428567 -55.762079) (xy 451.428566 -55.707339)
			(xy 451.436392 -55.653163) (xy 451.451885 -55.600662) (xy 451.474726 -55.550916) (xy 451.504446 -55.504948)
			(xy 451.522084 -55.484014) (xy 451.531311 -55.472679) (xy 451.543491 -55.446124) (xy 451.547667 -55.417209)
			(xy 451.543496 -55.388293) (xy 451.53132 -55.361737) (xy 451.522084 -55.35041) (xy 451.504434 -55.329487)
			(xy 451.474724 -55.283511) (xy 451.451891 -55.233762) (xy 451.436402 -55.181259) (xy 451.428577 -55.127082)
			(xy 451.428104 -55.099712) (xy 451.42859 -55.072461) (xy 451.436346 -55.018513) (xy 451.451701 -54.966218)
			(xy 451.474343 -54.916641) (xy 451.503809 -54.870791) (xy 451.5395 -54.8296) (xy 451.580691 -54.793909)
			(xy 451.626541 -54.764443) (xy 451.676118 -54.741801) (xy 451.728413 -54.726446) (xy 451.782361 -54.71869)
			(xy 451.836863 -54.71869) (xy 451.890811 -54.726446) (xy 451.943106 -54.741801) (xy 451.992683 -54.764443)
			(xy 452.038533 -54.793909) (xy 452.079724 -54.8296) (xy 452.115415 -54.870791) (xy 452.144881 -54.916641)
			(xy 452.167523 -54.966218) (xy 452.182878 -55.018513) (xy 452.190634 -55.072461) (xy 452.19112 -55.099712)
			(xy 452.19068 -55.127083) (xy 452.182859 -55.181264) (xy 452.167365 -55.233769) (xy 452.144517 -55.283515)
			(xy 452.114785 -55.32948) (xy 452.09714 -55.35041) (xy 452.087888 -55.361727) (xy 452.075708 -55.388288)
			(xy 452.071535 -55.417209) (xy 452.075713 -55.44613) (xy 452.087898 -55.472688) (xy 452.09714 -55.484014)
			(xy 452.114794 -55.504937) (xy 452.144521 -55.550905) (xy 452.167367 -55.600653) (xy 452.182864 -55.653157)
			(xy 452.190692 -55.707337) (xy 452.190691 -55.762081) (xy 452.18286 -55.816261) (xy 452.167361 -55.868764)
			(xy 452.144512 -55.918511) (xy 452.114783 -55.964478) (xy 452.09714 -55.98541) (xy 452.087888 -55.996727)
			(xy 452.075708 -56.023288) (xy 452.071535 -56.052209) (xy 452.075713 -56.08113) (xy 452.087898 -56.107688)
			(xy 452.09714 -56.119014) (xy 452.114759 -56.139962) (xy 452.144472 -56.185931) (xy 452.167312 -56.235675)
			(xy 452.182808 -56.288172) (xy 452.190643 -56.342344) (xy 452.19112 -56.369712) (xy 452.190634 -56.396963)
			(xy 452.182878 -56.450911) (xy 452.167523 -56.503206) (xy 452.144881 -56.552783) (xy 452.115415 -56.598633)
			(xy 452.079724 -56.639824) (xy 452.038533 -56.675515) (xy 451.992683 -56.704981) (xy 451.943106 -56.727623)
			(xy 451.890811 -56.742978) (xy 451.836863 -56.750734) (xy 451.782361 -56.750734) (xy 451.728413 -56.742978)
			(xy 451.676118 -56.727623) (xy 451.626541 -56.704981) (xy 451.580691 -56.675515) (xy 451.5395 -56.639824)
			(xy 451.503809 -56.598633) (xy 451.474343 -56.552783) (xy 451.451701 -56.503206) (xy 451.436346 -56.450911)
			(xy 451.42859 -56.396963) (xy 451.428104 -56.369712) (xy 446.170891 -56.369712) (xy 446.170891 -56.397081)
			(xy 446.16306 -56.451261) (xy 446.147561 -56.503764) (xy 446.124712 -56.553511) (xy 446.094983 -56.599478)
			(xy 446.07734 -56.62041) (xy 446.068088 -56.631727) (xy 446.055908 -56.658288) (xy 446.051735 -56.687209)
			(xy 446.055913 -56.71613) (xy 446.068098 -56.742688) (xy 446.07734 -56.754014) (xy 446.094959 -56.774962)
			(xy 446.124672 -56.820931) (xy 446.147512 -56.870675) (xy 446.163008 -56.923172) (xy 446.170843 -56.977344)
			(xy 446.17132 -57.004712) (xy 446.170833 -57.031963) (xy 446.163076 -57.08591) (xy 446.14772 -57.138204)
			(xy 446.125078 -57.187781) (xy 446.095611 -57.23363) (xy 446.05992 -57.27482) (xy 446.01873 -57.310511)
			(xy 445.972881 -57.339978) (xy 445.923304 -57.36262) (xy 445.87101 -57.377976) (xy 445.817063 -57.385733)
			(xy 445.789812 -57.38622) (xy 445.762381 -57.385755) (xy 445.708084 -57.377911) (xy 445.65547 -57.362369)
			(xy 445.605626 -57.339449) (xy 445.55958 -57.309624) (xy 445.518282 -57.27351) (xy 445.482584 -57.231852)
			(xy 445.453222 -57.185509) (xy 445.441578 -57.160668) (xy 445.436517 -57.15084) (xy 445.419862 -57.13635)
			(xy 445.398659 -57.130199) (xy 445.376835 -57.133527) (xy 445.358428 -57.145717) (xy 445.35217 -57.154826)
			(xy 445.343856 -57.167909) (xy 445.325419 -57.192833) (xy 445.31534 -57.20461) (xy 445.306088 -57.215927)
			(xy 445.293908 -57.242488) (xy 445.289735 -57.271409) (xy 445.293913 -57.30033) (xy 445.306098 -57.326888)
			(xy 445.31534 -57.338214) (xy 445.332959 -57.359162) (xy 445.362672 -57.405131) (xy 445.385512 -57.454875)
			(xy 445.401008 -57.507372) (xy 445.408843 -57.561544) (xy 445.40932 -57.588912) (xy 445.408834 -57.616163)
			(xy 445.405448 -57.639712) (xy 452.723504 -57.639712) (xy 452.723976 -57.612342) (xy 452.731792 -57.558163)
			(xy 452.74728 -57.50566) (xy 452.77012 -57.455913) (xy 452.799843 -57.409946) (xy 452.817484 -57.389014)
			(xy 452.826711 -57.377679) (xy 452.838891 -57.351124) (xy 452.843067 -57.322209) (xy 452.838896 -57.293293)
			(xy 452.82672 -57.266737) (xy 452.817484 -57.25541) (xy 452.799857 -57.234467) (xy 452.770135 -57.1885)
			(xy 452.747291 -57.138755) (xy 452.731796 -57.086255) (xy 452.723967 -57.032079) (xy 452.723966 -56.977339)
			(xy 452.731792 -56.923163) (xy 452.747285 -56.870662) (xy 452.770126 -56.820916) (xy 452.799846 -56.774948)
			(xy 452.817484 -56.754014) (xy 452.826711 -56.742679) (xy 452.838891 -56.716124) (xy 452.843067 -56.687209)
			(xy 452.838896 -56.658293) (xy 452.82672 -56.631737) (xy 452.817484 -56.62041) (xy 452.799857 -56.599467)
			(xy 452.770135 -56.5535) (xy 452.747291 -56.503755) (xy 452.731796 -56.451255) (xy 452.723967 -56.397079)
			(xy 452.723966 -56.342339) (xy 452.731792 -56.288163) (xy 452.747285 -56.235662) (xy 452.770126 -56.185916)
			(xy 452.799846 -56.139948) (xy 452.817484 -56.119014) (xy 452.826711 -56.107679) (xy 452.838891 -56.081124)
			(xy 452.843067 -56.052209) (xy 452.838896 -56.023293) (xy 452.82672 -55.996737) (xy 452.817484 -55.98541)
			(xy 452.799857 -55.964467) (xy 452.770135 -55.9185) (xy 452.747291 -55.868755) (xy 452.731796 -55.816255)
			(xy 452.723967 -55.762079) (xy 452.723966 -55.707339) (xy 452.731792 -55.653163) (xy 452.747285 -55.600662)
			(xy 452.770126 -55.550916) (xy 452.799846 -55.504948) (xy 452.817484 -55.484014) (xy 452.826711 -55.472679)
			(xy 452.838891 -55.446124) (xy 452.843067 -55.417209) (xy 452.838896 -55.388293) (xy 452.82672 -55.361737)
			(xy 452.817484 -55.35041) (xy 452.799834 -55.329487) (xy 452.770124 -55.283511) (xy 452.747291 -55.233762)
			(xy 452.731802 -55.181259) (xy 452.723977 -55.127082) (xy 452.723504 -55.099712) (xy 452.72399 -55.072461)
			(xy 452.731746 -55.018513) (xy 452.747101 -54.966218) (xy 452.769743 -54.916641) (xy 452.799209 -54.870791)
			(xy 452.8349 -54.8296) (xy 452.876091 -54.793909) (xy 452.921941 -54.764443) (xy 452.971518 -54.741801)
			(xy 453.023813 -54.726446) (xy 453.077761 -54.71869) (xy 453.132263 -54.71869) (xy 453.186211 -54.726446)
			(xy 453.238506 -54.741801) (xy 453.288083 -54.764443) (xy 453.333933 -54.793909) (xy 453.375124 -54.8296)
			(xy 453.410815 -54.870791) (xy 453.440281 -54.916641) (xy 453.462923 -54.966218) (xy 453.478278 -55.018513)
			(xy 453.486034 -55.072461) (xy 453.48652 -55.099712) (xy 453.48608 -55.127083) (xy 453.478259 -55.181264)
			(xy 453.462765 -55.233769) (xy 453.439917 -55.283515) (xy 453.410185 -55.32948) (xy 453.39254 -55.35041)
			(xy 453.383288 -55.361727) (xy 453.371108 -55.388288) (xy 453.366935 -55.417209) (xy 453.371113 -55.44613)
			(xy 453.383298 -55.472688) (xy 453.39254 -55.484014) (xy 453.410194 -55.504937) (xy 453.439921 -55.550905)
			(xy 453.462767 -55.600653) (xy 453.478264 -55.653157) (xy 453.486092 -55.707337) (xy 453.486091 -55.762081)
			(xy 453.47826 -55.816261) (xy 453.462761 -55.868764) (xy 453.439912 -55.918511) (xy 453.410183 -55.964478)
			(xy 453.39254 -55.98541) (xy 453.383288 -55.996727) (xy 453.371108 -56.023288) (xy 453.366935 -56.052209)
			(xy 453.371113 -56.08113) (xy 453.383298 -56.107688) (xy 453.39254 -56.119014) (xy 453.410194 -56.139937)
			(xy 453.439921 -56.185905) (xy 453.462767 -56.235653) (xy 453.478264 -56.288157) (xy 453.486092 -56.342337)
			(xy 453.486091 -56.397081) (xy 453.47826 -56.451261) (xy 453.462761 -56.503764) (xy 453.439912 -56.553511)
			(xy 453.410183 -56.599478) (xy 453.39254 -56.62041) (xy 453.383288 -56.631727) (xy 453.371108 -56.658288)
			(xy 453.366935 -56.687209) (xy 453.371113 -56.71613) (xy 453.383298 -56.742688) (xy 453.39254 -56.754014)
			(xy 453.410194 -56.774937) (xy 453.439921 -56.820905) (xy 453.462767 -56.870653) (xy 453.478264 -56.923157)
			(xy 453.486092 -56.977337) (xy 453.486091 -57.032081) (xy 453.47826 -57.086261) (xy 453.462761 -57.138764)
			(xy 453.439912 -57.188511) (xy 453.410183 -57.234478) (xy 453.39254 -57.25541) (xy 453.383288 -57.266727)
			(xy 453.371108 -57.293288) (xy 453.366935 -57.322209) (xy 453.371113 -57.35113) (xy 453.383298 -57.377688)
			(xy 453.39254 -57.389014) (xy 453.410159 -57.409962) (xy 453.439872 -57.455931) (xy 453.462712 -57.505675)
			(xy 453.478208 -57.558172) (xy 453.486043 -57.612344) (xy 453.48652 -57.639712) (xy 453.486034 -57.666963)
			(xy 453.478278 -57.720911) (xy 453.462923 -57.773206) (xy 453.440281 -57.822783) (xy 453.410815 -57.868633)
			(xy 453.375124 -57.909824) (xy 453.333933 -57.945515) (xy 453.288083 -57.974981) (xy 453.238506 -57.997623)
			(xy 453.186211 -58.012978) (xy 453.132263 -58.020734) (xy 453.077761 -58.020734) (xy 453.023813 -58.012978)
			(xy 452.971518 -57.997623) (xy 452.921941 -57.974981) (xy 452.876091 -57.945515) (xy 452.8349 -57.909824)
			(xy 452.799209 -57.868633) (xy 452.769743 -57.822783) (xy 452.747101 -57.773206) (xy 452.731746 -57.720911)
			(xy 452.72399 -57.666963) (xy 452.723504 -57.639712) (xy 445.405448 -57.639712) (xy 445.401078 -57.670111)
			(xy 445.385723 -57.722406) (xy 445.363081 -57.771983) (xy 445.333615 -57.817833) (xy 445.297924 -57.859024)
			(xy 445.256733 -57.894715) (xy 445.210883 -57.924181) (xy 445.161306 -57.946823) (xy 445.109011 -57.962178)
			(xy 445.055063 -57.969934) (xy 445.000561 -57.969934) (xy 444.946613 -57.962178) (xy 444.894318 -57.946823)
			(xy 444.844741 -57.924181) (xy 444.798891 -57.894715) (xy 444.7577 -57.859024) (xy 444.722009 -57.817833)
			(xy 444.692543 -57.771983) (xy 444.669901 -57.722406) (xy 444.654546 -57.670111) (xy 444.64679 -57.616163)
			(xy 444.646304 -57.588912) (xy 442.463333 -57.588912) (xy 442.46799 -57.619431) (xy 442.468508 -57.648348)
			(xy 442.468019 -57.675597) (xy 442.460257 -57.72954) (xy 442.444898 -57.781829) (xy 442.422254 -57.8314)
			(xy 442.392786 -57.877244) (xy 442.357095 -57.918429) (xy 442.315906 -57.954115) (xy 442.270058 -57.983577)
			(xy 442.220484 -58.006214) (xy 442.168193 -58.021567) (xy 442.114249 -58.029322) (xy 442.087 -58.029856)
			(xy 442.058084 -58.029322) (xy 442.000914 -58.020594) (xy 441.945715 -58.003339) (xy 441.893753 -57.977951)
			(xy 441.846218 -57.945012) (xy 441.804198 -57.905276) (xy 441.78601 -57.88279) (xy 441.776113 -57.870985)
			(xy 441.750789 -57.853466) (xy 441.721396 -57.84429) (xy 441.690604 -57.84429) (xy 441.661211 -57.853466)
			(xy 441.635887 -57.870985) (xy 441.62599 -57.88279) (xy 441.607801 -57.905277) (xy 441.565786 -57.945022)
			(xy 441.518252 -57.977969) (xy 441.46629 -58.003364) (xy 441.41109 -58.020624) (xy 441.353918 -58.029354)
			(xy 441.325 -58.029856) (xy 441.301022 -58.029495) (xy 441.25344 -58.023521) (xy 441.206978 -58.011642)
			(xy 441.184538 -58.003186) (xy 441.171218 -57.998419) (xy 441.143075 -57.995639) (xy 441.115248 -58.000682)
			(xy 441.089871 -58.013161) (xy 441.068888 -58.03212) (xy 441.053907 -58.056107) (xy 441.046078 -58.083281)
			(xy 441.0456 -58.09742) (xy 441.0456 -59.418982) (xy 462.938622 -59.418982) (xy 462.939072 -59.391611)
			(xy 462.946893 -59.337431) (xy 462.962386 -59.284928) (xy 462.985231 -59.235181) (xy 463.014959 -59.189215)
			(xy 463.032602 -59.168284) (xy 463.041856 -59.15697) (xy 463.054031 -59.130407) (xy 463.0582 -59.101486)
			(xy 463.054023 -59.072567) (xy 463.041841 -59.046007) (xy 463.032602 -59.03468) (xy 463.014945 -59.013761)
			(xy 462.985223 -58.96779) (xy 462.96238 -58.918042) (xy 462.946886 -58.865538) (xy 462.93906 -58.811358)
			(xy 462.939062 -58.756615) (xy 462.946892 -58.702436) (xy 462.962389 -58.649933) (xy 462.985236 -58.600186)
			(xy 463.014961 -58.554217) (xy 463.032602 -58.533284) (xy 463.041856 -58.52197) (xy 463.054031 -58.495407)
			(xy 463.0582 -58.466486) (xy 463.054023 -58.437567) (xy 463.041841 -58.411007) (xy 463.032602 -58.39968)
			(xy 463.014987 -58.378728) (xy 462.985272 -58.332761) (xy 462.962431 -58.283018) (xy 462.946934 -58.230522)
			(xy 462.9391 -58.17635) (xy 462.938622 -58.148982) (xy 462.939156 -58.120244) (xy 462.947779 -58.063418)
			(xy 462.964828 -58.008528) (xy 462.989917 -57.956816) (xy 463.022478 -57.909452) (xy 463.041746 -57.888124)
			(xy 463.051837 -57.876605) (xy 463.065181 -57.849054) (xy 463.069763 -57.818787) (xy 463.065173 -57.788521)
			(xy 463.051822 -57.760973) (xy 463.041746 -57.74944) (xy 463.022456 -57.728129) (xy 462.98989 -57.680765)
			(xy 462.964798 -57.62905) (xy 462.947748 -57.574157) (xy 462.939127 -57.517327) (xy 462.939129 -57.459847)
			(xy 462.947754 -57.403017) (xy 462.964807 -57.348125) (xy 462.989903 -57.296413) (xy 463.022473 -57.24905)
			(xy 463.041746 -57.227724) (xy 463.051837 -57.216205) (xy 463.065181 -57.188654) (xy 463.069763 -57.158387)
			(xy 463.065173 -57.128121) (xy 463.051822 -57.100573) (xy 463.041746 -57.08904) (xy 463.022468 -57.067719)
			(xy 462.989902 -57.020356) (xy 462.964811 -56.968642) (xy 462.947762 -56.91375) (xy 462.939142 -56.856921)
			(xy 462.938622 -56.828182) (xy 462.939038 -56.800927) (xy 462.946798 -56.746973) (xy 462.962158 -56.694672)
			(xy 462.984805 -56.64509) (xy 463.014278 -56.599236) (xy 463.049976 -56.558042) (xy 463.091174 -56.522349)
			(xy 463.137032 -56.492882) (xy 463.186618 -56.470241) (xy 463.23892 -56.454888) (xy 463.292875 -56.447135)
			(xy 463.32013 -56.446674) (xy 463.349046 -56.447215) (xy 463.406218 -56.455935) (xy 463.461417 -56.473187)
			(xy 463.51338 -56.498574) (xy 463.560914 -56.531515) (xy 463.60293 -56.571255) (xy 463.62112 -56.59374)
			(xy 463.631017 -56.605545) (xy 463.656341 -56.623064) (xy 463.685734 -56.63224) (xy 463.716526 -56.63224)
			(xy 463.745919 -56.623064) (xy 463.771243 -56.605545) (xy 463.78114 -56.59374) (xy 463.799319 -56.571246)
			(xy 463.84134 -56.531509) (xy 463.888877 -56.49857) (xy 463.940841 -56.473184) (xy 463.996041 -56.45593)
			(xy 464.053213 -56.447206) (xy 464.08213 -56.446674) (xy 464.110869 -56.447186) (xy 464.167697 -56.455813)
			(xy 464.222587 -56.472866) (xy 464.274299 -56.49796) (xy 464.321661 -56.530527) (xy 464.342988 -56.549798)
			(xy 464.354522 -56.55987) (xy 464.382068 -56.573212) (xy 464.41233 -56.577797) (xy 464.442592 -56.573212)
			(xy 464.470138 -56.55987) (xy 464.481672 -56.549798) (xy 464.502999 -56.530528) (xy 464.550362 -56.497963)
			(xy 464.602073 -56.472872) (xy 464.656964 -56.455822) (xy 464.713791 -56.4472) (xy 464.771269 -56.4472)
			(xy 464.828096 -56.455822) (xy 464.882987 -56.472872) (xy 464.934698 -56.497963) (xy 464.982061 -56.530528)
			(xy 465.003388 -56.549798) (xy 465.014922 -56.55987) (xy 465.042468 -56.573212) (xy 465.07273 -56.577797)
			(xy 465.102992 -56.573212) (xy 465.130538 -56.55987) (xy 465.142072 -56.549798) (xy 465.163399 -56.530528)
			(xy 465.210762 -56.497963) (xy 465.262473 -56.472872) (xy 465.317364 -56.455822) (xy 465.374191 -56.4472)
			(xy 465.431669 -56.4472) (xy 465.488496 -56.455822) (xy 465.543387 -56.472872) (xy 465.595098 -56.497963)
			(xy 465.642461 -56.530528) (xy 465.663788 -56.549798) (xy 465.675322 -56.55987) (xy 465.702868 -56.573212)
			(xy 465.73313 -56.577797) (xy 465.763392 -56.573212) (xy 465.790938 -56.55987) (xy 465.802472 -56.549798)
			(xy 465.823796 -56.530523) (xy 465.871158 -56.497955) (xy 465.92287 -56.472863) (xy 465.977762 -56.455813)
			(xy 466.034591 -56.447193) (xy 466.06333 -56.446674) (xy 466.092246 -56.447215) (xy 466.149418 -56.455935)
			(xy 466.204617 -56.473187) (xy 466.25658 -56.498574) (xy 466.304114 -56.531515) (xy 466.34613 -56.571255)
			(xy 466.36432 -56.59374) (xy 466.374217 -56.605545) (xy 466.399541 -56.623064) (xy 466.428934 -56.63224)
			(xy 466.459726 -56.63224) (xy 466.489119 -56.623064) (xy 466.514443 -56.605545) (xy 466.52434 -56.59374)
			(xy 466.542519 -56.571246) (xy 466.58454 -56.531509) (xy 466.632077 -56.49857) (xy 466.684041 -56.473184)
			(xy 466.739241 -56.45593) (xy 466.796413 -56.447206) (xy 466.82533 -56.446674) (xy 466.852581 -56.44715)
			(xy 466.906528 -56.45491) (xy 466.958822 -56.470268) (xy 467.008398 -56.492911) (xy 467.054248 -56.522379)
			(xy 467.095437 -56.558071) (xy 467.131128 -56.599262) (xy 467.160594 -56.645112) (xy 467.183236 -56.694689)
			(xy 467.198593 -56.746983) (xy 467.206351 -56.800931) (xy 467.206838 -56.828182) (xy 467.206293 -56.85692)
			(xy 467.197674 -56.913746) (xy 467.180628 -56.968636) (xy 467.155542 -57.020348) (xy 467.122982 -57.067712)
			(xy 467.103714 -57.08904) (xy 467.093661 -57.100589) (xy 467.080319 -57.12813) (xy 467.075732 -57.158387)
			(xy 467.080311 -57.188645) (xy 467.093646 -57.21619) (xy 467.103714 -57.227724) (xy 467.122965 -57.249067)
			(xy 467.155528 -57.296428) (xy 467.180618 -57.348137) (xy 467.197667 -57.403025) (xy 467.206291 -57.459849)
			(xy 467.206293 -57.517324) (xy 467.197673 -57.574149) (xy 467.180628 -57.629038) (xy 467.155541 -57.680749)
			(xy 467.122982 -57.728112) (xy 467.103714 -57.74944) (xy 467.093661 -57.760989) (xy 467.080319 -57.78853)
			(xy 467.075732 -57.818787) (xy 467.080311 -57.849045) (xy 467.093646 -57.87659) (xy 467.103714 -57.888124)
			(xy 467.122968 -57.909465) (xy 467.155539 -57.956823) (xy 467.180635 -58.008531) (xy 467.197689 -58.063418)
			(xy 467.206316 -58.120244) (xy 467.206838 -58.148982) (xy 467.206376 -58.176353) (xy 467.19856 -58.230532)
			(xy 467.183071 -58.283036) (xy 467.160227 -58.332783) (xy 467.130501 -58.378749) (xy 467.112858 -58.39968)
			(xy 467.103642 -58.411022) (xy 467.091467 -58.437575) (xy 467.087293 -58.466486) (xy 467.09146 -58.495399)
			(xy 467.103627 -58.521955) (xy 467.112858 -58.533284) (xy 467.130482 -58.554231) (xy 467.160208 -58.600196)
			(xy 467.183056 -58.64994) (xy 467.198554 -58.70244) (xy 467.206385 -58.756617) (xy 467.206387 -58.811356)
			(xy 467.19856 -58.865534) (xy 467.183065 -58.918035) (xy 467.160221 -58.96778) (xy 467.130498 -59.013748)
			(xy 467.112858 -59.03468) (xy 467.103642 -59.046022) (xy 467.091467 -59.072575) (xy 467.087293 -59.101486)
			(xy 467.09146 -59.130399) (xy 467.103627 -59.156955) (xy 467.112858 -59.168284) (xy 467.130497 -59.189217)
			(xy 467.16021 -59.235189) (xy 467.183047 -59.284936) (xy 467.198538 -59.337437) (xy 467.206365 -59.391613)
			(xy 467.206838 -59.418982) (xy 467.206305 -59.446231) (xy 467.198552 -59.500176) (xy 467.1832 -59.552468)
			(xy 467.160564 -59.602043) (xy 467.131102 -59.647892) (xy 467.095416 -59.689082) (xy 467.05423 -59.724773)
			(xy 467.008385 -59.754241) (xy 466.958813 -59.776884) (xy 466.906523 -59.792242) (xy 466.852579 -59.800002)
			(xy 466.82533 -59.80049) (xy 466.796414 -59.799954) (xy 466.739243 -59.791229) (xy 466.684045 -59.773975)
			(xy 466.632083 -59.748587) (xy 466.584548 -59.715646) (xy 466.542531 -59.675908) (xy 466.52434 -59.653424)
			(xy 466.514443 -59.641619) (xy 466.489119 -59.6241) (xy 466.459726 -59.614924) (xy 466.428934 -59.614924)
			(xy 466.399541 -59.6241) (xy 466.374217 -59.641619) (xy 466.36432 -59.653424) (xy 466.346124 -59.675903)
			(xy 466.304104 -59.715637) (xy 466.25657 -59.748576) (xy 466.20461 -59.773965) (xy 466.149414 -59.791223)
			(xy 466.092246 -59.799954) (xy 466.06333 -59.80049) (xy 466.034592 -59.799951) (xy 465.977765 -59.791332)
			(xy 465.922874 -59.774286) (xy 465.871162 -59.749198) (xy 465.823799 -59.716636) (xy 465.802472 -59.697366)
			(xy 465.790938 -59.687294) (xy 465.763392 -59.673952) (xy 465.73313 -59.669367) (xy 465.702868 -59.673952)
			(xy 465.675322 -59.687294) (xy 465.663788 -59.697366) (xy 465.642461 -59.716636) (xy 465.595098 -59.749201)
			(xy 465.543387 -59.774292) (xy 465.488496 -59.791342) (xy 465.431669 -59.799964) (xy 465.374191 -59.799964)
			(xy 465.317364 -59.791342) (xy 465.262473 -59.774292) (xy 465.210762 -59.749201) (xy 465.163399 -59.716636)
			(xy 465.142072 -59.697366) (xy 465.130538 -59.687294) (xy 465.102992 -59.673952) (xy 465.07273 -59.669367)
			(xy 465.042468 -59.673952) (xy 465.014922 -59.687294) (xy 465.003388 -59.697366) (xy 464.982061 -59.716636)
			(xy 464.934698 -59.749201) (xy 464.882987 -59.774292) (xy 464.828096 -59.791342) (xy 464.771269 -59.799964)
			(xy 464.713791 -59.799964) (xy 464.656964 -59.791342) (xy 464.602073 -59.774292) (xy 464.550362 -59.749201)
			(xy 464.502999 -59.716636) (xy 464.481672 -59.697366) (xy 464.470138 -59.687294) (xy 464.442592 -59.673952)
			(xy 464.41233 -59.669367) (xy 464.382068 -59.673952) (xy 464.354522 -59.687294) (xy 464.342988 -59.697366)
			(xy 464.321649 -59.716623) (xy 464.27429 -59.749191) (xy 464.222582 -59.774286) (xy 464.167694 -59.79134)
			(xy 464.110868 -59.799967) (xy 464.08213 -59.80049) (xy 464.053214 -59.799954) (xy 463.996043 -59.791229)
			(xy 463.940845 -59.773975) (xy 463.888883 -59.748587) (xy 463.841348 -59.715646) (xy 463.799331 -59.675908)
			(xy 463.78114 -59.653424) (xy 463.771243 -59.641619) (xy 463.745919 -59.6241) (xy 463.716526 -59.614924)
			(xy 463.685734 -59.614924) (xy 463.656341 -59.6241) (xy 463.631017 -59.641619) (xy 463.62112 -59.653424)
			(xy 463.602924 -59.675903) (xy 463.560904 -59.715637) (xy 463.51337 -59.748576) (xy 463.46141 -59.773965)
			(xy 463.406214 -59.791223) (xy 463.349046 -59.799954) (xy 463.32013 -59.80049) (xy 463.292877 -59.800017)
			(xy 463.238926 -59.792263) (xy 463.186627 -59.77691) (xy 463.137046 -59.75427) (xy 463.091191 -59.724803)
			(xy 463.049998 -59.689111) (xy 463.014304 -59.647918) (xy 462.984836 -59.602065) (xy 462.962194 -59.552484)
			(xy 462.946839 -59.500186) (xy 462.939084 -59.446235) (xy 462.938622 -59.418982) (xy 441.0456 -59.418982)
			(xy 441.0456 -68.56215) (xy 463.017866 -68.56215) (xy 463.017866 -68.477454) (xy 463.025917 -68.39314)
			(xy 463.041946 -68.309974) (xy 463.065807 -68.228707) (xy 463.097286 -68.150077) (xy 463.136097 -68.074796)
			(xy 463.181887 -68.003544) (xy 463.234243 -67.936968) (xy 463.292691 -67.87567) (xy 463.356701 -67.820205)
			(xy 463.425693 -67.771076) (xy 463.499043 -67.728727) (xy 463.576086 -67.693543) (xy 463.656125 -67.665841)
			(xy 463.738434 -67.645873) (xy 463.822269 -67.63382) (xy 463.90687 -67.62979) (xy 463.991471 -67.63382)
			(xy 464.075306 -67.645873) (xy 464.157615 -67.665841) (xy 464.237654 -67.693543) (xy 464.314697 -67.728727)
			(xy 464.388047 -67.771076) (xy 464.457039 -67.820205) (xy 464.521049 -67.87567) (xy 464.579497 -67.936968)
			(xy 464.631853 -68.003544) (xy 464.677643 -68.074796) (xy 464.716454 -68.150077) (xy 464.747933 -68.228707)
			(xy 464.771794 -68.309974) (xy 464.787823 -68.39314) (xy 464.795874 -68.477454) (xy 464.796378 -68.519802)
			(xy 465.542379 -68.519802) (xy 465.546415 -68.436355) (xy 465.558487 -68.353687) (xy 465.57848 -68.27257)
			(xy 465.606209 -68.193761) (xy 465.641415 -68.117996) (xy 465.683769 -68.045983) (xy 465.732875 -67.978394)
			(xy 465.788276 -67.91586) (xy 465.849453 -67.858965) (xy 465.915836 -67.808239) (xy 465.986804 -67.764158)
			(xy 466.061696 -67.727132) (xy 466.139812 -67.697506) (xy 466.220422 -67.675558) (xy 466.302774 -67.661493)
			(xy 466.3861 -67.655441) (xy 466.46962 -67.65746) (xy 466.552556 -67.66753) (xy 466.634132 -67.685558)
			(xy 466.713588 -67.711375) (xy 466.790181 -67.74474) (xy 466.863197 -67.785341) (xy 466.931953 -67.8328)
			(xy 466.995807 -67.886673) (xy 467.054164 -67.946458) (xy 467.106479 -68.011595) (xy 467.152262 -68.081478)
			(xy 467.191087 -68.155453) (xy 467.222592 -68.23283) (xy 467.246481 -68.312887) (xy 467.262532 -68.394875)
			(xy 467.270595 -68.47803) (xy 467.2711 -68.519802) (xy 467.270595 -68.561574) (xy 467.262532 -68.644729)
			(xy 467.246481 -68.726717) (xy 467.222592 -68.806774) (xy 467.191087 -68.884151) (xy 467.152262 -68.958126)
			(xy 467.106479 -69.028009) (xy 467.054164 -69.093146) (xy 466.995807 -69.152931) (xy 466.931953 -69.206804)
			(xy 466.863197 -69.254263) (xy 466.790181 -69.294864) (xy 466.713588 -69.328229) (xy 466.634132 -69.354046)
			(xy 466.552556 -69.372074) (xy 466.46962 -69.382144) (xy 466.3861 -69.384163) (xy 466.302774 -69.378111)
			(xy 466.220422 -69.364046) (xy 466.139812 -69.342098) (xy 466.061696 -69.312472) (xy 465.986804 -69.275446)
			(xy 465.915836 -69.231365) (xy 465.849453 -69.180639) (xy 465.788276 -69.123744) (xy 465.732875 -69.06121)
			(xy 465.683769 -68.993621) (xy 465.641415 -68.921608) (xy 465.606209 -68.845843) (xy 465.57848 -68.767034)
			(xy 465.558487 -68.685917) (xy 465.546415 -68.603249) (xy 465.542379 -68.519802) (xy 464.796378 -68.519802)
			(xy 464.795874 -68.56215) (xy 464.787823 -68.646464) (xy 464.771794 -68.72963) (xy 464.747933 -68.810897)
			(xy 464.716454 -68.889527) (xy 464.677643 -68.964808) (xy 464.631853 -69.03606) (xy 464.579497 -69.102636)
			(xy 464.521049 -69.163934) (xy 464.457039 -69.219399) (xy 464.388047 -69.268528) (xy 464.314697 -69.310877)
			(xy 464.237654 -69.346061) (xy 464.157615 -69.373763) (xy 464.075306 -69.393731) (xy 463.991471 -69.405784)
			(xy 463.90687 -69.409815) (xy 463.822269 -69.405784) (xy 463.738434 -69.393731) (xy 463.656125 -69.373763)
			(xy 463.576086 -69.346061) (xy 463.499043 -69.310877) (xy 463.425693 -69.268528) (xy 463.356701 -69.219399)
			(xy 463.292691 -69.163934) (xy 463.234243 -69.102636) (xy 463.181887 -69.03606) (xy 463.136097 -68.964808)
			(xy 463.097286 -68.889527) (xy 463.065807 -68.810897) (xy 463.041946 -68.72963) (xy 463.025917 -68.646464)
			(xy 463.017866 -68.56215) (xy 441.0456 -68.56215) (xy 441.0456 -71.039228) (xy 443.224918 -71.039228)
			(xy 443.228989 -70.983606) (xy 443.241115 -70.929169) (xy 443.261038 -70.877078) (xy 443.288334 -70.828443)
			(xy 443.32242 -70.7843) (xy 443.362569 -70.745591) (xy 443.407927 -70.71314) (xy 443.457527 -70.687639)
			(xy 443.510311 -70.669632) (xy 443.565154 -70.659502) (xy 443.620888 -70.657465) (xy 443.676325 -70.663565)
			(xy 443.730282 -70.677671) (xy 443.781611 -70.699483) (xy 443.829217 -70.728537) (xy 443.872085 -70.764212)
			(xy 443.909302 -70.805749) (xy 443.940075 -70.852262) (xy 443.963747 -70.902759) (xy 443.979815 -70.956166)
			(xy 443.987935 -71.011342) (xy 443.988444 -71.039228) (xy 443.987935 -71.067114) (xy 443.979815 -71.12229)
			(xy 443.963747 -71.175697) (xy 443.940075 -71.226194) (xy 443.909302 -71.272707) (xy 443.872085 -71.314244)
			(xy 443.829217 -71.349919) (xy 443.781611 -71.378973) (xy 443.730282 -71.400785) (xy 443.676325 -71.414891)
			(xy 443.620888 -71.420991) (xy 443.565154 -71.418954) (xy 443.510311 -71.408824) (xy 443.457527 -71.390817)
			(xy 443.407927 -71.365316) (xy 443.362569 -71.332865) (xy 443.32242 -71.294156) (xy 443.288334 -71.250013)
			(xy 443.261038 -71.201378) (xy 443.241115 -71.149287) (xy 443.228989 -71.09485) (xy 443.224918 -71.039228)
			(xy 441.0456 -71.039228) (xy 441.0456 -73.088052) (xy 452.643969 -73.088052) (xy 452.643969 -73.033548)
			(xy 452.651726 -72.979599) (xy 452.667082 -72.927303) (xy 452.689723 -72.877724) (xy 452.719191 -72.831873)
			(xy 452.754883 -72.790682) (xy 452.796074 -72.754989) (xy 452.841926 -72.725522) (xy 452.891505 -72.702881)
			(xy 452.943801 -72.687526) (xy 452.99775 -72.679769) (xy 453.025002 -72.679306) (xy 453.052711 -72.679821)
			(xy 453.107544 -72.687844) (xy 453.160639 -72.703721) (xy 453.210876 -72.727117) (xy 453.257196 -72.75754)
			(xy 453.27824 -72.775572) (xy 453.289642 -72.78504) (xy 453.316492 -72.797557) (xy 453.345804 -72.80185)
			(xy 453.375116 -72.797557) (xy 453.401966 -72.78504) (xy 453.413368 -72.775572) (xy 453.434411 -72.757537)
			(xy 453.480729 -72.727108) (xy 453.530966 -72.703707) (xy 453.584061 -72.687827) (xy 453.638896 -72.679803)
			(xy 453.666606 -72.679306) (xy 453.693858 -72.679764) (xy 453.747807 -72.687522) (xy 453.800103 -72.702878)
			(xy 453.849681 -72.72552) (xy 453.895533 -72.754988) (xy 453.936724 -72.790681) (xy 453.972416 -72.831872)
			(xy 454.001883 -72.877724) (xy 454.024524 -72.927303) (xy 454.03988 -72.979599) (xy 454.047636 -73.033548)
			(xy 454.047636 -73.088052) (xy 454.047636 -73.088053) (xy 454.467669 -73.088053) (xy 454.467669 -73.033547)
			(xy 454.475427 -72.979596) (xy 454.490783 -72.927299) (xy 454.513426 -72.877719) (xy 454.542895 -72.831866)
			(xy 454.57859 -72.790675) (xy 454.619784 -72.754982) (xy 454.665638 -72.725516) (xy 454.715219 -72.702876)
			(xy 454.767518 -72.687522) (xy 454.821469 -72.679768) (xy 454.848722 -72.679306) (xy 454.876431 -72.679809)
			(xy 454.931265 -72.687835) (xy 454.98436 -72.703715) (xy 455.034596 -72.727113) (xy 455.080916 -72.757538)
			(xy 455.10196 -72.775572) (xy 455.113362 -72.78504) (xy 455.140212 -72.797557) (xy 455.169524 -72.80185)
			(xy 455.198836 -72.797557) (xy 455.225686 -72.78504) (xy 455.237088 -72.775572) (xy 455.258124 -72.757528)
			(xy 455.304444 -72.7271) (xy 455.354682 -72.703701) (xy 455.407779 -72.687823) (xy 455.462616 -72.679801)
			(xy 455.490326 -72.679306) (xy 455.517577 -72.679766) (xy 455.571524 -72.687525) (xy 455.623817 -72.702883)
			(xy 455.673393 -72.725527) (xy 455.719242 -72.754995) (xy 455.760431 -72.790688) (xy 455.796121 -72.831879)
			(xy 455.825586 -72.87773) (xy 455.848226 -72.927307) (xy 455.86358 -72.979602) (xy 455.871336 -73.033549)
			(xy 455.871336 -73.088051) (xy 455.86358 -73.141998) (xy 455.848226 -73.194293) (xy 455.825586 -73.24387)
			(xy 455.796121 -73.289721) (xy 455.760431 -73.330912) (xy 455.719242 -73.366605) (xy 455.673393 -73.396073)
			(xy 455.623817 -73.418717) (xy 455.571524 -73.434075) (xy 455.517577 -73.441834) (xy 455.490326 -73.442322)
			(xy 455.462616 -73.441843) (xy 455.407781 -73.43381) (xy 455.354686 -73.417924) (xy 455.30445 -73.39452)
			(xy 455.258131 -73.364091) (xy 455.237088 -73.346056) (xy 455.225686 -73.336588) (xy 455.198836 -73.324071)
			(xy 455.169524 -73.319778) (xy 455.140212 -73.324071) (xy 455.113362 -73.336588) (xy 455.10196 -73.346056)
			(xy 455.08091 -73.364082) (xy 455.034593 -73.394511) (xy 454.984358 -73.417914) (xy 454.931265 -73.433796)
			(xy 454.876431 -73.441823) (xy 454.848722 -73.442322) (xy 454.821469 -73.441832) (xy 454.767518 -73.434078)
			(xy 454.715219 -73.418724) (xy 454.665638 -73.396084) (xy 454.619784 -73.366618) (xy 454.57859 -73.330925)
			(xy 454.542895 -73.289734) (xy 454.513426 -73.243881) (xy 454.490783 -73.194301) (xy 454.475427 -73.142004)
			(xy 454.467669 -73.088053) (xy 454.047636 -73.088053) (xy 454.03988 -73.142001) (xy 454.024524 -73.194297)
			(xy 454.001883 -73.243876) (xy 453.972416 -73.289728) (xy 453.936724 -73.330919) (xy 453.895533 -73.366612)
			(xy 453.849681 -73.39608) (xy 453.800103 -73.418722) (xy 453.747807 -73.434078) (xy 453.693858 -73.441836)
			(xy 453.666606 -73.442322) (xy 453.638898 -73.441795) (xy 453.584065 -73.433774) (xy 453.530971 -73.4179)
			(xy 453.480734 -73.394506) (xy 453.434413 -73.364087) (xy 453.413368 -73.346056) (xy 453.401966 -73.336588)
			(xy 453.375116 -73.324071) (xy 453.345804 -73.319778) (xy 453.316492 -73.324071) (xy 453.289642 -73.336588)
			(xy 453.27824 -73.346056) (xy 453.257197 -73.364091) (xy 453.210879 -73.394519) (xy 453.160642 -73.41792)
			(xy 453.107547 -73.4338) (xy 453.052712 -73.441825) (xy 453.025002 -73.442322) (xy 452.99775 -73.441831)
			(xy 452.943801 -73.434074) (xy 452.891505 -73.418719) (xy 452.841926 -73.396078) (xy 452.796074 -73.366611)
			(xy 452.754883 -73.330918) (xy 452.719191 -73.289727) (xy 452.689723 -73.243876) (xy 452.667082 -73.194297)
			(xy 452.651726 -73.142001) (xy 452.643969 -73.088052) (xy 441.0456 -73.088052) (xy 441.0456 -74.640948)
			(xy 443.978282 -74.640948) (xy 443.982353 -74.585326) (xy 443.994479 -74.530889) (xy 444.014402 -74.478798)
			(xy 444.041698 -74.430163) (xy 444.075784 -74.38602) (xy 444.115933 -74.347311) (xy 444.161291 -74.31486)
			(xy 444.210891 -74.289359) (xy 444.263675 -74.271352) (xy 444.318518 -74.261222) (xy 444.374252 -74.259185)
			(xy 444.429689 -74.265285) (xy 444.483646 -74.279391) (xy 444.534975 -74.301203) (xy 444.582581 -74.330257)
			(xy 444.625449 -74.365932) (xy 444.662666 -74.407469) (xy 444.693439 -74.453982) (xy 444.717111 -74.504479)
			(xy 444.733179 -74.557886) (xy 444.741299 -74.613062) (xy 444.741808 -74.640948) (xy 444.741299 -74.668834)
			(xy 444.733179 -74.72401) (xy 444.717111 -74.777417) (xy 444.693439 -74.827914) (xy 444.662666 -74.874427)
			(xy 444.625449 -74.915964) (xy 444.582581 -74.951639) (xy 444.534975 -74.980693) (xy 444.483646 -75.002505)
			(xy 444.429689 -75.016611) (xy 444.374252 -75.022711) (xy 444.318518 -75.020674) (xy 444.263675 -75.010544)
			(xy 444.210891 -74.992537) (xy 444.161291 -74.967036) (xy 444.115933 -74.934585) (xy 444.075784 -74.895876)
			(xy 444.041698 -74.851733) (xy 444.014402 -74.803098) (xy 443.994479 -74.751007) (xy 443.982353 -74.69657)
			(xy 443.978282 -74.640948) (xy 441.0456 -74.640948) (xy 441.0456 -75.054206) (xy 451.065898 -75.054206)
			(xy 451.069969 -74.998584) (xy 451.082095 -74.944147) (xy 451.102018 -74.892056) (xy 451.129314 -74.843421)
			(xy 451.1634 -74.799278) (xy 451.203549 -74.760569) (xy 451.248907 -74.728118) (xy 451.298507 -74.702617)
			(xy 451.351291 -74.68461) (xy 451.406134 -74.67448) (xy 451.461868 -74.672443) (xy 451.517305 -74.678543)
			(xy 451.571262 -74.692649) (xy 451.622591 -74.714461) (xy 451.670197 -74.743515) (xy 451.713065 -74.77919)
			(xy 451.745377 -74.815253) (xy 454.048569 -74.815253) (xy 454.048569 -74.760747) (xy 454.056327 -74.706796)
			(xy 454.071683 -74.654499) (xy 454.094326 -74.604919) (xy 454.123795 -74.559066) (xy 454.15949 -74.517875)
			(xy 454.200684 -74.482182) (xy 454.246538 -74.452716) (xy 454.296119 -74.430076) (xy 454.348418 -74.414722)
			(xy 454.402369 -74.406968) (xy 454.429622 -74.406506) (xy 454.457331 -74.407009) (xy 454.512165 -74.415035)
			(xy 454.56526 -74.430915) (xy 454.615496 -74.454313) (xy 454.661816 -74.484738) (xy 454.68286 -74.502772)
			(xy 454.694262 -74.51224) (xy 454.721112 -74.524757) (xy 454.750424 -74.52905) (xy 454.779736 -74.524757)
			(xy 454.806586 -74.51224) (xy 454.817988 -74.502772) (xy 454.839024 -74.484728) (xy 454.885344 -74.4543)
			(xy 454.935582 -74.430901) (xy 454.988679 -74.415023) (xy 455.043516 -74.407001) (xy 455.071226 -74.406506)
			(xy 455.098477 -74.406966) (xy 455.152424 -74.414725) (xy 455.204717 -74.430083) (xy 455.254293 -74.452727)
			(xy 455.300142 -74.482195) (xy 455.341331 -74.517888) (xy 455.377021 -74.559079) (xy 455.406486 -74.60493)
			(xy 455.429126 -74.654507) (xy 455.44448 -74.706802) (xy 455.452236 -74.760749) (xy 455.452236 -74.815251)
			(xy 455.44448 -74.869198) (xy 455.429126 -74.921493) (xy 455.406486 -74.97107) (xy 455.377021 -75.016921)
			(xy 455.341331 -75.058112) (xy 455.300142 -75.093805) (xy 455.254293 -75.123273) (xy 455.204717 -75.145917)
			(xy 455.152424 -75.161275) (xy 455.098477 -75.169034) (xy 455.071226 -75.169522) (xy 455.043516 -75.169043)
			(xy 454.988681 -75.16101) (xy 454.935586 -75.145124) (xy 454.88535 -75.12172) (xy 454.839031 -75.091291)
			(xy 454.817988 -75.073256) (xy 454.806586 -75.063788) (xy 454.779736 -75.051271) (xy 454.750424 -75.046978)
			(xy 454.721112 -75.051271) (xy 454.694262 -75.063788) (xy 454.68286 -75.073256) (xy 454.66181 -75.091282)
			(xy 454.615493 -75.121711) (xy 454.565258 -75.145114) (xy 454.512165 -75.160996) (xy 454.457331 -75.169023)
			(xy 454.429622 -75.169522) (xy 454.402369 -75.169032) (xy 454.348418 -75.161278) (xy 454.296119 -75.145924)
			(xy 454.246538 -75.123284) (xy 454.200684 -75.093818) (xy 454.15949 -75.058125) (xy 454.123795 -75.016934)
			(xy 454.094326 -74.971081) (xy 454.071683 -74.921501) (xy 454.056327 -74.869204) (xy 454.048569 -74.815253)
			(xy 451.745377 -74.815253) (xy 451.750282 -74.820727) (xy 451.781055 -74.86724) (xy 451.804727 -74.917737)
			(xy 451.820795 -74.971144) (xy 451.828915 -75.02632) (xy 451.829424 -75.054206) (xy 451.828915 -75.082092)
			(xy 451.820795 -75.137268) (xy 451.804727 -75.190675) (xy 451.781055 -75.241172) (xy 451.750282 -75.287685)
			(xy 451.713065 -75.329222) (xy 451.670197 -75.364897) (xy 451.622591 -75.393951) (xy 451.571262 -75.415763)
			(xy 451.517305 -75.429869) (xy 451.461868 -75.435969) (xy 451.406134 -75.433932) (xy 451.351291 -75.423802)
			(xy 451.298507 -75.405795) (xy 451.248907 -75.380294) (xy 451.203549 -75.347843) (xy 451.1634 -75.309134)
			(xy 451.129314 -75.264991) (xy 451.102018 -75.216356) (xy 451.082095 -75.164265) (xy 451.069969 -75.109828)
			(xy 451.065898 -75.054206) (xy 441.0456 -75.054206) (xy 441.0456 -76.002572) (xy 463.017866 -76.002572)
			(xy 463.017866 -75.917876) (xy 463.025917 -75.833562) (xy 463.041946 -75.750396) (xy 463.065807 -75.669129)
			(xy 463.097286 -75.590499) (xy 463.136097 -75.515218) (xy 463.181887 -75.443966) (xy 463.234243 -75.37739)
			(xy 463.292691 -75.316092) (xy 463.356701 -75.260627) (xy 463.425693 -75.211498) (xy 463.499043 -75.169149)
			(xy 463.576086 -75.133965) (xy 463.656125 -75.106263) (xy 463.738434 -75.086295) (xy 463.822269 -75.074242)
			(xy 463.90687 -75.070212) (xy 463.991471 -75.074242) (xy 464.075306 -75.086295) (xy 464.157615 -75.106263)
			(xy 464.237654 -75.133965) (xy 464.314697 -75.169149) (xy 464.388047 -75.211498) (xy 464.457039 -75.260627)
			(xy 464.521049 -75.316092) (xy 464.579497 -75.37739) (xy 464.631853 -75.443966) (xy 464.677643 -75.515218)
			(xy 464.716454 -75.590499) (xy 464.747933 -75.669129) (xy 464.771794 -75.750396) (xy 464.787823 -75.833562)
			(xy 464.795874 -75.917876) (xy 464.796378 -75.960224) (xy 465.542379 -75.960224) (xy 465.546415 -75.876777)
			(xy 465.558487 -75.794109) (xy 465.57848 -75.712992) (xy 465.606209 -75.634183) (xy 465.641415 -75.558418)
			(xy 465.683769 -75.486405) (xy 465.732875 -75.418816) (xy 465.788276 -75.356282) (xy 465.849453 -75.299387)
			(xy 465.915836 -75.248661) (xy 465.986804 -75.20458) (xy 466.061696 -75.167554) (xy 466.139812 -75.137928)
			(xy 466.220422 -75.11598) (xy 466.302774 -75.101915) (xy 466.3861 -75.095863) (xy 466.46962 -75.097882)
			(xy 466.552556 -75.107952) (xy 466.634132 -75.12598) (xy 466.713588 -75.151797) (xy 466.790181 -75.185162)
			(xy 466.863197 -75.225763) (xy 466.931953 -75.273222) (xy 466.995807 -75.327095) (xy 467.054164 -75.38688)
			(xy 467.106479 -75.452017) (xy 467.152262 -75.5219) (xy 467.191087 -75.595875) (xy 467.222592 -75.673252)
			(xy 467.246481 -75.753309) (xy 467.262532 -75.835297) (xy 467.270595 -75.918452) (xy 467.2711 -75.960224)
			(xy 467.270595 -76.001996) (xy 467.262532 -76.085151) (xy 467.246481 -76.167139) (xy 467.222592 -76.247196)
			(xy 467.191087 -76.324573) (xy 467.152262 -76.398548) (xy 467.106479 -76.468431) (xy 467.054164 -76.533568)
			(xy 466.995807 -76.593353) (xy 466.931953 -76.647226) (xy 466.863197 -76.694685) (xy 466.790181 -76.735286)
			(xy 466.713588 -76.768651) (xy 466.634132 -76.794468) (xy 466.552556 -76.812496) (xy 466.46962 -76.822566)
			(xy 466.3861 -76.824585) (xy 466.302774 -76.818533) (xy 466.220422 -76.804468) (xy 466.139812 -76.78252)
			(xy 466.061696 -76.752894) (xy 465.986804 -76.715868) (xy 465.915836 -76.671787) (xy 465.849453 -76.621061)
			(xy 465.788276 -76.564166) (xy 465.732875 -76.501632) (xy 465.683769 -76.434043) (xy 465.641415 -76.36203)
			(xy 465.606209 -76.286265) (xy 465.57848 -76.207456) (xy 465.558487 -76.126339) (xy 465.546415 -76.043671)
			(xy 465.542379 -75.960224) (xy 464.796378 -75.960224) (xy 464.795874 -76.002572) (xy 464.787823 -76.086886)
			(xy 464.771794 -76.170052) (xy 464.747933 -76.251319) (xy 464.716454 -76.329949) (xy 464.677643 -76.40523)
			(xy 464.631853 -76.476482) (xy 464.579497 -76.543058) (xy 464.521049 -76.604356) (xy 464.457039 -76.659821)
			(xy 464.388047 -76.70895) (xy 464.314697 -76.751299) (xy 464.237654 -76.786483) (xy 464.157615 -76.814185)
			(xy 464.075306 -76.834153) (xy 463.991471 -76.846206) (xy 463.90687 -76.850237) (xy 463.822269 -76.846206)
			(xy 463.738434 -76.834153) (xy 463.656125 -76.814185) (xy 463.576086 -76.786483) (xy 463.499043 -76.751299)
			(xy 463.425693 -76.70895) (xy 463.356701 -76.659821) (xy 463.292691 -76.604356) (xy 463.234243 -76.543058)
			(xy 463.181887 -76.476482) (xy 463.136097 -76.40523) (xy 463.097286 -76.329949) (xy 463.065807 -76.251319)
			(xy 463.041946 -76.170052) (xy 463.025917 -76.086886) (xy 463.017866 -76.002572) (xy 441.0456 -76.002572)
			(xy 441.0456 -76.63053) (xy 445.693798 -76.63053) (xy 445.697869 -76.574908) (xy 445.709995 -76.520471)
			(xy 445.729918 -76.46838) (xy 445.757214 -76.419745) (xy 445.7913 -76.375602) (xy 445.831449 -76.336893)
			(xy 445.876807 -76.304442) (xy 445.926407 -76.278941) (xy 445.979191 -76.260934) (xy 446.034034 -76.250804)
			(xy 446.089768 -76.248767) (xy 446.145205 -76.254867) (xy 446.199162 -76.268973) (xy 446.250491 -76.290785)
			(xy 446.298097 -76.319839) (xy 446.340965 -76.355514) (xy 446.378182 -76.397051) (xy 446.408955 -76.443564)
			(xy 446.432627 -76.494061) (xy 446.448695 -76.547468) (xy 446.456815 -76.602644) (xy 446.457106 -76.618592)
			(xy 446.684398 -76.618592) (xy 446.688469 -76.56297) (xy 446.700595 -76.508533) (xy 446.720518 -76.456442)
			(xy 446.747814 -76.407807) (xy 446.7819 -76.363664) (xy 446.822049 -76.324955) (xy 446.867407 -76.292504)
			(xy 446.917007 -76.267003) (xy 446.969791 -76.248996) (xy 447.024634 -76.238866) (xy 447.080368 -76.236829)
			(xy 447.135805 -76.242929) (xy 447.189762 -76.257035) (xy 447.241091 -76.278847) (xy 447.288697 -76.307901)
			(xy 447.331565 -76.343576) (xy 447.368782 -76.385113) (xy 447.399555 -76.431626) (xy 447.423227 -76.482123)
			(xy 447.439295 -76.53553) (xy 447.447415 -76.590706) (xy 447.447924 -76.618592) (xy 447.447548 -76.639166)
			(xy 452.504554 -76.639166) (xy 452.508625 -76.583544) (xy 452.520751 -76.529107) (xy 452.540674 -76.477016)
			(xy 452.56797 -76.428381) (xy 452.602056 -76.384238) (xy 452.642205 -76.345529) (xy 452.687563 -76.313078)
			(xy 452.737163 -76.287577) (xy 452.789947 -76.26957) (xy 452.84479 -76.25944) (xy 452.900524 -76.257403)
			(xy 452.955961 -76.263503) (xy 453.009918 -76.277609) (xy 453.061247 -76.299421) (xy 453.108853 -76.328475)
			(xy 453.151721 -76.36415) (xy 453.188938 -76.405687) (xy 453.219711 -76.4522) (xy 453.243383 -76.502697)
			(xy 453.259451 -76.556104) (xy 453.267571 -76.61128) (xy 453.26808 -76.639166) (xy 453.267571 -76.667052)
			(xy 453.259451 -76.722228) (xy 453.243383 -76.775635) (xy 453.219711 -76.826132) (xy 453.188938 -76.872645)
			(xy 453.151721 -76.914182) (xy 453.108853 -76.949857) (xy 453.061247 -76.978911) (xy 453.009918 -77.000723)
			(xy 452.955961 -77.014829) (xy 452.900524 -77.020929) (xy 452.84479 -77.018892) (xy 452.789947 -77.008762)
			(xy 452.737163 -76.990755) (xy 452.687563 -76.965254) (xy 452.642205 -76.932803) (xy 452.602056 -76.894094)
			(xy 452.56797 -76.849951) (xy 452.540674 -76.801316) (xy 452.520751 -76.749225) (xy 452.508625 -76.694788)
			(xy 452.504554 -76.639166) (xy 447.447548 -76.639166) (xy 447.447415 -76.646478) (xy 447.439295 -76.701654)
			(xy 447.423227 -76.755061) (xy 447.399555 -76.805558) (xy 447.368782 -76.852071) (xy 447.331565 -76.893608)
			(xy 447.288697 -76.929283) (xy 447.241091 -76.958337) (xy 447.189762 -76.980149) (xy 447.135805 -76.994255)
			(xy 447.080368 -77.000355) (xy 447.024634 -76.998318) (xy 446.969791 -76.988188) (xy 446.917007 -76.970181)
			(xy 446.867407 -76.94468) (xy 446.822049 -76.912229) (xy 446.7819 -76.87352) (xy 446.747814 -76.829377)
			(xy 446.720518 -76.780742) (xy 446.700595 -76.728651) (xy 446.688469 -76.674214) (xy 446.684398 -76.618592)
			(xy 446.457106 -76.618592) (xy 446.457324 -76.63053) (xy 446.456815 -76.658416) (xy 446.448695 -76.713592)
			(xy 446.432627 -76.766999) (xy 446.408955 -76.817496) (xy 446.378182 -76.864009) (xy 446.340965 -76.905546)
			(xy 446.298097 -76.941221) (xy 446.250491 -76.970275) (xy 446.199162 -76.992087) (xy 446.145205 -77.006193)
			(xy 446.089768 -77.012293) (xy 446.034034 -77.010256) (xy 445.979191 -77.000126) (xy 445.926407 -76.982119)
			(xy 445.876807 -76.956618) (xy 445.831449 -76.924167) (xy 445.7913 -76.885458) (xy 445.757214 -76.841315)
			(xy 445.729918 -76.79268) (xy 445.709995 -76.740589) (xy 445.697869 -76.686152) (xy 445.693798 -76.63053)
			(xy 441.0456 -76.63053) (xy 441.0456 -78.857348) (xy 442.3156 -80.127348) (xy 443.337188 -80.127348)
		)
		(stroke
			(width 0)
			(type solid)
		)
		(fill yes)
		(layer "In2.Cu")
		(net "GND")
	)
	(gr_poly
		(pts
			(xy 225.406458 -52.5018) (xy 225.407336 -52.474821) (xy 225.415757 -52.421503) (xy 225.431609 -52.369905)
			(xy 225.454576 -52.321056) (xy 225.4842 -52.275933) (xy 225.519889 -52.235436) (xy 225.56093 -52.200374)
			(xy 225.606503 -52.171447) (xy 225.655699 -52.149234) (xy 225.707536 -52.134177) (xy 225.760977 -52.126577)
			(xy 225.787966 -52.126134) (xy 225.814162 -52.126573) (xy 225.866058 -52.133753) (xy 225.916484 -52.14797)
			(xy 225.964489 -52.168956) (xy 226.009169 -52.196316) (xy 226.049683 -52.229534) (xy 226.085269 -52.267985)
			(xy 226.10064 -52.289202) (xy 226.108749 -52.300077) (xy 226.129579 -52.317437) (xy 226.154252 -52.328686)
			(xy 226.181019 -52.333028) (xy 226.207982 -52.330154) (xy 226.233232 -52.320268) (xy 226.244404 -52.31257)
			(xy 226.269202 -52.294943) (xy 226.323219 -52.266958) (xy 226.380994 -52.247901) (xy 226.441062 -52.238257)
			(xy 226.47148 -52.23764) (xy 226.498848 -52.238117) (xy 226.55302 -52.245952) (xy 226.605516 -52.261449)
			(xy 226.655258 -52.284291) (xy 226.701225 -52.314007) (xy 226.722178 -52.33162) (xy 226.733506 -52.340856)
			(xy 226.760063 -52.353032) (xy 226.78898 -52.357205) (xy 226.817897 -52.353032) (xy 226.844454 -52.340856)
			(xy 226.855782 -52.33162) (xy 226.876715 -52.313979) (xy 226.922683 -52.284255) (xy 226.972429 -52.261409)
			(xy 227.024931 -52.245913) (xy 227.079109 -52.238084) (xy 227.133851 -52.238084) (xy 227.188029 -52.245913)
			(xy 227.240531 -52.261409) (xy 227.290277 -52.284255) (xy 227.336245 -52.313979) (xy 227.357178 -52.33162)
			(xy 227.368506 -52.340856) (xy 227.395063 -52.353032) (xy 227.42398 -52.357205) (xy 227.452897 -52.353032)
			(xy 227.479454 -52.340856) (xy 227.490782 -52.33162) (xy 227.511713 -52.313976) (xy 227.557678 -52.284246)
			(xy 227.607425 -52.2614) (xy 227.659928 -52.245906) (xy 227.714109 -52.238085) (xy 227.74148 -52.23764)
			(xy 227.768928 -52.238115) (xy 227.823257 -52.245979) (xy 227.875899 -52.261548) (xy 227.925767 -52.284501)
			(xy 227.97183 -52.314362) (xy 228.013138 -52.350517) (xy 228.048839 -52.392218) (xy 228.078195 -52.438606)
			(xy 228.1006 -52.488721) (xy 228.10851 -52.515008) (xy 228.118924 -52.551838) (xy 228.815392 -52.551838)
			(xy 228.815392 -52.043076) (xy 228.815845 -52.016302) (xy 228.823335 -51.963279) (xy 228.838163 -51.911824)
			(xy 228.86004 -51.862948) (xy 228.888534 -51.81761) (xy 228.923087 -51.776701) (xy 228.96302 -51.741023)
			(xy 229.007548 -51.711279) (xy 229.055797 -51.688052) (xy 229.10682 -51.671799) (xy 229.133146 -51.666902)
			(xy 229.147886 -51.663903) (xy 229.174819 -51.650544) (xy 229.19669 -51.629916) (xy 229.211602 -51.603811)
			(xy 229.218259 -51.574493) (xy 229.217728 -51.55946) (xy 229.216712 -51.53279) (xy 229.217198 -51.505539)
			(xy 229.224954 -51.451591) (xy 229.240309 -51.399296) (xy 229.262951 -51.349719) (xy 229.292417 -51.303869)
			(xy 229.328108 -51.262678) (xy 229.369299 -51.226987) (xy 229.415149 -51.197521) (xy 229.464726 -51.174879)
			(xy 229.517021 -51.159524) (xy 229.570969 -51.151768) (xy 229.625471 -51.151768) (xy 229.679419 -51.159524)
			(xy 229.731714 -51.174879) (xy 229.781291 -51.197521) (xy 229.827141 -51.226987) (xy 229.868332 -51.262678)
			(xy 229.904023 -51.303869) (xy 229.933489 -51.349719) (xy 229.956131 -51.399296) (xy 229.971486 -51.451591)
			(xy 229.979242 -51.505539) (xy 229.979728 -51.53279) (xy 229.979277 -51.559564) (xy 229.978539 -51.564794)
			(xy 230.602026 -51.564794) (xy 230.606097 -51.509172) (xy 230.618223 -51.454735) (xy 230.638146 -51.402644)
			(xy 230.665442 -51.354009) (xy 230.699528 -51.309866) (xy 230.739677 -51.271157) (xy 230.785035 -51.238706)
			(xy 230.834635 -51.213205) (xy 230.887419 -51.195198) (xy 230.942262 -51.185068) (xy 230.997996 -51.183031)
			(xy 231.053433 -51.189131) (xy 231.10739 -51.203237) (xy 231.158719 -51.225049) (xy 231.206325 -51.254103)
			(xy 231.249193 -51.289778) (xy 231.28641 -51.331315) (xy 231.317183 -51.377828) (xy 231.340855 -51.428325)
			(xy 231.356923 -51.481732) (xy 231.365043 -51.536908) (xy 231.365552 -51.564794) (xy 231.365043 -51.59268)
			(xy 231.356923 -51.647856) (xy 231.352263 -51.663346) (xy 234.649262 -51.663346) (xy 234.653333 -51.607724)
			(xy 234.665459 -51.553287) (xy 234.685382 -51.501196) (xy 234.712678 -51.452561) (xy 234.746764 -51.408418)
			(xy 234.786913 -51.369709) (xy 234.832271 -51.337258) (xy 234.881871 -51.311757) (xy 234.934655 -51.29375)
			(xy 234.989498 -51.28362) (xy 235.045232 -51.281583) (xy 235.100669 -51.287683) (xy 235.154626 -51.301789)
			(xy 235.205955 -51.323601) (xy 235.253561 -51.352655) (xy 235.296429 -51.38833) (xy 235.333646 -51.429867)
			(xy 235.364419 -51.47638) (xy 235.388091 -51.526877) (xy 235.404159 -51.580284) (xy 235.412279 -51.63546)
			(xy 235.412788 -51.663346) (xy 235.412279 -51.691232) (xy 235.404159 -51.746408) (xy 235.388091 -51.799815)
			(xy 235.364419 -51.850312) (xy 235.333646 -51.896825) (xy 235.296429 -51.938362) (xy 235.253561 -51.974037)
			(xy 235.205955 -52.003091) (xy 235.154626 -52.024903) (xy 235.100669 -52.039009) (xy 235.045232 -52.045109)
			(xy 234.989498 -52.043072) (xy 234.934655 -52.032942) (xy 234.881871 -52.014935) (xy 234.832271 -51.989434)
			(xy 234.786913 -51.956983) (xy 234.746764 -51.918274) (xy 234.712678 -51.874131) (xy 234.685382 -51.825496)
			(xy 234.665459 -51.773405) (xy 234.653333 -51.718968) (xy 234.649262 -51.663346) (xy 231.352263 -51.663346)
			(xy 231.340855 -51.701263) (xy 231.317183 -51.75176) (xy 231.28641 -51.798273) (xy 231.249193 -51.83981)
			(xy 231.206325 -51.875485) (xy 231.158719 -51.904539) (xy 231.10739 -51.926351) (xy 231.053433 -51.940457)
			(xy 230.997996 -51.946557) (xy 230.942262 -51.94452) (xy 230.887419 -51.93439) (xy 230.834635 -51.916383)
			(xy 230.785035 -51.890882) (xy 230.739677 -51.858431) (xy 230.699528 -51.819722) (xy 230.665442 -51.775579)
			(xy 230.638146 -51.726944) (xy 230.618223 -51.674853) (xy 230.606097 -51.620416) (xy 230.602026 -51.564794)
			(xy 229.978539 -51.564794) (xy 229.971791 -51.612587) (xy 229.956964 -51.664041) (xy 229.935088 -51.712917)
			(xy 229.906593 -51.758254) (xy 229.872038 -51.799162) (xy 229.832103 -51.834835) (xy 229.787572 -51.864574)
			(xy 229.73932 -51.887794) (xy 229.688295 -51.904039) (xy 229.661974 -51.908964) (xy 229.647298 -51.912007)
			(xy 229.620498 -51.925393) (xy 229.598727 -51.945971) (xy 229.583853 -51.971974) (xy 229.577153 -52.001172)
			(xy 229.577646 -52.016152) (xy 229.578408 -52.043076) (xy 229.578408 -52.551838) (xy 235.434378 -52.551838)
			(xy 236.67847 -51.307746) (xy 237.334298 -51.307746) (xy 237.354126 -51.28682) (xy 237.398965 -51.250592)
			(xy 237.448744 -51.221521) (xy 237.50233 -51.20027) (xy 237.558503 -51.187323) (xy 237.615984 -51.182975)
			(xy 237.673465 -51.187323) (xy 237.729638 -51.20027) (xy 237.783224 -51.221521) (xy 237.833003 -51.250592)
			(xy 237.877842 -51.28682) (xy 237.89767 -51.307746) (xy 240.754154 -51.307746) (xy 241.161316 -50.900584)
			(xy 241.171562 -50.889559) (xy 241.185705 -50.863007) (xy 241.191515 -50.83349) (xy 241.188491 -50.803559)
			(xy 241.176893 -50.775801) (xy 241.157725 -50.752615) (xy 241.132643 -50.736006) (xy 241.11839 -50.731166)
			(xy 241.092415 -50.723016) (xy 241.042908 -50.700373) (xy 240.997126 -50.670917) (xy 240.956001 -50.635247)
			(xy 240.920369 -50.594089) (xy 240.890956 -50.54828) (xy 240.868359 -50.498752) (xy 240.853039 -50.446513)
			(xy 240.845307 -50.392626) (xy 240.844832 -50.365406) (xy 240.845295 -50.338154) (xy 240.853051 -50.284204)
			(xy 240.868407 -50.231908) (xy 240.89105 -50.18233) (xy 240.920519 -50.136479) (xy 240.956213 -50.095289)
			(xy 240.997406 -50.059598) (xy 241.04326 -50.030134) (xy 241.09284 -50.007495) (xy 241.145138 -49.992144)
			(xy 241.199088 -49.984393) (xy 241.22634 -49.983898) (xy 241.253556 -49.984385) (xy 241.307435 -49.992132)
			(xy 241.359665 -50.007462) (xy 241.409183 -50.030064) (xy 241.454985 -50.059478) (xy 241.496137 -50.095106)
			(xy 241.531805 -50.136225) (xy 241.561263 -50.181998) (xy 241.583911 -50.231495) (xy 241.5921 -50.257456)
			(xy 241.596892 -50.271743) (xy 241.613483 -50.296881) (xy 241.636678 -50.316095) (xy 241.664465 -50.327718)
			(xy 241.694432 -50.330741) (xy 241.72398 -50.324902) (xy 241.750546 -50.310708) (xy 241.761518 -50.300382)
			(xy 242.542568 -49.519332) (xy 242.542568 -46.660816) (xy 242.212876 -46.331124) (xy 239.199166 -46.331124)
			(xy 239.185659 -46.331509) (xy 239.159575 -46.338527) (xy 239.136246 -46.352143) (xy 239.117306 -46.371402)
			(xy 239.104083 -46.394956) (xy 239.097501 -46.421153) (xy 239.098024 -46.44816) (xy 239.105613 -46.474084)
			(xy 239.119738 -46.497108) (xy 239.129316 -46.506638) (xy 239.147881 -46.524733) (xy 239.180445 -46.565071)
			(xy 239.207251 -46.609445) (xy 239.227804 -46.657039) (xy 239.241727 -46.706977) (xy 239.248762 -46.758339)
			(xy 239.249204 -46.78426) (xy 239.248718 -46.811511) (xy 239.240962 -46.865459) (xy 239.225607 -46.917754)
			(xy 239.202965 -46.967331) (xy 239.202761 -46.967648) (xy 240.694462 -46.967648) (xy 240.698533 -46.912026)
			(xy 240.710659 -46.857589) (xy 240.730582 -46.805498) (xy 240.757878 -46.756863) (xy 240.791964 -46.71272)
			(xy 240.832113 -46.674011) (xy 240.877471 -46.64156) (xy 240.927071 -46.616059) (xy 240.979855 -46.598052)
			(xy 241.034698 -46.587922) (xy 241.090432 -46.585885) (xy 241.145869 -46.591985) (xy 241.199826 -46.606091)
			(xy 241.251155 -46.627903) (xy 241.298761 -46.656957) (xy 241.341629 -46.692632) (xy 241.378846 -46.734169)
			(xy 241.409619 -46.780682) (xy 241.433291 -46.831179) (xy 241.449359 -46.884586) (xy 241.457479 -46.939762)
			(xy 241.457988 -46.967648) (xy 241.457479 -46.995534) (xy 241.449359 -47.05071) (xy 241.433291 -47.104117)
			(xy 241.409619 -47.154614) (xy 241.378846 -47.201127) (xy 241.341629 -47.242664) (xy 241.298761 -47.278339)
			(xy 241.251155 -47.307393) (xy 241.199826 -47.329205) (xy 241.145869 -47.343311) (xy 241.090432 -47.349411)
			(xy 241.034698 -47.347374) (xy 240.979855 -47.337244) (xy 240.927071 -47.319237) (xy 240.877471 -47.293736)
			(xy 240.832113 -47.261285) (xy 240.791964 -47.222576) (xy 240.757878 -47.178433) (xy 240.730582 -47.129798)
			(xy 240.710659 -47.077707) (xy 240.698533 -47.02327) (xy 240.694462 -46.967648) (xy 239.202761 -46.967648)
			(xy 239.173499 -47.013181) (xy 239.137808 -47.054372) (xy 239.096617 -47.090063) (xy 239.050767 -47.119529)
			(xy 239.00119 -47.142171) (xy 238.948895 -47.157526) (xy 238.894947 -47.165282) (xy 238.840445 -47.165282)
			(xy 238.786497 -47.157526) (xy 238.734202 -47.142171) (xy 238.684625 -47.119529) (xy 238.638775 -47.090063)
			(xy 238.597584 -47.054372) (xy 238.561893 -47.013181) (xy 238.532427 -46.967331) (xy 238.509785 -46.917754)
			(xy 238.49443 -46.865459) (xy 238.486674 -46.811511) (xy 238.486188 -46.78426) (xy 238.48662 -46.758337)
			(xy 238.493637 -46.706967) (xy 238.507549 -46.657022) (xy 238.528101 -46.609423) (xy 238.554913 -46.565047)
			(xy 238.58749 -46.524714) (xy 238.606076 -46.506638) (xy 238.615613 -46.497075) (xy 238.62972 -46.474054)
			(xy 238.637298 -46.44814) (xy 238.637817 -46.421146) (xy 238.63124 -46.39496) (xy 238.618027 -46.371415)
			(xy 238.599104 -46.352158) (xy 238.575793 -46.338535) (xy 238.549726 -46.331501) (xy 238.536226 -46.331124)
			(xy 238.183166 -46.331124) (xy 238.169659 -46.331509) (xy 238.143575 -46.338527) (xy 238.120246 -46.352143)
			(xy 238.101306 -46.371402) (xy 238.088083 -46.394956) (xy 238.081501 -46.421153) (xy 238.082024 -46.44816)
			(xy 238.089613 -46.474084) (xy 238.103738 -46.497108) (xy 238.113316 -46.506638) (xy 238.131881 -46.524733)
			(xy 238.164445 -46.565071) (xy 238.191251 -46.609445) (xy 238.211804 -46.657039) (xy 238.225727 -46.706977)
			(xy 238.232762 -46.758339) (xy 238.233204 -46.78426) (xy 238.232718 -46.811511) (xy 238.224962 -46.865459)
			(xy 238.209607 -46.917754) (xy 238.186965 -46.967331) (xy 238.157499 -47.013181) (xy 238.121808 -47.054372)
			(xy 238.080617 -47.090063) (xy 238.034767 -47.119529) (xy 237.98519 -47.142171) (xy 237.932895 -47.157526)
			(xy 237.878947 -47.165282) (xy 237.824445 -47.165282) (xy 237.770497 -47.157526) (xy 237.718202 -47.142171)
			(xy 237.668625 -47.119529) (xy 237.622775 -47.090063) (xy 237.581584 -47.054372) (xy 237.545893 -47.013181)
			(xy 237.516427 -46.967331) (xy 237.493785 -46.917754) (xy 237.47843 -46.865459) (xy 237.470674 -46.811511)
			(xy 237.470188 -46.78426) (xy 237.47062 -46.758337) (xy 237.477637 -46.706967) (xy 237.491549 -46.657022)
			(xy 237.512101 -46.609423) (xy 237.538913 -46.565047) (xy 237.57149 -46.524714) (xy 237.590076 -46.506638)
			(xy 237.599613 -46.497075) (xy 237.61372 -46.474054) (xy 237.621298 -46.44814) (xy 237.621817 -46.421146)
			(xy 237.61524 -46.39496) (xy 237.602027 -46.371415) (xy 237.583104 -46.352158) (xy 237.559793 -46.338535)
			(xy 237.533726 -46.331501) (xy 237.520226 -46.331124) (xy 234.56138 -46.331124) (xy 234.549694 -46.355986)
			(xy 234.520241 -46.402358) (xy 234.484444 -46.444027) (xy 234.443042 -46.480134) (xy 234.396891 -46.509933)
			(xy 234.346945 -46.532806) (xy 234.294236 -46.548283) (xy 234.239852 -46.556043) (xy 234.212384 -46.556422)
			(xy 234.19702 -46.556921) (xy 234.167662 -46.565991) (xy 234.142322 -46.583369) (xy 234.123284 -46.607488)
			(xy 234.112266 -46.636171) (xy 234.110262 -46.666833) (xy 234.113324 -46.681898) (xy 234.118297 -46.703851)
			(xy 234.123651 -46.748545) (xy 234.123992 -46.771052) (xy 234.123532 -46.798307) (xy 234.11578 -46.852262)
			(xy 234.100428 -46.904565) (xy 234.077788 -46.95415) (xy 234.048321 -47.000008) (xy 234.012628 -47.041205)
			(xy 233.971433 -47.076902) (xy 233.925578 -47.106373) (xy 233.875995 -47.129017) (xy 233.823693 -47.144374)
			(xy 233.769739 -47.15213) (xy 233.742484 -47.15256) (xy 233.715147 -47.152092) (xy 233.661031 -47.144293)
			(xy 233.608579 -47.128859) (xy 233.558865 -47.106103) (xy 233.512903 -47.076491) (xy 233.471633 -47.040628)
			(xy 233.453432 -47.020226) (xy 233.443643 -47.009605) (xy 233.419448 -46.993856) (xy 233.391807 -46.985523)
			(xy 233.362938 -46.985273) (xy 233.335157 -46.993128) (xy 233.310692 -47.008456) (xy 233.300778 -47.018956)
			(xy 233.282595 -47.038643) (xy 233.241664 -47.073236) (xy 233.196299 -47.101767) (xy 233.147392 -47.123676)
			(xy 233.095901 -47.138532) (xy 233.042839 -47.146044) (xy 233.016044 -47.146464) (xy 232.98879 -47.146004)
			(xy 232.934837 -47.138252) (xy 232.882536 -47.122899) (xy 232.832953 -47.100258) (xy 232.787098 -47.070791)
			(xy 232.745904 -47.035096) (xy 232.710209 -46.993902) (xy 232.680742 -46.948047) (xy 232.658101 -46.898464)
			(xy 232.642748 -46.846163) (xy 232.634996 -46.79221) (xy 232.634536 -46.764956) (xy 232.635078 -46.736005)
			(xy 232.64384 -46.678769) (xy 232.661156 -46.623516) (xy 232.686627 -46.571517) (xy 232.719669 -46.523967)
			(xy 232.739184 -46.502574) (xy 232.749013 -46.491456) (xy 232.762365 -46.464969) (xy 232.767547 -46.435763)
			(xy 232.764124 -46.406299) (xy 232.752384 -46.37906) (xy 232.733315 -46.356339) (xy 232.708525 -46.340052)
			(xy 232.680102 -46.33157) (xy 232.66527 -46.331124) (xy 231.701848 -46.331124) (xy 231.101392 -46.93158)
			(xy 224.206308 -46.93158) (xy 222.559626 -45.284898) (xy 222.549212 -45.281088) (xy 222.523463 -45.27113)
			(xy 222.474908 -45.244857) (xy 222.430647 -45.211861) (xy 222.391605 -45.172828) (xy 222.358597 -45.128576)
			(xy 222.332312 -45.080029) (xy 222.32239 -45.054266) (xy 222.31858 -45.043852) (xy 221.860364 -44.585636)
			(xy 221.860364 -41.93921) (xy 221.83983 -41.925131) (xy 221.802247 -41.892478) (xy 221.76923 -41.855213)
			(xy 221.754954 -41.834816) (xy 221.74662 -41.823336) (xy 221.724876 -41.805132) (xy 221.698963 -41.793614)
			(xy 221.67088 -41.789674) (xy 221.642797 -41.793614) (xy 221.616884 -41.805132) (xy 221.59514 -41.823336)
			(xy 221.586806 -41.834816) (xy 221.571513 -41.856589) (xy 221.535857 -41.89608) (xy 221.495058 -41.93023)
			(xy 221.449907 -41.958377) (xy 221.401281 -41.979973) (xy 221.350126 -41.9946) (xy 221.297433 -42.001973)
			(xy 221.27083 -42.002456) (xy 221.243572 -42.001995) (xy 221.189611 -41.994241) (xy 221.137303 -41.978885)
			(xy 221.087713 -41.956242) (xy 221.04185 -41.926771) (xy 221.000649 -41.891072) (xy 220.964947 -41.849874)
			(xy 220.935473 -41.804013) (xy 220.912825 -41.754425) (xy 220.897466 -41.702118) (xy 220.889707 -41.648158)
			(xy 220.889707 -41.593642) (xy 220.897466 -41.539682) (xy 220.912825 -41.487375) (xy 220.935473 -41.437787)
			(xy 220.964947 -41.391926) (xy 221.000649 -41.350728) (xy 221.04185 -41.315029) (xy 221.087713 -41.285558)
			(xy 221.137303 -41.262915) (xy 221.189611 -41.247559) (xy 221.243572 -41.239805) (xy 221.27083 -41.23944)
			(xy 221.297432 -41.239903) (xy 221.35012 -41.247297) (xy 221.40127 -41.261937) (xy 221.449891 -41.28354)
			(xy 221.49504 -41.311687) (xy 221.535843 -41.345832) (xy 221.571507 -41.385313) (xy 221.586806 -41.40708)
			(xy 221.59514 -41.41856) (xy 221.616884 -41.436764) (xy 221.642797 -41.448282) (xy 221.67088 -41.452222)
			(xy 221.698963 -41.448282) (xy 221.724876 -41.436764) (xy 221.74662 -41.41856) (xy 221.754954 -41.40708)
			(xy 221.76923 -41.386683) (xy 221.802246 -41.349417) (xy 221.839831 -41.316766) (xy 221.860364 -41.302686)
			(xy 221.860364 -36.356798) (xy 219.748354 -34.244788) (xy 219.748354 -20.75053) (xy 214.207852 -15.209774)
			(xy 209.62747 -15.209774) (xy 209.408014 -15.42923) (xy 209.408014 -15.920974) (xy 211.993986 -15.920974)
			(xy 211.998057 -15.865352) (xy 212.010183 -15.810915) (xy 212.030106 -15.758824) (xy 212.057402 -15.710189)
			(xy 212.091488 -15.666046) (xy 212.131637 -15.627337) (xy 212.176995 -15.594886) (xy 212.226595 -15.569385)
			(xy 212.279379 -15.551378) (xy 212.334222 -15.541248) (xy 212.389956 -15.539211) (xy 212.445393 -15.545311)
			(xy 212.49935 -15.559417) (xy 212.550679 -15.581229) (xy 212.598285 -15.610283) (xy 212.641153 -15.645958)
			(xy 212.67837 -15.687495) (xy 212.709143 -15.734008) (xy 212.732815 -15.784505) (xy 212.748883 -15.837912)
			(xy 212.757003 -15.893088) (xy 212.757512 -15.920974) (xy 212.757003 -15.94886) (xy 212.748883 -16.004036)
			(xy 212.732815 -16.057443) (xy 212.709143 -16.10794) (xy 212.67837 -16.154453) (xy 212.641153 -16.19599)
			(xy 212.598285 -16.231665) (xy 212.550679 -16.260719) (xy 212.49935 -16.282531) (xy 212.445393 -16.296637)
			(xy 212.389956 -16.302737) (xy 212.334222 -16.3007) (xy 212.279379 -16.29057) (xy 212.226595 -16.272563)
			(xy 212.176995 -16.247062) (xy 212.131637 -16.214611) (xy 212.091488 -16.175902) (xy 212.057402 -16.131759)
			(xy 212.030106 -16.083124) (xy 212.010183 -16.031033) (xy 211.998057 -15.976596) (xy 211.993986 -15.920974)
			(xy 209.408014 -15.920974) (xy 209.408014 -17.274032) (xy 212.159848 -17.274032) (xy 212.163919 -17.21841)
			(xy 212.176045 -17.163973) (xy 212.195968 -17.111882) (xy 212.223264 -17.063247) (xy 212.25735 -17.019104)
			(xy 212.297499 -16.980395) (xy 212.342857 -16.947944) (xy 212.392457 -16.922443) (xy 212.445241 -16.904436)
			(xy 212.500084 -16.894306) (xy 212.555818 -16.892269) (xy 212.611255 -16.898369) (xy 212.665212 -16.912475)
			(xy 212.716541 -16.934287) (xy 212.764147 -16.963341) (xy 212.807015 -16.999016) (xy 212.844232 -17.040553)
			(xy 212.875005 -17.087066) (xy 212.898677 -17.137563) (xy 212.914745 -17.19097) (xy 212.922865 -17.246146)
			(xy 212.923374 -17.274032) (xy 212.922865 -17.301918) (xy 212.914745 -17.357094) (xy 212.898677 -17.410501)
			(xy 212.875005 -17.460998) (xy 212.844232 -17.507511) (xy 212.807015 -17.549048) (xy 212.764147 -17.584723)
			(xy 212.716541 -17.613777) (xy 212.665212 -17.635589) (xy 212.611255 -17.649695) (xy 212.555818 -17.655795)
			(xy 212.500084 -17.653758) (xy 212.445241 -17.643628) (xy 212.392457 -17.625621) (xy 212.342857 -17.60012)
			(xy 212.297499 -17.567669) (xy 212.25735 -17.52896) (xy 212.223264 -17.484817) (xy 212.195968 -17.436182)
			(xy 212.176045 -17.384091) (xy 212.163919 -17.329654) (xy 212.159848 -17.274032) (xy 209.408014 -17.274032)
			(xy 209.408014 -21.664449) (xy 212.417841 -21.664449) (xy 212.417841 -21.60994) (xy 212.4256 -21.555985)
			(xy 212.440958 -21.503684) (xy 212.463604 -21.454101) (xy 212.493075 -21.408246) (xy 212.528773 -21.367052)
			(xy 212.56997 -21.331357) (xy 212.615828 -21.301889) (xy 212.665412 -21.279248) (xy 212.717715 -21.263893)
			(xy 212.77167 -21.256139) (xy 212.826179 -21.256143) (xy 212.880134 -21.263904) (xy 212.932434 -21.279265)
			(xy 212.982016 -21.301913) (xy 213.02787 -21.331387) (xy 213.069062 -21.367087) (xy 213.104754 -21.408285)
			(xy 213.13422 -21.454145) (xy 213.156859 -21.50373) (xy 213.172211 -21.556034) (xy 213.179962 -21.609989)
			(xy 213.180422 -21.637244) (xy 213.178898 -21.671788) (xy 213.178083 -21.686808) (xy 213.184223 -21.716238)
			(xy 213.19867 -21.742604) (xy 213.22017 -21.763619) (xy 213.246859 -21.777459) (xy 213.276423 -21.782925)
			(xy 213.29142 -21.78177) (xy 213.302053 -21.78067) (xy 213.323402 -21.779528) (xy 213.334092 -21.779484)
			(xy 213.361346 -21.779947) (xy 213.415298 -21.787703) (xy 213.467598 -21.803058) (xy 213.51718 -21.825701)
			(xy 213.563035 -21.855169) (xy 213.604229 -21.890863) (xy 213.639925 -21.932056) (xy 213.669394 -21.977911)
			(xy 213.692038 -22.027492) (xy 213.707395 -22.079791) (xy 213.715152 -22.133744) (xy 213.715153 -22.184614)
			(xy 215.521792 -22.184614) (xy 215.525863 -22.128992) (xy 215.537989 -22.074555) (xy 215.557912 -22.022464)
			(xy 215.585208 -21.973829) (xy 215.619294 -21.929686) (xy 215.659443 -21.890977) (xy 215.704801 -21.858526)
			(xy 215.754401 -21.833025) (xy 215.807185 -21.815018) (xy 215.862028 -21.804888) (xy 215.917762 -21.802851)
			(xy 215.973199 -21.808951) (xy 216.027156 -21.823057) (xy 216.078485 -21.844869) (xy 216.126091 -21.873923)
			(xy 216.168959 -21.909598) (xy 216.206176 -21.951135) (xy 216.236949 -21.997648) (xy 216.260621 -22.048145)
			(xy 216.276689 -22.101552) (xy 216.284809 -22.156728) (xy 216.285318 -22.184614) (xy 216.284809 -22.2125)
			(xy 216.276689 -22.267676) (xy 216.260621 -22.321083) (xy 216.236949 -22.37158) (xy 216.206176 -22.418093)
			(xy 216.168959 -22.45963) (xy 216.126091 -22.495305) (xy 216.078485 -22.524359) (xy 216.027156 -22.546171)
			(xy 215.973199 -22.560277) (xy 215.917762 -22.566377) (xy 215.862028 -22.56434) (xy 215.807185 -22.55421)
			(xy 215.754401 -22.536203) (xy 215.704801 -22.510702) (xy 215.659443 -22.478251) (xy 215.619294 -22.439542)
			(xy 215.585208 -22.395399) (xy 215.557912 -22.346764) (xy 215.537989 -22.294673) (xy 215.525863 -22.240236)
			(xy 215.521792 -22.184614) (xy 213.715153 -22.184614) (xy 213.715153 -22.188251) (xy 213.707396 -22.242204)
			(xy 213.69204 -22.294503) (xy 213.669397 -22.344085) (xy 213.639928 -22.389939) (xy 213.604233 -22.431133)
			(xy 213.563039 -22.466828) (xy 213.517185 -22.496297) (xy 213.467603 -22.51894) (xy 213.415304 -22.534296)
			(xy 213.361351 -22.542053) (xy 213.306844 -22.542052) (xy 213.252891 -22.534295) (xy 213.200592 -22.518938)
			(xy 213.151011 -22.496294) (xy 213.105156 -22.466825) (xy 213.063963 -22.431129) (xy 213.028269 -22.389935)
			(xy 212.998801 -22.34408) (xy 212.976158 -22.294498) (xy 212.960803 -22.242198) (xy 212.953047 -22.188246)
			(xy 212.952584 -22.160992) (xy 212.954108 -22.126448) (xy 212.954882 -22.111427) (xy 212.948751 -22.082)
			(xy 212.934313 -22.055635) (xy 212.912821 -22.034621) (xy 212.886138 -22.020779) (xy 212.856581 -22.015312)
			(xy 212.841586 -22.016466) (xy 212.830953 -22.017566) (xy 212.809604 -22.018708) (xy 212.798914 -22.018752)
			(xy 212.771659 -22.01826) (xy 212.717704 -22.010504) (xy 212.665402 -21.995149) (xy 212.615818 -21.972506)
			(xy 212.569961 -21.943036) (xy 212.528765 -21.907341) (xy 212.493069 -21.866146) (xy 212.463598 -21.820289)
			(xy 212.440954 -21.770706) (xy 212.425598 -21.718404) (xy 212.417841 -21.664449) (xy 209.408014 -21.664449)
			(xy 209.408014 -23.172928) (xy 216.56116 -23.172928) (xy 216.565231 -23.117306) (xy 216.577357 -23.062869)
			(xy 216.59728 -23.010778) (xy 216.624576 -22.962143) (xy 216.658662 -22.918) (xy 216.698811 -22.879291)
			(xy 216.744169 -22.84684) (xy 216.793769 -22.821339) (xy 216.846553 -22.803332) (xy 216.901396 -22.793202)
			(xy 216.95713 -22.791165) (xy 217.012567 -22.797265) (xy 217.066524 -22.811371) (xy 217.117853 -22.833183)
			(xy 217.165459 -22.862237) (xy 217.208327 -22.897912) (xy 217.245544 -22.939449) (xy 217.276317 -22.985962)
			(xy 217.299989 -23.036459) (xy 217.316057 -23.089866) (xy 217.324177 -23.145042) (xy 217.324686 -23.172928)
			(xy 217.324177 -23.200814) (xy 217.316057 -23.25599) (xy 217.299989 -23.309397) (xy 217.276317 -23.359894)
			(xy 217.245544 -23.406407) (xy 217.208327 -23.447944) (xy 217.165459 -23.483619) (xy 217.117853 -23.512673)
			(xy 217.066524 -23.534485) (xy 217.012567 -23.548591) (xy 216.95713 -23.554691) (xy 216.901396 -23.552654)
			(xy 216.846553 -23.542524) (xy 216.793769 -23.524517) (xy 216.744169 -23.499016) (xy 216.698811 -23.466565)
			(xy 216.658662 -23.427856) (xy 216.624576 -23.383713) (xy 216.59728 -23.335078) (xy 216.577357 -23.282987)
			(xy 216.565231 -23.22855) (xy 216.56116 -23.172928) (xy 209.408014 -23.172928) (xy 209.408014 -23.678134)
			(xy 212.279482 -23.678134) (xy 212.283553 -23.622512) (xy 212.295679 -23.568075) (xy 212.315602 -23.515984)
			(xy 212.342898 -23.467349) (xy 212.376984 -23.423206) (xy 212.417133 -23.384497) (xy 212.462491 -23.352046)
			(xy 212.512091 -23.326545) (xy 212.564875 -23.308538) (xy 212.619718 -23.298408) (xy 212.675452 -23.296371)
			(xy 212.730889 -23.302471) (xy 212.784846 -23.316577) (xy 212.836175 -23.338389) (xy 212.883781 -23.367443)
			(xy 212.926649 -23.403118) (xy 212.963866 -23.444655) (xy 212.994639 -23.491168) (xy 213.018311 -23.541665)
			(xy 213.034379 -23.595072) (xy 213.042499 -23.650248) (xy 213.043008 -23.678134) (xy 213.042499 -23.70602)
			(xy 213.034379 -23.761196) (xy 213.018311 -23.814603) (xy 212.994639 -23.8651) (xy 212.963866 -23.911613)
			(xy 212.926649 -23.95315) (xy 212.883781 -23.988825) (xy 212.836175 -24.017879) (xy 212.784846 -24.039691)
			(xy 212.730889 -24.053797) (xy 212.675452 -24.059897) (xy 212.619718 -24.05786) (xy 212.564875 -24.04773)
			(xy 212.512091 -24.029723) (xy 212.462491 -24.004222) (xy 212.417133 -23.971771) (xy 212.376984 -23.933062)
			(xy 212.342898 -23.888919) (xy 212.315602 -23.840284) (xy 212.295679 -23.788193) (xy 212.283553 -23.733756)
			(xy 212.279482 -23.678134) (xy 209.408014 -23.678134) (xy 209.408014 -24.53513) (xy 207.47482 -26.468324)
			(xy 210.76742 -26.468324) (xy 210.771491 -26.412702) (xy 210.783617 -26.358265) (xy 210.80354 -26.306174)
			(xy 210.830836 -26.257539) (xy 210.864922 -26.213396) (xy 210.905071 -26.174687) (xy 210.950429 -26.142236)
			(xy 211.000029 -26.116735) (xy 211.052813 -26.098728) (xy 211.107656 -26.088598) (xy 211.16339 -26.086561)
			(xy 211.218827 -26.092661) (xy 211.272784 -26.106767) (xy 211.324113 -26.128579) (xy 211.371719 -26.157633)
			(xy 211.414587 -26.193308) (xy 211.451804 -26.234845) (xy 211.482577 -26.281358) (xy 211.506249 -26.331855)
			(xy 211.522317 -26.385262) (xy 211.530437 -26.440438) (xy 211.530946 -26.468324) (xy 211.530437 -26.49621)
			(xy 211.522317 -26.551386) (xy 211.506249 -26.604793) (xy 211.482577 -26.65529) (xy 211.451804 -26.701803)
			(xy 211.414587 -26.74334) (xy 211.371719 -26.779015) (xy 211.324113 -26.808069) (xy 211.272784 -26.829881)
			(xy 211.218827 -26.843987) (xy 211.16339 -26.850087) (xy 211.107656 -26.84805) (xy 211.052813 -26.83792)
			(xy 211.000029 -26.819913) (xy 210.950429 -26.794412) (xy 210.905071 -26.761961) (xy 210.864922 -26.723252)
			(xy 210.830836 -26.679109) (xy 210.80354 -26.630474) (xy 210.783617 -26.578383) (xy 210.771491 -26.523946)
			(xy 210.76742 -26.468324) (xy 207.47482 -26.468324) (xy 206.440786 -27.502358) (xy 212.780372 -27.502358)
			(xy 212.780372 -24.703278) (xy 213.11997 -24.36368) (xy 213.419436 -24.36368) (xy 213.434379 -24.363144)
			(xy 213.462975 -24.354456) (xy 213.487833 -24.337865) (xy 213.506827 -24.31479) (xy 213.51833 -24.287206)
			(xy 213.521358 -24.257473) (xy 213.515652 -24.228136) (xy 213.5017 -24.201706) (xy 213.491572 -24.190706)
			(xy 213.470958 -24.169129) (xy 213.436023 -24.120755) (xy 213.409049 -24.067529) (xy 213.390693 -24.010752)
			(xy 213.381403 -23.951809) (xy 213.380828 -23.921974) (xy 213.381314 -23.894723) (xy 213.38907 -23.840775)
			(xy 213.404425 -23.78848) (xy 213.427067 -23.738903) (xy 213.456533 -23.693053) (xy 213.492224 -23.651862)
			(xy 213.533415 -23.616171) (xy 213.579265 -23.586705) (xy 213.628842 -23.564063) (xy 213.681137 -23.548708)
			(xy 213.735085 -23.540952) (xy 213.789587 -23.540952) (xy 213.843535 -23.548708) (xy 213.89583 -23.564063)
			(xy 213.945407 -23.586705) (xy 213.991257 -23.616171) (xy 214.032448 -23.651862) (xy 214.068139 -23.693053)
			(xy 214.097605 -23.738903) (xy 214.120247 -23.78848) (xy 214.135602 -23.840775) (xy 214.143358 -23.894723)
			(xy 214.143844 -23.921974) (xy 214.143251 -23.951807) (xy 214.133953 -24.010746) (xy 214.115597 -24.067519)
			(xy 214.088628 -24.120744) (xy 214.053705 -24.169123) (xy 214.0331 -24.190706) (xy 214.022989 -24.201734)
			(xy 214.008993 -24.228155) (xy 214.003255 -24.2575) (xy 214.006268 -24.287247) (xy 214.017774 -24.314845)
			(xy 214.036784 -24.337923) (xy 214.061666 -24.354502) (xy 214.090286 -24.363157) (xy 214.105236 -24.36368)
			(xy 214.815674 -24.36368) (xy 214.830105 -24.363224) (xy 214.857811 -24.355131) (xy 214.882147 -24.339611)
			(xy 214.901171 -24.317905) (xy 214.913364 -24.291743) (xy 214.917753 -24.263216) (xy 214.913988 -24.234599)
			(xy 214.908638 -24.221186) (xy 214.898416 -24.196873) (xy 214.884036 -24.14613) (xy 214.876803 -24.093887)
			(xy 214.87638 -24.067516) (xy 214.876866 -24.040265) (xy 214.884622 -23.986317) (xy 214.899977 -23.934022)
			(xy 214.922619 -23.884445) (xy 214.952085 -23.838595) (xy 214.987776 -23.797404) (xy 215.028967 -23.761713)
			(xy 215.074817 -23.732247) (xy 215.124394 -23.709605) (xy 215.176689 -23.69425) (xy 215.230637 -23.686494)
			(xy 215.285139 -23.686494) (xy 215.339087 -23.69425) (xy 215.391382 -23.709605) (xy 215.440959 -23.732247)
			(xy 215.486809 -23.761713) (xy 215.528 -23.797404) (xy 215.563691 -23.838595) (xy 215.593157 -23.884445)
			(xy 215.615799 -23.934022) (xy 215.631154 -23.986317) (xy 215.63891 -24.040265) (xy 215.639396 -24.067516)
			(xy 215.638956 -24.093885) (xy 215.631697 -24.14612) (xy 215.617332 -24.196864) (xy 215.607138 -24.221186)
			(xy 215.601773 -24.234592) (xy 215.598004 -24.263207) (xy 215.602393 -24.291734) (xy 215.614589 -24.317893)
			(xy 215.633619 -24.339593) (xy 215.657961 -24.355101) (xy 215.685671 -24.363178) (xy 215.700102 -24.36368)
			(xy 216.84361 -24.36368) (xy 217.587068 -25.107138) (xy 217.587068 -27.052778) (xy 216.75471 -27.885136)
			(xy 214.569802 -27.885136) (xy 214.555981 -27.885585) (xy 214.529346 -27.892969) (xy 214.505665 -27.907225)
			(xy 214.486674 -27.927308) (xy 214.473763 -27.951747) (xy 214.467877 -27.978754) (xy 214.468202 -27.992578)
			(xy 214.468964 -28.015184) (xy 214.468478 -28.042435) (xy 214.460722 -28.096383) (xy 214.445367 -28.148678)
			(xy 214.422725 -28.198255) (xy 214.393259 -28.244105) (xy 214.357568 -28.285296) (xy 214.316377 -28.320987)
			(xy 214.270527 -28.350453) (xy 214.22095 -28.373095) (xy 214.168655 -28.38845) (xy 214.114707 -28.396206)
			(xy 214.060205 -28.396206) (xy 214.006257 -28.38845) (xy 213.953962 -28.373095) (xy 213.904385 -28.350453)
			(xy 213.858535 -28.320987) (xy 213.817344 -28.285296) (xy 213.781653 -28.244105) (xy 213.752187 -28.198255)
			(xy 213.729545 -28.148678) (xy 213.71419 -28.096383) (xy 213.706434 -28.042435) (xy 213.705948 -28.015184)
			(xy 213.70671 -27.992578) (xy 213.707038 -27.978747) (xy 213.701189 -27.95172) (xy 213.68829 -27.92726)
			(xy 213.669293 -27.907166) (xy 213.645594 -27.892917) (xy 213.618938 -27.885561) (xy 213.60511 -27.885136)
			(xy 213.16315 -27.885136) (xy 212.780372 -27.502358) (xy 206.440786 -27.502358) (xy 204.676502 -29.266642)
			(xy 207.672938 -29.266642) (xy 207.677009 -29.21102) (xy 207.689135 -29.156583) (xy 207.709058 -29.104492)
			(xy 207.736354 -29.055857) (xy 207.77044 -29.011714) (xy 207.810589 -28.973005) (xy 207.855947 -28.940554)
			(xy 207.905547 -28.915053) (xy 207.958331 -28.897046) (xy 208.013174 -28.886916) (xy 208.068908 -28.884879)
			(xy 208.124345 -28.890979) (xy 208.178302 -28.905085) (xy 208.229631 -28.926897) (xy 208.277237 -28.955951)
			(xy 208.320105 -28.991626) (xy 208.357322 -29.033163) (xy 208.388095 -29.079676) (xy 208.411767 -29.130173)
			(xy 208.427835 -29.18358) (xy 208.435955 -29.238756) (xy 208.436464 -29.266642) (xy 208.435955 -29.294528)
			(xy 208.427835 -29.349704) (xy 208.411767 -29.403111) (xy 208.388095 -29.453608) (xy 208.357322 -29.500121)
			(xy 208.320105 -29.541658) (xy 208.277237 -29.577333) (xy 208.229631 -29.606387) (xy 208.178302 -29.628199)
			(xy 208.124345 -29.642305) (xy 208.068908 -29.648405) (xy 208.013174 -29.646368) (xy 207.958331 -29.636238)
			(xy 207.905547 -29.618231) (xy 207.855947 -29.59273) (xy 207.810589 -29.560279) (xy 207.77044 -29.52157)
			(xy 207.736354 -29.477427) (xy 207.709058 -29.428792) (xy 207.689135 -29.376701) (xy 207.677009 -29.322264)
			(xy 207.672938 -29.266642) (xy 204.676502 -29.266642) (xy 204.278992 -29.664152) (xy 204.278992 -34.196528)
			(xy 208.181954 -34.196528) (xy 208.186025 -34.140906) (xy 208.198151 -34.086469) (xy 208.218074 -34.034378)
			(xy 208.24537 -33.985743) (xy 208.279456 -33.9416) (xy 208.319605 -33.902891) (xy 208.364963 -33.87044)
			(xy 208.414563 -33.844939) (xy 208.467347 -33.826932) (xy 208.52219 -33.816802) (xy 208.577924 -33.814765)
			(xy 208.633361 -33.820865) (xy 208.687318 -33.834971) (xy 208.738647 -33.856783) (xy 208.786253 -33.885837)
			(xy 208.829121 -33.921512) (xy 208.866338 -33.963049) (xy 208.897111 -34.009562) (xy 208.920783 -34.060059)
			(xy 208.936851 -34.113466) (xy 208.944971 -34.168642) (xy 208.94548 -34.196528) (xy 208.944971 -34.224414)
			(xy 208.936851 -34.27959) (xy 208.920783 -34.332997) (xy 208.897111 -34.383494) (xy 208.866338 -34.430007)
			(xy 208.829121 -34.471544) (xy 208.786253 -34.507219) (xy 208.738647 -34.536273) (xy 208.687318 -34.558085)
			(xy 208.633361 -34.572191) (xy 208.577924 -34.578291) (xy 208.52219 -34.576254) (xy 208.467347 -34.566124)
			(xy 208.414563 -34.548117) (xy 208.364963 -34.522616) (xy 208.319605 -34.490165) (xy 208.279456 -34.451456)
			(xy 208.24537 -34.407313) (xy 208.218074 -34.358678) (xy 208.198151 -34.306587) (xy 208.186025 -34.25215)
			(xy 208.181954 -34.196528) (xy 204.278992 -34.196528) (xy 204.278992 -35.522154) (xy 206.508856 -35.522154)
			(xy 206.512927 -35.466532) (xy 206.525053 -35.412095) (xy 206.544976 -35.360004) (xy 206.572272 -35.311369)
			(xy 206.606358 -35.267226) (xy 206.646507 -35.228517) (xy 206.691865 -35.196066) (xy 206.741465 -35.170565)
			(xy 206.794249 -35.152558) (xy 206.849092 -35.142428) (xy 206.904826 -35.140391) (xy 206.960263 -35.146491)
			(xy 207.01422 -35.160597) (xy 207.065549 -35.182409) (xy 207.113155 -35.211463) (xy 207.156023 -35.247138)
			(xy 207.19324 -35.288675) (xy 207.215121 -35.321748) (xy 209.345274 -35.321748) (xy 209.349345 -35.266126)
			(xy 209.361471 -35.211689) (xy 209.381394 -35.159598) (xy 209.40869 -35.110963) (xy 209.442776 -35.06682)
			(xy 209.482925 -35.028111) (xy 209.528283 -34.99566) (xy 209.577883 -34.970159) (xy 209.630667 -34.952152)
			(xy 209.68551 -34.942022) (xy 209.741244 -34.939985) (xy 209.796681 -34.946085) (xy 209.850638 -34.960191)
			(xy 209.901967 -34.982003) (xy 209.949573 -35.011057) (xy 209.992441 -35.046732) (xy 210.029658 -35.088269)
			(xy 210.060431 -35.134782) (xy 210.084103 -35.185279) (xy 210.100171 -35.238686) (xy 210.108291 -35.293862)
			(xy 210.1088 -35.321748) (xy 210.108291 -35.349634) (xy 210.100171 -35.40481) (xy 210.084103 -35.458217)
			(xy 210.060431 -35.508714) (xy 210.029658 -35.555227) (xy 209.992441 -35.596764) (xy 209.949573 -35.632439)
			(xy 209.901967 -35.661493) (xy 209.850638 -35.683305) (xy 209.796681 -35.697411) (xy 209.741244 -35.703511)
			(xy 209.68551 -35.701474) (xy 209.630667 -35.691344) (xy 209.577883 -35.673337) (xy 209.528283 -35.647836)
			(xy 209.482925 -35.615385) (xy 209.442776 -35.576676) (xy 209.40869 -35.532533) (xy 209.381394 -35.483898)
			(xy 209.361471 -35.431807) (xy 209.349345 -35.37737) (xy 209.345274 -35.321748) (xy 207.215121 -35.321748)
			(xy 207.224013 -35.335188) (xy 207.247685 -35.385685) (xy 207.263753 -35.439092) (xy 207.271873 -35.494268)
			(xy 207.272382 -35.522154) (xy 207.271873 -35.55004) (xy 207.263753 -35.605216) (xy 207.247685 -35.658623)
			(xy 207.224013 -35.70912) (xy 207.19324 -35.755633) (xy 207.156023 -35.79717) (xy 207.113155 -35.832845)
			(xy 207.065549 -35.861899) (xy 207.01422 -35.883711) (xy 206.960263 -35.897817) (xy 206.904826 -35.903917)
			(xy 206.849092 -35.90188) (xy 206.794249 -35.89175) (xy 206.741465 -35.873743) (xy 206.691865 -35.848242)
			(xy 206.646507 -35.815791) (xy 206.606358 -35.777082) (xy 206.572272 -35.732939) (xy 206.544976 -35.684304)
			(xy 206.525053 -35.632213) (xy 206.512927 -35.577776) (xy 206.508856 -35.522154) (xy 204.278992 -35.522154)
			(xy 204.278992 -36.52139) (xy 204.82941 -37.071808) (xy 206.518762 -37.071808) (xy 206.522833 -37.016186)
			(xy 206.534959 -36.961749) (xy 206.554882 -36.909658) (xy 206.582178 -36.861023) (xy 206.616264 -36.81688)
			(xy 206.656413 -36.778171) (xy 206.701771 -36.74572) (xy 206.751371 -36.720219) (xy 206.804155 -36.702212)
			(xy 206.858998 -36.692082) (xy 206.914732 -36.690045) (xy 206.970169 -36.696145) (xy 207.024126 -36.710251)
			(xy 207.075455 -36.732063) (xy 207.123061 -36.761117) (xy 207.165929 -36.796792) (xy 207.203146 -36.838329)
			(xy 207.230909 -36.880292) (xy 209.040474 -36.880292) (xy 209.044545 -36.82467) (xy 209.056671 -36.770233)
			(xy 209.076594 -36.718142) (xy 209.10389 -36.669507) (xy 209.137976 -36.625364) (xy 209.178125 -36.586655)
			(xy 209.223483 -36.554204) (xy 209.273083 -36.528703) (xy 209.325867 -36.510696) (xy 209.38071 -36.500566)
			(xy 209.436444 -36.498529) (xy 209.491881 -36.504629) (xy 209.545838 -36.518735) (xy 209.597167 -36.540547)
			(xy 209.644773 -36.569601) (xy 209.687641 -36.605276) (xy 209.724858 -36.646813) (xy 209.755631 -36.693326)
			(xy 209.779303 -36.743823) (xy 209.795371 -36.79723) (xy 209.803491 -36.852406) (xy 209.804 -36.880292)
			(xy 209.803491 -36.908178) (xy 209.795371 -36.963354) (xy 209.779303 -37.016761) (xy 209.755631 -37.067258)
			(xy 209.724858 -37.113771) (xy 209.687641 -37.155308) (xy 209.644773 -37.190983) (xy 209.597167 -37.220037)
			(xy 209.545838 -37.241849) (xy 209.491881 -37.255955) (xy 209.436444 -37.262055) (xy 209.38071 -37.260018)
			(xy 209.325867 -37.249888) (xy 209.273083 -37.231881) (xy 209.223483 -37.20638) (xy 209.178125 -37.173929)
			(xy 209.137976 -37.13522) (xy 209.10389 -37.091077) (xy 209.076594 -37.042442) (xy 209.056671 -36.990351)
			(xy 209.044545 -36.935914) (xy 209.040474 -36.880292) (xy 207.230909 -36.880292) (xy 207.233919 -36.884842)
			(xy 207.257591 -36.935339) (xy 207.273659 -36.988746) (xy 207.281779 -37.043922) (xy 207.282288 -37.071808)
			(xy 207.281779 -37.099694) (xy 207.273659 -37.15487) (xy 207.257591 -37.208277) (xy 207.233919 -37.258774)
			(xy 207.203146 -37.305287) (xy 207.165929 -37.346824) (xy 207.142348 -37.366448) (xy 208.126582 -37.366448)
			(xy 208.130653 -37.310826) (xy 208.142779 -37.256389) (xy 208.162702 -37.204298) (xy 208.189998 -37.155663)
			(xy 208.224084 -37.11152) (xy 208.264233 -37.072811) (xy 208.309591 -37.04036) (xy 208.359191 -37.014859)
			(xy 208.411975 -36.996852) (xy 208.466818 -36.986722) (xy 208.522552 -36.984685) (xy 208.577989 -36.990785)
			(xy 208.631946 -37.004891) (xy 208.683275 -37.026703) (xy 208.730881 -37.055757) (xy 208.773749 -37.091432)
			(xy 208.810966 -37.132969) (xy 208.841739 -37.179482) (xy 208.865411 -37.229979) (xy 208.881479 -37.283386)
			(xy 208.889599 -37.338562) (xy 208.890108 -37.366448) (xy 208.889599 -37.394334) (xy 208.881479 -37.44951)
			(xy 208.865411 -37.502917) (xy 208.841739 -37.553414) (xy 208.810966 -37.599927) (xy 208.773749 -37.641464)
			(xy 208.730881 -37.677139) (xy 208.683275 -37.706193) (xy 208.631946 -37.728005) (xy 208.577989 -37.742111)
			(xy 208.522552 -37.748211) (xy 208.466818 -37.746174) (xy 208.411975 -37.736044) (xy 208.359191 -37.718037)
			(xy 208.309591 -37.692536) (xy 208.264233 -37.660085) (xy 208.224084 -37.621376) (xy 208.189998 -37.577233)
			(xy 208.162702 -37.528598) (xy 208.142779 -37.476507) (xy 208.130653 -37.42207) (xy 208.126582 -37.366448)
			(xy 207.142348 -37.366448) (xy 207.123061 -37.382499) (xy 207.075455 -37.411553) (xy 207.024126 -37.433365)
			(xy 206.970169 -37.447471) (xy 206.914732 -37.453571) (xy 206.858998 -37.451534) (xy 206.804155 -37.441404)
			(xy 206.751371 -37.423397) (xy 206.701771 -37.397896) (xy 206.656413 -37.365445) (xy 206.616264 -37.326736)
			(xy 206.582178 -37.282593) (xy 206.554882 -37.233958) (xy 206.534959 -37.181867) (xy 206.522833 -37.12743)
			(xy 206.518762 -37.071808) (xy 204.82941 -37.071808) (xy 208.914492 -41.15689) (xy 210.669632 -41.15689)
			(xy 210.943952 -40.88257) (xy 210.943952 -38.584378) (xy 210.943543 -38.570957) (xy 210.93655 -38.545042)
			(xy 210.923053 -38.521839) (xy 210.903982 -38.50295) (xy 210.880652 -38.489677) (xy 210.85467 -38.482933)
			(xy 210.827829 -38.483185) (xy 210.801979 -38.490414) (xy 210.790282 -38.497002) (xy 210.768045 -38.509783)
			(xy 210.720873 -38.52992) (xy 210.671427 -38.543552) (xy 210.620601 -38.550435) (xy 210.594956 -38.55085)
			(xy 210.567704 -38.550361) (xy 210.513755 -38.542599) (xy 210.46146 -38.527238) (xy 210.411883 -38.504592)
			(xy 210.366033 -38.475121) (xy 210.324843 -38.439426) (xy 210.289152 -38.398232) (xy 210.259687 -38.352379)
			(xy 210.237047 -38.302799) (xy 210.221692 -38.250502) (xy 210.213936 -38.196552) (xy 210.213936 -38.142048)
			(xy 210.221692 -38.088098) (xy 210.237047 -38.035801) (xy 210.259687 -37.986221) (xy 210.289152 -37.940368)
			(xy 210.324843 -37.899174) (xy 210.366033 -37.863479) (xy 210.411883 -37.834008) (xy 210.46146 -37.811362)
			(xy 210.513755 -37.796001) (xy 210.567704 -37.788239) (xy 210.594956 -37.787834) (xy 210.620602 -37.788249)
			(xy 210.67143 -37.795123) (xy 210.720877 -37.808753) (xy 210.768049 -37.828893) (xy 210.790282 -37.841682)
			(xy 210.802023 -37.848216) (xy 210.827877 -37.855499) (xy 210.854737 -37.855789) (xy 210.880743 -37.849066)
			(xy 210.904097 -37.835796) (xy 210.923184 -37.816897) (xy 210.936683 -37.793675) (xy 210.943662 -37.767737)
			(xy 210.943952 -37.754306) (xy 210.943952 -29.613352) (xy 210.919406 -29.601582) (xy 210.873636 -29.572115)
			(xy 210.832522 -29.536439) (xy 210.796898 -29.49528) (xy 210.767488 -29.449473) (xy 210.744891 -29.39995)
			(xy 210.729565 -29.347717) (xy 210.721822 -29.293835) (xy 210.72182 -29.2394) (xy 210.729558 -29.185518)
			(xy 210.744879 -29.133283) (xy 210.767471 -29.083758) (xy 210.796877 -29.037948) (xy 210.832497 -28.996786)
			(xy 210.873608 -28.961106) (xy 210.919375 -28.931635) (xy 210.943952 -28.919932) (xy 210.943952 -28.814268)
			(xy 211.05368 -28.70454) (xy 212.644482 -28.70454) (xy 212.913493 -28.973551) (xy 214.924603 -28.973551)
			(xy 214.924603 -28.919049) (xy 214.93236 -28.865101) (xy 214.947716 -28.812807) (xy 214.970359 -28.76323)
			(xy 214.999827 -28.717381) (xy 215.035521 -28.676192) (xy 215.076713 -28.640503) (xy 215.122565 -28.61104)
			(xy 215.172144 -28.588402) (xy 215.22444 -28.573052) (xy 215.278389 -28.5653) (xy 215.30564 -28.56484)
			(xy 215.333067 -28.565329) (xy 215.387359 -28.57317) (xy 215.43997 -28.588699) (xy 215.489817 -28.611597)
			(xy 215.535874 -28.641392) (xy 215.556846 -28.659074) (xy 215.568881 -28.668853) (xy 215.597228 -28.681379)
			(xy 215.628029 -28.684813) (xy 215.658439 -28.678839) (xy 215.685651 -28.664008) (xy 215.6968 -28.653232)
			(xy 215.714865 -28.635204) (xy 215.754915 -28.603573) (xy 215.798823 -28.577562) (xy 215.845806 -28.557633)
			(xy 215.895025 -28.544143) (xy 215.945603 -28.537331) (xy 215.97112 -28.5369) (xy 215.99668 -28.537311)
			(xy 216.04734 -28.544157) (xy 216.096632 -28.557711) (xy 216.14367 -28.577728) (xy 216.187612 -28.603852)
			(xy 216.22767 -28.635612) (xy 216.245694 -28.65374) (xy 216.255857 -28.663629) (xy 216.280395 -28.67782)
			(xy 216.307888 -28.684726) (xy 216.33622 -28.683814) (xy 216.363212 -28.675156) (xy 216.386789 -28.659418)
			(xy 216.396316 -28.648914) (xy 216.414532 -28.628166) (xy 216.455924 -28.591631) (xy 216.50215 -28.561444)
			(xy 216.552245 -28.538233) (xy 216.605161 -28.522485) (xy 216.659795 -28.514528) (xy 216.6874 -28.51404)
			(xy 216.714655 -28.51443) (xy 216.768609 -28.522187) (xy 216.820911 -28.537544) (xy 216.870494 -28.560188)
			(xy 216.91635 -28.589658) (xy 216.957546 -28.625354) (xy 216.993242 -28.66655) (xy 217.022712 -28.712406)
			(xy 217.045356 -28.761989) (xy 217.060713 -28.814291) (xy 217.06847 -28.868245) (xy 217.06847 -28.922755)
			(xy 217.060713 -28.976709) (xy 217.045356 -29.029011) (xy 217.022712 -29.078594) (xy 216.993242 -29.12445)
			(xy 216.957546 -29.165646) (xy 216.91635 -29.201342) (xy 216.870494 -29.230812) (xy 216.820911 -29.253456)
			(xy 216.768609 -29.268813) (xy 216.714655 -29.27657) (xy 216.6874 -29.277056) (xy 216.66184 -29.276645)
			(xy 216.611179 -29.269801) (xy 216.561887 -29.256248) (xy 216.514848 -29.23623) (xy 216.470906 -29.210107)
			(xy 216.430849 -29.178345) (xy 216.412826 -29.160216) (xy 216.402642 -29.150353) (xy 216.378108 -29.136167)
			(xy 216.350622 -29.129262) (xy 216.322297 -29.130169) (xy 216.295309 -29.138818) (xy 216.271733 -29.154545)
			(xy 216.262204 -29.165042) (xy 216.24399 -29.185791) (xy 216.202596 -29.222324) (xy 216.156369 -29.25251)
			(xy 216.106274 -29.275719) (xy 216.053358 -29.291468) (xy 215.998725 -29.299427) (xy 215.97112 -29.299916)
			(xy 215.943692 -29.299438) (xy 215.889401 -29.291592) (xy 215.836791 -29.27606) (xy 215.786944 -29.25316)
			(xy 215.740886 -29.223364) (xy 215.719914 -29.205682) (xy 215.707906 -29.195868) (xy 215.679548 -29.183353)
			(xy 215.648741 -29.179929) (xy 215.618327 -29.18591) (xy 215.591111 -29.200746) (xy 215.57996 -29.211524)
			(xy 215.561906 -29.229563) (xy 215.521854 -29.261194) (xy 215.477944 -29.287206) (xy 215.430959 -29.307133)
			(xy 215.381738 -29.32062) (xy 215.331158 -29.327427) (xy 215.30564 -29.327856) (xy 215.278389 -29.3273)
			(xy 215.22444 -29.319548) (xy 215.172144 -29.304198) (xy 215.122565 -29.28156) (xy 215.076713 -29.252097)
			(xy 215.035521 -29.216408) (xy 214.999827 -29.175219) (xy 214.970359 -29.12937) (xy 214.947716 -29.079793)
			(xy 214.93236 -29.027499) (xy 214.924603 -28.973551) (xy 212.913493 -28.973551) (xy 212.973666 -29.033724)
			(xy 212.973666 -29.883862) (xy 214.015828 -30.926024) (xy 216.731342 -30.926024) (xy 218.459304 -32.653986)
			(xy 218.459304 -38.249352) (xy 218.204796 -38.50386) (xy 218.68079 -38.50386) (xy 218.684861 -38.448238)
			(xy 218.696987 -38.393801) (xy 218.71691 -38.34171) (xy 218.744206 -38.293075) (xy 218.778292 -38.248932)
			(xy 218.818441 -38.210223) (xy 218.863799 -38.177772) (xy 218.913399 -38.152271) (xy 218.966183 -38.134264)
			(xy 219.021026 -38.124134) (xy 219.07676 -38.122097) (xy 219.132197 -38.128197) (xy 219.186154 -38.142303)
			(xy 219.237483 -38.164115) (xy 219.285089 -38.193169) (xy 219.327957 -38.228844) (xy 219.365174 -38.270381)
			(xy 219.395947 -38.316894) (xy 219.419619 -38.367391) (xy 219.435687 -38.420798) (xy 219.443807 -38.475974)
			(xy 219.444316 -38.50386) (xy 219.443807 -38.531746) (xy 219.435687 -38.586922) (xy 219.419619 -38.640329)
			(xy 219.395947 -38.690826) (xy 219.365174 -38.737339) (xy 219.327957 -38.778876) (xy 219.285089 -38.814551)
			(xy 219.237483 -38.843605) (xy 219.186154 -38.865417) (xy 219.132197 -38.879523) (xy 219.07676 -38.885623)
			(xy 219.021026 -38.883586) (xy 218.966183 -38.873456) (xy 218.913399 -38.855449) (xy 218.863799 -38.829948)
			(xy 218.818441 -38.797497) (xy 218.778292 -38.758788) (xy 218.744206 -38.714645) (xy 218.71691 -38.66601)
			(xy 218.696987 -38.613919) (xy 218.684861 -38.559482) (xy 218.68079 -38.50386) (xy 218.204796 -38.50386)
			(xy 217.500708 -39.207948) (xy 219.993462 -39.207948) (xy 219.997533 -39.152326) (xy 220.009659 -39.097889)
			(xy 220.029582 -39.045798) (xy 220.056878 -38.997163) (xy 220.090964 -38.95302) (xy 220.131113 -38.914311)
			(xy 220.176471 -38.88186) (xy 220.226071 -38.856359) (xy 220.278855 -38.838352) (xy 220.333698 -38.828222)
			(xy 220.389432 -38.826185) (xy 220.444869 -38.832285) (xy 220.498826 -38.846391) (xy 220.550155 -38.868203)
			(xy 220.597761 -38.897257) (xy 220.640629 -38.932932) (xy 220.677846 -38.974469) (xy 220.708619 -39.020982)
			(xy 220.732291 -39.071479) (xy 220.748359 -39.124886) (xy 220.756479 -39.180062) (xy 220.756988 -39.207948)
			(xy 220.756479 -39.235834) (xy 220.748359 -39.29101) (xy 220.732291 -39.344417) (xy 220.708619 -39.394914)
			(xy 220.677846 -39.441427) (xy 220.640629 -39.482964) (xy 220.597761 -39.518639) (xy 220.550155 -39.547693)
			(xy 220.498826 -39.569505) (xy 220.444869 -39.583611) (xy 220.389432 -39.589711) (xy 220.333698 -39.587674)
			(xy 220.278855 -39.577544) (xy 220.226071 -39.559537) (xy 220.176471 -39.534036) (xy 220.131113 -39.501585)
			(xy 220.090964 -39.462876) (xy 220.056878 -39.418733) (xy 220.029582 -39.370098) (xy 220.009659 -39.318007)
			(xy 219.997533 -39.26357) (xy 219.993462 -39.207948) (xy 217.500708 -39.207948) (xy 216.512394 -40.196262)
			(xy 216.502814 -40.20646) (xy 216.48914 -40.23086) (xy 216.482602 -40.258056) (xy 216.483689 -40.286005)
			(xy 216.49232 -40.31261) (xy 216.507848 -40.335875) (xy 216.529106 -40.354052) (xy 216.541604 -40.360346)
			(xy 216.566022 -40.372176) (xy 216.611532 -40.401715) (xy 216.652399 -40.437404) (xy 216.687799 -40.478521)
			(xy 216.717017 -40.524239) (xy 216.739464 -40.573634) (xy 216.754688 -40.625711) (xy 216.762381 -40.67942)
			(xy 216.762838 -40.706548) (xy 216.762352 -40.733799) (xy 216.754596 -40.787747) (xy 216.739241 -40.840042)
			(xy 216.716599 -40.889619) (xy 216.687133 -40.935469) (xy 216.651442 -40.97666) (xy 216.610251 -41.012351)
			(xy 216.564401 -41.041817) (xy 216.514824 -41.064459) (xy 216.462529 -41.079814) (xy 216.408581 -41.08757)
			(xy 216.354079 -41.08757) (xy 216.300131 -41.079814) (xy 216.247836 -41.064459) (xy 216.198259 -41.041817)
			(xy 216.152409 -41.012351) (xy 216.111218 -40.97666) (xy 216.075527 -40.935469) (xy 216.046061 -40.889619)
			(xy 216.023419 -40.840042) (xy 216.008064 -40.787747) (xy 216.000308 -40.733799) (xy 215.999822 -40.706548)
			(xy 216.00029 -40.679768) (xy 216.007803 -40.626736) (xy 216.014808 -40.600884) (xy 216.018144 -40.58784)
			(xy 216.018592 -40.560928) (xy 216.01199 -40.534835) (xy 215.998798 -40.511375) (xy 215.979932 -40.492179)
			(xy 215.956704 -40.478581) (xy 215.930729 -40.471528) (xy 215.917272 -40.47109) (xy 215.250014 -40.47109)
			(xy 215.250014 -44.788328) (xy 218.943934 -44.788328) (xy 218.948005 -44.732706) (xy 218.960131 -44.678269)
			(xy 218.980054 -44.626178) (xy 219.00735 -44.577543) (xy 219.041436 -44.5334) (xy 219.081585 -44.494691)
			(xy 219.126943 -44.46224) (xy 219.176543 -44.436739) (xy 219.229327 -44.418732) (xy 219.28417 -44.408602)
			(xy 219.339904 -44.406565) (xy 219.395341 -44.412665) (xy 219.449298 -44.426771) (xy 219.500627 -44.448583)
			(xy 219.548233 -44.477637) (xy 219.591101 -44.513312) (xy 219.628318 -44.554849) (xy 219.659091 -44.601362)
			(xy 219.682763 -44.651859) (xy 219.698831 -44.705266) (xy 219.706951 -44.760442) (xy 219.70746 -44.788328)
			(xy 219.706951 -44.816214) (xy 219.698831 -44.87139) (xy 219.682763 -44.924797) (xy 219.659091 -44.975294)
			(xy 219.628318 -45.021807) (xy 219.591101 -45.063344) (xy 219.548233 -45.099019) (xy 219.500627 -45.128073)
			(xy 219.449298 -45.149885) (xy 219.395341 -45.163991) (xy 219.339904 -45.170091) (xy 219.28417 -45.168054)
			(xy 219.229327 -45.157924) (xy 219.176543 -45.139917) (xy 219.126943 -45.114416) (xy 219.081585 -45.081965)
			(xy 219.041436 -45.043256) (xy 219.00735 -44.999113) (xy 218.980054 -44.950478) (xy 218.960131 -44.898387)
			(xy 218.948005 -44.84395) (xy 218.943934 -44.788328) (xy 215.250014 -44.788328) (xy 215.250014 -45.984668)
			(xy 215.250431 -45.998093) (xy 215.257444 -46.024011) (xy 215.270967 -46.047207) (xy 215.290066 -46.066078)
			(xy 215.313422 -46.079322) (xy 215.339423 -46.086024) (xy 215.366271 -46.08572) (xy 215.3793 -46.082458)
			(xy 215.404802 -46.075692) (xy 215.45706 -46.068432) (xy 215.48344 -46.06798) (xy 215.51069 -46.068468)
			(xy 215.564634 -46.07623) (xy 215.616924 -46.091588) (xy 215.666497 -46.114231) (xy 215.712344 -46.143698)
			(xy 215.75353 -46.17939) (xy 215.789218 -46.220579) (xy 215.818682 -46.266427) (xy 215.841322 -46.316002)
			(xy 215.856676 -46.368294) (xy 215.864434 -46.422238) (xy 215.864948 -46.449488) (xy 215.864821 -46.46242)
			(xy 215.863044 -46.488223) (xy 215.861392 -46.50105) (xy 215.858225 -46.524926) (xy 222.71304 -46.524926)
			(xy 222.717111 -46.469304) (xy 222.729237 -46.414867) (xy 222.74916 -46.362776) (xy 222.776456 -46.314141)
			(xy 222.810542 -46.269998) (xy 222.850691 -46.231289) (xy 222.896049 -46.198838) (xy 222.945649 -46.173337)
			(xy 222.998433 -46.15533) (xy 223.053276 -46.1452) (xy 223.10901 -46.143163) (xy 223.164447 -46.149263)
			(xy 223.218404 -46.163369) (xy 223.269733 -46.185181) (xy 223.317339 -46.214235) (xy 223.360207 -46.24991)
			(xy 223.397424 -46.291447) (xy 223.428197 -46.33796) (xy 223.451869 -46.388457) (xy 223.467937 -46.441864)
			(xy 223.476057 -46.49704) (xy 223.476566 -46.524926) (xy 223.476057 -46.552812) (xy 223.467937 -46.607988)
			(xy 223.451869 -46.661395) (xy 223.428197 -46.711892) (xy 223.397424 -46.758405) (xy 223.360207 -46.799942)
			(xy 223.317339 -46.835617) (xy 223.269733 -46.864671) (xy 223.218404 -46.886483) (xy 223.164447 -46.900589)
			(xy 223.10901 -46.906689) (xy 223.053276 -46.904652) (xy 222.998433 -46.894522) (xy 222.945649 -46.876515)
			(xy 222.896049 -46.851014) (xy 222.850691 -46.818563) (xy 222.810542 -46.779854) (xy 222.776456 -46.735711)
			(xy 222.74916 -46.687076) (xy 222.729237 -46.634985) (xy 222.717111 -46.580548) (xy 222.71304 -46.524926)
			(xy 215.858225 -46.524926) (xy 215.85809 -46.525942) (xy 216.139268 -46.80712) (xy 216.458038 -46.80712)
			(xy 216.66962 -47.018702) (xy 221.910908 -47.018702) (xy 221.914979 -46.96308) (xy 221.927105 -46.908643)
			(xy 221.947028 -46.856552) (xy 221.974324 -46.807917) (xy 222.00841 -46.763774) (xy 222.048559 -46.725065)
			(xy 222.093917 -46.692614) (xy 222.143517 -46.667113) (xy 222.196301 -46.649106) (xy 222.251144 -46.638976)
			(xy 222.306878 -46.636939) (xy 222.362315 -46.643039) (xy 222.416272 -46.657145) (xy 222.467601 -46.678957)
			(xy 222.515207 -46.708011) (xy 222.558075 -46.743686) (xy 222.595292 -46.785223) (xy 222.626065 -46.831736)
			(xy 222.649737 -46.882233) (xy 222.665805 -46.93564) (xy 222.673925 -46.990816) (xy 222.674434 -47.018702)
			(xy 222.673925 -47.046588) (xy 222.665805 -47.101764) (xy 222.649737 -47.155171) (xy 222.626065 -47.205668)
			(xy 222.595292 -47.252181) (xy 222.558075 -47.293718) (xy 222.515207 -47.329393) (xy 222.467601 -47.358447)
			(xy 222.416272 -47.380259) (xy 222.362315 -47.394365) (xy 222.306878 -47.400465) (xy 222.251144 -47.398428)
			(xy 222.196301 -47.388298) (xy 222.143517 -47.370291) (xy 222.093917 -47.34479) (xy 222.048559 -47.312339)
			(xy 222.00841 -47.27363) (xy 221.974324 -47.229487) (xy 221.947028 -47.180852) (xy 221.927105 -47.128761)
			(xy 221.914979 -47.074324) (xy 221.910908 -47.018702) (xy 216.66962 -47.018702) (xy 217.262964 -47.612046)
			(xy 222.685862 -47.612046) (xy 222.689933 -47.556424) (xy 222.702059 -47.501987) (xy 222.721982 -47.449896)
			(xy 222.749278 -47.401261) (xy 222.783364 -47.357118) (xy 222.823513 -47.318409) (xy 222.868871 -47.285958)
			(xy 222.918471 -47.260457) (xy 222.971255 -47.24245) (xy 223.026098 -47.23232) (xy 223.081832 -47.230283)
			(xy 223.137269 -47.236383) (xy 223.191226 -47.250489) (xy 223.242555 -47.272301) (xy 223.290161 -47.301355)
			(xy 223.333029 -47.33703) (xy 223.370246 -47.378567) (xy 223.401019 -47.42508) (xy 223.424691 -47.475577)
			(xy 223.440759 -47.528984) (xy 223.448879 -47.58416) (xy 223.449388 -47.612046) (xy 223.448879 -47.639932)
			(xy 223.440759 -47.695108) (xy 223.424691 -47.748515) (xy 223.401019 -47.799012) (xy 223.370246 -47.845525)
			(xy 223.333029 -47.887062) (xy 223.290161 -47.922737) (xy 223.242555 -47.951791) (xy 223.191226 -47.973603)
			(xy 223.165433 -47.980346) (xy 230.407462 -47.980346) (xy 230.411533 -47.924724) (xy 230.423659 -47.870287)
			(xy 230.443582 -47.818196) (xy 230.470878 -47.769561) (xy 230.504964 -47.725418) (xy 230.545113 -47.686709)
			(xy 230.590471 -47.654258) (xy 230.640071 -47.628757) (xy 230.692855 -47.61075) (xy 230.747698 -47.60062)
			(xy 230.803432 -47.598583) (xy 230.858869 -47.604683) (xy 230.912826 -47.618789) (xy 230.964155 -47.640601)
			(xy 231.011761 -47.669655) (xy 231.054629 -47.70533) (xy 231.091846 -47.746867) (xy 231.122619 -47.79338)
			(xy 231.146291 -47.843877) (xy 231.162359 -47.897284) (xy 231.170479 -47.95246) (xy 231.170988 -47.980346)
			(xy 231.170479 -48.008232) (xy 231.162359 -48.063408) (xy 231.150133 -48.104044) (xy 235.109764 -48.104044)
			(xy 235.113835 -48.048422) (xy 235.125961 -47.993985) (xy 235.145884 -47.941894) (xy 235.17318 -47.893259)
			(xy 235.207266 -47.849116) (xy 235.247415 -47.810407) (xy 235.292773 -47.777956) (xy 235.342373 -47.752455)
			(xy 235.395157 -47.734448) (xy 235.45 -47.724318) (xy 235.505734 -47.722281) (xy 235.561171 -47.728381)
			(xy 235.615128 -47.742487) (xy 235.666457 -47.764299) (xy 235.714063 -47.793353) (xy 235.756931 -47.829028)
			(xy 235.794148 -47.870565) (xy 235.824921 -47.917078) (xy 235.848593 -47.967575) (xy 235.864661 -48.020982)
			(xy 235.872781 -48.076158) (xy 235.87329 -48.104044) (xy 235.872781 -48.13193) (xy 235.864661 -48.187106)
			(xy 235.848593 -48.240513) (xy 235.824921 -48.29101) (xy 235.794148 -48.337523) (xy 235.756931 -48.37906)
			(xy 235.714063 -48.414735) (xy 235.666457 -48.443789) (xy 235.615128 -48.465601) (xy 235.561171 -48.479707)
			(xy 235.505734 -48.485807) (xy 235.45 -48.48377) (xy 235.395157 -48.47364) (xy 235.342373 -48.455633)
			(xy 235.292773 -48.430132) (xy 235.247415 -48.397681) (xy 235.207266 -48.358972) (xy 235.17318 -48.314829)
			(xy 235.145884 -48.266194) (xy 235.125961 -48.214103) (xy 235.113835 -48.159666) (xy 235.109764 -48.104044)
			(xy 231.150133 -48.104044) (xy 231.146291 -48.116815) (xy 231.122619 -48.167312) (xy 231.091846 -48.213825)
			(xy 231.054629 -48.255362) (xy 231.011761 -48.291037) (xy 230.964155 -48.320091) (xy 230.912826 -48.341903)
			(xy 230.858869 -48.356009) (xy 230.803432 -48.362109) (xy 230.747698 -48.360072) (xy 230.692855 -48.349942)
			(xy 230.640071 -48.331935) (xy 230.590471 -48.306434) (xy 230.545113 -48.273983) (xy 230.504964 -48.235274)
			(xy 230.470878 -48.191131) (xy 230.443582 -48.142496) (xy 230.423659 -48.090405) (xy 230.411533 -48.035968)
			(xy 230.407462 -47.980346) (xy 223.165433 -47.980346) (xy 223.137269 -47.987709) (xy 223.081832 -47.993809)
			(xy 223.026098 -47.991772) (xy 222.971255 -47.981642) (xy 222.918471 -47.963635) (xy 222.868871 -47.938134)
			(xy 222.823513 -47.905683) (xy 222.783364 -47.866974) (xy 222.749278 -47.822831) (xy 222.721982 -47.774196)
			(xy 222.702059 -47.722105) (xy 222.689933 -47.667668) (xy 222.685862 -47.612046) (xy 217.262964 -47.612046)
			(xy 218.432888 -48.78197) (xy 222.685862 -48.78197) (xy 222.689933 -48.726348) (xy 222.702059 -48.671911)
			(xy 222.721982 -48.61982) (xy 222.749278 -48.571185) (xy 222.783364 -48.527042) (xy 222.823513 -48.488333)
			(xy 222.868871 -48.455882) (xy 222.918471 -48.430381) (xy 222.971255 -48.412374) (xy 223.026098 -48.402244)
			(xy 223.081832 -48.400207) (xy 223.137269 -48.406307) (xy 223.191226 -48.420413) (xy 223.242555 -48.442225)
			(xy 223.290161 -48.471279) (xy 223.333029 -48.506954) (xy 223.370246 -48.548491) (xy 223.401019 -48.595004)
			(xy 223.412936 -48.620426) (xy 237.303562 -48.620426) (xy 237.307633 -48.564804) (xy 237.319759 -48.510367)
			(xy 237.339682 -48.458276) (xy 237.366978 -48.409641) (xy 237.401064 -48.365498) (xy 237.441213 -48.326789)
			(xy 237.486571 -48.294338) (xy 237.536171 -48.268837) (xy 237.588955 -48.25083) (xy 237.643798 -48.2407)
			(xy 237.699532 -48.238663) (xy 237.754969 -48.244763) (xy 237.808926 -48.258869) (xy 237.860255 -48.280681)
			(xy 237.907861 -48.309735) (xy 237.950729 -48.34541) (xy 237.987946 -48.386947) (xy 238.018719 -48.43346)
			(xy 238.042391 -48.483957) (xy 238.058459 -48.537364) (xy 238.066579 -48.59254) (xy 238.067088 -48.620426)
			(xy 238.193072 -48.620426) (xy 238.193555 -48.593956) (xy 238.200891 -48.541527) (xy 238.215399 -48.490613)
			(xy 238.236799 -48.442191) (xy 238.264682 -48.397189) (xy 238.298514 -48.356469) (xy 238.337645 -48.320813)
			(xy 238.381326 -48.290903) (xy 238.42872 -48.267312) (xy 238.453676 -48.258476) (xy 238.466917 -48.253583)
			(xy 238.490258 -48.237729) (xy 238.508354 -48.21608) (xy 238.519817 -48.190298) (xy 238.523769 -48.162361)
			(xy 238.519906 -48.134411) (xy 238.514636 -48.121316) (xy 238.504519 -48.097108) (xy 238.490265 -48.046613)
			(xy 238.48307 -47.994642) (xy 238.482632 -47.968408) (xy 238.483118 -47.941157) (xy 238.490874 -47.887209)
			(xy 238.506229 -47.834914) (xy 238.528871 -47.785337) (xy 238.558337 -47.739487) (xy 238.594028 -47.698296)
			(xy 238.635219 -47.662605) (xy 238.681069 -47.633139) (xy 238.730646 -47.610497) (xy 238.782941 -47.595142)
			(xy 238.836889 -47.587386) (xy 238.891391 -47.587386) (xy 238.945339 -47.595142) (xy 238.997634 -47.610497)
			(xy 239.047211 -47.633139) (xy 239.093061 -47.662605) (xy 239.134252 -47.698296) (xy 239.169943 -47.739487)
			(xy 239.199409 -47.785337) (xy 239.222051 -47.834914) (xy 239.237406 -47.887209) (xy 239.245162 -47.941157)
			(xy 239.245648 -47.968408) (xy 239.245249 -47.994881) (xy 239.237906 -48.047317) (xy 239.223391 -48.098235)
			(xy 239.201982 -48.146661) (xy 239.174088 -48.191664) (xy 239.140246 -48.232384) (xy 239.101103 -48.268038)
			(xy 239.05741 -48.297943) (xy 239.010005 -48.321526) (xy 238.985044 -48.330358) (xy 238.971773 -48.335174)
			(xy 238.948435 -48.35105) (xy 238.930345 -48.372716) (xy 238.918889 -48.398512) (xy 238.914943 -48.42646)
			(xy 238.918812 -48.454419) (xy 238.924084 -48.467518) (xy 238.934213 -48.491722) (xy 238.948462 -48.542218)
			(xy 238.955653 -48.594192) (xy 238.956088 -48.620426) (xy 238.95431 -48.658526) (xy 238.95331 -48.672457)
			(xy 238.958194 -48.699949) (xy 238.970339 -48.725092) (xy 238.988838 -48.746008) (xy 239.012309 -48.761134)
			(xy 239.038998 -48.769341) (xy 239.066913 -48.770016) (xy 239.080548 -48.766984) (xy 239.103772 -48.761413)
			(xy 239.151156 -48.75543) (xy 239.175036 -48.755046) (xy 239.203904 -48.755581) (xy 239.260982 -48.764265)
			(xy 239.316098 -48.781458) (xy 239.367991 -48.806767) (xy 239.415472 -48.839613) (xy 239.457456 -48.879245)
			(xy 239.492983 -48.924756) (xy 239.521239 -48.975104) (xy 239.521606 -48.976026) (xy 240.803682 -48.976026)
			(xy 240.807753 -48.920404) (xy 240.819879 -48.865967) (xy 240.839802 -48.813876) (xy 240.867098 -48.765241)
			(xy 240.901184 -48.721098) (xy 240.941333 -48.682389) (xy 240.986691 -48.649938) (xy 241.036291 -48.624437)
			(xy 241.089075 -48.60643) (xy 241.143918 -48.5963) (xy 241.199652 -48.594263) (xy 241.255089 -48.600363)
			(xy 241.309046 -48.614469) (xy 241.360375 -48.636281) (xy 241.407981 -48.665335) (xy 241.450849 -48.70101)
			(xy 241.488066 -48.742547) (xy 241.518839 -48.78906) (xy 241.542511 -48.839557) (xy 241.558579 -48.892964)
			(xy 241.566699 -48.94814) (xy 241.567208 -48.976026) (xy 241.566699 -49.003912) (xy 241.558579 -49.059088)
			(xy 241.542511 -49.112495) (xy 241.518839 -49.162992) (xy 241.488066 -49.209505) (xy 241.450849 -49.251042)
			(xy 241.407981 -49.286717) (xy 241.360375 -49.315771) (xy 241.309046 -49.337583) (xy 241.255089 -49.351689)
			(xy 241.199652 -49.357789) (xy 241.143918 -49.355752) (xy 241.089075 -49.345622) (xy 241.036291 -49.327615)
			(xy 240.986691 -49.302114) (xy 240.941333 -49.269663) (xy 240.901184 -49.230954) (xy 240.867098 -49.186811)
			(xy 240.839802 -49.138176) (xy 240.819879 -49.086085) (xy 240.807753 -49.031648) (xy 240.803682 -48.976026)
			(xy 239.521606 -48.976026) (xy 239.531906 -49.001934) (xy 239.537309 -49.01503) (xy 239.554144 -49.0378)
			(xy 239.576593 -49.05506) (xy 239.602924 -49.065478) (xy 239.631105 -49.068251) (xy 239.658962 -49.063165)
			(xy 239.67186 -49.057306) (xy 239.698091 -49.04506) (xy 239.753336 -49.027768) (xy 239.810556 -49.018999)
			(xy 239.8395 -49.018444) (xy 239.866762 -49.018956) (xy 239.920731 -49.026718) (xy 239.973046 -49.042085)
			(xy 240.022639 -49.064742) (xy 240.068502 -49.094229) (xy 240.1097 -49.129945) (xy 240.145394 -49.171163)
			(xy 240.174857 -49.217042) (xy 240.197487 -49.266648) (xy 240.212826 -49.31897) (xy 240.220559 -49.372944)
			(xy 240.221008 -49.400206) (xy 240.221008 -50.263806) (xy 240.220482 -50.291062) (xy 240.212727 -50.345019)
			(xy 240.197377 -50.397325) (xy 240.174742 -50.446915) (xy 240.145283 -50.492782) (xy 240.1096 -50.533991)
			(xy 240.068417 -50.569706) (xy 240.022574 -50.5992) (xy 239.973001 -50.621874) (xy 239.920707 -50.637265)
			(xy 239.866756 -50.645061) (xy 239.8395 -50.645568) (xy 239.811869 -50.645054) (xy 239.757192 -50.637018)
			(xy 239.70424 -50.621202) (xy 239.678972 -50.610008) (xy 239.665652 -50.604379) (xy 239.637063 -50.600105)
			(xy 239.60842 -50.604008) (xy 239.582017 -50.615774) (xy 239.559964 -50.634463) (xy 239.544027 -50.65858)
			(xy 239.539272 -50.672238) (xy 239.530865 -50.697809) (xy 239.507825 -50.746457) (xy 239.478174 -50.791381)
			(xy 239.442501 -50.83169) (xy 239.401514 -50.866583) (xy 239.356027 -50.895365) (xy 239.306946 -50.917465)
			(xy 239.255244 -50.932444) (xy 239.20195 -50.940004) (xy 239.175036 -50.940462) (xy 239.147778 -50.940093)
			(xy 239.093817 -50.93234) (xy 239.041508 -50.916985) (xy 238.991918 -50.894342) (xy 238.946054 -50.864871)
			(xy 238.904852 -50.829173) (xy 238.86915 -50.787975) (xy 238.839676 -50.742114) (xy 238.817028 -50.692526)
			(xy 238.801668 -50.640218) (xy 238.793909 -50.586258) (xy 238.793909 -50.531742) (xy 238.801668 -50.477782)
			(xy 238.817028 -50.425474) (xy 238.839676 -50.375886) (xy 238.86915 -50.330025) (xy 238.904852 -50.288827)
			(xy 238.946054 -50.253129) (xy 238.991918 -50.223658) (xy 239.041508 -50.201015) (xy 239.093817 -50.18566)
			(xy 239.147778 -50.177907) (xy 239.175036 -50.177446) (xy 239.199478 -50.177855) (xy 239.247957 -50.184146)
			(xy 239.295237 -50.196569) (xy 239.318038 -50.205386) (xy 239.331387 -50.210361) (xy 239.35971 -50.213355)
			(xy 239.387761 -50.208426) (xy 239.413366 -50.195956) (xy 239.434542 -50.17691) (xy 239.449648 -50.152765)
			(xy 239.457512 -50.125392) (xy 239.457992 -50.111152) (xy 239.457992 -49.584356) (xy 239.457544 -49.570108)
			(xy 239.449714 -49.542712) (xy 239.434619 -49.518545) (xy 239.413434 -49.49949) (xy 239.38781 -49.487029)
			(xy 239.35974 -49.482133) (xy 239.33141 -49.485184) (xy 239.318038 -49.490122) (xy 239.295242 -49.498953)
			(xy 239.247962 -49.511387) (xy 239.19948 -49.517671) (xy 239.175036 -49.518062) (xy 239.147782 -49.517611)
			(xy 239.093828 -49.509858) (xy 239.041527 -49.494504) (xy 238.991944 -49.471862) (xy 238.946089 -49.442394)
			(xy 238.904894 -49.406699) (xy 238.8692 -49.365503) (xy 238.839733 -49.319647) (xy 238.817092 -49.270063)
			(xy 238.80174 -49.217762) (xy 238.793988 -49.163808) (xy 238.793528 -49.136554) (xy 238.795306 -49.098454)
			(xy 238.796305 -49.084524) (xy 238.791417 -49.057034) (xy 238.77927 -49.031894) (xy 238.760772 -49.01098)
			(xy 238.737303 -48.995854) (xy 238.710616 -48.987645) (xy 238.682703 -48.986967) (xy 238.669068 -48.989996)
			(xy 238.645844 -48.995565) (xy 238.59846 -49.001549) (xy 238.57458 -49.001934) (xy 238.547329 -49.001441)
			(xy 238.493383 -48.993682) (xy 238.44109 -48.978326) (xy 238.391515 -48.955684) (xy 238.345666 -48.926218)
			(xy 238.304476 -48.890528) (xy 238.268785 -48.849339) (xy 238.239318 -48.803491) (xy 238.216676 -48.753915)
			(xy 238.201319 -48.701623) (xy 238.19356 -48.647677) (xy 238.193072 -48.620426) (xy 238.067088 -48.620426)
			(xy 238.066579 -48.648312) (xy 238.058459 -48.703488) (xy 238.042391 -48.756895) (xy 238.018719 -48.807392)
			(xy 237.987946 -48.853905) (xy 237.950729 -48.895442) (xy 237.907861 -48.931117) (xy 237.860255 -48.960171)
			(xy 237.808926 -48.981983) (xy 237.754969 -48.996089) (xy 237.699532 -49.002189) (xy 237.643798 -49.000152)
			(xy 237.588955 -48.990022) (xy 237.536171 -48.972015) (xy 237.486571 -48.946514) (xy 237.441213 -48.914063)
			(xy 237.401064 -48.875354) (xy 237.366978 -48.831211) (xy 237.339682 -48.782576) (xy 237.319759 -48.730485)
			(xy 237.307633 -48.676048) (xy 237.303562 -48.620426) (xy 223.412936 -48.620426) (xy 223.424691 -48.645501)
			(xy 223.440759 -48.698908) (xy 223.448879 -48.754084) (xy 223.449388 -48.78197) (xy 223.448879 -48.809856)
			(xy 223.440759 -48.865032) (xy 223.424691 -48.918439) (xy 223.401019 -48.968936) (xy 223.370246 -49.015449)
			(xy 223.333029 -49.056986) (xy 223.290161 -49.092661) (xy 223.242555 -49.121715) (xy 223.191226 -49.143527)
			(xy 223.137269 -49.157633) (xy 223.081832 -49.163733) (xy 223.026098 -49.161696) (xy 222.971255 -49.151566)
			(xy 222.918471 -49.133559) (xy 222.868871 -49.108058) (xy 222.823513 -49.075607) (xy 222.783364 -49.036898)
			(xy 222.749278 -48.992755) (xy 222.721982 -48.94412) (xy 222.702059 -48.892029) (xy 222.689933 -48.837592)
			(xy 222.685862 -48.78197) (xy 218.432888 -48.78197) (xy 219.622878 -49.97196) (xy 221.078552 -49.97196)
			(xy 221.079088 -49.944079) (xy 221.087211 -49.888912) (xy 221.103278 -49.835515) (xy 221.126948 -49.785025)
			(xy 221.157715 -49.73852) (xy 221.194924 -49.696988) (xy 221.237783 -49.661315) (xy 221.285378 -49.632262)
			(xy 221.336695 -49.610446) (xy 221.36354 -49.602898) (xy 221.377001 -49.598878) (xy 221.401177 -49.584592)
			(xy 221.420551 -49.564264) (xy 221.43366 -49.53943) (xy 221.439514 -49.511965) (xy 221.43767 -49.483944)
			(xy 221.43339 -49.470564) (xy 221.42308 -49.439569) (xy 221.411963 -49.375206) (xy 221.411292 -49.342548)
			(xy 221.411778 -49.315297) (xy 221.419534 -49.261349) (xy 221.434889 -49.209054) (xy 221.457531 -49.159477)
			(xy 221.486997 -49.113627) (xy 221.522688 -49.072436) (xy 221.563879 -49.036745) (xy 221.609729 -49.007279)
			(xy 221.659306 -48.984637) (xy 221.711601 -48.969282) (xy 221.765549 -48.961526) (xy 221.820051 -48.961526)
			(xy 221.873999 -48.969282) (xy 221.926294 -48.984637) (xy 221.975871 -49.007279) (xy 222.021721 -49.036745)
			(xy 222.062912 -49.072436) (xy 222.098603 -49.113627) (xy 222.128069 -49.159477) (xy 222.130592 -49.165002)
			(xy 234.272326 -49.165002) (xy 234.276397 -49.10938) (xy 234.288523 -49.054943) (xy 234.308446 -49.002852)
			(xy 234.335742 -48.954217) (xy 234.369828 -48.910074) (xy 234.409977 -48.871365) (xy 234.455335 -48.838914)
			(xy 234.504935 -48.813413) (xy 234.557719 -48.795406) (xy 234.612562 -48.785276) (xy 234.668296 -48.783239)
			(xy 234.723733 -48.789339) (xy 234.77769 -48.803445) (xy 234.829019 -48.825257) (xy 234.876625 -48.854311)
			(xy 234.919493 -48.889986) (xy 234.95671 -48.931523) (xy 234.987483 -48.978036) (xy 235.011155 -49.028533)
			(xy 235.027223 -49.08194) (xy 235.035343 -49.137116) (xy 235.035852 -49.165002) (xy 235.035343 -49.192888)
			(xy 235.027223 -49.248064) (xy 235.011155 -49.301471) (xy 234.987483 -49.351968) (xy 234.95671 -49.398481)
			(xy 234.919493 -49.440018) (xy 234.876625 -49.475693) (xy 234.829019 -49.504747) (xy 234.77769 -49.526559)
			(xy 234.723733 -49.540665) (xy 234.668296 -49.546765) (xy 234.612562 -49.544728) (xy 234.557719 -49.534598)
			(xy 234.504935 -49.516591) (xy 234.455335 -49.49109) (xy 234.409977 -49.458639) (xy 234.369828 -49.41993)
			(xy 234.335742 -49.375787) (xy 234.308446 -49.327152) (xy 234.288523 -49.275061) (xy 234.276397 -49.220624)
			(xy 234.272326 -49.165002) (xy 222.130592 -49.165002) (xy 222.150711 -49.209054) (xy 222.166066 -49.261349)
			(xy 222.173822 -49.315297) (xy 222.174308 -49.342548) (xy 222.173809 -49.370431) (xy 222.165684 -49.425601)
			(xy 222.149613 -49.479) (xy 222.12594 -49.529491) (xy 222.095168 -49.575998) (xy 222.057954 -49.61753)
			(xy 222.01509 -49.653201) (xy 221.96749 -49.682252) (xy 221.916167 -49.704064) (xy 221.88932 -49.71161)
			(xy 221.87585 -49.715599) (xy 221.851675 -49.729895) (xy 221.832303 -49.75023) (xy 221.819197 -49.775069)
			(xy 221.813345 -49.802538) (xy 221.81519 -49.830562) (xy 221.81947 -49.843944) (xy 221.829784 -49.874938)
			(xy 221.840898 -49.939302) (xy 221.841109 -49.949608) (xy 222.622616 -49.949608) (xy 222.626687 -49.893986)
			(xy 222.638813 -49.839549) (xy 222.658736 -49.787458) (xy 222.686032 -49.738823) (xy 222.720118 -49.69468)
			(xy 222.760267 -49.655971) (xy 222.805625 -49.62352) (xy 222.855225 -49.598019) (xy 222.908009 -49.580012)
			(xy 222.962852 -49.569882) (xy 223.018586 -49.567845) (xy 223.074023 -49.573945) (xy 223.12798 -49.588051)
			(xy 223.179309 -49.609863) (xy 223.226915 -49.638917) (xy 223.269783 -49.674592) (xy 223.307 -49.716129)
			(xy 223.337773 -49.762642) (xy 223.338855 -49.76495) (xy 230.602026 -49.76495) (xy 230.606097 -49.709328)
			(xy 230.618223 -49.654891) (xy 230.638146 -49.6028) (xy 230.665442 -49.554165) (xy 230.699528 -49.510022)
			(xy 230.739677 -49.471313) (xy 230.785035 -49.438862) (xy 230.834635 -49.413361) (xy 230.887419 -49.395354)
			(xy 230.942262 -49.385224) (xy 230.997996 -49.383187) (xy 231.053433 -49.389287) (xy 231.10739 -49.403393)
			(xy 231.158719 -49.425205) (xy 231.206325 -49.454259) (xy 231.249193 -49.489934) (xy 231.28641 -49.531471)
			(xy 231.317183 -49.577984) (xy 231.340855 -49.628481) (xy 231.356923 -49.681888) (xy 231.365043 -49.737064)
			(xy 231.365552 -49.76495) (xy 237.233966 -49.76495) (xy 237.238037 -49.709328) (xy 237.250163 -49.654891)
			(xy 237.270086 -49.6028) (xy 237.297382 -49.554165) (xy 237.331468 -49.510022) (xy 237.371617 -49.471313)
			(xy 237.416975 -49.438862) (xy 237.466575 -49.413361) (xy 237.519359 -49.395354) (xy 237.574202 -49.385224)
			(xy 237.629936 -49.383187) (xy 237.685373 -49.389287) (xy 237.73933 -49.403393) (xy 237.790659 -49.425205)
			(xy 237.838265 -49.454259) (xy 237.881133 -49.489934) (xy 237.91835 -49.531471) (xy 237.949123 -49.577984)
			(xy 237.972795 -49.628481) (xy 237.988863 -49.681888) (xy 237.996983 -49.737064) (xy 237.997492 -49.76495)
			(xy 237.996983 -49.792836) (xy 237.988863 -49.848012) (xy 237.972795 -49.901419) (xy 237.949123 -49.951916)
			(xy 237.91835 -49.998429) (xy 237.881133 -50.039966) (xy 237.838265 -50.075641) (xy 237.790659 -50.104695)
			(xy 237.73933 -50.126507) (xy 237.685373 -50.140613) (xy 237.629936 -50.146713) (xy 237.574202 -50.144676)
			(xy 237.519359 -50.134546) (xy 237.466575 -50.116539) (xy 237.416975 -50.091038) (xy 237.371617 -50.058587)
			(xy 237.331468 -50.019878) (xy 237.297382 -49.975735) (xy 237.270086 -49.9271) (xy 237.250163 -49.875009)
			(xy 237.238037 -49.820572) (xy 237.233966 -49.76495) (xy 231.365552 -49.76495) (xy 231.365043 -49.792836)
			(xy 231.356923 -49.848012) (xy 231.340855 -49.901419) (xy 231.317183 -49.951916) (xy 231.28641 -49.998429)
			(xy 231.249193 -50.039966) (xy 231.206325 -50.075641) (xy 231.158719 -50.104695) (xy 231.10739 -50.126507)
			(xy 231.053433 -50.140613) (xy 230.997996 -50.146713) (xy 230.942262 -50.144676) (xy 230.887419 -50.134546)
			(xy 230.834635 -50.116539) (xy 230.785035 -50.091038) (xy 230.739677 -50.058587) (xy 230.699528 -50.019878)
			(xy 230.665442 -49.975735) (xy 230.638146 -49.9271) (xy 230.618223 -49.875009) (xy 230.606097 -49.820572)
			(xy 230.602026 -49.76495) (xy 223.338855 -49.76495) (xy 223.361445 -49.813139) (xy 223.377513 -49.866546)
			(xy 223.385633 -49.921722) (xy 223.386142 -49.949608) (xy 223.385633 -49.977494) (xy 223.377513 -50.03267)
			(xy 223.361445 -50.086077) (xy 223.337773 -50.136574) (xy 223.307 -50.183087) (xy 223.269783 -50.224624)
			(xy 223.226915 -50.260299) (xy 223.179309 -50.289353) (xy 223.12798 -50.311165) (xy 223.074023 -50.325271)
			(xy 223.018586 -50.331371) (xy 222.962852 -50.329334) (xy 222.908009 -50.319204) (xy 222.855225 -50.301197)
			(xy 222.805625 -50.275696) (xy 222.760267 -50.243245) (xy 222.720118 -50.204536) (xy 222.686032 -50.160393)
			(xy 222.658736 -50.111758) (xy 222.638813 -50.059667) (xy 222.626687 -50.00523) (xy 222.622616 -49.949608)
			(xy 221.841109 -49.949608) (xy 221.841568 -49.97196) (xy 221.840968 -50.001721) (xy 221.831718 -50.060521)
			(xy 221.813451 -50.117172) (xy 221.786611 -50.170299) (xy 221.751848 -50.218616) (xy 221.731332 -50.240184)
			(xy 221.721981 -50.25033) (xy 221.708547 -50.274416) (xy 221.702042 -50.301216) (xy 221.702941 -50.32878)
			(xy 221.711177 -50.355101) (xy 221.72615 -50.37826) (xy 221.736158 -50.387758) (xy 221.75596 -50.405923)
			(xy 221.790752 -50.446874) (xy 221.81945 -50.492304) (xy 221.841487 -50.541312) (xy 221.856425 -50.592929)
			(xy 221.863969 -50.646132) (xy 221.864428 -50.673) (xy 221.863942 -50.700251) (xy 221.856186 -50.754199)
			(xy 221.840831 -50.806494) (xy 221.818189 -50.856071) (xy 221.788723 -50.901921) (xy 221.753032 -50.943112)
			(xy 221.711841 -50.978803) (xy 221.665991 -51.008269) (xy 221.656512 -51.012598) (xy 222.559878 -51.012598)
			(xy 222.563949 -50.956976) (xy 222.576075 -50.902539) (xy 222.595998 -50.850448) (xy 222.623294 -50.801813)
			(xy 222.65738 -50.75767) (xy 222.697529 -50.718961) (xy 222.742887 -50.68651) (xy 222.792487 -50.661009)
			(xy 222.845271 -50.643002) (xy 222.900114 -50.632872) (xy 222.955848 -50.630835) (xy 223.011285 -50.636935)
			(xy 223.065242 -50.651041) (xy 223.116571 -50.672853) (xy 223.164177 -50.701907) (xy 223.207045 -50.737582)
			(xy 223.244262 -50.779119) (xy 223.275035 -50.825632) (xy 223.298707 -50.876129) (xy 223.314775 -50.929536)
			(xy 223.322895 -50.984712) (xy 223.323404 -51.012598) (xy 223.322895 -51.040484) (xy 223.314775 -51.09566)
			(xy 223.298707 -51.149067) (xy 223.275035 -51.199564) (xy 223.244262 -51.246077) (xy 223.207045 -51.287614)
			(xy 223.164177 -51.323289) (xy 223.116571 -51.352343) (xy 223.065242 -51.374155) (xy 223.011285 -51.388261)
			(xy 222.955848 -51.394361) (xy 222.900114 -51.392324) (xy 222.845271 -51.382194) (xy 222.792487 -51.364187)
			(xy 222.742887 -51.338686) (xy 222.697529 -51.306235) (xy 222.65738 -51.267526) (xy 222.623294 -51.223383)
			(xy 222.595998 -51.174748) (xy 222.576075 -51.122657) (xy 222.563949 -51.06822) (xy 222.559878 -51.012598)
			(xy 221.656512 -51.012598) (xy 221.616414 -51.030911) (xy 221.564119 -51.046266) (xy 221.510171 -51.054022)
			(xy 221.455669 -51.054022) (xy 221.401721 -51.046266) (xy 221.349426 -51.030911) (xy 221.299849 -51.008269)
			(xy 221.253999 -50.978803) (xy 221.212808 -50.943112) (xy 221.177117 -50.901921) (xy 221.147651 -50.856071)
			(xy 221.125009 -50.806494) (xy 221.109654 -50.754199) (xy 221.101898 -50.700251) (xy 221.101412 -50.673)
			(xy 221.101964 -50.643236) (xy 221.111222 -50.584434) (xy 221.129499 -50.527782) (xy 221.156351 -50.474654)
			(xy 221.191126 -50.426341) (xy 221.211648 -50.404776) (xy 221.221031 -50.39466) (xy 221.234451 -50.370563)
			(xy 221.240945 -50.343757) (xy 221.240039 -50.31619) (xy 221.231801 -50.289867) (xy 221.216828 -50.266703)
			(xy 221.206822 -50.257202) (xy 221.187045 -50.239011) (xy 221.152252 -50.198065) (xy 221.123551 -50.152641)
			(xy 221.10151 -50.103637) (xy 221.086566 -50.052025) (xy 221.079016 -49.998826) (xy 221.078552 -49.97196)
			(xy 219.622878 -49.97196) (xy 222.202756 -52.551838) (xy 225.405696 -52.551838)
		)
		(stroke
			(width 0)
			(type solid)
		)
		(fill yes)
		(layer "In2.Cu")
		(net "P3V3_AUX")
	)
	(gr_poly
		(pts
			(xy 294.1574 -327.1012) (xy 294.1574 -326.4916) (xy 296.3926 -324.2564) (xy 300.1772 -324.2564) (xy 301.1932 -323.2404)
			(xy 301.1932 -319.3542) (xy 297.170856 -319.3542) (xy 297.157007 -319.354671) (xy 297.13033 -319.362122)
			(xy 297.106634 -319.376463) (xy 297.08766 -319.396643) (xy 297.074803 -319.421176) (xy 297.069008 -319.448262)
			(xy 297.0707 -319.475908) (xy 297.079755 -319.502084) (xy 297.08729 -319.513712) (xy 297.10227 -319.536189)
			(xy 297.125997 -319.584711) (xy 297.142126 -319.636259) (xy 297.150287 -319.689652) (xy 297.15079 -319.716658)
			(xy 297.150292 -319.743307) (xy 297.142349 -319.796011) (xy 297.126639 -319.846941) (xy 297.103513 -319.894962)
			(xy 297.073489 -319.938999) (xy 297.037237 -319.97807) (xy 296.995566 -320.011301) (xy 296.949408 -320.03795)
			(xy 296.899794 -320.057422) (xy 296.847832 -320.069282) (xy 296.794682 -320.073266) (xy 296.741532 -320.069282)
			(xy 296.68957 -320.057422) (xy 296.639956 -320.03795) (xy 296.593798 -320.011301) (xy 296.552127 -319.97807)
			(xy 296.515875 -319.938999) (xy 296.485851 -319.894962) (xy 296.462725 -319.846941) (xy 296.447015 -319.796011)
			(xy 296.439072 -319.743307) (xy 296.438574 -319.716658) (xy 296.43907 -319.68965) (xy 296.447221 -319.636253)
			(xy 296.463344 -319.5847) (xy 296.487071 -319.536174) (xy 296.502074 -319.513712) (xy 296.509587 -319.502064)
			(xy 296.518677 -319.47589) (xy 296.520393 -319.448237) (xy 296.514609 -319.42114) (xy 296.501751 -319.396598)
			(xy 296.482767 -319.376417) (xy 296.459055 -319.362086) (xy 296.432362 -319.354659) (xy 296.418508 -319.3542)
			(xy 295.25849 -319.3542) (xy 295.243998 -319.354712) (xy 295.216183 -319.362858) (xy 295.191776 -319.378489)
			(xy 295.172744 -319.400348) (xy 295.160619 -319.426674) (xy 295.156379 -319.455345) (xy 295.160364 -319.484054)
			(xy 295.172254 -319.510486) (xy 295.181274 -319.52184) (xy 295.197302 -319.541284) (xy 295.224296 -319.583833)
			(xy 295.245026 -319.629761) (xy 295.259079 -319.678152) (xy 295.266173 -319.728039) (xy 295.266618 -319.753234)
			(xy 295.26612 -319.779883) (xy 295.258177 -319.832587) (xy 295.242467 -319.883517) (xy 295.219341 -319.931538)
			(xy 295.189317 -319.975575) (xy 295.153065 -320.014646) (xy 295.111394 -320.047877) (xy 295.065236 -320.074526)
			(xy 295.015622 -320.093998) (xy 294.96366 -320.105858) (xy 294.91051 -320.109842) (xy 294.85736 -320.105858)
			(xy 294.805398 -320.093998) (xy 294.755784 -320.074526) (xy 294.709626 -320.047877) (xy 294.667955 -320.014646)
			(xy 294.631703 -319.975575) (xy 294.601679 -319.931538) (xy 294.578553 -319.883517) (xy 294.562843 -319.832587)
			(xy 294.5549 -319.779883) (xy 294.554402 -319.753234) (xy 294.554835 -319.728038) (xy 294.561929 -319.678148)
			(xy 294.575979 -319.629754) (xy 294.596706 -319.583822) (xy 294.623696 -319.541267) (xy 294.639746 -319.52184)
			(xy 294.648776 -319.510492) (xy 294.660665 -319.484055) (xy 294.664649 -319.455343) (xy 294.660408 -319.426667)
			(xy 294.648283 -319.400338) (xy 294.629249 -319.378475) (xy 294.604841 -319.362838) (xy 294.577023 -319.354687)
			(xy 294.56253 -319.3542) (xy 292.089586 -319.3542) (xy 292.07968 -319.3923) (xy 292.072681 -319.417404)
			(xy 292.05235 -319.465391) (xy 292.025243 -319.509902) (xy 291.991939 -319.549987) (xy 291.953148 -319.584791)
			(xy 291.9097 -319.61357) (xy 291.862521 -319.63571) (xy 291.812619 -319.650738) (xy 291.76106 -319.658333)
			(xy 291.708944 -319.658333) (xy 291.657385 -319.650738) (xy 291.607483 -319.63571) (xy 291.560304 -319.61357)
			(xy 291.516856 -319.584791) (xy 291.478065 -319.549987) (xy 291.444761 -319.509902) (xy 291.417654 -319.465391)
			(xy 291.397323 -319.417404) (xy 291.390324 -319.3923) (xy 291.380418 -319.3542) (xy 289.627056 -319.3542)
			(xy 289.613207 -319.354671) (xy 289.58653 -319.362122) (xy 289.562834 -319.376463) (xy 289.54386 -319.396643)
			(xy 289.531003 -319.421176) (xy 289.525208 -319.448262) (xy 289.5269 -319.475908) (xy 289.535955 -319.502084)
			(xy 289.54349 -319.513712) (xy 289.55847 -319.536189) (xy 289.582197 -319.584711) (xy 289.598326 -319.636259)
			(xy 289.606487 -319.689652) (xy 289.60699 -319.716658) (xy 289.606492 -319.743307) (xy 289.598549 -319.796011)
			(xy 289.582839 -319.846941) (xy 289.559713 -319.894962) (xy 289.529689 -319.938999) (xy 289.493437 -319.97807)
			(xy 289.451766 -320.011301) (xy 289.405608 -320.03795) (xy 289.355994 -320.057422) (xy 289.304032 -320.069282)
			(xy 289.250882 -320.073266) (xy 289.197732 -320.069282) (xy 289.14577 -320.057422) (xy 289.096156 -320.03795)
			(xy 289.049998 -320.011301) (xy 289.008327 -319.97807) (xy 288.972075 -319.938999) (xy 288.942051 -319.894962)
			(xy 288.918925 -319.846941) (xy 288.903215 -319.796011) (xy 288.895272 -319.743307) (xy 288.894774 -319.716658)
			(xy 288.895237 -319.690746) (xy 288.902744 -319.639469) (xy 288.917609 -319.589823) (xy 288.939516 -319.542857)
			(xy 288.968002 -319.499565) (xy 289.002466 -319.460861) (xy 289.022028 -319.443862) (xy 289.040062 -319.428622)
			(xy 289.040062 -319.3542) (xy 288.875978 -319.3542) (xy 288.8615 -319.367154) (xy 288.835242 -319.389942)
			(xy 288.778173 -319.429657) (xy 288.716709 -319.462158) (xy 288.651757 -319.486966) (xy 288.584277 -319.503715)
			(xy 288.515264 -319.512158) (xy 288.4805 -319.512696) (xy 288.44415 -319.512111) (xy 288.372039 -319.502861)
			(xy 288.301682 -319.484548) (xy 288.234212 -319.457467) (xy 288.170718 -319.422055) (xy 288.112223 -319.378883)
			(xy 288.08553 -319.3542) (xy 287.743138 -319.3542) (xy 287.737296 -319.398396) (xy 287.733276 -319.425101)
			(xy 287.718224 -319.476963) (xy 287.695515 -319.525957) (xy 287.665667 -319.570961) (xy 287.629367 -319.610943)
			(xy 287.587447 -319.644985) (xy 287.540867 -319.672308) (xy 287.490695 -319.692284) (xy 287.438083 -319.704456)
			(xy 287.384236 -319.708545) (xy 287.330389 -319.704456) (xy 287.277777 -319.692284) (xy 287.227605 -319.672308)
			(xy 287.181025 -319.644985) (xy 287.139105 -319.610943) (xy 287.102805 -319.570961) (xy 287.072957 -319.525957)
			(xy 287.050248 -319.476963) (xy 287.035196 -319.425101) (xy 287.031176 -319.398396) (xy 287.025334 -319.3542)
			(xy 280.149554 -319.3542) (xy 280.139648 -319.3923) (xy 280.132718 -319.417493) (xy 280.112491 -319.465667)
			(xy 280.085441 -319.510368) (xy 280.052149 -319.550637) (xy 280.01333 -319.585608) (xy 279.969817 -319.614531)
			(xy 279.922545 -319.636785) (xy 279.872528 -319.651892) (xy 279.82084 -319.659527) (xy 279.768592 -319.659527)
			(xy 279.716904 -319.651892) (xy 279.666887 -319.636785) (xy 279.619615 -319.614531) (xy 279.576102 -319.585608)
			(xy 279.537283 -319.550637) (xy 279.503991 -319.510368) (xy 279.476941 -319.465667) (xy 279.456714 -319.417493)
			(xy 279.449784 -319.3923) (xy 279.439878 -319.3542) (xy 274.539456 -319.3542) (xy 274.525607 -319.354671)
			(xy 274.49893 -319.362122) (xy 274.475234 -319.376463) (xy 274.45626 -319.396643) (xy 274.443403 -319.421176)
			(xy 274.437608 -319.448262) (xy 274.4393 -319.475908) (xy 274.448355 -319.502084) (xy 274.45589 -319.513712)
			(xy 274.47087 -319.536189) (xy 274.494597 -319.584711) (xy 274.510726 -319.636259) (xy 274.518887 -319.689652)
			(xy 274.51939 -319.716658) (xy 274.518873 -319.744645) (xy 274.510122 -319.799931) (xy 274.49283 -319.853166)
			(xy 274.467421 -319.903041) (xy 274.434523 -319.948327) (xy 274.394945 -319.987907) (xy 274.349662 -320.020809)
			(xy 274.299789 -320.04622) (xy 274.246554 -320.063516) (xy 274.191269 -320.072271) (xy 274.163282 -320.072766)
			(xy 274.134506 -320.072212) (xy 274.077703 -320.062953) (xy 274.023129 -320.044679) (xy 273.972205 -320.017865)
			(xy 273.926256 -319.98321) (xy 273.90598 -319.962784) (xy 273.896348 -319.95331) (xy 273.873222 -319.939359)
			(xy 273.847248 -319.931958) (xy 273.820242 -319.931626) (xy 273.794093 -319.938385) (xy 273.770632 -319.951764)
			(xy 273.751498 -319.970825) (xy 273.744436 -319.982342) (xy 273.730679 -320.005167) (xy 273.697449 -320.046827)
			(xy 273.658382 -320.083072) (xy 273.614352 -320.113092) (xy 273.56634 -320.136216) (xy 273.515419 -320.15193)
			(xy 273.462725 -320.159881) (xy 273.43608 -320.160396) (xy 273.408098 -320.159846) (xy 273.352824 -320.151088)
			(xy 273.299601 -320.133792) (xy 273.249738 -320.108382) (xy 273.204464 -320.075485) (xy 273.164894 -320.035911)
			(xy 273.132001 -319.990635) (xy 273.106596 -319.94077) (xy 273.089305 -319.887545) (xy 273.080552 -319.83227)
			(xy 273.079972 -319.804288) (xy 273.080424 -319.778603) (xy 273.08781 -319.727766) (xy 273.102429 -319.67852)
			(xy 273.123975 -319.631886) (xy 273.152001 -319.588835) (xy 273.185925 -319.55026) (xy 273.205194 -319.53327)
			(xy 273.215406 -319.523998) (xy 273.23088 -319.501178) (xy 273.239686 -319.475051) (xy 273.241181 -319.44752)
			(xy 273.235256 -319.420593) (xy 273.222343 -319.396232) (xy 273.203383 -319.376214) (xy 273.17976 -319.361997)
			(xy 273.153194 -319.354619) (xy 273.139408 -319.3542) (xy 272.644362 -319.3542) (xy 272.637758 -319.39738)
			(xy 272.633349 -319.423682) (xy 272.617692 -319.47466) (xy 272.594604 -319.522732) (xy 272.564604 -319.566822)
			(xy 272.528362 -319.605943) (xy 272.486689 -319.639219) (xy 272.440518 -319.665907) (xy 272.390882 -319.685407)
			(xy 272.338893 -319.697285) (xy 272.285714 -319.701274) (xy 272.232535 -319.697285) (xy 272.180546 -319.685407)
			(xy 272.13091 -319.665907) (xy 272.084739 -319.639219) (xy 272.043066 -319.605943) (xy 272.006824 -319.566822)
			(xy 271.976824 -319.522732) (xy 271.953736 -319.47466) (xy 271.938079 -319.423682) (xy 271.93367 -319.39738)
			(xy 271.927066 -319.3542) (xy 266.995656 -319.3542) (xy 266.981807 -319.354671) (xy 266.95513 -319.362122)
			(xy 266.931434 -319.376463) (xy 266.91246 -319.396643) (xy 266.899603 -319.421176) (xy 266.893808 -319.448262)
			(xy 266.8955 -319.475908) (xy 266.904555 -319.502084) (xy 266.91209 -319.513712) (xy 266.92707 -319.536189)
			(xy 266.950797 -319.584711) (xy 266.966926 -319.636259) (xy 266.975087 -319.689652) (xy 266.97559 -319.716658)
			(xy 266.975073 -319.744645) (xy 266.966322 -319.799931) (xy 266.94903 -319.853166) (xy 266.923621 -319.903041)
			(xy 266.890723 -319.948327) (xy 266.851145 -319.987907) (xy 266.805862 -320.020809) (xy 266.755989 -320.04622)
			(xy 266.702754 -320.063516) (xy 266.647469 -320.072271) (xy 266.619482 -320.072766) (xy 266.589587 -320.072154)
			(xy 266.530636 -320.062167) (xy 266.474181 -320.042477) (xy 266.421806 -320.013636) (xy 266.397994 -319.99555)
			(xy 266.386313 -319.986922) (xy 266.359428 -319.975976) (xy 266.330551 -319.973025) (xy 266.302009 -319.978307)
			(xy 266.2761 -319.991396) (xy 266.254914 -320.011238) (xy 266.247118 -320.02349) (xy 266.233281 -320.045973)
			(xy 266.200017 -320.086965) (xy 266.161067 -320.1226) (xy 266.117286 -320.152096) (xy 266.06963 -320.174808)
			(xy 266.019145 -320.190238) (xy 265.966935 -320.19805) (xy 265.94054 -320.198496) (xy 265.913888 -320.198026)
			(xy 265.861178 -320.190086) (xy 265.81024 -320.174379) (xy 265.762213 -320.151255) (xy 265.718169 -320.121231)
			(xy 265.679092 -320.084977) (xy 265.645855 -320.043304) (xy 265.619201 -319.997142) (xy 265.599726 -319.947523)
			(xy 265.587864 -319.895555) (xy 265.58388 -319.8424) (xy 265.587864 -319.789245) (xy 265.599726 -319.737277)
			(xy 265.619201 -319.687658) (xy 265.645855 -319.641496) (xy 265.679092 -319.599823) (xy 265.718169 -319.563569)
			(xy 265.762213 -319.533545) (xy 265.81024 -319.510421) (xy 265.861178 -319.494714) (xy 265.913888 -319.486774)
			(xy 265.94054 -319.48628) (xy 265.970438 -319.486886) (xy 266.029395 -319.49686) (xy 266.08586 -319.516538)
			(xy 266.138246 -319.545367) (xy 266.162028 -319.563496) (xy 266.173707 -319.572125) (xy 266.200587 -319.58307)
			(xy 266.229461 -319.586018) (xy 266.257999 -319.580731) (xy 266.2839 -319.567635) (xy 266.305075 -319.547786)
			(xy 266.312904 -319.535556) (xy 266.326874 -319.513712) (xy 266.334387 -319.502064) (xy 266.343477 -319.47589)
			(xy 266.345193 -319.448237) (xy 266.339409 -319.42114) (xy 266.326551 -319.396598) (xy 266.307567 -319.376417)
			(xy 266.283855 -319.362086) (xy 266.257162 -319.354659) (xy 266.243308 -319.3542) (xy 265.108436 -319.3542)
			(xy 265.108182 -319.404492) (xy 265.107504 -319.431017) (xy 265.099258 -319.483431) (xy 265.083326 -319.534041)
			(xy 265.060062 -319.581727) (xy 265.02998 -319.625433) (xy 264.993746 -319.664193) (xy 264.952162 -319.697147)
			(xy 264.906149 -319.723567) (xy 264.856726 -319.742868) (xy 264.804985 -319.754621) (xy 264.752074 -319.758569)
			(xy 264.699163 -319.754621) (xy 264.647422 -319.742868) (xy 264.597999 -319.723567) (xy 264.551986 -319.697147)
			(xy 264.510402 -319.664193) (xy 264.474168 -319.625433) (xy 264.444086 -319.581727) (xy 264.420822 -319.534041)
			(xy 264.40489 -319.483431) (xy 264.396644 -319.431017) (xy 264.395966 -319.404492) (xy 264.395712 -319.3542)
			(xy 261.84606 -319.3542) (xy 261.836154 -319.358772) (xy 261.812876 -319.36887) (xy 261.764177 -319.38312)
			(xy 261.71395 -319.390317) (xy 261.66321 -319.390317) (xy 261.612983 -319.38312) (xy 261.564284 -319.36887)
			(xy 261.541006 -319.358772) (xy 261.5311 -319.3542) (xy 257.543554 -319.3542) (xy 257.53568 -319.395348)
			(xy 257.530041 -319.422111) (xy 257.511652 -319.473618) (xy 257.485605 -319.521708) (xy 257.452511 -319.565251)
			(xy 257.41315 -319.603223) (xy 257.368446 -319.63473) (xy 257.319451 -319.659033) (xy 257.267316 -319.675559)
			(xy 257.213268 -319.683921) (xy 257.158576 -319.683921) (xy 257.104528 -319.675559) (xy 257.052393 -319.659033)
			(xy 257.003398 -319.63473) (xy 256.958694 -319.603223) (xy 256.919333 -319.565251) (xy 256.886239 -319.521708)
			(xy 256.860192 -319.473618) (xy 256.841803 -319.422111) (xy 256.836164 -319.395348) (xy 256.82829 -319.3542)
			(xy 254.871982 -319.3542) (xy 254.859536 -319.38722) (xy 254.850271 -319.410926) (xy 254.82594 -319.45563)
			(xy 254.795491 -319.496414) (xy 254.759543 -319.532445) (xy 254.718831 -319.56299) (xy 254.674184 -319.587425)
			(xy 254.626511 -319.605254) (xy 254.576786 -319.616111) (xy 254.551434 -319.61836) (xy 254.53625 -319.619977)
			(xy 254.507817 -319.631078) (xy 254.483928 -319.650077) (xy 254.466712 -319.675281) (xy 254.457704 -319.704445)
			(xy 254.4572 -319.719706) (xy 254.4572 -320.593445) (xy 254.620004 -320.593445) (xy 254.620004 -320.540147)
			(xy 254.627947 -320.487443) (xy 254.643657 -320.436513) (xy 254.666783 -320.388492) (xy 254.696807 -320.344455)
			(xy 254.733059 -320.305384) (xy 254.77473 -320.272153) (xy 254.820888 -320.245504) (xy 254.870502 -320.226032)
			(xy 254.922464 -320.214172) (xy 254.975614 -320.210189) (xy 255.028764 -320.214172) (xy 255.080726 -320.226032)
			(xy 255.13034 -320.245504) (xy 255.176498 -320.272153) (xy 255.218169 -320.305384) (xy 255.254421 -320.344455)
			(xy 255.284445 -320.388492) (xy 255.307571 -320.436513) (xy 255.323281 -320.487443) (xy 255.331224 -320.540147)
			(xy 255.331722 -320.566796) (xy 255.331224 -320.593445) (xy 258.720072 -320.593445) (xy 258.720072 -320.540147)
			(xy 258.728015 -320.487443) (xy 258.743725 -320.436513) (xy 258.766851 -320.388492) (xy 258.796875 -320.344455)
			(xy 258.833127 -320.305384) (xy 258.874798 -320.272153) (xy 258.920956 -320.245504) (xy 258.97057 -320.226032)
			(xy 259.022532 -320.214172) (xy 259.075682 -320.210189) (xy 259.128832 -320.214172) (xy 259.180794 -320.226032)
			(xy 259.230408 -320.245504) (xy 259.276566 -320.272153) (xy 259.318237 -320.305384) (xy 259.354489 -320.344455)
			(xy 259.384513 -320.388492) (xy 259.388782 -320.397357) (xy 261.47521 -320.397357) (xy 261.47521 -320.344059)
			(xy 261.483153 -320.291355) (xy 261.498863 -320.240425) (xy 261.521989 -320.192404) (xy 261.552013 -320.148367)
			(xy 261.588265 -320.109296) (xy 261.629936 -320.076065) (xy 261.676094 -320.049416) (xy 261.725708 -320.029944)
			(xy 261.77767 -320.018084) (xy 261.83082 -320.014101) (xy 261.88397 -320.018084) (xy 261.935932 -320.029944)
			(xy 261.985546 -320.049416) (xy 262.031704 -320.076065) (xy 262.073375 -320.109296) (xy 262.109627 -320.148367)
			(xy 262.139651 -320.192404) (xy 262.162777 -320.240425) (xy 262.178487 -320.291355) (xy 262.18643 -320.344059)
			(xy 262.186928 -320.370708) (xy 262.18643 -320.397357) (xy 262.178487 -320.450061) (xy 262.162777 -320.500991)
			(xy 262.139651 -320.549012) (xy 262.109627 -320.593049) (xy 262.073375 -320.63212) (xy 262.031704 -320.665351)
			(xy 261.985546 -320.692) (xy 261.935932 -320.711472) (xy 261.88397 -320.723332) (xy 261.83082 -320.727316)
			(xy 261.77767 -320.723332) (xy 261.725708 -320.711472) (xy 261.676094 -320.692) (xy 261.629936 -320.665351)
			(xy 261.588265 -320.63212) (xy 261.552013 -320.593049) (xy 261.521989 -320.549012) (xy 261.498863 -320.500991)
			(xy 261.483153 -320.450061) (xy 261.47521 -320.397357) (xy 259.388782 -320.397357) (xy 259.407639 -320.436513)
			(xy 259.423349 -320.487443) (xy 259.431292 -320.540147) (xy 259.43179 -320.566796) (xy 259.431292 -320.593445)
			(xy 259.423349 -320.646149) (xy 259.407639 -320.697079) (xy 259.384513 -320.7451) (xy 259.354489 -320.789137)
			(xy 259.318237 -320.828208) (xy 259.276566 -320.861439) (xy 259.230408 -320.888088) (xy 259.180794 -320.90756)
			(xy 259.128832 -320.91942) (xy 259.075682 -320.923404) (xy 259.022532 -320.91942) (xy 258.97057 -320.90756)
			(xy 258.920956 -320.888088) (xy 258.874798 -320.861439) (xy 258.833127 -320.828208) (xy 258.796875 -320.789137)
			(xy 258.766851 -320.7451) (xy 258.743725 -320.697079) (xy 258.728015 -320.646149) (xy 258.720072 -320.593445)
			(xy 255.331224 -320.593445) (xy 255.323281 -320.646149) (xy 255.307571 -320.697079) (xy 255.284445 -320.7451)
			(xy 255.254421 -320.789137) (xy 255.218169 -320.828208) (xy 255.176498 -320.861439) (xy 255.13034 -320.888088)
			(xy 255.080726 -320.90756) (xy 255.028764 -320.91942) (xy 254.975614 -320.923404) (xy 254.922464 -320.91942)
			(xy 254.870502 -320.90756) (xy 254.820888 -320.888088) (xy 254.77473 -320.861439) (xy 254.733059 -320.828208)
			(xy 254.696807 -320.789137) (xy 254.666783 -320.7451) (xy 254.643657 -320.697079) (xy 254.627947 -320.646149)
			(xy 254.620004 -320.593445) (xy 254.4572 -320.593445) (xy 254.4572 -320.953617) (xy 265.05661 -320.953617)
			(xy 265.05661 -320.900319) (xy 265.064553 -320.847615) (xy 265.080263 -320.796685) (xy 265.103389 -320.748664)
			(xy 265.133413 -320.704627) (xy 265.169665 -320.665556) (xy 265.211336 -320.632325) (xy 265.257494 -320.605676)
			(xy 265.307108 -320.586204) (xy 265.35907 -320.574344) (xy 265.41222 -320.570361) (xy 265.46537 -320.574344)
			(xy 265.517332 -320.586204) (xy 265.535782 -320.593445) (xy 266.263872 -320.593445) (xy 266.263872 -320.540147)
			(xy 266.271815 -320.487443) (xy 266.287525 -320.436513) (xy 266.310651 -320.388492) (xy 266.340675 -320.344455)
			(xy 266.376927 -320.305384) (xy 266.418598 -320.272153) (xy 266.464756 -320.245504) (xy 266.51437 -320.226032)
			(xy 266.566332 -320.214172) (xy 266.619482 -320.210189) (xy 266.672632 -320.214172) (xy 266.724594 -320.226032)
			(xy 266.774208 -320.245504) (xy 266.820366 -320.272153) (xy 266.862037 -320.305384) (xy 266.898289 -320.344455)
			(xy 266.928313 -320.388492) (xy 266.951439 -320.436513) (xy 266.967149 -320.487443) (xy 266.975092 -320.540147)
			(xy 266.97559 -320.566796) (xy 266.975092 -320.593445) (xy 269.22221 -320.593445) (xy 269.22221 -320.540147)
			(xy 269.230153 -320.487443) (xy 269.245863 -320.436513) (xy 269.268989 -320.388492) (xy 269.299013 -320.344455)
			(xy 269.335265 -320.305384) (xy 269.376936 -320.272153) (xy 269.423094 -320.245504) (xy 269.472708 -320.226032)
			(xy 269.52467 -320.214172) (xy 269.57782 -320.210189) (xy 269.63097 -320.214172) (xy 269.682932 -320.226032)
			(xy 269.732546 -320.245504) (xy 269.778704 -320.272153) (xy 269.820375 -320.305384) (xy 269.856627 -320.344455)
			(xy 269.886651 -320.388492) (xy 269.909777 -320.436513) (xy 269.925487 -320.487443) (xy 269.93343 -320.540147)
			(xy 269.933928 -320.566796) (xy 269.93343 -320.593445) (xy 273.807672 -320.593445) (xy 273.807672 -320.540147)
			(xy 273.815615 -320.487443) (xy 273.831325 -320.436513) (xy 273.854451 -320.388492) (xy 273.884475 -320.344455)
			(xy 273.920727 -320.305384) (xy 273.962398 -320.272153) (xy 274.008556 -320.245504) (xy 274.05817 -320.226032)
			(xy 274.110132 -320.214172) (xy 274.163282 -320.210189) (xy 274.216432 -320.214172) (xy 274.268394 -320.226032)
			(xy 274.318008 -320.245504) (xy 274.364166 -320.272153) (xy 274.405837 -320.305384) (xy 274.442089 -320.344455)
			(xy 274.472113 -320.388492) (xy 274.495239 -320.436513) (xy 274.510949 -320.487443) (xy 274.518892 -320.540147)
			(xy 274.51939 -320.566796) (xy 274.518892 -320.593445) (xy 276.75839 -320.593445) (xy 276.75839 -320.540147)
			(xy 276.766333 -320.487443) (xy 276.782043 -320.436513) (xy 276.805169 -320.388492) (xy 276.835193 -320.344455)
			(xy 276.871445 -320.305384) (xy 276.913116 -320.272153) (xy 276.959274 -320.245504) (xy 277.008888 -320.226032)
			(xy 277.06085 -320.214172) (xy 277.114 -320.210189) (xy 277.16715 -320.214172) (xy 277.219112 -320.226032)
			(xy 277.268726 -320.245504) (xy 277.314884 -320.272153) (xy 277.356555 -320.305384) (xy 277.392807 -320.344455)
			(xy 277.422831 -320.388492) (xy 277.445957 -320.436513) (xy 277.461667 -320.487443) (xy 277.46961 -320.540147)
			(xy 277.470108 -320.566796) (xy 277.46961 -320.593445) (xy 277.461667 -320.646149) (xy 277.445957 -320.697079)
			(xy 277.422831 -320.7451) (xy 277.392807 -320.789137) (xy 277.356555 -320.828208) (xy 277.314884 -320.861439)
			(xy 277.268726 -320.888088) (xy 277.219112 -320.90756) (xy 277.16715 -320.91942) (xy 277.114 -320.923404)
			(xy 277.06085 -320.91942) (xy 277.008888 -320.90756) (xy 276.959274 -320.888088) (xy 276.913116 -320.861439)
			(xy 276.871445 -320.828208) (xy 276.835193 -320.789137) (xy 276.805169 -320.7451) (xy 276.782043 -320.697079)
			(xy 276.766333 -320.646149) (xy 276.75839 -320.593445) (xy 274.518892 -320.593445) (xy 274.510949 -320.646149)
			(xy 274.495239 -320.697079) (xy 274.472113 -320.7451) (xy 274.442089 -320.789137) (xy 274.405837 -320.828208)
			(xy 274.364166 -320.861439) (xy 274.318008 -320.888088) (xy 274.268394 -320.90756) (xy 274.216432 -320.91942)
			(xy 274.163282 -320.923404) (xy 274.110132 -320.91942) (xy 274.05817 -320.90756) (xy 274.008556 -320.888088)
			(xy 273.962398 -320.861439) (xy 273.920727 -320.828208) (xy 273.884475 -320.789137) (xy 273.854451 -320.7451)
			(xy 273.831325 -320.697079) (xy 273.815615 -320.646149) (xy 273.807672 -320.593445) (xy 269.93343 -320.593445)
			(xy 269.925487 -320.646149) (xy 269.909777 -320.697079) (xy 269.886651 -320.7451) (xy 269.856627 -320.789137)
			(xy 269.820375 -320.828208) (xy 269.778704 -320.861439) (xy 269.732546 -320.888088) (xy 269.682932 -320.90756)
			(xy 269.63097 -320.91942) (xy 269.57782 -320.923404) (xy 269.52467 -320.91942) (xy 269.472708 -320.90756)
			(xy 269.423094 -320.888088) (xy 269.376936 -320.861439) (xy 269.335265 -320.828208) (xy 269.299013 -320.789137)
			(xy 269.268989 -320.7451) (xy 269.245863 -320.697079) (xy 269.230153 -320.646149) (xy 269.22221 -320.593445)
			(xy 266.975092 -320.593445) (xy 266.967149 -320.646149) (xy 266.951439 -320.697079) (xy 266.928313 -320.7451)
			(xy 266.898289 -320.789137) (xy 266.862037 -320.828208) (xy 266.820366 -320.861439) (xy 266.774208 -320.888088)
			(xy 266.724594 -320.90756) (xy 266.672632 -320.91942) (xy 266.619482 -320.923404) (xy 266.566332 -320.91942)
			(xy 266.51437 -320.90756) (xy 266.464756 -320.888088) (xy 266.418598 -320.861439) (xy 266.376927 -320.828208)
			(xy 266.340675 -320.789137) (xy 266.310651 -320.7451) (xy 266.287525 -320.697079) (xy 266.271815 -320.646149)
			(xy 266.263872 -320.593445) (xy 265.535782 -320.593445) (xy 265.566946 -320.605676) (xy 265.613104 -320.632325)
			(xy 265.654775 -320.665556) (xy 265.691027 -320.704627) (xy 265.721051 -320.748664) (xy 265.744177 -320.796685)
			(xy 265.759887 -320.847615) (xy 265.76783 -320.900319) (xy 265.768328 -320.926968) (xy 265.76783 -320.953617)
			(xy 265.759887 -321.006321) (xy 265.756557 -321.017117) (xy 272.56231 -321.017117) (xy 272.56231 -320.963819)
			(xy 272.570253 -320.911115) (xy 272.585963 -320.860185) (xy 272.609089 -320.812164) (xy 272.639113 -320.768127)
			(xy 272.675365 -320.729056) (xy 272.717036 -320.695825) (xy 272.763194 -320.669176) (xy 272.812808 -320.649704)
			(xy 272.86477 -320.637844) (xy 272.91792 -320.633861) (xy 272.97107 -320.637844) (xy 273.023032 -320.649704)
			(xy 273.072646 -320.669176) (xy 273.118804 -320.695825) (xy 273.160475 -320.729056) (xy 273.196727 -320.768127)
			(xy 273.226751 -320.812164) (xy 273.249877 -320.860185) (xy 273.265587 -320.911115) (xy 273.27353 -320.963819)
			(xy 273.273861 -320.981557) (xy 279.94101 -320.981557) (xy 279.94101 -320.928259) (xy 279.948953 -320.875555)
			(xy 279.964663 -320.824625) (xy 279.987789 -320.776604) (xy 280.017813 -320.732567) (xy 280.054065 -320.693496)
			(xy 280.095736 -320.660265) (xy 280.141894 -320.633616) (xy 280.191508 -320.614144) (xy 280.24347 -320.602284)
			(xy 280.29662 -320.598301) (xy 280.34977 -320.602284) (xy 280.401732 -320.614144) (xy 280.451346 -320.633616)
			(xy 280.497504 -320.660265) (xy 280.539175 -320.693496) (xy 280.575427 -320.732567) (xy 280.605451 -320.776604)
			(xy 280.614256 -320.794888) (xy 281.342592 -320.794888) (xy 281.34309 -320.768239) (xy 281.351033 -320.715535)
			(xy 281.366743 -320.664605) (xy 281.389869 -320.616584) (xy 281.419893 -320.572547) (xy 281.456145 -320.533476)
			(xy 281.497816 -320.500245) (xy 281.543974 -320.473596) (xy 281.593588 -320.454124) (xy 281.64555 -320.442264)
			(xy 281.6987 -320.438281) (xy 281.75185 -320.442264) (xy 281.803812 -320.454124) (xy 281.853426 -320.473596)
			(xy 281.899584 -320.500245) (xy 281.941255 -320.533476) (xy 281.963793 -320.557767) (xy 284.326682 -320.557767)
			(xy 284.332162 -320.503885) (xy 284.345737 -320.451453) (xy 284.367095 -320.401682) (xy 284.395743 -320.355719)
			(xy 284.431022 -320.314625) (xy 284.472116 -320.279346) (xy 284.518079 -320.250697) (xy 284.567849 -320.229338)
			(xy 284.620281 -320.215762) (xy 284.674163 -320.210283) (xy 284.728254 -320.213025) (xy 284.781305 -320.223927)
			(xy 284.832094 -320.242737) (xy 284.879449 -320.269021) (xy 284.922278 -320.302172) (xy 284.959593 -320.341427)
			(xy 284.990534 -320.385879) (xy 285.014386 -320.434504) (xy 285.0306 -320.48618) (xy 285.038802 -320.539716)
			(xy 285.039308 -320.566796) (xy 285.038872 -320.592492) (xy 285.03149 -320.64335) (xy 285.016892 -320.692625)
			(xy 285.006542 -320.716148) (xy 285.000606 -320.73027) (xy 284.996587 -320.760625) (xy 285.001747 -320.790806)
			(xy 285.015621 -320.818102) (xy 285.036963 -320.840058) (xy 285.063853 -320.854702) (xy 285.093876 -320.860717)
			(xy 285.109158 -320.859658) (xy 285.14548 -320.85788) (xy 285.172562 -320.858376) (xy 285.226102 -320.866575)
			(xy 285.277784 -320.882788) (xy 285.326414 -320.906639) (xy 285.370871 -320.937579) (xy 285.410131 -320.974895)
			(xy 285.443287 -321.017726) (xy 285.469575 -321.065083) (xy 285.486155 -321.109848) (xy 288.690812 -321.109848)
			(xy 288.691276 -321.083011) (xy 288.699318 -321.029943) (xy 288.715243 -320.978686) (xy 288.738687 -320.930403)
			(xy 288.76912 -320.88619) (xy 288.80585 -320.847052) (xy 288.848044 -320.813877) (xy 288.871152 -320.800222)
			(xy 288.883314 -320.792712) (xy 288.903247 -320.772242) (xy 288.916742 -320.747059) (xy 288.922747 -320.719126)
			(xy 288.920794 -320.690622) (xy 288.916364 -320.677032) (xy 288.906279 -320.647501) (xy 288.895422 -320.586056)
			(xy 288.894774 -320.554858) (xy 288.895272 -320.528209) (xy 288.903215 -320.475505) (xy 288.918925 -320.424575)
			(xy 288.942051 -320.376554) (xy 288.972075 -320.332517) (xy 289.008327 -320.293446) (xy 289.049998 -320.260215)
			(xy 289.096156 -320.233566) (xy 289.14577 -320.214094) (xy 289.197732 -320.202234) (xy 289.250882 -320.198251)
			(xy 289.304032 -320.202234) (xy 289.355994 -320.214094) (xy 289.405608 -320.233566) (xy 289.451766 -320.260215)
			(xy 289.493437 -320.293446) (xy 289.529689 -320.332517) (xy 289.559713 -320.376554) (xy 289.582839 -320.424575)
			(xy 289.598549 -320.475505) (xy 289.606492 -320.528209) (xy 289.60699 -320.554858) (xy 289.60653 -320.581695)
			(xy 289.604749 -320.593445) (xy 291.84599 -320.593445) (xy 291.84599 -320.540147) (xy 291.853933 -320.487443)
			(xy 291.869643 -320.436513) (xy 291.892769 -320.388492) (xy 291.922793 -320.344455) (xy 291.959045 -320.305384)
			(xy 292.000716 -320.272153) (xy 292.046874 -320.245504) (xy 292.096488 -320.226032) (xy 292.14845 -320.214172)
			(xy 292.2016 -320.210189) (xy 292.25475 -320.214172) (xy 292.306712 -320.226032) (xy 292.356326 -320.245504)
			(xy 292.402484 -320.272153) (xy 292.444155 -320.305384) (xy 292.480407 -320.344455) (xy 292.510431 -320.388492)
			(xy 292.533557 -320.436513) (xy 292.549267 -320.487443) (xy 292.55721 -320.540147) (xy 292.557708 -320.566796)
			(xy 292.55721 -320.593445) (xy 296.439072 -320.593445) (xy 296.439072 -320.540147) (xy 296.447015 -320.487443)
			(xy 296.462725 -320.436513) (xy 296.485851 -320.388492) (xy 296.515875 -320.344455) (xy 296.552127 -320.305384)
			(xy 296.593798 -320.272153) (xy 296.639956 -320.245504) (xy 296.68957 -320.226032) (xy 296.741532 -320.214172)
			(xy 296.794682 -320.210189) (xy 296.847832 -320.214172) (xy 296.899794 -320.226032) (xy 296.949408 -320.245504)
			(xy 296.995566 -320.272153) (xy 297.037237 -320.305384) (xy 297.073489 -320.344455) (xy 297.103513 -320.388492)
			(xy 297.126639 -320.436513) (xy 297.142349 -320.487443) (xy 297.150292 -320.540147) (xy 297.15079 -320.566796)
			(xy 297.150292 -320.593445) (xy 297.142349 -320.646149) (xy 297.126639 -320.697079) (xy 297.103513 -320.7451)
			(xy 297.073489 -320.789137) (xy 297.037237 -320.828208) (xy 296.995566 -320.861439) (xy 296.949408 -320.888088)
			(xy 296.899794 -320.90756) (xy 296.847832 -320.91942) (xy 296.794682 -320.923404) (xy 296.741532 -320.91942)
			(xy 296.68957 -320.90756) (xy 296.639956 -320.888088) (xy 296.593798 -320.861439) (xy 296.552127 -320.828208)
			(xy 296.515875 -320.789137) (xy 296.485851 -320.7451) (xy 296.462725 -320.697079) (xy 296.447015 -320.646149)
			(xy 296.439072 -320.593445) (xy 292.55721 -320.593445) (xy 292.549267 -320.646149) (xy 292.533557 -320.697079)
			(xy 292.510431 -320.7451) (xy 292.480407 -320.789137) (xy 292.444155 -320.828208) (xy 292.402484 -320.861439)
			(xy 292.356326 -320.888088) (xy 292.306712 -320.90756) (xy 292.25475 -320.91942) (xy 292.2016 -320.923404)
			(xy 292.14845 -320.91942) (xy 292.096488 -320.90756) (xy 292.046874 -320.888088) (xy 292.000716 -320.861439)
			(xy 291.959045 -320.828208) (xy 291.922793 -320.789137) (xy 291.892769 -320.7451) (xy 291.869643 -320.697079)
			(xy 291.853933 -320.646149) (xy 291.84599 -320.593445) (xy 289.604749 -320.593445) (xy 289.598487 -320.634763)
			(xy 289.582562 -320.686021) (xy 289.559116 -320.734304) (xy 289.528683 -320.778516) (xy 289.491952 -320.817654)
			(xy 289.449759 -320.850829) (xy 289.42665 -320.864484) (xy 289.414484 -320.871989) (xy 289.394551 -320.89246)
			(xy 289.381057 -320.917644) (xy 289.375053 -320.945579) (xy 289.377007 -320.974084) (xy 289.381438 -320.987674)
			(xy 289.391524 -321.017204) (xy 289.402381 -321.07865) (xy 289.403028 -321.109848) (xy 289.40253 -321.136497)
			(xy 289.394587 -321.189201) (xy 289.378877 -321.240131) (xy 289.355751 -321.288152) (xy 289.325727 -321.332189)
			(xy 289.289475 -321.37126) (xy 289.247804 -321.404491) (xy 289.201646 -321.43114) (xy 289.170589 -321.443329)
			(xy 292.339004 -321.443329) (xy 292.339004 -321.390031) (xy 292.346947 -321.337327) (xy 292.362657 -321.286397)
			(xy 292.385783 -321.238376) (xy 292.415807 -321.194339) (xy 292.452059 -321.155268) (xy 292.49373 -321.122037)
			(xy 292.539888 -321.095388) (xy 292.589502 -321.075916) (xy 292.641464 -321.064056) (xy 292.694614 -321.060073)
			(xy 292.747764 -321.064056) (xy 292.799726 -321.075916) (xy 292.84934 -321.095388) (xy 292.895498 -321.122037)
			(xy 292.937169 -321.155268) (xy 292.973421 -321.194339) (xy 293.003445 -321.238376) (xy 293.026571 -321.286397)
			(xy 293.042281 -321.337327) (xy 293.050224 -321.390031) (xy 293.050722 -321.41668) (xy 293.050224 -321.443329)
			(xy 296.439072 -321.443329) (xy 296.439072 -321.390031) (xy 296.447015 -321.337327) (xy 296.462725 -321.286397)
			(xy 296.485851 -321.238376) (xy 296.515875 -321.194339) (xy 296.552127 -321.155268) (xy 296.593798 -321.122037)
			(xy 296.639956 -321.095388) (xy 296.68957 -321.075916) (xy 296.741532 -321.064056) (xy 296.794682 -321.060073)
			(xy 296.847832 -321.064056) (xy 296.899794 -321.075916) (xy 296.949408 -321.095388) (xy 296.995566 -321.122037)
			(xy 297.037237 -321.155268) (xy 297.073489 -321.194339) (xy 297.103513 -321.238376) (xy 297.126639 -321.286397)
			(xy 297.142349 -321.337327) (xy 297.150292 -321.390031) (xy 297.15079 -321.41668) (xy 297.150292 -321.443329)
			(xy 297.142349 -321.496033) (xy 297.131409 -321.5315) (xy 299.155056 -321.5315) (xy 299.15904 -321.478343)
			(xy 299.170902 -321.426374) (xy 299.190377 -321.376753) (xy 299.217031 -321.330589) (xy 299.250268 -321.288913)
			(xy 299.289345 -321.252657) (xy 299.33339 -321.222631) (xy 299.381418 -321.199504) (xy 299.432356 -321.183794)
			(xy 299.485067 -321.175852) (xy 299.51172 -321.17538) (xy 299.539399 -321.175919) (xy 299.594091 -321.184481)
			(xy 299.646801 -321.201397) (xy 299.696263 -321.226259) (xy 299.741285 -321.258469) (xy 299.761402 -321.277488)
			(xy 299.771387 -321.286697) (xy 299.795056 -321.299997) (xy 299.821397 -321.306576) (xy 299.84854 -321.305967)
			(xy 299.874559 -321.298211) (xy 299.897607 -321.283861) (xy 299.916047 -321.263934) (xy 299.922692 -321.252088)
			(xy 299.936 -321.227737) (xy 299.968957 -321.183096) (xy 300.008442 -321.14411) (xy 300.053499 -321.111724)
			(xy 300.103036 -321.086722) (xy 300.155853 -321.069711) (xy 300.21067 -321.061102) (xy 300.238414 -321.060572)
			(xy 300.265061 -321.061111) (xy 300.31776 -321.069056) (xy 300.368686 -321.084766) (xy 300.416702 -321.107891)
			(xy 300.460735 -321.137914) (xy 300.499801 -321.174164) (xy 300.533029 -321.215832) (xy 300.559676 -321.261986)
			(xy 300.579146 -321.311597) (xy 300.591004 -321.363555) (xy 300.594987 -321.4167) (xy 300.591004 -321.469845)
			(xy 300.579146 -321.521803) (xy 300.559676 -321.571414) (xy 300.533029 -321.617568) (xy 300.499801 -321.659236)
			(xy 300.460735 -321.695486) (xy 300.416702 -321.725509) (xy 300.368686 -321.748634) (xy 300.31776 -321.764344)
			(xy 300.265061 -321.772289) (xy 300.238414 -321.772788) (xy 300.210733 -321.772299) (xy 300.156038 -321.763726)
			(xy 300.103327 -321.746799) (xy 300.053867 -321.721926) (xy 300.008847 -321.689704) (xy 299.988732 -321.67068)
			(xy 299.978825 -321.661378) (xy 299.955136 -321.64807) (xy 299.928774 -321.641493) (xy 299.901611 -321.642114)
			(xy 299.875576 -321.649888) (xy 299.852521 -321.664264) (xy 299.834082 -321.68422) (xy 299.827442 -321.69608)
			(xy 299.814169 -321.720451) (xy 299.781208 -321.765095) (xy 299.741718 -321.804082) (xy 299.696655 -321.836467)
			(xy 299.647112 -321.861465) (xy 299.594289 -321.87847) (xy 299.539467 -321.887071) (xy 299.51172 -321.887596)
			(xy 299.485067 -321.887148) (xy 299.432356 -321.879206) (xy 299.381418 -321.863496) (xy 299.33339 -321.840369)
			(xy 299.289345 -321.810343) (xy 299.250268 -321.774087) (xy 299.217031 -321.732411) (xy 299.190377 -321.686247)
			(xy 299.170902 -321.636626) (xy 299.15904 -321.584657) (xy 299.155056 -321.5315) (xy 297.131409 -321.5315)
			(xy 297.126639 -321.546963) (xy 297.103513 -321.594984) (xy 297.073489 -321.639021) (xy 297.037237 -321.678092)
			(xy 296.995566 -321.711323) (xy 296.949408 -321.737972) (xy 296.899794 -321.757444) (xy 296.847832 -321.769304)
			(xy 296.794682 -321.773288) (xy 296.741532 -321.769304) (xy 296.68957 -321.757444) (xy 296.639956 -321.737972)
			(xy 296.593798 -321.711323) (xy 296.552127 -321.678092) (xy 296.515875 -321.639021) (xy 296.485851 -321.594984)
			(xy 296.462725 -321.546963) (xy 296.447015 -321.496033) (xy 296.439072 -321.443329) (xy 293.050224 -321.443329)
			(xy 293.042281 -321.496033) (xy 293.026571 -321.546963) (xy 293.003445 -321.594984) (xy 292.973421 -321.639021)
			(xy 292.937169 -321.678092) (xy 292.895498 -321.711323) (xy 292.84934 -321.737972) (xy 292.799726 -321.757444)
			(xy 292.747764 -321.769304) (xy 292.694614 -321.773288) (xy 292.641464 -321.769304) (xy 292.589502 -321.757444)
			(xy 292.539888 -321.737972) (xy 292.49373 -321.711323) (xy 292.452059 -321.678092) (xy 292.415807 -321.639021)
			(xy 292.385783 -321.594984) (xy 292.362657 -321.546963) (xy 292.346947 -321.496033) (xy 292.339004 -321.443329)
			(xy 289.170589 -321.443329) (xy 289.152032 -321.450612) (xy 289.10007 -321.462472) (xy 289.04692 -321.466456)
			(xy 288.99377 -321.462472) (xy 288.941808 -321.450612) (xy 288.892194 -321.43114) (xy 288.846036 -321.404491)
			(xy 288.804365 -321.37126) (xy 288.768113 -321.332189) (xy 288.738089 -321.288152) (xy 288.714963 -321.240131)
			(xy 288.699253 -321.189201) (xy 288.69131 -321.136497) (xy 288.690812 -321.109848) (xy 285.486155 -321.109848)
			(xy 285.488388 -321.115876) (xy 285.499293 -321.168931) (xy 285.502038 -321.223026) (xy 285.496559 -321.276912)
			(xy 285.482984 -321.329348) (xy 285.461625 -321.379123) (xy 285.432975 -321.42509) (xy 285.397694 -321.466188)
			(xy 285.356597 -321.50147) (xy 285.31063 -321.530121) (xy 285.260856 -321.551481) (xy 285.20842 -321.565058)
			(xy 285.154534 -321.570538) (xy 285.100439 -321.567794) (xy 285.047383 -321.55689) (xy 284.996591 -321.538078)
			(xy 284.949233 -321.511791) (xy 284.906401 -321.478636) (xy 284.869084 -321.439378) (xy 284.838143 -321.394921)
			(xy 284.814291 -321.346291) (xy 284.798077 -321.29461) (xy 284.789877 -321.24107) (xy 284.789372 -321.213988)
			(xy 284.789804 -321.188292) (xy 284.797188 -321.137434) (xy 284.811788 -321.088159) (xy 284.822138 -321.064636)
			(xy 284.828113 -321.050528) (xy 284.83213 -321.020166) (xy 284.826967 -320.989978) (xy 284.813086 -320.962678)
			(xy 284.791737 -320.940719) (xy 284.764838 -320.926076) (xy 284.734807 -320.920064) (xy 284.719522 -320.921126)
			(xy 284.6832 -320.922904) (xy 284.65612 -320.922402) (xy 284.602584 -320.914201) (xy 284.550908 -320.897987)
			(xy 284.502282 -320.874136) (xy 284.45783 -320.843196) (xy 284.418575 -320.805881) (xy 284.385423 -320.763053)
			(xy 284.359139 -320.715698) (xy 284.340328 -320.664909) (xy 284.329426 -320.611858) (xy 284.326682 -320.557767)
			(xy 281.963793 -320.557767) (xy 281.977507 -320.572547) (xy 282.007531 -320.616584) (xy 282.030657 -320.664605)
			(xy 282.046367 -320.715535) (xy 282.05431 -320.768239) (xy 282.054808 -320.794888) (xy 282.054343 -320.821001)
			(xy 282.046717 -320.872667) (xy 282.031626 -320.922665) (xy 282.009394 -320.969922) (xy 281.980498 -321.013426)
			(xy 281.963368 -321.03314) (xy 281.953556 -321.044803) (xy 281.940685 -321.072414) (xy 281.936525 -321.102593)
			(xy 281.941447 -321.132656) (xy 281.955012 -321.159933) (xy 281.965146 -321.171316) (xy 281.983425 -321.191307)
			(xy 282.014382 -321.235754) (xy 282.038249 -321.284379) (xy 282.054474 -321.336057) (xy 282.062682 -321.389597)
			(xy 282.06319 -321.41668) (xy 282.062692 -321.443329) (xy 282.054749 -321.496033) (xy 282.039039 -321.546963)
			(xy 282.015913 -321.594984) (xy 281.985889 -321.639021) (xy 281.949637 -321.678092) (xy 281.907966 -321.711323)
			(xy 281.861808 -321.737972) (xy 281.812194 -321.757444) (xy 281.760232 -321.769304) (xy 281.707082 -321.773288)
			(xy 281.653932 -321.769304) (xy 281.60197 -321.757444) (xy 281.552356 -321.737972) (xy 281.506198 -321.711323)
			(xy 281.464527 -321.678092) (xy 281.428275 -321.639021) (xy 281.398251 -321.594984) (xy 281.375125 -321.546963)
			(xy 281.359415 -321.496033) (xy 281.351472 -321.443329) (xy 281.350974 -321.41668) (xy 281.351424 -321.390567)
			(xy 281.359055 -321.3389) (xy 281.37415 -321.288902) (xy 281.396385 -321.241645) (xy 281.425283 -321.198142)
			(xy 281.442414 -321.178428) (xy 281.452259 -321.16679) (xy 281.465129 -321.13917) (xy 281.469284 -321.108983)
			(xy 281.464353 -321.078914) (xy 281.450776 -321.051635) (xy 281.440636 -321.040252) (xy 281.422339 -321.020277)
			(xy 281.391385 -320.975825) (xy 281.367522 -320.927197) (xy 281.351301 -320.875515) (xy 281.343097 -320.821972)
			(xy 281.342592 -320.794888) (xy 280.614256 -320.794888) (xy 280.628577 -320.824625) (xy 280.644287 -320.875555)
			(xy 280.65223 -320.928259) (xy 280.652728 -320.954908) (xy 280.65223 -320.981557) (xy 280.644287 -321.034261)
			(xy 280.628577 -321.085191) (xy 280.605451 -321.133212) (xy 280.575427 -321.177249) (xy 280.539175 -321.21632)
			(xy 280.497504 -321.249551) (xy 280.451346 -321.2762) (xy 280.401732 -321.295672) (xy 280.34977 -321.307532)
			(xy 280.29662 -321.311516) (xy 280.24347 -321.307532) (xy 280.191508 -321.295672) (xy 280.141894 -321.2762)
			(xy 280.095736 -321.249551) (xy 280.054065 -321.21632) (xy 280.017813 -321.177249) (xy 279.987789 -321.133212)
			(xy 279.964663 -321.085191) (xy 279.948953 -321.034261) (xy 279.94101 -320.981557) (xy 273.273861 -320.981557)
			(xy 273.274028 -320.990468) (xy 273.27353 -321.017117) (xy 273.265587 -321.069821) (xy 273.249877 -321.120751)
			(xy 273.226751 -321.168772) (xy 273.196727 -321.212809) (xy 273.160475 -321.25188) (xy 273.118804 -321.285111)
			(xy 273.072646 -321.31176) (xy 273.023032 -321.331232) (xy 272.97107 -321.343092) (xy 272.91792 -321.347076)
			(xy 272.86477 -321.343092) (xy 272.812808 -321.331232) (xy 272.763194 -321.31176) (xy 272.717036 -321.285111)
			(xy 272.675365 -321.25188) (xy 272.639113 -321.212809) (xy 272.609089 -321.168772) (xy 272.585963 -321.120751)
			(xy 272.570253 -321.069821) (xy 272.56231 -321.017117) (xy 265.756557 -321.017117) (xy 265.744177 -321.057251)
			(xy 265.721051 -321.105272) (xy 265.691027 -321.149309) (xy 265.654775 -321.18838) (xy 265.613104 -321.221611)
			(xy 265.566946 -321.24826) (xy 265.517332 -321.267732) (xy 265.46537 -321.279592) (xy 265.41222 -321.283576)
			(xy 265.35907 -321.279592) (xy 265.307108 -321.267732) (xy 265.257494 -321.24826) (xy 265.211336 -321.221611)
			(xy 265.169665 -321.18838) (xy 265.133413 -321.149309) (xy 265.103389 -321.105272) (xy 265.080263 -321.057251)
			(xy 265.064553 -321.006321) (xy 265.05661 -320.953617) (xy 254.4572 -320.953617) (xy 254.4572 -321.443329)
			(xy 254.620004 -321.443329) (xy 254.620004 -321.390031) (xy 254.627947 -321.337327) (xy 254.643657 -321.286397)
			(xy 254.666783 -321.238376) (xy 254.696807 -321.194339) (xy 254.733059 -321.155268) (xy 254.77473 -321.122037)
			(xy 254.820888 -321.095388) (xy 254.870502 -321.075916) (xy 254.922464 -321.064056) (xy 254.975614 -321.060073)
			(xy 255.028764 -321.064056) (xy 255.080726 -321.075916) (xy 255.13034 -321.095388) (xy 255.176498 -321.122037)
			(xy 255.218169 -321.155268) (xy 255.254421 -321.194339) (xy 255.284445 -321.238376) (xy 255.307571 -321.286397)
			(xy 255.323281 -321.337327) (xy 255.331224 -321.390031) (xy 255.331722 -321.41668) (xy 255.331224 -321.443329)
			(xy 258.720072 -321.443329) (xy 258.720072 -321.390031) (xy 258.728015 -321.337327) (xy 258.743725 -321.286397)
			(xy 258.766851 -321.238376) (xy 258.796875 -321.194339) (xy 258.833127 -321.155268) (xy 258.874798 -321.122037)
			(xy 258.920956 -321.095388) (xy 258.97057 -321.075916) (xy 259.022532 -321.064056) (xy 259.075682 -321.060073)
			(xy 259.128832 -321.064056) (xy 259.180794 -321.075916) (xy 259.230408 -321.095388) (xy 259.276566 -321.122037)
			(xy 259.318237 -321.155268) (xy 259.354489 -321.194339) (xy 259.384513 -321.238376) (xy 259.407639 -321.286397)
			(xy 259.423349 -321.337327) (xy 259.431292 -321.390031) (xy 259.43179 -321.41668) (xy 259.431292 -321.443329)
			(xy 259.423349 -321.496033) (xy 259.407639 -321.546963) (xy 259.384513 -321.594984) (xy 259.354489 -321.639021)
			(xy 259.318237 -321.678092) (xy 259.291893 -321.6991) (xy 261.461496 -321.6991) (xy 261.465479 -321.645949)
			(xy 261.47734 -321.593985) (xy 261.496813 -321.54437) (xy 261.523464 -321.498212) (xy 261.556697 -321.456541)
			(xy 261.59577 -321.420289) (xy 261.63981 -321.390265) (xy 261.687832 -321.367141) (xy 261.738765 -321.351433)
			(xy 261.79147 -321.343492) (xy 261.81812 -321.34302) (xy 261.844355 -321.343479) (xy 261.896263 -321.351139)
			(xy 261.946479 -321.366348) (xy 261.993914 -321.388776) (xy 262.015986 -321.402964) (xy 262.027996 -321.410429)
			(xy 262.05491 -321.419073) (xy 262.083162 -321.420013) (xy 262.11059 -321.413176) (xy 262.135096 -321.399086)
			(xy 262.154803 -321.378821) (xy 262.168204 -321.353932) (xy 262.171688 -321.340226) (xy 262.177956 -321.314158)
			(xy 262.197167 -321.264107) (xy 262.223667 -321.217504) (xy 262.256856 -321.175402) (xy 262.295985 -321.138753)
			(xy 262.340167 -321.108388) (xy 262.388404 -321.084992) (xy 262.439604 -321.069095) (xy 262.492608 -321.061057)
			(xy 262.519414 -321.060572) (xy 262.546061 -321.061111) (xy 262.59876 -321.069056) (xy 262.649686 -321.084766)
			(xy 262.697702 -321.107891) (xy 262.741735 -321.137914) (xy 262.780801 -321.174164) (xy 262.814029 -321.215832)
			(xy 262.840676 -321.261986) (xy 262.860146 -321.311597) (xy 262.872004 -321.363555) (xy 262.875987 -321.4167)
			(xy 262.873991 -321.443329) (xy 266.263872 -321.443329) (xy 266.263872 -321.390031) (xy 266.271815 -321.337327)
			(xy 266.287525 -321.286397) (xy 266.310651 -321.238376) (xy 266.340675 -321.194339) (xy 266.376927 -321.155268)
			(xy 266.418598 -321.122037) (xy 266.464756 -321.095388) (xy 266.51437 -321.075916) (xy 266.566332 -321.064056)
			(xy 266.619482 -321.060073) (xy 266.672632 -321.064056) (xy 266.724594 -321.075916) (xy 266.774208 -321.095388)
			(xy 266.820366 -321.122037) (xy 266.862037 -321.155268) (xy 266.898289 -321.194339) (xy 266.928313 -321.238376)
			(xy 266.951439 -321.286397) (xy 266.967149 -321.337327) (xy 266.975092 -321.390031) (xy 266.97559 -321.41668)
			(xy 266.975092 -321.443329) (xy 269.707604 -321.443329) (xy 269.707604 -321.390031) (xy 269.715547 -321.337327)
			(xy 269.731257 -321.286397) (xy 269.754383 -321.238376) (xy 269.784407 -321.194339) (xy 269.820659 -321.155268)
			(xy 269.86233 -321.122037) (xy 269.908488 -321.095388) (xy 269.958102 -321.075916) (xy 270.010064 -321.064056)
			(xy 270.063214 -321.060073) (xy 270.116364 -321.064056) (xy 270.168326 -321.075916) (xy 270.21794 -321.095388)
			(xy 270.264098 -321.122037) (xy 270.305769 -321.155268) (xy 270.342021 -321.194339) (xy 270.372045 -321.238376)
			(xy 270.395171 -321.286397) (xy 270.410881 -321.337327) (xy 270.418824 -321.390031) (xy 270.419322 -321.41668)
			(xy 270.418824 -321.443329) (xy 273.807672 -321.443329) (xy 273.807672 -321.390031) (xy 273.815615 -321.337327)
			(xy 273.831325 -321.286397) (xy 273.854451 -321.238376) (xy 273.884475 -321.194339) (xy 273.920727 -321.155268)
			(xy 273.962398 -321.122037) (xy 274.008556 -321.095388) (xy 274.05817 -321.075916) (xy 274.110132 -321.064056)
			(xy 274.163282 -321.060073) (xy 274.216432 -321.064056) (xy 274.268394 -321.075916) (xy 274.318008 -321.095388)
			(xy 274.364166 -321.122037) (xy 274.405837 -321.155268) (xy 274.442089 -321.194339) (xy 274.472113 -321.238376)
			(xy 274.495239 -321.286397) (xy 274.510949 -321.337327) (xy 274.518892 -321.390031) (xy 274.51939 -321.41668)
			(xy 274.518892 -321.443329) (xy 277.251404 -321.443329) (xy 277.251404 -321.390031) (xy 277.259347 -321.337327)
			(xy 277.275057 -321.286397) (xy 277.298183 -321.238376) (xy 277.328207 -321.194339) (xy 277.364459 -321.155268)
			(xy 277.40613 -321.122037) (xy 277.452288 -321.095388) (xy 277.501902 -321.075916) (xy 277.553864 -321.064056)
			(xy 277.607014 -321.060073) (xy 277.660164 -321.064056) (xy 277.712126 -321.075916) (xy 277.76174 -321.095388)
			(xy 277.807898 -321.122037) (xy 277.849569 -321.155268) (xy 277.885821 -321.194339) (xy 277.915845 -321.238376)
			(xy 277.938971 -321.286397) (xy 277.954681 -321.337327) (xy 277.962624 -321.390031) (xy 277.963122 -321.41668)
			(xy 277.962624 -321.443329) (xy 277.954681 -321.496033) (xy 277.938971 -321.546963) (xy 277.915845 -321.594984)
			(xy 277.885821 -321.639021) (xy 277.849569 -321.678092) (xy 277.807898 -321.711323) (xy 277.76174 -321.737972)
			(xy 277.712126 -321.757444) (xy 277.660164 -321.769304) (xy 277.607014 -321.773288) (xy 277.553864 -321.769304)
			(xy 277.501902 -321.757444) (xy 277.452288 -321.737972) (xy 277.40613 -321.711323) (xy 277.364459 -321.678092)
			(xy 277.328207 -321.639021) (xy 277.298183 -321.594984) (xy 277.275057 -321.546963) (xy 277.259347 -321.496033)
			(xy 277.251404 -321.443329) (xy 274.518892 -321.443329) (xy 274.510949 -321.496033) (xy 274.495239 -321.546963)
			(xy 274.472113 -321.594984) (xy 274.442089 -321.639021) (xy 274.405837 -321.678092) (xy 274.364166 -321.711323)
			(xy 274.318008 -321.737972) (xy 274.268394 -321.757444) (xy 274.216432 -321.769304) (xy 274.163282 -321.773288)
			(xy 274.110132 -321.769304) (xy 274.05817 -321.757444) (xy 274.008556 -321.737972) (xy 273.962398 -321.711323)
			(xy 273.920727 -321.678092) (xy 273.884475 -321.639021) (xy 273.854451 -321.594984) (xy 273.831325 -321.546963)
			(xy 273.815615 -321.496033) (xy 273.807672 -321.443329) (xy 270.418824 -321.443329) (xy 270.410881 -321.496033)
			(xy 270.395171 -321.546963) (xy 270.372045 -321.594984) (xy 270.342021 -321.639021) (xy 270.305769 -321.678092)
			(xy 270.264098 -321.711323) (xy 270.21794 -321.737972) (xy 270.168326 -321.757444) (xy 270.116364 -321.769304)
			(xy 270.063214 -321.773288) (xy 270.010064 -321.769304) (xy 269.958102 -321.757444) (xy 269.908488 -321.737972)
			(xy 269.86233 -321.711323) (xy 269.820659 -321.678092) (xy 269.784407 -321.639021) (xy 269.754383 -321.594984)
			(xy 269.731257 -321.546963) (xy 269.715547 -321.496033) (xy 269.707604 -321.443329) (xy 266.975092 -321.443329)
			(xy 266.967149 -321.496033) (xy 266.951439 -321.546963) (xy 266.928313 -321.594984) (xy 266.898289 -321.639021)
			(xy 266.862037 -321.678092) (xy 266.820366 -321.711323) (xy 266.774208 -321.737972) (xy 266.724594 -321.757444)
			(xy 266.672632 -321.769304) (xy 266.619482 -321.773288) (xy 266.566332 -321.769304) (xy 266.51437 -321.757444)
			(xy 266.464756 -321.737972) (xy 266.418598 -321.711323) (xy 266.376927 -321.678092) (xy 266.340675 -321.639021)
			(xy 266.310651 -321.594984) (xy 266.287525 -321.546963) (xy 266.271815 -321.496033) (xy 266.263872 -321.443329)
			(xy 262.873991 -321.443329) (xy 262.872004 -321.469845) (xy 262.860146 -321.521803) (xy 262.840676 -321.571414)
			(xy 262.814029 -321.617568) (xy 262.780801 -321.659236) (xy 262.741735 -321.695486) (xy 262.697702 -321.725509)
			(xy 262.649686 -321.748634) (xy 262.59876 -321.764344) (xy 262.546061 -321.772289) (xy 262.519414 -321.772788)
			(xy 262.493178 -321.77236) (xy 262.441269 -321.764691) (xy 262.391052 -321.749473) (xy 262.343619 -321.727037)
			(xy 262.321548 -321.712844) (xy 262.309516 -321.705416) (xy 262.28261 -321.696766) (xy 262.254363 -321.69582)
			(xy 262.226938 -321.70265) (xy 262.202434 -321.716735) (xy 262.182729 -321.736995) (xy 262.169329 -321.761879)
			(xy 262.165846 -321.775582) (xy 262.159644 -321.801668) (xy 262.140428 -321.851723) (xy 262.113921 -321.898329)
			(xy 262.080723 -321.940433) (xy 262.041586 -321.977081) (xy 261.997395 -322.007444) (xy 261.949149 -322.030835)
			(xy 261.897941 -322.046726) (xy 261.844929 -322.054756) (xy 261.81812 -322.055236) (xy 261.79147 -322.054708)
			(xy 261.738765 -322.046767) (xy 261.687832 -322.031059) (xy 261.63981 -322.007935) (xy 261.59577 -321.977911)
			(xy 261.556697 -321.941659) (xy 261.523464 -321.899988) (xy 261.496813 -321.85383) (xy 261.47734 -321.804215)
			(xy 261.465479 -321.752251) (xy 261.461496 -321.6991) (xy 259.291893 -321.6991) (xy 259.276566 -321.711323)
			(xy 259.230408 -321.737972) (xy 259.180794 -321.757444) (xy 259.128832 -321.769304) (xy 259.075682 -321.773288)
			(xy 259.022532 -321.769304) (xy 258.97057 -321.757444) (xy 258.920956 -321.737972) (xy 258.874798 -321.711323)
			(xy 258.833127 -321.678092) (xy 258.796875 -321.639021) (xy 258.766851 -321.594984) (xy 258.743725 -321.546963)
			(xy 258.728015 -321.496033) (xy 258.720072 -321.443329) (xy 255.331224 -321.443329) (xy 255.323281 -321.496033)
			(xy 255.307571 -321.546963) (xy 255.284445 -321.594984) (xy 255.254421 -321.639021) (xy 255.218169 -321.678092)
			(xy 255.176498 -321.711323) (xy 255.13034 -321.737972) (xy 255.080726 -321.757444) (xy 255.028764 -321.769304)
			(xy 254.975614 -321.773288) (xy 254.922464 -321.769304) (xy 254.870502 -321.757444) (xy 254.820888 -321.737972)
			(xy 254.77473 -321.711323) (xy 254.733059 -321.678092) (xy 254.696807 -321.639021) (xy 254.666783 -321.594984)
			(xy 254.643657 -321.546963) (xy 254.627947 -321.496033) (xy 254.620004 -321.443329) (xy 254.4572 -321.443329)
			(xy 254.4572 -322.073757) (xy 280.75635 -322.073757) (xy 280.75635 -322.020459) (xy 280.764293 -321.967755)
			(xy 280.780003 -321.916825) (xy 280.803129 -321.868804) (xy 280.833153 -321.824767) (xy 280.869405 -321.785696)
			(xy 280.911076 -321.752465) (xy 280.957234 -321.725816) (xy 281.006848 -321.706344) (xy 281.05881 -321.694484)
			(xy 281.11196 -321.690501) (xy 281.16511 -321.694484) (xy 281.217072 -321.706344) (xy 281.266686 -321.725816)
			(xy 281.312844 -321.752465) (xy 281.354515 -321.785696) (xy 281.390767 -321.824767) (xy 281.420791 -321.868804)
			(xy 281.443917 -321.916825) (xy 281.459627 -321.967755) (xy 281.46757 -322.020459) (xy 281.468068 -322.047108)
			(xy 281.46757 -322.073757) (xy 281.459627 -322.126461) (xy 281.443917 -322.177391) (xy 281.420791 -322.225412)
			(xy 281.390767 -322.269449) (xy 281.354515 -322.30852) (xy 281.312844 -322.341751) (xy 281.266686 -322.3684)
			(xy 281.217072 -322.387872) (xy 281.16511 -322.399732) (xy 281.11196 -322.403716) (xy 281.05881 -322.399732)
			(xy 281.006848 -322.387872) (xy 280.957234 -322.3684) (xy 280.911076 -322.341751) (xy 280.869405 -322.30852)
			(xy 280.833153 -322.269449) (xy 280.803129 -322.225412) (xy 280.780003 -322.177391) (xy 280.764293 -322.126461)
			(xy 280.75635 -322.073757) (xy 254.4572 -322.073757) (xy 254.4572 -322.677007) (xy 288.747444 -322.677007)
			(xy 288.747444 -322.623709) (xy 288.755387 -322.571005) (xy 288.771097 -322.520075) (xy 288.794223 -322.472054)
			(xy 288.824247 -322.428017) (xy 288.860499 -322.388946) (xy 288.90217 -322.355715) (xy 288.948328 -322.329066)
			(xy 288.997942 -322.309594) (xy 289.049904 -322.297734) (xy 289.103054 -322.293751) (xy 289.156204 -322.297734)
			(xy 289.208166 -322.309594) (xy 289.25778 -322.329066) (xy 289.303938 -322.355715) (xy 289.345609 -322.388946)
			(xy 289.381861 -322.428017) (xy 289.411885 -322.472054) (xy 289.435011 -322.520075) (xy 289.436957 -322.526385)
			(xy 291.155364 -322.526385) (xy 291.155364 -322.473087) (xy 291.163307 -322.420383) (xy 291.179017 -322.369453)
			(xy 291.202143 -322.321432) (xy 291.232167 -322.277395) (xy 291.268419 -322.238324) (xy 291.31009 -322.205093)
			(xy 291.356248 -322.178444) (xy 291.405862 -322.158972) (xy 291.457824 -322.147112) (xy 291.510974 -322.143129)
			(xy 291.564124 -322.147112) (xy 291.616086 -322.158972) (xy 291.6657 -322.178444) (xy 291.711858 -322.205093)
			(xy 291.753529 -322.238324) (xy 291.789781 -322.277395) (xy 291.819805 -322.321432) (xy 291.842931 -322.369453)
			(xy 291.858641 -322.420383) (xy 291.866584 -322.473087) (xy 291.867082 -322.499736) (xy 291.866584 -322.526385)
			(xy 292.349164 -322.526385) (xy 292.349164 -322.473087) (xy 292.357107 -322.420383) (xy 292.372817 -322.369453)
			(xy 292.395943 -322.321432) (xy 292.425967 -322.277395) (xy 292.462219 -322.238324) (xy 292.50389 -322.205093)
			(xy 292.550048 -322.178444) (xy 292.599662 -322.158972) (xy 292.651624 -322.147112) (xy 292.704774 -322.143129)
			(xy 292.757924 -322.147112) (xy 292.809886 -322.158972) (xy 292.8595 -322.178444) (xy 292.905658 -322.205093)
			(xy 292.947329 -322.238324) (xy 292.983581 -322.277395) (xy 293.013605 -322.321432) (xy 293.036731 -322.369453)
			(xy 293.052441 -322.420383) (xy 293.060384 -322.473087) (xy 293.060882 -322.499736) (xy 293.060384 -322.526385)
			(xy 294.736764 -322.526385) (xy 294.736764 -322.473087) (xy 294.744707 -322.420383) (xy 294.760417 -322.369453)
			(xy 294.783543 -322.321432) (xy 294.813567 -322.277395) (xy 294.849819 -322.238324) (xy 294.89149 -322.205093)
			(xy 294.937648 -322.178444) (xy 294.987262 -322.158972) (xy 295.039224 -322.147112) (xy 295.092374 -322.143129)
			(xy 295.145524 -322.147112) (xy 295.197486 -322.158972) (xy 295.2471 -322.178444) (xy 295.293258 -322.205093)
			(xy 295.334929 -322.238324) (xy 295.371181 -322.277395) (xy 295.401205 -322.321432) (xy 295.424331 -322.369453)
			(xy 295.440041 -322.420383) (xy 295.447984 -322.473087) (xy 295.448482 -322.499736) (xy 295.447984 -322.526385)
			(xy 295.440041 -322.579089) (xy 295.429268 -322.614015) (xy 298.568608 -322.614015) (xy 298.568608 -322.560717)
			(xy 298.576551 -322.508013) (xy 298.592261 -322.457083) (xy 298.615387 -322.409062) (xy 298.645411 -322.365025)
			(xy 298.681663 -322.325954) (xy 298.723334 -322.292723) (xy 298.769492 -322.266074) (xy 298.819106 -322.246602)
			(xy 298.871068 -322.234742) (xy 298.924218 -322.230759) (xy 298.977368 -322.234742) (xy 299.02933 -322.246602)
			(xy 299.078944 -322.266074) (xy 299.125102 -322.292723) (xy 299.166773 -322.325954) (xy 299.203025 -322.365025)
			(xy 299.233049 -322.409062) (xy 299.256175 -322.457083) (xy 299.271885 -322.508013) (xy 299.279828 -322.560717)
			(xy 299.280326 -322.587366) (xy 299.279828 -322.614015) (xy 299.271885 -322.666719) (xy 299.256175 -322.717649)
			(xy 299.233049 -322.76567) (xy 299.203025 -322.809707) (xy 299.166773 -322.848778) (xy 299.125102 -322.882009)
			(xy 299.078944 -322.908658) (xy 299.02933 -322.92813) (xy 298.977368 -322.93999) (xy 298.924218 -322.943974)
			(xy 298.871068 -322.93999) (xy 298.819106 -322.92813) (xy 298.769492 -322.908658) (xy 298.723334 -322.882009)
			(xy 298.681663 -322.848778) (xy 298.645411 -322.809707) (xy 298.615387 -322.76567) (xy 298.592261 -322.717649)
			(xy 298.576551 -322.666719) (xy 298.568608 -322.614015) (xy 295.429268 -322.614015) (xy 295.424331 -322.630019)
			(xy 295.401205 -322.67804) (xy 295.371181 -322.722077) (xy 295.334929 -322.761148) (xy 295.293258 -322.794379)
			(xy 295.2471 -322.821028) (xy 295.197486 -322.8405) (xy 295.145524 -322.85236) (xy 295.092374 -322.856344)
			(xy 295.039224 -322.85236) (xy 294.987262 -322.8405) (xy 294.937648 -322.821028) (xy 294.89149 -322.794379)
			(xy 294.849819 -322.761148) (xy 294.813567 -322.722077) (xy 294.783543 -322.67804) (xy 294.760417 -322.630019)
			(xy 294.744707 -322.579089) (xy 294.736764 -322.526385) (xy 293.060384 -322.526385) (xy 293.052441 -322.579089)
			(xy 293.036731 -322.630019) (xy 293.013605 -322.67804) (xy 292.983581 -322.722077) (xy 292.947329 -322.761148)
			(xy 292.905658 -322.794379) (xy 292.8595 -322.821028) (xy 292.809886 -322.8405) (xy 292.757924 -322.85236)
			(xy 292.704774 -322.856344) (xy 292.651624 -322.85236) (xy 292.599662 -322.8405) (xy 292.550048 -322.821028)
			(xy 292.50389 -322.794379) (xy 292.462219 -322.761148) (xy 292.425967 -322.722077) (xy 292.395943 -322.67804)
			(xy 292.372817 -322.630019) (xy 292.357107 -322.579089) (xy 292.349164 -322.526385) (xy 291.866584 -322.526385)
			(xy 291.858641 -322.579089) (xy 291.842931 -322.630019) (xy 291.819805 -322.67804) (xy 291.789781 -322.722077)
			(xy 291.753529 -322.761148) (xy 291.711858 -322.794379) (xy 291.6657 -322.821028) (xy 291.616086 -322.8405)
			(xy 291.564124 -322.85236) (xy 291.510974 -322.856344) (xy 291.457824 -322.85236) (xy 291.405862 -322.8405)
			(xy 291.356248 -322.821028) (xy 291.31009 -322.794379) (xy 291.268419 -322.761148) (xy 291.232167 -322.722077)
			(xy 291.202143 -322.67804) (xy 291.179017 -322.630019) (xy 291.163307 -322.579089) (xy 291.155364 -322.526385)
			(xy 289.436957 -322.526385) (xy 289.450721 -322.571005) (xy 289.458664 -322.623709) (xy 289.459162 -322.650358)
			(xy 289.458664 -322.677007) (xy 289.450721 -322.729711) (xy 289.435011 -322.780641) (xy 289.411885 -322.828662)
			(xy 289.381861 -322.872699) (xy 289.345609 -322.91177) (xy 289.303938 -322.945001) (xy 289.25778 -322.97165)
			(xy 289.208166 -322.991122) (xy 289.156204 -323.002982) (xy 289.103054 -323.006966) (xy 289.049904 -323.002982)
			(xy 288.997942 -322.991122) (xy 288.948328 -322.97165) (xy 288.90217 -322.945001) (xy 288.860499 -322.91177)
			(xy 288.824247 -322.872699) (xy 288.794223 -322.828662) (xy 288.771097 -322.780641) (xy 288.755387 -322.729711)
			(xy 288.747444 -322.677007) (xy 254.4572 -322.677007) (xy 254.4572 -323.4179) (xy 257.227639 -323.4179)
			(xy 257.231621 -323.364758) (xy 257.24348 -323.312803) (xy 257.262949 -323.263196) (xy 257.289594 -323.217044)
			(xy 257.32282 -323.175379) (xy 257.361885 -323.139132) (xy 257.405916 -323.109111) (xy 257.453929 -323.085988)
			(xy 257.504853 -323.07028) (xy 257.557548 -323.062336) (xy 257.584194 -323.061838) (xy 257.60922 -323.062245)
			(xy 257.658779 -323.069254) (xy 257.706868 -323.083133) (xy 257.752539 -323.10361) (xy 257.794893 -323.130281)
			(xy 257.833095 -323.16262) (xy 257.866391 -323.199991) (xy 257.880612 -323.220588) (xy 257.888945 -323.232217)
			(xy 257.910781 -323.250684) (xy 257.936878 -323.262376) (xy 257.965194 -323.266377) (xy 257.99351 -323.262376)
			(xy 258.019607 -323.250684) (xy 258.041443 -323.232217) (xy 258.049776 -323.220588) (xy 258.064018 -323.200007)
			(xy 258.097311 -323.162638) (xy 258.13551 -323.1303) (xy 258.17786 -323.103629) (xy 258.223528 -323.083152)
			(xy 258.271614 -323.069272) (xy 258.32117 -323.062263) (xy 258.346194 -323.061838) (xy 258.372849 -323.062219)
			(xy 258.425563 -323.070164) (xy 258.476505 -323.085876) (xy 258.524536 -323.109006) (xy 258.568582 -323.139036)
			(xy 258.607662 -323.175295) (xy 258.6409 -323.216974) (xy 258.667555 -323.263142) (xy 258.687031 -323.312766)
			(xy 258.698894 -323.364739) (xy 258.702878 -323.4179) (xy 258.702016 -323.4294) (xy 259.456968 -323.4294)
			(xy 259.460951 -323.376251) (xy 259.47281 -323.32429) (xy 259.49228 -323.274676) (xy 259.518927 -323.228517)
			(xy 259.552155 -323.186846) (xy 259.591222 -323.150591) (xy 259.635256 -323.120564) (xy 259.683274 -323.097434)
			(xy 259.734202 -323.081719) (xy 259.786903 -323.073769) (xy 259.813552 -323.073268) (xy 259.839959 -323.07379)
			(xy 259.892195 -323.081584) (xy 259.942707 -323.097008) (xy 259.990387 -323.119723) (xy 260.034188 -323.149232)
			(xy 260.073151 -323.184887) (xy 260.090158 -323.205094) (xy 260.100095 -323.216487) (xy 260.125148 -323.233378)
			(xy 260.154044 -323.242209) (xy 260.18426 -323.242209) (xy 260.213156 -323.233378) (xy 260.238209 -323.216487)
			(xy 260.248146 -323.205094) (xy 260.265172 -323.184902) (xy 260.304129 -323.149239) (xy 260.347925 -323.119721)
			(xy 260.3956 -323.096994) (xy 260.44611 -323.081558) (xy 260.498344 -323.073751) (xy 260.524752 -323.073268)
			(xy 260.551404 -323.073786) (xy 260.604113 -323.081724) (xy 260.655049 -323.09743) (xy 260.703076 -323.120552)
			(xy 260.74712 -323.150576) (xy 260.786197 -323.186828) (xy 260.819433 -323.2285) (xy 260.846087 -323.274661)
			(xy 260.865562 -323.324279) (xy 260.877424 -323.376246) (xy 260.881408 -323.4294) (xy 262.936768 -323.4294)
			(xy 262.940751 -323.376251) (xy 262.95261 -323.32429) (xy 262.97208 -323.274676) (xy 262.998727 -323.228517)
			(xy 263.031955 -323.186846) (xy 263.071022 -323.150591) (xy 263.115056 -323.120564) (xy 263.163074 -323.097434)
			(xy 263.214002 -323.081719) (xy 263.266703 -323.073769) (xy 263.293352 -323.073268) (xy 263.319759 -323.07379)
			(xy 263.371995 -323.081584) (xy 263.422507 -323.097008) (xy 263.470187 -323.119723) (xy 263.513988 -323.149232)
			(xy 263.552951 -323.184887) (xy 263.569958 -323.205094) (xy 263.579895 -323.216487) (xy 263.604948 -323.233378)
			(xy 263.633844 -323.242209) (xy 263.66406 -323.242209) (xy 263.692956 -323.233378) (xy 263.718009 -323.216487)
			(xy 263.727946 -323.205094) (xy 263.744972 -323.184902) (xy 263.783929 -323.149239) (xy 263.827725 -323.119721)
			(xy 263.8754 -323.096994) (xy 263.92591 -323.081558) (xy 263.978144 -323.073751) (xy 264.004552 -323.073268)
			(xy 264.031204 -323.073786) (xy 264.083913 -323.081724) (xy 264.134849 -323.09743) (xy 264.182876 -323.120552)
			(xy 264.22692 -323.150576) (xy 264.265997 -323.186828) (xy 264.299233 -323.2285) (xy 264.325887 -323.274661)
			(xy 264.345362 -323.324279) (xy 264.357224 -323.376246) (xy 264.361208 -323.4294) (xy 267.000768 -323.4294)
			(xy 267.004751 -323.376251) (xy 267.01661 -323.32429) (xy 267.03608 -323.274676) (xy 267.062727 -323.228517)
			(xy 267.095955 -323.186846) (xy 267.135022 -323.150591) (xy 267.179056 -323.120564) (xy 267.227074 -323.097434)
			(xy 267.278002 -323.081719) (xy 267.330703 -323.073769) (xy 267.357352 -323.073268) (xy 267.383759 -323.07379)
			(xy 267.435995 -323.081584) (xy 267.486507 -323.097008) (xy 267.534187 -323.119723) (xy 267.577988 -323.149232)
			(xy 267.616951 -323.184887) (xy 267.633958 -323.205094) (xy 267.643895 -323.216487) (xy 267.668948 -323.233378)
			(xy 267.697844 -323.242209) (xy 267.72806 -323.242209) (xy 267.756956 -323.233378) (xy 267.782009 -323.216487)
			(xy 267.791946 -323.205094) (xy 267.808972 -323.184902) (xy 267.847929 -323.149239) (xy 267.891725 -323.119721)
			(xy 267.9394 -323.096994) (xy 267.98991 -323.081558) (xy 268.042144 -323.073751) (xy 268.068552 -323.073268)
			(xy 268.095204 -323.073786) (xy 268.147913 -323.081724) (xy 268.198849 -323.09743) (xy 268.246876 -323.120552)
			(xy 268.29092 -323.150576) (xy 268.329997 -323.186828) (xy 268.363233 -323.2285) (xy 268.389887 -323.274661)
			(xy 268.409362 -323.324279) (xy 268.421224 -323.376246) (xy 268.425208 -323.4294) (xy 270.480568 -323.4294)
			(xy 270.484551 -323.376251) (xy 270.49641 -323.32429) (xy 270.51588 -323.274676) (xy 270.542527 -323.228517)
			(xy 270.575755 -323.186846) (xy 270.614822 -323.150591) (xy 270.658856 -323.120564) (xy 270.706874 -323.097434)
			(xy 270.757802 -323.081719) (xy 270.810503 -323.073769) (xy 270.837152 -323.073268) (xy 270.863559 -323.07379)
			(xy 270.915795 -323.081584) (xy 270.966307 -323.097008) (xy 271.013987 -323.119723) (xy 271.057788 -323.149232)
			(xy 271.096751 -323.184887) (xy 271.113758 -323.205094) (xy 271.123695 -323.216487) (xy 271.148748 -323.233378)
			(xy 271.177644 -323.242209) (xy 271.20786 -323.242209) (xy 271.236756 -323.233378) (xy 271.261809 -323.216487)
			(xy 271.271746 -323.205094) (xy 271.288772 -323.184902) (xy 271.327729 -323.149239) (xy 271.371525 -323.119721)
			(xy 271.4192 -323.096994) (xy 271.46971 -323.081558) (xy 271.521944 -323.073751) (xy 271.548352 -323.073268)
			(xy 271.575004 -323.073786) (xy 271.627713 -323.081724) (xy 271.678649 -323.09743) (xy 271.726676 -323.120552)
			(xy 271.77072 -323.150576) (xy 271.809797 -323.186828) (xy 271.843033 -323.2285) (xy 271.869687 -323.274661)
			(xy 271.889162 -323.324279) (xy 271.901024 -323.376246) (xy 271.905008 -323.4294) (xy 274.544568 -323.4294)
			(xy 274.548551 -323.376251) (xy 274.56041 -323.32429) (xy 274.57988 -323.274676) (xy 274.606527 -323.228517)
			(xy 274.639755 -323.186846) (xy 274.678822 -323.150591) (xy 274.722856 -323.120564) (xy 274.770874 -323.097434)
			(xy 274.821802 -323.081719) (xy 274.874503 -323.073769) (xy 274.901152 -323.073268) (xy 274.927559 -323.07379)
			(xy 274.979795 -323.081584) (xy 275.030307 -323.097008) (xy 275.077987 -323.119723) (xy 275.121788 -323.149232)
			(xy 275.160751 -323.184887) (xy 275.177758 -323.205094) (xy 275.187695 -323.216487) (xy 275.212748 -323.233378)
			(xy 275.241644 -323.242209) (xy 275.27186 -323.242209) (xy 275.300756 -323.233378) (xy 275.325809 -323.216487)
			(xy 275.335746 -323.205094) (xy 275.352772 -323.184902) (xy 275.391729 -323.149239) (xy 275.435525 -323.119721)
			(xy 275.4832 -323.096994) (xy 275.53371 -323.081558) (xy 275.585944 -323.073751) (xy 275.612352 -323.073268)
			(xy 275.639004 -323.073786) (xy 275.691713 -323.081724) (xy 275.742649 -323.09743) (xy 275.790676 -323.120552)
			(xy 275.83472 -323.150576) (xy 275.873797 -323.186828) (xy 275.907033 -323.2285) (xy 275.933687 -323.274661)
			(xy 275.953162 -323.324279) (xy 275.965024 -323.376246) (xy 275.969008 -323.4294) (xy 278.024368 -323.4294)
			(xy 278.028351 -323.376251) (xy 278.04021 -323.32429) (xy 278.05968 -323.274676) (xy 278.086327 -323.228517)
			(xy 278.119555 -323.186846) (xy 278.158622 -323.150591) (xy 278.202656 -323.120564) (xy 278.250674 -323.097434)
			(xy 278.301602 -323.081719) (xy 278.354303 -323.073769) (xy 278.380952 -323.073268) (xy 278.407359 -323.07379)
			(xy 278.459595 -323.081584) (xy 278.510107 -323.097008) (xy 278.557787 -323.119723) (xy 278.601588 -323.149232)
			(xy 278.640551 -323.184887) (xy 278.657558 -323.205094) (xy 278.667495 -323.216487) (xy 278.692548 -323.233378)
			(xy 278.721444 -323.242209) (xy 278.75166 -323.242209) (xy 278.780556 -323.233378) (xy 278.805609 -323.216487)
			(xy 278.815546 -323.205094) (xy 278.832572 -323.184902) (xy 278.871529 -323.149239) (xy 278.915325 -323.119721)
			(xy 278.963 -323.096994) (xy 279.01351 -323.081558) (xy 279.065744 -323.073751) (xy 279.092152 -323.073268)
			(xy 279.118804 -323.073786) (xy 279.171513 -323.081724) (xy 279.222449 -323.09743) (xy 279.270476 -323.120552)
			(xy 279.31452 -323.150576) (xy 279.353597 -323.186828) (xy 279.386833 -323.2285) (xy 279.413487 -323.274661)
			(xy 279.432962 -323.324279) (xy 279.444824 -323.376246) (xy 279.448808 -323.4294) (xy 282.088368 -323.4294)
			(xy 282.092351 -323.376251) (xy 282.10421 -323.32429) (xy 282.12368 -323.274676) (xy 282.150327 -323.228517)
			(xy 282.183555 -323.186846) (xy 282.222622 -323.150591) (xy 282.266656 -323.120564) (xy 282.314674 -323.097434)
			(xy 282.365602 -323.081719) (xy 282.418303 -323.073769) (xy 282.444952 -323.073268) (xy 282.471359 -323.07379)
			(xy 282.523595 -323.081584) (xy 282.574107 -323.097008) (xy 282.621787 -323.119723) (xy 282.665588 -323.149232)
			(xy 282.704551 -323.184887) (xy 282.721558 -323.205094) (xy 282.731495 -323.216487) (xy 282.756548 -323.233378)
			(xy 282.785444 -323.242209) (xy 282.81566 -323.242209) (xy 282.844556 -323.233378) (xy 282.869609 -323.216487)
			(xy 282.879546 -323.205094) (xy 282.896572 -323.184902) (xy 282.935529 -323.149239) (xy 282.979325 -323.119721)
			(xy 283.027 -323.096994) (xy 283.07751 -323.081558) (xy 283.129744 -323.073751) (xy 283.156152 -323.073268)
			(xy 283.182804 -323.073786) (xy 283.235513 -323.081724) (xy 283.286449 -323.09743) (xy 283.334476 -323.120552)
			(xy 283.37852 -323.150576) (xy 283.417597 -323.186828) (xy 283.450833 -323.2285) (xy 283.477487 -323.274661)
			(xy 283.496962 -323.324279) (xy 283.508824 -323.376246) (xy 283.512808 -323.4294) (xy 285.695168 -323.4294)
			(xy 285.699151 -323.376251) (xy 285.71101 -323.32429) (xy 285.73048 -323.274676) (xy 285.757127 -323.228517)
			(xy 285.790355 -323.186846) (xy 285.829422 -323.150591) (xy 285.873456 -323.120564) (xy 285.921474 -323.097434)
			(xy 285.972402 -323.081719) (xy 286.025103 -323.073769) (xy 286.051752 -323.073268) (xy 286.078159 -323.07379)
			(xy 286.130395 -323.081584) (xy 286.180907 -323.097008) (xy 286.228587 -323.119723) (xy 286.272388 -323.149232)
			(xy 286.311351 -323.184887) (xy 286.328358 -323.205094) (xy 286.338295 -323.216487) (xy 286.363348 -323.233378)
			(xy 286.392244 -323.242209) (xy 286.42246 -323.242209) (xy 286.451356 -323.233378) (xy 286.476409 -323.216487)
			(xy 286.486346 -323.205094) (xy 286.503372 -323.184902) (xy 286.542329 -323.149239) (xy 286.586125 -323.119721)
			(xy 286.6338 -323.096994) (xy 286.68431 -323.081558) (xy 286.736544 -323.073751) (xy 286.762952 -323.073268)
			(xy 286.789604 -323.073786) (xy 286.842313 -323.081724) (xy 286.893249 -323.09743) (xy 286.941276 -323.120552)
			(xy 286.98532 -323.150576) (xy 287.024397 -323.186828) (xy 287.057633 -323.2285) (xy 287.084287 -323.274661)
			(xy 287.103762 -323.324279) (xy 287.115624 -323.376246) (xy 287.119608 -323.4294) (xy 287.115624 -323.482554)
			(xy 287.103762 -323.534521) (xy 287.084287 -323.584139) (xy 287.057633 -323.6303) (xy 287.024397 -323.671972)
			(xy 286.98532 -323.708224) (xy 286.941276 -323.738248) (xy 286.893249 -323.76137) (xy 286.842313 -323.777076)
			(xy 286.789604 -323.785014) (xy 286.762952 -323.785484) (xy 286.736544 -323.784977) (xy 286.684307 -323.777182)
			(xy 286.633794 -323.761757) (xy 286.586114 -323.739038) (xy 286.542313 -323.709526) (xy 286.503352 -323.673867)
			(xy 286.486346 -323.653658) (xy 286.476409 -323.642265) (xy 286.451356 -323.625374) (xy 286.42246 -323.616543)
			(xy 286.392244 -323.616543) (xy 286.363348 -323.625374) (xy 286.338295 -323.642265) (xy 286.328358 -323.653658)
			(xy 286.311318 -323.673838) (xy 286.272366 -323.709504) (xy 286.228573 -323.739025) (xy 286.1809 -323.761754)
			(xy 286.130392 -323.777192) (xy 286.078159 -323.785) (xy 286.051752 -323.785484) (xy 286.025103 -323.785031)
			(xy 285.972402 -323.777081) (xy 285.921474 -323.761366) (xy 285.873456 -323.738236) (xy 285.829422 -323.708209)
			(xy 285.790355 -323.671954) (xy 285.757127 -323.630283) (xy 285.73048 -323.584124) (xy 285.71101 -323.53451)
			(xy 285.699151 -323.482549) (xy 285.695168 -323.4294) (xy 283.512808 -323.4294) (xy 283.508824 -323.482554)
			(xy 283.496962 -323.534521) (xy 283.477487 -323.584139) (xy 283.450833 -323.6303) (xy 283.417597 -323.671972)
			(xy 283.37852 -323.708224) (xy 283.334476 -323.738248) (xy 283.286449 -323.76137) (xy 283.235513 -323.777076)
			(xy 283.182804 -323.785014) (xy 283.156152 -323.785484) (xy 283.129744 -323.784977) (xy 283.077507 -323.777182)
			(xy 283.026994 -323.761757) (xy 282.979314 -323.739038) (xy 282.935513 -323.709526) (xy 282.896552 -323.673867)
			(xy 282.879546 -323.653658) (xy 282.869609 -323.642265) (xy 282.844556 -323.625374) (xy 282.81566 -323.616543)
			(xy 282.785444 -323.616543) (xy 282.756548 -323.625374) (xy 282.731495 -323.642265) (xy 282.721558 -323.653658)
			(xy 282.704518 -323.673838) (xy 282.665566 -323.709504) (xy 282.621773 -323.739025) (xy 282.5741 -323.761754)
			(xy 282.523592 -323.777192) (xy 282.471359 -323.785) (xy 282.444952 -323.785484) (xy 282.418303 -323.785031)
			(xy 282.365602 -323.777081) (xy 282.314674 -323.761366) (xy 282.266656 -323.738236) (xy 282.222622 -323.708209)
			(xy 282.183555 -323.671954) (xy 282.150327 -323.630283) (xy 282.12368 -323.584124) (xy 282.10421 -323.53451)
			(xy 282.092351 -323.482549) (xy 282.088368 -323.4294) (xy 279.448808 -323.4294) (xy 279.444824 -323.482554)
			(xy 279.432962 -323.534521) (xy 279.413487 -323.584139) (xy 279.386833 -323.6303) (xy 279.353597 -323.671972)
			(xy 279.31452 -323.708224) (xy 279.270476 -323.738248) (xy 279.222449 -323.76137) (xy 279.171513 -323.777076)
			(xy 279.118804 -323.785014) (xy 279.092152 -323.785484) (xy 279.065744 -323.784977) (xy 279.013507 -323.777182)
			(xy 278.962994 -323.761757) (xy 278.915314 -323.739038) (xy 278.871513 -323.709526) (xy 278.832552 -323.673867)
			(xy 278.815546 -323.653658) (xy 278.805609 -323.642265) (xy 278.780556 -323.625374) (xy 278.75166 -323.616543)
			(xy 278.721444 -323.616543) (xy 278.692548 -323.625374) (xy 278.667495 -323.642265) (xy 278.657558 -323.653658)
			(xy 278.640518 -323.673838) (xy 278.601566 -323.709504) (xy 278.557773 -323.739025) (xy 278.5101 -323.761754)
			(xy 278.459592 -323.777192) (xy 278.407359 -323.785) (xy 278.380952 -323.785484) (xy 278.354303 -323.785031)
			(xy 278.301602 -323.777081) (xy 278.250674 -323.761366) (xy 278.202656 -323.738236) (xy 278.158622 -323.708209)
			(xy 278.119555 -323.671954) (xy 278.086327 -323.630283) (xy 278.05968 -323.584124) (xy 278.04021 -323.53451)
			(xy 278.028351 -323.482549) (xy 278.024368 -323.4294) (xy 275.969008 -323.4294) (xy 275.965024 -323.482554)
			(xy 275.953162 -323.534521) (xy 275.933687 -323.584139) (xy 275.907033 -323.6303) (xy 275.873797 -323.671972)
			(xy 275.83472 -323.708224) (xy 275.790676 -323.738248) (xy 275.742649 -323.76137) (xy 275.691713 -323.777076)
			(xy 275.639004 -323.785014) (xy 275.612352 -323.785484) (xy 275.585944 -323.784977) (xy 275.533707 -323.777182)
			(xy 275.483194 -323.761757) (xy 275.435514 -323.739038) (xy 275.391713 -323.709526) (xy 275.352752 -323.673867)
			(xy 275.335746 -323.653658) (xy 275.325809 -323.642265) (xy 275.300756 -323.625374) (xy 275.27186 -323.616543)
			(xy 275.241644 -323.616543) (xy 275.212748 -323.625374) (xy 275.187695 -323.642265) (xy 275.177758 -323.653658)
			(xy 275.160718 -323.673838) (xy 275.121766 -323.709504) (xy 275.077973 -323.739025) (xy 275.0303 -323.761754)
			(xy 274.979792 -323.777192) (xy 274.927559 -323.785) (xy 274.901152 -323.785484) (xy 274.874503 -323.785031)
			(xy 274.821802 -323.777081) (xy 274.770874 -323.761366) (xy 274.722856 -323.738236) (xy 274.678822 -323.708209)
			(xy 274.639755 -323.671954) (xy 274.606527 -323.630283) (xy 274.57988 -323.584124) (xy 274.56041 -323.53451)
			(xy 274.548551 -323.482549) (xy 274.544568 -323.4294) (xy 271.905008 -323.4294) (xy 271.901024 -323.482554)
			(xy 271.889162 -323.534521) (xy 271.869687 -323.584139) (xy 271.843033 -323.6303) (xy 271.809797 -323.671972)
			(xy 271.77072 -323.708224) (xy 271.726676 -323.738248) (xy 271.678649 -323.76137) (xy 271.627713 -323.777076)
			(xy 271.575004 -323.785014) (xy 271.548352 -323.785484) (xy 271.521944 -323.784977) (xy 271.469707 -323.777182)
			(xy 271.419194 -323.761757) (xy 271.371514 -323.739038) (xy 271.327713 -323.709526) (xy 271.288752 -323.673867)
			(xy 271.271746 -323.653658) (xy 271.261809 -323.642265) (xy 271.236756 -323.625374) (xy 271.20786 -323.616543)
			(xy 271.177644 -323.616543) (xy 271.148748 -323.625374) (xy 271.123695 -323.642265) (xy 271.113758 -323.653658)
			(xy 271.096718 -323.673838) (xy 271.057766 -323.709504) (xy 271.013973 -323.739025) (xy 270.9663 -323.761754)
			(xy 270.915792 -323.777192) (xy 270.863559 -323.785) (xy 270.837152 -323.785484) (xy 270.810503 -323.785031)
			(xy 270.757802 -323.777081) (xy 270.706874 -323.761366) (xy 270.658856 -323.738236) (xy 270.614822 -323.708209)
			(xy 270.575755 -323.671954) (xy 270.542527 -323.630283) (xy 270.51588 -323.584124) (xy 270.49641 -323.53451)
			(xy 270.484551 -323.482549) (xy 270.480568 -323.4294) (xy 268.425208 -323.4294) (xy 268.421224 -323.482554)
			(xy 268.409362 -323.534521) (xy 268.389887 -323.584139) (xy 268.363233 -323.6303) (xy 268.329997 -323.671972)
			(xy 268.29092 -323.708224) (xy 268.246876 -323.738248) (xy 268.198849 -323.76137) (xy 268.147913 -323.777076)
			(xy 268.095204 -323.785014) (xy 268.068552 -323.785484) (xy 268.042144 -323.784977) (xy 267.989907 -323.777182)
			(xy 267.939394 -323.761757) (xy 267.891714 -323.739038) (xy 267.847913 -323.709526) (xy 267.808952 -323.673867)
			(xy 267.791946 -323.653658) (xy 267.782009 -323.642265) (xy 267.756956 -323.625374) (xy 267.72806 -323.616543)
			(xy 267.697844 -323.616543) (xy 267.668948 -323.625374) (xy 267.643895 -323.642265) (xy 267.633958 -323.653658)
			(xy 267.616918 -323.673838) (xy 267.577966 -323.709504) (xy 267.534173 -323.739025) (xy 267.4865 -323.761754)
			(xy 267.435992 -323.777192) (xy 267.383759 -323.785) (xy 267.357352 -323.785484) (xy 267.330703 -323.785031)
			(xy 267.278002 -323.777081) (xy 267.227074 -323.761366) (xy 267.179056 -323.738236) (xy 267.135022 -323.708209)
			(xy 267.095955 -323.671954) (xy 267.062727 -323.630283) (xy 267.03608 -323.584124) (xy 267.01661 -323.53451)
			(xy 267.004751 -323.482549) (xy 267.000768 -323.4294) (xy 264.361208 -323.4294) (xy 264.357224 -323.482554)
			(xy 264.345362 -323.534521) (xy 264.325887 -323.584139) (xy 264.299233 -323.6303) (xy 264.265997 -323.671972)
			(xy 264.22692 -323.708224) (xy 264.182876 -323.738248) (xy 264.134849 -323.76137) (xy 264.083913 -323.777076)
			(xy 264.031204 -323.785014) (xy 264.004552 -323.785484) (xy 263.978144 -323.784977) (xy 263.925907 -323.777182)
			(xy 263.875394 -323.761757) (xy 263.827714 -323.739038) (xy 263.783913 -323.709526) (xy 263.744952 -323.673867)
			(xy 263.727946 -323.653658) (xy 263.718009 -323.642265) (xy 263.692956 -323.625374) (xy 263.66406 -323.616543)
			(xy 263.633844 -323.616543) (xy 263.604948 -323.625374) (xy 263.579895 -323.642265) (xy 263.569958 -323.653658)
			(xy 263.552918 -323.673838) (xy 263.513966 -323.709504) (xy 263.470173 -323.739025) (xy 263.4225 -323.761754)
			(xy 263.371992 -323.777192) (xy 263.319759 -323.785) (xy 263.293352 -323.785484) (xy 263.266703 -323.785031)
			(xy 263.214002 -323.777081) (xy 263.163074 -323.761366) (xy 263.115056 -323.738236) (xy 263.071022 -323.708209)
			(xy 263.031955 -323.671954) (xy 262.998727 -323.630283) (xy 262.97208 -323.584124) (xy 262.95261 -323.53451)
			(xy 262.940751 -323.482549) (xy 262.936768 -323.4294) (xy 260.881408 -323.4294) (xy 260.877424 -323.482554)
			(xy 260.865562 -323.534521) (xy 260.846087 -323.584139) (xy 260.819433 -323.6303) (xy 260.786197 -323.671972)
			(xy 260.74712 -323.708224) (xy 260.703076 -323.738248) (xy 260.655049 -323.76137) (xy 260.604113 -323.777076)
			(xy 260.551404 -323.785014) (xy 260.524752 -323.785484) (xy 260.498344 -323.784977) (xy 260.446107 -323.777182)
			(xy 260.395594 -323.761757) (xy 260.347914 -323.739038) (xy 260.304113 -323.709526) (xy 260.265152 -323.673867)
			(xy 260.248146 -323.653658) (xy 260.238209 -323.642265) (xy 260.213156 -323.625374) (xy 260.18426 -323.616543)
			(xy 260.154044 -323.616543) (xy 260.125148 -323.625374) (xy 260.100095 -323.642265) (xy 260.090158 -323.653658)
			(xy 260.073118 -323.673838) (xy 260.034166 -323.709504) (xy 259.990373 -323.739025) (xy 259.9427 -323.761754)
			(xy 259.892192 -323.777192) (xy 259.839959 -323.785) (xy 259.813552 -323.785484) (xy 259.786903 -323.785031)
			(xy 259.734202 -323.777081) (xy 259.683274 -323.761366) (xy 259.635256 -323.738236) (xy 259.591222 -323.708209)
			(xy 259.552155 -323.671954) (xy 259.518927 -323.630283) (xy 259.49228 -323.584124) (xy 259.47281 -323.53451)
			(xy 259.460951 -323.482549) (xy 259.456968 -323.4294) (xy 258.702016 -323.4294) (xy 258.698894 -323.471061)
			(xy 258.687031 -323.523034) (xy 258.667555 -323.572658) (xy 258.6409 -323.618826) (xy 258.607662 -323.660505)
			(xy 258.568582 -323.696764) (xy 258.524536 -323.726794) (xy 258.476505 -323.749924) (xy 258.425563 -323.765636)
			(xy 258.372849 -323.773581) (xy 258.346194 -323.774054) (xy 258.321168 -323.773659) (xy 258.271608 -323.766649)
			(xy 258.223519 -323.752768) (xy 258.177847 -323.732289) (xy 258.135493 -323.705616) (xy 258.097292 -323.673275)
			(xy 258.063996 -323.635902) (xy 258.049776 -323.615304) (xy 258.041443 -323.603675) (xy 258.019607 -323.585208)
			(xy 257.99351 -323.573516) (xy 257.965194 -323.569515) (xy 257.936878 -323.573516) (xy 257.910781 -323.585208)
			(xy 257.888945 -323.603675) (xy 257.880612 -323.615304) (xy 257.866407 -323.635912) (xy 257.833104 -323.673276)
			(xy 257.794898 -323.705609) (xy 257.752541 -323.732274) (xy 257.706868 -323.752747) (xy 257.658778 -323.766623)
			(xy 257.60922 -323.77363) (xy 257.584194 -323.774054) (xy 257.557548 -323.773464) (xy 257.504853 -323.76552)
			(xy 257.453929 -323.749812) (xy 257.405916 -323.726689) (xy 257.361885 -323.696668) (xy 257.32282 -323.660421)
			(xy 257.289594 -323.618756) (xy 257.262949 -323.572604) (xy 257.24348 -323.522997) (xy 257.231621 -323.471042)
			(xy 257.227639 -323.4179) (xy 254.4572 -323.4179) (xy 254.4572 -323.8246) (xy 254.889 -324.2564)
			(xy 288.9758 -324.2564) (xy 292.0238 -327.3044) (xy 293.9542 -327.3044)
		)
		(stroke
			(width 0)
			(type solid)
		)
		(fill yes)
		(layer "In2.Cu")
		(net "P3V3_AUX")
	)
	(gr_poly
		(pts
			(xy 84.35848 -33.238948) (xy 84.35848 -32.87268) (xy 83.749388 -32.263842) (xy 83.728609 -32.242227)
			(xy 83.693372 -32.193722) (xy 83.666152 -32.140303) (xy 83.64762 -32.083285) (xy 83.638231 -32.024071)
			(xy 83.637628 -31.994094) (xy 83.637628 -21.233384) (xy 83.402424 -20.99818) (xy 82.37474 -20.99818)
			(xy 82.360199 -20.998642) (xy 82.332293 -21.00683) (xy 82.307829 -21.022555) (xy 82.288791 -21.04454)
			(xy 82.276724 -21.071) (xy 82.272607 -21.099789) (xy 82.276774 -21.128571) (xy 82.288887 -21.15501)
			(xy 82.298032 -21.166328) (xy 82.315622 -21.187255) (xy 82.345255 -21.233194) (xy 82.368029 -21.282892)
			(xy 82.383478 -21.335331) (xy 82.391284 -21.389438) (xy 82.391758 -21.416772) (xy 82.391272 -21.444023)
			(xy 82.383516 -21.497971) (xy 82.368161 -21.550266) (xy 82.345519 -21.599843) (xy 82.316053 -21.645693)
			(xy 82.280362 -21.686884) (xy 82.239171 -21.722575) (xy 82.193321 -21.752041) (xy 82.143744 -21.774683)
			(xy 82.091449 -21.790038) (xy 82.037501 -21.797794) (xy 81.982999 -21.797794) (xy 81.929051 -21.790038)
			(xy 81.876756 -21.774683) (xy 81.827179 -21.752041) (xy 81.781329 -21.722575) (xy 81.740138 -21.686884)
			(xy 81.704447 -21.645693) (xy 81.674981 -21.599843) (xy 81.652339 -21.550266) (xy 81.636984 -21.497971)
			(xy 81.629228 -21.444023) (xy 81.628742 -21.416772) (xy 81.629265 -21.38795) (xy 81.63793 -21.33096)
			(xy 81.655073 -21.275924) (xy 81.680304 -21.224095) (xy 81.713048 -21.176654) (xy 81.752559 -21.134681)
			(xy 81.797938 -21.099132) (xy 81.822798 -21.08454) (xy 81.834992 -21.077119) (xy 81.855005 -21.056781)
			(xy 81.868613 -21.031701) (xy 81.874754 -21.003836) (xy 81.872948 -20.97536) (xy 81.863337 -20.948494)
			(xy 81.84667 -20.925334) (xy 81.835752 -20.916138) (xy 81.813517 -20.897955) (xy 81.774246 -20.85604)
			(xy 81.741707 -20.808709) (xy 81.716637 -20.757032) (xy 81.699603 -20.702178) (xy 81.690991 -20.645391)
			(xy 81.690464 -20.616672) (xy 81.690464 -20.252436) (xy 81.689952 -20.237898) (xy 81.681773 -20.209995)
			(xy 81.666065 -20.185526) (xy 81.644103 -20.166471) (xy 81.617662 -20.154374) (xy 81.588885 -20.150214)
			(xy 81.5601 -20.154327) (xy 81.5467 -20.15998) (xy 81.521852 -20.170727) (xy 81.469881 -20.185884)
			(xy 81.416288 -20.193534) (xy 81.38922 -20.194016) (xy 81.361966 -20.193554) (xy 81.308011 -20.185799)
			(xy 81.25571 -20.170445) (xy 81.206126 -20.147803) (xy 81.16027 -20.118335) (xy 81.119074 -20.08264)
			(xy 81.083377 -20.041446) (xy 81.053907 -19.995591) (xy 81.031262 -19.946009) (xy 81.015905 -19.893708)
			(xy 81.008147 -19.839754) (xy 81.008147 -19.785246) (xy 81.015905 -19.731292) (xy 81.031262 -19.678991)
			(xy 81.053907 -19.629409) (xy 81.083377 -19.583554) (xy 81.119074 -19.54236) (xy 81.16027 -19.506665)
			(xy 81.206126 -19.477197) (xy 81.25571 -19.454555) (xy 81.308011 -19.439201) (xy 81.361966 -19.431446)
			(xy 81.38922 -19.431) (xy 81.420159 -19.431601) (xy 81.481228 -19.441583) (xy 81.539887 -19.461282)
			(xy 81.567528 -19.475196) (xy 81.580702 -19.481621) (xy 81.609424 -19.487404) (xy 81.638606 -19.484789)
			(xy 81.665842 -19.473991) (xy 81.688888 -19.4559) (xy 81.705845 -19.432006) (xy 81.711038 -19.4183)
			(xy 81.719979 -19.393576) (xy 81.743701 -19.346658) (xy 81.773646 -19.303445) (xy 81.809246 -19.264758)
			(xy 81.849825 -19.231331) (xy 81.894614 -19.203798) (xy 81.942761 -19.182682) (xy 81.993353 -19.168384)
			(xy 82.045431 -19.161174) (xy 82.071718 -19.160744) (xy 82.098963 -19.161209) (xy 82.152899 -19.168969)
			(xy 82.20518 -19.184329) (xy 82.254742 -19.206976) (xy 82.300575 -19.236449) (xy 82.341745 -19.272146)
			(xy 82.377413 -19.313341) (xy 82.406853 -19.359195) (xy 82.429465 -19.408773) (xy 82.444788 -19.461065)
			(xy 82.45251 -19.515006) (xy 82.452972 -19.542252) (xy 82.452972 -20.235164) (xy 83.560412 -20.235164)
			(xy 83.590392 -20.235723) (xy 83.649612 -20.245108) (xy 83.706634 -20.263645) (xy 83.760053 -20.290878)
			(xy 83.808551 -20.326135) (xy 83.83016 -20.346924) (xy 84.184998 -20.702016) (xy 84.195978 -20.712255)
			(xy 84.222435 -20.726411) (xy 84.251864 -20.732274) (xy 84.281727 -20.729337) (xy 84.309449 -20.717853)
			(xy 84.332642 -20.698812) (xy 84.349304 -20.673857) (xy 84.358 -20.645138) (xy 84.35848 -20.630134)
			(xy 84.35848 -20.005548) (xy 82.50428 -18.151348) (xy 82.41411 -18.151348) (xy 82.399503 -18.151822)
			(xy 82.371481 -18.160082) (xy 82.346939 -18.175931) (xy 82.327883 -18.198075) (xy 82.315868 -18.224704)
			(xy 82.311876 -18.253644) (xy 82.316233 -18.282532) (xy 82.328582 -18.309008) (xy 82.33791 -18.320258)
			(xy 82.355852 -18.341287) (xy 82.386114 -18.387544) (xy 82.409387 -18.437682) (xy 82.425184 -18.490654)
			(xy 82.433174 -18.54535) (xy 82.433668 -18.572988) (xy 82.433182 -18.600239) (xy 82.425426 -18.654187)
			(xy 82.410071 -18.706482) (xy 82.387429 -18.756059) (xy 82.357963 -18.801909) (xy 82.322272 -18.8431)
			(xy 82.281081 -18.878791) (xy 82.235231 -18.908257) (xy 82.185654 -18.930899) (xy 82.133359 -18.946254)
			(xy 82.079411 -18.95401) (xy 82.024909 -18.95401) (xy 81.970961 -18.946254) (xy 81.918666 -18.930899)
			(xy 81.869089 -18.908257) (xy 81.823239 -18.878791) (xy 81.782048 -18.8431) (xy 81.746357 -18.801909)
			(xy 81.716891 -18.756059) (xy 81.694249 -18.706482) (xy 81.678894 -18.654187) (xy 81.671138 -18.600239)
			(xy 81.670652 -18.572988) (xy 81.671138 -18.545347) (xy 81.679109 -18.490644) (xy 81.694897 -18.437666)
			(xy 81.718171 -18.387523) (xy 81.748444 -18.341268) (xy 81.76641 -18.320258) (xy 81.775724 -18.309)
			(xy 81.78808 -18.282535) (xy 81.792441 -18.253655) (xy 81.788451 -18.224722) (xy 81.776435 -18.198101)
			(xy 81.757377 -18.175968) (xy 81.732834 -18.160134) (xy 81.704814 -18.151893) (xy 81.69021 -18.151348)
			(xy 81.00568 -18.151348) (xy 80.934814 -18.080482) (xy 80.92186 -18.076926) (xy 80.895503 -18.069109)
			(xy 80.84576 -18.045712) (xy 80.800764 -18.014133) (xy 80.78089 -17.995138) (xy 80.428338 -17.642586)
			(xy 80.418251 -17.633158) (xy 80.394215 -17.619593) (xy 80.367426 -17.61296) (xy 80.339838 -17.613742)
			(xy 80.313467 -17.621883) (xy 80.290238 -17.636788) (xy 80.271849 -17.657368) (xy 80.26527 -17.66951)
			(xy 80.253359 -17.692743) (xy 80.224174 -17.736033) (xy 80.18937 -17.774949) (xy 80.169766 -17.792192)
			(xy 80.158867 -17.802093) (xy 80.142789 -17.826747) (xy 80.1344 -17.854959) (xy 80.134393 -17.884392)
			(xy 80.142769 -17.912608) (xy 80.158834 -17.93727) (xy 80.169766 -17.947132) (xy 80.19047 -17.965349)
			(xy 80.226932 -18.006721) (xy 80.257058 -18.052912) (xy 80.280221 -18.102958) (xy 80.295938 -18.155817)
			(xy 80.303882 -18.210389) (xy 80.304386 -18.237962) (xy 80.3039 -18.265213) (xy 80.296144 -18.319161)
			(xy 80.280789 -18.371456) (xy 80.258147 -18.421033) (xy 80.228681 -18.466883) (xy 80.19299 -18.508074)
			(xy 80.151799 -18.543765) (xy 80.105949 -18.573231) (xy 80.056372 -18.595873) (xy 80.004077 -18.611228)
			(xy 79.950129 -18.618984) (xy 79.895627 -18.618984) (xy 79.841679 -18.611228) (xy 79.789384 -18.595873)
			(xy 79.739807 -18.573231) (xy 79.693957 -18.543765) (xy 79.652766 -18.508074) (xy 79.617075 -18.466883)
			(xy 79.587609 -18.421033) (xy 79.564967 -18.371456) (xy 79.549612 -18.319161) (xy 79.541856 -18.265213)
			(xy 79.54137 -18.237962) (xy 79.541852 -18.210386) (xy 79.549787 -18.155808) (xy 79.565499 -18.102941)
			(xy 79.588661 -18.052889) (xy 79.61879 -18.006694) (xy 79.655258 -17.965321) (xy 79.67599 -17.947132)
			(xy 79.686882 -17.937234) (xy 79.702945 -17.912587) (xy 79.711321 -17.884385) (xy 79.711313 -17.854966)
			(xy 79.702925 -17.826768) (xy 79.68685 -17.802129) (xy 79.67599 -17.792192) (xy 79.655286 -17.773975)
			(xy 79.618826 -17.732601) (xy 79.588701 -17.68641) (xy 79.565537 -17.636365) (xy 79.549819 -17.583506)
			(xy 79.541872 -17.528935) (xy 79.54137 -17.501362) (xy 79.541827 -17.474782) (xy 79.549202 -17.422135)
			(xy 79.563818 -17.371024) (xy 79.585393 -17.322438) (xy 79.613506 -17.27732) (xy 79.647614 -17.236544)
			(xy 79.687056 -17.200901) (xy 79.731065 -17.171082) (xy 79.75473 -17.15897) (xy 79.766911 -17.152455)
			(xy 79.787504 -17.134059) (xy 79.802415 -17.110818) (xy 79.810554 -17.084432) (xy 79.811327 -17.056831)
			(xy 79.804677 -17.030031) (xy 79.791089 -17.005992) (xy 79.781654 -16.995902) (xy 78.105508 -15.319756)
			(xy 78.01356 -15.319756) (xy 78.01356 -15.3797) (xy 78.016862 -15.388336) (xy 78.028209 -15.420764)
			(xy 78.040473 -15.488355) (xy 78.041246 -15.522702) (xy 78.040759 -15.550276) (xy 78.032817 -15.60485)
			(xy 78.017099 -15.657711) (xy 77.993932 -15.707757) (xy 77.9638 -15.753946) (xy 77.92733 -15.795313)
			(xy 77.906626 -15.813532) (xy 77.895727 -15.823429) (xy 77.879652 -15.848079) (xy 77.871266 -15.876287)
			(xy 77.871267 -15.905715) (xy 77.879653 -15.933923) (xy 77.895729 -15.958572) (xy 77.906626 -15.968472)
			(xy 77.927335 -15.986686) (xy 77.963807 -16.028056) (xy 77.993944 -16.074245) (xy 78.017117 -16.124291)
			(xy 78.032844 -16.177152) (xy 78.040798 -16.231727) (xy 78.041246 -16.259302) (xy 78.04076 -16.286553)
			(xy 78.033004 -16.340501) (xy 78.017649 -16.392796) (xy 77.995007 -16.442373) (xy 77.965541 -16.488223)
			(xy 77.92985 -16.529414) (xy 77.888659 -16.565105) (xy 77.842809 -16.594571) (xy 77.793232 -16.617213)
			(xy 77.740937 -16.632568) (xy 77.686989 -16.640324) (xy 77.632487 -16.640324) (xy 77.578539 -16.632568)
			(xy 77.526244 -16.617213) (xy 77.476667 -16.594571) (xy 77.430817 -16.565105) (xy 77.389626 -16.529414)
			(xy 77.353935 -16.488223) (xy 77.324469 -16.442373) (xy 77.301827 -16.392796) (xy 77.286472 -16.340501)
			(xy 77.278716 -16.286553) (xy 77.27823 -16.259302) (xy 77.278716 -16.231727) (xy 77.286658 -16.177153)
			(xy 77.302375 -16.124291) (xy 77.32554 -16.074244) (xy 77.355671 -16.028053) (xy 77.392139 -15.986683)
			(xy 77.41285 -15.968472) (xy 77.423752 -15.958576) (xy 77.439832 -15.933927) (xy 77.448221 -15.905717)
			(xy 77.448221 -15.876286) (xy 77.439833 -15.848076) (xy 77.423753 -15.823426) (xy 77.41285 -15.813532)
			(xy 77.392142 -15.795317) (xy 77.355671 -15.753947) (xy 77.325536 -15.707758) (xy 77.302364 -15.657712)
			(xy 77.286637 -15.604851) (xy 77.278684 -15.550277) (xy 77.27823 -15.522702) (xy 77.278525 -15.502478)
			(xy 77.282855 -15.462262) (xy 77.286866 -15.442438) (xy 77.289456 -15.427539) (xy 77.286792 -15.397433)
			(xy 77.275441 -15.369421) (xy 77.256397 -15.345951) (xy 77.231323 -15.329075) (xy 77.202411 -15.320267)
			(xy 77.187298 -15.319756) (xy 76.02728 -15.319756) (xy 76.001642 -15.319247) (xy 75.951036 -15.310973)
			(xy 75.902418 -15.294676) (xy 75.857049 -15.270778) (xy 75.836272 -15.255748) (xy 70.56628 -15.255748)
			(xy 69.334634 -14.024356) (xy 67.682872 -14.024356) (xy 67.668533 -14.024877) (xy 67.641002 -14.03291)
			(xy 67.616787 -14.048278) (xy 67.597798 -14.069771) (xy 67.585531 -14.095695) (xy 67.580953 -14.124007)
			(xy 67.584423 -14.152475) (xy 67.589654 -14.165834) (xy 67.599391 -14.189648) (xy 67.61309 -14.239239)
			(xy 67.619986 -14.290223) (xy 67.620388 -14.315948) (xy 67.619902 -14.343199) (xy 67.612146 -14.397147)
			(xy 67.596791 -14.449442) (xy 67.574149 -14.499019) (xy 67.544683 -14.544869) (xy 67.508992 -14.58606)
			(xy 67.467801 -14.621751) (xy 67.421951 -14.651217) (xy 67.372374 -14.673859) (xy 67.320079 -14.689214)
			(xy 67.266131 -14.69697) (xy 67.211629 -14.69697) (xy 67.157681 -14.689214) (xy 67.105386 -14.673859)
			(xy 67.055809 -14.651217) (xy 67.009959 -14.621751) (xy 66.968768 -14.58606) (xy 66.933077 -14.544869)
			(xy 66.903611 -14.499019) (xy 66.880969 -14.449442) (xy 66.865614 -14.397147) (xy 66.857858 -14.343199)
			(xy 66.857372 -14.315948) (xy 66.857794 -14.290225) (xy 66.864698 -14.239244) (xy 66.878374 -14.189649)
			(xy 66.888106 -14.165834) (xy 66.893278 -14.152461) (xy 66.896748 -14.124012) (xy 66.892172 -14.09572)
			(xy 66.879912 -14.069816) (xy 66.860933 -14.048341) (xy 66.836732 -14.032989) (xy 66.809217 -14.02497)
			(xy 66.794888 -14.024356) (xy 63.847726 -14.024356) (xy 62.539894 -15.331948) (xy 66.856862 -15.331948)
			(xy 66.860933 -15.276326) (xy 66.873059 -15.221889) (xy 66.892982 -15.169798) (xy 66.920278 -15.121163)
			(xy 66.954364 -15.07702) (xy 66.994513 -15.038311) (xy 67.039871 -15.00586) (xy 67.089471 -14.980359)
			(xy 67.142255 -14.962352) (xy 67.197098 -14.952222) (xy 67.252832 -14.950185) (xy 67.308269 -14.956285)
			(xy 67.362226 -14.970391) (xy 67.413555 -14.992203) (xy 67.461161 -15.021257) (xy 67.504029 -15.056932)
			(xy 67.541246 -15.098469) (xy 67.572019 -15.144982) (xy 67.595691 -15.195479) (xy 67.611759 -15.248886)
			(xy 67.619879 -15.304062) (xy 67.620388 -15.331948) (xy 67.619879 -15.359834) (xy 67.611759 -15.41501)
			(xy 67.595691 -15.468417) (xy 67.572019 -15.518914) (xy 67.541246 -15.565427) (xy 67.504029 -15.606964)
			(xy 67.461161 -15.642639) (xy 67.413555 -15.671693) (xy 67.362226 -15.693505) (xy 67.308269 -15.707611)
			(xy 67.252832 -15.713711) (xy 67.197098 -15.711674) (xy 67.142255 -15.701544) (xy 67.089471 -15.683537)
			(xy 67.039871 -15.658036) (xy 66.994513 -15.625585) (xy 66.954364 -15.586876) (xy 66.920278 -15.542733)
			(xy 66.892982 -15.494098) (xy 66.873059 -15.442007) (xy 66.860933 -15.38757) (xy 66.856862 -15.331948)
			(xy 62.539894 -15.331948) (xy 62.46368 -15.408148) (xy 62.46368 -16.347948) (xy 66.856862 -16.347948)
			(xy 66.860933 -16.292326) (xy 66.873059 -16.237889) (xy 66.892982 -16.185798) (xy 66.920278 -16.137163)
			(xy 66.954364 -16.09302) (xy 66.994513 -16.054311) (xy 67.039871 -16.02186) (xy 67.089471 -15.996359)
			(xy 67.142255 -15.978352) (xy 67.197098 -15.968222) (xy 67.252832 -15.966185) (xy 67.308269 -15.972285)
			(xy 67.362226 -15.986391) (xy 67.413555 -16.008203) (xy 67.461161 -16.037257) (xy 67.504029 -16.072932)
			(xy 67.541246 -16.114469) (xy 67.572019 -16.160982) (xy 67.595691 -16.211479) (xy 67.611759 -16.264886)
			(xy 67.619879 -16.320062) (xy 67.620388 -16.347948) (xy 67.619879 -16.375834) (xy 67.611759 -16.43101)
			(xy 67.595691 -16.484417) (xy 67.572019 -16.534914) (xy 67.541246 -16.581427) (xy 67.504029 -16.622964)
			(xy 67.461161 -16.658639) (xy 67.413555 -16.687693) (xy 67.362226 -16.709505) (xy 67.308269 -16.723611)
			(xy 67.252832 -16.729711) (xy 67.197098 -16.727674) (xy 67.142255 -16.717544) (xy 67.089471 -16.699537)
			(xy 67.039871 -16.674036) (xy 66.994513 -16.641585) (xy 66.954364 -16.602876) (xy 66.920278 -16.558733)
			(xy 66.892982 -16.510098) (xy 66.873059 -16.458007) (xy 66.860933 -16.40357) (xy 66.856862 -16.347948)
			(xy 62.46368 -16.347948) (xy 62.46368 -16.899382) (xy 62.4879 -16.912694) (xy 62.532569 -16.945236)
			(xy 62.572075 -16.983884) (xy 62.605591 -17.027827) (xy 62.632414 -17.076148) (xy 62.651984 -17.127833)
			(xy 62.663892 -17.181801) (xy 62.667886 -17.236922) (xy 62.663885 -17.292043) (xy 62.651972 -17.34601)
			(xy 62.632395 -17.397693) (xy 62.605566 -17.44601) (xy 62.572046 -17.48995) (xy 62.532535 -17.528593)
			(xy 62.487862 -17.56113) (xy 62.46368 -17.574514) (xy 62.46368 -17.684242) (xy 63.088772 -17.684242)
			(xy 63.092843 -17.62862) (xy 63.104969 -17.574183) (xy 63.124892 -17.522092) (xy 63.152188 -17.473457)
			(xy 63.186274 -17.429314) (xy 63.226423 -17.390605) (xy 63.271781 -17.358154) (xy 63.321381 -17.332653)
			(xy 63.374165 -17.314646) (xy 63.429008 -17.304516) (xy 63.484742 -17.302479) (xy 63.540179 -17.308579)
			(xy 63.594136 -17.322685) (xy 63.645465 -17.344497) (xy 63.693071 -17.373551) (xy 63.735939 -17.409226)
			(xy 63.773156 -17.450763) (xy 63.803929 -17.497276) (xy 63.827601 -17.547773) (xy 63.843669 -17.60118)
			(xy 63.851789 -17.656356) (xy 63.852298 -17.684242) (xy 63.851789 -17.712128) (xy 63.843669 -17.767304)
			(xy 63.827601 -17.820711) (xy 63.803929 -17.871208) (xy 63.773156 -17.917721) (xy 63.735939 -17.959258)
			(xy 63.693071 -17.994933) (xy 63.645465 -18.023987) (xy 63.594136 -18.045799) (xy 63.540179 -18.059905)
			(xy 63.484742 -18.066005) (xy 63.429008 -18.063968) (xy 63.374165 -18.053838) (xy 63.321381 -18.035831)
			(xy 63.271781 -18.01033) (xy 63.226423 -17.977879) (xy 63.186274 -17.93917) (xy 63.152188 -17.895027)
			(xy 63.124892 -17.846392) (xy 63.104969 -17.794301) (xy 63.092843 -17.739864) (xy 63.088772 -17.684242)
			(xy 62.46368 -17.684242) (xy 62.46368 -18.297144) (xy 67.30873 -18.297144) (xy 67.309215 -18.269774)
			(xy 67.317027 -18.215596) (xy 67.332511 -18.163093) (xy 67.355349 -18.113345) (xy 67.38507 -18.067378)
			(xy 67.40271 -18.046446) (xy 67.411904 -18.035087) (xy 67.424085 -18.00854) (xy 67.428265 -17.979633)
			(xy 67.424104 -17.950724) (xy 67.41194 -17.924169) (xy 67.40271 -17.912842) (xy 67.385079 -17.891904)
			(xy 67.355365 -17.845933) (xy 67.332528 -17.796187) (xy 67.317035 -17.743687) (xy 67.309205 -17.689513)
			(xy 67.30873 -17.662144) (xy 67.309216 -17.634893) (xy 67.316972 -17.580945) (xy 67.332327 -17.52865)
			(xy 67.354969 -17.479073) (xy 67.384435 -17.433223) (xy 67.420126 -17.392032) (xy 67.461317 -17.356341)
			(xy 67.507167 -17.326875) (xy 67.556744 -17.304233) (xy 67.609039 -17.288878) (xy 67.662987 -17.281122)
			(xy 67.717489 -17.281122) (xy 67.771437 -17.288878) (xy 67.823732 -17.304233) (xy 67.873309 -17.326875)
			(xy 67.919159 -17.356341) (xy 67.96035 -17.392032) (xy 67.996041 -17.433223) (xy 68.025507 -17.479073)
			(xy 68.048149 -17.52865) (xy 68.063504 -17.580945) (xy 68.07126 -17.634893) (xy 68.071746 -17.662144)
			(xy 68.07126 -17.689514) (xy 68.063449 -17.743692) (xy 68.047965 -17.796196) (xy 68.025128 -17.845943)
			(xy 67.995406 -17.89191) (xy 67.977766 -17.912842) (xy 67.968489 -17.924139) (xy 67.956321 -17.950708)
			(xy 67.952159 -17.979633) (xy 67.95634 -18.008556) (xy 67.968526 -18.035117) (xy 67.977766 -18.046446)
			(xy 67.995388 -18.067392) (xy 68.025104 -18.11336) (xy 68.04686 -18.160746) (xy 74.02525 -18.160746)
			(xy 74.029321 -18.105124) (xy 74.041447 -18.050687) (xy 74.06137 -17.998596) (xy 74.088666 -17.949961)
			(xy 74.122752 -17.905818) (xy 74.162901 -17.867109) (xy 74.208259 -17.834658) (xy 74.257859 -17.809157)
			(xy 74.310643 -17.79115) (xy 74.365486 -17.78102) (xy 74.42122 -17.778983) (xy 74.476657 -17.785083)
			(xy 74.530614 -17.799189) (xy 74.581943 -17.821001) (xy 74.629549 -17.850055) (xy 74.672417 -17.88573)
			(xy 74.709634 -17.927267) (xy 74.740407 -17.97378) (xy 74.764079 -18.024277) (xy 74.780147 -18.077684)
			(xy 74.788267 -18.13286) (xy 74.788776 -18.160746) (xy 74.788461 -18.178018) (xy 77.15072 -18.178018)
			(xy 77.154791 -18.122396) (xy 77.166917 -18.067959) (xy 77.18684 -18.015868) (xy 77.214136 -17.967233)
			(xy 77.248222 -17.92309) (xy 77.288371 -17.884381) (xy 77.333729 -17.85193) (xy 77.383329 -17.826429)
			(xy 77.436113 -17.808422) (xy 77.490956 -17.798292) (xy 77.54669 -17.796255) (xy 77.602127 -17.802355)
			(xy 77.656084 -17.816461) (xy 77.707413 -17.838273) (xy 77.755019 -17.867327) (xy 77.797887 -17.903002)
			(xy 77.835104 -17.944539) (xy 77.865877 -17.991052) (xy 77.889549 -18.041549) (xy 77.905617 -18.094956)
			(xy 77.913737 -18.150132) (xy 77.914246 -18.178018) (xy 77.913737 -18.205904) (xy 77.905617 -18.26108)
			(xy 77.889549 -18.314487) (xy 77.865877 -18.364984) (xy 77.835104 -18.411497) (xy 77.797887 -18.453034)
			(xy 77.755019 -18.488709) (xy 77.707413 -18.517763) (xy 77.656084 -18.539575) (xy 77.602127 -18.553681)
			(xy 77.54669 -18.559781) (xy 77.490956 -18.557744) (xy 77.436113 -18.547614) (xy 77.383329 -18.529607)
			(xy 77.333729 -18.504106) (xy 77.288371 -18.471655) (xy 77.248222 -18.432946) (xy 77.214136 -18.388803)
			(xy 77.18684 -18.340168) (xy 77.166917 -18.288077) (xy 77.154791 -18.23364) (xy 77.15072 -18.178018)
			(xy 74.788461 -18.178018) (xy 74.788267 -18.188632) (xy 74.780147 -18.243808) (xy 74.764079 -18.297215)
			(xy 74.740407 -18.347712) (xy 74.709634 -18.394225) (xy 74.672417 -18.435762) (xy 74.629549 -18.471437)
			(xy 74.581943 -18.500491) (xy 74.530614 -18.522303) (xy 74.476657 -18.536409) (xy 74.42122 -18.542509)
			(xy 74.365486 -18.540472) (xy 74.310643 -18.530342) (xy 74.257859 -18.512335) (xy 74.208259 -18.486834)
			(xy 74.162901 -18.454383) (xy 74.122752 -18.415674) (xy 74.088666 -18.371531) (xy 74.06137 -18.322896)
			(xy 74.041447 -18.270805) (xy 74.029321 -18.216368) (xy 74.02525 -18.160746) (xy 68.04686 -18.160746)
			(xy 68.047943 -18.163104) (xy 68.063438 -18.215602) (xy 68.07127 -18.269776) (xy 68.071746 -18.297144)
			(xy 68.07126 -18.324395) (xy 68.063504 -18.378343) (xy 68.048149 -18.430638) (xy 68.025507 -18.480215)
			(xy 67.996041 -18.526065) (xy 67.96035 -18.567256) (xy 67.919159 -18.602947) (xy 67.873309 -18.632413)
			(xy 67.823732 -18.655055) (xy 67.771437 -18.67041) (xy 67.717489 -18.678166) (xy 67.662987 -18.678166)
			(xy 67.609039 -18.67041) (xy 67.556744 -18.655055) (xy 67.507167 -18.632413) (xy 67.461317 -18.602947)
			(xy 67.420126 -18.567256) (xy 67.384435 -18.526065) (xy 67.354969 -18.480215) (xy 67.332327 -18.430638)
			(xy 67.316972 -18.378343) (xy 67.309216 -18.324395) (xy 67.30873 -18.297144) (xy 62.46368 -18.297144)
			(xy 62.46368 -19.220942) (xy 76.404722 -19.220942) (xy 76.408793 -19.16532) (xy 76.420919 -19.110883)
			(xy 76.440842 -19.058792) (xy 76.468138 -19.010157) (xy 76.502224 -18.966014) (xy 76.542373 -18.927305)
			(xy 76.587731 -18.894854) (xy 76.637331 -18.869353) (xy 76.690115 -18.851346) (xy 76.744958 -18.841216)
			(xy 76.800692 -18.839179) (xy 76.856129 -18.845279) (xy 76.910086 -18.859385) (xy 76.961415 -18.881197)
			(xy 77.009021 -18.910251) (xy 77.051889 -18.945926) (xy 77.089106 -18.987463) (xy 77.119879 -19.033976)
			(xy 77.143551 -19.084473) (xy 77.159619 -19.13788) (xy 77.167739 -19.193056) (xy 77.168248 -19.220942)
			(xy 77.167739 -19.248828) (xy 77.163657 -19.276568) (xy 78.474568 -19.276568) (xy 78.478639 -19.220946)
			(xy 78.490765 -19.166509) (xy 78.510688 -19.114418) (xy 78.537984 -19.065783) (xy 78.57207 -19.02164)
			(xy 78.612219 -18.982931) (xy 78.657577 -18.95048) (xy 78.707177 -18.924979) (xy 78.759961 -18.906972)
			(xy 78.814804 -18.896842) (xy 78.870538 -18.894805) (xy 78.925975 -18.900905) (xy 78.979932 -18.915011)
			(xy 79.031261 -18.936823) (xy 79.078867 -18.965877) (xy 79.121735 -19.001552) (xy 79.158952 -19.043089)
			(xy 79.189725 -19.089602) (xy 79.213397 -19.140099) (xy 79.229465 -19.193506) (xy 79.237585 -19.248682)
			(xy 79.238094 -19.276568) (xy 79.237585 -19.304454) (xy 79.229465 -19.35963) (xy 79.213397 -19.413037)
			(xy 79.189725 -19.463534) (xy 79.158952 -19.510047) (xy 79.121735 -19.551584) (xy 79.078867 -19.587259)
			(xy 79.031261 -19.616313) (xy 78.979932 -19.638125) (xy 78.925975 -19.652231) (xy 78.870538 -19.658331)
			(xy 78.814804 -19.656294) (xy 78.759961 -19.646164) (xy 78.707177 -19.628157) (xy 78.657577 -19.602656)
			(xy 78.612219 -19.570205) (xy 78.57207 -19.531496) (xy 78.537984 -19.487353) (xy 78.510688 -19.438718)
			(xy 78.490765 -19.386627) (xy 78.478639 -19.33219) (xy 78.474568 -19.276568) (xy 77.163657 -19.276568)
			(xy 77.159619 -19.304004) (xy 77.143551 -19.357411) (xy 77.119879 -19.407908) (xy 77.089106 -19.454421)
			(xy 77.051889 -19.495958) (xy 77.009021 -19.531633) (xy 76.961415 -19.560687) (xy 76.910086 -19.582499)
			(xy 76.856129 -19.596605) (xy 76.800692 -19.602705) (xy 76.744958 -19.600668) (xy 76.690115 -19.590538)
			(xy 76.637331 -19.572531) (xy 76.587731 -19.54703) (xy 76.542373 -19.514579) (xy 76.502224 -19.47587)
			(xy 76.468138 -19.431727) (xy 76.440842 -19.383092) (xy 76.420919 -19.331001) (xy 76.408793 -19.276564)
			(xy 76.404722 -19.220942) (xy 62.46368 -19.220942) (xy 62.46368 -20.326604) (xy 67.33413 -20.326604)
			(xy 67.334591 -20.299234) (xy 67.342409 -20.245054) (xy 67.357899 -20.19255) (xy 67.380742 -20.142804)
			(xy 67.410468 -20.096837) (xy 67.42811 -20.075906) (xy 67.437342 -20.064576) (xy 67.449519 -20.038019)
			(xy 67.453692 -20.009103) (xy 67.449521 -19.980187) (xy 67.437345 -19.95363) (xy 67.42811 -19.942302)
			(xy 67.41046 -19.921379) (xy 67.380749 -19.875404) (xy 67.357915 -19.825654) (xy 67.342427 -19.773151)
			(xy 67.334602 -19.718974) (xy 67.33413 -19.691604) (xy 67.334616 -19.664353) (xy 67.342372 -19.610405)
			(xy 67.357727 -19.55811) (xy 67.380369 -19.508533) (xy 67.409835 -19.462683) (xy 67.445526 -19.421492)
			(xy 67.486717 -19.385801) (xy 67.532567 -19.356335) (xy 67.582144 -19.333693) (xy 67.634439 -19.318338)
			(xy 67.688387 -19.310582) (xy 67.742889 -19.310582) (xy 67.796837 -19.318338) (xy 67.849132 -19.333693)
			(xy 67.898709 -19.356335) (xy 67.944559 -19.385801) (xy 67.98575 -19.421492) (xy 68.021441 -19.462683)
			(xy 68.050907 -19.508533) (xy 68.073549 -19.55811) (xy 68.088904 -19.610405) (xy 68.09666 -19.664353)
			(xy 68.097146 -19.691604) (xy 68.096695 -19.718975) (xy 68.088876 -19.773155) (xy 68.073384 -19.825659)
			(xy 68.050538 -19.875406) (xy 68.02081 -19.921371) (xy 68.003166 -19.942302) (xy 67.993928 -19.953628)
			(xy 67.981755 -19.980187) (xy 67.977585 -20.009103) (xy 67.981757 -20.038019) (xy 67.993931 -20.064578)
			(xy 68.003166 -20.075906) (xy 68.020816 -20.096829) (xy 68.050527 -20.142804) (xy 68.073362 -20.192554)
			(xy 68.08885 -20.245056) (xy 68.096674 -20.299234) (xy 68.097146 -20.326604) (xy 68.09666 -20.353855)
			(xy 68.088904 -20.407803) (xy 68.073549 -20.460098) (xy 68.050907 -20.509675) (xy 68.021441 -20.555525)
			(xy 67.98575 -20.596716) (xy 67.944559 -20.632407) (xy 67.898709 -20.661873) (xy 67.849132 -20.684515)
			(xy 67.796837 -20.69987) (xy 67.742889 -20.707626) (xy 67.688387 -20.707626) (xy 67.634439 -20.69987)
			(xy 67.582144 -20.684515) (xy 67.532567 -20.661873) (xy 67.486717 -20.632407) (xy 67.445526 -20.596716)
			(xy 67.409835 -20.555525) (xy 67.380369 -20.509675) (xy 67.357727 -20.460098) (xy 67.342372 -20.407803)
			(xy 67.334616 -20.353855) (xy 67.33413 -20.326604) (xy 62.46368 -20.326604) (xy 62.46368 -20.944078)
			(xy 76.224382 -20.944078) (xy 76.228453 -20.888456) (xy 76.240579 -20.834019) (xy 76.260502 -20.781928)
			(xy 76.287798 -20.733293) (xy 76.321884 -20.68915) (xy 76.362033 -20.650441) (xy 76.407391 -20.61799)
			(xy 76.456991 -20.592489) (xy 76.509775 -20.574482) (xy 76.564618 -20.564352) (xy 76.620352 -20.562315)
			(xy 76.675789 -20.568415) (xy 76.729746 -20.582521) (xy 76.781075 -20.604333) (xy 76.828681 -20.633387)
			(xy 76.871549 -20.669062) (xy 76.908766 -20.710599) (xy 76.939539 -20.757112) (xy 76.963211 -20.807609)
			(xy 76.979279 -20.861016) (xy 76.987399 -20.916192) (xy 76.987908 -20.944078) (xy 76.987399 -20.971964)
			(xy 76.979279 -21.02714) (xy 76.963211 -21.080547) (xy 76.939539 -21.131044) (xy 76.908766 -21.177557)
			(xy 76.871549 -21.219094) (xy 76.828681 -21.254769) (xy 76.781075 -21.283823) (xy 76.729746 -21.305635)
			(xy 76.675789 -21.319741) (xy 76.620352 -21.325841) (xy 76.564618 -21.323804) (xy 76.509775 -21.313674)
			(xy 76.456991 -21.295667) (xy 76.407391 -21.270166) (xy 76.362033 -21.237715) (xy 76.321884 -21.199006)
			(xy 76.287798 -21.154863) (xy 76.260502 -21.106228) (xy 76.240579 -21.054137) (xy 76.228453 -20.9997)
			(xy 76.224382 -20.944078) (xy 62.46368 -20.944078) (xy 62.46368 -22.266148) (xy 66.501262 -22.266148)
			(xy 66.505333 -22.210526) (xy 66.517459 -22.156089) (xy 66.537382 -22.103998) (xy 66.564678 -22.055363)
			(xy 66.598764 -22.01122) (xy 66.638913 -21.972511) (xy 66.684271 -21.94006) (xy 66.733871 -21.914559)
			(xy 66.786655 -21.896552) (xy 66.841498 -21.886422) (xy 66.897232 -21.884385) (xy 66.952669 -21.890485)
			(xy 67.006626 -21.904591) (xy 67.057955 -21.926403) (xy 67.105561 -21.955457) (xy 67.148429 -21.991132)
			(xy 67.185646 -22.032669) (xy 67.216419 -22.079182) (xy 67.240091 -22.129679) (xy 67.256159 -22.183086)
			(xy 67.264279 -22.238262) (xy 67.264788 -22.266148) (xy 67.264279 -22.294034) (xy 67.256159 -22.34921)
			(xy 67.240091 -22.402617) (xy 67.216419 -22.453114) (xy 67.185646 -22.499627) (xy 67.148429 -22.541164)
			(xy 67.105561 -22.576839) (xy 67.09815 -22.581362) (xy 74.63866 -22.581362) (xy 74.642731 -22.52574)
			(xy 74.654857 -22.471303) (xy 74.67478 -22.419212) (xy 74.702076 -22.370577) (xy 74.736162 -22.326434)
			(xy 74.776311 -22.287725) (xy 74.821669 -22.255274) (xy 74.871269 -22.229773) (xy 74.924053 -22.211766)
			(xy 74.978896 -22.201636) (xy 75.03463 -22.199599) (xy 75.090067 -22.205699) (xy 75.144024 -22.219805)
			(xy 75.195353 -22.241617) (xy 75.242959 -22.270671) (xy 75.285827 -22.306346) (xy 75.323044 -22.347883)
			(xy 75.353817 -22.394396) (xy 75.377489 -22.444893) (xy 75.393557 -22.4983) (xy 75.401677 -22.553476)
			(xy 75.402186 -22.581362) (xy 75.401677 -22.609248) (xy 75.393557 -22.664424) (xy 75.377489 -22.717831)
			(xy 75.357227 -22.761053) (xy 79.21164 -22.761053) (xy 79.21164 -22.706547) (xy 79.219397 -22.652596)
			(xy 79.234752 -22.600298) (xy 79.257394 -22.550717) (xy 79.286861 -22.504863) (xy 79.322554 -22.463669)
			(xy 79.363745 -22.427974) (xy 79.409598 -22.398504) (xy 79.459177 -22.37586) (xy 79.511474 -22.360501)
			(xy 79.565425 -22.352741) (xy 79.592678 -22.352254) (xy 79.618793 -22.352689) (xy 79.670533 -22.35983)
			(xy 79.720814 -22.373967) (xy 79.768694 -22.394835) (xy 79.813277 -22.422045) (xy 79.853729 -22.455085)
			(xy 79.871824 -22.47392) (xy 79.881243 -22.483397) (xy 79.903906 -22.497534) (xy 79.929458 -22.505316)
			(xy 79.956154 -22.506211) (xy 79.98217 -22.500157) (xy 80.005729 -22.487569) (xy 80.025221 -22.469307)
			(xy 80.032606 -22.458172) (xy 80.047649 -22.43498) (xy 80.083338 -22.392766) (xy 80.124745 -22.356144)
			(xy 80.171003 -22.325881) (xy 80.221144 -22.302609) (xy 80.274118 -22.286817) (xy 80.328817 -22.278834)
			(xy 80.356456 -22.27834) (xy 80.383714 -22.278704) (xy 80.437677 -22.286457) (xy 80.489987 -22.301811)
			(xy 80.539579 -22.324454) (xy 80.585443 -22.353924) (xy 80.626646 -22.389623) (xy 80.662349 -22.430822)
			(xy 80.691825 -22.476683) (xy 80.714474 -22.526272) (xy 80.729834 -22.57858) (xy 80.737593 -22.632542)
			(xy 80.737593 -22.687058) (xy 80.729834 -22.74102) (xy 80.714474 -22.793328) (xy 80.691825 -22.842917)
			(xy 80.662349 -22.888778) (xy 80.626646 -22.929977) (xy 80.585443 -22.965676) (xy 80.539579 -22.995146)
			(xy 80.489987 -23.017789) (xy 80.437677 -23.033143) (xy 80.383714 -23.040896) (xy 80.356456 -23.041356)
			(xy 80.33034 -23.040961) (xy 80.278598 -23.033812) (xy 80.228317 -23.019667) (xy 80.180437 -22.998791)
			(xy 80.135854 -22.971575) (xy 80.095404 -22.938528) (xy 80.07731 -22.91969) (xy 80.067857 -22.910248)
			(xy 80.045203 -22.896108) (xy 80.019659 -22.888321) (xy 79.992969 -22.887421) (xy 79.966958 -22.893469)
			(xy 79.943403 -22.90605) (xy 79.923913 -22.924307) (xy 79.916528 -22.935438) (xy 79.901532 -22.958663)
			(xy 79.865835 -23.000875) (xy 79.82442 -23.037495) (xy 79.778154 -23.067754) (xy 79.728005 -23.091021)
			(xy 79.675024 -23.106806) (xy 79.620319 -23.114781) (xy 79.592678 -23.11527) (xy 79.565425 -23.114859)
			(xy 79.511474 -23.107099) (xy 79.459177 -23.09174) (xy 79.409598 -23.069096) (xy 79.363745 -23.039626)
			(xy 79.322554 -23.003931) (xy 79.286861 -22.962737) (xy 79.257394 -22.916883) (xy 79.234752 -22.867302)
			(xy 79.219397 -22.815004) (xy 79.21164 -22.761053) (xy 75.357227 -22.761053) (xy 75.353817 -22.768328)
			(xy 75.323044 -22.814841) (xy 75.285827 -22.856378) (xy 75.242959 -22.892053) (xy 75.195353 -22.921107)
			(xy 75.144024 -22.942919) (xy 75.090067 -22.957025) (xy 75.03463 -22.963125) (xy 74.978896 -22.961088)
			(xy 74.924053 -22.950958) (xy 74.871269 -22.932951) (xy 74.821669 -22.90745) (xy 74.776311 -22.874999)
			(xy 74.736162 -22.83629) (xy 74.702076 -22.792147) (xy 74.67478 -22.743512) (xy 74.654857 -22.691421)
			(xy 74.642731 -22.636984) (xy 74.63866 -22.581362) (xy 67.09815 -22.581362) (xy 67.057955 -22.605893)
			(xy 67.006626 -22.627705) (xy 66.952669 -22.641811) (xy 66.897232 -22.647911) (xy 66.841498 -22.645874)
			(xy 66.786655 -22.635744) (xy 66.733871 -22.617737) (xy 66.684271 -22.592236) (xy 66.638913 -22.559785)
			(xy 66.598764 -22.521076) (xy 66.564678 -22.476933) (xy 66.537382 -22.428298) (xy 66.517459 -22.376207)
			(xy 66.505333 -22.32177) (xy 66.501262 -22.266148) (xy 62.46368 -22.266148) (xy 62.46368 -23.404322)
			(xy 62.63462 -23.404322) (xy 62.638691 -23.3487) (xy 62.650817 -23.294263) (xy 62.67074 -23.242172)
			(xy 62.698036 -23.193537) (xy 62.732122 -23.149394) (xy 62.772271 -23.110685) (xy 62.817629 -23.078234)
			(xy 62.867229 -23.052733) (xy 62.920013 -23.034726) (xy 62.974856 -23.024596) (xy 63.03059 -23.022559)
			(xy 63.086027 -23.028659) (xy 63.139984 -23.042765) (xy 63.191313 -23.064577) (xy 63.238919 -23.093631)
			(xy 63.281787 -23.129306) (xy 63.319004 -23.170843) (xy 63.349777 -23.217356) (xy 63.373449 -23.267853)
			(xy 63.389517 -23.32126) (xy 63.397637 -23.376436) (xy 63.398146 -23.404322) (xy 63.397637 -23.432208)
			(xy 63.389517 -23.487384) (xy 63.373449 -23.540791) (xy 63.349777 -23.591288) (xy 63.319004 -23.637801)
			(xy 63.281787 -23.679338) (xy 63.238919 -23.715013) (xy 63.191313 -23.744067) (xy 63.139984 -23.765879)
			(xy 63.086027 -23.779985) (xy 63.03059 -23.786085) (xy 62.974856 -23.784048) (xy 62.920013 -23.773918)
			(xy 62.867229 -23.755911) (xy 62.817629 -23.73041) (xy 62.772271 -23.697959) (xy 62.732122 -23.65925)
			(xy 62.698036 -23.615107) (xy 62.67074 -23.566472) (xy 62.650817 -23.514381) (xy 62.638691 -23.459944)
			(xy 62.63462 -23.404322) (xy 62.46368 -23.404322) (xy 62.46368 -25.537922) (xy 62.58382 -25.537922)
			(xy 62.587891 -25.4823) (xy 62.600017 -25.427863) (xy 62.61994 -25.375772) (xy 62.647236 -25.327137)
			(xy 62.681322 -25.282994) (xy 62.721471 -25.244285) (xy 62.766829 -25.211834) (xy 62.816429 -25.186333)
			(xy 62.869213 -25.168326) (xy 62.924056 -25.158196) (xy 62.97979 -25.156159) (xy 63.035227 -25.162259)
			(xy 63.089184 -25.176365) (xy 63.140513 -25.198177) (xy 63.188119 -25.227231) (xy 63.230987 -25.262906)
			(xy 63.268204 -25.304443) (xy 63.298977 -25.350956) (xy 63.322649 -25.401453) (xy 63.338717 -25.45486)
			(xy 63.346837 -25.510036) (xy 63.347346 -25.537922) (xy 63.346837 -25.565808) (xy 63.346493 -25.568148)
			(xy 66.019172 -25.568148) (xy 66.019706 -25.540386) (xy 66.027747 -25.485449) (xy 66.043668 -25.432258)
			(xy 66.067132 -25.381936) (xy 66.097642 -25.335547) (xy 66.134555 -25.294072) (xy 66.17709 -25.258385)
			(xy 66.224349 -25.229241) (xy 66.275334 -25.207256) (xy 66.328968 -25.192894) (xy 66.356484 -25.18918)
			(xy 66.370108 -25.187096) (xy 66.395616 -25.176695) (xy 66.417412 -25.159849) (xy 66.433905 -25.137784)
			(xy 66.443893 -25.112112) (xy 66.446647 -25.084702) (xy 66.441968 -25.057556) (xy 66.436494 -25.044908)
			(xy 66.425012 -25.019366) (xy 66.408841 -24.96575) (xy 66.400665 -24.910349) (xy 66.400172 -24.882348)
			(xy 66.400658 -24.855097) (xy 66.408414 -24.801149) (xy 66.423769 -24.748854) (xy 66.446411 -24.699277)
			(xy 66.475877 -24.653427) (xy 66.511568 -24.612236) (xy 66.552759 -24.576545) (xy 66.598609 -24.547079)
			(xy 66.648186 -24.524437) (xy 66.700481 -24.509082) (xy 66.754429 -24.501326) (xy 66.808931 -24.501326)
			(xy 66.862879 -24.509082) (xy 66.915174 -24.524437) (xy 66.964751 -24.547079) (xy 67.010601 -24.576545)
			(xy 67.051792 -24.612236) (xy 67.087483 -24.653427) (xy 67.116949 -24.699277) (xy 67.139591 -24.748854)
			(xy 67.154946 -24.801149) (xy 67.162702 -24.855097) (xy 67.163188 -24.882348) (xy 67.162706 -24.910674)
			(xy 67.154363 -24.966709) (xy 67.137823 -25.020893) (xy 67.126104 -25.046686) (xy 67.120615 -25.059312)
			(xy 67.115846 -25.086415) (xy 67.118487 -25.113808) (xy 67.128346 -25.139501) (xy 67.144706 -25.161629)
			(xy 67.166381 -25.178585) (xy 67.191796 -25.189139) (xy 67.219106 -25.192524) (xy 67.232784 -25.190958)
			(xy 67.245484 -25.18918) (xy 67.259108 -25.187096) (xy 67.284616 -25.176695) (xy 67.306412 -25.159849)
			(xy 67.322905 -25.137784) (xy 67.332893 -25.112112) (xy 67.335647 -25.084702) (xy 67.330968 -25.057556)
			(xy 67.325494 -25.044908) (xy 67.314012 -25.019366) (xy 67.297841 -24.96575) (xy 67.289665 -24.910349)
			(xy 67.289172 -24.882348) (xy 67.289658 -24.855097) (xy 67.297414 -24.801149) (xy 67.312769 -24.748854)
			(xy 67.335411 -24.699277) (xy 67.364877 -24.653427) (xy 67.400568 -24.612236) (xy 67.441759 -24.576545)
			(xy 67.487609 -24.547079) (xy 67.537186 -24.524437) (xy 67.589481 -24.509082) (xy 67.643429 -24.501326)
			(xy 67.697931 -24.501326) (xy 67.751879 -24.509082) (xy 67.804174 -24.524437) (xy 67.853751 -24.547079)
			(xy 67.899601 -24.576545) (xy 67.940792 -24.612236) (xy 67.976483 -24.653427) (xy 68.005949 -24.699277)
			(xy 68.028591 -24.748854) (xy 68.043946 -24.801149) (xy 68.051702 -24.855097) (xy 68.052188 -24.882348)
			(xy 68.051706 -24.910674) (xy 68.043363 -24.966709) (xy 68.026823 -25.020893) (xy 68.015104 -25.046686)
			(xy 68.009615 -25.059312) (xy 68.004846 -25.086415) (xy 68.007487 -25.113808) (xy 68.017346 -25.139501)
			(xy 68.033706 -25.161629) (xy 68.055381 -25.178585) (xy 68.080796 -25.189139) (xy 68.108106 -25.192524)
			(xy 68.121784 -25.190958) (xy 68.134484 -25.18918) (xy 68.148108 -25.187096) (xy 68.173616 -25.176695)
			(xy 68.195412 -25.159849) (xy 68.211905 -25.137784) (xy 68.221893 -25.112112) (xy 68.224647 -25.084702)
			(xy 68.219968 -25.057556) (xy 68.214494 -25.044908) (xy 68.203012 -25.019366) (xy 68.186841 -24.96575)
			(xy 68.178665 -24.910349) (xy 68.178172 -24.882348) (xy 68.178658 -24.855097) (xy 68.186414 -24.801149)
			(xy 68.201769 -24.748854) (xy 68.224411 -24.699277) (xy 68.253877 -24.653427) (xy 68.289568 -24.612236)
			(xy 68.330759 -24.576545) (xy 68.376609 -24.547079) (xy 68.426186 -24.524437) (xy 68.478481 -24.509082)
			(xy 68.532429 -24.501326) (xy 68.586931 -24.501326) (xy 68.640879 -24.509082) (xy 68.693174 -24.524437)
			(xy 68.742751 -24.547079) (xy 68.750639 -24.552148) (xy 69.117462 -24.552148) (xy 69.121533 -24.496526)
			(xy 69.133659 -24.442089) (xy 69.153582 -24.389998) (xy 69.180878 -24.341363) (xy 69.214964 -24.29722)
			(xy 69.255113 -24.258511) (xy 69.300471 -24.22606) (xy 69.350071 -24.200559) (xy 69.402855 -24.182552)
			(xy 69.457698 -24.172422) (xy 69.513432 -24.170385) (xy 69.568869 -24.176485) (xy 69.622826 -24.190591)
			(xy 69.674155 -24.212403) (xy 69.721761 -24.241457) (xy 69.764629 -24.277132) (xy 69.797569 -24.313896)
			(xy 77.804262 -24.313896) (xy 77.808333 -24.258274) (xy 77.820459 -24.203837) (xy 77.840382 -24.151746)
			(xy 77.867678 -24.103111) (xy 77.901764 -24.058968) (xy 77.941913 -24.020259) (xy 77.987271 -23.987808)
			(xy 78.036871 -23.962307) (xy 78.089655 -23.9443) (xy 78.144498 -23.93417) (xy 78.200232 -23.932133)
			(xy 78.255669 -23.938233) (xy 78.309626 -23.952339) (xy 78.360955 -23.974151) (xy 78.408561 -24.003205)
			(xy 78.451429 -24.03888) (xy 78.488646 -24.080417) (xy 78.519419 -24.12693) (xy 78.543091 -24.177427)
			(xy 78.559159 -24.230834) (xy 78.567279 -24.28601) (xy 78.567788 -24.313896) (xy 78.567279 -24.341782)
			(xy 78.559159 -24.396958) (xy 78.543091 -24.450365) (xy 78.519419 -24.500862) (xy 78.488646 -24.547375)
			(xy 78.45228 -24.587962) (xy 79.23606 -24.587962) (xy 79.240131 -24.53234) (xy 79.252257 -24.477903)
			(xy 79.27218 -24.425812) (xy 79.299476 -24.377177) (xy 79.333562 -24.333034) (xy 79.373711 -24.294325)
			(xy 79.419069 -24.261874) (xy 79.468669 -24.236373) (xy 79.521453 -24.218366) (xy 79.576296 -24.208236)
			(xy 79.63203 -24.206199) (xy 79.687467 -24.212299) (xy 79.741424 -24.226405) (xy 79.792753 -24.248217)
			(xy 79.840359 -24.277271) (xy 79.883227 -24.312946) (xy 79.920444 -24.354483) (xy 79.951217 -24.400996)
			(xy 79.974889 -24.451493) (xy 79.990957 -24.5049) (xy 79.999077 -24.560076) (xy 79.999586 -24.587962)
			(xy 79.999077 -24.615848) (xy 79.990957 -24.671024) (xy 79.974889 -24.724431) (xy 79.951217 -24.774928)
			(xy 79.920444 -24.821441) (xy 79.883227 -24.862978) (xy 79.840359 -24.898653) (xy 79.792753 -24.927707)
			(xy 79.741424 -24.949519) (xy 79.687467 -24.963625) (xy 79.63203 -24.969725) (xy 79.576296 -24.967688)
			(xy 79.521453 -24.957558) (xy 79.468669 -24.939551) (xy 79.419069 -24.91405) (xy 79.373711 -24.881599)
			(xy 79.333562 -24.84289) (xy 79.299476 -24.798747) (xy 79.27218 -24.750112) (xy 79.252257 -24.698021)
			(xy 79.240131 -24.643584) (xy 79.23606 -24.587962) (xy 78.45228 -24.587962) (xy 78.451429 -24.588912)
			(xy 78.408561 -24.624587) (xy 78.360955 -24.653641) (xy 78.309626 -24.675453) (xy 78.255669 -24.689559)
			(xy 78.200232 -24.695659) (xy 78.144498 -24.693622) (xy 78.089655 -24.683492) (xy 78.036871 -24.665485)
			(xy 77.987271 -24.639984) (xy 77.941913 -24.607533) (xy 77.901764 -24.568824) (xy 77.867678 -24.524681)
			(xy 77.840382 -24.476046) (xy 77.820459 -24.423955) (xy 77.808333 -24.369518) (xy 77.804262 -24.313896)
			(xy 69.797569 -24.313896) (xy 69.801846 -24.318669) (xy 69.832619 -24.365182) (xy 69.856291 -24.415679)
			(xy 69.872359 -24.469086) (xy 69.880479 -24.524262) (xy 69.880988 -24.552148) (xy 69.880479 -24.580034)
			(xy 69.872359 -24.63521) (xy 69.856291 -24.688617) (xy 69.832619 -24.739114) (xy 69.801846 -24.785627)
			(xy 69.764629 -24.827164) (xy 69.721761 -24.862839) (xy 69.674155 -24.891893) (xy 69.622826 -24.913705)
			(xy 69.568869 -24.927811) (xy 69.513432 -24.933911) (xy 69.457698 -24.931874) (xy 69.402855 -24.921744)
			(xy 69.350071 -24.903737) (xy 69.300471 -24.878236) (xy 69.255113 -24.845785) (xy 69.214964 -24.807076)
			(xy 69.180878 -24.762933) (xy 69.153582 -24.714298) (xy 69.133659 -24.662207) (xy 69.121533 -24.60777)
			(xy 69.117462 -24.552148) (xy 68.750639 -24.552148) (xy 68.788601 -24.576545) (xy 68.829792 -24.612236)
			(xy 68.865483 -24.653427) (xy 68.894949 -24.699277) (xy 68.917591 -24.748854) (xy 68.932946 -24.801149)
			(xy 68.940702 -24.855097) (xy 68.941188 -24.882348) (xy 68.940686 -24.910111) (xy 68.932644 -24.965052)
			(xy 68.916721 -25.018246) (xy 68.893255 -25.068569) (xy 68.862742 -25.11496) (xy 68.825825 -25.156436)
			(xy 68.783285 -25.192122) (xy 68.736021 -25.221264) (xy 68.685032 -25.243246) (xy 68.631394 -25.257604)
			(xy 68.603876 -25.261316) (xy 68.590232 -25.263308) (xy 68.564703 -25.273709) (xy 68.542892 -25.290567)
			(xy 68.526392 -25.31265) (xy 68.516408 -25.338345) (xy 68.513669 -25.365775) (xy 68.518376 -25.392937)
			(xy 68.523866 -25.405588) (xy 68.535351 -25.431129) (xy 68.551519 -25.484746) (xy 68.559695 -25.540147)
			(xy 68.560188 -25.568148) (xy 68.559702 -25.595399) (xy 68.551946 -25.649347) (xy 68.536591 -25.701642)
			(xy 68.513949 -25.751219) (xy 68.484483 -25.797069) (xy 68.448792 -25.83826) (xy 68.407601 -25.873951)
			(xy 68.361751 -25.903417) (xy 68.312174 -25.926059) (xy 68.259879 -25.941414) (xy 68.205931 -25.94917)
			(xy 68.151429 -25.94917) (xy 68.097481 -25.941414) (xy 68.045186 -25.926059) (xy 67.995609 -25.903417)
			(xy 67.949759 -25.873951) (xy 67.908568 -25.83826) (xy 67.872877 -25.797069) (xy 67.843411 -25.751219)
			(xy 67.820769 -25.701642) (xy 67.805414 -25.649347) (xy 67.797658 -25.595399) (xy 67.797172 -25.568148)
			(xy 67.797656 -25.539822) (xy 67.805999 -25.483787) (xy 67.822537 -25.429603) (xy 67.834256 -25.40381)
			(xy 67.839791 -25.391201) (xy 67.844563 -25.364089) (xy 67.841922 -25.336687) (xy 67.832058 -25.310986)
			(xy 67.81569 -25.288853) (xy 67.794005 -25.271895) (xy 67.768578 -25.261344) (xy 67.741258 -25.257966)
			(xy 67.727576 -25.259538) (xy 67.714876 -25.261316) (xy 67.701232 -25.263308) (xy 67.675703 -25.273709)
			(xy 67.653892 -25.290567) (xy 67.637392 -25.31265) (xy 67.627408 -25.338345) (xy 67.624669 -25.365775)
			(xy 67.629376 -25.392937) (xy 67.634866 -25.405588) (xy 67.646351 -25.431129) (xy 67.662519 -25.484746)
			(xy 67.670695 -25.540147) (xy 67.671188 -25.568148) (xy 67.670702 -25.595399) (xy 67.662946 -25.649347)
			(xy 67.647591 -25.701642) (xy 67.624949 -25.751219) (xy 67.595483 -25.797069) (xy 67.559792 -25.83826)
			(xy 67.518601 -25.873951) (xy 67.472751 -25.903417) (xy 67.423174 -25.926059) (xy 67.370879 -25.941414)
			(xy 67.316931 -25.94917) (xy 67.262429 -25.94917) (xy 67.208481 -25.941414) (xy 67.156186 -25.926059)
			(xy 67.106609 -25.903417) (xy 67.060759 -25.873951) (xy 67.019568 -25.83826) (xy 66.983877 -25.797069)
			(xy 66.954411 -25.751219) (xy 66.931769 -25.701642) (xy 66.916414 -25.649347) (xy 66.908658 -25.595399)
			(xy 66.908172 -25.568148) (xy 66.908656 -25.539822) (xy 66.916999 -25.483787) (xy 66.933537 -25.429603)
			(xy 66.945256 -25.40381) (xy 66.950791 -25.391201) (xy 66.955563 -25.364089) (xy 66.952922 -25.336687)
			(xy 66.943058 -25.310986) (xy 66.92669 -25.288853) (xy 66.905005 -25.271895) (xy 66.879578 -25.261344)
			(xy 66.852258 -25.257966) (xy 66.838576 -25.259538) (xy 66.825876 -25.261316) (xy 66.812232 -25.263308)
			(xy 66.786703 -25.273709) (xy 66.764892 -25.290567) (xy 66.748392 -25.31265) (xy 66.738408 -25.338345)
			(xy 66.735669 -25.365775) (xy 66.740376 -25.392937) (xy 66.745866 -25.405588) (xy 66.757351 -25.431129)
			(xy 66.773519 -25.484746) (xy 66.781695 -25.540147) (xy 66.782188 -25.568148) (xy 66.781702 -25.595399)
			(xy 66.773946 -25.649347) (xy 66.758591 -25.701642) (xy 66.735949 -25.751219) (xy 66.706483 -25.797069)
			(xy 66.670792 -25.83826) (xy 66.629601 -25.873951) (xy 66.583751 -25.903417) (xy 66.534174 -25.926059)
			(xy 66.481879 -25.941414) (xy 66.427931 -25.94917) (xy 66.373429 -25.94917) (xy 66.319481 -25.941414)
			(xy 66.267186 -25.926059) (xy 66.217609 -25.903417) (xy 66.171759 -25.873951) (xy 66.130568 -25.83826)
			(xy 66.094877 -25.797069) (xy 66.065411 -25.751219) (xy 66.042769 -25.701642) (xy 66.027414 -25.649347)
			(xy 66.019658 -25.595399) (xy 66.019172 -25.568148) (xy 63.346493 -25.568148) (xy 63.338717 -25.620984)
			(xy 63.322649 -25.674391) (xy 63.298977 -25.724888) (xy 63.268204 -25.771401) (xy 63.230987 -25.812938)
			(xy 63.188119 -25.848613) (xy 63.140513 -25.877667) (xy 63.089184 -25.899479) (xy 63.035227 -25.913585)
			(xy 62.97979 -25.919685) (xy 62.924056 -25.917648) (xy 62.869213 -25.907518) (xy 62.816429 -25.889511)
			(xy 62.766829 -25.86401) (xy 62.721471 -25.831559) (xy 62.681322 -25.79285) (xy 62.647236 -25.748707)
			(xy 62.61994 -25.700072) (xy 62.600017 -25.647981) (xy 62.587891 -25.593544) (xy 62.58382 -25.537922)
			(xy 62.46368 -25.537922) (xy 62.46368 -26.698053) (xy 72.09964 -26.698053) (xy 72.09964 -26.643547)
			(xy 72.107397 -26.589596) (xy 72.122752 -26.537298) (xy 72.145394 -26.487717) (xy 72.174861 -26.441863)
			(xy 72.210554 -26.400669) (xy 72.251745 -26.364974) (xy 72.297598 -26.335504) (xy 72.347177 -26.31286)
			(xy 72.399474 -26.297501) (xy 72.453425 -26.289741) (xy 72.480678 -26.289254) (xy 72.507935 -26.289747)
			(xy 72.561894 -26.297511) (xy 72.6142 -26.312871) (xy 72.66379 -26.335513) (xy 72.709656 -26.364978)
			(xy 72.750865 -26.400666) (xy 72.786579 -26.441853) (xy 72.801734 -26.464514) (xy 72.810015 -26.476441)
			(xy 72.831951 -26.495445) (xy 72.858351 -26.5075) (xy 72.887078 -26.51163) (xy 72.915805 -26.5075)
			(xy 72.942205 -26.495445) (xy 72.964141 -26.476441) (xy 72.972422 -26.464514) (xy 72.987539 -26.441825)
			(xy 73.023252 -26.400629) (xy 73.064464 -26.364935) (xy 73.110336 -26.335469) (xy 73.159935 -26.312831)
			(xy 73.21225 -26.297482) (xy 73.266218 -26.289735) (xy 73.293478 -26.289254) (xy 73.320729 -26.289792)
			(xy 73.374677 -26.297545) (xy 73.426972 -26.312898) (xy 73.47655 -26.335537) (xy 73.522402 -26.365001)
			(xy 73.563593 -26.400692) (xy 73.599285 -26.441881) (xy 73.628752 -26.48773) (xy 73.651394 -26.537307)
			(xy 73.66675 -26.589601) (xy 73.674507 -26.643549) (xy 73.674507 -26.698051) (xy 73.66675 -26.751999)
			(xy 73.651394 -26.804293) (xy 73.628752 -26.85387) (xy 73.599285 -26.899719) (xy 73.563593 -26.940908)
			(xy 73.522402 -26.976599) (xy 73.47655 -27.006063) (xy 73.426972 -27.028702) (xy 73.374677 -27.044055)
			(xy 73.320729 -27.051808) (xy 73.293478 -27.05227) (xy 73.26622 -27.0518) (xy 73.212261 -27.044031)
			(xy 73.159954 -27.028666) (xy 73.110365 -27.00602) (xy 73.064499 -26.976552) (xy 73.023291 -26.940861)
			(xy 72.987577 -26.899672) (xy 72.972422 -26.87701) (xy 72.964141 -26.865083) (xy 72.942205 -26.846079)
			(xy 72.915805 -26.834024) (xy 72.887078 -26.829894) (xy 72.858351 -26.834024) (xy 72.831951 -26.846079)
			(xy 72.810015 -26.865083) (xy 72.801734 -26.87701) (xy 72.786588 -26.899679) (xy 72.750879 -26.940873)
			(xy 72.709671 -26.976568) (xy 72.663804 -27.006036) (xy 72.614211 -27.028677) (xy 72.5619 -27.044031)
			(xy 72.507937 -27.051786) (xy 72.480678 -27.05227) (xy 72.453425 -27.051859) (xy 72.399474 -27.044099)
			(xy 72.347177 -27.02874) (xy 72.297598 -27.006096) (xy 72.251745 -26.976626) (xy 72.210554 -26.940931)
			(xy 72.174861 -26.899737) (xy 72.145394 -26.853883) (xy 72.122752 -26.804302) (xy 72.107397 -26.752004)
			(xy 72.09964 -26.698053) (xy 62.46368 -26.698053) (xy 62.46368 -28.071572) (xy 62.482865 -28.09288)
			(xy 62.515277 -28.140176) (xy 62.540247 -28.191789) (xy 62.557211 -28.246558) (xy 62.565789 -28.303248)
			(xy 62.565786 -28.360584) (xy 62.561358 -28.389834) (xy 64.102994 -28.389834) (xy 64.107065 -28.334212)
			(xy 64.119191 -28.279775) (xy 64.139114 -28.227684) (xy 64.16641 -28.179049) (xy 64.200496 -28.134906)
			(xy 64.240645 -28.096197) (xy 64.286003 -28.063746) (xy 64.335603 -28.038245) (xy 64.388387 -28.020238)
			(xy 64.44323 -28.010108) (xy 64.498964 -28.008071) (xy 64.554401 -28.014171) (xy 64.608358 -28.028277)
			(xy 64.659687 -28.050089) (xy 64.707293 -28.079143) (xy 64.750161 -28.114818) (xy 64.787378 -28.156355)
			(xy 64.818151 -28.202868) (xy 64.820305 -28.207462) (xy 66.166238 -28.207462) (xy 66.166725 -28.18014)
			(xy 66.17507 -28.126136) (xy 66.191558 -28.074039) (xy 66.215804 -28.025068) (xy 66.247239 -27.980371)
			(xy 66.265806 -27.96032) (xy 66.276244 -27.94873) (xy 66.290071 -27.920786) (xy 66.294822 -27.889972)
			(xy 66.290054 -27.859161) (xy 66.276212 -27.831225) (xy 66.265806 -27.819604) (xy 66.247204 -27.799581)
			(xy 66.215746 -27.754891) (xy 66.191495 -27.705914) (xy 66.175021 -27.653805) (xy 66.166712 -27.599788)
			(xy 66.166238 -27.572462) (xy 66.166736 -27.545813) (xy 66.174679 -27.493109) (xy 66.190389 -27.442179)
			(xy 66.213515 -27.394158) (xy 66.243539 -27.350121) (xy 66.279791 -27.31105) (xy 66.321462 -27.277819)
			(xy 66.36762 -27.25117) (xy 66.417234 -27.231698) (xy 66.469196 -27.219838) (xy 66.522346 -27.215855)
			(xy 66.575496 -27.219838) (xy 66.627458 -27.231698) (xy 66.677072 -27.25117) (xy 66.72323 -27.277819)
			(xy 66.764901 -27.31105) (xy 66.801153 -27.350121) (xy 66.831177 -27.394158) (xy 66.854303 -27.442179)
			(xy 66.870013 -27.493109) (xy 66.877956 -27.545813) (xy 66.878454 -27.572462) (xy 66.877922 -27.599782)
			(xy 66.869589 -27.653784) (xy 66.853111 -27.705881) (xy 66.828875 -27.754853) (xy 66.797449 -27.799552)
			(xy 66.778886 -27.819604) (xy 66.768524 -27.831256) (xy 66.75469 -27.859178) (xy 66.749926 -27.889972)
			(xy 66.754674 -27.92077) (xy 66.768492 -27.948699) (xy 66.778886 -27.96032) (xy 66.797498 -27.980334)
			(xy 66.828955 -28.025027) (xy 66.853205 -28.074005) (xy 66.869676 -28.126117) (xy 66.877982 -28.180135)
			(xy 66.878454 -28.207462) (xy 67.06616 -28.207462) (xy 67.066669 -28.180141) (xy 67.075011 -28.126139)
			(xy 67.091496 -28.074043) (xy 67.115736 -28.025072) (xy 67.147164 -27.980372) (xy 67.165728 -27.96032)
			(xy 67.176164 -27.948729) (xy 67.189988 -27.920785) (xy 67.194738 -27.889972) (xy 67.189971 -27.859162)
			(xy 67.176132 -27.831226) (xy 67.165728 -27.819604) (xy 67.14713 -27.799577) (xy 67.115671 -27.754889)
			(xy 67.091418 -27.705913) (xy 67.074943 -27.653804) (xy 67.066634 -27.599788) (xy 67.06616 -27.572462)
			(xy 67.066658 -27.545813) (xy 67.074601 -27.493109) (xy 67.090311 -27.442179) (xy 67.113437 -27.394158)
			(xy 67.143461 -27.350121) (xy 67.179713 -27.31105) (xy 67.221384 -27.277819) (xy 67.267542 -27.25117)
			(xy 67.317156 -27.231698) (xy 67.369118 -27.219838) (xy 67.422268 -27.215855) (xy 67.475418 -27.219838)
			(xy 67.52738 -27.231698) (xy 67.576994 -27.25117) (xy 67.623152 -27.277819) (xy 67.664823 -27.31105)
			(xy 67.701075 -27.350121) (xy 67.731099 -27.394158) (xy 67.754225 -27.442179) (xy 67.769935 -27.493109)
			(xy 67.777878 -27.545813) (xy 67.778376 -27.572462) (xy 67.777838 -27.599782) (xy 67.769505 -27.653783)
			(xy 67.753029 -27.70588) (xy 67.728794 -27.754852) (xy 67.69737 -27.799552) (xy 67.678808 -27.819604)
			(xy 67.668452 -27.831259) (xy 67.65463 -27.859181) (xy 67.649869 -27.889972) (xy 67.654613 -27.920766)
			(xy 67.668421 -27.948696) (xy 67.678808 -27.96032) (xy 67.697423 -27.980331) (xy 67.728879 -28.025025)
			(xy 67.753128 -28.074004) (xy 67.769599 -28.126116) (xy 67.777904 -28.180135) (xy 67.778376 -28.207462)
			(xy 67.966082 -28.207462) (xy 67.966585 -28.180141) (xy 67.974928 -28.126139) (xy 67.991414 -28.074042)
			(xy 68.015655 -28.025071) (xy 68.047085 -27.980372) (xy 68.06565 -27.96032) (xy 68.076084 -27.948728)
			(xy 68.089905 -27.920784) (xy 68.094654 -27.889972) (xy 68.089888 -27.859163) (xy 68.076052 -27.831226)
			(xy 68.06565 -27.819604) (xy 68.047056 -27.799574) (xy 68.015595 -27.754887) (xy 67.991341 -27.705912)
			(xy 67.974866 -27.653804) (xy 67.966556 -27.599788) (xy 67.966082 -27.572462) (xy 67.96658 -27.545813)
			(xy 67.974523 -27.493109) (xy 67.990233 -27.442179) (xy 68.013359 -27.394158) (xy 68.043383 -27.350121)
			(xy 68.079635 -27.31105) (xy 68.121306 -27.277819) (xy 68.167464 -27.25117) (xy 68.217078 -27.231698)
			(xy 68.26904 -27.219838) (xy 68.32219 -27.215855) (xy 68.37534 -27.219838) (xy 68.427302 -27.231698)
			(xy 68.476916 -27.25117) (xy 68.523074 -27.277819) (xy 68.564745 -27.31105) (xy 68.600997 -27.350121)
			(xy 68.631021 -27.394158) (xy 68.654147 -27.442179) (xy 68.669857 -27.493109) (xy 68.6778 -27.545813)
			(xy 68.678298 -27.572462) (xy 68.677754 -27.599782) (xy 68.669422 -27.653782) (xy 68.652946 -27.705879)
			(xy 68.628713 -27.754851) (xy 68.597291 -27.799551) (xy 68.57873 -27.819604) (xy 68.568372 -27.831258)
			(xy 68.554547 -27.85918) (xy 68.549785 -27.889972) (xy 68.55453 -27.920767) (xy 68.568341 -27.948697)
			(xy 68.57873 -27.96032) (xy 68.597349 -27.980328) (xy 68.628804 -28.025023) (xy 68.653051 -28.074003)
			(xy 68.669521 -28.126116) (xy 68.677826 -28.180135) (xy 68.678298 -28.207462) (xy 68.866258 -28.207462)
			(xy 68.86674 -28.18014) (xy 68.875085 -28.126136) (xy 68.891574 -28.074038) (xy 68.915821 -28.025067)
			(xy 68.947258 -27.98037) (xy 68.965826 -27.96032) (xy 68.976262 -27.948729) (xy 68.990086 -27.920785)
			(xy 68.994836 -27.889972) (xy 68.99007 -27.859162) (xy 68.976231 -27.831225) (xy 68.965826 -27.819604)
			(xy 68.947228 -27.799578) (xy 68.915768 -27.754889) (xy 68.891516 -27.705913) (xy 68.875041 -27.653804)
			(xy 68.866732 -27.599788) (xy 68.866258 -27.572462) (xy 68.866756 -27.545813) (xy 68.874699 -27.493109)
			(xy 68.890409 -27.442179) (xy 68.913535 -27.394158) (xy 68.943559 -27.350121) (xy 68.979811 -27.31105)
			(xy 69.021482 -27.277819) (xy 69.06764 -27.25117) (xy 69.117254 -27.231698) (xy 69.169216 -27.219838)
			(xy 69.222366 -27.215855) (xy 69.275516 -27.219838) (xy 69.327478 -27.231698) (xy 69.377092 -27.25117)
			(xy 69.42325 -27.277819) (xy 69.464921 -27.31105) (xy 69.501173 -27.350121) (xy 69.531197 -27.394158)
			(xy 69.554323 -27.442179) (xy 69.570033 -27.493109) (xy 69.577976 -27.545813) (xy 69.578474 -27.572462)
			(xy 69.577937 -27.599782) (xy 69.569604 -27.653783) (xy 69.553127 -27.70588) (xy 69.528893 -27.754852)
			(xy 69.497468 -27.799552) (xy 69.478906 -27.819604) (xy 69.468551 -27.831259) (xy 69.454728 -27.859181)
			(xy 69.449967 -27.889972) (xy 69.453879 -27.915362) (xy 70.95617 -27.915362) (xy 70.956679 -27.886623)
			(xy 70.965306 -27.829795) (xy 70.98236 -27.774904) (xy 71.007455 -27.723193) (xy 71.040022 -27.675831)
			(xy 71.059294 -27.654504) (xy 71.069401 -27.642999) (xy 71.082736 -27.615442) (xy 71.087312 -27.585172)
			(xy 71.082719 -27.554905) (xy 71.069369 -27.527355) (xy 71.059294 -27.51582) (xy 71.040015 -27.4945)
			(xy 71.007448 -27.447137) (xy 70.982356 -27.395424) (xy 70.965308 -27.340531) (xy 70.956689 -27.283702)
			(xy 70.95617 -27.254962) (xy 70.956656 -27.227711) (xy 70.964412 -27.173763) (xy 70.979767 -27.121468)
			(xy 71.002409 -27.071891) (xy 71.031875 -27.026041) (xy 71.067566 -26.98485) (xy 71.108757 -26.949159)
			(xy 71.154607 -26.919693) (xy 71.204184 -26.897051) (xy 71.256479 -26.881696) (xy 71.310427 -26.87394)
			(xy 71.364929 -26.87394) (xy 71.418877 -26.881696) (xy 71.471172 -26.897051) (xy 71.520749 -26.919693)
			(xy 71.566599 -26.949159) (xy 71.60779 -26.98485) (xy 71.643481 -27.026041) (xy 71.672947 -27.071891)
			(xy 71.695589 -27.121468) (xy 71.710944 -27.173763) (xy 71.7187 -27.227711) (xy 71.719186 -27.254962)
			(xy 71.718677 -27.283701) (xy 71.710047 -27.340528) (xy 71.692992 -27.395418) (xy 71.667898 -27.44713)
			(xy 71.635332 -27.494492) (xy 71.616062 -27.51582) (xy 71.606025 -27.527383) (xy 71.592674 -27.554918)
			(xy 71.588081 -27.585172) (xy 71.592658 -27.615429) (xy 71.605993 -27.642971) (xy 71.616062 -27.654504)
			(xy 71.635315 -27.675847) (xy 71.667883 -27.723204) (xy 71.692979 -27.774912) (xy 71.710034 -27.829799)
			(xy 71.718662 -27.886624) (xy 71.719186 -27.915362) (xy 71.7187 -27.942613) (xy 71.710944 -27.996561)
			(xy 71.695589 -28.048856) (xy 71.672947 -28.098433) (xy 71.643481 -28.144283) (xy 71.60779 -28.185474)
			(xy 71.566599 -28.221165) (xy 71.520749 -28.250631) (xy 71.471172 -28.273273) (xy 71.418877 -28.288628)
			(xy 71.364929 -28.296384) (xy 71.310427 -28.296384) (xy 71.256479 -28.288628) (xy 71.204184 -28.273273)
			(xy 71.154607 -28.250631) (xy 71.108757 -28.221165) (xy 71.067566 -28.185474) (xy 71.031875 -28.144283)
			(xy 71.002409 -28.098433) (xy 70.979767 -28.048856) (xy 70.964412 -27.996561) (xy 70.956656 -27.942613)
			(xy 70.95617 -27.915362) (xy 69.453879 -27.915362) (xy 69.454712 -27.920766) (xy 69.468519 -27.948696)
			(xy 69.478906 -27.96032) (xy 69.497521 -27.980331) (xy 69.528977 -28.025025) (xy 69.553226 -28.074004)
			(xy 69.569697 -28.126116) (xy 69.578002 -28.180135) (xy 69.578474 -28.207462) (xy 69.577976 -28.234111)
			(xy 69.570033 -28.286815) (xy 69.554323 -28.337745) (xy 69.531197 -28.385766) (xy 69.501173 -28.429803)
			(xy 69.464921 -28.468874) (xy 69.42325 -28.502105) (xy 69.377092 -28.528754) (xy 69.327478 -28.548226)
			(xy 69.275516 -28.560086) (xy 69.222366 -28.56407) (xy 69.169216 -28.560086) (xy 69.117254 -28.548226)
			(xy 69.06764 -28.528754) (xy 69.021482 -28.502105) (xy 68.979811 -28.468874) (xy 68.943559 -28.429803)
			(xy 68.913535 -28.385766) (xy 68.890409 -28.337745) (xy 68.874699 -28.286815) (xy 68.866756 -28.234111)
			(xy 68.866258 -28.207462) (xy 68.678298 -28.207462) (xy 68.6778 -28.234111) (xy 68.669857 -28.286815)
			(xy 68.654147 -28.337745) (xy 68.631021 -28.385766) (xy 68.600997 -28.429803) (xy 68.564745 -28.468874)
			(xy 68.523074 -28.502105) (xy 68.476916 -28.528754) (xy 68.427302 -28.548226) (xy 68.37534 -28.560086)
			(xy 68.32219 -28.56407) (xy 68.26904 -28.560086) (xy 68.217078 -28.548226) (xy 68.167464 -28.528754)
			(xy 68.121306 -28.502105) (xy 68.079635 -28.468874) (xy 68.043383 -28.429803) (xy 68.013359 -28.385766)
			(xy 67.990233 -28.337745) (xy 67.974523 -28.286815) (xy 67.96658 -28.234111) (xy 67.966082 -28.207462)
			(xy 67.778376 -28.207462) (xy 67.777878 -28.234111) (xy 67.769935 -28.286815) (xy 67.754225 -28.337745)
			(xy 67.731099 -28.385766) (xy 67.701075 -28.429803) (xy 67.664823 -28.468874) (xy 67.623152 -28.502105)
			(xy 67.576994 -28.528754) (xy 67.52738 -28.548226) (xy 67.475418 -28.560086) (xy 67.422268 -28.56407)
			(xy 67.369118 -28.560086) (xy 67.317156 -28.548226) (xy 67.267542 -28.528754) (xy 67.221384 -28.502105)
			(xy 67.179713 -28.468874) (xy 67.143461 -28.429803) (xy 67.113437 -28.385766) (xy 67.090311 -28.337745)
			(xy 67.074601 -28.286815) (xy 67.066658 -28.234111) (xy 67.06616 -28.207462) (xy 66.878454 -28.207462)
			(xy 66.877956 -28.234111) (xy 66.870013 -28.286815) (xy 66.854303 -28.337745) (xy 66.831177 -28.385766)
			(xy 66.801153 -28.429803) (xy 66.764901 -28.468874) (xy 66.72323 -28.502105) (xy 66.677072 -28.528754)
			(xy 66.627458 -28.548226) (xy 66.575496 -28.560086) (xy 66.522346 -28.56407) (xy 66.469196 -28.560086)
			(xy 66.417234 -28.548226) (xy 66.36762 -28.528754) (xy 66.321462 -28.502105) (xy 66.279791 -28.468874)
			(xy 66.243539 -28.429803) (xy 66.213515 -28.385766) (xy 66.190389 -28.337745) (xy 66.174679 -28.286815)
			(xy 66.166736 -28.234111) (xy 66.166238 -28.207462) (xy 64.820305 -28.207462) (xy 64.841823 -28.253365)
			(xy 64.857891 -28.306772) (xy 64.866011 -28.361948) (xy 64.86652 -28.389834) (xy 64.866011 -28.41772)
			(xy 64.857891 -28.472896) (xy 64.841823 -28.526303) (xy 64.818151 -28.5768) (xy 64.787378 -28.623313)
			(xy 64.761709 -28.651962) (xy 76.118974 -28.651962) (xy 76.11943 -28.625646) (xy 76.126651 -28.573513)
			(xy 76.140964 -28.522865) (xy 76.162098 -28.474663) (xy 76.189652 -28.429821) (xy 76.223104 -28.389189)
			(xy 76.242164 -28.371038) (xy 76.252225 -28.361264) (xy 76.266926 -28.337381) (xy 76.274562 -28.310397)
			(xy 76.274555 -28.282352) (xy 76.266905 -28.255371) (xy 76.252193 -28.231497) (xy 76.242164 -28.221686)
			(xy 76.22309 -28.203546) (xy 76.189609 -28.162928) (xy 76.162036 -28.118089) (xy 76.140896 -28.069882)
			(xy 76.126591 -28.019225) (xy 76.119394 -27.967081) (xy 76.118974 -27.940762) (xy 76.119492 -27.913189)
			(xy 76.127435 -27.858619) (xy 76.14315 -27.805761) (xy 76.16631 -27.755715) (xy 76.196433 -27.709524)
			(xy 76.232891 -27.66815) (xy 76.253594 -27.649932) (xy 76.264529 -27.640072) (xy 76.280601 -27.615411)
			(xy 76.28898 -27.587193) (xy 76.288973 -27.557758) (xy 76.28058 -27.529544) (xy 76.264497 -27.504891)
			(xy 76.253594 -27.494992) (xy 76.232875 -27.47679) (xy 76.196405 -27.435419) (xy 76.166274 -27.389227)
			(xy 76.14311 -27.339177) (xy 76.127395 -27.286313) (xy 76.119458 -27.231737) (xy 76.118974 -27.204162)
			(xy 76.11946 -27.176911) (xy 76.127216 -27.122963) (xy 76.142571 -27.070668) (xy 76.165213 -27.021091)
			(xy 76.194679 -26.975241) (xy 76.23037 -26.93405) (xy 76.271561 -26.898359) (xy 76.317411 -26.868893)
			(xy 76.366988 -26.846251) (xy 76.419283 -26.830896) (xy 76.473231 -26.82314) (xy 76.527733 -26.82314)
			(xy 76.581681 -26.830896) (xy 76.633976 -26.846251) (xy 76.683553 -26.868893) (xy 76.729403 -26.898359)
			(xy 76.770594 -26.93405) (xy 76.806285 -26.975241) (xy 76.835751 -27.021091) (xy 76.858393 -27.070668)
			(xy 76.873748 -27.122963) (xy 76.881504 -27.176911) (xy 76.88199 -27.204162) (xy 76.881502 -27.231736)
			(xy 76.873554 -27.286308) (xy 76.857834 -27.339167) (xy 76.834668 -27.389213) (xy 76.804539 -27.435404)
			(xy 76.768076 -27.476776) (xy 76.74737 -27.494992) (xy 76.736514 -27.504931) (xy 76.720445 -27.529571)
			(xy 76.71206 -27.557767) (xy 76.712053 -27.587184) (xy 76.720425 -27.615384) (xy 76.736481 -27.640032)
			(xy 76.74737 -27.649932) (xy 76.768094 -27.66813) (xy 76.804564 -27.7095) (xy 76.834696 -27.755693)
			(xy 76.85786 -27.805744) (xy 76.873573 -27.858609) (xy 76.881508 -27.913186) (xy 76.88199 -27.940762)
			(xy 76.881561 -27.967079) (xy 76.874337 -28.019214) (xy 76.860019 -28.069863) (xy 76.83888 -28.118065)
			(xy 76.81132 -28.162906) (xy 76.777862 -28.203537) (xy 76.7588 -28.221686) (xy 76.748818 -28.231534)
			(xy 76.734119 -28.255397) (xy 76.726476 -28.282361) (xy 76.726469 -28.310388) (xy 76.734098 -28.337356)
			(xy 76.748785 -28.361226) (xy 76.7588 -28.371038) (xy 76.777898 -28.389154) (xy 76.811374 -28.429779)
			(xy 76.838942 -28.474623) (xy 76.860078 -28.522834) (xy 76.874378 -28.573495) (xy 76.881572 -28.625641)
			(xy 76.88199 -28.651962) (xy 78.62697 -28.651962) (xy 78.627428 -28.625646) (xy 78.634648 -28.573513)
			(xy 78.648961 -28.522865) (xy 78.670095 -28.474663) (xy 78.697649 -28.429821) (xy 78.731101 -28.389189)
			(xy 78.75016 -28.371038) (xy 78.760222 -28.361264) (xy 78.774923 -28.337381) (xy 78.782559 -28.310397)
			(xy 78.782552 -28.282352) (xy 78.774902 -28.255371) (xy 78.760189 -28.231496) (xy 78.75016 -28.221686)
			(xy 78.731085 -28.203546) (xy 78.697605 -28.162928) (xy 78.670032 -28.118089) (xy 78.648892 -28.069883)
			(xy 78.634587 -28.019225) (xy 78.62739 -27.967081) (xy 78.62697 -27.940762) (xy 78.627489 -27.913189)
			(xy 78.635432 -27.858619) (xy 78.651147 -27.805761) (xy 78.674307 -27.755715) (xy 78.70443 -27.709524)
			(xy 78.740888 -27.66815) (xy 78.76159 -27.649932) (xy 78.772526 -27.640072) (xy 78.788598 -27.615411)
			(xy 78.796978 -27.587193) (xy 78.796971 -27.557758) (xy 78.788577 -27.529544) (xy 78.772493 -27.504891)
			(xy 78.76159 -27.494992) (xy 78.74087 -27.476791) (xy 78.704401 -27.43542) (xy 78.67427 -27.389228)
			(xy 78.651106 -27.339178) (xy 78.635391 -27.286314) (xy 78.627454 -27.231737) (xy 78.62697 -27.204162)
			(xy 78.627456 -27.176911) (xy 78.635212 -27.122963) (xy 78.650567 -27.070668) (xy 78.673209 -27.021091)
			(xy 78.702675 -26.975241) (xy 78.738366 -26.93405) (xy 78.779557 -26.898359) (xy 78.825407 -26.868893)
			(xy 78.874984 -26.846251) (xy 78.927279 -26.830896) (xy 78.981227 -26.82314) (xy 79.035729 -26.82314)
			(xy 79.089677 -26.830896) (xy 79.141972 -26.846251) (xy 79.191549 -26.868893) (xy 79.237399 -26.898359)
			(xy 79.27859 -26.93405) (xy 79.314281 -26.975241) (xy 79.343747 -27.021091) (xy 79.366389 -27.070668)
			(xy 79.381744 -27.122963) (xy 79.3895 -27.176911) (xy 79.389986 -27.204162) (xy 79.389499 -27.231736)
			(xy 79.381552 -27.286308) (xy 79.365831 -27.339168) (xy 79.342665 -27.389214) (xy 79.312536 -27.435404)
			(xy 79.276072 -27.476776) (xy 79.255366 -27.494992) (xy 79.24451 -27.504931) (xy 79.228442 -27.529571)
			(xy 79.220058 -27.557767) (xy 79.22005 -27.587184) (xy 79.228422 -27.615384) (xy 79.244478 -27.640032)
			(xy 79.255366 -27.649932) (xy 79.276089 -27.66813) (xy 79.31256 -27.709501) (xy 79.342691 -27.755693)
			(xy 79.365855 -27.805744) (xy 79.381569 -27.858609) (xy 79.389504 -27.913186) (xy 79.389986 -27.940762)
			(xy 79.389559 -27.967079) (xy 79.382334 -28.019214) (xy 79.368016 -28.069863) (xy 79.346877 -28.118065)
			(xy 79.319317 -28.162906) (xy 79.285858 -28.203537) (xy 79.266796 -28.221686) (xy 79.256814 -28.231534)
			(xy 79.242116 -28.255397) (xy 79.234473 -28.282361) (xy 79.234466 -28.310388) (xy 79.242095 -28.337356)
			(xy 79.256782 -28.361226) (xy 79.266796 -28.371038) (xy 79.285893 -28.389155) (xy 79.31937 -28.429779)
			(xy 79.346938 -28.474623) (xy 79.368073 -28.522834) (xy 79.382374 -28.573495) (xy 79.389568 -28.625641)
			(xy 79.389986 -28.651962) (xy 79.3895 -28.679213) (xy 79.381744 -28.733161) (xy 79.366389 -28.785456)
			(xy 79.343747 -28.835033) (xy 79.314281 -28.880883) (xy 79.27859 -28.922074) (xy 79.237399 -28.957765)
			(xy 79.191549 -28.987231) (xy 79.141972 -29.009873) (xy 79.089677 -29.025228) (xy 79.035729 -29.032984)
			(xy 78.981227 -29.032984) (xy 78.927279 -29.025228) (xy 78.874984 -29.009873) (xy 78.825407 -28.987231)
			(xy 78.779557 -28.957765) (xy 78.738366 -28.922074) (xy 78.702675 -28.880883) (xy 78.673209 -28.835033)
			(xy 78.650567 -28.785456) (xy 78.635212 -28.733161) (xy 78.627456 -28.679213) (xy 78.62697 -28.651962)
			(xy 76.88199 -28.651962) (xy 76.881504 -28.679213) (xy 76.873748 -28.733161) (xy 76.858393 -28.785456)
			(xy 76.835751 -28.835033) (xy 76.806285 -28.880883) (xy 76.770594 -28.922074) (xy 76.729403 -28.957765)
			(xy 76.683553 -28.987231) (xy 76.633976 -29.009873) (xy 76.581681 -29.025228) (xy 76.527733 -29.032984)
			(xy 76.473231 -29.032984) (xy 76.419283 -29.025228) (xy 76.366988 -29.009873) (xy 76.317411 -28.987231)
			(xy 76.271561 -28.957765) (xy 76.23037 -28.922074) (xy 76.194679 -28.880883) (xy 76.165213 -28.835033)
			(xy 76.142571 -28.785456) (xy 76.127216 -28.733161) (xy 76.11946 -28.679213) (xy 76.118974 -28.651962)
			(xy 64.761709 -28.651962) (xy 64.750161 -28.66485) (xy 64.707293 -28.700525) (xy 64.659687 -28.729579)
			(xy 64.608358 -28.751391) (xy 64.554401 -28.765497) (xy 64.498964 -28.771597) (xy 64.44323 -28.76956)
			(xy 64.388387 -28.75943) (xy 64.335603 -28.741423) (xy 64.286003 -28.715922) (xy 64.240645 -28.683471)
			(xy 64.200496 -28.644762) (xy 64.16641 -28.600619) (xy 64.139114 -28.551984) (xy 64.119191 -28.499893)
			(xy 64.107065 -28.445456) (xy 64.102994 -28.389834) (xy 62.561358 -28.389834) (xy 62.557204 -28.417274)
			(xy 62.540235 -28.472041) (xy 62.515261 -28.523652) (xy 62.482845 -28.570945) (xy 62.46368 -28.592272)
			(xy 62.46368 -29.087572) (xy 62.482865 -29.10888) (xy 62.515277 -29.156176) (xy 62.540247 -29.207789)
			(xy 62.557211 -29.262558) (xy 62.565789 -29.319248) (xy 62.565786 -29.376584) (xy 62.563242 -29.393388)
			(xy 64.111122 -29.393388) (xy 64.115193 -29.337766) (xy 64.127319 -29.283329) (xy 64.147242 -29.231238)
			(xy 64.174538 -29.182603) (xy 64.208624 -29.13846) (xy 64.248773 -29.099751) (xy 64.294131 -29.0673)
			(xy 64.343731 -29.041799) (xy 64.396515 -29.023792) (xy 64.451358 -29.013662) (xy 64.507092 -29.011625)
			(xy 64.562529 -29.017725) (xy 64.616486 -29.031831) (xy 64.667815 -29.053643) (xy 64.715421 -29.082697)
			(xy 64.758289 -29.118372) (xy 64.795506 -29.159909) (xy 64.826279 -29.206422) (xy 64.849951 -29.256919)
			(xy 64.866019 -29.310326) (xy 64.874139 -29.365502) (xy 64.874594 -29.390453) (xy 71.46464 -29.390453)
			(xy 71.46464 -29.335947) (xy 71.472397 -29.281996) (xy 71.487752 -29.229698) (xy 71.510394 -29.180117)
			(xy 71.539861 -29.134263) (xy 71.575554 -29.093069) (xy 71.616745 -29.057374) (xy 71.662598 -29.027904)
			(xy 71.712177 -29.00526) (xy 71.764474 -28.989901) (xy 71.818425 -28.982141) (xy 71.845678 -28.981654)
			(xy 71.874595 -28.982168) (xy 71.931768 -28.990895) (xy 71.986967 -29.008152) (xy 72.03893 -29.033545)
			(xy 72.086463 -29.06649) (xy 72.128479 -29.106233) (xy 72.146668 -29.12872) (xy 72.156565 -29.140525)
			(xy 72.181889 -29.158044) (xy 72.211282 -29.16722) (xy 72.242074 -29.16722) (xy 72.271467 -29.158044)
			(xy 72.296791 -29.140525) (xy 72.306688 -29.12872) (xy 72.324891 -29.106246) (xy 72.366908 -29.06651)
			(xy 72.41444 -29.033569) (xy 72.466399 -29.008179) (xy 72.521595 -28.990921) (xy 72.578763 -28.98219)
			(xy 72.607678 -28.981654) (xy 72.634929 -28.982192) (xy 72.688877 -28.989945) (xy 72.741172 -29.005298)
			(xy 72.79075 -29.027937) (xy 72.836602 -29.057401) (xy 72.877793 -29.093092) (xy 72.913485 -29.134281)
			(xy 72.942952 -29.18013) (xy 72.965594 -29.229707) (xy 72.98095 -29.282001) (xy 72.988707 -29.335949)
			(xy 72.988707 -29.390451) (xy 72.98095 -29.444399) (xy 72.965594 -29.496693) (xy 72.942952 -29.54627)
			(xy 72.913485 -29.592119) (xy 72.877793 -29.633308) (xy 72.836602 -29.668999) (xy 72.79075 -29.698463)
			(xy 72.741172 -29.721102) (xy 72.688877 -29.736455) (xy 72.634929 -29.744208) (xy 72.607678 -29.74467)
			(xy 72.578763 -29.744107) (xy 72.521593 -29.735389) (xy 72.466395 -29.71814) (xy 72.414433 -29.692757)
			(xy 72.366898 -29.659821) (xy 72.324879 -29.620086) (xy 72.306688 -29.597604) (xy 72.296791 -29.585799)
			(xy 72.271467 -29.56828) (xy 72.242074 -29.559104) (xy 72.211282 -29.559104) (xy 72.181889 -29.56828)
			(xy 72.156565 -29.585799) (xy 72.146668 -29.597604) (xy 72.128496 -29.620104) (xy 72.086472 -29.659838)
			(xy 72.038933 -29.692775) (xy 71.986968 -29.71816) (xy 71.931767 -29.735413) (xy 71.874595 -29.744137)
			(xy 71.845678 -29.74467) (xy 71.818425 -29.744259) (xy 71.764474 -29.736499) (xy 71.712177 -29.72114)
			(xy 71.662598 -29.698496) (xy 71.616745 -29.669026) (xy 71.575554 -29.633331) (xy 71.539861 -29.592137)
			(xy 71.510394 -29.546283) (xy 71.487752 -29.496702) (xy 71.472397 -29.444404) (xy 71.46464 -29.390453)
			(xy 64.874594 -29.390453) (xy 64.874648 -29.393388) (xy 64.874139 -29.421274) (xy 64.866019 -29.47645)
			(xy 64.849951 -29.529857) (xy 64.826279 -29.580354) (xy 64.795506 -29.626867) (xy 64.758289 -29.668404)
			(xy 64.715421 -29.704079) (xy 64.667815 -29.733133) (xy 64.616486 -29.754945) (xy 64.562529 -29.769051)
			(xy 64.507092 -29.775151) (xy 64.451358 -29.773114) (xy 64.396515 -29.762984) (xy 64.343731 -29.744977)
			(xy 64.294131 -29.719476) (xy 64.248773 -29.687025) (xy 64.208624 -29.648316) (xy 64.174538 -29.604173)
			(xy 64.147242 -29.555538) (xy 64.127319 -29.503447) (xy 64.115193 -29.44901) (xy 64.111122 -29.393388)
			(xy 62.563242 -29.393388) (xy 62.557204 -29.433274) (xy 62.540235 -29.488041) (xy 62.515261 -29.539652)
			(xy 62.482845 -29.586945) (xy 62.46368 -29.608272) (xy 62.46368 -30.714188) (xy 66.559682 -30.714188)
			(xy 66.563753 -30.658566) (xy 66.575879 -30.604129) (xy 66.595802 -30.552038) (xy 66.623098 -30.503403)
			(xy 66.657184 -30.45926) (xy 66.697333 -30.420551) (xy 66.742691 -30.3881) (xy 66.792291 -30.362599)
			(xy 66.845075 -30.344592) (xy 66.899918 -30.334462) (xy 66.955652 -30.332425) (xy 67.011089 -30.338525)
			(xy 67.065046 -30.352631) (xy 67.116375 -30.374443) (xy 67.163981 -30.403497) (xy 67.206849 -30.439172)
			(xy 67.244066 -30.480709) (xy 67.274839 -30.527222) (xy 67.298511 -30.577719) (xy 67.314579 -30.631126)
			(xy 67.322699 -30.686302) (xy 67.323208 -30.714188) (xy 67.322699 -30.742074) (xy 67.320448 -30.757368)
			(xy 67.992496 -30.757368) (xy 67.996567 -30.701746) (xy 68.008693 -30.647309) (xy 68.028616 -30.595218)
			(xy 68.055912 -30.546583) (xy 68.089998 -30.50244) (xy 68.130147 -30.463731) (xy 68.175505 -30.43128)
			(xy 68.225105 -30.405779) (xy 68.277889 -30.387772) (xy 68.332732 -30.377642) (xy 68.388466 -30.375605)
			(xy 68.443903 -30.381705) (xy 68.49786 -30.395811) (xy 68.549189 -30.417623) (xy 68.596795 -30.446677)
			(xy 68.639663 -30.482352) (xy 68.67688 -30.523889) (xy 68.689014 -30.54223) (xy 69.67042 -30.54223)
			(xy 69.674491 -30.486608) (xy 69.686617 -30.432171) (xy 69.70654 -30.38008) (xy 69.733836 -30.331445)
			(xy 69.767922 -30.287302) (xy 69.808071 -30.248593) (xy 69.853429 -30.216142) (xy 69.903029 -30.190641)
			(xy 69.955813 -30.172634) (xy 70.010656 -30.162504) (xy 70.06639 -30.160467) (xy 70.121827 -30.166567)
			(xy 70.175784 -30.180673) (xy 70.227113 -30.202485) (xy 70.274719 -30.231539) (xy 70.317587 -30.267214)
			(xy 70.354804 -30.308751) (xy 70.385577 -30.355264) (xy 70.409249 -30.405761) (xy 70.425317 -30.459168)
			(xy 70.433437 -30.514344) (xy 70.433946 -30.54223) (xy 70.433437 -30.570116) (xy 70.425317 -30.625292)
			(xy 70.409249 -30.678699) (xy 70.385577 -30.729196) (xy 70.354804 -30.775709) (xy 70.317587 -30.817246)
			(xy 70.274719 -30.852921) (xy 70.227113 -30.881975) (xy 70.175784 -30.903787) (xy 70.121827 -30.917893)
			(xy 70.06639 -30.923993) (xy 70.010656 -30.921956) (xy 69.955813 -30.911826) (xy 69.903029 -30.893819)
			(xy 69.853429 -30.868318) (xy 69.808071 -30.835867) (xy 69.767922 -30.797158) (xy 69.733836 -30.753015)
			(xy 69.70654 -30.70438) (xy 69.686617 -30.652289) (xy 69.674491 -30.597852) (xy 69.67042 -30.54223)
			(xy 68.689014 -30.54223) (xy 68.707653 -30.570402) (xy 68.731325 -30.620899) (xy 68.747393 -30.674306)
			(xy 68.755513 -30.729482) (xy 68.756022 -30.757368) (xy 68.755513 -30.785254) (xy 68.747393 -30.84043)
			(xy 68.731325 -30.893837) (xy 68.707653 -30.944334) (xy 68.67688 -30.990847) (xy 68.639663 -31.032384)
			(xy 68.596795 -31.068059) (xy 68.549189 -31.097113) (xy 68.49786 -31.118925) (xy 68.443903 -31.133031)
			(xy 68.388466 -31.139131) (xy 68.332732 -31.137094) (xy 68.277889 -31.126964) (xy 68.225105 -31.108957)
			(xy 68.175505 -31.083456) (xy 68.130147 -31.051005) (xy 68.089998 -31.012296) (xy 68.055912 -30.968153)
			(xy 68.028616 -30.919518) (xy 68.008693 -30.867427) (xy 67.996567 -30.81299) (xy 67.992496 -30.757368)
			(xy 67.320448 -30.757368) (xy 67.314579 -30.79725) (xy 67.298511 -30.850657) (xy 67.274839 -30.901154)
			(xy 67.244066 -30.947667) (xy 67.206849 -30.989204) (xy 67.163981 -31.024879) (xy 67.116375 -31.053933)
			(xy 67.065046 -31.075745) (xy 67.011089 -31.089851) (xy 66.955652 -31.095951) (xy 66.899918 -31.093914)
			(xy 66.845075 -31.083784) (xy 66.792291 -31.065777) (xy 66.742691 -31.040276) (xy 66.697333 -31.007825)
			(xy 66.657184 -30.969116) (xy 66.623098 -30.924973) (xy 66.595802 -30.876338) (xy 66.575879 -30.824247)
			(xy 66.563753 -30.76981) (xy 66.559682 -30.714188) (xy 62.46368 -30.714188) (xy 62.46368 -31.874968)
			(xy 67.159122 -31.874968) (xy 67.163193 -31.819346) (xy 67.175319 -31.764909) (xy 67.195242 -31.712818)
			(xy 67.222538 -31.664183) (xy 67.256624 -31.62004) (xy 67.296773 -31.581331) (xy 67.342131 -31.54888)
			(xy 67.391731 -31.523379) (xy 67.444515 -31.505372) (xy 67.499358 -31.495242) (xy 67.555092 -31.493205)
			(xy 67.610529 -31.499305) (xy 67.664486 -31.513411) (xy 67.715815 -31.535223) (xy 67.763421 -31.564277)
			(xy 67.806289 -31.599952) (xy 67.843506 -31.641489) (xy 67.874279 -31.688002) (xy 67.897951 -31.738499)
			(xy 67.914019 -31.791906) (xy 67.922139 -31.847082) (xy 67.922648 -31.874968) (xy 67.922139 -31.902854)
			(xy 67.914019 -31.95803) (xy 67.897951 -32.011437) (xy 67.874279 -32.061934) (xy 67.843506 -32.108447)
			(xy 67.806289 -32.149984) (xy 67.763421 -32.185659) (xy 67.715815 -32.214713) (xy 67.664486 -32.236525)
			(xy 67.610529 -32.250631) (xy 67.555092 -32.256731) (xy 67.499358 -32.254694) (xy 67.444515 -32.244564)
			(xy 67.391731 -32.226557) (xy 67.342131 -32.201056) (xy 67.296773 -32.168605) (xy 67.256624 -32.129896)
			(xy 67.222538 -32.085753) (xy 67.195242 -32.037118) (xy 67.175319 -31.985027) (xy 67.163193 -31.93059)
			(xy 67.159122 -31.874968) (xy 62.46368 -31.874968) (xy 62.46368 -32.222948) (xy 63.1571 -32.916368)
			(xy 69.67042 -32.916368) (xy 69.674491 -32.860746) (xy 69.686617 -32.806309) (xy 69.70654 -32.754218)
			(xy 69.733836 -32.705583) (xy 69.767922 -32.66144) (xy 69.808071 -32.622731) (xy 69.853429 -32.59028)
			(xy 69.903029 -32.564779) (xy 69.955813 -32.546772) (xy 70.010656 -32.536642) (xy 70.06639 -32.534605)
			(xy 70.121827 -32.540705) (xy 70.175784 -32.554811) (xy 70.227113 -32.576623) (xy 70.274719 -32.605677)
			(xy 70.317587 -32.641352) (xy 70.354804 -32.682889) (xy 70.385577 -32.729402) (xy 70.409249 -32.779899)
			(xy 70.425317 -32.833306) (xy 70.433437 -32.888482) (xy 70.433946 -32.916368) (xy 70.433437 -32.944254)
			(xy 70.425317 -32.99943) (xy 70.409249 -33.052837) (xy 70.385577 -33.103334) (xy 70.354804 -33.149847)
			(xy 70.317587 -33.191384) (xy 70.274719 -33.227059) (xy 70.227113 -33.256113) (xy 70.175784 -33.277925)
			(xy 70.121827 -33.292031) (xy 70.06639 -33.298131) (xy 70.010656 -33.296094) (xy 69.955813 -33.285964)
			(xy 69.903029 -33.267957) (xy 69.853429 -33.242456) (xy 69.808071 -33.210005) (xy 69.767922 -33.171296)
			(xy 69.733836 -33.127153) (xy 69.70654 -33.078518) (xy 69.686617 -33.026427) (xy 69.674491 -32.97199)
			(xy 69.67042 -32.916368) (xy 63.1571 -32.916368) (xy 64.44488 -34.204148) (xy 83.39328 -34.204148)
		)
		(stroke
			(width 0)
			(type solid)
		)
		(fill yes)
		(layer "In2.Cu")
		(net "GND")
	)
	(gr_poly
		(pts
			(xy 387.244844 -332.653132) (xy 387.244844 -327.082912) (xy 387.05028 -326.888348) (xy 368.07648 -302.732948)
			(xy 365.28248 -299.938948) (xy 365.28248 -290.136834) (xy 365.244634 -290.126928) (xy 365.220043 -290.119949)
			(xy 365.173211 -290.099463) (xy 365.130088 -290.072016) (xy 365.091702 -290.038262) (xy 365.058965 -289.999004)
			(xy 365.032657 -289.955177) (xy 365.013404 -289.907825) (xy 365.001666 -289.858075) (xy 364.99772 -289.807111)
			(xy 365.001662 -289.756147) (xy 365.013398 -289.706396) (xy 365.032647 -289.659042) (xy 365.058952 -289.615214)
			(xy 365.091687 -289.575954) (xy 365.130071 -289.542197) (xy 365.173192 -289.514747) (xy 365.220022 -289.494258)
			(xy 365.244634 -289.487356) (xy 365.28248 -289.47745) (xy 365.28248 -288.432748) (xy 365.244634 -288.422842)
			(xy 365.220049 -288.415863) (xy 365.173231 -288.395379) (xy 365.130121 -288.367936) (xy 365.091746 -288.334188)
			(xy 365.05902 -288.294938) (xy 365.032721 -288.25112) (xy 365.013477 -288.203779) (xy 365.001744 -288.15404)
			(xy 364.997804 -288.103089) (xy 365.001748 -288.052138) (xy 365.013484 -288.0024) (xy 365.032731 -287.95506)
			(xy 365.059033 -287.911244) (xy 365.091762 -287.871996) (xy 365.130139 -287.83825) (xy 365.17325 -287.81081)
			(xy 365.22007 -287.790329) (xy 365.244634 -287.78327) (xy 365.28248 -287.773364) (xy 365.28248 -286.805116)
			(xy 365.244634 -286.79521) (xy 365.220044 -286.788231) (xy 365.173215 -286.767745) (xy 365.130095 -286.740299)
			(xy 365.091711 -286.706546) (xy 365.058976 -286.66729) (xy 365.03267 -286.623465) (xy 365.013419 -286.576115)
			(xy 365.001682 -286.526367) (xy 364.997738 -286.475406) (xy 365.00168 -286.424445) (xy 365.013416 -286.374696)
			(xy 365.032665 -286.327346) (xy 365.058969 -286.28352) (xy 365.091702 -286.244263) (xy 365.130085 -286.210508)
			(xy 365.173204 -286.183061) (xy 365.220032 -286.162573) (xy 365.244634 -286.155638) (xy 365.28248 -286.145732)
			(xy 365.28248 -285.17723) (xy 365.244634 -285.167324) (xy 365.220043 -285.160345) (xy 365.173212 -285.139859)
			(xy 365.13009 -285.112412) (xy 365.091704 -285.078658) (xy 365.058967 -285.039401) (xy 365.03266 -284.995574)
			(xy 365.013408 -284.948223) (xy 365.001669 -284.898473) (xy 364.997724 -284.84751) (xy 365.001666 -284.796546)
			(xy 365.013402 -284.746796) (xy 365.032651 -284.699443) (xy 365.058956 -284.655615) (xy 365.09169 -284.616356)
			(xy 365.130074 -284.5826) (xy 365.173195 -284.55515) (xy 365.220024 -284.534661) (xy 365.244634 -284.527752)
			(xy 365.28248 -284.517846) (xy 365.28248 -283.549598) (xy 365.244634 -283.539692) (xy 365.218513 -283.532242)
			(xy 365.168958 -283.510006) (xy 365.123703 -283.479971) (xy 365.083964 -283.442945) (xy 365.050809 -283.399923)
			(xy 365.025131 -283.352062) (xy 365.007617 -283.300648) (xy 364.998741 -283.247063) (xy 364.998254 -283.219906)
			(xy 364.998821 -283.192147) (xy 365.008093 -283.137407) (xy 365.026377 -283.084985) (xy 365.053159 -283.036354)
			(xy 365.087688 -282.992878) (xy 365.128993 -282.95578) (xy 365.152178 -282.940506) (xy 365.164725 -282.931897)
			(xy 365.184501 -282.908792) (xy 365.196606 -282.880893) (xy 365.199968 -282.850667) (xy 365.194292 -282.820789)
			(xy 365.180078 -282.793902) (xy 365.169704 -282.782772) (xy 365.057436 -282.670504) (xy 365.035856 -282.686022)
			(xy 364.988777 -282.710689) (xy 364.938354 -282.727496) (xy 364.885891 -282.736011) (xy 364.859316 -282.736544)
			(xy 364.833327 -282.736036) (xy 364.781988 -282.727907) (xy 364.732553 -282.711848) (xy 364.686239 -282.688254)
			(xy 364.644186 -282.657705) (xy 364.607429 -282.620954) (xy 364.576873 -282.578905) (xy 364.553272 -282.532595)
			(xy 364.537205 -282.483162) (xy 364.529068 -282.431825) (xy 364.528608 -282.405836) (xy 364.529208 -282.37681)
			(xy 364.539324 -282.319646) (xy 364.559253 -282.265121) (xy 364.573312 -282.23972) (xy 364.59287 -282.205938)
			(xy 364.296706 -281.909774) (xy 364.285276 -281.905964) (xy 364.261043 -281.897431) (xy 364.215354 -281.873939)
			(xy 364.173847 -281.843665) (xy 364.137521 -281.807336) (xy 364.107249 -281.765827) (xy 364.083761 -281.720136)
			(xy 364.075218 -281.695906) (xy 364.071408 -281.684476) (xy 363.691424 -281.304492) (xy 363.691424 -281.017726)
			(xy 363.672387 -280.998859) (xy 363.640063 -280.956108) (xy 363.615051 -280.908707) (xy 363.598004 -280.857895)
			(xy 363.589367 -280.805) (xy 363.589367 -280.751405) (xy 363.598003 -280.69851) (xy 363.615049 -280.647698)
			(xy 363.64006 -280.600297) (xy 363.672383 -280.557545) (xy 363.691424 -280.538682) (xy 363.691424 -279.389586)
			(xy 363.672378 -279.370754) (xy 363.640034 -279.328065) (xy 363.615003 -279.280716) (xy 363.597941 -279.229948)
			(xy 363.589296 -279.177092) (xy 363.589294 -279.123533) (xy 363.597935 -279.070676) (xy 363.614993 -279.019907)
			(xy 363.64002 -278.972556) (xy 363.672361 -278.929864) (xy 363.691424 -278.91105) (xy 363.691424 -278.744934)
			(xy 363.691002 -278.731086) (xy 363.683642 -278.704391) (xy 363.669372 -278.680658) (xy 363.649244 -278.661639)
			(xy 363.624743 -278.648734) (xy 363.597673 -278.642895) (xy 363.570031 -278.644552) (xy 363.556804 -278.648668)
			(xy 363.530744 -278.657082) (xy 363.476741 -278.666142) (xy 363.449362 -278.666702) (xy 363.423395 -278.66619)
			(xy 363.372102 -278.658061) (xy 363.322712 -278.64201) (xy 363.276439 -278.618431) (xy 363.234425 -278.587905)
			(xy 363.197702 -278.551183) (xy 363.167174 -278.509169) (xy 363.143594 -278.462898) (xy 363.127541 -278.413508)
			(xy 363.119411 -278.362215) (xy 363.118908 -278.336248) (xy 363.119364 -278.311639) (xy 363.126666 -278.262966)
			(xy 363.141102 -278.215912) (xy 363.162353 -278.171518) (xy 363.189948 -278.130764) (xy 363.223279 -278.09455)
			(xy 363.26161 -278.063676) (xy 363.304093 -278.038825) (xy 363.34979 -278.020544) (xy 363.397692 -278.009238)
			(xy 363.422184 -278.00681) (xy 363.436543 -278.005101) (xy 363.463519 -277.994721) (xy 363.486508 -277.977202)
			(xy 363.503673 -277.953947) (xy 363.513639 -277.926816) (xy 363.51561 -277.897979) (xy 363.509427 -277.869744)
			(xy 363.495586 -277.84437) (xy 363.485684 -277.833836) (xy 363.38129 -277.729442) (xy 363.37106 -277.719818)
			(xy 363.346564 -277.706097) (xy 363.319254 -277.699584) (xy 363.291202 -277.700773) (xy 363.26454 -277.709573)
			(xy 363.241293 -277.725316) (xy 363.231938 -277.735792) (xy 363.216145 -277.7538) (xy 363.180255 -277.785519)
			(xy 363.140165 -277.811728) (xy 363.096712 -277.831878) (xy 363.050808 -277.845549) (xy 363.003411 -277.852454)
			(xy 362.979462 -277.852886) (xy 362.953496 -277.852374) (xy 362.902204 -277.844245) (xy 362.852814 -277.828193)
			(xy 362.806543 -277.804614) (xy 362.76453 -277.774088) (xy 362.727808 -277.737366) (xy 362.697283 -277.695352)
			(xy 362.673704 -277.64908) (xy 362.657653 -277.599691) (xy 362.649526 -277.548398) (xy 362.649008 -277.522432)
			(xy 362.64943 -277.498482) (xy 362.656334 -277.451082) (xy 362.670003 -277.405173) (xy 362.69015 -277.361716)
			(xy 362.716355 -277.321619) (xy 362.748068 -277.285721) (xy 362.766102 -277.269956) (xy 362.776515 -277.260553)
			(xy 362.792186 -277.237291) (xy 362.800951 -277.210648) (xy 362.802151 -277.182626) (xy 362.795696 -277.155331)
			(xy 362.782072 -277.130814) (xy 362.772452 -277.120604) (xy 362.657644 -277.005796) (xy 362.627164 -277.01748)
			(xy 362.598878 -277.027551) (xy 362.539834 -277.038414) (xy 362.509816 -277.03907) (xy 362.483848 -277.038562)
			(xy 362.43255 -277.03044) (xy 362.383154 -277.014393) (xy 362.336877 -276.990816) (xy 362.294857 -276.96029)
			(xy 362.25813 -276.923567) (xy 362.227601 -276.881551) (xy 362.20402 -276.835276) (xy 362.187968 -276.785882)
			(xy 362.179841 -276.734584) (xy 362.179362 -276.708616) (xy 362.180044 -276.678601) (xy 362.190908 -276.619561)
			(xy 362.200952 -276.591268) (xy 362.212636 -276.560788) (xy 361.329478 -275.67763) (xy 358.696768 -275.67763)
			(xy 358.683379 -275.678027) (xy 358.65752 -275.684982) (xy 358.634365 -275.698431) (xy 358.61551 -275.717445)
			(xy 358.602256 -275.740712) (xy 358.595519 -275.766629) (xy 358.595762 -275.793405) (xy 358.598978 -275.806408)
			(xy 358.60459 -275.828073) (xy 358.610581 -275.872423) (xy 358.610916 -275.8948) (xy 358.610433 -275.920768)
			(xy 358.602308 -275.972065) (xy 358.586258 -276.021459) (xy 358.562677 -276.067734) (xy 358.532148 -276.10975)
			(xy 358.495421 -276.146473) (xy 358.453402 -276.176997) (xy 358.407124 -276.200572) (xy 358.357728 -276.216617)
			(xy 358.30643 -276.224736) (xy 358.280462 -276.225254) (xy 358.252366 -276.224696) (xy 358.196983 -276.215201)
			(xy 358.144004 -276.196475) (xy 358.094956 -276.169056) (xy 358.051253 -276.133736) (xy 358.032304 -276.112986)
			(xy 358.022782 -276.10291) (xy 357.99953 -276.087836) (xy 357.973082 -276.079566) (xy 357.945384 -276.078709)
			(xy 357.918475 -276.085326) (xy 357.894335 -276.098932) (xy 357.884222 -276.108414) (xy 357.742744 -276.249892)
			(xy 357.742744 -276.277832) (xy 357.743311 -276.293032) (xy 357.75226 -276.322086) (xy 357.769358 -276.347224)
			(xy 357.793091 -276.366222) (xy 357.821362 -276.3774) (xy 357.83647 -276.379178) (xy 357.862323 -276.381693)
			(xy 357.912832 -276.393811) (xy 357.960822 -276.413682) (xy 358.005113 -276.440816) (xy 358.044613 -276.474546)
			(xy 358.07835 -276.51404) (xy 358.105492 -276.558326) (xy 358.125371 -276.606313) (xy 358.137498 -276.65682)
			(xy 358.141574 -276.708601) (xy 358.137498 -276.760383) (xy 358.125371 -276.810889) (xy 358.105491 -276.858876)
			(xy 358.078348 -276.903162) (xy 358.044612 -276.942656) (xy 358.005111 -276.976385) (xy 357.96082 -277.003519)
			(xy 357.912829 -277.02339) (xy 357.862321 -277.035508) (xy 357.83647 -277.038054) (xy 357.821352 -277.03979)
			(xy 357.793066 -277.05096) (xy 357.769323 -277.069966) (xy 357.752229 -277.09512) (xy 357.743302 -277.124193)
			(xy 357.742744 -277.1394) (xy 357.742744 -277.548399) (xy 357.950517 -277.548399) (xy 357.950517 -277.496465)
			(xy 357.958642 -277.44517) (xy 357.97469 -277.395777) (xy 357.998268 -277.349503) (xy 358.028794 -277.307487)
			(xy 358.065517 -277.270764) (xy 358.107533 -277.240238) (xy 358.153807 -277.21666) (xy 358.2032 -277.200612)
			(xy 358.254495 -277.192487) (xy 358.306429 -277.192487) (xy 358.357724 -277.200612) (xy 358.407117 -277.21666)
			(xy 358.453391 -277.240238) (xy 358.495407 -277.270764) (xy 358.53213 -277.307487) (xy 358.562656 -277.349503)
			(xy 358.586234 -277.395777) (xy 358.602282 -277.44517) (xy 358.610407 -277.496465) (xy 358.610916 -277.522432)
			(xy 358.610407 -277.548399) (xy 358.602282 -277.599694) (xy 358.586234 -277.649087) (xy 358.562656 -277.695361)
			(xy 358.53213 -277.737377) (xy 358.495407 -277.7741) (xy 358.453391 -277.804626) (xy 358.407117 -277.828204)
			(xy 358.357724 -277.844252) (xy 358.306429 -277.852377) (xy 358.254495 -277.852377) (xy 358.2032 -277.844252)
			(xy 358.153807 -277.828204) (xy 358.107533 -277.804626) (xy 358.065517 -277.7741) (xy 358.028794 -277.737377)
			(xy 357.998268 -277.695361) (xy 357.97469 -277.649087) (xy 357.958642 -277.599694) (xy 357.950517 -277.548399)
			(xy 357.742744 -277.548399) (xy 357.742744 -277.905718) (xy 357.743309 -277.92092) (xy 357.752256 -277.949977)
			(xy 357.769353 -277.975118) (xy 357.793087 -277.994119) (xy 357.82136 -278.0053) (xy 357.83647 -278.007064)
			(xy 357.861029 -278.009451) (xy 357.909097 -278.020585) (xy 357.954976 -278.038743) (xy 357.997644 -278.06352)
			(xy 358.036155 -278.094366) (xy 358.06965 -278.130595) (xy 358.097387 -278.171402) (xy 358.118747 -278.21588)
			(xy 358.133257 -278.263039) (xy 358.140593 -278.311832) (xy 358.141016 -278.336502) (xy 358.140538 -278.362215)
			(xy 362.179617 -278.362215) (xy 362.179617 -278.310281) (xy 362.187742 -278.258986) (xy 362.20379 -278.209593)
			(xy 362.227368 -278.163319) (xy 362.257894 -278.121303) (xy 362.294617 -278.08458) (xy 362.336633 -278.054054)
			(xy 362.382907 -278.030476) (xy 362.4323 -278.014428) (xy 362.483595 -278.006303) (xy 362.535529 -278.006303)
			(xy 362.586824 -278.014428) (xy 362.636217 -278.030476) (xy 362.682491 -278.054054) (xy 362.724507 -278.08458)
			(xy 362.76123 -278.121303) (xy 362.791756 -278.163319) (xy 362.815334 -278.209593) (xy 362.831382 -278.258986)
			(xy 362.839507 -278.310281) (xy 362.840016 -278.336248) (xy 362.839507 -278.362215) (xy 362.831382 -278.41351)
			(xy 362.815334 -278.462903) (xy 362.791756 -278.509177) (xy 362.76123 -278.551193) (xy 362.724507 -278.587916)
			(xy 362.682491 -278.618442) (xy 362.636217 -278.64202) (xy 362.586824 -278.658068) (xy 362.535529 -278.666193)
			(xy 362.483595 -278.666193) (xy 362.4323 -278.658068) (xy 362.382907 -278.64202) (xy 362.336633 -278.618442)
			(xy 362.294617 -278.587916) (xy 362.257894 -278.551193) (xy 362.227368 -278.509177) (xy 362.20379 -278.462903)
			(xy 362.187742 -278.41351) (xy 362.179617 -278.362215) (xy 358.140538 -278.362215) (xy 358.140533 -278.36247)
			(xy 358.132407 -278.413767) (xy 358.116357 -278.463161) (xy 358.092777 -278.509435) (xy 358.062247 -278.551451)
			(xy 358.025521 -278.588173) (xy 357.983501 -278.618698) (xy 357.937224 -278.642272) (xy 357.887828 -278.658317)
			(xy 357.83653 -278.666436) (xy 357.810562 -278.666956) (xy 357.785023 -278.666485) (xy 357.73455 -278.658637)
			(xy 357.685886 -278.643119) (xy 357.640188 -278.6203) (xy 357.598544 -278.590723) (xy 357.57993 -278.57323)
			(xy 357.570176 -278.564317) (xy 357.547162 -278.551355) (xy 357.521596 -278.544719) (xy 357.495183 -278.544852)
			(xy 357.469685 -278.551745) (xy 357.446803 -278.564938) (xy 357.437182 -278.573992) (xy 356.834889 -279.176285)
			(xy 362.649517 -279.176285) (xy 362.649517 -279.124351) (xy 362.657642 -279.073056) (xy 362.67369 -279.023663)
			(xy 362.697268 -278.977389) (xy 362.727794 -278.935373) (xy 362.764517 -278.89865) (xy 362.806533 -278.868124)
			(xy 362.852807 -278.844546) (xy 362.9022 -278.828498) (xy 362.953495 -278.820373) (xy 363.005429 -278.820373)
			(xy 363.056724 -278.828498) (xy 363.106117 -278.844546) (xy 363.152391 -278.868124) (xy 363.194407 -278.89865)
			(xy 363.23113 -278.935373) (xy 363.261656 -278.977389) (xy 363.285234 -279.023663) (xy 363.301282 -279.073056)
			(xy 363.309407 -279.124351) (xy 363.309916 -279.150318) (xy 363.309407 -279.176285) (xy 363.301282 -279.22758)
			(xy 363.285234 -279.276973) (xy 363.261656 -279.323247) (xy 363.23113 -279.365263) (xy 363.194407 -279.401986)
			(xy 363.152391 -279.432512) (xy 363.106117 -279.45609) (xy 363.056724 -279.472138) (xy 363.005429 -279.480263)
			(xy 362.953495 -279.480263) (xy 362.9022 -279.472138) (xy 362.852807 -279.45609) (xy 362.806533 -279.432512)
			(xy 362.764517 -279.401986) (xy 362.727794 -279.365263) (xy 362.697268 -279.323247) (xy 362.67369 -279.276973)
			(xy 362.657642 -279.22758) (xy 362.649517 -279.176285) (xy 356.834889 -279.176285) (xy 356.672134 -279.33904)
			(xy 356.669848 -279.342342) (xy 356.652896 -279.365082) (xy 356.612537 -279.404927) (xy 356.589584 -279.42159)
			(xy 356.216712 -279.794462) (xy 356.231444 -279.826466) (xy 356.240919 -279.848166) (xy 356.254272 -279.893593)
			(xy 356.261021 -279.940459) (xy 356.261416 -279.964134) (xy 356.260931 -279.9901) (xy 356.260931 -279.990101)
			(xy 361.239817 -279.990101) (xy 361.239817 -279.938167) (xy 361.247942 -279.886872) (xy 361.26399 -279.837479)
			(xy 361.287568 -279.791205) (xy 361.318094 -279.749189) (xy 361.354817 -279.712466) (xy 361.396833 -279.68194)
			(xy 361.443107 -279.658362) (xy 361.4925 -279.642314) (xy 361.543795 -279.634189) (xy 361.595729 -279.634189)
			(xy 361.647024 -279.642314) (xy 361.696417 -279.658362) (xy 361.742691 -279.68194) (xy 361.784707 -279.712466)
			(xy 361.82143 -279.749189) (xy 361.851956 -279.791205) (xy 361.875534 -279.837479) (xy 361.891582 -279.886872)
			(xy 361.899707 -279.938167) (xy 361.900216 -279.964134) (xy 361.899707 -279.990101) (xy 361.891582 -280.041396)
			(xy 361.875534 -280.090789) (xy 361.851956 -280.137063) (xy 361.82143 -280.179079) (xy 361.784707 -280.215802)
			(xy 361.742691 -280.246328) (xy 361.696417 -280.269906) (xy 361.647024 -280.285954) (xy 361.595729 -280.294079)
			(xy 361.543795 -280.294079) (xy 361.4925 -280.285954) (xy 361.443107 -280.269906) (xy 361.396833 -280.246328)
			(xy 361.354817 -280.215802) (xy 361.318094 -280.179079) (xy 361.287568 -280.137063) (xy 361.26399 -280.090789)
			(xy 361.247942 -280.041396) (xy 361.239817 -279.990101) (xy 356.260931 -279.990101) (xy 356.252801 -280.041393)
			(xy 356.236748 -280.090783) (xy 356.213166 -280.137053) (xy 356.182636 -280.179064) (xy 356.14591 -280.215783)
			(xy 356.103891 -280.246303) (xy 356.057616 -280.269875) (xy 356.008223 -280.285918) (xy 355.956929 -280.294036)
			(xy 355.930962 -280.294588) (xy 355.907285 -280.294204) (xy 355.860414 -280.287477) (xy 355.814987 -280.274109)
			(xy 355.793294 -280.264616) (xy 355.76129 -280.249884) (xy 355.64953 -280.361644) (xy 355.639631 -280.372257)
			(xy 355.625701 -280.397703) (xy 355.619492 -280.426039) (xy 355.621504 -280.454978) (xy 355.631575 -280.482182)
			(xy 355.648892 -280.505455) (xy 355.660198 -280.514552) (xy 355.680227 -280.530269) (xy 355.715668 -280.566818)
			(xy 355.745088 -280.608368) (xy 355.767791 -280.653935) (xy 355.783242 -280.702445) (xy 355.791075 -280.752749)
			(xy 355.791516 -280.778204) (xy 355.791033 -280.804171) (xy 357.950517 -280.804171) (xy 357.950517 -280.752237)
			(xy 357.958642 -280.700942) (xy 357.97469 -280.651549) (xy 357.998268 -280.605275) (xy 358.028794 -280.563259)
			(xy 358.065517 -280.526536) (xy 358.107533 -280.49601) (xy 358.153807 -280.472432) (xy 358.2032 -280.456384)
			(xy 358.254495 -280.448259) (xy 358.306429 -280.448259) (xy 358.357724 -280.456384) (xy 358.407117 -280.472432)
			(xy 358.453391 -280.49601) (xy 358.495407 -280.526536) (xy 358.53213 -280.563259) (xy 358.562656 -280.605275)
			(xy 358.586234 -280.651549) (xy 358.602282 -280.700942) (xy 358.610407 -280.752237) (xy 358.610916 -280.778204)
			(xy 358.610407 -280.804171) (xy 358.602282 -280.855466) (xy 358.586234 -280.904859) (xy 358.562656 -280.951133)
			(xy 358.53213 -280.993149) (xy 358.495407 -281.029872) (xy 358.453391 -281.060398) (xy 358.407117 -281.083976)
			(xy 358.357724 -281.100024) (xy 358.306429 -281.108149) (xy 358.254495 -281.108149) (xy 358.2032 -281.100024)
			(xy 358.153807 -281.083976) (xy 358.107533 -281.060398) (xy 358.065517 -281.029872) (xy 358.028794 -280.993149)
			(xy 357.998268 -280.951133) (xy 357.97469 -280.904859) (xy 357.958642 -280.855466) (xy 357.950517 -280.804171)
			(xy 355.791033 -280.804171) (xy 355.791033 -280.804172) (xy 355.782907 -280.855468) (xy 355.766856 -280.904862)
			(xy 355.743276 -280.951136) (xy 355.712746 -280.993152) (xy 355.67602 -281.029874) (xy 355.634 -281.060398)
			(xy 355.587723 -281.083972) (xy 355.538328 -281.100017) (xy 355.48703 -281.108136) (xy 355.461062 -281.108658)
			(xy 355.435605 -281.108192) (xy 355.385294 -281.100388) (xy 355.336776 -281.084955) (xy 355.291201 -281.062259)
			(xy 355.249649 -281.032838) (xy 355.213105 -280.997388) (xy 355.19741 -280.97734) (xy 355.18826 -280.96609)
			(xy 355.164988 -280.948811) (xy 355.137802 -280.938759) (xy 355.108888 -280.936741) (xy 355.080569 -280.94292)
			(xy 355.055123 -280.956798) (xy 355.044502 -280.966672) (xy 354.92309 -281.088084) (xy 354.912887 -281.099013)
			(xy 354.898752 -281.125343) (xy 354.892837 -281.154637) (xy 354.895649 -281.184389) (xy 354.906947 -281.212056)
			(xy 354.925764 -281.235272) (xy 354.950493 -281.252052) (xy 354.979019 -281.260962) (xy 354.993956 -281.261566)
			(xy 355.019791 -281.262265) (xy 355.070777 -281.270705) (xy 355.119827 -281.286979) (xy 355.165746 -281.310691)
			(xy 355.207414 -281.341263) (xy 355.243814 -281.377948) (xy 355.274059 -281.419852) (xy 355.297413 -281.465954)
			(xy 355.313304 -281.51513) (xy 355.321346 -281.56618) (xy 355.32187 -281.59202) (xy 355.321359 -281.617987)
			(xy 361.239817 -281.617987) (xy 361.239817 -281.566053) (xy 361.247942 -281.514758) (xy 361.26399 -281.465365)
			(xy 361.287568 -281.419091) (xy 361.318094 -281.377075) (xy 361.354817 -281.340352) (xy 361.396833 -281.309826)
			(xy 361.443107 -281.286248) (xy 361.4925 -281.2702) (xy 361.543795 -281.262075) (xy 361.595729 -281.262075)
			(xy 361.647024 -281.2702) (xy 361.696417 -281.286248) (xy 361.742691 -281.309826) (xy 361.784707 -281.340352)
			(xy 361.82143 -281.377075) (xy 361.851956 -281.419091) (xy 361.875534 -281.465365) (xy 361.891582 -281.514758)
			(xy 361.899707 -281.566053) (xy 361.900216 -281.59202) (xy 361.899707 -281.617987) (xy 361.891582 -281.669282)
			(xy 361.875534 -281.718675) (xy 361.851956 -281.764949) (xy 361.82143 -281.806965) (xy 361.784707 -281.843688)
			(xy 361.742691 -281.874214) (xy 361.696417 -281.897792) (xy 361.647024 -281.91384) (xy 361.595729 -281.921965)
			(xy 361.543795 -281.921965) (xy 361.4925 -281.91384) (xy 361.443107 -281.897792) (xy 361.396833 -281.874214)
			(xy 361.354817 -281.843688) (xy 361.318094 -281.806965) (xy 361.287568 -281.764949) (xy 361.26399 -281.718675)
			(xy 361.247942 -281.669282) (xy 361.239817 -281.617987) (xy 355.321359 -281.617987) (xy 355.313233 -281.66928)
			(xy 355.297182 -281.718671) (xy 355.273604 -281.764943) (xy 355.243077 -281.806958) (xy 355.206355 -281.84368)
			(xy 355.16434 -281.874206) (xy 355.118067 -281.897784) (xy 355.068676 -281.913833) (xy 355.017383 -281.92196)
			(xy 354.991416 -281.922474) (xy 354.965574 -281.921976) (xy 354.91452 -281.913933) (xy 354.865341 -281.89804)
			(xy 354.819236 -281.874684) (xy 354.777328 -281.844437) (xy 354.74064 -281.808033) (xy 354.710066 -281.766363)
			(xy 354.686352 -281.720441) (xy 354.670077 -281.671387) (xy 354.661635 -281.620397) (xy 354.660962 -281.59456)
			(xy 354.660287 -281.579633) (xy 354.651364 -281.55113) (xy 354.634584 -281.526422) (xy 354.61138 -281.507617)
			(xy 354.583732 -281.496321) (xy 354.553999 -281.493496) (xy 354.524718 -281.499385) (xy 354.498388 -281.513484)
			(xy 354.48748 -281.523694) (xy 354.380038 -281.631136) (xy 354.377498 -281.646884) (xy 354.374986 -281.66085)
			(xy 354.367861 -281.68832) (xy 354.363274 -281.701748) (xy 354.3554 -281.723846) (xy 354.559108 -282.076652)
			(xy 354.582222 -282.08097) (xy 354.607155 -282.086118) (xy 354.655163 -282.103055) (xy 354.700005 -282.127155)
			(xy 354.740619 -282.15785) (xy 354.776044 -282.194411) (xy 354.805442 -282.235974) (xy 354.828116 -282.281554)
			(xy 354.843529 -282.330073) (xy 354.851318 -282.380382) (xy 354.851716 -282.405836) (xy 354.851207 -282.431803)
			(xy 355.131117 -282.431803) (xy 355.131117 -282.379869) (xy 355.139242 -282.328574) (xy 355.15529 -282.279181)
			(xy 355.178868 -282.232907) (xy 355.209394 -282.190891) (xy 355.246117 -282.154168) (xy 355.288133 -282.123642)
			(xy 355.334407 -282.100064) (xy 355.3838 -282.084016) (xy 355.435095 -282.075891) (xy 355.487029 -282.075891)
			(xy 355.538324 -282.084016) (xy 355.587717 -282.100064) (xy 355.633991 -282.123642) (xy 355.676007 -282.154168)
			(xy 355.71273 -282.190891) (xy 355.743256 -282.232907) (xy 355.766834 -282.279181) (xy 355.782882 -282.328574)
			(xy 355.791007 -282.379869) (xy 355.791516 -282.405836) (xy 355.791007 -282.431803) (xy 357.950517 -282.431803)
			(xy 357.950517 -282.379869) (xy 357.958642 -282.328574) (xy 357.97469 -282.279181) (xy 357.998268 -282.232907)
			(xy 358.028794 -282.190891) (xy 358.065517 -282.154168) (xy 358.107533 -282.123642) (xy 358.153807 -282.100064)
			(xy 358.2032 -282.084016) (xy 358.254495 -282.075891) (xy 358.306429 -282.075891) (xy 358.357724 -282.084016)
			(xy 358.407117 -282.100064) (xy 358.453391 -282.123642) (xy 358.495407 -282.154168) (xy 358.53213 -282.190891)
			(xy 358.562656 -282.232907) (xy 358.586234 -282.279181) (xy 358.602282 -282.328574) (xy 358.610407 -282.379869)
			(xy 358.610916 -282.405836) (xy 358.610407 -282.431803) (xy 358.602282 -282.483098) (xy 358.586234 -282.532491)
			(xy 358.562656 -282.578765) (xy 358.53213 -282.620781) (xy 358.495407 -282.657504) (xy 358.453391 -282.68803)
			(xy 358.407117 -282.711608) (xy 358.357724 -282.727656) (xy 358.306429 -282.735781) (xy 358.254495 -282.735781)
			(xy 358.2032 -282.727656) (xy 358.153807 -282.711608) (xy 358.107533 -282.68803) (xy 358.065517 -282.657504)
			(xy 358.028794 -282.620781) (xy 357.998268 -282.578765) (xy 357.97469 -282.532491) (xy 357.958642 -282.483098)
			(xy 357.950517 -282.431803) (xy 355.791007 -282.431803) (xy 355.782882 -282.483098) (xy 355.766834 -282.532491)
			(xy 355.743256 -282.578765) (xy 355.71273 -282.620781) (xy 355.676007 -282.657504) (xy 355.633991 -282.68803)
			(xy 355.587717 -282.711608) (xy 355.538324 -282.727656) (xy 355.487029 -282.735781) (xy 355.435095 -282.735781)
			(xy 355.3838 -282.727656) (xy 355.334407 -282.711608) (xy 355.288133 -282.68803) (xy 355.246117 -282.657504)
			(xy 355.209394 -282.620781) (xy 355.178868 -282.578765) (xy 355.15529 -282.532491) (xy 355.139242 -282.483098)
			(xy 355.131117 -282.431803) (xy 354.851207 -282.431803) (xy 354.843082 -282.483098) (xy 354.827034 -282.532491)
			(xy 354.803456 -282.578765) (xy 354.77293 -282.620781) (xy 354.736207 -282.657504) (xy 354.694191 -282.68803)
			(xy 354.647917 -282.711608) (xy 354.598524 -282.727656) (xy 354.547229 -282.735781) (xy 354.495295 -282.735781)
			(xy 354.444 -282.727656) (xy 354.394607 -282.711608) (xy 354.348333 -282.68803) (xy 354.306317 -282.657504)
			(xy 354.269594 -282.620781) (xy 354.239068 -282.578765) (xy 354.21549 -282.532491) (xy 354.199442 -282.483098)
			(xy 354.191317 -282.431803) (xy 354.190808 -282.405836) (xy 354.191418 -282.377855) (xy 354.200864 -282.322696)
			(xy 354.209604 -282.296108) (xy 354.217224 -282.27401) (xy 354.10775 -282.084272) (xy 354.10071 -282.072964)
			(xy 354.081874 -282.054143) (xy 354.058815 -282.040828) (xy 354.033098 -282.033926) (xy 354.006471 -282.033904)
			(xy 353.980742 -282.040763) (xy 353.957661 -282.054039) (xy 353.947984 -282.06319) (xy 353.826826 -282.184348)
			(xy 353.84277 -282.202665) (xy 353.869666 -282.243096) (xy 353.890357 -282.287028) (xy 353.904396 -282.333515)
			(xy 353.911482 -282.381556) (xy 353.911916 -282.405836) (xy 353.911453 -282.431273) (xy 353.903668 -282.481547)
			(xy 353.88827 -282.530035) (xy 353.865625 -282.575591) (xy 353.836267 -282.617139) (xy 353.800889 -282.653697)
			(xy 353.760327 -282.684403) (xy 353.715539 -282.708531) (xy 353.667582 -282.725511) (xy 353.642676 -282.730702)
			(xy 353.619562 -282.73502) (xy 353.475544 -282.984702) (xy 353.475544 -283.245873) (xy 353.721417 -283.245873)
			(xy 353.721417 -283.193939) (xy 353.729542 -283.142644) (xy 353.74559 -283.093251) (xy 353.769168 -283.046977)
			(xy 353.799694 -283.004961) (xy 353.836417 -282.968238) (xy 353.878433 -282.937712) (xy 353.924707 -282.914134)
			(xy 353.9741 -282.898086) (xy 354.025395 -282.889961) (xy 354.077329 -282.889961) (xy 354.128624 -282.898086)
			(xy 354.178017 -282.914134) (xy 354.224291 -282.937712) (xy 354.266307 -282.968238) (xy 354.30303 -283.004961)
			(xy 354.333556 -283.046977) (xy 354.357134 -283.093251) (xy 354.373182 -283.142644) (xy 354.381307 -283.193939)
			(xy 354.381816 -283.219906) (xy 354.381307 -283.245873) (xy 354.661471 -283.245873) (xy 354.661471 -283.193939)
			(xy 354.669596 -283.142644) (xy 354.685644 -283.093251) (xy 354.709222 -283.046977) (xy 354.739748 -283.004961)
			(xy 354.776471 -282.968238) (xy 354.818487 -282.937712) (xy 354.864761 -282.914134) (xy 354.914154 -282.898086)
			(xy 354.965449 -282.889961) (xy 355.017383 -282.889961) (xy 355.068678 -282.898086) (xy 355.118071 -282.914134)
			(xy 355.164345 -282.937712) (xy 355.206361 -282.968238) (xy 355.243084 -283.004961) (xy 355.27361 -283.046977)
			(xy 355.297188 -283.093251) (xy 355.313236 -283.142644) (xy 355.321361 -283.193939) (xy 355.32187 -283.219906)
			(xy 355.321361 -283.245873) (xy 361.239817 -283.245873) (xy 361.239817 -283.193939) (xy 361.247942 -283.142644)
			(xy 361.26399 -283.093251) (xy 361.287568 -283.046977) (xy 361.318094 -283.004961) (xy 361.354817 -282.968238)
			(xy 361.396833 -282.937712) (xy 361.443107 -282.914134) (xy 361.4925 -282.898086) (xy 361.543795 -282.889961)
			(xy 361.595729 -282.889961) (xy 361.647024 -282.898086) (xy 361.696417 -282.914134) (xy 361.742691 -282.937712)
			(xy 361.784707 -282.968238) (xy 361.82143 -283.004961) (xy 361.851956 -283.046977) (xy 361.875534 -283.093251)
			(xy 361.891582 -283.142644) (xy 361.899707 -283.193939) (xy 361.900216 -283.219906) (xy 361.899707 -283.245873)
			(xy 364.059471 -283.245873) (xy 364.059471 -283.193939) (xy 364.067596 -283.142644) (xy 364.083644 -283.093251)
			(xy 364.107222 -283.046977) (xy 364.137748 -283.004961) (xy 364.174471 -282.968238) (xy 364.216487 -282.937712)
			(xy 364.262761 -282.914134) (xy 364.312154 -282.898086) (xy 364.363449 -282.889961) (xy 364.415383 -282.889961)
			(xy 364.466678 -282.898086) (xy 364.516071 -282.914134) (xy 364.562345 -282.937712) (xy 364.604361 -282.968238)
			(xy 364.641084 -283.004961) (xy 364.67161 -283.046977) (xy 364.695188 -283.093251) (xy 364.711236 -283.142644)
			(xy 364.719361 -283.193939) (xy 364.71987 -283.219906) (xy 364.719361 -283.245873) (xy 364.711236 -283.297168)
			(xy 364.695188 -283.346561) (xy 364.67161 -283.392835) (xy 364.641084 -283.434851) (xy 364.604361 -283.471574)
			(xy 364.562345 -283.5021) (xy 364.516071 -283.525678) (xy 364.466678 -283.541726) (xy 364.415383 -283.549851)
			(xy 364.363449 -283.549851) (xy 364.312154 -283.541726) (xy 364.262761 -283.525678) (xy 364.216487 -283.5021)
			(xy 364.174471 -283.471574) (xy 364.137748 -283.434851) (xy 364.107222 -283.392835) (xy 364.083644 -283.346561)
			(xy 364.067596 -283.297168) (xy 364.059471 -283.245873) (xy 361.899707 -283.245873) (xy 361.891582 -283.297168)
			(xy 361.875534 -283.346561) (xy 361.851956 -283.392835) (xy 361.82143 -283.434851) (xy 361.784707 -283.471574)
			(xy 361.742691 -283.5021) (xy 361.696417 -283.525678) (xy 361.647024 -283.541726) (xy 361.595729 -283.549851)
			(xy 361.543795 -283.549851) (xy 361.4925 -283.541726) (xy 361.443107 -283.525678) (xy 361.396833 -283.5021)
			(xy 361.354817 -283.471574) (xy 361.318094 -283.434851) (xy 361.287568 -283.392835) (xy 361.26399 -283.346561)
			(xy 361.247942 -283.297168) (xy 361.239817 -283.245873) (xy 355.321361 -283.245873) (xy 355.313236 -283.297168)
			(xy 355.297188 -283.346561) (xy 355.27361 -283.392835) (xy 355.243084 -283.434851) (xy 355.206361 -283.471574)
			(xy 355.164345 -283.5021) (xy 355.118071 -283.525678) (xy 355.068678 -283.541726) (xy 355.017383 -283.549851)
			(xy 354.965449 -283.549851) (xy 354.914154 -283.541726) (xy 354.864761 -283.525678) (xy 354.818487 -283.5021)
			(xy 354.776471 -283.471574) (xy 354.739748 -283.434851) (xy 354.709222 -283.392835) (xy 354.685644 -283.346561)
			(xy 354.669596 -283.297168) (xy 354.661471 -283.245873) (xy 354.381307 -283.245873) (xy 354.373182 -283.297168)
			(xy 354.357134 -283.346561) (xy 354.333556 -283.392835) (xy 354.30303 -283.434851) (xy 354.266307 -283.471574)
			(xy 354.224291 -283.5021) (xy 354.178017 -283.525678) (xy 354.128624 -283.541726) (xy 354.077329 -283.549851)
			(xy 354.025395 -283.549851) (xy 353.9741 -283.541726) (xy 353.924707 -283.525678) (xy 353.878433 -283.5021)
			(xy 353.836417 -283.471574) (xy 353.799694 -283.434851) (xy 353.769168 -283.392835) (xy 353.74559 -283.346561)
			(xy 353.729542 -283.297168) (xy 353.721417 -283.245873) (xy 353.475544 -283.245873) (xy 353.475544 -283.601668)
			(xy 353.475946 -283.615082) (xy 353.482924 -283.640986) (xy 353.496406 -283.664179) (xy 353.515462 -283.683062)
			(xy 353.538777 -283.696331) (xy 353.564744 -283.703072) (xy 353.57816 -283.703268) (xy 353.581462 -283.703268)
			(xy 353.607432 -283.703748) (xy 353.658732 -283.711868) (xy 353.70813 -283.727913) (xy 353.75441 -283.751489)
			(xy 353.796432 -283.782015) (xy 353.83316 -283.818739) (xy 353.863691 -283.860758) (xy 353.887272 -283.907035)
			(xy 353.903323 -283.956431) (xy 353.911449 -284.007731) (xy 353.911449 -284.059669) (xy 353.911446 -284.059689)
			(xy 355.131117 -284.059689) (xy 355.131117 -284.007755) (xy 355.139242 -283.95646) (xy 355.15529 -283.907067)
			(xy 355.178868 -283.860793) (xy 355.209394 -283.818777) (xy 355.246117 -283.782054) (xy 355.288133 -283.751528)
			(xy 355.334407 -283.72795) (xy 355.3838 -283.711902) (xy 355.435095 -283.703777) (xy 355.487029 -283.703777)
			(xy 355.538324 -283.711902) (xy 355.587717 -283.72795) (xy 355.633991 -283.751528) (xy 355.676007 -283.782054)
			(xy 355.71273 -283.818777) (xy 355.743256 -283.860793) (xy 355.766834 -283.907067) (xy 355.782882 -283.95646)
			(xy 355.791007 -284.007755) (xy 355.791516 -284.033722) (xy 355.791007 -284.059689) (xy 357.950517 -284.059689)
			(xy 357.950517 -284.007755) (xy 357.958642 -283.95646) (xy 357.97469 -283.907067) (xy 357.998268 -283.860793)
			(xy 358.028794 -283.818777) (xy 358.065517 -283.782054) (xy 358.107533 -283.751528) (xy 358.153807 -283.72795)
			(xy 358.2032 -283.711902) (xy 358.254495 -283.703777) (xy 358.306429 -283.703777) (xy 358.357724 -283.711902)
			(xy 358.407117 -283.72795) (xy 358.453391 -283.751528) (xy 358.495407 -283.782054) (xy 358.53213 -283.818777)
			(xy 358.562656 -283.860793) (xy 358.586234 -283.907067) (xy 358.602282 -283.95646) (xy 358.610407 -284.007755)
			(xy 358.610916 -284.033722) (xy 358.610407 -284.059689) (xy 358.602282 -284.110984) (xy 358.586234 -284.160377)
			(xy 358.562656 -284.206651) (xy 358.53213 -284.248667) (xy 358.495407 -284.28539) (xy 358.453391 -284.315916)
			(xy 358.407117 -284.339494) (xy 358.357724 -284.355542) (xy 358.306429 -284.363667) (xy 358.254495 -284.363667)
			(xy 358.2032 -284.355542) (xy 358.153807 -284.339494) (xy 358.107533 -284.315916) (xy 358.065517 -284.28539)
			(xy 358.028794 -284.248667) (xy 357.998268 -284.206651) (xy 357.97469 -284.160377) (xy 357.958642 -284.110984)
			(xy 357.950517 -284.059689) (xy 355.791007 -284.059689) (xy 355.782882 -284.110984) (xy 355.766834 -284.160377)
			(xy 355.743256 -284.206651) (xy 355.71273 -284.248667) (xy 355.676007 -284.28539) (xy 355.633991 -284.315916)
			(xy 355.587717 -284.339494) (xy 355.538324 -284.355542) (xy 355.487029 -284.363667) (xy 355.435095 -284.363667)
			(xy 355.3838 -284.355542) (xy 355.334407 -284.339494) (xy 355.288133 -284.315916) (xy 355.246117 -284.28539)
			(xy 355.209394 -284.248667) (xy 355.178868 -284.206651) (xy 355.15529 -284.160377) (xy 355.139242 -284.110984)
			(xy 355.131117 -284.059689) (xy 353.911446 -284.059689) (xy 353.903323 -284.110969) (xy 353.887272 -284.160365)
			(xy 353.863691 -284.206642) (xy 353.83316 -284.248661) (xy 353.796432 -284.285385) (xy 353.75441 -284.315911)
			(xy 353.70813 -284.339487) (xy 353.658732 -284.355532) (xy 353.607432 -284.363652) (xy 353.581462 -284.364176)
			(xy 353.57816 -284.364176) (xy 353.564743 -284.364443) (xy 353.53877 -284.37116) (xy 353.515443 -284.38441)
			(xy 353.496373 -284.403279) (xy 353.482875 -284.426463) (xy 353.475881 -284.452362) (xy 353.475544 -284.465776)
			(xy 353.475544 -284.873505) (xy 361.239817 -284.873505) (xy 361.239817 -284.821571) (xy 361.247942 -284.770276)
			(xy 361.26399 -284.720883) (xy 361.287568 -284.674609) (xy 361.318094 -284.632593) (xy 361.354817 -284.59587)
			(xy 361.396833 -284.565344) (xy 361.443107 -284.541766) (xy 361.4925 -284.525718) (xy 361.543795 -284.517593)
			(xy 361.595729 -284.517593) (xy 361.647024 -284.525718) (xy 361.696417 -284.541766) (xy 361.742691 -284.565344)
			(xy 361.784707 -284.59587) (xy 361.82143 -284.632593) (xy 361.851956 -284.674609) (xy 361.875534 -284.720883)
			(xy 361.891582 -284.770276) (xy 361.899707 -284.821571) (xy 361.900216 -284.847538) (xy 361.899707 -284.873505)
			(xy 364.059471 -284.873505) (xy 364.059471 -284.821571) (xy 364.067596 -284.770276) (xy 364.083644 -284.720883)
			(xy 364.107222 -284.674609) (xy 364.137748 -284.632593) (xy 364.174471 -284.59587) (xy 364.216487 -284.565344)
			(xy 364.262761 -284.541766) (xy 364.312154 -284.525718) (xy 364.363449 -284.517593) (xy 364.415383 -284.517593)
			(xy 364.466678 -284.525718) (xy 364.516071 -284.541766) (xy 364.562345 -284.565344) (xy 364.604361 -284.59587)
			(xy 364.641084 -284.632593) (xy 364.67161 -284.674609) (xy 364.695188 -284.720883) (xy 364.711236 -284.770276)
			(xy 364.719361 -284.821571) (xy 364.71987 -284.847538) (xy 364.719361 -284.873505) (xy 364.711236 -284.9248)
			(xy 364.695188 -284.974193) (xy 364.67161 -285.020467) (xy 364.641084 -285.062483) (xy 364.604361 -285.099206)
			(xy 364.562345 -285.129732) (xy 364.516071 -285.15331) (xy 364.466678 -285.169358) (xy 364.415383 -285.177483)
			(xy 364.363449 -285.177483) (xy 364.312154 -285.169358) (xy 364.262761 -285.15331) (xy 364.216487 -285.129732)
			(xy 364.174471 -285.099206) (xy 364.137748 -285.062483) (xy 364.107222 -285.020467) (xy 364.083644 -284.974193)
			(xy 364.067596 -284.9248) (xy 364.059471 -284.873505) (xy 361.899707 -284.873505) (xy 361.891582 -284.9248)
			(xy 361.875534 -284.974193) (xy 361.851956 -285.020467) (xy 361.82143 -285.062483) (xy 361.784707 -285.099206)
			(xy 361.742691 -285.129732) (xy 361.696417 -285.15331) (xy 361.647024 -285.169358) (xy 361.595729 -285.177483)
			(xy 361.543795 -285.177483) (xy 361.4925 -285.169358) (xy 361.443107 -285.15331) (xy 361.396833 -285.129732)
			(xy 361.354817 -285.099206) (xy 361.318094 -285.062483) (xy 361.287568 -285.020467) (xy 361.26399 -284.974193)
			(xy 361.247942 -284.9248) (xy 361.239817 -284.873505) (xy 353.475544 -284.873505) (xy 353.475544 -285.687321)
			(xy 355.131117 -285.687321) (xy 355.131117 -285.635387) (xy 355.139242 -285.584092) (xy 355.15529 -285.534699)
			(xy 355.178868 -285.488425) (xy 355.209394 -285.446409) (xy 355.246117 -285.409686) (xy 355.288133 -285.37916)
			(xy 355.334407 -285.355582) (xy 355.3838 -285.339534) (xy 355.435095 -285.331409) (xy 355.487029 -285.331409)
			(xy 355.538324 -285.339534) (xy 355.587717 -285.355582) (xy 355.633991 -285.37916) (xy 355.676007 -285.409686)
			(xy 355.71273 -285.446409) (xy 355.743256 -285.488425) (xy 355.766834 -285.534699) (xy 355.782882 -285.584092)
			(xy 355.791007 -285.635387) (xy 355.791516 -285.661354) (xy 355.791007 -285.687321) (xy 357.950517 -285.687321)
			(xy 357.950517 -285.635387) (xy 357.958642 -285.584092) (xy 357.97469 -285.534699) (xy 357.998268 -285.488425)
			(xy 358.028794 -285.446409) (xy 358.065517 -285.409686) (xy 358.107533 -285.37916) (xy 358.153807 -285.355582)
			(xy 358.2032 -285.339534) (xy 358.254495 -285.331409) (xy 358.306429 -285.331409) (xy 358.357724 -285.339534)
			(xy 358.407117 -285.355582) (xy 358.453391 -285.37916) (xy 358.495407 -285.409686) (xy 358.53213 -285.446409)
			(xy 358.562656 -285.488425) (xy 358.586234 -285.534699) (xy 358.602282 -285.584092) (xy 358.610407 -285.635387)
			(xy 358.610916 -285.661354) (xy 358.610407 -285.687321) (xy 358.602282 -285.738616) (xy 358.586234 -285.788009)
			(xy 358.562656 -285.834283) (xy 358.53213 -285.876299) (xy 358.495407 -285.913022) (xy 358.453391 -285.943548)
			(xy 358.407117 -285.967126) (xy 358.357724 -285.983174) (xy 358.306429 -285.991299) (xy 358.254495 -285.991299)
			(xy 358.2032 -285.983174) (xy 358.153807 -285.967126) (xy 358.107533 -285.943548) (xy 358.065517 -285.913022)
			(xy 358.028794 -285.876299) (xy 357.998268 -285.834283) (xy 357.97469 -285.788009) (xy 357.958642 -285.738616)
			(xy 357.950517 -285.687321) (xy 355.791007 -285.687321) (xy 355.782882 -285.738616) (xy 355.766834 -285.788009)
			(xy 355.743256 -285.834283) (xy 355.71273 -285.876299) (xy 355.676007 -285.913022) (xy 355.633991 -285.943548)
			(xy 355.587717 -285.967126) (xy 355.538324 -285.983174) (xy 355.487029 -285.991299) (xy 355.435095 -285.991299)
			(xy 355.3838 -285.983174) (xy 355.334407 -285.967126) (xy 355.288133 -285.943548) (xy 355.246117 -285.913022)
			(xy 355.209394 -285.876299) (xy 355.178868 -285.834283) (xy 355.15529 -285.788009) (xy 355.139242 -285.738616)
			(xy 355.131117 -285.687321) (xy 353.475544 -285.687321) (xy 353.475544 -286.501391) (xy 361.239817 -286.501391)
			(xy 361.239817 -286.449457) (xy 361.247942 -286.398162) (xy 361.26399 -286.348769) (xy 361.287568 -286.302495)
			(xy 361.318094 -286.260479) (xy 361.354817 -286.223756) (xy 361.396833 -286.19323) (xy 361.443107 -286.169652)
			(xy 361.4925 -286.153604) (xy 361.543795 -286.145479) (xy 361.595729 -286.145479) (xy 361.647024 -286.153604)
			(xy 361.696417 -286.169652) (xy 361.742691 -286.19323) (xy 361.784707 -286.223756) (xy 361.82143 -286.260479)
			(xy 361.851956 -286.302495) (xy 361.875534 -286.348769) (xy 361.891582 -286.398162) (xy 361.899707 -286.449457)
			(xy 361.900216 -286.475424) (xy 361.899707 -286.501391) (xy 364.059471 -286.501391) (xy 364.059471 -286.449457)
			(xy 364.067596 -286.398162) (xy 364.083644 -286.348769) (xy 364.107222 -286.302495) (xy 364.137748 -286.260479)
			(xy 364.174471 -286.223756) (xy 364.216487 -286.19323) (xy 364.262761 -286.169652) (xy 364.312154 -286.153604)
			(xy 364.363449 -286.145479) (xy 364.415383 -286.145479) (xy 364.466678 -286.153604) (xy 364.516071 -286.169652)
			(xy 364.562345 -286.19323) (xy 364.604361 -286.223756) (xy 364.641084 -286.260479) (xy 364.67161 -286.302495)
			(xy 364.695188 -286.348769) (xy 364.711236 -286.398162) (xy 364.719361 -286.449457) (xy 364.71987 -286.475424)
			(xy 364.719361 -286.501391) (xy 364.711236 -286.552686) (xy 364.695188 -286.602079) (xy 364.67161 -286.648353)
			(xy 364.641084 -286.690369) (xy 364.604361 -286.727092) (xy 364.562345 -286.757618) (xy 364.516071 -286.781196)
			(xy 364.466678 -286.797244) (xy 364.415383 -286.805369) (xy 364.363449 -286.805369) (xy 364.312154 -286.797244)
			(xy 364.262761 -286.781196) (xy 364.216487 -286.757618) (xy 364.174471 -286.727092) (xy 364.137748 -286.690369)
			(xy 364.107222 -286.648353) (xy 364.083644 -286.602079) (xy 364.067596 -286.552686) (xy 364.059471 -286.501391)
			(xy 361.899707 -286.501391) (xy 361.891582 -286.552686) (xy 361.875534 -286.602079) (xy 361.851956 -286.648353)
			(xy 361.82143 -286.690369) (xy 361.784707 -286.727092) (xy 361.742691 -286.757618) (xy 361.696417 -286.781196)
			(xy 361.647024 -286.797244) (xy 361.595729 -286.805369) (xy 361.543795 -286.805369) (xy 361.4925 -286.797244)
			(xy 361.443107 -286.781196) (xy 361.396833 -286.757618) (xy 361.354817 -286.727092) (xy 361.318094 -286.690369)
			(xy 361.287568 -286.648353) (xy 361.26399 -286.602079) (xy 361.247942 -286.552686) (xy 361.239817 -286.501391)
			(xy 353.475544 -286.501391) (xy 353.475544 -287.315207) (xy 355.131117 -287.315207) (xy 355.131117 -287.263273)
			(xy 355.139242 -287.211978) (xy 355.15529 -287.162585) (xy 355.178868 -287.116311) (xy 355.209394 -287.074295)
			(xy 355.246117 -287.037572) (xy 355.288133 -287.007046) (xy 355.334407 -286.983468) (xy 355.3838 -286.96742)
			(xy 355.435095 -286.959295) (xy 355.487029 -286.959295) (xy 355.538324 -286.96742) (xy 355.587717 -286.983468)
			(xy 355.633991 -287.007046) (xy 355.676007 -287.037572) (xy 355.71273 -287.074295) (xy 355.743256 -287.116311)
			(xy 355.766834 -287.162585) (xy 355.782882 -287.211978) (xy 355.791007 -287.263273) (xy 355.791516 -287.28924)
			(xy 355.791007 -287.315207) (xy 357.950517 -287.315207) (xy 357.950517 -287.263273) (xy 357.958642 -287.211978)
			(xy 357.97469 -287.162585) (xy 357.998268 -287.116311) (xy 358.028794 -287.074295) (xy 358.065517 -287.037572)
			(xy 358.107533 -287.007046) (xy 358.153807 -286.983468) (xy 358.2032 -286.96742) (xy 358.254495 -286.959295)
			(xy 358.306429 -286.959295) (xy 358.357724 -286.96742) (xy 358.407117 -286.983468) (xy 358.453391 -287.007046)
			(xy 358.495407 -287.037572) (xy 358.53213 -287.074295) (xy 358.562656 -287.116311) (xy 358.586234 -287.162585)
			(xy 358.602282 -287.211978) (xy 358.610407 -287.263273) (xy 358.610916 -287.28924) (xy 358.610407 -287.315207)
			(xy 358.602282 -287.366502) (xy 358.586234 -287.415895) (xy 358.562656 -287.462169) (xy 358.53213 -287.504185)
			(xy 358.495407 -287.540908) (xy 358.453391 -287.571434) (xy 358.407117 -287.595012) (xy 358.357724 -287.61106)
			(xy 358.306429 -287.619185) (xy 358.254495 -287.619185) (xy 358.2032 -287.61106) (xy 358.153807 -287.595012)
			(xy 358.107533 -287.571434) (xy 358.065517 -287.540908) (xy 358.028794 -287.504185) (xy 357.998268 -287.462169)
			(xy 357.97469 -287.415895) (xy 357.958642 -287.366502) (xy 357.950517 -287.315207) (xy 355.791007 -287.315207)
			(xy 355.782882 -287.366502) (xy 355.766834 -287.415895) (xy 355.743256 -287.462169) (xy 355.71273 -287.504185)
			(xy 355.676007 -287.540908) (xy 355.633991 -287.571434) (xy 355.587717 -287.595012) (xy 355.538324 -287.61106)
			(xy 355.487029 -287.619185) (xy 355.435095 -287.619185) (xy 355.3838 -287.61106) (xy 355.334407 -287.595012)
			(xy 355.288133 -287.571434) (xy 355.246117 -287.540908) (xy 355.209394 -287.504185) (xy 355.178868 -287.462169)
			(xy 355.15529 -287.415895) (xy 355.139242 -287.366502) (xy 355.131117 -287.315207) (xy 353.475544 -287.315207)
			(xy 353.475544 -288.129023) (xy 361.239817 -288.129023) (xy 361.239817 -288.077089) (xy 361.247942 -288.025794)
			(xy 361.26399 -287.976401) (xy 361.287568 -287.930127) (xy 361.318094 -287.888111) (xy 361.354817 -287.851388)
			(xy 361.396833 -287.820862) (xy 361.443107 -287.797284) (xy 361.4925 -287.781236) (xy 361.543795 -287.773111)
			(xy 361.595729 -287.773111) (xy 361.647024 -287.781236) (xy 361.696417 -287.797284) (xy 361.742691 -287.820862)
			(xy 361.784707 -287.851388) (xy 361.82143 -287.888111) (xy 361.851956 -287.930127) (xy 361.875534 -287.976401)
			(xy 361.891582 -288.025794) (xy 361.899707 -288.077089) (xy 361.900216 -288.103056) (xy 361.899707 -288.129023)
			(xy 364.059471 -288.129023) (xy 364.059471 -288.077089) (xy 364.067596 -288.025794) (xy 364.083644 -287.976401)
			(xy 364.107222 -287.930127) (xy 364.137748 -287.888111) (xy 364.174471 -287.851388) (xy 364.216487 -287.820862)
			(xy 364.262761 -287.797284) (xy 364.312154 -287.781236) (xy 364.363449 -287.773111) (xy 364.415383 -287.773111)
			(xy 364.466678 -287.781236) (xy 364.516071 -287.797284) (xy 364.562345 -287.820862) (xy 364.604361 -287.851388)
			(xy 364.641084 -287.888111) (xy 364.67161 -287.930127) (xy 364.695188 -287.976401) (xy 364.711236 -288.025794)
			(xy 364.719361 -288.077089) (xy 364.71987 -288.103056) (xy 364.719361 -288.129023) (xy 364.711236 -288.180318)
			(xy 364.695188 -288.229711) (xy 364.67161 -288.275985) (xy 364.641084 -288.318001) (xy 364.604361 -288.354724)
			(xy 364.562345 -288.38525) (xy 364.516071 -288.408828) (xy 364.466678 -288.424876) (xy 364.415383 -288.433001)
			(xy 364.363449 -288.433001) (xy 364.312154 -288.424876) (xy 364.262761 -288.408828) (xy 364.216487 -288.38525)
			(xy 364.174471 -288.354724) (xy 364.137748 -288.318001) (xy 364.107222 -288.275985) (xy 364.083644 -288.229711)
			(xy 364.067596 -288.180318) (xy 364.059471 -288.129023) (xy 361.899707 -288.129023) (xy 361.891582 -288.180318)
			(xy 361.875534 -288.229711) (xy 361.851956 -288.275985) (xy 361.82143 -288.318001) (xy 361.784707 -288.354724)
			(xy 361.742691 -288.38525) (xy 361.696417 -288.408828) (xy 361.647024 -288.424876) (xy 361.595729 -288.433001)
			(xy 361.543795 -288.433001) (xy 361.4925 -288.424876) (xy 361.443107 -288.408828) (xy 361.396833 -288.38525)
			(xy 361.354817 -288.354724) (xy 361.318094 -288.318001) (xy 361.287568 -288.275985) (xy 361.26399 -288.229711)
			(xy 361.247942 -288.180318) (xy 361.239817 -288.129023) (xy 353.475544 -288.129023) (xy 353.475544 -288.943093)
			(xy 355.131371 -288.943093) (xy 355.131371 -288.891159) (xy 355.139496 -288.839864) (xy 355.155544 -288.790471)
			(xy 355.179122 -288.744197) (xy 355.209648 -288.702181) (xy 355.246371 -288.665458) (xy 355.288387 -288.634932)
			(xy 355.334661 -288.611354) (xy 355.384054 -288.595306) (xy 355.435349 -288.587181) (xy 355.487283 -288.587181)
			(xy 355.538578 -288.595306) (xy 355.587971 -288.611354) (xy 355.634245 -288.634932) (xy 355.676261 -288.665458)
			(xy 355.712984 -288.702181) (xy 355.74351 -288.744197) (xy 355.767088 -288.790471) (xy 355.783136 -288.839864)
			(xy 355.791261 -288.891159) (xy 355.79177 -288.917126) (xy 355.791261 -288.943093) (xy 355.783136 -288.994388)
			(xy 355.775044 -289.019293) (xy 357.950771 -289.019293) (xy 357.950771 -288.967359) (xy 357.958896 -288.916064)
			(xy 357.974944 -288.866671) (xy 357.998522 -288.820397) (xy 358.029048 -288.778381) (xy 358.065771 -288.741658)
			(xy 358.107787 -288.711132) (xy 358.154061 -288.687554) (xy 358.203454 -288.671506) (xy 358.254749 -288.663381)
			(xy 358.306683 -288.663381) (xy 358.357978 -288.671506) (xy 358.407371 -288.687554) (xy 358.453645 -288.711132)
			(xy 358.495661 -288.741658) (xy 358.532384 -288.778381) (xy 358.56291 -288.820397) (xy 358.586488 -288.866671)
			(xy 358.602536 -288.916064) (xy 358.610661 -288.967359) (xy 358.61117 -288.993326) (xy 358.610661 -289.019293)
			(xy 358.602536 -289.070588) (xy 358.586488 -289.119981) (xy 358.56291 -289.166255) (xy 358.532384 -289.208271)
			(xy 358.495661 -289.244994) (xy 358.453645 -289.27552) (xy 358.407371 -289.299098) (xy 358.357978 -289.315146)
			(xy 358.306683 -289.323271) (xy 358.254749 -289.323271) (xy 358.203454 -289.315146) (xy 358.154061 -289.299098)
			(xy 358.107787 -289.27552) (xy 358.065771 -289.244994) (xy 358.029048 -289.208271) (xy 357.998522 -289.166255)
			(xy 357.974944 -289.119981) (xy 357.958896 -289.070588) (xy 357.950771 -289.019293) (xy 355.775044 -289.019293)
			(xy 355.767088 -289.043781) (xy 355.74351 -289.090055) (xy 355.712984 -289.132071) (xy 355.676261 -289.168794)
			(xy 355.634245 -289.19932) (xy 355.587971 -289.222898) (xy 355.538578 -289.238946) (xy 355.487283 -289.247071)
			(xy 355.435349 -289.247071) (xy 355.384054 -289.238946) (xy 355.334661 -289.222898) (xy 355.288387 -289.19932)
			(xy 355.246371 -289.168794) (xy 355.209648 -289.132071) (xy 355.179122 -289.090055) (xy 355.155544 -289.043781)
			(xy 355.139496 -288.994388) (xy 355.131371 -288.943093) (xy 353.475544 -288.943093) (xy 353.475544 -289.08883)
			(xy 352.858578 -289.705796) (xy 352.858578 -289.97783) (xy 352.445828 -290.39058) (xy 352.445828 -292.644576)
			(xy 352.467064 -292.661321) (xy 352.505052 -292.69981) (xy 352.537229 -292.743275) (xy 352.56295 -292.790845)
			(xy 352.5817 -292.84157) (xy 352.593103 -292.894433) (xy 352.596932 -292.948376) (xy 352.594482 -292.982951)
			(xy 357.228881 -292.982951) (xy 357.228881 -292.928449) (xy 357.236638 -292.874501) (xy 357.251993 -292.822207)
			(xy 357.274634 -292.77263) (xy 357.3041 -292.72678) (xy 357.339792 -292.68559) (xy 357.380982 -292.649899)
			(xy 357.426832 -292.620433) (xy 357.476409 -292.597792) (xy 357.528703 -292.582437) (xy 357.582651 -292.574681)
			(xy 357.609902 -292.574218) (xy 357.637272 -292.574679) (xy 357.691452 -292.582497) (xy 357.743955 -292.597987)
			(xy 357.793702 -292.62083) (xy 357.839669 -292.650556) (xy 357.8606 -292.668198) (xy 357.871928 -292.677434)
			(xy 357.898485 -292.68961) (xy 357.927402 -292.693783) (xy 357.956319 -292.68961) (xy 357.982876 -292.677434)
			(xy 357.994204 -292.668198) (xy 358.015123 -292.650543) (xy 358.0611 -292.620834) (xy 358.11085 -292.598001)
			(xy 358.163354 -292.582514) (xy 358.217532 -292.57469) (xy 358.244902 -292.574218) (xy 358.272155 -292.574652)
			(xy 358.326106 -292.582409) (xy 358.378404 -292.597766) (xy 358.427985 -292.620408) (xy 358.473838 -292.649877)
			(xy 358.515031 -292.685571) (xy 358.550724 -292.726764) (xy 358.580193 -292.772617) (xy 358.602835 -292.822198)
			(xy 358.618191 -292.874496) (xy 358.625948 -292.928447) (xy 358.625948 -292.982949) (xy 363.686604 -292.982949)
			(xy 363.686604 -292.928451) (xy 363.69436 -292.874507) (xy 363.709714 -292.822216) (xy 363.732354 -292.772642)
			(xy 363.761818 -292.726795) (xy 363.797506 -292.685608) (xy 363.838694 -292.649919) (xy 363.884541 -292.620454)
			(xy 363.934114 -292.597815) (xy 363.986405 -292.582461) (xy 364.040349 -292.574704) (xy 364.067598 -292.574218)
			(xy 364.094968 -292.574681) (xy 364.149148 -292.582499) (xy 364.201651 -292.597988) (xy 364.251398 -292.620831)
			(xy 364.297365 -292.650556) (xy 364.318296 -292.668198) (xy 364.329624 -292.677434) (xy 364.356181 -292.68961)
			(xy 364.385098 -292.693783) (xy 364.414015 -292.68961) (xy 364.440572 -292.677434) (xy 364.4519 -292.668198)
			(xy 364.472821 -292.650545) (xy 364.518797 -292.620835) (xy 364.568547 -292.598002) (xy 364.62105 -292.582514)
			(xy 364.675228 -292.57469) (xy 364.702598 -292.574218) (xy 364.729853 -292.574629) (xy 364.783808 -292.582386)
			(xy 364.836109 -292.597743) (xy 364.885693 -292.620387) (xy 364.93155 -292.649857) (xy 364.972746 -292.685553)
			(xy 365.008442 -292.726749) (xy 365.037912 -292.772605) (xy 365.060556 -292.822189) (xy 365.075914 -292.87449)
			(xy 365.083671 -292.928445) (xy 365.083671 -292.982955) (xy 365.075914 -293.03691) (xy 365.060556 -293.089211)
			(xy 365.037912 -293.138795) (xy 365.008442 -293.184651) (xy 364.972746 -293.225847) (xy 364.93155 -293.261543)
			(xy 364.885693 -293.291013) (xy 364.836109 -293.313657) (xy 364.783808 -293.329014) (xy 364.729853 -293.336771)
			(xy 364.702598 -293.337234) (xy 364.675227 -293.336785) (xy 364.621046 -293.328966) (xy 364.568543 -293.313473)
			(xy 364.518796 -293.290627) (xy 364.47283 -293.260898) (xy 364.4519 -293.243254) (xy 364.440572 -293.234018)
			(xy 364.414015 -293.221842) (xy 364.385098 -293.217669) (xy 364.356181 -293.221842) (xy 364.329624 -293.234018)
			(xy 364.318296 -293.243254) (xy 364.29737 -293.260901) (xy 364.251397 -293.290613) (xy 364.201647 -293.313449)
			(xy 364.149145 -293.328938) (xy 364.094968 -293.336762) (xy 364.067598 -293.337234) (xy 364.040349 -293.336696)
			(xy 363.986405 -293.328939) (xy 363.934114 -293.313585) (xy 363.884541 -293.290946) (xy 363.838694 -293.261481)
			(xy 363.797506 -293.225792) (xy 363.761818 -293.184605) (xy 363.732354 -293.138758) (xy 363.709714 -293.089184)
			(xy 363.69436 -293.036893) (xy 363.686604 -292.982949) (xy 358.625948 -292.982949) (xy 358.625948 -292.982953)
			(xy 358.618191 -293.036904) (xy 358.602835 -293.089202) (xy 358.580193 -293.138783) (xy 358.550724 -293.184636)
			(xy 358.515031 -293.225829) (xy 358.473838 -293.261523) (xy 358.427985 -293.290992) (xy 358.378404 -293.313634)
			(xy 358.326106 -293.328991) (xy 358.272155 -293.336748) (xy 358.244902 -293.337234) (xy 358.217531 -293.336783)
			(xy 358.163351 -293.328964) (xy 358.110847 -293.313472) (xy 358.0611 -293.290627) (xy 358.015135 -293.260898)
			(xy 357.994204 -293.243254) (xy 357.982876 -293.234018) (xy 357.956319 -293.221842) (xy 357.927402 -293.217669)
			(xy 357.898485 -293.221842) (xy 357.871928 -293.234018) (xy 357.8606 -293.243254) (xy 357.839673 -293.260899)
			(xy 357.793699 -293.290612) (xy 357.743951 -293.313447) (xy 357.691449 -293.328937) (xy 357.637272 -293.336762)
			(xy 357.609902 -293.337234) (xy 357.582651 -293.336719) (xy 357.528703 -293.328963) (xy 357.476409 -293.313608)
			(xy 357.426832 -293.290967) (xy 357.380982 -293.261501) (xy 357.339792 -293.22581) (xy 357.3041 -293.18462)
			(xy 357.274634 -293.13877) (xy 357.251993 -293.089193) (xy 357.236638 -293.036899) (xy 357.228881 -292.982951)
			(xy 352.594482 -292.982951) (xy 352.59311 -293.002319) (xy 352.581713 -293.055184) (xy 352.56297 -293.105911)
			(xy 352.537255 -293.153485) (xy 352.505084 -293.196953) (xy 352.4671 -293.235447) (xy 352.445828 -293.252144)
			(xy 352.445828 -294.722296) (xy 352.467062 -294.739041) (xy 352.505048 -294.777529) (xy 352.537222 -294.820993)
			(xy 352.562941 -294.868563) (xy 352.581688 -294.919286) (xy 352.593089 -294.972147) (xy 352.596916 -295.026088)
			(xy 352.594105 -295.065751) (xy 357.228881 -295.065751) (xy 357.228881 -295.011249) (xy 357.236638 -294.957301)
			(xy 357.251993 -294.905007) (xy 357.274634 -294.85543) (xy 357.3041 -294.80958) (xy 357.339792 -294.76839)
			(xy 357.380982 -294.732699) (xy 357.426832 -294.703233) (xy 357.476409 -294.680592) (xy 357.528703 -294.665237)
			(xy 357.582651 -294.657481) (xy 357.609902 -294.657018) (xy 357.640025 -294.657597) (xy 357.699521 -294.667077)
			(xy 357.756788 -294.685787) (xy 357.810405 -294.713261) (xy 357.85904 -294.748816) (xy 357.880666 -294.769794)
			(xy 357.890388 -294.779012) (xy 357.91355 -294.792457) (xy 357.939411 -294.799419) (xy 357.966193 -294.799419)
			(xy 357.992054 -294.792457) (xy 358.015216 -294.779012) (xy 358.024938 -294.769794) (xy 358.046566 -294.748817)
			(xy 358.095194 -294.713249) (xy 358.14881 -294.685768) (xy 358.206079 -294.667059) (xy 358.265578 -294.657587)
			(xy 358.295702 -294.657018) (xy 358.322955 -294.657452) (xy 358.376906 -294.665209) (xy 358.429204 -294.680566)
			(xy 358.478785 -294.703208) (xy 358.524638 -294.732677) (xy 358.565831 -294.768371) (xy 358.601524 -294.809564)
			(xy 358.630993 -294.855417) (xy 358.653635 -294.904998) (xy 358.668991 -294.957296) (xy 358.676748 -295.011247)
			(xy 358.676748 -295.065749) (xy 363.572304 -295.065749) (xy 363.572304 -295.011251) (xy 363.58006 -294.957307)
			(xy 363.595414 -294.905016) (xy 363.618054 -294.855442) (xy 363.647518 -294.809595) (xy 363.683206 -294.768408)
			(xy 363.724394 -294.732719) (xy 363.770241 -294.703254) (xy 363.819814 -294.680615) (xy 363.872105 -294.665261)
			(xy 363.926049 -294.657504) (xy 363.953298 -294.657018) (xy 363.980668 -294.657481) (xy 364.034848 -294.665299)
			(xy 364.087351 -294.680788) (xy 364.137098 -294.703631) (xy 364.183065 -294.733356) (xy 364.203996 -294.750998)
			(xy 364.215324 -294.760234) (xy 364.241881 -294.77241) (xy 364.270798 -294.776583) (xy 364.299715 -294.77241)
			(xy 364.326272 -294.760234) (xy 364.3376 -294.750998) (xy 364.358521 -294.733345) (xy 364.404497 -294.703635)
			(xy 364.454247 -294.680802) (xy 364.50675 -294.665314) (xy 364.560928 -294.65749) (xy 364.588298 -294.657018)
			(xy 364.615553 -294.657429) (xy 364.669508 -294.665186) (xy 364.721809 -294.680543) (xy 364.771393 -294.703187)
			(xy 364.81725 -294.732657) (xy 364.858446 -294.768353) (xy 364.894142 -294.809549) (xy 364.923612 -294.855405)
			(xy 364.946256 -294.904989) (xy 364.961614 -294.95729) (xy 364.969371 -295.011245) (xy 364.969371 -295.065755)
			(xy 364.961614 -295.11971) (xy 364.946256 -295.172011) (xy 364.923612 -295.221595) (xy 364.894142 -295.267451)
			(xy 364.858446 -295.308647) (xy 364.81725 -295.344343) (xy 364.771393 -295.373813) (xy 364.721809 -295.396457)
			(xy 364.669508 -295.411814) (xy 364.615553 -295.419571) (xy 364.588298 -295.420034) (xy 364.560927 -295.419585)
			(xy 364.506746 -295.411766) (xy 364.454243 -295.396273) (xy 364.404496 -295.373427) (xy 364.35853 -295.343698)
			(xy 364.3376 -295.326054) (xy 364.326272 -295.316818) (xy 364.299715 -295.304642) (xy 364.270798 -295.300469)
			(xy 364.241881 -295.304642) (xy 364.215324 -295.316818) (xy 364.203996 -295.326054) (xy 364.18307 -295.343701)
			(xy 364.137097 -295.373413) (xy 364.087347 -295.396249) (xy 364.034845 -295.411738) (xy 363.980668 -295.419562)
			(xy 363.953298 -295.420034) (xy 363.926049 -295.419496) (xy 363.872105 -295.411739) (xy 363.819814 -295.396385)
			(xy 363.770241 -295.373746) (xy 363.724394 -295.344281) (xy 363.683206 -295.308592) (xy 363.647518 -295.267405)
			(xy 363.618054 -295.221558) (xy 363.595414 -295.171984) (xy 363.58006 -295.119693) (xy 363.572304 -295.065749)
			(xy 358.676748 -295.065749) (xy 358.676748 -295.065753) (xy 358.668991 -295.119704) (xy 358.653635 -295.172002)
			(xy 358.630993 -295.221583) (xy 358.601524 -295.267436) (xy 358.565831 -295.308629) (xy 358.524638 -295.344323)
			(xy 358.478785 -295.373792) (xy 358.429204 -295.396434) (xy 358.376906 -295.411791) (xy 358.322955 -295.419548)
			(xy 358.295702 -295.420034) (xy 358.265578 -295.419467) (xy 358.206082 -295.409986) (xy 358.148813 -295.391274)
			(xy 358.095196 -295.363797) (xy 358.046562 -295.328238) (xy 358.024938 -295.307258) (xy 358.015216 -295.29804)
			(xy 357.992054 -295.284595) (xy 357.966193 -295.277633) (xy 357.939411 -295.277633) (xy 357.91355 -295.284595)
			(xy 357.890388 -295.29804) (xy 357.880666 -295.307258) (xy 357.859028 -295.328224) (xy 357.810404 -295.363796)
			(xy 357.756791 -295.39128) (xy 357.699523 -295.409991) (xy 357.640025 -295.419465) (xy 357.609902 -295.420034)
			(xy 357.582651 -295.419519) (xy 357.528703 -295.411763) (xy 357.476409 -295.396408) (xy 357.426832 -295.373767)
			(xy 357.380982 -295.344301) (xy 357.339792 -295.30861) (xy 357.3041 -295.26742) (xy 357.274634 -295.22157)
			(xy 357.251993 -295.171993) (xy 357.236638 -295.119699) (xy 357.228881 -295.065751) (xy 352.594105 -295.065751)
			(xy 352.593093 -295.080029) (xy 352.581695 -295.132891) (xy 352.562951 -295.183615) (xy 352.537235 -295.231186)
			(xy 352.505064 -295.274652) (xy 352.46708 -295.313143) (xy 352.445828 -295.329864) (xy 352.445828 -296.766996)
			(xy 352.467062 -296.783741) (xy 352.505048 -296.822229) (xy 352.537222 -296.865693) (xy 352.562941 -296.913263)
			(xy 352.581688 -296.963986) (xy 352.593089 -297.016847) (xy 352.596916 -297.070788) (xy 352.593093 -297.124729)
			(xy 352.581695 -297.177591) (xy 352.564268 -297.224751) (xy 357.228881 -297.224751) (xy 357.228881 -297.170249)
			(xy 357.236638 -297.116301) (xy 357.251993 -297.064007) (xy 357.274634 -297.01443) (xy 357.3041 -296.96858)
			(xy 357.339792 -296.92739) (xy 357.380982 -296.891699) (xy 357.426832 -296.862233) (xy 357.476409 -296.839592)
			(xy 357.528703 -296.824237) (xy 357.582651 -296.816481) (xy 357.609902 -296.816018) (xy 357.640025 -296.816597)
			(xy 357.699521 -296.826077) (xy 357.756788 -296.844787) (xy 357.810405 -296.872261) (xy 357.85904 -296.907816)
			(xy 357.880666 -296.928794) (xy 357.890388 -296.938012) (xy 357.91355 -296.951457) (xy 357.939411 -296.958419)
			(xy 357.966193 -296.958419) (xy 357.992054 -296.951457) (xy 358.015216 -296.938012) (xy 358.024938 -296.928794)
			(xy 358.046566 -296.907817) (xy 358.095194 -296.872249) (xy 358.14881 -296.844768) (xy 358.206079 -296.826059)
			(xy 358.265578 -296.816587) (xy 358.295702 -296.816018) (xy 358.322955 -296.816452) (xy 358.376906 -296.824209)
			(xy 358.429204 -296.839566) (xy 358.478785 -296.862208) (xy 358.524638 -296.891677) (xy 358.565831 -296.927371)
			(xy 358.601524 -296.968564) (xy 358.630993 -297.014417) (xy 358.653635 -297.063998) (xy 358.668991 -297.116296)
			(xy 358.676748 -297.170247) (xy 358.676748 -297.224749) (xy 363.572304 -297.224749) (xy 363.572304 -297.170251)
			(xy 363.58006 -297.116307) (xy 363.595414 -297.064016) (xy 363.618054 -297.014442) (xy 363.647518 -296.968595)
			(xy 363.683206 -296.927408) (xy 363.724394 -296.891719) (xy 363.770241 -296.862254) (xy 363.819814 -296.839615)
			(xy 363.872105 -296.824261) (xy 363.926049 -296.816504) (xy 363.953298 -296.816018) (xy 363.980668 -296.816481)
			(xy 364.034848 -296.824299) (xy 364.087351 -296.839788) (xy 364.137098 -296.862631) (xy 364.183065 -296.892356)
			(xy 364.203996 -296.909998) (xy 364.215324 -296.919234) (xy 364.241881 -296.93141) (xy 364.270798 -296.935583)
			(xy 364.299715 -296.93141) (xy 364.326272 -296.919234) (xy 364.3376 -296.909998) (xy 364.358521 -296.892345)
			(xy 364.404497 -296.862635) (xy 364.454247 -296.839802) (xy 364.50675 -296.824314) (xy 364.560928 -296.81649)
			(xy 364.588298 -296.816018) (xy 364.615553 -296.816429) (xy 364.669508 -296.824186) (xy 364.721809 -296.839543)
			(xy 364.771393 -296.862187) (xy 364.81725 -296.891657) (xy 364.858446 -296.927353) (xy 364.894142 -296.968549)
			(xy 364.923612 -297.014405) (xy 364.946256 -297.063989) (xy 364.961614 -297.11629) (xy 364.969371 -297.170245)
			(xy 364.969371 -297.224755) (xy 364.961614 -297.27871) (xy 364.946256 -297.331011) (xy 364.923612 -297.380595)
			(xy 364.894142 -297.426451) (xy 364.858446 -297.467647) (xy 364.81725 -297.503343) (xy 364.771393 -297.532813)
			(xy 364.721809 -297.555457) (xy 364.669508 -297.570814) (xy 364.615553 -297.578571) (xy 364.588298 -297.579034)
			(xy 364.560927 -297.578585) (xy 364.506746 -297.570766) (xy 364.454243 -297.555273) (xy 364.404496 -297.532427)
			(xy 364.35853 -297.502698) (xy 364.3376 -297.485054) (xy 364.326272 -297.475818) (xy 364.299715 -297.463642)
			(xy 364.270798 -297.459469) (xy 364.241881 -297.463642) (xy 364.215324 -297.475818) (xy 364.203996 -297.485054)
			(xy 364.18307 -297.502701) (xy 364.137097 -297.532413) (xy 364.087347 -297.555249) (xy 364.034845 -297.570738)
			(xy 363.980668 -297.578562) (xy 363.953298 -297.579034) (xy 363.926049 -297.578496) (xy 363.872105 -297.570739)
			(xy 363.819814 -297.555385) (xy 363.770241 -297.532746) (xy 363.724394 -297.503281) (xy 363.683206 -297.467592)
			(xy 363.647518 -297.426405) (xy 363.618054 -297.380558) (xy 363.595414 -297.330984) (xy 363.58006 -297.278693)
			(xy 363.572304 -297.224749) (xy 358.676748 -297.224749) (xy 358.676748 -297.224753) (xy 358.668991 -297.278704)
			(xy 358.653635 -297.331002) (xy 358.630993 -297.380583) (xy 358.601524 -297.426436) (xy 358.565831 -297.467629)
			(xy 358.524638 -297.503323) (xy 358.478785 -297.532792) (xy 358.429204 -297.555434) (xy 358.376906 -297.570791)
			(xy 358.322955 -297.578548) (xy 358.295702 -297.579034) (xy 358.265578 -297.578467) (xy 358.206082 -297.568986)
			(xy 358.148813 -297.550274) (xy 358.095196 -297.522797) (xy 358.046562 -297.487238) (xy 358.024938 -297.466258)
			(xy 358.015216 -297.45704) (xy 357.992054 -297.443595) (xy 357.966193 -297.436633) (xy 357.939411 -297.436633)
			(xy 357.91355 -297.443595) (xy 357.890388 -297.45704) (xy 357.880666 -297.466258) (xy 357.859028 -297.487224)
			(xy 357.810404 -297.522796) (xy 357.756791 -297.55028) (xy 357.699523 -297.568991) (xy 357.640025 -297.578465)
			(xy 357.609902 -297.579034) (xy 357.582651 -297.578519) (xy 357.528703 -297.570763) (xy 357.476409 -297.555408)
			(xy 357.426832 -297.532767) (xy 357.380982 -297.503301) (xy 357.339792 -297.46761) (xy 357.3041 -297.42642)
			(xy 357.274634 -297.38057) (xy 357.251993 -297.330993) (xy 357.236638 -297.278699) (xy 357.228881 -297.224751)
			(xy 352.564268 -297.224751) (xy 352.562951 -297.228315) (xy 352.537235 -297.275886) (xy 352.505064 -297.319352)
			(xy 352.46708 -297.357843) (xy 352.445828 -297.374564) (xy 352.445828 -303.29886) (xy 340.03495 -315.709738)
			(xy 345.576648 -315.709738) (xy 345.576648 -315.625042) (xy 345.584699 -315.540728) (xy 345.600728 -315.457562)
			(xy 345.624589 -315.376295) (xy 345.656068 -315.297665) (xy 345.694879 -315.222384) (xy 345.740669 -315.151132)
			(xy 345.793025 -315.084556) (xy 345.851473 -315.023258) (xy 345.915483 -314.967793) (xy 345.984475 -314.918664)
			(xy 346.057825 -314.876315) (xy 346.134868 -314.841131) (xy 346.214907 -314.813429) (xy 346.297216 -314.793461)
			(xy 346.381051 -314.781408) (xy 346.465652 -314.777378) (xy 346.550253 -314.781408) (xy 346.634088 -314.793461)
			(xy 346.716397 -314.813429) (xy 346.796436 -314.841131) (xy 346.873479 -314.876315) (xy 346.946829 -314.918664)
			(xy 347.015821 -314.967793) (xy 347.079831 -315.023258) (xy 347.138279 -315.084556) (xy 347.190635 -315.151132)
			(xy 347.236425 -315.222384) (xy 347.275236 -315.297665) (xy 347.306715 -315.376295) (xy 347.330576 -315.457562)
			(xy 347.346605 -315.540728) (xy 347.354656 -315.625042) (xy 347.35516 -315.66739) (xy 347.550237 -315.66739)
			(xy 347.554259 -315.58167) (xy 347.56629 -315.496702) (xy 347.586226 -315.413235) (xy 347.613889 -315.332001)
			(xy 347.649038 -315.253715) (xy 347.691364 -315.179064) (xy 347.740493 -315.108705) (xy 347.795996 -315.043255)
			(xy 347.857383 -314.983291) (xy 347.924116 -314.929338) (xy 347.995608 -314.881871) (xy 348.07123 -314.841307)
			(xy 348.150319 -314.808003) (xy 348.232179 -314.782251) (xy 348.31609 -314.764278) (xy 348.401316 -314.754242)
			(xy 348.487108 -314.75223) (xy 348.57271 -314.758261) (xy 348.657372 -314.772281) (xy 348.740349 -314.794167)
			(xy 348.820912 -314.823728) (xy 348.898352 -314.860702) (xy 348.971991 -314.904766) (xy 349.041179 -314.955532)
			(xy 349.10531 -315.012553) (xy 349.163819 -315.075329) (xy 349.216192 -315.143309) (xy 349.26197 -315.215894)
			(xy 349.30075 -315.292446) (xy 349.332191 -315.372294) (xy 349.356017 -315.454735) (xy 349.372018 -315.539045)
			(xy 349.380053 -315.624483) (xy 349.380556 -315.66739) (xy 349.38006 -315.709738) (xy 351.774248 -315.709738)
			(xy 351.774248 -315.625042) (xy 351.782299 -315.540728) (xy 351.798328 -315.457562) (xy 351.822189 -315.376295)
			(xy 351.853668 -315.297665) (xy 351.892479 -315.222384) (xy 351.938269 -315.151132) (xy 351.990625 -315.084556)
			(xy 352.049073 -315.023258) (xy 352.113083 -314.967793) (xy 352.182075 -314.918664) (xy 352.255425 -314.876315)
			(xy 352.332468 -314.841131) (xy 352.412507 -314.813429) (xy 352.494816 -314.793461) (xy 352.578651 -314.781408)
			(xy 352.663252 -314.777378) (xy 352.747853 -314.781408) (xy 352.831688 -314.793461) (xy 352.913997 -314.813429)
			(xy 352.994036 -314.841131) (xy 353.071079 -314.876315) (xy 353.144429 -314.918664) (xy 353.213421 -314.967793)
			(xy 353.277431 -315.023258) (xy 353.335879 -315.084556) (xy 353.388235 -315.151132) (xy 353.434025 -315.222384)
			(xy 353.472836 -315.297665) (xy 353.504315 -315.376295) (xy 353.528176 -315.457562) (xy 353.544205 -315.540728)
			(xy 353.552256 -315.625042) (xy 353.55276 -315.66739) (xy 353.747837 -315.66739) (xy 353.751859 -315.58167)
			(xy 353.76389 -315.496702) (xy 353.783826 -315.413235) (xy 353.811489 -315.332001) (xy 353.846638 -315.253715)
			(xy 353.888964 -315.179064) (xy 353.938093 -315.108705) (xy 353.993596 -315.043255) (xy 354.054983 -314.983291)
			(xy 354.121716 -314.929338) (xy 354.193208 -314.881871) (xy 354.26883 -314.841307) (xy 354.347919 -314.808003)
			(xy 354.429779 -314.782251) (xy 354.51369 -314.764278) (xy 354.598916 -314.754242) (xy 354.684708 -314.75223)
			(xy 354.77031 -314.758261) (xy 354.854972 -314.772281) (xy 354.937949 -314.794167) (xy 355.018512 -314.823728)
			(xy 355.095952 -314.860702) (xy 355.169591 -314.904766) (xy 355.238779 -314.955532) (xy 355.30291 -315.012553)
			(xy 355.361419 -315.075329) (xy 355.413792 -315.143309) (xy 355.45957 -315.215894) (xy 355.49835 -315.292446)
			(xy 355.529791 -315.372294) (xy 355.553617 -315.454735) (xy 355.569618 -315.539045) (xy 355.577653 -315.624483)
			(xy 355.578156 -315.66739) (xy 355.57766 -315.709738) (xy 357.952036 -315.709738) (xy 357.952036 -315.625042)
			(xy 357.960087 -315.540728) (xy 357.976116 -315.457562) (xy 357.999977 -315.376295) (xy 358.031456 -315.297665)
			(xy 358.070267 -315.222384) (xy 358.116057 -315.151132) (xy 358.168413 -315.084556) (xy 358.226861 -315.023258)
			(xy 358.290871 -314.967793) (xy 358.359863 -314.918664) (xy 358.433213 -314.876315) (xy 358.510256 -314.841131)
			(xy 358.590295 -314.813429) (xy 358.672604 -314.793461) (xy 358.756439 -314.781408) (xy 358.84104 -314.777378)
			(xy 358.925641 -314.781408) (xy 359.009476 -314.793461) (xy 359.091785 -314.813429) (xy 359.171824 -314.841131)
			(xy 359.248867 -314.876315) (xy 359.322217 -314.918664) (xy 359.391209 -314.967793) (xy 359.455219 -315.023258)
			(xy 359.513667 -315.084556) (xy 359.566023 -315.151132) (xy 359.611813 -315.222384) (xy 359.650624 -315.297665)
			(xy 359.682103 -315.376295) (xy 359.705964 -315.457562) (xy 359.721993 -315.540728) (xy 359.730044 -315.625042)
			(xy 359.730548 -315.66739) (xy 359.925625 -315.66739) (xy 359.929647 -315.58167) (xy 359.941678 -315.496702)
			(xy 359.961614 -315.413235) (xy 359.989277 -315.332001) (xy 360.024426 -315.253715) (xy 360.066752 -315.179064)
			(xy 360.115881 -315.108705) (xy 360.171384 -315.043255) (xy 360.232771 -314.983291) (xy 360.299504 -314.929338)
			(xy 360.370996 -314.881871) (xy 360.446618 -314.841307) (xy 360.525707 -314.808003) (xy 360.607567 -314.782251)
			(xy 360.691478 -314.764278) (xy 360.776704 -314.754242) (xy 360.862496 -314.75223) (xy 360.948098 -314.758261)
			(xy 361.03276 -314.772281) (xy 361.115737 -314.794167) (xy 361.1963 -314.823728) (xy 361.27374 -314.860702)
			(xy 361.347379 -314.904766) (xy 361.416567 -314.955532) (xy 361.480698 -315.012553) (xy 361.539207 -315.075329)
			(xy 361.59158 -315.143309) (xy 361.637358 -315.215894) (xy 361.676138 -315.292446) (xy 361.707579 -315.372294)
			(xy 361.731405 -315.454735) (xy 361.747406 -315.539045) (xy 361.755441 -315.624483) (xy 361.755944 -315.66739)
			(xy 361.755448 -315.709738) (xy 364.149636 -315.709738) (xy 364.149636 -315.625042) (xy 364.157687 -315.540728)
			(xy 364.173716 -315.457562) (xy 364.197577 -315.376295) (xy 364.229056 -315.297665) (xy 364.267867 -315.222384)
			(xy 364.313657 -315.151132) (xy 364.366013 -315.084556) (xy 364.424461 -315.023258) (xy 364.488471 -314.967793)
			(xy 364.557463 -314.918664) (xy 364.630813 -314.876315) (xy 364.707856 -314.841131) (xy 364.787895 -314.813429)
			(xy 364.870204 -314.793461) (xy 364.954039 -314.781408) (xy 365.03864 -314.777378) (xy 365.123241 -314.781408)
			(xy 365.207076 -314.793461) (xy 365.289385 -314.813429) (xy 365.369424 -314.841131) (xy 365.446467 -314.876315)
			(xy 365.519817 -314.918664) (xy 365.588809 -314.967793) (xy 365.652819 -315.023258) (xy 365.711267 -315.084556)
			(xy 365.763623 -315.151132) (xy 365.809413 -315.222384) (xy 365.848224 -315.297665) (xy 365.879703 -315.376295)
			(xy 365.903564 -315.457562) (xy 365.919593 -315.540728) (xy 365.927644 -315.625042) (xy 365.928148 -315.66739)
			(xy 366.123225 -315.66739) (xy 366.127247 -315.58167) (xy 366.139278 -315.496702) (xy 366.159214 -315.413235)
			(xy 366.186877 -315.332001) (xy 366.222026 -315.253715) (xy 366.264352 -315.179064) (xy 366.313481 -315.108705)
			(xy 366.368984 -315.043255) (xy 366.430371 -314.983291) (xy 366.497104 -314.929338) (xy 366.568596 -314.881871)
			(xy 366.644218 -314.841307) (xy 366.723307 -314.808003) (xy 366.805167 -314.782251) (xy 366.889078 -314.764278)
			(xy 366.974304 -314.754242) (xy 367.060096 -314.75223) (xy 367.145698 -314.758261) (xy 367.23036 -314.772281)
			(xy 367.313337 -314.794167) (xy 367.3939 -314.823728) (xy 367.47134 -314.860702) (xy 367.544979 -314.904766)
			(xy 367.614167 -314.955532) (xy 367.678298 -315.012553) (xy 367.736807 -315.075329) (xy 367.78918 -315.143309)
			(xy 367.834958 -315.215894) (xy 367.873738 -315.292446) (xy 367.905179 -315.372294) (xy 367.929005 -315.454735)
			(xy 367.945006 -315.539045) (xy 367.953041 -315.624483) (xy 367.953544 -315.66739) (xy 367.953048 -315.709738)
			(xy 370.347236 -315.709738) (xy 370.347236 -315.625042) (xy 370.355287 -315.540728) (xy 370.371316 -315.457562)
			(xy 370.395177 -315.376295) (xy 370.426656 -315.297665) (xy 370.465467 -315.222384) (xy 370.511257 -315.151132)
			(xy 370.563613 -315.084556) (xy 370.622061 -315.023258) (xy 370.686071 -314.967793) (xy 370.755063 -314.918664)
			(xy 370.828413 -314.876315) (xy 370.905456 -314.841131) (xy 370.985495 -314.813429) (xy 371.067804 -314.793461)
			(xy 371.151639 -314.781408) (xy 371.23624 -314.777378) (xy 371.320841 -314.781408) (xy 371.404676 -314.793461)
			(xy 371.486985 -314.813429) (xy 371.567024 -314.841131) (xy 371.644067 -314.876315) (xy 371.717417 -314.918664)
			(xy 371.786409 -314.967793) (xy 371.850419 -315.023258) (xy 371.908867 -315.084556) (xy 371.961223 -315.151132)
			(xy 372.007013 -315.222384) (xy 372.045824 -315.297665) (xy 372.077303 -315.376295) (xy 372.101164 -315.457562)
			(xy 372.117193 -315.540728) (xy 372.125244 -315.625042) (xy 372.125748 -315.66739) (xy 372.320825 -315.66739)
			(xy 372.324847 -315.58167) (xy 372.336878 -315.496702) (xy 372.356814 -315.413235) (xy 372.384477 -315.332001)
			(xy 372.419626 -315.253715) (xy 372.461952 -315.179064) (xy 372.511081 -315.108705) (xy 372.566584 -315.043255)
			(xy 372.627971 -314.983291) (xy 372.694704 -314.929338) (xy 372.766196 -314.881871) (xy 372.841818 -314.841307)
			(xy 372.920907 -314.808003) (xy 373.002767 -314.782251) (xy 373.086678 -314.764278) (xy 373.171904 -314.754242)
			(xy 373.257696 -314.75223) (xy 373.343298 -314.758261) (xy 373.42796 -314.772281) (xy 373.510937 -314.794167)
			(xy 373.5915 -314.823728) (xy 373.66894 -314.860702) (xy 373.742579 -314.904766) (xy 373.811767 -314.955532)
			(xy 373.875898 -315.012553) (xy 373.934407 -315.075329) (xy 373.98678 -315.143309) (xy 374.032558 -315.215894)
			(xy 374.071338 -315.292446) (xy 374.102779 -315.372294) (xy 374.126605 -315.454735) (xy 374.142606 -315.539045)
			(xy 374.150641 -315.624483) (xy 374.151144 -315.66739) (xy 374.150641 -315.710297) (xy 374.142606 -315.795735)
			(xy 374.126605 -315.880045) (xy 374.102779 -315.962486) (xy 374.071338 -316.042334) (xy 374.032558 -316.118886)
			(xy 373.98678 -316.191471) (xy 373.934407 -316.259451) (xy 373.875898 -316.322227) (xy 373.811767 -316.379248)
			(xy 373.742579 -316.430014) (xy 373.66894 -316.474078) (xy 373.5915 -316.511052) (xy 373.510937 -316.540613)
			(xy 373.42796 -316.562499) (xy 373.343298 -316.576519) (xy 373.257696 -316.58255) (xy 373.171904 -316.580538)
			(xy 373.086678 -316.570502) (xy 373.002767 -316.552529) (xy 372.920907 -316.526777) (xy 372.841818 -316.493473)
			(xy 372.766196 -316.452909) (xy 372.694704 -316.405442) (xy 372.627971 -316.351489) (xy 372.566584 -316.291525)
			(xy 372.511081 -316.226075) (xy 372.461952 -316.155716) (xy 372.419626 -316.081065) (xy 372.384477 -316.002779)
			(xy 372.356814 -315.921545) (xy 372.336878 -315.838078) (xy 372.324847 -315.75311) (xy 372.320825 -315.66739)
			(xy 372.125748 -315.66739) (xy 372.125244 -315.709738) (xy 372.117193 -315.794052) (xy 372.101164 -315.877218)
			(xy 372.077303 -315.958485) (xy 372.045824 -316.037115) (xy 372.007013 -316.112396) (xy 371.961223 -316.183648)
			(xy 371.908867 -316.250224) (xy 371.850419 -316.311522) (xy 371.786409 -316.366987) (xy 371.717417 -316.416116)
			(xy 371.644067 -316.458465) (xy 371.567024 -316.493649) (xy 371.486985 -316.521351) (xy 371.404676 -316.541319)
			(xy 371.320841 -316.553372) (xy 371.23624 -316.557403) (xy 371.151639 -316.553372) (xy 371.067804 -316.541319)
			(xy 370.985495 -316.521351) (xy 370.905456 -316.493649) (xy 370.828413 -316.458465) (xy 370.755063 -316.416116)
			(xy 370.686071 -316.366987) (xy 370.622061 -316.311522) (xy 370.563613 -316.250224) (xy 370.511257 -316.183648)
			(xy 370.465467 -316.112396) (xy 370.426656 -316.037115) (xy 370.395177 -315.958485) (xy 370.371316 -315.877218)
			(xy 370.355287 -315.794052) (xy 370.347236 -315.709738) (xy 367.953048 -315.709738) (xy 367.953041 -315.710297)
			(xy 367.945006 -315.795735) (xy 367.929005 -315.880045) (xy 367.905179 -315.962486) (xy 367.873738 -316.042334)
			(xy 367.834958 -316.118886) (xy 367.78918 -316.191471) (xy 367.736807 -316.259451) (xy 367.678298 -316.322227)
			(xy 367.614167 -316.379248) (xy 367.544979 -316.430014) (xy 367.47134 -316.474078) (xy 367.3939 -316.511052)
			(xy 367.313337 -316.540613) (xy 367.23036 -316.562499) (xy 367.145698 -316.576519) (xy 367.060096 -316.58255)
			(xy 366.974304 -316.580538) (xy 366.889078 -316.570502) (xy 366.805167 -316.552529) (xy 366.723307 -316.526777)
			(xy 366.644218 -316.493473) (xy 366.568596 -316.452909) (xy 366.497104 -316.405442) (xy 366.430371 -316.351489)
			(xy 366.368984 -316.291525) (xy 366.313481 -316.226075) (xy 366.264352 -316.155716) (xy 366.222026 -316.081065)
			(xy 366.186877 -316.002779) (xy 366.159214 -315.921545) (xy 366.139278 -315.838078) (xy 366.127247 -315.75311)
			(xy 366.123225 -315.66739) (xy 365.928148 -315.66739) (xy 365.927644 -315.709738) (xy 365.919593 -315.794052)
			(xy 365.903564 -315.877218) (xy 365.879703 -315.958485) (xy 365.848224 -316.037115) (xy 365.809413 -316.112396)
			(xy 365.763623 -316.183648) (xy 365.711267 -316.250224) (xy 365.652819 -316.311522) (xy 365.588809 -316.366987)
			(xy 365.519817 -316.416116) (xy 365.446467 -316.458465) (xy 365.369424 -316.493649) (xy 365.289385 -316.521351)
			(xy 365.207076 -316.541319) (xy 365.123241 -316.553372) (xy 365.03864 -316.557403) (xy 364.954039 -316.553372)
			(xy 364.870204 -316.541319) (xy 364.787895 -316.521351) (xy 364.707856 -316.493649) (xy 364.630813 -316.458465)
			(xy 364.557463 -316.416116) (xy 364.488471 -316.366987) (xy 364.424461 -316.311522) (xy 364.366013 -316.250224)
			(xy 364.313657 -316.183648) (xy 364.267867 -316.112396) (xy 364.229056 -316.037115) (xy 364.197577 -315.958485)
			(xy 364.173716 -315.877218) (xy 364.157687 -315.794052) (xy 364.149636 -315.709738) (xy 361.755448 -315.709738)
			(xy 361.755441 -315.710297) (xy 361.747406 -315.795735) (xy 361.731405 -315.880045) (xy 361.707579 -315.962486)
			(xy 361.676138 -316.042334) (xy 361.637358 -316.118886) (xy 361.59158 -316.191471) (xy 361.539207 -316.259451)
			(xy 361.480698 -316.322227) (xy 361.416567 -316.379248) (xy 361.347379 -316.430014) (xy 361.27374 -316.474078)
			(xy 361.1963 -316.511052) (xy 361.115737 -316.540613) (xy 361.03276 -316.562499) (xy 360.948098 -316.576519)
			(xy 360.862496 -316.58255) (xy 360.776704 -316.580538) (xy 360.691478 -316.570502) (xy 360.607567 -316.552529)
			(xy 360.525707 -316.526777) (xy 360.446618 -316.493473) (xy 360.370996 -316.452909) (xy 360.299504 -316.405442)
			(xy 360.232771 -316.351489) (xy 360.171384 -316.291525) (xy 360.115881 -316.226075) (xy 360.066752 -316.155716)
			(xy 360.024426 -316.081065) (xy 359.989277 -316.002779) (xy 359.961614 -315.921545) (xy 359.941678 -315.838078)
			(xy 359.929647 -315.75311) (xy 359.925625 -315.66739) (xy 359.730548 -315.66739) (xy 359.730044 -315.709738)
			(xy 359.721993 -315.794052) (xy 359.705964 -315.877218) (xy 359.682103 -315.958485) (xy 359.650624 -316.037115)
			(xy 359.611813 -316.112396) (xy 359.566023 -316.183648) (xy 359.513667 -316.250224) (xy 359.455219 -316.311522)
			(xy 359.391209 -316.366987) (xy 359.322217 -316.416116) (xy 359.248867 -316.458465) (xy 359.171824 -316.493649)
			(xy 359.091785 -316.521351) (xy 359.009476 -316.541319) (xy 358.925641 -316.553372) (xy 358.84104 -316.557403)
			(xy 358.756439 -316.553372) (xy 358.672604 -316.541319) (xy 358.590295 -316.521351) (xy 358.510256 -316.493649)
			(xy 358.433213 -316.458465) (xy 358.359863 -316.416116) (xy 358.290871 -316.366987) (xy 358.226861 -316.311522)
			(xy 358.168413 -316.250224) (xy 358.116057 -316.183648) (xy 358.070267 -316.112396) (xy 358.031456 -316.037115)
			(xy 357.999977 -315.958485) (xy 357.976116 -315.877218) (xy 357.960087 -315.794052) (xy 357.952036 -315.709738)
			(xy 355.57766 -315.709738) (xy 355.577653 -315.710297) (xy 355.569618 -315.795735) (xy 355.553617 -315.880045)
			(xy 355.529791 -315.962486) (xy 355.49835 -316.042334) (xy 355.45957 -316.118886) (xy 355.413792 -316.191471)
			(xy 355.361419 -316.259451) (xy 355.30291 -316.322227) (xy 355.238779 -316.379248) (xy 355.169591 -316.430014)
			(xy 355.095952 -316.474078) (xy 355.018512 -316.511052) (xy 354.937949 -316.540613) (xy 354.854972 -316.562499)
			(xy 354.77031 -316.576519) (xy 354.684708 -316.58255) (xy 354.598916 -316.580538) (xy 354.51369 -316.570502)
			(xy 354.429779 -316.552529) (xy 354.347919 -316.526777) (xy 354.26883 -316.493473) (xy 354.193208 -316.452909)
			(xy 354.121716 -316.405442) (xy 354.054983 -316.351489) (xy 353.993596 -316.291525) (xy 353.938093 -316.226075)
			(xy 353.888964 -316.155716) (xy 353.846638 -316.081065) (xy 353.811489 -316.002779) (xy 353.783826 -315.921545)
			(xy 353.76389 -315.838078) (xy 353.751859 -315.75311) (xy 353.747837 -315.66739) (xy 353.55276 -315.66739)
			(xy 353.552256 -315.709738) (xy 353.544205 -315.794052) (xy 353.528176 -315.877218) (xy 353.504315 -315.958485)
			(xy 353.472836 -316.037115) (xy 353.434025 -316.112396) (xy 353.388235 -316.183648) (xy 353.335879 -316.250224)
			(xy 353.277431 -316.311522) (xy 353.213421 -316.366987) (xy 353.144429 -316.416116) (xy 353.071079 -316.458465)
			(xy 352.994036 -316.493649) (xy 352.913997 -316.521351) (xy 352.831688 -316.541319) (xy 352.747853 -316.553372)
			(xy 352.663252 -316.557403) (xy 352.578651 -316.553372) (xy 352.494816 -316.541319) (xy 352.412507 -316.521351)
			(xy 352.332468 -316.493649) (xy 352.255425 -316.458465) (xy 352.182075 -316.416116) (xy 352.113083 -316.366987)
			(xy 352.049073 -316.311522) (xy 351.990625 -316.250224) (xy 351.938269 -316.183648) (xy 351.892479 -316.112396)
			(xy 351.853668 -316.037115) (xy 351.822189 -315.958485) (xy 351.798328 -315.877218) (xy 351.782299 -315.794052)
			(xy 351.774248 -315.709738) (xy 349.38006 -315.709738) (xy 349.380053 -315.710297) (xy 349.372018 -315.795735)
			(xy 349.356017 -315.880045) (xy 349.332191 -315.962486) (xy 349.30075 -316.042334) (xy 349.26197 -316.118886)
			(xy 349.216192 -316.191471) (xy 349.163819 -316.259451) (xy 349.10531 -316.322227) (xy 349.041179 -316.379248)
			(xy 348.971991 -316.430014) (xy 348.898352 -316.474078) (xy 348.820912 -316.511052) (xy 348.740349 -316.540613)
			(xy 348.657372 -316.562499) (xy 348.57271 -316.576519) (xy 348.487108 -316.58255) (xy 348.401316 -316.580538)
			(xy 348.31609 -316.570502) (xy 348.232179 -316.552529) (xy 348.150319 -316.526777) (xy 348.07123 -316.493473)
			(xy 347.995608 -316.452909) (xy 347.924116 -316.405442) (xy 347.857383 -316.351489) (xy 347.795996 -316.291525)
			(xy 347.740493 -316.226075) (xy 347.691364 -316.155716) (xy 347.649038 -316.081065) (xy 347.613889 -316.002779)
			(xy 347.586226 -315.921545) (xy 347.56629 -315.838078) (xy 347.554259 -315.75311) (xy 347.550237 -315.66739)
			(xy 347.35516 -315.66739) (xy 347.354656 -315.709738) (xy 347.346605 -315.794052) (xy 347.330576 -315.877218)
			(xy 347.306715 -315.958485) (xy 347.275236 -316.037115) (xy 347.236425 -316.112396) (xy 347.190635 -316.183648)
			(xy 347.138279 -316.250224) (xy 347.079831 -316.311522) (xy 347.015821 -316.366987) (xy 346.946829 -316.416116)
			(xy 346.873479 -316.458465) (xy 346.796436 -316.493649) (xy 346.716397 -316.521351) (xy 346.634088 -316.541319)
			(xy 346.550253 -316.553372) (xy 346.465652 -316.557403) (xy 346.381051 -316.553372) (xy 346.297216 -316.541319)
			(xy 346.214907 -316.521351) (xy 346.134868 -316.493649) (xy 346.057825 -316.458465) (xy 345.984475 -316.416116)
			(xy 345.915483 -316.366987) (xy 345.851473 -316.311522) (xy 345.793025 -316.250224) (xy 345.740669 -316.183648)
			(xy 345.694879 -316.112396) (xy 345.656068 -316.037115) (xy 345.624589 -315.958485) (xy 345.600728 -315.877218)
			(xy 345.584699 -315.794052) (xy 345.576648 -315.709738) (xy 340.03495 -315.709738) (xy 338.71916 -317.025528)
			(xy 337.35518 -317.025528) (xy 328.819764 -325.560944) (xy 328.819764 -331.301852) (xy 329.241404 -331.723492)
			(xy 338.535264 -331.723492) (xy 338.834984 -331.423772) (xy 338.834984 -329.307952) (xy 342.126824 -326.016112)
			(xy 371.433344 -326.016112) (xy 374.932194 -329.514962) (xy 379.828044 -329.514962) (xy 383.070354 -332.757272)
			(xy 387.140704 -332.757272)
		)
		(stroke
			(width 0)
			(type solid)
		)
		(fill yes)
		(layer "In2.Cu")
		(net "PVCCIN_CPU0")
	)
	(gr_poly
		(pts
			(xy 310.7944 -439.039) (xy 310.7944 -437.68264) (xy 310.551068 -437.439308) (xy 303.48936 -437.439308)
			(xy 303.464371 -437.438846) (xy 303.415009 -437.431025) (xy 303.367481 -437.415568) (xy 303.322962 -437.392856)
			(xy 303.282551 -437.363449) (xy 303.26457 -437.34609) (xy 301.75327 -435.83479) (xy 301.735924 -435.8168)
			(xy 301.706537 -435.776381) (xy 301.683835 -435.731863) (xy 301.668377 -435.684341) (xy 301.660543 -435.634986)
			(xy 301.660052 -435.61) (xy 301.660052 -429.31969) (xy 301.660512 -429.2947) (xy 301.668327 -429.245334)
			(xy 301.68378 -429.197803) (xy 301.706487 -429.153278) (xy 301.735889 -429.112861) (xy 301.75327 -429.0949)
			(xy 302.072294 -428.775876) (xy 302.07585 -428.761906) (xy 302.082947 -428.734499) (xy 302.104134 -428.682002)
			(xy 302.132854 -428.633215) (xy 302.168474 -428.589214) (xy 302.210211 -428.550965) (xy 302.257146 -428.519311)
			(xy 302.308247 -428.494948) (xy 302.36239 -428.478411) (xy 302.418384 -428.470065) (xy 302.44669 -428.469552)
			(xy 302.473943 -428.470037) (xy 302.527894 -428.477792) (xy 302.580192 -428.493146) (xy 302.629773 -428.515786)
			(xy 302.675627 -428.545251) (xy 302.716822 -428.580942) (xy 302.752519 -428.622132) (xy 302.78199 -428.667983)
			(xy 302.804636 -428.717561) (xy 302.819997 -428.769857) (xy 302.827759 -428.823807) (xy 302.828198 -428.85106)
			(xy 302.827679 -428.879363) (xy 302.819305 -428.935347) (xy 302.802752 -428.989479) (xy 302.778381 -429.04057)
			(xy 302.746728 -429.0875) (xy 302.708488 -429.129237) (xy 302.664501 -429.164866) (xy 302.615732 -429.193604)
			(xy 302.563252 -429.21482) (xy 302.535844 -429.2219) (xy 302.521874 -429.225456) (xy 302.296068 -429.451262)
			(xy 302.296068 -431.879979) (xy 302.473364 -431.879979) (xy 302.481116 -431.82603) (xy 302.496467 -431.773733)
			(xy 302.519104 -431.724153) (xy 302.548567 -431.678299) (xy 302.584255 -431.637105) (xy 302.625442 -431.601409)
			(xy 302.671291 -431.571938) (xy 302.720867 -431.549291) (xy 302.773161 -431.533931) (xy 302.827108 -431.526169)
			(xy 302.85436 -431.52568) (xy 302.883797 -431.52624) (xy 302.94197 -431.535298) (xy 302.970184 -431.543714)
			(xy 302.984506 -431.547768) (xy 303.014254 -431.548274) (xy 303.042886 -431.540185) (xy 303.067971 -431.524186)
			(xy 303.087381 -431.501636) (xy 303.099467 -431.474449) (xy 303.103204 -431.444932) (xy 303.101248 -431.430176)
			(xy 303.098752 -431.414484) (xy 303.096085 -431.382819) (xy 303.095914 -431.36693) (xy 303.0964 -431.339679)
			(xy 303.104156 -431.285731) (xy 303.119511 -431.233436) (xy 303.142153 -431.183859) (xy 303.171619 -431.138009)
			(xy 303.20731 -431.096818) (xy 303.248501 -431.061127) (xy 303.294351 -431.031661) (xy 303.343928 -431.009019)
			(xy 303.396223 -430.993664) (xy 303.450171 -430.985908) (xy 303.504673 -430.985908) (xy 303.558621 -430.993664)
			(xy 303.610916 -431.009019) (xy 303.660493 -431.031661) (xy 303.706343 -431.061127) (xy 303.747534 -431.096818)
			(xy 303.783225 -431.138009) (xy 303.812691 -431.183859) (xy 303.835333 -431.233436) (xy 303.850688 -431.285731)
			(xy 303.858444 -431.339679) (xy 303.85893 -431.36693) (xy 303.858788 -431.382686) (xy 303.856248 -431.414095)
			(xy 303.85385 -431.429668) (xy 303.851848 -431.444373) (xy 303.855576 -431.473805) (xy 303.86761 -431.500922)
			(xy 303.886933 -431.523433) (xy 303.911913 -431.539436) (xy 303.94044 -431.547581) (xy 303.970105 -431.547177)
			(xy 303.984406 -431.543206) (xy 304.012332 -431.535011) (xy 304.069861 -431.526209) (xy 304.09896 -431.52568)
			(xy 304.126217 -431.526112) (xy 304.180176 -431.533865) (xy 304.232482 -431.549218) (xy 304.282071 -431.571859)
			(xy 304.327933 -431.601327) (xy 304.369134 -431.637022) (xy 304.404836 -431.678217) (xy 304.434311 -431.724074)
			(xy 304.45696 -431.773659) (xy 304.472322 -431.825963) (xy 304.480083 -431.879921) (xy 304.480087 -431.934434)
			(xy 304.478451 -431.945819) (xy 305.208871 -431.945819) (xy 305.208876 -431.891315) (xy 305.216637 -431.837367)
			(xy 305.231997 -431.785072) (xy 305.254643 -431.735496) (xy 305.284115 -431.689647) (xy 305.319811 -431.648459)
			(xy 305.361006 -431.612771) (xy 305.40686 -431.583309) (xy 305.456441 -431.560672) (xy 305.508738 -431.545322)
			(xy 305.562688 -431.53757) (xy 305.58994 -431.53711) (xy 305.619377 -431.537674) (xy 305.67755 -431.546729)
			(xy 305.705764 -431.555144) (xy 305.720099 -431.559141) (xy 305.749838 -431.559651) (xy 305.778462 -431.551569)
			(xy 305.803541 -431.535579) (xy 305.822949 -431.51304) (xy 305.835037 -431.485865) (xy 305.83878 -431.456358)
			(xy 305.836828 -431.441606) (xy 305.834337 -431.425913) (xy 305.831667 -431.394248) (xy 305.831494 -431.37836)
			(xy 305.83198 -431.351109) (xy 305.839736 -431.297161) (xy 305.855091 -431.244866) (xy 305.877733 -431.195289)
			(xy 305.907199 -431.149439) (xy 305.94289 -431.108248) (xy 305.984081 -431.072557) (xy 306.029931 -431.043091)
			(xy 306.079508 -431.020449) (xy 306.131803 -431.005094) (xy 306.185751 -430.997338) (xy 306.240253 -430.997338)
			(xy 306.294201 -431.005094) (xy 306.346496 -431.020449) (xy 306.396073 -431.043091) (xy 306.441923 -431.072557)
			(xy 306.483114 -431.108248) (xy 306.518805 -431.149439) (xy 306.548271 -431.195289) (xy 306.570913 -431.244866)
			(xy 306.586268 -431.297161) (xy 306.594024 -431.351109) (xy 306.59451 -431.37836) (xy 306.594372 -431.394116)
			(xy 306.591829 -431.425525) (xy 306.58943 -431.441098) (xy 306.587425 -431.455801) (xy 306.591159 -431.48523)
			(xy 306.603196 -431.512343) (xy 306.622519 -431.534852) (xy 306.647498 -431.550855) (xy 306.676022 -431.559001)
			(xy 306.705685 -431.558604) (xy 306.719986 -431.554636) (xy 306.747914 -431.546446) (xy 306.805441 -431.537641)
			(xy 306.83454 -431.53711) (xy 306.861787 -431.537621) (xy 306.915727 -431.545382) (xy 306.968013 -431.56074)
			(xy 307.017581 -431.583382) (xy 307.063423 -431.612849) (xy 307.104604 -431.648539) (xy 307.140288 -431.689726)
			(xy 307.169747 -431.735572) (xy 307.192381 -431.785144) (xy 307.207731 -431.837432) (xy 307.215483 -431.891373)
			(xy 307.21548 -431.945868) (xy 307.207722 -431.999808) (xy 307.203814 -432.013115) (xy 307.952081 -432.013115)
			(xy 307.952086 -431.958613) (xy 307.959847 -431.904666) (xy 307.975207 -431.852374) (xy 307.997853 -431.802799)
			(xy 308.027324 -431.756952) (xy 308.063019 -431.715765) (xy 308.104213 -431.680078) (xy 308.150066 -431.650617)
			(xy 308.199645 -431.627981) (xy 308.251941 -431.612631) (xy 308.305889 -431.60488) (xy 308.33314 -431.60442)
			(xy 308.362577 -431.604983) (xy 308.42075 -431.614039) (xy 308.448964 -431.622454) (xy 308.463278 -431.626553)
			(xy 308.493037 -431.627066) (xy 308.521681 -431.618977) (xy 308.546774 -431.602971) (xy 308.566187 -431.580408)
			(xy 308.578268 -431.553207) (xy 308.581993 -431.523677) (xy 308.580028 -431.508916) (xy 308.577538 -431.493223)
			(xy 308.574867 -431.461558) (xy 308.574694 -431.44567) (xy 308.57518 -431.418419) (xy 308.582936 -431.364471)
			(xy 308.598291 -431.312176) (xy 308.620933 -431.262599) (xy 308.650399 -431.216749) (xy 308.68609 -431.175558)
			(xy 308.727281 -431.139867) (xy 308.773131 -431.110401) (xy 308.822708 -431.087759) (xy 308.875003 -431.072404)
			(xy 308.928951 -431.064648) (xy 308.983453 -431.064648) (xy 309.037401 -431.072404) (xy 309.089696 -431.087759)
			(xy 309.139273 -431.110401) (xy 309.185123 -431.139867) (xy 309.226314 -431.175558) (xy 309.262005 -431.216749)
			(xy 309.291471 -431.262599) (xy 309.314113 -431.312176) (xy 309.329468 -431.364471) (xy 309.337224 -431.418419)
			(xy 309.33771 -431.44567) (xy 309.337573 -431.461426) (xy 309.335029 -431.492835) (xy 309.33263 -431.508408)
			(xy 309.330713 -431.523122) (xy 309.334425 -431.552545) (xy 309.346443 -431.579657) (xy 309.365753 -431.602166)
			(xy 309.39072 -431.61817) (xy 309.419236 -431.626316) (xy 309.44889 -431.625916) (xy 309.463186 -431.621946)
			(xy 309.491114 -431.613756) (xy 309.548641 -431.604951) (xy 309.57774 -431.60442) (xy 309.604987 -431.604921)
			(xy 309.658926 -431.612682) (xy 309.711212 -431.62804) (xy 309.76078 -431.650682) (xy 309.806622 -431.680148)
			(xy 309.847803 -431.715837) (xy 309.883487 -431.757024) (xy 309.912946 -431.80287) (xy 309.93558 -431.852442)
			(xy 309.95093 -431.90473) (xy 309.958683 -431.95867) (xy 309.958681 -432.013165) (xy 309.950923 -432.067104)
			(xy 309.935568 -432.119391) (xy 309.912929 -432.16896) (xy 309.883466 -432.214804) (xy 309.847779 -432.255987)
			(xy 309.806594 -432.291673) (xy 309.76075 -432.321135) (xy 309.71118 -432.343773) (xy 309.658893 -432.359126)
			(xy 309.604953 -432.366882) (xy 309.550458 -432.366882) (xy 309.496518 -432.359128) (xy 309.44423 -432.343776)
			(xy 309.394659 -432.32114) (xy 309.348815 -432.291679) (xy 309.307629 -432.255995) (xy 309.271941 -432.214812)
			(xy 309.242476 -432.16897) (xy 309.219835 -432.119401) (xy 309.204479 -432.067115) (xy 309.19672 -432.013175)
			(xy 309.196232 -431.985928) (xy 309.196368 -431.970172) (xy 309.198912 -431.938763) (xy 309.201312 -431.92319)
			(xy 309.203177 -431.908473) (xy 309.199465 -431.879059) (xy 309.187452 -431.851956) (xy 309.168152 -431.829452)
			(xy 309.143196 -431.813449) (xy 309.114692 -431.805298) (xy 309.085049 -431.805689) (xy 309.070756 -431.809652)
			(xy 309.042831 -431.817854) (xy 308.985302 -431.826652) (xy 308.956202 -431.827178) (xy 308.926765 -431.826628)
			(xy 308.868591 -431.817563) (xy 308.840378 -431.809144) (xy 308.826051 -431.805095) (xy 308.796298 -431.804572)
			(xy 308.767658 -431.812652) (xy 308.742566 -431.82865) (xy 308.723155 -431.851205) (xy 308.711073 -431.8784)
			(xy 308.707349 -431.907924) (xy 308.709314 -431.922682) (xy 308.711804 -431.938375) (xy 308.714475 -431.97004)
			(xy 308.714648 -431.985928) (xy 308.714115 -432.013179) (xy 308.706354 -432.067126) (xy 308.690995 -432.119419)
			(xy 308.668351 -432.168994) (xy 308.638881 -432.214842) (xy 308.603186 -432.256029) (xy 308.561994 -432.291717)
			(xy 308.516141 -432.321179) (xy 308.466563 -432.343816) (xy 308.414267 -432.359167) (xy 308.360319 -432.366919)
			(xy 308.305817 -432.366914) (xy 308.25187 -432.359153) (xy 308.199577 -432.343794) (xy 308.150002 -432.321149)
			(xy 308.104155 -432.291679) (xy 308.062968 -432.255984) (xy 308.027281 -432.214791) (xy 307.997819 -432.168938)
			(xy 307.975182 -432.119359) (xy 307.959832 -432.067063) (xy 307.952081 -432.013115) (xy 307.203814 -432.013115)
			(xy 307.192367 -432.052095) (xy 307.169727 -432.101664) (xy 307.140263 -432.147507) (xy 307.104575 -432.188691)
			(xy 307.06339 -432.224376) (xy 307.017545 -432.253837) (xy 306.967974 -432.276475) (xy 306.915686 -432.291827)
			(xy 306.861746 -432.299582) (xy 306.807251 -432.299582) (xy 306.753311 -432.291826) (xy 306.701023 -432.276474)
			(xy 306.651453 -432.253836) (xy 306.605608 -432.224375) (xy 306.564423 -432.188689) (xy 306.528735 -432.147505)
			(xy 306.499272 -432.101662) (xy 306.476632 -432.052092) (xy 306.461277 -431.999805) (xy 306.453519 -431.945865)
			(xy 306.453032 -431.918618) (xy 306.453167 -431.902862) (xy 306.455712 -431.871453) (xy 306.458112 -431.85588)
			(xy 306.459987 -431.841164) (xy 306.456273 -431.81175) (xy 306.444257 -431.784647) (xy 306.424956 -431.762143)
			(xy 306.399999 -431.74614) (xy 306.371494 -431.737989) (xy 306.341849 -431.738379) (xy 306.327556 -431.742342)
			(xy 306.299632 -431.750547) (xy 306.242102 -431.759342) (xy 306.213002 -431.759868) (xy 306.183565 -431.759318)
			(xy 306.125391 -431.750254) (xy 306.097178 -431.741834) (xy 306.082849 -431.737796) (xy 306.053098 -431.737273)
			(xy 306.02446 -431.745353) (xy 305.99937 -431.761349) (xy 305.979959 -431.783901) (xy 305.967877 -431.811094)
			(xy 305.964151 -431.840615) (xy 305.966114 -431.855372) (xy 305.968603 -431.871065) (xy 305.971274 -431.90273)
			(xy 305.971448 -431.918618) (xy 305.970925 -431.94587) (xy 305.963166 -431.999819) (xy 305.947808 -432.052114)
			(xy 305.925164 -432.101691) (xy 305.895694 -432.147541) (xy 305.859999 -432.18873) (xy 305.818806 -432.22442)
			(xy 305.772953 -432.253884) (xy 305.723373 -432.276523) (xy 305.671076 -432.291875) (xy 305.617127 -432.299628)
			(xy 305.562623 -432.299625) (xy 305.508674 -432.291864) (xy 305.456379 -432.276505) (xy 305.406803 -432.25386)
			(xy 305.360953 -432.22439) (xy 305.319765 -432.188694) (xy 305.284075 -432.1475) (xy 305.254612 -432.101646)
			(xy 305.231974 -432.052066) (xy 305.216623 -431.999769) (xy 305.208871 -431.945819) (xy 304.478451 -431.945819)
			(xy 304.472332 -431.988393) (xy 304.456976 -432.040698) (xy 304.434333 -432.090286) (xy 304.404863 -432.136147)
			(xy 304.369166 -432.177346) (xy 304.327969 -432.213046) (xy 304.282111 -432.24252) (xy 304.232524 -432.265166)
			(xy 304.18022 -432.280526) (xy 304.126262 -432.288285) (xy 304.071749 -432.288285) (xy 304.017791 -432.280528)
			(xy 303.965486 -432.26517) (xy 303.915899 -432.242525) (xy 303.870039 -432.213053) (xy 303.828841 -432.177354)
			(xy 303.793143 -432.136155) (xy 303.763672 -432.090295) (xy 303.741028 -432.040708) (xy 303.725671 -431.988403)
			(xy 303.717914 -431.934445) (xy 303.717452 -431.907188) (xy 303.717595 -431.891432) (xy 303.720135 -431.860023)
			(xy 303.722532 -431.84445) (xy 303.72454 -431.829745) (xy 303.720816 -431.800309) (xy 303.708783 -431.773189)
			(xy 303.689459 -431.750675) (xy 303.664476 -431.734671) (xy 303.635945 -431.726529) (xy 303.606278 -431.726937)
			(xy 303.591976 -431.730912) (xy 303.564051 -431.739112) (xy 303.506522 -431.747911) (xy 303.477422 -431.748438)
			(xy 303.447985 -431.747885) (xy 303.389811 -431.738823) (xy 303.361598 -431.730404) (xy 303.347285 -431.72631)
			(xy 303.317531 -431.725807) (xy 303.288894 -431.733902) (xy 303.263805 -431.749907) (xy 303.244394 -431.772464)
			(xy 303.232309 -431.799659) (xy 303.228576 -431.829183) (xy 303.230534 -431.843942) (xy 303.233019 -431.859636)
			(xy 303.235693 -431.8913) (xy 303.235868 -431.907188) (xy 303.235435 -431.93444) (xy 303.22768 -431.988389)
			(xy 303.212327 -432.040685) (xy 303.189687 -432.090264) (xy 303.160222 -432.136116) (xy 303.124532 -432.177308)
			(xy 303.083343 -432.213002) (xy 303.037493 -432.242471) (xy 302.987916 -432.265115) (xy 302.935621 -432.280473)
			(xy 302.881673 -432.288233) (xy 302.82717 -432.288236) (xy 302.773221 -432.280482) (xy 302.720924 -432.26513)
			(xy 302.671345 -432.242492) (xy 302.625492 -432.213028) (xy 302.584298 -432.177339) (xy 302.548603 -432.13615)
			(xy 302.519133 -432.090301) (xy 302.496488 -432.040725) (xy 302.481129 -431.98843) (xy 302.473368 -431.934482)
			(xy 302.473364 -431.879979) (xy 302.296068 -431.879979) (xy 302.296068 -435.478428) (xy 303.620932 -436.803292)
			(xy 310.68264 -436.803292) (xy 310.69026 -436.803546) (xy 310.703803 -436.80346) (xy 310.730092 -436.796998)
			(xy 310.753758 -436.78385) (xy 310.773134 -436.764943) (xy 310.786857 -436.741606) (xy 310.793961 -436.715482)
			(xy 310.7944 -436.701946) (xy 310.7944 -425.88815) (xy 310.793834 -425.873175) (xy 310.785077 -425.84453)
			(xy 310.768389 -425.819655) (xy 310.745206 -425.800689) (xy 310.717518 -425.789261) (xy 310.687706 -425.786353)
			(xy 310.658332 -425.792215) (xy 310.63192 -425.806344) (xy 310.620918 -425.816522) (xy 309.123588 -427.313852)
			(xy 309.113542 -427.324567) (xy 309.099525 -427.350364) (xy 309.093429 -427.379083) (xy 309.095759 -427.40835)
			(xy 309.106321 -427.435743) (xy 309.124243 -427.458997) (xy 309.148043 -427.476189) (xy 309.175751 -427.485896)
			(xy 309.19039 -427.48708) (xy 309.219348 -427.489074) (xy 309.27621 -427.500726) (xy 309.33065 -427.520858)
			(xy 309.381412 -427.549004) (xy 309.427325 -427.584515) (xy 309.467329 -427.626571) (xy 309.5005 -427.674201)
			(xy 309.526073 -427.726307) (xy 309.543458 -427.781686) (xy 309.552254 -427.839058) (xy 309.552848 -427.86808)
			(xy 309.552364 -427.895333) (xy 309.54461 -427.949285) (xy 309.529257 -428.001585) (xy 309.506617 -428.051167)
			(xy 309.477152 -428.097023) (xy 309.441461 -428.138219) (xy 309.400271 -428.173916) (xy 309.35442 -428.203388)
			(xy 309.304841 -428.226036) (xy 309.252544 -428.241397) (xy 309.198593 -428.249159) (xy 309.17134 -428.249588)
			(xy 309.144954 -428.249144) (xy 309.092686 -428.241876) (xy 309.041918 -428.227473) (xy 308.99362 -428.20621)
			(xy 308.948713 -428.178493) (xy 308.908056 -428.144851) (xy 308.872423 -428.105927) (xy 308.842496 -428.062462)
			(xy 308.818845 -428.015287) (xy 308.801922 -427.965303) (xy 308.792049 -427.913463) (xy 308.79034 -427.88713)
			(xy 308.789111 -427.872505) (xy 308.779361 -427.844836) (xy 308.762156 -427.821074) (xy 308.738911 -427.803176)
			(xy 308.711541 -427.792616) (xy 308.682299 -427.790261) (xy 308.653592 -427.796308) (xy 308.627784 -427.810256)
			(xy 308.617112 -427.820328) (xy 308.029356 -428.408084) (xy 308.019542 -428.41865) (xy 308.005721 -428.443945)
			(xy 307.999515 -428.472094) (xy 308.001417 -428.500856) (xy 308.011276 -428.527942) (xy 308.028307 -428.551197)
			(xy 308.051156 -428.568769) (xy 308.064408 -428.574454) (xy 308.090843 -428.585337) (xy 308.140381 -428.613868)
			(xy 308.185106 -428.649471) (xy 308.224018 -428.69135) (xy 308.256244 -428.738567) (xy 308.281064 -428.790064)
			(xy 308.29792 -428.844688) (xy 308.306436 -428.901217) (xy 308.306978 -428.9298) (xy 308.306515 -428.957052)
			(xy 308.298758 -429.011001) (xy 308.283401 -429.063298) (xy 308.260758 -429.112876) (xy 308.23129 -429.158727)
			(xy 308.195596 -429.199917) (xy 308.154403 -429.235608) (xy 308.108549 -429.265073) (xy 308.058969 -429.287712)
			(xy 308.006672 -429.303064) (xy 307.952722 -429.310817) (xy 307.92547 -429.311308) (xy 307.896887 -429.310797)
			(xy 307.840361 -429.302265) (xy 307.78574 -429.285397) (xy 307.734246 -429.260571) (xy 307.687032 -429.228341)
			(xy 307.645153 -429.189429) (xy 307.609547 -429.144706) (xy 307.581011 -429.095171) (xy 307.570124 -429.068738)
			(xy 307.564443 -429.055468) (xy 307.546902 -429.032559) (xy 307.523647 -429.015479) (xy 307.49654 -429.005594)
			(xy 307.46775 -429.003695) (xy 307.439579 -429.009934) (xy 307.414283 -429.023813) (xy 307.403754 -429.033686)
			(xy 307.35016 -429.08728) (xy 307.332142 -429.104581) (xy 307.291713 -429.133914) (xy 307.247195 -429.156564)
			(xy 307.199682 -429.171974) (xy 307.150345 -429.179764) (xy 307.12537 -429.180244) (xy 305.393344 -429.180244)
			(xy 305.369775 -429.195322) (xy 305.319155 -429.219155) (xy 305.265595 -429.235332) (xy 305.210245 -429.243506)
			(xy 305.18227 -429.243998) (xy 305.155021 -429.24351) (xy 305.101078 -429.23575) (xy 305.048788 -429.220393)
			(xy 304.999216 -429.19775) (xy 304.953371 -429.168284) (xy 304.912185 -429.132594) (xy 304.876498 -429.091405)
			(xy 304.847035 -429.045558) (xy 304.824397 -428.995984) (xy 304.809044 -428.943693) (xy 304.801288 -428.889749)
			(xy 304.801288 -428.835251) (xy 304.809044 -428.781307) (xy 304.824397 -428.729016) (xy 304.847035 -428.679442)
			(xy 304.876498 -428.633595) (xy 304.912185 -428.592406) (xy 304.953371 -428.556716) (xy 304.999216 -428.52725)
			(xy 305.048788 -428.504607) (xy 305.101078 -428.48925) (xy 305.155021 -428.48149) (xy 305.18227 -428.480982)
			(xy 305.210246 -428.481471) (xy 305.265597 -428.489643) (xy 305.31916 -428.505816) (xy 305.369785 -428.529643)
			(xy 305.393344 -428.544736) (xy 306.230274 -428.544736) (xy 306.244221 -428.544293) (xy 306.271072 -428.536736)
			(xy 306.294882 -428.522203) (xy 306.313879 -428.501777) (xy 306.326649 -428.476977) (xy 306.332243 -428.449649)
			(xy 306.330243 -428.421826) (xy 306.320799 -428.395579) (xy 306.313078 -428.383954) (xy 306.296386 -428.359596)
			(xy 306.26992 -428.306812) (xy 306.251904 -428.25058) (xy 306.24277 -428.192243) (xy 306.242212 -428.16272)
			(xy 306.242698 -428.135469) (xy 306.250454 -428.081521) (xy 306.265809 -428.029226) (xy 306.288451 -427.979649)
			(xy 306.317917 -427.933799) (xy 306.353608 -427.892608) (xy 306.394799 -427.856917) (xy 306.440649 -427.827451)
			(xy 306.490226 -427.804809) (xy 306.542521 -427.789454) (xy 306.596469 -427.781698) (xy 306.650971 -427.781698)
			(xy 306.704919 -427.789454) (xy 306.757214 -427.804809) (xy 306.806791 -427.827451) (xy 306.852641 -427.856917)
			(xy 306.893832 -427.892608) (xy 306.929523 -427.933799) (xy 306.958989 -427.979649) (xy 306.981631 -428.029226)
			(xy 306.996986 -428.081521) (xy 307.004742 -428.135469) (xy 307.005228 -428.16272) (xy 307.004735 -428.190461)
			(xy 306.996706 -428.245358) (xy 306.980807 -428.298512) (xy 306.957372 -428.348802) (xy 306.926897 -428.395164)
			(xy 306.890025 -428.43662) (xy 306.869084 -428.45482) (xy 306.850796 -428.47006) (xy 306.850796 -428.544736)
			(xy 306.993798 -428.544736) (xy 309.945024 -425.593256) (xy 309.955205 -425.582273) (xy 309.969261 -425.555845)
			(xy 309.975055 -425.526478) (xy 309.972089 -425.496692) (xy 309.960618 -425.469044) (xy 309.941626 -425.445907)
			(xy 309.916744 -425.429267) (xy 309.888108 -425.420552) (xy 309.873142 -425.420028) (xy 307.92166 -425.420028)
			(xy 307.907242 -425.420521) (xy 307.879553 -425.428566) (xy 307.855218 -425.444033) (xy 307.836177 -425.465688)
			(xy 307.823951 -425.491802) (xy 307.819514 -425.520293) (xy 307.823221 -425.548889) (xy 307.834774 -425.575307)
			(xy 307.843682 -425.586652) (xy 307.860347 -425.607309) (xy 307.8884 -425.652363) (xy 307.909929 -425.700874)
			(xy 307.924518 -425.751903) (xy 307.931883 -425.804463) (xy 307.932328 -425.831) (xy 307.931842 -425.858251)
			(xy 307.924086 -425.912199) (xy 307.908731 -425.964494) (xy 307.886089 -426.014071) (xy 307.856623 -426.059921)
			(xy 307.820932 -426.101112) (xy 307.779741 -426.136803) (xy 307.733891 -426.166269) (xy 307.684314 -426.188911)
			(xy 307.632019 -426.204266) (xy 307.578071 -426.212022) (xy 307.523569 -426.212022) (xy 307.469621 -426.204266)
			(xy 307.417326 -426.188911) (xy 307.367749 -426.166269) (xy 307.321899 -426.136803) (xy 307.280708 -426.101112)
			(xy 307.245017 -426.059921) (xy 307.215551 -426.014071) (xy 307.192909 -425.964494) (xy 307.177554 -425.912199)
			(xy 307.169798 -425.858251) (xy 307.169312 -425.831) (xy 307.169788 -425.804465) (xy 307.177173 -425.751912)
			(xy 307.191761 -425.700887) (xy 307.213269 -425.652371) (xy 307.241285 -425.607299) (xy 307.257958 -425.586652)
			(xy 307.266799 -425.575264) (xy 307.27833 -425.548854) (xy 307.282025 -425.520275) (xy 307.27759 -425.491801)
			(xy 307.265377 -425.465699) (xy 307.24636 -425.444048) (xy 307.222052 -425.428571) (xy 307.194388 -425.420499)
			(xy 307.17998 -425.420028) (xy 300.32452 -425.420028) (xy 300.299532 -425.419563) (xy 300.250173 -425.411737)
			(xy 300.202648 -425.396276) (xy 300.158133 -425.373561) (xy 300.117725 -425.344154) (xy 300.09973 -425.32681)
			(xy 296.49547 -421.72255) (xy 296.47814 -421.704544) (xy 296.448748 -421.664131) (xy 296.426039 -421.619617)
			(xy 296.410573 -421.572098) (xy 296.402731 -421.522746) (xy 296.402252 -421.49776) (xy 296.402252 -417.50869)
			(xy 296.402712 -417.4837) (xy 296.410527 -417.434334) (xy 296.42598 -417.386803) (xy 296.448687 -417.342278)
			(xy 296.478089 -417.301861) (xy 296.49547 -417.2839) (xy 296.634154 -417.145216) (xy 296.63771 -417.131246)
			(xy 296.644804 -417.103836) (xy 296.665987 -417.051331) (xy 296.694703 -417.002536) (xy 296.730322 -416.958526)
			(xy 296.772058 -416.920269) (xy 296.818994 -416.888607) (xy 296.870097 -416.864235) (xy 296.924243 -416.847691)
			(xy 296.980241 -416.839338) (xy 297.00855 -416.838892) (xy 297.035805 -416.839352) (xy 297.089762 -416.847103)
			(xy 297.142065 -416.862455) (xy 297.191652 -416.885094) (xy 297.237511 -416.914561) (xy 297.27871 -416.950255)
			(xy 297.314409 -416.991449) (xy 297.343882 -417.037304) (xy 297.366528 -417.086888) (xy 297.381886 -417.13919)
			(xy 297.389645 -417.193145) (xy 297.390058 -417.2204) (xy 299.420532 -417.2204) (xy 299.424603 -417.164778)
			(xy 299.436729 -417.110341) (xy 299.456652 -417.05825) (xy 299.483948 -417.009615) (xy 299.518034 -416.965472)
			(xy 299.558183 -416.926763) (xy 299.603541 -416.894312) (xy 299.653141 -416.868811) (xy 299.705925 -416.850804)
			(xy 299.760768 -416.840674) (xy 299.816502 -416.838637) (xy 299.871939 -416.844737) (xy 299.925896 -416.858843)
			(xy 299.977225 -416.880655) (xy 300.024831 -416.909709) (xy 300.067699 -416.945384) (xy 300.104916 -416.986921)
			(xy 300.135689 -417.033434) (xy 300.159361 -417.083931) (xy 300.175429 -417.137338) (xy 300.183549 -417.192514)
			(xy 300.184058 -417.2204) (xy 300.183549 -417.248286) (xy 300.176065 -417.29914) (xy 302.105312 -417.29914)
			(xy 302.109383 -417.243518) (xy 302.121509 -417.189081) (xy 302.141432 -417.13699) (xy 302.168728 -417.088355)
			(xy 302.202814 -417.044212) (xy 302.242963 -417.005503) (xy 302.288321 -416.973052) (xy 302.337921 -416.947551)
			(xy 302.390705 -416.929544) (xy 302.445548 -416.919414) (xy 302.501282 -416.917377) (xy 302.556719 -416.923477)
			(xy 302.610676 -416.937583) (xy 302.662005 -416.959395) (xy 302.709611 -416.988449) (xy 302.752479 -417.024124)
			(xy 302.789696 -417.065661) (xy 302.820469 -417.112174) (xy 302.844141 -417.162671) (xy 302.860209 -417.216078)
			(xy 302.868329 -417.271254) (xy 302.868838 -417.29914) (xy 302.868329 -417.327026) (xy 302.860209 -417.382202)
			(xy 302.844141 -417.435609) (xy 302.820469 -417.486106) (xy 302.789696 -417.532619) (xy 302.752479 -417.574156)
			(xy 302.709611 -417.609831) (xy 302.662005 -417.638885) (xy 302.610676 -417.660697) (xy 302.556719 -417.674803)
			(xy 302.501282 -417.680903) (xy 302.445548 -417.678866) (xy 302.390705 -417.668736) (xy 302.337921 -417.650729)
			(xy 302.288321 -417.625228) (xy 302.242963 -417.592777) (xy 302.202814 -417.554068) (xy 302.168728 -417.509925)
			(xy 302.141432 -417.46129) (xy 302.121509 -417.409199) (xy 302.109383 -417.354762) (xy 302.105312 -417.29914)
			(xy 300.176065 -417.29914) (xy 300.175429 -417.303462) (xy 300.159361 -417.356869) (xy 300.135689 -417.407366)
			(xy 300.104916 -417.453879) (xy 300.067699 -417.495416) (xy 300.024831 -417.531091) (xy 299.977225 -417.560145)
			(xy 299.925896 -417.581957) (xy 299.871939 -417.596063) (xy 299.816502 -417.602163) (xy 299.760768 -417.600126)
			(xy 299.705925 -417.589996) (xy 299.653141 -417.571989) (xy 299.603541 -417.546488) (xy 299.558183 -417.514037)
			(xy 299.518034 -417.475328) (xy 299.483948 -417.431185) (xy 299.456652 -417.38255) (xy 299.436729 -417.330459)
			(xy 299.424603 -417.276022) (xy 299.420532 -417.2204) (xy 297.390058 -417.2204) (xy 297.389536 -417.248701)
			(xy 297.381157 -417.304678) (xy 297.364599 -417.358804) (xy 297.340225 -417.409888) (xy 297.308569 -417.45681)
			(xy 297.270328 -417.498539) (xy 297.22634 -417.53416) (xy 297.177572 -417.562889) (xy 297.125094 -417.584096)
			(xy 297.097704 -417.59124) (xy 297.083734 -417.594796) (xy 297.038268 -417.640262) (xy 297.038268 -419.880288)
			(xy 297.038721 -419.894139) (xy 297.046152 -419.920825) (xy 297.060494 -419.944524) (xy 297.080689 -419.963485)
			(xy 297.105244 -419.976308) (xy 297.132345 -419.982043) (xy 297.15999 -419.980269) (xy 297.186135 -419.971115)
			(xy 297.19778 -419.9636) (xy 297.221949 -419.947418) (xy 297.274156 -419.92178) (xy 297.329647 -419.904358)
			(xy 297.387139 -419.895554) (xy 297.41622 -419.89502) (xy 297.445658 -419.895565) (xy 297.503833 -419.904624)
			(xy 297.532044 -419.913054) (xy 297.54636 -419.917046) (xy 297.576063 -419.917483) (xy 297.604639 -419.909364)
			(xy 297.629675 -419.893375) (xy 297.649059 -419.870864) (xy 297.661156 -419.843732) (xy 297.664943 -419.814267)
			(xy 297.663108 -419.799516) (xy 297.660626 -419.783822) (xy 297.657957 -419.752158) (xy 297.657774 -419.73627)
			(xy 297.65826 -419.709019) (xy 297.666016 -419.655071) (xy 297.681371 -419.602776) (xy 297.704013 -419.553199)
			(xy 297.733479 -419.507349) (xy 297.76917 -419.466158) (xy 297.810361 -419.430467) (xy 297.856211 -419.401001)
			(xy 297.905788 -419.378359) (xy 297.958083 -419.363004) (xy 298.012031 -419.355248) (xy 298.066533 -419.355248)
			(xy 298.120481 -419.363004) (xy 298.172776 -419.378359) (xy 298.222353 -419.401001) (xy 298.268203 -419.430467)
			(xy 298.309394 -419.466158) (xy 298.345085 -419.507349) (xy 298.374551 -419.553199) (xy 298.397193 -419.602776)
			(xy 298.412548 -419.655071) (xy 298.420304 -419.709019) (xy 298.42079 -419.73627) (xy 298.420664 -419.752027)
			(xy 298.418119 -419.783436) (xy 298.41571 -419.799008) (xy 298.413759 -419.813722) (xy 298.417473 -419.843158)
			(xy 298.429496 -419.870281) (xy 298.448812 -419.892801) (xy 298.473788 -419.908814) (xy 298.502315 -419.916967)
			(xy 298.531981 -419.916571) (xy 298.546266 -419.912546) (xy 298.574192 -419.90435) (xy 298.631721 -419.895546)
			(xy 298.66082 -419.89502) (xy 298.688068 -419.895508) (xy 298.74201 -419.903266) (xy 298.794299 -419.918622)
			(xy 298.84387 -419.941263) (xy 298.889715 -419.970728) (xy 298.9309 -420.006417) (xy 298.966587 -420.047604)
			(xy 298.996049 -420.093451) (xy 299.018687 -420.143023) (xy 299.034039 -420.195313) (xy 299.041794 -420.249256)
			(xy 299.041794 -420.303726) (xy 299.829205 -420.303726) (xy 299.829208 -420.249228) (xy 299.836967 -420.195285)
			(xy 299.852324 -420.142996) (xy 299.874966 -420.093424) (xy 299.904433 -420.047578) (xy 299.940124 -420.006393)
			(xy 299.981313 -419.970707) (xy 300.027161 -419.941246) (xy 300.076736 -419.918609) (xy 300.129027 -419.903258)
			(xy 300.182971 -419.895505) (xy 300.21022 -419.89502) (xy 300.239656 -419.895588) (xy 300.29783 -419.90464)
			(xy 300.326044 -419.913054) (xy 300.340364 -419.917131) (xy 300.37012 -419.917649) (xy 300.398762 -419.909563)
			(xy 300.423856 -419.893561) (xy 300.443268 -419.871002) (xy 300.455349 -419.843803) (xy 300.459073 -419.814275)
			(xy 300.457108 -419.799516) (xy 300.454618 -419.783823) (xy 300.451947 -419.752158) (xy 300.451774 -419.73627)
			(xy 300.45226 -419.709019) (xy 300.460016 -419.655071) (xy 300.475371 -419.602776) (xy 300.498013 -419.553199)
			(xy 300.527479 -419.507349) (xy 300.56317 -419.466158) (xy 300.604361 -419.430467) (xy 300.650211 -419.401001)
			(xy 300.699788 -419.378359) (xy 300.752083 -419.363004) (xy 300.806031 -419.355248) (xy 300.860533 -419.355248)
			(xy 300.914481 -419.363004) (xy 300.966776 -419.378359) (xy 301.016353 -419.401001) (xy 301.062203 -419.430467)
			(xy 301.103394 -419.466158) (xy 301.139085 -419.507349) (xy 301.168551 -419.553199) (xy 301.191193 -419.602776)
			(xy 301.206548 -419.655071) (xy 301.214304 -419.709019) (xy 301.21479 -419.73627) (xy 301.214653 -419.752026)
			(xy 301.212109 -419.783435) (xy 301.20971 -419.799008) (xy 301.207819 -419.813724) (xy 301.21153 -419.843142)
			(xy 301.223546 -419.87025) (xy 301.242851 -419.892757) (xy 301.267813 -419.90876) (xy 301.296323 -419.916908)
			(xy 301.325972 -419.916513) (xy 301.340266 -419.912546) (xy 301.368195 -419.904361) (xy 301.425721 -419.895552)
			(xy 301.45482 -419.89502) (xy 301.482069 -419.8955) (xy 301.536012 -419.903258) (xy 301.588302 -419.918614)
			(xy 301.637874 -419.941256) (xy 301.68372 -419.970721) (xy 301.724906 -420.006411) (xy 301.760593 -420.047599)
			(xy 301.790056 -420.093447) (xy 301.812694 -420.143021) (xy 301.828047 -420.195311) (xy 301.835802 -420.249255)
			(xy 301.835802 -420.303753) (xy 301.828394 -420.355268) (xy 302.512982 -420.355268) (xy 302.517053 -420.299646)
			(xy 302.529179 -420.245209) (xy 302.549102 -420.193118) (xy 302.576398 -420.144483) (xy 302.610484 -420.10034)
			(xy 302.650633 -420.061631) (xy 302.695991 -420.02918) (xy 302.745591 -420.003679) (xy 302.798375 -419.985672)
			(xy 302.853218 -419.975542) (xy 302.908952 -419.973505) (xy 302.964389 -419.979605) (xy 303.018346 -419.993711)
			(xy 303.069675 -420.015523) (xy 303.117281 -420.044577) (xy 303.160149 -420.080252) (xy 303.197366 -420.121789)
			(xy 303.228139 -420.168302) (xy 303.251811 -420.218799) (xy 303.267879 -420.272206) (xy 303.275999 -420.327382)
			(xy 303.276508 -420.355268) (xy 303.757582 -420.355268) (xy 303.761653 -420.299646) (xy 303.773779 -420.245209)
			(xy 303.793702 -420.193118) (xy 303.820998 -420.144483) (xy 303.855084 -420.10034) (xy 303.895233 -420.061631)
			(xy 303.940591 -420.02918) (xy 303.990191 -420.003679) (xy 304.042975 -419.985672) (xy 304.097818 -419.975542)
			(xy 304.153552 -419.973505) (xy 304.208989 -419.979605) (xy 304.262946 -419.993711) (xy 304.314275 -420.015523)
			(xy 304.361881 -420.044577) (xy 304.404749 -420.080252) (xy 304.441966 -420.121789) (xy 304.472739 -420.168302)
			(xy 304.496411 -420.218799) (xy 304.512479 -420.272206) (xy 304.520599 -420.327382) (xy 304.521108 -420.355268)
			(xy 304.520599 -420.383154) (xy 304.512479 -420.43833) (xy 304.496411 -420.491737) (xy 304.472739 -420.542234)
			(xy 304.441966 -420.588747) (xy 304.404749 -420.630284) (xy 304.361881 -420.665959) (xy 304.314275 -420.695013)
			(xy 304.262946 -420.716825) (xy 304.208989 -420.730931) (xy 304.153552 -420.737031) (xy 304.097818 -420.734994)
			(xy 304.042975 -420.724864) (xy 303.990191 -420.706857) (xy 303.940591 -420.681356) (xy 303.895233 -420.648905)
			(xy 303.855084 -420.610196) (xy 303.820998 -420.566053) (xy 303.793702 -420.517418) (xy 303.773779 -420.465327)
			(xy 303.761653 -420.41089) (xy 303.757582 -420.355268) (xy 303.276508 -420.355268) (xy 303.275999 -420.383154)
			(xy 303.267879 -420.43833) (xy 303.251811 -420.491737) (xy 303.228139 -420.542234) (xy 303.197366 -420.588747)
			(xy 303.160149 -420.630284) (xy 303.117281 -420.665959) (xy 303.069675 -420.695013) (xy 303.018346 -420.716825)
			(xy 302.964389 -420.730931) (xy 302.908952 -420.737031) (xy 302.853218 -420.734994) (xy 302.798375 -420.724864)
			(xy 302.745591 -420.706857) (xy 302.695991 -420.681356) (xy 302.650633 -420.648905) (xy 302.610484 -420.610196)
			(xy 302.576398 -420.566053) (xy 302.549102 -420.517418) (xy 302.529179 -420.465327) (xy 302.517053 -420.41089)
			(xy 302.512982 -420.355268) (xy 301.828394 -420.355268) (xy 301.828045 -420.357696) (xy 301.812691 -420.409987)
			(xy 301.790052 -420.45956) (xy 301.760588 -420.505407) (xy 301.7249 -420.546594) (xy 301.683713 -420.582283)
			(xy 301.637867 -420.611748) (xy 301.588294 -420.634388) (xy 301.536004 -420.649744) (xy 301.482061 -420.657501)
			(xy 301.427563 -420.657503) (xy 301.373619 -420.649749) (xy 301.321328 -420.634397) (xy 301.271754 -420.61176)
			(xy 301.225906 -420.582298) (xy 301.184717 -420.546611) (xy 301.149026 -420.505426) (xy 301.11956 -420.459581)
			(xy 301.096917 -420.410009) (xy 301.08156 -420.35772) (xy 301.0738 -420.303777) (xy 301.073312 -420.276528)
			(xy 301.073448 -420.260772) (xy 301.075992 -420.229363) (xy 301.078392 -420.21379) (xy 301.080283 -420.199074)
			(xy 301.076571 -420.169656) (xy 301.064555 -420.142549) (xy 301.04525 -420.120043) (xy 301.020289 -420.104039)
			(xy 300.991779 -420.095891) (xy 300.96213 -420.096286) (xy 300.947836 -420.100252) (xy 300.919907 -420.108437)
			(xy 300.862381 -420.117246) (xy 300.833282 -420.117778) (xy 300.803846 -420.11721) (xy 300.745672 -420.108157)
			(xy 300.717458 -420.099744) (xy 300.703137 -420.095672) (xy 300.673381 -420.095153) (xy 300.64474 -420.103238)
			(xy 300.619647 -420.11924) (xy 300.600235 -420.141798) (xy 300.588154 -420.168996) (xy 300.584429 -420.198523)
			(xy 300.586394 -420.213282) (xy 300.588884 -420.228975) (xy 300.591555 -420.26064) (xy 300.591728 -420.276528)
			(xy 300.591192 -420.303777) (xy 300.583432 -420.35772) (xy 300.568074 -420.410009) (xy 300.545431 -420.459581)
			(xy 300.515964 -420.505426) (xy 300.480273 -420.54661) (xy 300.439083 -420.582296) (xy 300.393234 -420.611757)
			(xy 300.343659 -420.634393) (xy 300.291368 -420.649743) (xy 300.237424 -420.657496) (xy 300.182926 -420.657492)
			(xy 300.128983 -420.649733) (xy 300.076693 -420.634375) (xy 300.027121 -420.611733) (xy 299.981276 -420.582266)
			(xy 299.940092 -420.546574) (xy 299.904405 -420.505385) (xy 299.874944 -420.459537) (xy 299.852308 -420.409962)
			(xy 299.836957 -420.35767) (xy 299.829205 -420.303726) (xy 299.041794 -420.303726) (xy 299.041794 -420.303752)
			(xy 299.034037 -420.357695) (xy 299.018684 -420.409984) (xy 298.996045 -420.459556) (xy 298.966582 -420.505402)
			(xy 298.930894 -420.546589) (xy 298.889709 -420.582277) (xy 298.843863 -420.611741) (xy 298.794292 -420.634381)
			(xy 298.742003 -420.649736) (xy 298.68806 -420.657493) (xy 298.633563 -420.657495) (xy 298.579621 -420.649741)
			(xy 298.527331 -420.634389) (xy 298.477758 -420.611753) (xy 298.431911 -420.582291) (xy 298.390723 -420.546606)
			(xy 298.355033 -420.505421) (xy 298.325567 -420.459577) (xy 298.302925 -420.410007) (xy 298.287568 -420.357718)
			(xy 298.279808 -420.303776) (xy 298.279312 -420.276528) (xy 298.279438 -420.260771) (xy 298.281983 -420.229362)
			(xy 298.284392 -420.21379) (xy 298.286342 -420.199076) (xy 298.282628 -420.16964) (xy 298.270605 -420.142517)
			(xy 298.251289 -420.119998) (xy 298.226313 -420.103985) (xy 298.197787 -420.095832) (xy 298.168121 -420.096227)
			(xy 298.153836 -420.100252) (xy 298.12591 -420.108448) (xy 298.068381 -420.117253) (xy 298.039282 -420.117778)
			(xy 298.009844 -420.117233) (xy 297.951669 -420.108174) (xy 297.923458 -420.099744) (xy 297.909142 -420.095752)
			(xy 297.879438 -420.095315) (xy 297.850861 -420.103433) (xy 297.825824 -420.119423) (xy 297.806439 -420.141934)
			(xy 297.794342 -420.169066) (xy 297.790554 -420.198531) (xy 297.792394 -420.213282) (xy 297.794876 -420.228976)
			(xy 297.797545 -420.26064) (xy 297.797728 -420.276528) (xy 297.79724 -420.303778) (xy 297.789481 -420.357724)
			(xy 297.774123 -420.410017) (xy 297.751481 -420.459592) (xy 297.722014 -420.50544) (xy 297.686323 -420.546629)
			(xy 297.645134 -420.582319) (xy 297.599285 -420.611785) (xy 297.549709 -420.634426) (xy 297.497416 -420.649782)
			(xy 297.44347 -420.657541) (xy 297.41622 -420.658036) (xy 297.387137 -420.657512) (xy 297.329639 -420.648725)
			(xy 297.274143 -420.631305) (xy 297.221937 -420.605658) (xy 297.19778 -420.589456) (xy 297.186149 -420.581954)
			(xy 297.160016 -420.572872) (xy 297.132404 -420.571145) (xy 297.105343 -420.5769) (xy 297.080823 -420.589713)
			(xy 297.060646 -420.608642) (xy 297.046297 -420.632296) (xy 297.03883 -420.658936) (xy 297.038268 -420.672768)
			(xy 297.038268 -421.366188) (xy 300.456092 -424.784012) (xy 310.134508 -424.784012) (xy 310.7944 -424.12412)
			(xy 310.7944 -419.04666) (xy 305.198526 -413.450786) (xy 305.188163 -413.441144) (xy 305.163389 -413.427476)
			(xy 305.135816 -413.421127) (xy 305.107559 -413.422585) (xy 305.080786 -413.431737) (xy 305.05755 -413.447882)
			(xy 305.039633 -413.46978) (xy 305.02841 -413.495754) (xy 305.02606 -413.509714) (xy 305.022076 -413.536974)
			(xy 305.007282 -413.590041) (xy 304.985008 -413.640427) (xy 304.955718 -413.687086) (xy 304.92002 -413.729046)
			(xy 304.878657 -413.765434) (xy 304.83249 -413.795493) (xy 304.782479 -413.818599) (xy 304.729665 -413.83427)
			(xy 304.675145 -413.84218) (xy 304.6476 -413.842708) (xy 304.620349 -413.842222) (xy 304.566401 -413.834466)
			(xy 304.514106 -413.819111) (xy 304.464529 -413.796469) (xy 304.418679 -413.767003) (xy 304.377488 -413.731312)
			(xy 304.341797 -413.690121) (xy 304.312331 -413.644271) (xy 304.289689 -413.594694) (xy 304.274334 -413.542399)
			(xy 304.266578 -413.488451) (xy 304.266092 -413.4612) (xy 304.266576 -413.433653) (xy 304.274498 -413.379132)
			(xy 304.290179 -413.326317) (xy 304.313292 -413.276306) (xy 304.343356 -413.230139) (xy 304.379747 -413.188775)
			(xy 304.421708 -413.153073) (xy 304.468367 -413.123777) (xy 304.518753 -413.101496) (xy 304.57182 -413.086691)
			(xy 304.599086 -413.08274) (xy 304.613084 -413.08049) (xy 304.639129 -413.069318) (xy 304.661094 -413.05141)
			(xy 304.677281 -413.028148) (xy 304.686441 -413.001329) (xy 304.687866 -412.973025) (xy 304.681446 -412.945422)
			(xy 304.667676 -412.920652) (xy 304.658014 -412.910274) (xy 302.649636 -410.901896) (xy 302.638655 -410.891717)
			(xy 302.612232 -410.877664) (xy 302.58287 -410.871874) (xy 302.553091 -410.874841) (xy 302.525449 -410.886313)
			(xy 302.502319 -410.905303) (xy 302.485686 -410.930183) (xy 302.476977 -410.958815) (xy 302.476408 -410.973778)
			(xy 302.476408 -412.961328) (xy 304.49774 -414.98266) (xy 304.824382 -414.98266) (xy 304.828453 -414.927038)
			(xy 304.840579 -414.872601) (xy 304.860502 -414.82051) (xy 304.887798 -414.771875) (xy 304.921884 -414.727732)
			(xy 304.962033 -414.689023) (xy 305.007391 -414.656572) (xy 305.056991 -414.631071) (xy 305.109775 -414.613064)
			(xy 305.164618 -414.602934) (xy 305.220352 -414.600897) (xy 305.275789 -414.606997) (xy 305.329746 -414.621103)
			(xy 305.381075 -414.642915) (xy 305.428681 -414.671969) (xy 305.471549 -414.707644) (xy 305.508766 -414.749181)
			(xy 305.539539 -414.795694) (xy 305.563211 -414.846191) (xy 305.579279 -414.899598) (xy 305.587399 -414.954774)
			(xy 305.587908 -414.98266) (xy 305.587399 -415.010546) (xy 305.579279 -415.065722) (xy 305.563211 -415.119129)
			(xy 305.539539 -415.169626) (xy 305.508766 -415.216139) (xy 305.471549 -415.257676) (xy 305.428681 -415.293351)
			(xy 305.381075 -415.322405) (xy 305.329746 -415.344217) (xy 305.275789 -415.358323) (xy 305.220352 -415.364423)
			(xy 305.164618 -415.362386) (xy 305.109775 -415.352256) (xy 305.056991 -415.334249) (xy 305.007391 -415.308748)
			(xy 304.962033 -415.276297) (xy 304.921884 -415.237588) (xy 304.887798 -415.193445) (xy 304.860502 -415.14481)
			(xy 304.840579 -415.092719) (xy 304.828453 -415.038282) (xy 304.824382 -414.98266) (xy 304.49774 -414.98266)
			(xy 306.62499 -417.10991) (xy 306.642338 -417.127899) (xy 306.671729 -417.168317) (xy 306.694434 -417.212835)
			(xy 306.709894 -417.260357) (xy 306.717728 -417.309713) (xy 306.718208 -417.3347) (xy 306.718208 -419.71722)
			(xy 306.717678 -419.74309) (xy 306.709266 -419.794142) (xy 306.692715 -419.843165) (xy 306.668461 -419.888868)
			(xy 306.653184 -419.909752) (xy 306.64785 -419.935632) (xy 306.63099 -419.985712) (xy 306.60738 -420.032986)
			(xy 306.577472 -420.076548) (xy 306.541837 -420.115566) (xy 306.501159 -420.149292) (xy 306.456215 -420.177082)
			(xy 306.407866 -420.198402) (xy 306.357037 -420.212846) (xy 306.304701 -420.220136) (xy 306.27828 -420.220648)
			(xy 306.251029 -420.220161) (xy 306.197081 -420.212402) (xy 306.144786 -420.197046) (xy 306.095209 -420.174404)
			(xy 306.049358 -420.144938) (xy 306.008167 -420.109247) (xy 305.972474 -420.068058) (xy 305.943006 -420.022209)
			(xy 305.920361 -419.972632) (xy 305.905002 -419.920339) (xy 305.897241 -419.866391) (xy 305.896772 -419.83914)
			(xy 305.89727 -419.811022) (xy 305.905515 -419.755393) (xy 305.921832 -419.701576) (xy 305.945869 -419.650735)
			(xy 305.977104 -419.603971) (xy 306.014863 -419.562296) (xy 306.058327 -419.526612) (xy 306.082192 -419.511734)
			(xy 306.082192 -417.466272) (xy 301.93361 -413.31769) (xy 301.916262 -413.299701) (xy 301.886871 -413.259283)
			(xy 301.864166 -413.214765) (xy 301.848706 -413.167243) (xy 301.840872 -413.117887) (xy 301.840392 -413.0929)
			(xy 301.840392 -412.479236) (xy 301.83988 -412.464354) (xy 301.831303 -412.435853) (xy 301.814869 -412.411039)
			(xy 301.791975 -412.39202) (xy 301.764568 -412.380415) (xy 301.734977 -412.37721) (xy 301.72025 -412.379414)
			(xy 301.702944 -412.382408) (xy 301.667963 -412.385587) (xy 301.6504 -412.385764) (xy 301.623152 -412.385278)
			(xy 301.56921 -412.377522) (xy 301.516922 -412.362169) (xy 301.46735 -412.33953) (xy 301.421505 -412.310068)
			(xy 301.38032 -412.27438) (xy 301.344632 -412.233195) (xy 301.31517 -412.18735) (xy 301.292531 -412.137778)
			(xy 301.277178 -412.08549) (xy 301.269422 -412.031548) (xy 301.269422 -411.977052) (xy 301.277178 -411.92311)
			(xy 301.292531 -411.870822) (xy 301.31517 -411.82125) (xy 301.344632 -411.775405) (xy 301.38032 -411.73422)
			(xy 301.421505 -411.698532) (xy 301.46735 -411.66907) (xy 301.516922 -411.646431) (xy 301.56921 -411.631078)
			(xy 301.623152 -411.623322) (xy 301.6504 -411.622748) (xy 301.667963 -411.622925) (xy 301.702944 -411.626102)
			(xy 301.72025 -411.629098) (xy 301.734973 -411.631308) (xy 301.764556 -411.62808) (xy 301.791954 -411.616466)
			(xy 301.814844 -411.59745) (xy 301.831284 -411.572645) (xy 301.839879 -411.544155) (xy 301.840392 -411.529276)
			(xy 301.840392 -410.29128) (xy 298.8183 -410.29128) (xy 298.802785 -410.291842) (xy 298.773186 -410.301162)
			(xy 298.747735 -410.318915) (xy 298.728767 -410.343474) (xy 298.71802 -410.372585) (xy 298.7167 -410.388054)
			(xy 298.714897 -410.415684) (xy 298.70431 -410.470031) (xy 298.685977 -410.522276) (xy 298.660282 -410.571321)
			(xy 298.627766 -410.616136) (xy 298.589112 -410.655779) (xy 298.545132 -410.689416) (xy 298.496751 -410.716341)
			(xy 298.444985 -410.735988) (xy 298.390923 -410.747943) (xy 298.3357 -410.751957) (xy 298.280477 -410.747943)
			(xy 298.226415 -410.735988) (xy 298.174649 -410.716341) (xy 298.126268 -410.689416) (xy 298.082288 -410.655779)
			(xy 298.043634 -410.616136) (xy 298.011118 -410.571321) (xy 297.985423 -410.522276) (xy 297.96709 -410.470031)
			(xy 297.956503 -410.415684) (xy 297.9547 -410.388054) (xy 297.95342 -410.37257) (xy 297.942715 -410.343421)
			(xy 297.923745 -410.318835) (xy 297.898264 -410.301086) (xy 297.868628 -410.291813) (xy 297.8531 -410.29128)
			(xy 297.46702 -410.29128) (xy 297.451979 -410.291818) (xy 297.4232 -410.300579) (xy 297.398225 -410.317348)
			(xy 297.379221 -410.340667) (xy 297.367837 -410.368513) (xy 297.365064 -410.398467) (xy 297.371141 -410.427929)
			(xy 297.377866 -410.441394) (xy 297.392521 -410.469578) (xy 297.413269 -410.529613) (xy 297.423762 -410.59226)
			(xy 297.424348 -410.62402) (xy 297.423862 -410.651271) (xy 297.416106 -410.705219) (xy 297.400751 -410.757514)
			(xy 297.378109 -410.807091) (xy 297.348643 -410.852941) (xy 297.312952 -410.894132) (xy 297.271761 -410.929823)
			(xy 297.225911 -410.959289) (xy 297.176334 -410.981931) (xy 297.124039 -410.997286) (xy 297.070091 -411.005042)
			(xy 297.015589 -411.005042) (xy 296.961641 -410.997286) (xy 296.909346 -410.981931) (xy 296.859769 -410.959289)
			(xy 296.813919 -410.929823) (xy 296.772728 -410.894132) (xy 296.737037 -410.852941) (xy 296.707571 -410.807091)
			(xy 296.684929 -410.757514) (xy 296.669574 -410.705219) (xy 296.661818 -410.651271) (xy 296.661332 -410.62402)
			(xy 296.661965 -410.592264) (xy 296.67247 -410.529626) (xy 296.693178 -410.469583) (xy 296.707814 -410.441394)
			(xy 296.714514 -410.427927) (xy 296.720552 -410.398475) (xy 296.717758 -410.36854) (xy 296.706376 -410.340713)
			(xy 296.687389 -410.317402) (xy 296.662442 -410.300624) (xy 296.633692 -410.291831) (xy 296.61866 -410.29128)
			(xy 295.06418 -410.29128) (xy 294.457628 -410.897832) (xy 294.457628 -411.078172) (xy 294.464994 -411.090364)
			(xy 294.47831 -411.112935) (xy 294.499304 -411.16095) (xy 294.513524 -411.211388) (xy 294.520702 -411.263298)
			(xy 294.521128 -411.2895) (xy 294.520642 -411.316751) (xy 294.512886 -411.370699) (xy 294.497531 -411.422994)
			(xy 294.474889 -411.472571) (xy 294.445423 -411.518421) (xy 294.409732 -411.559612) (xy 294.368541 -411.595303)
			(xy 294.322691 -411.624769) (xy 294.305982 -411.6324) (xy 295.266362 -411.6324) (xy 295.270433 -411.576778)
			(xy 295.282559 -411.522341) (xy 295.302482 -411.47025) (xy 295.329778 -411.421615) (xy 295.363864 -411.377472)
			(xy 295.404013 -411.338763) (xy 295.449371 -411.306312) (xy 295.498971 -411.280811) (xy 295.551755 -411.262804)
			(xy 295.606598 -411.252674) (xy 295.662332 -411.250637) (xy 295.717769 -411.256737) (xy 295.771726 -411.270843)
			(xy 295.823055 -411.292655) (xy 295.870661 -411.321709) (xy 295.913529 -411.357384) (xy 295.950746 -411.398921)
			(xy 295.981519 -411.445434) (xy 296.005191 -411.495931) (xy 296.021259 -411.549338) (xy 296.029379 -411.604514)
			(xy 296.029888 -411.6324) (xy 296.029379 -411.660286) (xy 296.021259 -411.715462) (xy 296.005191 -411.768869)
			(xy 295.981519 -411.819366) (xy 295.950746 -411.865879) (xy 295.913529 -411.907416) (xy 295.870661 -411.943091)
			(xy 295.823055 -411.972145) (xy 295.771726 -411.993957) (xy 295.717769 -412.008063) (xy 295.662332 -412.014163)
			(xy 295.606598 -412.012126) (xy 295.551755 -412.001996) (xy 295.498971 -411.983989) (xy 295.449371 -411.958488)
			(xy 295.404013 -411.926037) (xy 295.363864 -411.887328) (xy 295.329778 -411.843185) (xy 295.302482 -411.79455)
			(xy 295.282559 -411.742459) (xy 295.270433 -411.688022) (xy 295.266362 -411.6324) (xy 294.305982 -411.6324)
			(xy 294.273114 -411.647411) (xy 294.220819 -411.662766) (xy 294.166871 -411.670522) (xy 294.112369 -411.670522)
			(xy 294.058421 -411.662766) (xy 294.006126 -411.647411) (xy 293.956549 -411.624769) (xy 293.910699 -411.595303)
			(xy 293.869508 -411.559612) (xy 293.833817 -411.518421) (xy 293.804351 -411.472571) (xy 293.781709 -411.422994)
			(xy 293.766354 -411.370699) (xy 293.758598 -411.316751) (xy 293.758112 -411.2895) (xy 293.758586 -411.261536)
			(xy 293.766714 -411.206201) (xy 293.782826 -411.152644) (xy 293.806578 -411.10201) (xy 293.821612 -411.078426)
			(xy 293.821612 -410.76626) (xy 293.822074 -410.74127) (xy 293.829893 -410.691906) (xy 293.845347 -410.644377)
			(xy 293.868055 -410.599854) (xy 293.897457 -410.559438) (xy 293.91483 -410.54147) (xy 293.991538 -410.464762)
			(xy 294.001759 -410.453795) (xy 294.015894 -410.427376) (xy 294.021758 -410.397992) (xy 294.018848 -410.36817)
			(xy 294.007412 -410.340475) (xy 293.988435 -410.317287) (xy 293.963548 -410.3006) (xy 293.934891 -410.29185)
			(xy 293.91991 -410.29128) (xy 288.72688 -410.29128) (xy 287.80232 -411.21584) (xy 290.945822 -411.21584)
			(xy 290.949893 -411.160218) (xy 290.962019 -411.105781) (xy 290.981942 -411.05369) (xy 291.009238 -411.005055)
			(xy 291.043324 -410.960912) (xy 291.083473 -410.922203) (xy 291.128831 -410.889752) (xy 291.178431 -410.864251)
			(xy 291.231215 -410.846244) (xy 291.286058 -410.836114) (xy 291.341792 -410.834077) (xy 291.397229 -410.840177)
			(xy 291.451186 -410.854283) (xy 291.502515 -410.876095) (xy 291.550121 -410.905149) (xy 291.592989 -410.940824)
			(xy 291.630206 -410.982361) (xy 291.660979 -411.028874) (xy 291.684651 -411.079371) (xy 291.700719 -411.132778)
			(xy 291.708839 -411.187954) (xy 291.709348 -411.21584) (xy 291.708839 -411.243726) (xy 291.700719 -411.298902)
			(xy 291.684651 -411.352309) (xy 291.660979 -411.402806) (xy 291.630206 -411.449319) (xy 291.592989 -411.490856)
			(xy 291.550121 -411.526531) (xy 291.502515 -411.555585) (xy 291.451186 -411.577397) (xy 291.397229 -411.591503)
			(xy 291.341792 -411.597603) (xy 291.286058 -411.595566) (xy 291.231215 -411.585436) (xy 291.178431 -411.567429)
			(xy 291.128831 -411.541928) (xy 291.083473 -411.509477) (xy 291.043324 -411.470768) (xy 291.009238 -411.426625)
			(xy 290.981942 -411.37799) (xy 290.962019 -411.325899) (xy 290.949893 -411.271462) (xy 290.945822 -411.21584)
			(xy 287.80232 -411.21584) (xy 287.23971 -411.77845) (xy 287.221703 -411.795777) (xy 287.181288 -411.825162)
			(xy 287.136773 -411.847864) (xy 287.089255 -411.863323) (xy 287.039904 -411.871158) (xy 287.01492 -411.871668)
			(xy 286.206946 -411.871668) (xy 285.414804 -412.66364) (xy 300.615602 -412.66364) (xy 300.619673 -412.608018)
			(xy 300.631799 -412.553581) (xy 300.651722 -412.50149) (xy 300.679018 -412.452855) (xy 300.713104 -412.408712)
			(xy 300.753253 -412.370003) (xy 300.798611 -412.337552) (xy 300.848211 -412.312051) (xy 300.900995 -412.294044)
			(xy 300.955838 -412.283914) (xy 301.011572 -412.281877) (xy 301.067009 -412.287977) (xy 301.120966 -412.302083)
			(xy 301.172295 -412.323895) (xy 301.219901 -412.352949) (xy 301.262769 -412.388624) (xy 301.299986 -412.430161)
			(xy 301.330759 -412.476674) (xy 301.354431 -412.527171) (xy 301.370499 -412.580578) (xy 301.378619 -412.635754)
			(xy 301.379128 -412.66364) (xy 301.378619 -412.691526) (xy 301.370499 -412.746702) (xy 301.354431 -412.800109)
			(xy 301.330759 -412.850606) (xy 301.299986 -412.897119) (xy 301.262769 -412.938656) (xy 301.219901 -412.974331)
			(xy 301.172295 -413.003385) (xy 301.120966 -413.025197) (xy 301.067009 -413.039303) (xy 301.011572 -413.045403)
			(xy 300.955838 -413.043366) (xy 300.900995 -413.033236) (xy 300.848211 -413.015229) (xy 300.798611 -412.989728)
			(xy 300.753253 -412.957277) (xy 300.713104 -412.918568) (xy 300.679018 -412.874425) (xy 300.651722 -412.82579)
			(xy 300.631799 -412.773699) (xy 300.619673 -412.719262) (xy 300.615602 -412.66364) (xy 285.414804 -412.66364)
			(xy 285.02356 -413.0548) (xy 285.02356 -413.74314) (xy 292.29126 -413.74314) (xy 292.295331 -413.687518)
			(xy 292.307457 -413.633081) (xy 292.32738 -413.58099) (xy 292.354676 -413.532355) (xy 292.388762 -413.488212)
			(xy 292.428911 -413.449503) (xy 292.474269 -413.417052) (xy 292.523869 -413.391551) (xy 292.576653 -413.373544)
			(xy 292.631496 -413.363414) (xy 292.68723 -413.361377) (xy 292.742667 -413.367477) (xy 292.796624 -413.381583)
			(xy 292.847953 -413.403395) (xy 292.895559 -413.432449) (xy 292.938427 -413.468124) (xy 292.975644 -413.509661)
			(xy 293.006417 -413.556174) (xy 293.030089 -413.606671) (xy 293.046157 -413.660078) (xy 293.054277 -413.715254)
			(xy 293.054415 -413.72282) (xy 295.484802 -413.72282) (xy 295.488873 -413.667198) (xy 295.500999 -413.612761)
			(xy 295.520922 -413.56067) (xy 295.548218 -413.512035) (xy 295.582304 -413.467892) (xy 295.622453 -413.429183)
			(xy 295.667811 -413.396732) (xy 295.717411 -413.371231) (xy 295.770195 -413.353224) (xy 295.825038 -413.343094)
			(xy 295.880772 -413.341057) (xy 295.936209 -413.347157) (xy 295.990166 -413.361263) (xy 296.041495 -413.383075)
			(xy 296.089101 -413.412129) (xy 296.131969 -413.447804) (xy 296.169186 -413.489341) (xy 296.199959 -413.535854)
			(xy 296.223631 -413.586351) (xy 296.239699 -413.639758) (xy 296.247819 -413.694934) (xy 296.248328 -413.72282)
			(xy 296.247819 -413.750706) (xy 296.239699 -413.805882) (xy 296.223631 -413.859289) (xy 296.199959 -413.909786)
			(xy 296.169186 -413.956299) (xy 296.131969 -413.997836) (xy 296.089101 -414.033511) (xy 296.041495 -414.062565)
			(xy 295.990166 -414.084377) (xy 295.936209 -414.098483) (xy 295.880772 -414.104583) (xy 295.825038 -414.102546)
			(xy 295.770195 -414.092416) (xy 295.717411 -414.074409) (xy 295.667811 -414.048908) (xy 295.622453 -414.016457)
			(xy 295.582304 -413.977748) (xy 295.548218 -413.933605) (xy 295.520922 -413.88497) (xy 295.500999 -413.832879)
			(xy 295.488873 -413.778442) (xy 295.484802 -413.72282) (xy 293.054415 -413.72282) (xy 293.054786 -413.74314)
			(xy 293.054277 -413.771026) (xy 293.046157 -413.826202) (xy 293.030089 -413.879609) (xy 293.006417 -413.930106)
			(xy 292.975644 -413.976619) (xy 292.938427 -414.018156) (xy 292.895559 -414.053831) (xy 292.847953 -414.082885)
			(xy 292.796624 -414.104697) (xy 292.742667 -414.118803) (xy 292.68723 -414.124903) (xy 292.631496 -414.122866)
			(xy 292.576653 -414.112736) (xy 292.523869 -414.094729) (xy 292.474269 -414.069228) (xy 292.428911 -414.036777)
			(xy 292.388762 -413.998068) (xy 292.354676 -413.953925) (xy 292.32738 -413.90529) (xy 292.307457 -413.853199)
			(xy 292.295331 -413.798762) (xy 292.29126 -413.74314) (xy 285.02356 -413.74314) (xy 285.02356 -415.97326)
			(xy 284.757368 -416.239706) (xy 284.757368 -416.42284) (xy 284.756906 -416.44783) (xy 284.749087 -416.497193)
			(xy 284.733632 -416.544722) (xy 284.725839 -416.56) (xy 300.861982 -416.56) (xy 300.866053 -416.504378)
			(xy 300.878179 -416.449941) (xy 300.898102 -416.39785) (xy 300.925398 -416.349215) (xy 300.959484 -416.305072)
			(xy 300.999633 -416.266363) (xy 301.044991 -416.233912) (xy 301.094591 -416.208411) (xy 301.147375 -416.190404)
			(xy 301.202218 -416.180274) (xy 301.257952 -416.178237) (xy 301.313389 -416.184337) (xy 301.367346 -416.198443)
			(xy 301.418675 -416.220255) (xy 301.466281 -416.249309) (xy 301.509149 -416.284984) (xy 301.546366 -416.326521)
			(xy 301.577139 -416.373034) (xy 301.600811 -416.423531) (xy 301.616879 -416.476938) (xy 301.624999 -416.532114)
			(xy 301.625508 -416.56) (xy 301.624999 -416.587886) (xy 301.616879 -416.643062) (xy 301.600811 -416.696469)
			(xy 301.577139 -416.746966) (xy 301.546366 -416.793479) (xy 301.509149 -416.835016) (xy 301.466281 -416.870691)
			(xy 301.418675 -416.899745) (xy 301.367346 -416.921557) (xy 301.313389 -416.935663) (xy 301.257952 -416.941763)
			(xy 301.202218 -416.939726) (xy 301.147375 -416.929596) (xy 301.094591 -416.911589) (xy 301.044991 -416.886088)
			(xy 300.999633 -416.853637) (xy 300.959484 -416.814928) (xy 300.925398 -416.770785) (xy 300.898102 -416.72215)
			(xy 300.878179 -416.670059) (xy 300.866053 -416.615622) (xy 300.861982 -416.56) (xy 284.725839 -416.56)
			(xy 284.710923 -416.589244) (xy 284.68152 -416.629659) (xy 284.66415 -416.64763) (xy 284.09138 -417.2204)
			(xy 293.832532 -417.2204) (xy 293.836603 -417.164778) (xy 293.848729 -417.110341) (xy 293.868652 -417.05825)
			(xy 293.895948 -417.009615) (xy 293.930034 -416.965472) (xy 293.970183 -416.926763) (xy 294.015541 -416.894312)
			(xy 294.065141 -416.868811) (xy 294.117925 -416.850804) (xy 294.172768 -416.840674) (xy 294.228502 -416.838637)
			(xy 294.283939 -416.844737) (xy 294.337896 -416.858843) (xy 294.389225 -416.880655) (xy 294.436831 -416.909709)
			(xy 294.479699 -416.945384) (xy 294.516916 -416.986921) (xy 294.547689 -417.033434) (xy 294.571361 -417.083931)
			(xy 294.587429 -417.137338) (xy 294.595549 -417.192514) (xy 294.596058 -417.2204) (xy 294.595549 -417.248286)
			(xy 294.587429 -417.303462) (xy 294.571361 -417.356869) (xy 294.547689 -417.407366) (xy 294.516916 -417.453879)
			(xy 294.479699 -417.495416) (xy 294.436831 -417.531091) (xy 294.389225 -417.560145) (xy 294.337896 -417.581957)
			(xy 294.283939 -417.596063) (xy 294.228502 -417.602163) (xy 294.172768 -417.600126) (xy 294.117925 -417.589996)
			(xy 294.065141 -417.571989) (xy 294.015541 -417.546488) (xy 293.970183 -417.514037) (xy 293.930034 -417.475328)
			(xy 293.895948 -417.431185) (xy 293.868652 -417.38255) (xy 293.848729 -417.330459) (xy 293.836603 -417.276022)
			(xy 293.832532 -417.2204) (xy 284.09138 -417.2204) (xy 281.008054 -420.303726) (xy 294.241205 -420.303726)
			(xy 294.241208 -420.249228) (xy 294.248967 -420.195285) (xy 294.264324 -420.142996) (xy 294.286966 -420.093424)
			(xy 294.316433 -420.047578) (xy 294.352124 -420.006393) (xy 294.393313 -419.970707) (xy 294.439161 -419.941246)
			(xy 294.488736 -419.918609) (xy 294.541027 -419.903258) (xy 294.594971 -419.895505) (xy 294.62222 -419.89502)
			(xy 294.651656 -419.895588) (xy 294.70983 -419.90464) (xy 294.738044 -419.913054) (xy 294.752364 -419.917131)
			(xy 294.78212 -419.917649) (xy 294.810762 -419.909563) (xy 294.835856 -419.893561) (xy 294.855268 -419.871002)
			(xy 294.867349 -419.843803) (xy 294.871073 -419.814275) (xy 294.869108 -419.799516) (xy 294.866618 -419.783823)
			(xy 294.863947 -419.752158) (xy 294.863774 -419.73627) (xy 294.86426 -419.709019) (xy 294.872016 -419.655071)
			(xy 294.887371 -419.602776) (xy 294.910013 -419.553199) (xy 294.939479 -419.507349) (xy 294.97517 -419.466158)
			(xy 295.016361 -419.430467) (xy 295.062211 -419.401001) (xy 295.111788 -419.378359) (xy 295.164083 -419.363004)
			(xy 295.218031 -419.355248) (xy 295.272533 -419.355248) (xy 295.326481 -419.363004) (xy 295.378776 -419.378359)
			(xy 295.428353 -419.401001) (xy 295.474203 -419.430467) (xy 295.515394 -419.466158) (xy 295.551085 -419.507349)
			(xy 295.580551 -419.553199) (xy 295.603193 -419.602776) (xy 295.618548 -419.655071) (xy 295.626304 -419.709019)
			(xy 295.62679 -419.73627) (xy 295.626653 -419.752026) (xy 295.624109 -419.783435) (xy 295.62171 -419.799008)
			(xy 295.619819 -419.813724) (xy 295.62353 -419.843142) (xy 295.635546 -419.87025) (xy 295.654851 -419.892757)
			(xy 295.679813 -419.90876) (xy 295.708323 -419.916908) (xy 295.737972 -419.916513) (xy 295.752266 -419.912546)
			(xy 295.780195 -419.904361) (xy 295.837721 -419.895552) (xy 295.86682 -419.89502) (xy 295.894069 -419.8955)
			(xy 295.948012 -419.903258) (xy 296.000302 -419.918614) (xy 296.049874 -419.941256) (xy 296.09572 -419.970721)
			(xy 296.136906 -420.006411) (xy 296.172593 -420.047599) (xy 296.202056 -420.093447) (xy 296.224694 -420.143021)
			(xy 296.240047 -420.195311) (xy 296.247802 -420.249255) (xy 296.247802 -420.303753) (xy 296.240045 -420.357696)
			(xy 296.224691 -420.409987) (xy 296.202052 -420.45956) (xy 296.172588 -420.505407) (xy 296.1369 -420.546594)
			(xy 296.095713 -420.582283) (xy 296.049867 -420.611748) (xy 296.000294 -420.634388) (xy 295.948004 -420.649744)
			(xy 295.894061 -420.657501) (xy 295.839563 -420.657503) (xy 295.785619 -420.649749) (xy 295.733328 -420.634397)
			(xy 295.683754 -420.61176) (xy 295.637906 -420.582298) (xy 295.596717 -420.546611) (xy 295.561026 -420.505426)
			(xy 295.53156 -420.459581) (xy 295.508917 -420.410009) (xy 295.49356 -420.35772) (xy 295.4858 -420.303777)
			(xy 295.485312 -420.276528) (xy 295.485448 -420.260772) (xy 295.487992 -420.229363) (xy 295.490392 -420.21379)
			(xy 295.492283 -420.199074) (xy 295.488571 -420.169656) (xy 295.476555 -420.142549) (xy 295.45725 -420.120043)
			(xy 295.432289 -420.104039) (xy 295.403779 -420.095891) (xy 295.37413 -420.096286) (xy 295.359836 -420.100252)
			(xy 295.331907 -420.108437) (xy 295.274381 -420.117246) (xy 295.245282 -420.117778) (xy 295.215846 -420.11721)
			(xy 295.157672 -420.108157) (xy 295.129458 -420.099744) (xy 295.115137 -420.095672) (xy 295.085381 -420.095153)
			(xy 295.05674 -420.103238) (xy 295.031647 -420.11924) (xy 295.012235 -420.141798) (xy 295.000154 -420.168996)
			(xy 294.996429 -420.198523) (xy 294.998394 -420.213282) (xy 295.000884 -420.228975) (xy 295.003555 -420.26064)
			(xy 295.003728 -420.276528) (xy 295.003192 -420.303777) (xy 294.995432 -420.35772) (xy 294.980074 -420.410009)
			(xy 294.957431 -420.459581) (xy 294.927964 -420.505426) (xy 294.892273 -420.54661) (xy 294.851083 -420.582296)
			(xy 294.805234 -420.611757) (xy 294.755659 -420.634393) (xy 294.703368 -420.649743) (xy 294.649424 -420.657496)
			(xy 294.594926 -420.657492) (xy 294.540983 -420.649733) (xy 294.488693 -420.634375) (xy 294.439121 -420.611733)
			(xy 294.393276 -420.582266) (xy 294.352092 -420.546574) (xy 294.316405 -420.505385) (xy 294.286944 -420.459537)
			(xy 294.264308 -420.409962) (xy 294.248957 -420.35767) (xy 294.241205 -420.303726) (xy 281.008054 -420.303726)
			(xy 280.52776 -420.78402) (xy 280.509741 -420.801319) (xy 280.469311 -420.830648) (xy 280.424793 -420.853295)
			(xy 280.377281 -420.868703) (xy 280.327944 -420.876493) (xy 280.30297 -420.876984) (xy 280.119836 -420.876984)
			(xy 277.71598 -423.28084) (xy 282.347922 -423.28084) (xy 282.351993 -423.225218) (xy 282.364119 -423.170781)
			(xy 282.384042 -423.11869) (xy 282.411338 -423.070055) (xy 282.445424 -423.025912) (xy 282.485573 -422.987203)
			(xy 282.530931 -422.954752) (xy 282.580531 -422.929251) (xy 282.633315 -422.911244) (xy 282.688158 -422.901114)
			(xy 282.743892 -422.899077) (xy 282.799329 -422.905177) (xy 282.853286 -422.919283) (xy 282.904615 -422.941095)
			(xy 282.952221 -422.970149) (xy 282.995089 -423.005824) (xy 283.032306 -423.047361) (xy 283.063079 -423.093874)
			(xy 283.086751 -423.144371) (xy 283.102819 -423.197778) (xy 283.110939 -423.252954) (xy 283.111448 -423.28084)
			(xy 283.110939 -423.308726) (xy 283.102819 -423.363902) (xy 283.086751 -423.417309) (xy 283.063079 -423.467806)
			(xy 283.032306 -423.514319) (xy 282.995089 -423.555856) (xy 282.952221 -423.591531) (xy 282.904615 -423.620585)
			(xy 282.853286 -423.642397) (xy 282.799329 -423.656503) (xy 282.743892 -423.662603) (xy 282.688158 -423.660566)
			(xy 282.633315 -423.650436) (xy 282.580531 -423.632429) (xy 282.530931 -423.606928) (xy 282.485573 -423.574477)
			(xy 282.445424 -423.535768) (xy 282.411338 -423.491625) (xy 282.384042 -423.44299) (xy 282.364119 -423.390899)
			(xy 282.351993 -423.336462) (xy 282.347922 -423.28084) (xy 277.71598 -423.28084) (xy 275.844672 -425.152148)
			(xy 276.956434 -425.152148) (xy 276.956435 -425.097638) (xy 276.964194 -425.043684) (xy 276.979553 -424.991382)
			(xy 277.002198 -424.941799) (xy 277.03167 -424.895943) (xy 277.067367 -424.854749) (xy 277.108565 -424.819054)
			(xy 277.154422 -424.789585) (xy 277.204007 -424.766943) (xy 277.25631 -424.751588) (xy 277.310265 -424.743834)
			(xy 277.33752 -424.743372) (xy 277.360289 -424.743721) (xy 277.405495 -424.749201) (xy 277.42769 -424.754294)
			(xy 277.441172 -424.757127) (xy 277.468696 -424.756194) (xy 277.494973 -424.747948) (xy 277.518097 -424.732989)
			(xy 277.536389 -424.7124) (xy 277.548522 -424.687677) (xy 277.553617 -424.660612) (xy 277.552912 -424.646852)
			(xy 277.551642 -424.61434) (xy 277.552112 -424.587083) (xy 277.559865 -424.533123) (xy 277.575219 -424.480815)
			(xy 277.597861 -424.431226) (xy 277.62733 -424.385363) (xy 277.663026 -424.344162) (xy 277.704223 -424.30846)
			(xy 277.750082 -424.278985) (xy 277.799668 -424.256336) (xy 277.851974 -424.240976) (xy 277.905933 -424.233216)
			(xy 277.960447 -424.233214) (xy 278.014407 -424.240971) (xy 278.066713 -424.256329) (xy 278.116301 -424.278975)
			(xy 278.162161 -424.308448) (xy 278.20336 -424.344147) (xy 278.239058 -424.385347) (xy 278.26853 -424.431208)
			(xy 278.291174 -424.480797) (xy 278.306531 -424.533103) (xy 278.314286 -424.587063) (xy 278.314284 -424.641577)
			(xy 278.306522 -424.695536) (xy 278.29116 -424.747841) (xy 278.268511 -424.797427) (xy 278.239034 -424.843285)
			(xy 278.203331 -424.884481) (xy 278.162129 -424.920176) (xy 278.116266 -424.949644) (xy 278.066675 -424.972285)
			(xy 278.014367 -424.987637) (xy 277.960407 -424.995389) (xy 277.93315 -424.995848) (xy 277.910382 -424.995486)
			(xy 277.865175 -424.990015) (xy 277.84298 -424.984926) (xy 277.829492 -424.982146) (xy 277.80198 -424.983087)
			(xy 277.775716 -424.991331) (xy 277.752601 -425.006283) (xy 277.734312 -425.026857) (xy 277.722173 -425.051564)
			(xy 277.717063 -425.078614) (xy 277.717758 -425.092368) (xy 277.719028 -425.12488) (xy 277.718566 -425.152135)
			(xy 277.710812 -425.20609) (xy 277.695457 -425.258393) (xy 277.672815 -425.307978) (xy 277.643346 -425.353835)
			(xy 277.607651 -425.395033) (xy 277.566457 -425.43073) (xy 277.520601 -425.460202) (xy 277.471018 -425.482847)
			(xy 277.418716 -425.498206) (xy 277.364762 -425.505965) (xy 277.310252 -425.505966) (xy 277.256297 -425.498209)
			(xy 277.203995 -425.482852) (xy 277.154411 -425.460208) (xy 277.108554 -425.430738) (xy 277.067358 -425.395042)
			(xy 277.031662 -425.353846) (xy 277.002192 -425.307989) (xy 276.979548 -425.258405) (xy 276.964191 -425.206103)
			(xy 276.956434 -425.152148) (xy 275.844672 -425.152148) (xy 275.64588 -425.35094) (xy 241.74196 -425.35094)
			(xy 241.09172 -426.00118) (xy 241.09172 -426.179742) (xy 304.698906 -426.179742) (xy 304.702977 -426.12412)
			(xy 304.715103 -426.069683) (xy 304.735026 -426.017592) (xy 304.762322 -425.968957) (xy 304.796408 -425.924814)
			(xy 304.836557 -425.886105) (xy 304.881915 -425.853654) (xy 304.931515 -425.828153) (xy 304.984299 -425.810146)
			(xy 305.039142 -425.800016) (xy 305.094876 -425.797979) (xy 305.150313 -425.804079) (xy 305.20427 -425.818185)
			(xy 305.255599 -425.839997) (xy 305.303205 -425.869051) (xy 305.346073 -425.904726) (xy 305.38329 -425.946263)
			(xy 305.414063 -425.992776) (xy 305.437735 -426.043273) (xy 305.453803 -426.09668) (xy 305.461923 -426.151856)
			(xy 305.462432 -426.179742) (xy 305.461923 -426.207628) (xy 305.453803 -426.262804) (xy 305.437735 -426.316211)
			(xy 305.414063 -426.366708) (xy 305.38329 -426.413221) (xy 305.346073 -426.454758) (xy 305.303205 -426.490433)
			(xy 305.255599 -426.519487) (xy 305.20427 -426.541299) (xy 305.150313 -426.555405) (xy 305.094876 -426.561505)
			(xy 305.039142 -426.559468) (xy 304.984299 -426.549338) (xy 304.931515 -426.531331) (xy 304.881915 -426.50583)
			(xy 304.836557 -426.473379) (xy 304.796408 -426.43467) (xy 304.762322 -426.390527) (xy 304.735026 -426.341892)
			(xy 304.715103 -426.289801) (xy 304.702977 -426.235364) (xy 304.698906 -426.179742) (xy 241.09172 -426.179742)
			(xy 241.09172 -426.7708) (xy 281.131262 -426.7708) (xy 281.135333 -426.715178) (xy 281.147459 -426.660741)
			(xy 281.167382 -426.60865) (xy 281.194678 -426.560015) (xy 281.228764 -426.515872) (xy 281.268913 -426.477163)
			(xy 281.314271 -426.444712) (xy 281.363871 -426.419211) (xy 281.416655 -426.401204) (xy 281.471498 -426.391074)
			(xy 281.527232 -426.389037) (xy 281.582669 -426.395137) (xy 281.636626 -426.409243) (xy 281.687955 -426.431055)
			(xy 281.735561 -426.460109) (xy 281.778429 -426.495784) (xy 281.815646 -426.537321) (xy 281.846419 -426.583834)
			(xy 281.870091 -426.634331) (xy 281.886159 -426.687738) (xy 281.894279 -426.742914) (xy 281.894788 -426.7708)
			(xy 281.894279 -426.798686) (xy 281.886159 -426.853862) (xy 281.870091 -426.907269) (xy 281.846419 -426.957766)
			(xy 281.818874 -426.9994) (xy 293.673782 -426.9994) (xy 293.677853 -426.943778) (xy 293.689979 -426.889341)
			(xy 293.709902 -426.83725) (xy 293.737198 -426.788615) (xy 293.771284 -426.744472) (xy 293.811433 -426.705763)
			(xy 293.856791 -426.673312) (xy 293.906391 -426.647811) (xy 293.959175 -426.629804) (xy 294.014018 -426.619674)
			(xy 294.069752 -426.617637) (xy 294.125189 -426.623737) (xy 294.179146 -426.637843) (xy 294.230475 -426.659655)
			(xy 294.278081 -426.688709) (xy 294.320949 -426.724384) (xy 294.358166 -426.765921) (xy 294.388939 -426.812434)
			(xy 294.412611 -426.862931) (xy 294.417294 -426.878496) (xy 294.531286 -426.878496) (xy 294.535357 -426.822874)
			(xy 294.547483 -426.768437) (xy 294.567406 -426.716346) (xy 294.594702 -426.667711) (xy 294.628788 -426.623568)
			(xy 294.668937 -426.584859) (xy 294.714295 -426.552408) (xy 294.763895 -426.526907) (xy 294.816679 -426.5089)
			(xy 294.871522 -426.49877) (xy 294.927256 -426.496733) (xy 294.982693 -426.502833) (xy 295.03665 -426.516939)
			(xy 295.087979 -426.538751) (xy 295.135585 -426.567805) (xy 295.178453 -426.60348) (xy 295.21567 -426.645017)
			(xy 295.246443 -426.69153) (xy 295.270115 -426.742027) (xy 295.286183 -426.795434) (xy 295.294303 -426.85061)
			(xy 295.294812 -426.878496) (xy 297.325286 -426.878496) (xy 297.329357 -426.822874) (xy 297.341483 -426.768437)
			(xy 297.361406 -426.716346) (xy 297.388702 -426.667711) (xy 297.422788 -426.623568) (xy 297.462937 -426.584859)
			(xy 297.508295 -426.552408) (xy 297.557895 -426.526907) (xy 297.610679 -426.5089) (xy 297.665522 -426.49877)
			(xy 297.721256 -426.496733) (xy 297.776693 -426.502833) (xy 297.83065 -426.516939) (xy 297.881979 -426.538751)
			(xy 297.929585 -426.567805) (xy 297.972453 -426.60348) (xy 298.00967 -426.645017) (xy 298.040443 -426.69153)
			(xy 298.064115 -426.742027) (xy 298.080183 -426.795434) (xy 298.088303 -426.85061) (xy 298.088812 -426.878496)
			(xy 300.119286 -426.878496) (xy 300.123357 -426.822874) (xy 300.135483 -426.768437) (xy 300.155406 -426.716346)
			(xy 300.182702 -426.667711) (xy 300.216788 -426.623568) (xy 300.256937 -426.584859) (xy 300.302295 -426.552408)
			(xy 300.351895 -426.526907) (xy 300.404679 -426.5089) (xy 300.459522 -426.49877) (xy 300.515256 -426.496733)
			(xy 300.570693 -426.502833) (xy 300.62465 -426.516939) (xy 300.675979 -426.538751) (xy 300.723585 -426.567805)
			(xy 300.766453 -426.60348) (xy 300.80367 -426.645017) (xy 300.834443 -426.69153) (xy 300.858115 -426.742027)
			(xy 300.874183 -426.795434) (xy 300.882303 -426.85061) (xy 300.882812 -426.878496) (xy 300.882303 -426.906382)
			(xy 300.874819 -426.957236) (xy 302.804066 -426.957236) (xy 302.808137 -426.901614) (xy 302.820263 -426.847177)
			(xy 302.840186 -426.795086) (xy 302.867482 -426.746451) (xy 302.901568 -426.702308) (xy 302.941717 -426.663599)
			(xy 302.987075 -426.631148) (xy 303.036675 -426.605647) (xy 303.089459 -426.58764) (xy 303.144302 -426.57751)
			(xy 303.200036 -426.575473) (xy 303.255473 -426.581573) (xy 303.30943 -426.595679) (xy 303.360759 -426.617491)
			(xy 303.408365 -426.646545) (xy 303.451233 -426.68222) (xy 303.48845 -426.723757) (xy 303.519223 -426.77027)
			(xy 303.542895 -426.820767) (xy 303.558963 -426.874174) (xy 303.567083 -426.92935) (xy 303.567592 -426.957236)
			(xy 303.567083 -426.985122) (xy 303.558963 -427.040298) (xy 303.542895 -427.093705) (xy 303.519223 -427.144202)
			(xy 303.48845 -427.190715) (xy 303.451233 -427.232252) (xy 303.408365 -427.267927) (xy 303.360759 -427.296981)
			(xy 303.30943 -427.318793) (xy 303.255473 -427.332899) (xy 303.200036 -427.338999) (xy 303.144302 -427.336962)
			(xy 303.089459 -427.326832) (xy 303.036675 -427.308825) (xy 302.987075 -427.283324) (xy 302.941717 -427.250873)
			(xy 302.901568 -427.212164) (xy 302.867482 -427.168021) (xy 302.840186 -427.119386) (xy 302.820263 -427.067295)
			(xy 302.808137 -427.012858) (xy 302.804066 -426.957236) (xy 300.874819 -426.957236) (xy 300.874183 -426.961558)
			(xy 300.858115 -427.014965) (xy 300.834443 -427.065462) (xy 300.80367 -427.111975) (xy 300.766453 -427.153512)
			(xy 300.723585 -427.189187) (xy 300.675979 -427.218241) (xy 300.62465 -427.240053) (xy 300.570693 -427.254159)
			(xy 300.515256 -427.260259) (xy 300.459522 -427.258222) (xy 300.404679 -427.248092) (xy 300.351895 -427.230085)
			(xy 300.302295 -427.204584) (xy 300.256937 -427.172133) (xy 300.216788 -427.133424) (xy 300.182702 -427.089281)
			(xy 300.155406 -427.040646) (xy 300.135483 -426.988555) (xy 300.123357 -426.934118) (xy 300.119286 -426.878496)
			(xy 298.088812 -426.878496) (xy 298.088303 -426.906382) (xy 298.080183 -426.961558) (xy 298.064115 -427.014965)
			(xy 298.040443 -427.065462) (xy 298.00967 -427.111975) (xy 297.972453 -427.153512) (xy 297.929585 -427.189187)
			(xy 297.881979 -427.218241) (xy 297.83065 -427.240053) (xy 297.776693 -427.254159) (xy 297.721256 -427.260259)
			(xy 297.665522 -427.258222) (xy 297.610679 -427.248092) (xy 297.557895 -427.230085) (xy 297.508295 -427.204584)
			(xy 297.462937 -427.172133) (xy 297.422788 -427.133424) (xy 297.388702 -427.089281) (xy 297.361406 -427.040646)
			(xy 297.341483 -426.988555) (xy 297.329357 -426.934118) (xy 297.325286 -426.878496) (xy 295.294812 -426.878496)
			(xy 295.294303 -426.906382) (xy 295.286183 -426.961558) (xy 295.270115 -427.014965) (xy 295.246443 -427.065462)
			(xy 295.21567 -427.111975) (xy 295.178453 -427.153512) (xy 295.135585 -427.189187) (xy 295.087979 -427.218241)
			(xy 295.03665 -427.240053) (xy 294.982693 -427.254159) (xy 294.927256 -427.260259) (xy 294.871522 -427.258222)
			(xy 294.816679 -427.248092) (xy 294.763895 -427.230085) (xy 294.714295 -427.204584) (xy 294.668937 -427.172133)
			(xy 294.628788 -427.133424) (xy 294.594702 -427.089281) (xy 294.567406 -427.040646) (xy 294.547483 -426.988555)
			(xy 294.535357 -426.934118) (xy 294.531286 -426.878496) (xy 294.417294 -426.878496) (xy 294.428679 -426.916338)
			(xy 294.436799 -426.971514) (xy 294.437308 -426.9994) (xy 294.436799 -427.027286) (xy 294.428679 -427.082462)
			(xy 294.412611 -427.135869) (xy 294.388939 -427.186366) (xy 294.358166 -427.232879) (xy 294.320949 -427.274416)
			(xy 294.278081 -427.310091) (xy 294.230475 -427.339145) (xy 294.179146 -427.360957) (xy 294.125189 -427.375063)
			(xy 294.069752 -427.381163) (xy 294.014018 -427.379126) (xy 293.959175 -427.368996) (xy 293.906391 -427.350989)
			(xy 293.856791 -427.325488) (xy 293.811433 -427.293037) (xy 293.771284 -427.254328) (xy 293.737198 -427.210185)
			(xy 293.709902 -427.16155) (xy 293.689979 -427.109459) (xy 293.677853 -427.055022) (xy 293.673782 -426.9994)
			(xy 281.818874 -426.9994) (xy 281.815646 -427.004279) (xy 281.778429 -427.045816) (xy 281.735561 -427.081491)
			(xy 281.687955 -427.110545) (xy 281.636626 -427.132357) (xy 281.582669 -427.146463) (xy 281.527232 -427.152563)
			(xy 281.471498 -427.150526) (xy 281.416655 -427.140396) (xy 281.363871 -427.122389) (xy 281.314271 -427.096888)
			(xy 281.268913 -427.064437) (xy 281.228764 -427.025728) (xy 281.194678 -426.981585) (xy 281.167382 -426.93295)
			(xy 281.147459 -426.880859) (xy 281.135333 -426.826422) (xy 281.131262 -426.7708) (xy 241.09172 -426.7708)
			(xy 241.09172 -433.04206) (xy 267.01141 -433.04206) (xy 267.01543 -432.866756) (xy 267.027484 -432.69182)
			(xy 267.047545 -432.517622) (xy 267.075571 -432.344526) (xy 267.111504 -432.172897) (xy 267.155267 -432.003095)
			(xy 267.20677 -431.835479) (xy 267.265903 -431.6704) (xy 267.332542 -431.508206) (xy 267.406547 -431.349238)
			(xy 267.487762 -431.19383) (xy 267.576017 -431.042308) (xy 267.671126 -430.894992) (xy 267.772888 -430.752191)
			(xy 267.881091 -430.614206) (xy 267.995506 -430.481327) (xy 268.115893 -430.353833) (xy 268.241998 -430.231992)
			(xy 268.373557 -430.116061) (xy 268.510292 -430.006284) (xy 268.651917 -429.902891) (xy 268.798133 -429.806099)
			(xy 268.948632 -429.716113) (xy 269.103099 -429.633121) (xy 269.261209 -429.557298) (xy 269.422628 -429.488804)
			(xy 269.587018 -429.427782) (xy 269.754033 -429.374362) (xy 269.923321 -429.328654) (xy 270.094527 -429.290756)
			(xy 270.26729 -429.260747) (xy 270.441247 -429.23869) (xy 270.616033 -429.224631) (xy 270.79128 -429.218601)
			(xy 270.966618 -429.220611) (xy 271.14168 -429.230658) (xy 271.316098 -429.248721) (xy 271.489504 -429.274761)
			(xy 271.661533 -429.308723) (xy 271.831825 -429.350537) (xy 272.000021 -429.400114) (xy 272.165767 -429.457351)
			(xy 272.328714 -429.522126) (xy 272.488521 -429.594303) (xy 272.64485 -429.673731) (xy 272.797374 -429.760243)
			(xy 272.94577 -429.853656) (xy 273.089728 -429.953775) (xy 273.228945 -430.060389) (xy 273.363127 -430.173273)
			(xy 273.491993 -430.29219) (xy 273.615272 -430.41689) (xy 273.732703 -430.547111) (xy 273.844042 -430.682578)
			(xy 273.949052 -430.823008) (xy 274.047513 -430.968105) (xy 274.139219 -431.117563) (xy 274.223977 -431.271068)
			(xy 274.301607 -431.428298) (xy 274.371948 -431.588921) (xy 274.43485 -431.752601) (xy 274.490182 -431.918992)
			(xy 274.537828 -432.087745) (xy 274.577686 -432.258505) (xy 274.609674 -432.430913) (xy 274.633724 -432.604606)
			(xy 274.649786 -432.779219) (xy 274.657825 -432.954385) (xy 274.658328 -433.04206) (xy 274.657825 -433.129735)
			(xy 274.649786 -433.304901) (xy 274.633724 -433.479514) (xy 274.609674 -433.653207) (xy 274.577686 -433.825615)
			(xy 274.537828 -433.996375) (xy 274.490182 -434.165128) (xy 274.43485 -434.331519) (xy 274.371948 -434.495199)
			(xy 274.301607 -434.655822) (xy 274.223977 -434.813052) (xy 274.139219 -434.966557) (xy 274.123129 -434.99278)
			(xy 278.489676 -434.99278) (xy 278.493642 -434.908249) (xy 278.505507 -434.824462) (xy 278.525165 -434.742153)
			(xy 278.552445 -434.662047) (xy 278.587106 -434.584848) (xy 278.628844 -434.511233) (xy 278.677291 -434.44185)
			(xy 278.732023 -434.377309) (xy 278.792559 -434.318177) (xy 278.858365 -434.264973) (xy 278.928865 -434.218165)
			(xy 279.003437 -434.178164) (xy 279.081428 -434.145322) (xy 279.162152 -434.119928) (xy 279.244899 -434.102205)
			(xy 279.328941 -434.092307) (xy 279.413542 -434.090324) (xy 279.497956 -434.096271) (xy 279.581443 -434.110096)
			(xy 279.663268 -434.131679) (xy 279.742712 -434.160829) (xy 279.819078 -434.19729) (xy 279.891694 -434.240742)
			(xy 279.959922 -434.290803) (xy 280.023162 -434.347033) (xy 280.080859 -434.408938) (xy 280.132506 -434.475974)
			(xy 280.177648 -434.547551) (xy 280.21589 -434.623041) (xy 280.246894 -434.70178) (xy 280.259789 -434.7464)
			(xy 282.099512 -434.7464) (xy 282.100064 -434.716636) (xy 282.109322 -434.657834) (xy 282.127599 -434.601182)
			(xy 282.154451 -434.548054) (xy 282.189226 -434.499741) (xy 282.209748 -434.478176) (xy 282.220182 -434.466921)
			(xy 282.234296 -434.439682) (xy 282.239712 -434.409485) (xy 282.235945 -434.379038) (xy 282.223332 -434.351072)
			(xy 282.213558 -434.339238) (xy 282.195524 -434.318194) (xy 282.165095 -434.271876) (xy 282.141694 -434.22164)
			(xy 282.125814 -434.168545) (xy 282.117789 -434.11371) (xy 282.117292 -434.086) (xy 282.117782 -434.058727)
			(xy 282.125557 -434.004736) (xy 282.140935 -433.952402) (xy 282.163602 -433.902787) (xy 282.193098 -433.856903)
			(xy 282.228823 -433.815682) (xy 282.249118 -433.797456) (xy 282.259544 -433.787753) (xy 282.275115 -433.763926)
			(xy 282.283494 -433.736722) (xy 282.284027 -433.708263) (xy 282.276674 -433.680765) (xy 282.262007 -433.65637)
			(xy 282.251912 -433.646326) (xy 282.233129 -433.628194) (xy 282.200149 -433.587724) (xy 282.172992 -433.543137)
			(xy 282.152166 -433.495265) (xy 282.138058 -433.445001) (xy 282.130932 -433.393283) (xy 282.1305 -433.36718)
			(xy 282.130986 -433.339929) (xy 282.138742 -433.285981) (xy 282.154097 -433.233686) (xy 282.176739 -433.184109)
			(xy 282.206205 -433.138259) (xy 282.241896 -433.097068) (xy 282.283087 -433.061377) (xy 282.328937 -433.031911)
			(xy 282.378514 -433.009269) (xy 282.430809 -432.993914) (xy 282.484757 -432.986158) (xy 282.539259 -432.986158)
			(xy 282.593207 -432.993914) (xy 282.645502 -433.009269) (xy 282.695079 -433.031911) (xy 282.740929 -433.061377)
			(xy 282.78212 -433.097068) (xy 282.817811 -433.138259) (xy 282.847277 -433.184109) (xy 282.869919 -433.233686)
			(xy 282.885274 -433.285981) (xy 282.89303 -433.339929) (xy 282.893516 -433.36718) (xy 282.893044 -433.394454)
			(xy 282.885269 -433.448447) (xy 282.86989 -433.500783) (xy 282.847219 -433.550398) (xy 282.817718 -433.596281)
			(xy 282.781988 -433.637499) (xy 282.76169 -433.655724) (xy 282.751184 -433.665347) (xy 282.735615 -433.689197)
			(xy 282.727245 -433.716421) (xy 282.726726 -433.744898) (xy 282.734099 -433.772409) (xy 282.748789 -433.79681)
			(xy 282.758896 -433.806854) (xy 282.77772 -433.824946) (xy 282.810695 -433.865425) (xy 282.837846 -433.91002)
			(xy 282.858666 -433.9579) (xy 282.872765 -434.008171) (xy 282.879881 -434.059895) (xy 282.880308 -434.086)
			(xy 282.87975 -434.115763) (xy 282.870492 -434.174566) (xy 282.852217 -434.231217) (xy 282.825366 -434.284345)
			(xy 282.790593 -434.332658) (xy 282.770072 -434.354224) (xy 282.759637 -434.365478) (xy 282.74552 -434.392717)
			(xy 282.740103 -434.422915) (xy 282.743871 -434.453363) (xy 282.756486 -434.481329) (xy 282.766262 -434.493162)
			(xy 282.784283 -434.514217) (xy 282.814716 -434.560531) (xy 282.838121 -434.610764) (xy 282.854004 -434.663857)
			(xy 282.86203 -434.718691) (xy 282.862528 -434.7464) (xy 282.862042 -434.773651) (xy 282.854286 -434.827599)
			(xy 282.838931 -434.879894) (xy 282.816289 -434.929471) (xy 282.786823 -434.975321) (xy 282.751132 -435.016512)
			(xy 282.709941 -435.052203) (xy 282.664091 -435.081669) (xy 282.614514 -435.104311) (xy 282.562219 -435.119666)
			(xy 282.508271 -435.127422) (xy 282.453769 -435.127422) (xy 282.399821 -435.119666) (xy 282.347526 -435.104311)
			(xy 282.297949 -435.081669) (xy 282.252099 -435.052203) (xy 282.210908 -435.016512) (xy 282.175217 -434.975321)
			(xy 282.145751 -434.929471) (xy 282.123109 -434.879894) (xy 282.107754 -434.827599) (xy 282.099998 -434.773651)
			(xy 282.099512 -434.7464) (xy 280.259789 -434.7464) (xy 280.270389 -434.783077) (xy 280.286168 -434.866216)
			(xy 280.294092 -434.950468) (xy 280.294588 -434.99278) (xy 280.294092 -435.035092) (xy 280.286168 -435.119344)
			(xy 280.270389 -435.202483) (xy 280.246894 -435.28378) (xy 280.21589 -435.362519) (xy 280.177648 -435.438009)
			(xy 280.132506 -435.509586) (xy 280.080859 -435.576622) (xy 280.023162 -435.638527) (xy 279.959922 -435.694757)
			(xy 279.891694 -435.744818) (xy 279.819078 -435.78827) (xy 279.806231 -435.794404) (xy 282.612082 -435.794404)
			(xy 282.616153 -435.738782) (xy 282.628279 -435.684345) (xy 282.648202 -435.632254) (xy 282.675498 -435.583619)
			(xy 282.709584 -435.539476) (xy 282.749733 -435.500767) (xy 282.795091 -435.468316) (xy 282.844691 -435.442815)
			(xy 282.897475 -435.424808) (xy 282.952318 -435.414678) (xy 283.008052 -435.412641) (xy 283.063489 -435.418741)
			(xy 283.117446 -435.432847) (xy 283.168775 -435.454659) (xy 283.216381 -435.483713) (xy 283.259249 -435.519388)
			(xy 283.296466 -435.560925) (xy 283.327239 -435.607438) (xy 283.350911 -435.657935) (xy 283.366979 -435.711342)
			(xy 283.375099 -435.766518) (xy 283.375608 -435.794404) (xy 283.375099 -435.82229) (xy 283.366979 -435.877466)
			(xy 283.350911 -435.930873) (xy 283.327239 -435.98137) (xy 283.296466 -436.027883) (xy 283.259249 -436.06942)
			(xy 283.216381 -436.105095) (xy 283.168775 -436.134149) (xy 283.117446 -436.155961) (xy 283.063489 -436.170067)
			(xy 283.008052 -436.176167) (xy 282.952318 -436.17413) (xy 282.897475 -436.164) (xy 282.844691 -436.145993)
			(xy 282.795091 -436.120492) (xy 282.749733 -436.088041) (xy 282.709584 -436.049332) (xy 282.675498 -436.005189)
			(xy 282.648202 -435.956554) (xy 282.628279 -435.904463) (xy 282.616153 -435.850026) (xy 282.612082 -435.794404)
			(xy 279.806231 -435.794404) (xy 279.742712 -435.824731) (xy 279.663268 -435.853881) (xy 279.581443 -435.875464)
			(xy 279.497956 -435.889289) (xy 279.413542 -435.895236) (xy 279.328941 -435.893253) (xy 279.244899 -435.883355)
			(xy 279.162152 -435.865632) (xy 279.081428 -435.840238) (xy 279.003437 -435.807396) (xy 278.928865 -435.767395)
			(xy 278.858365 -435.720587) (xy 278.792559 -435.667383) (xy 278.732023 -435.608251) (xy 278.677291 -435.54371)
			(xy 278.628844 -435.474327) (xy 278.587106 -435.400712) (xy 278.552445 -435.323513) (xy 278.525165 -435.243407)
			(xy 278.505507 -435.161098) (xy 278.493642 -435.077311) (xy 278.489676 -434.99278) (xy 274.123129 -434.99278)
			(xy 274.047513 -435.116015) (xy 273.949052 -435.261112) (xy 273.844042 -435.401542) (xy 273.732703 -435.537009)
			(xy 273.615272 -435.66723) (xy 273.491993 -435.79193) (xy 273.363127 -435.910847) (xy 273.228945 -436.023731)
			(xy 273.089728 -436.130345) (xy 272.94577 -436.230464) (xy 272.797374 -436.323877) (xy 272.64485 -436.410389)
			(xy 272.488521 -436.489817) (xy 272.328714 -436.561994) (xy 272.165767 -436.626769) (xy 272.000021 -436.684006)
			(xy 271.831825 -436.733583) (xy 271.661533 -436.775397) (xy 271.489504 -436.809359) (xy 271.316098 -436.835399)
			(xy 271.14168 -436.853462) (xy 270.966618 -436.863509) (xy 270.79128 -436.865519) (xy 270.616033 -436.859489)
			(xy 270.441247 -436.84543) (xy 270.26729 -436.823373) (xy 270.094527 -436.793364) (xy 269.923321 -436.755466)
			(xy 269.754033 -436.709758) (xy 269.587018 -436.656338) (xy 269.422628 -436.595316) (xy 269.261209 -436.526822)
			(xy 269.103099 -436.450999) (xy 268.948632 -436.368007) (xy 268.798133 -436.278021) (xy 268.651917 -436.181229)
			(xy 268.510292 -436.077836) (xy 268.373557 -435.968059) (xy 268.241998 -435.852128) (xy 268.115893 -435.730287)
			(xy 267.995506 -435.602793) (xy 267.881091 -435.469914) (xy 267.772888 -435.331929) (xy 267.671126 -435.189128)
			(xy 267.576017 -435.041812) (xy 267.487762 -434.89029) (xy 267.406547 -434.734882) (xy 267.332542 -434.575914)
			(xy 267.265903 -434.41372) (xy 267.20677 -434.248641) (xy 267.155267 -434.081025) (xy 267.111504 -433.911223)
			(xy 267.075571 -433.739594) (xy 267.047545 -433.566498) (xy 267.027484 -433.3923) (xy 267.01543 -433.217364)
			(xy 267.01141 -433.04206) (xy 241.09172 -433.04206) (xy 241.09172 -437.32704) (xy 241.29746 -437.53278)
			(xy 278.489676 -437.53278) (xy 278.493642 -437.448249) (xy 278.505507 -437.364462) (xy 278.525165 -437.282153)
			(xy 278.552445 -437.202047) (xy 278.587106 -437.124848) (xy 278.628844 -437.051233) (xy 278.677291 -436.98185)
			(xy 278.732023 -436.917309) (xy 278.792559 -436.858177) (xy 278.858365 -436.804973) (xy 278.928865 -436.758165)
			(xy 279.003437 -436.718164) (xy 279.081428 -436.685322) (xy 279.162152 -436.659928) (xy 279.244899 -436.642205)
			(xy 279.328941 -436.632307) (xy 279.413542 -436.630324) (xy 279.497956 -436.636271) (xy 279.581443 -436.650096)
			(xy 279.663268 -436.671679) (xy 279.66961 -436.674006) (xy 281.726384 -436.674006) (xy 281.730455 -436.618384)
			(xy 281.742581 -436.563947) (xy 281.762504 -436.511856) (xy 281.7898 -436.463221) (xy 281.823886 -436.419078)
			(xy 281.864035 -436.380369) (xy 281.909393 -436.347918) (xy 281.958993 -436.322417) (xy 282.011777 -436.30441)
			(xy 282.06662 -436.29428) (xy 282.122354 -436.292243) (xy 282.177791 -436.298343) (xy 282.231748 -436.312449)
			(xy 282.283077 -436.334261) (xy 282.330683 -436.363315) (xy 282.373551 -436.39899) (xy 282.410768 -436.440527)
			(xy 282.441541 -436.48704) (xy 282.465213 -436.537537) (xy 282.481281 -436.590944) (xy 282.489401 -436.64612)
			(xy 282.48991 -436.674006) (xy 282.489401 -436.701892) (xy 282.481281 -436.757068) (xy 282.465213 -436.810475)
			(xy 282.441541 -436.860972) (xy 282.410768 -436.907485) (xy 282.373551 -436.949022) (xy 282.330683 -436.984697)
			(xy 282.283077 -437.013751) (xy 282.231748 -437.035563) (xy 282.177791 -437.049669) (xy 282.122354 -437.055769)
			(xy 282.06662 -437.053732) (xy 282.011777 -437.043602) (xy 281.958993 -437.025595) (xy 281.909393 -437.000094)
			(xy 281.864035 -436.967643) (xy 281.823886 -436.928934) (xy 281.7898 -436.884791) (xy 281.762504 -436.836156)
			(xy 281.742581 -436.784065) (xy 281.730455 -436.729628) (xy 281.726384 -436.674006) (xy 279.66961 -436.674006)
			(xy 279.742712 -436.700829) (xy 279.819078 -436.73729) (xy 279.891694 -436.780742) (xy 279.959922 -436.830803)
			(xy 280.023162 -436.887033) (xy 280.080859 -436.948938) (xy 280.132506 -437.015974) (xy 280.177648 -437.087551)
			(xy 280.21589 -437.163041) (xy 280.246894 -437.24178) (xy 280.270389 -437.323077) (xy 280.286168 -437.406216)
			(xy 280.294092 -437.490468) (xy 280.294588 -437.53278) (xy 280.294201 -437.5658) (xy 282.650182 -437.5658)
			(xy 282.654253 -437.510178) (xy 282.666379 -437.455741) (xy 282.686302 -437.40365) (xy 282.713598 -437.355015)
			(xy 282.747684 -437.310872) (xy 282.787833 -437.272163) (xy 282.833191 -437.239712) (xy 282.882791 -437.214211)
			(xy 282.935575 -437.196204) (xy 282.990418 -437.186074) (xy 283.046152 -437.184037) (xy 283.101589 -437.190137)
			(xy 283.155546 -437.204243) (xy 283.206875 -437.226055) (xy 283.254481 -437.255109) (xy 283.297349 -437.290784)
			(xy 283.334566 -437.332321) (xy 283.365339 -437.378834) (xy 283.389011 -437.429331) (xy 283.405079 -437.482738)
			(xy 283.413199 -437.537914) (xy 283.413708 -437.5658) (xy 283.413199 -437.593686) (xy 283.405079 -437.648862)
			(xy 283.389011 -437.702269) (xy 283.365339 -437.752766) (xy 283.334566 -437.799279) (xy 283.297349 -437.840816)
			(xy 283.254481 -437.876491) (xy 283.206875 -437.905545) (xy 283.155546 -437.927357) (xy 283.101589 -437.941463)
			(xy 283.046152 -437.947563) (xy 282.990418 -437.945526) (xy 282.935575 -437.935396) (xy 282.882791 -437.917389)
			(xy 282.833191 -437.891888) (xy 282.787833 -437.859437) (xy 282.747684 -437.820728) (xy 282.713598 -437.776585)
			(xy 282.686302 -437.72795) (xy 282.666379 -437.675859) (xy 282.654253 -437.621422) (xy 282.650182 -437.5658)
			(xy 280.294201 -437.5658) (xy 280.294092 -437.575092) (xy 280.286168 -437.659344) (xy 280.270389 -437.742483)
			(xy 280.246894 -437.82378) (xy 280.21589 -437.902519) (xy 280.177648 -437.978009) (xy 280.132506 -438.049586)
			(xy 280.080859 -438.116622) (xy 280.023162 -438.178527) (xy 279.959922 -438.234757) (xy 279.891694 -438.284818)
			(xy 279.819078 -438.32827) (xy 279.742712 -438.364731) (xy 279.663268 -438.393881) (xy 279.581443 -438.415464)
			(xy 279.497956 -438.429289) (xy 279.413542 -438.435236) (xy 279.328941 -438.433253) (xy 279.244899 -438.423355)
			(xy 279.162152 -438.405632) (xy 279.081428 -438.380238) (xy 279.003437 -438.347396) (xy 278.928865 -438.307395)
			(xy 278.858365 -438.260587) (xy 278.792559 -438.207383) (xy 278.732023 -438.148251) (xy 278.677291 -438.08371)
			(xy 278.628844 -438.014327) (xy 278.587106 -437.940712) (xy 278.552445 -437.863513) (xy 278.525165 -437.783407)
			(xy 278.505507 -437.701098) (xy 278.493642 -437.617311) (xy 278.489676 -437.53278) (xy 241.29746 -437.53278)
			(xy 242.85194 -439.08726) (xy 276.94636 -439.08726) (xy 277.3553 -439.4962) (xy 283.895292 -439.4962)
			(xy 283.895717 -439.470224) (xy 283.90276 -439.418751) (xy 283.916731 -439.368713) (xy 283.937369 -439.321036)
			(xy 283.964293 -439.276604) (xy 283.997002 -439.236242) (xy 284.034891 -439.200697) (xy 284.05582 -439.185304)
			(xy 284.066833 -439.176895) (xy 284.084255 -439.155363) (xy 284.095248 -439.129941) (xy 284.099005 -439.1025)
			(xy 284.095248 -439.075059) (xy 284.084255 -439.049637) (xy 284.066833 -439.028105) (xy 284.05582 -439.019696)
			(xy 284.034878 -439.004323) (xy 283.997003 -438.968765) (xy 283.964305 -438.928395) (xy 283.93739 -438.88396)
			(xy 283.916755 -438.836282) (xy 283.902783 -438.786246) (xy 283.895731 -438.734775) (xy 283.895292 -438.7088)
			(xy 283.895749 -438.681934) (xy 283.903276 -438.628732) (xy 283.918196 -438.577113) (xy 283.940213 -438.528099)
			(xy 283.968892 -438.48266) (xy 284.003663 -438.441696) (xy 284.04384 -438.406018) (xy 284.06598 -438.390792)
			(xy 284.077295 -438.382758) (xy 284.095473 -438.361805) (xy 284.107329 -438.336728) (xy 284.111986 -438.309383)
			(xy 284.109099 -438.281795) (xy 284.098882 -438.256006) (xy 284.082091 -438.233927) (xy 284.071314 -438.225184)
			(xy 284.048329 -438.207012) (xy 284.007658 -438.164837) (xy 283.973912 -438.116941) (xy 283.947882 -438.06445)
			(xy 283.930182 -438.008597) (xy 283.921226 -437.950695) (xy 283.920692 -437.9214) (xy 283.921178 -437.894149)
			(xy 283.928934 -437.840201) (xy 283.944289 -437.787906) (xy 283.966931 -437.738329) (xy 283.996397 -437.692479)
			(xy 284.032088 -437.651288) (xy 284.073279 -437.615597) (xy 284.119129 -437.586131) (xy 284.168706 -437.563489)
			(xy 284.221001 -437.548134) (xy 284.274949 -437.540378) (xy 284.329451 -437.540378) (xy 284.383399 -437.548134)
			(xy 284.435694 -437.563489) (xy 284.485271 -437.586131) (xy 284.531121 -437.615597) (xy 284.572312 -437.651288)
			(xy 284.608003 -437.692479) (xy 284.637469 -437.738329) (xy 284.660111 -437.787906) (xy 284.675466 -437.840201)
			(xy 284.683222 -437.894149) (xy 284.683708 -437.9214) (xy 284.683251 -437.948266) (xy 284.675724 -438.001468)
			(xy 284.660804 -438.053087) (xy 284.638787 -438.102101) (xy 284.610108 -438.14754) (xy 284.575337 -438.188504)
			(xy 284.53516 -438.224182) (xy 284.51302 -438.239408) (xy 284.501705 -438.247442) (xy 284.483527 -438.268395)
			(xy 284.471671 -438.293472) (xy 284.467014 -438.320817) (xy 284.469901 -438.348405) (xy 284.480118 -438.374194)
			(xy 284.496909 -438.396273) (xy 284.507686 -438.405016) (xy 284.530671 -438.423188) (xy 284.571342 -438.465363)
			(xy 284.602197 -438.509156) (xy 302.684178 -438.509156) (xy 302.688249 -438.453534) (xy 302.700375 -438.399097)
			(xy 302.720298 -438.347006) (xy 302.747594 -438.298371) (xy 302.78168 -438.254228) (xy 302.821829 -438.215519)
			(xy 302.867187 -438.183068) (xy 302.916787 -438.157567) (xy 302.969571 -438.13956) (xy 303.024414 -438.12943)
			(xy 303.080148 -438.127393) (xy 303.135585 -438.133493) (xy 303.189542 -438.147599) (xy 303.240871 -438.169411)
			(xy 303.288477 -438.198465) (xy 303.331345 -438.23414) (xy 303.368562 -438.275677) (xy 303.399335 -438.32219)
			(xy 303.423007 -438.372687) (xy 303.439075 -438.426094) (xy 303.447195 -438.48127) (xy 303.447704 -438.509156)
			(xy 303.447495 -438.520586) (xy 305.418488 -438.520586) (xy 305.422559 -438.464964) (xy 305.434685 -438.410527)
			(xy 305.454608 -438.358436) (xy 305.481904 -438.309801) (xy 305.51599 -438.265658) (xy 305.556139 -438.226949)
			(xy 305.601497 -438.194498) (xy 305.651097 -438.168997) (xy 305.703881 -438.15099) (xy 305.758724 -438.14086)
			(xy 305.814458 -438.138823) (xy 305.869895 -438.144923) (xy 305.923852 -438.159029) (xy 305.975181 -438.180841)
			(xy 306.022787 -438.209895) (xy 306.065655 -438.24557) (xy 306.102872 -438.287107) (xy 306.133645 -438.33362)
			(xy 306.157317 -438.384117) (xy 306.173385 -438.437524) (xy 306.181505 -438.4927) (xy 306.182014 -438.520586)
			(xy 306.181505 -438.548472) (xy 306.175703 -438.587896) (xy 308.185818 -438.587896) (xy 308.189889 -438.532274)
			(xy 308.202015 -438.477837) (xy 308.221938 -438.425746) (xy 308.249234 -438.377111) (xy 308.28332 -438.332968)
			(xy 308.323469 -438.294259) (xy 308.368827 -438.261808) (xy 308.418427 -438.236307) (xy 308.471211 -438.2183)
			(xy 308.526054 -438.20817) (xy 308.581788 -438.206133) (xy 308.637225 -438.212233) (xy 308.691182 -438.226339)
			(xy 308.742511 -438.248151) (xy 308.790117 -438.277205) (xy 308.832985 -438.31288) (xy 308.870202 -438.354417)
			(xy 308.900975 -438.40093) (xy 308.924647 -438.451427) (xy 308.940715 -438.504834) (xy 308.948835 -438.56001)
			(xy 308.949344 -438.587896) (xy 308.948835 -438.615782) (xy 308.940715 -438.670958) (xy 308.924647 -438.724365)
			(xy 308.900975 -438.774862) (xy 308.870202 -438.821375) (xy 308.832985 -438.862912) (xy 308.790117 -438.898587)
			(xy 308.742511 -438.927641) (xy 308.691182 -438.949453) (xy 308.637225 -438.963559) (xy 308.581788 -438.969659)
			(xy 308.526054 -438.967622) (xy 308.471211 -438.957492) (xy 308.418427 -438.939485) (xy 308.368827 -438.913984)
			(xy 308.323469 -438.881533) (xy 308.28332 -438.842824) (xy 308.249234 -438.798681) (xy 308.221938 -438.750046)
			(xy 308.202015 -438.697955) (xy 308.189889 -438.643518) (xy 308.185818 -438.587896) (xy 306.175703 -438.587896)
			(xy 306.173385 -438.603648) (xy 306.157317 -438.657055) (xy 306.133645 -438.707552) (xy 306.102872 -438.754065)
			(xy 306.065655 -438.795602) (xy 306.022787 -438.831277) (xy 305.975181 -438.860331) (xy 305.923852 -438.882143)
			(xy 305.869895 -438.896249) (xy 305.814458 -438.902349) (xy 305.758724 -438.900312) (xy 305.703881 -438.890182)
			(xy 305.651097 -438.872175) (xy 305.601497 -438.846674) (xy 305.556139 -438.814223) (xy 305.51599 -438.775514)
			(xy 305.481904 -438.731371) (xy 305.454608 -438.682736) (xy 305.434685 -438.630645) (xy 305.422559 -438.576208)
			(xy 305.418488 -438.520586) (xy 303.447495 -438.520586) (xy 303.447195 -438.537042) (xy 303.439075 -438.592218)
			(xy 303.423007 -438.645625) (xy 303.399335 -438.696122) (xy 303.368562 -438.742635) (xy 303.331345 -438.784172)
			(xy 303.288477 -438.819847) (xy 303.240871 -438.848901) (xy 303.189542 -438.870713) (xy 303.135585 -438.884819)
			(xy 303.080148 -438.890919) (xy 303.024414 -438.888882) (xy 302.969571 -438.878752) (xy 302.916787 -438.860745)
			(xy 302.867187 -438.835244) (xy 302.821829 -438.802793) (xy 302.78168 -438.764084) (xy 302.747594 -438.719941)
			(xy 302.720298 -438.671306) (xy 302.700375 -438.619215) (xy 302.688249 -438.564778) (xy 302.684178 -438.509156)
			(xy 284.602197 -438.509156) (xy 284.605088 -438.513259) (xy 284.631118 -438.56575) (xy 284.648818 -438.621603)
			(xy 284.657774 -438.679505) (xy 284.658308 -438.7088) (xy 284.657883 -438.734776) (xy 284.65084 -438.786249)
			(xy 284.636869 -438.836287) (xy 284.616231 -438.883964) (xy 284.589307 -438.928396) (xy 284.556598 -438.968758)
			(xy 284.518709 -439.004303) (xy 284.49778 -439.019696) (xy 284.486767 -439.028105) (xy 284.469345 -439.049637)
			(xy 284.458352 -439.075059) (xy 284.454595 -439.1025) (xy 284.458352 -439.129941) (xy 284.469345 -439.155363)
			(xy 284.486767 -439.176895) (xy 284.49778 -439.185304) (xy 284.518722 -439.200677) (xy 284.556597 -439.236235)
			(xy 284.589295 -439.276605) (xy 284.61621 -439.32104) (xy 284.636845 -439.368718) (xy 284.650817 -439.418754)
			(xy 284.657869 -439.470225) (xy 284.658308 -439.4962) (xy 284.657822 -439.523451) (xy 284.650066 -439.577399)
			(xy 284.634711 -439.629694) (xy 284.612069 -439.679271) (xy 284.582603 -439.725121) (xy 284.546912 -439.766312)
			(xy 284.505721 -439.802003) (xy 284.459871 -439.831469) (xy 284.410294 -439.854111) (xy 284.357999 -439.869466)
			(xy 284.304051 -439.877222) (xy 284.249549 -439.877222) (xy 284.195601 -439.869466) (xy 284.143306 -439.854111)
			(xy 284.093729 -439.831469) (xy 284.047879 -439.802003) (xy 284.006688 -439.766312) (xy 283.970997 -439.725121)
			(xy 283.941531 -439.679271) (xy 283.918889 -439.629694) (xy 283.903534 -439.577399) (xy 283.895778 -439.523451)
			(xy 283.895292 -439.4962) (xy 277.3553 -439.4962) (xy 278.45512 -440.59602) (xy 309.23738 -440.59602)
		)
		(stroke
			(width 0)
			(type solid)
		)
		(fill yes)
		(layer "In2.Cu")
		(net "GND")
	)
	(gr_poly
		(pts
			(xy 84.76488 -332.196948) (xy 84.76488 -330.921106) (xy 86.41588 -329.270106) (xy 91.882722 -329.270106)
			(xy 95.169482 -325.983346) (xy 123.636278 -325.983346) (xy 127.30988 -329.656948) (xy 132.00888 -329.656948)
			(xy 133.633718 -331.281786) (xy 143.211042 -331.281786) (xy 143.69288 -330.799948) (xy 143.69288 -329.538584)
			(xy 142.33779 -327.958958) (xy 136.39038 -322.011548) (xy 118.85422 -301.155862) (xy 117.40388 -297.69181)
			(xy 117.40388 -297.582082) (xy 117.358414 -297.577256) (xy 117.329343 -297.573704) (xy 117.272701 -297.558826)
			(xy 117.219001 -297.535458) (xy 117.169508 -297.504149) (xy 117.147086 -297.485308) (xy 117.135758 -297.476072)
			(xy 117.109201 -297.463896) (xy 117.080284 -297.459723) (xy 117.051367 -297.463896) (xy 117.02481 -297.476072)
			(xy 117.013482 -297.485308) (xy 116.992549 -297.502949) (xy 116.946581 -297.532673) (xy 116.896835 -297.555519)
			(xy 116.844333 -297.571015) (xy 116.790155 -297.578844) (xy 116.735413 -297.578844) (xy 116.681235 -297.571015)
			(xy 116.628733 -297.555519) (xy 116.578987 -297.532673) (xy 116.533019 -297.502949) (xy 116.512086 -297.485308)
			(xy 116.500758 -297.476072) (xy 116.474201 -297.463896) (xy 116.445284 -297.459723) (xy 116.416367 -297.463896)
			(xy 116.38981 -297.476072) (xy 116.378482 -297.485308) (xy 116.35755 -297.502949) (xy 116.311583 -297.532672)
			(xy 116.261836 -297.555512) (xy 116.209333 -297.571) (xy 116.155154 -297.578815) (xy 116.127784 -297.579288)
			(xy 116.100535 -297.578801) (xy 116.046592 -297.571043) (xy 115.994302 -297.555687) (xy 115.944729 -297.533046)
			(xy 115.898883 -297.503581) (xy 115.857697 -297.467891) (xy 115.822009 -297.426704) (xy 115.792546 -297.380857)
			(xy 115.769907 -297.331283) (xy 115.754554 -297.278992) (xy 115.746798 -297.225049) (xy 115.746798 -297.170551)
			(xy 115.754554 -297.116608) (xy 115.769907 -297.064317) (xy 115.792546 -297.014743) (xy 115.822009 -296.968896)
			(xy 115.857697 -296.927709) (xy 115.898883 -296.892019) (xy 115.944729 -296.862554) (xy 115.994302 -296.839913)
			(xy 116.046592 -296.824557) (xy 116.100535 -296.816799) (xy 116.127784 -296.816272) (xy 116.155151 -296.81675)
			(xy 116.209323 -296.824586) (xy 116.261818 -296.840084) (xy 116.311559 -296.862927) (xy 116.357523 -296.892646)
			(xy 116.378482 -296.910252) (xy 116.38981 -296.919488) (xy 116.416367 -296.931664) (xy 116.445284 -296.935837)
			(xy 116.474201 -296.931664) (xy 116.500758 -296.919488) (xy 116.512086 -296.910252) (xy 116.533019 -296.892611)
			(xy 116.578987 -296.862887) (xy 116.628733 -296.840041) (xy 116.681235 -296.824545) (xy 116.735413 -296.816716)
			(xy 116.790155 -296.816716) (xy 116.844333 -296.824545) (xy 116.896835 -296.840041) (xy 116.946581 -296.862887)
			(xy 116.992549 -296.892611) (xy 117.013482 -296.910252) (xy 117.02481 -296.919488) (xy 117.051367 -296.931664)
			(xy 117.080284 -296.935837) (xy 117.109201 -296.931664) (xy 117.135758 -296.919488) (xy 117.147086 -296.910252)
			(xy 117.169527 -296.89144) (xy 117.219028 -296.860161) (xy 117.272723 -296.836804) (xy 117.329354 -296.821917)
			(xy 117.358414 -296.818304) (xy 117.40388 -296.813478) (xy 117.40388 -295.423082) (xy 117.358414 -295.418256)
			(xy 117.329343 -295.414704) (xy 117.272701 -295.399826) (xy 117.219001 -295.376458) (xy 117.169508 -295.345149)
			(xy 117.147086 -295.326308) (xy 117.135758 -295.317072) (xy 117.109201 -295.304896) (xy 117.080284 -295.300723)
			(xy 117.051367 -295.304896) (xy 117.02481 -295.317072) (xy 117.013482 -295.326308) (xy 116.992549 -295.343949)
			(xy 116.946581 -295.373673) (xy 116.896835 -295.396519) (xy 116.844333 -295.412015) (xy 116.790155 -295.419844)
			(xy 116.735413 -295.419844) (xy 116.681235 -295.412015) (xy 116.628733 -295.396519) (xy 116.578987 -295.373673)
			(xy 116.533019 -295.343949) (xy 116.512086 -295.326308) (xy 116.500758 -295.317072) (xy 116.474201 -295.304896)
			(xy 116.445284 -295.300723) (xy 116.416367 -295.304896) (xy 116.38981 -295.317072) (xy 116.378482 -295.326308)
			(xy 116.35755 -295.343949) (xy 116.311583 -295.373672) (xy 116.261836 -295.396512) (xy 116.209333 -295.412)
			(xy 116.155154 -295.419815) (xy 116.127784 -295.420288) (xy 116.100535 -295.419801) (xy 116.046592 -295.412043)
			(xy 115.994302 -295.396687) (xy 115.944729 -295.374046) (xy 115.898883 -295.344581) (xy 115.857697 -295.308891)
			(xy 115.822009 -295.267704) (xy 115.792546 -295.221857) (xy 115.769907 -295.172283) (xy 115.754554 -295.119992)
			(xy 115.746798 -295.066049) (xy 115.746798 -295.011551) (xy 115.754554 -294.957608) (xy 115.769907 -294.905317)
			(xy 115.792546 -294.855743) (xy 115.822009 -294.809896) (xy 115.857697 -294.768709) (xy 115.898883 -294.733019)
			(xy 115.944729 -294.703554) (xy 115.994302 -294.680913) (xy 116.046592 -294.665557) (xy 116.100535 -294.657799)
			(xy 116.127784 -294.657272) (xy 116.155151 -294.65775) (xy 116.209323 -294.665586) (xy 116.261818 -294.681084)
			(xy 116.311559 -294.703927) (xy 116.357523 -294.733646) (xy 116.378482 -294.751252) (xy 116.38981 -294.760488)
			(xy 116.416367 -294.772664) (xy 116.445284 -294.776837) (xy 116.474201 -294.772664) (xy 116.500758 -294.760488)
			(xy 116.512086 -294.751252) (xy 116.533019 -294.733611) (xy 116.578987 -294.703887) (xy 116.628733 -294.681041)
			(xy 116.681235 -294.665545) (xy 116.735413 -294.657716) (xy 116.790155 -294.657716) (xy 116.844333 -294.665545)
			(xy 116.896835 -294.681041) (xy 116.946581 -294.703887) (xy 116.992549 -294.733611) (xy 117.013482 -294.751252)
			(xy 117.02481 -294.760488) (xy 117.051367 -294.772664) (xy 117.080284 -294.776837) (xy 117.109201 -294.772664)
			(xy 117.135758 -294.760488) (xy 117.147086 -294.751252) (xy 117.169527 -294.73244) (xy 117.219028 -294.701161)
			(xy 117.272723 -294.677804) (xy 117.329354 -294.662917) (xy 117.358414 -294.659304) (xy 117.40388 -294.654478)
			(xy 117.40388 -293.340282) (xy 117.358414 -293.335456) (xy 117.329343 -293.331904) (xy 117.272701 -293.317026)
			(xy 117.219001 -293.293658) (xy 117.169508 -293.262349) (xy 117.147086 -293.243508) (xy 117.135758 -293.234272)
			(xy 117.109201 -293.222096) (xy 117.080284 -293.217923) (xy 117.051367 -293.222096) (xy 117.02481 -293.234272)
			(xy 117.013482 -293.243508) (xy 116.992549 -293.261149) (xy 116.946581 -293.290873) (xy 116.896835 -293.313719)
			(xy 116.844333 -293.329215) (xy 116.790155 -293.337044) (xy 116.735413 -293.337044) (xy 116.681235 -293.329215)
			(xy 116.628733 -293.313719) (xy 116.578987 -293.290873) (xy 116.533019 -293.261149) (xy 116.512086 -293.243508)
			(xy 116.500758 -293.234272) (xy 116.474201 -293.222096) (xy 116.445284 -293.217923) (xy 116.416367 -293.222096)
			(xy 116.38981 -293.234272) (xy 116.378482 -293.243508) (xy 116.35755 -293.261149) (xy 116.311583 -293.290872)
			(xy 116.261836 -293.313712) (xy 116.209333 -293.3292) (xy 116.155154 -293.337015) (xy 116.127784 -293.337488)
			(xy 116.100535 -293.337001) (xy 116.046592 -293.329243) (xy 115.994302 -293.313887) (xy 115.944729 -293.291246)
			(xy 115.898883 -293.261781) (xy 115.857697 -293.226091) (xy 115.822009 -293.184904) (xy 115.792546 -293.139057)
			(xy 115.769907 -293.089483) (xy 115.754554 -293.037192) (xy 115.746798 -292.983249) (xy 115.746798 -292.928751)
			(xy 115.754554 -292.874808) (xy 115.769907 -292.822517) (xy 115.792546 -292.772943) (xy 115.822009 -292.727096)
			(xy 115.857697 -292.685909) (xy 115.898883 -292.650219) (xy 115.944729 -292.620754) (xy 115.994302 -292.598113)
			(xy 116.046592 -292.582757) (xy 116.100535 -292.574999) (xy 116.127784 -292.574472) (xy 116.155151 -292.57495)
			(xy 116.209323 -292.582786) (xy 116.261818 -292.598284) (xy 116.311559 -292.621127) (xy 116.357523 -292.650846)
			(xy 116.378482 -292.668452) (xy 116.38981 -292.677688) (xy 116.416367 -292.689864) (xy 116.445284 -292.694037)
			(xy 116.474201 -292.689864) (xy 116.500758 -292.677688) (xy 116.512086 -292.668452) (xy 116.533019 -292.650811)
			(xy 116.578987 -292.621087) (xy 116.628733 -292.598241) (xy 116.681235 -292.582745) (xy 116.735413 -292.574916)
			(xy 116.790155 -292.574916) (xy 116.844333 -292.582745) (xy 116.896835 -292.598241) (xy 116.946581 -292.621087)
			(xy 116.992549 -292.650811) (xy 117.013482 -292.668452) (xy 117.02481 -292.677688) (xy 117.051367 -292.689864)
			(xy 117.080284 -292.694037) (xy 117.109201 -292.689864) (xy 117.135758 -292.677688) (xy 117.147086 -292.668452)
			(xy 117.169527 -292.64964) (xy 117.219028 -292.618361) (xy 117.272723 -292.595004) (xy 117.329354 -292.580117)
			(xy 117.358414 -292.576504) (xy 117.40388 -292.571678) (xy 117.40388 -291.683948) (xy 117.68328 -291.404548)
			(xy 117.68328 -289.197288) (xy 117.661746 -289.183206) (xy 117.622918 -289.149451) (xy 117.589786 -289.11009)
			(xy 117.563148 -289.066074) (xy 117.543648 -289.018463) (xy 117.531755 -288.968407) (xy 117.527758 -288.917114)
			(xy 117.531751 -288.86582) (xy 117.543639 -288.815763) (xy 117.563136 -288.768151) (xy 117.58977 -288.724132)
			(xy 117.622899 -288.684769) (xy 117.661724 -288.65101) (xy 117.68328 -288.636964) (xy 117.68328 -287.569402)
			(xy 117.661745 -287.55532) (xy 117.622915 -287.521565) (xy 117.589781 -287.482203) (xy 117.563141 -287.438186)
			(xy 117.543639 -287.390574) (xy 117.531745 -287.340517) (xy 117.527746 -287.289221) (xy 117.531738 -287.237925)
			(xy 117.543626 -287.187866) (xy 117.563122 -287.140252) (xy 117.589756 -287.096231) (xy 117.622885 -287.056866)
			(xy 117.661711 -287.023105) (xy 117.68328 -287.009078) (xy 117.68328 -285.941516) (xy 117.661752 -285.927434)
			(xy 117.622935 -285.89368) (xy 117.589814 -285.854323) (xy 117.563186 -285.810312) (xy 117.543695 -285.762708)
			(xy 117.53181 -285.71266) (xy 117.527819 -285.661376) (xy 117.531818 -285.610092) (xy 117.54371 -285.560045)
			(xy 117.563208 -285.512444) (xy 117.589842 -285.468437) (xy 117.62297 -285.429085) (xy 117.661792 -285.395337)
			(xy 117.68328 -285.381192) (xy 117.68328 -284.314138) (xy 117.661719 -284.300049) (xy 117.622839 -284.266272)
			(xy 117.589661 -284.22688) (xy 117.562986 -284.182823) (xy 117.543458 -284.135166) (xy 117.531549 -284.085059)
			(xy 117.527546 -284.033712) (xy 117.531545 -283.982364) (xy 117.543451 -283.932257) (xy 117.562976 -283.884598)
			(xy 117.589647 -283.840539) (xy 117.622823 -283.801145) (xy 117.6617 -283.767365) (xy 117.68328 -283.753306)
			(xy 117.68328 -282.685744) (xy 117.66179 -282.671657) (xy 117.623046 -282.637908) (xy 117.589988 -282.598572)
			(xy 117.563412 -282.554597) (xy 117.543958 -282.50704) (xy 117.532094 -282.457046) (xy 117.528105 -282.405819)
			(xy 117.532088 -282.354592) (xy 117.543946 -282.304597) (xy 117.563395 -282.257038) (xy 117.589965 -282.213059)
			(xy 117.623019 -282.173719) (xy 117.661759 -282.139966) (xy 117.68328 -282.125928) (xy 117.68328 -281.978862)
			(xy 117.682787 -281.964078) (xy 117.674336 -281.935743) (xy 117.658124 -281.911016) (xy 117.635509 -281.891968)
			(xy 117.608387 -281.880194) (xy 117.579028 -281.876681) (xy 117.549893 -281.881724) (xy 117.536468 -281.88793)
			(xy 117.513461 -281.898841) (xy 117.464928 -281.914244) (xy 117.414607 -281.922026) (xy 117.389148 -281.922474)
			(xy 117.363175 -281.921995) (xy 117.311867 -281.913875) (xy 117.262461 -281.897829) (xy 117.216174 -281.87425)
			(xy 117.174145 -281.84372) (xy 117.137411 -281.806991) (xy 117.106875 -281.764967) (xy 117.08329 -281.718684)
			(xy 117.067236 -281.66928) (xy 117.059109 -281.617973) (xy 117.059109 -281.566027) (xy 117.067236 -281.51472)
			(xy 117.08329 -281.465316) (xy 117.106875 -281.419033) (xy 117.137411 -281.377009) (xy 117.174145 -281.34028)
			(xy 117.216174 -281.30975) (xy 117.262461 -281.286171) (xy 117.311867 -281.270125) (xy 117.363175 -281.262005)
			(xy 117.389148 -281.261566) (xy 117.414607 -281.262017) (xy 117.464928 -281.269795) (xy 117.513458 -281.285203)
			(xy 117.536468 -281.29611) (xy 117.549923 -281.302239) (xy 117.579046 -281.30727) (xy 117.60839 -281.303758)
			(xy 117.635503 -281.291996) (xy 117.658117 -281.272969) (xy 117.674341 -281.248266) (xy 117.682819 -281.219955)
			(xy 117.68328 -281.205178) (xy 117.68328 -281.058112) (xy 117.661793 -281.044025) (xy 117.623053 -281.010276)
			(xy 117.59 -280.970942) (xy 117.563429 -280.926969) (xy 117.543979 -280.879415) (xy 117.532118 -280.829425)
			(xy 117.528132 -280.778202) (xy 117.532118 -280.726979) (xy 117.543978 -280.676989) (xy 117.563427 -280.629435)
			(xy 117.589998 -280.585461) (xy 117.62305 -280.546127) (xy 117.661789 -280.512378) (xy 117.68328 -280.498296)
			(xy 117.68328 -280.350976) (xy 117.682789 -280.33619) (xy 117.67434 -280.307852) (xy 117.658129 -280.283121)
			(xy 117.635513 -280.26407) (xy 117.608388 -280.252294) (xy 117.579026 -280.248781) (xy 117.549889 -280.253826)
			(xy 117.536468 -280.260044) (xy 117.51346 -280.270954) (xy 117.464928 -280.286357) (xy 117.414607 -280.294139)
			(xy 117.389148 -280.294588) (xy 117.363174 -280.294109) (xy 117.311863 -280.285989) (xy 117.262455 -280.269941)
			(xy 117.216166 -280.246362) (xy 117.174136 -280.215831) (xy 117.1374 -280.1791) (xy 117.106863 -280.137075)
			(xy 117.083277 -280.090789) (xy 117.067222 -280.041383) (xy 117.059095 -279.990074) (xy 117.059095 -279.938126)
			(xy 117.067222 -279.886817) (xy 117.083277 -279.837411) (xy 117.106863 -279.791125) (xy 117.1374 -279.7491)
			(xy 117.174136 -279.712369) (xy 117.216166 -279.681838) (xy 117.262455 -279.658259) (xy 117.311863 -279.642211)
			(xy 117.363174 -279.634091) (xy 117.389148 -279.63368) (xy 117.414607 -279.634131) (xy 117.464928 -279.641909)
			(xy 117.513458 -279.657318) (xy 117.536468 -279.668224) (xy 117.549924 -279.674352) (xy 117.579047 -279.679383)
			(xy 117.608393 -279.67587) (xy 117.635506 -279.664109) (xy 117.658122 -279.645082) (xy 117.674349 -279.620381)
			(xy 117.68283 -279.592069) (xy 117.68328 -279.577292) (xy 117.68328 -279.430226) (xy 117.66003 -279.414919)
			(xy 117.618546 -279.377808) (xy 117.583857 -279.334279) (xy 117.556941 -279.285558) (xy 117.538556 -279.233021)
			(xy 117.529223 -279.178148) (xy 117.528594 -279.150318) (xy 117.529356 -279.12949) (xy 117.530626 -279.10663)
			(xy 116.89842 -278.474424) (xy 116.888614 -278.465242) (xy 116.865299 -278.451915) (xy 116.839317 -278.445125)
			(xy 116.812463 -278.445339) (xy 116.786593 -278.452545) (xy 116.763494 -278.466243) (xy 116.744763 -278.485487)
			(xy 116.737892 -278.49703) (xy 116.725259 -278.518723) (xy 116.694464 -278.558366) (xy 116.658032 -278.592901)
			(xy 116.6168 -278.621534) (xy 116.571716 -278.643608) (xy 116.523813 -278.658617) (xy 116.474193 -278.666216)
			(xy 116.449094 -278.666702) (xy 116.423126 -278.666192) (xy 116.371829 -278.658068) (xy 116.322434 -278.642019)
			(xy 116.276157 -278.618442) (xy 116.234138 -278.587916) (xy 116.197411 -278.551194) (xy 116.16688 -278.509179)
			(xy 116.143297 -278.462905) (xy 116.127242 -278.413512) (xy 116.119111 -278.362216) (xy 116.11864 -278.336248)
			(xy 116.119103 -278.311146) (xy 116.126688 -278.261517) (xy 116.14169 -278.213607) (xy 116.163764 -278.168516)
			(xy 116.192403 -278.127281) (xy 116.226948 -278.090851) (xy 116.266605 -278.060065) (xy 116.288312 -278.04745)
			(xy 116.299868 -278.040584) (xy 116.319162 -278.021879) (xy 116.332896 -277.998782) (xy 116.340116 -277.972898)
			(xy 116.340318 -277.946027) (xy 116.333491 -277.920037) (xy 116.320107 -277.896735) (xy 116.310918 -277.886922)
			(xy 116.195856 -277.77186) (xy 116.177761 -277.787033) (xy 116.138052 -277.812589) (xy 116.095106 -277.832225)
			(xy 116.0498 -277.84554) (xy 116.003059 -277.852262) (xy 115.979448 -277.852632) (xy 115.953477 -277.852153)
			(xy 115.902173 -277.844034) (xy 115.852772 -277.827988) (xy 115.806489 -277.80441) (xy 115.764465 -277.773882)
			(xy 115.727735 -277.737155) (xy 115.697203 -277.695133) (xy 115.673622 -277.648852) (xy 115.657573 -277.599452)
			(xy 115.649449 -277.548149) (xy 115.648994 -277.522178) (xy 115.649397 -277.498569) (xy 115.656122 -277.451831)
			(xy 115.669432 -277.406527) (xy 115.689056 -277.363579) (xy 115.714593 -277.323862) (xy 115.729766 -277.30577)
			(xy 115.459256 -277.03526) (xy 115.44427 -277.032466) (xy 115.420546 -277.027268) (xy 115.374841 -277.010848)
			(xy 115.33203 -276.987917) (xy 115.293036 -276.958968) (xy 115.258698 -276.924624) (xy 115.229755 -276.885626)
			(xy 115.206831 -276.842812) (xy 115.190418 -276.797104) (xy 115.18519 -276.773386) (xy 115.182396 -276.7584)
			(xy 115.07343 -276.649434) (xy 115.062604 -276.639326) (xy 115.036542 -276.625278) (xy 115.007547 -276.619291)
			(xy 114.978053 -276.621868) (xy 114.950535 -276.632792) (xy 114.927305 -276.651147) (xy 114.910311 -276.675391)
			(xy 114.900982 -276.703489) (xy 114.899948 -276.718268) (xy 114.898724 -276.743718) (xy 114.889421 -276.793812)
			(xy 114.872539 -276.841884) (xy 114.84848 -276.886796) (xy 114.817813 -276.927483) (xy 114.781265 -276.962982)
			(xy 114.739702 -276.992451) (xy 114.694109 -277.015193) (xy 114.645566 -277.030668) (xy 114.595223 -277.03851)
			(xy 114.569748 -277.03907) (xy 114.543776 -277.038591) (xy 114.49247 -277.030472) (xy 114.443066 -277.014426)
			(xy 114.39678 -276.99085) (xy 114.354753 -276.960322) (xy 114.31802 -276.923595) (xy 114.287484 -276.881574)
			(xy 114.263898 -276.835293) (xy 114.247843 -276.785892) (xy 114.239714 -276.734588) (xy 114.239294 -276.708616)
			(xy 114.239758 -276.683132) (xy 114.247572 -276.632766) (xy 114.263032 -276.5842) (xy 114.28577 -276.538585)
			(xy 114.315248 -276.497007) (xy 114.350765 -276.460451) (xy 114.391476 -276.429787) (xy 114.436416 -276.405742)
			(xy 114.484517 -276.388889) (xy 114.534636 -276.379626) (xy 114.560096 -276.378416) (xy 114.57488 -276.377462)
			(xy 114.602978 -276.368115) (xy 114.627219 -276.351108) (xy 114.645569 -276.327868) (xy 114.65649 -276.300343)
			(xy 114.659063 -276.270843) (xy 114.653075 -276.241843) (xy 114.639027 -276.215775) (xy 114.62893 -276.204934)
			(xy 114.512598 -276.088602) (xy 114.502082 -276.078773) (xy 114.476879 -276.064892) (xy 114.448805 -276.058591)
			(xy 114.420088 -276.060371) (xy 114.393006 -276.070089) (xy 114.36971 -276.086975) (xy 114.360452 -276.098)
			(xy 114.344694 -276.117454) (xy 114.308304 -276.151834) (xy 114.267144 -276.180332) (xy 114.222156 -276.202294)
			(xy 114.17437 -276.217218) (xy 114.124879 -276.224762) (xy 114.099848 -276.225254) (xy 114.073876 -276.224775)
			(xy 114.022571 -276.216656) (xy 113.973168 -276.20061) (xy 113.926884 -276.177033) (xy 113.884858 -276.146505)
			(xy 113.848126 -276.109778) (xy 113.817592 -276.067757) (xy 113.794008 -276.021476) (xy 113.777956 -275.972075)
			(xy 113.769829 -275.920772) (xy 113.769394 -275.8948) (xy 113.769855 -275.869767) (xy 113.777407 -275.820275)
			(xy 113.792336 -275.772487) (xy 113.814302 -275.727498) (xy 113.842802 -275.686337) (xy 113.877185 -275.649945)
			(xy 113.896648 -275.634196) (xy 113.907721 -275.624982) (xy 113.924643 -275.601687) (xy 113.93438 -275.57459)
			(xy 113.936154 -275.545851) (xy 113.929824 -275.517762) (xy 113.915896 -275.492562) (xy 113.906046 -275.48205)
			(xy 113.793778 -275.369782) (xy 113.762028 -275.383498) (xy 113.741077 -275.392253) (xy 113.697376 -275.404585)
			(xy 113.652398 -275.410816) (xy 113.629694 -275.411184) (xy 113.603726 -275.410674) (xy 113.55243 -275.402549)
			(xy 113.503036 -275.386501) (xy 113.456761 -275.362923) (xy 113.414744 -275.332397) (xy 113.378018 -275.295675)
			(xy 113.347489 -275.253659) (xy 113.323909 -275.207386) (xy 113.307856 -275.157993) (xy 113.299728 -275.106698)
			(xy 113.29924 -275.08073) (xy 113.299616 -275.058026) (xy 113.305836 -275.013046) (xy 113.318164 -274.969344)
			(xy 113.326926 -274.948396) (xy 113.340642 -274.916646) (xy 112.480344 -274.056348) (xy 110.758478 -274.056348)
			(xy 110.745211 -274.056779) (xy 110.719577 -274.063629) (xy 110.696578 -274.076859) (xy 110.677769 -274.095574)
			(xy 110.664424 -274.118508) (xy 110.657447 -274.144107) (xy 110.657309 -274.17064) (xy 110.66018 -274.183602)
			(xy 110.665165 -274.204068) (xy 110.670512 -274.245852) (xy 110.670848 -274.266914) (xy 110.670339 -274.292881)
			(xy 110.662214 -274.344176) (xy 110.646166 -274.393569) (xy 110.622588 -274.439843) (xy 110.592062 -274.481859)
			(xy 110.555339 -274.518582) (xy 110.513323 -274.549108) (xy 110.467049 -274.572686) (xy 110.417656 -274.588734)
			(xy 110.366361 -274.596859) (xy 110.314427 -274.596859) (xy 110.263132 -274.588734) (xy 110.213739 -274.572686)
			(xy 110.167465 -274.549108) (xy 110.125449 -274.518582) (xy 110.088726 -274.481859) (xy 110.0582 -274.439843)
			(xy 110.034622 -274.393569) (xy 110.018574 -274.344176) (xy 110.010449 -274.292881) (xy 110.00994 -274.266914)
			(xy 110.01027 -274.245852) (xy 110.01562 -274.204068) (xy 110.020608 -274.183602) (xy 110.023982 -274.168474)
			(xy 110.02245 -274.137532) (xy 110.011719 -274.10847) (xy 109.992774 -274.083957) (xy 109.967356 -274.066246)
			(xy 109.9378 -274.056962) (xy 109.92231 -274.056348) (xy 109.818678 -274.056348) (xy 109.805411 -274.056779)
			(xy 109.779777 -274.063629) (xy 109.756778 -274.076859) (xy 109.737969 -274.095574) (xy 109.724624 -274.118508)
			(xy 109.717647 -274.144107) (xy 109.717509 -274.17064) (xy 109.72038 -274.183602) (xy 109.725365 -274.204068)
			(xy 109.730712 -274.245852) (xy 109.731048 -274.266914) (xy 109.730539 -274.292881) (xy 109.722414 -274.344176)
			(xy 109.706366 -274.393569) (xy 109.682788 -274.439843) (xy 109.652262 -274.481859) (xy 109.615539 -274.518582)
			(xy 109.573523 -274.549108) (xy 109.527249 -274.572686) (xy 109.477856 -274.588734) (xy 109.426561 -274.596859)
			(xy 109.374627 -274.596859) (xy 109.323332 -274.588734) (xy 109.273939 -274.572686) (xy 109.227665 -274.549108)
			(xy 109.185649 -274.518582) (xy 109.148926 -274.481859) (xy 109.1184 -274.439843) (xy 109.094822 -274.393569)
			(xy 109.078774 -274.344176) (xy 109.070649 -274.292881) (xy 109.07014 -274.266914) (xy 109.070752 -274.238934)
			(xy 109.080203 -274.183776) (xy 109.088936 -274.157186) (xy 109.096556 -274.135088) (xy 109.05109 -274.056348)
			(xy 108.99648 -274.056348) (xy 108.79201 -274.260818) (xy 108.791248 -274.28063) (xy 108.789776 -274.305221)
			(xy 108.780454 -274.353593) (xy 108.764049 -274.400043) (xy 108.740927 -274.44354) (xy 108.711599 -274.48312)
			(xy 108.676716 -274.517905) (xy 108.637054 -274.547121) (xy 108.61548 -274.559014) (xy 108.61548 -274.705318)
			(xy 108.616084 -274.720485) (xy 108.625072 -274.749459) (xy 108.642162 -274.774524) (xy 108.665852 -274.793474)
			(xy 108.694058 -274.804643) (xy 108.7243 -274.807048) (xy 108.753917 -274.800479) (xy 108.767372 -274.793456)
			(xy 108.792434 -274.779892) (xy 108.846065 -274.760638) (xy 108.902203 -274.750866) (xy 108.930694 -274.750276)
			(xy 108.956661 -274.750758) (xy 109.007956 -274.758882) (xy 109.057349 -274.77493) (xy 109.103624 -274.798507)
			(xy 109.14564 -274.829033) (xy 109.182363 -274.865756) (xy 109.21289 -274.907771) (xy 109.236468 -274.954045)
			(xy 109.252517 -275.003438) (xy 109.260641 -275.054733) (xy 109.260641 -275.106667) (xy 109.260636 -275.106697)
			(xy 109.540549 -275.106697) (xy 109.540549 -275.054763) (xy 109.548674 -275.003468) (xy 109.564722 -274.954075)
			(xy 109.5883 -274.907801) (xy 109.618826 -274.865785) (xy 109.655549 -274.829062) (xy 109.697565 -274.798536)
			(xy 109.743839 -274.774958) (xy 109.793232 -274.75891) (xy 109.844527 -274.750785) (xy 109.896461 -274.750785)
			(xy 109.947756 -274.75891) (xy 109.997149 -274.774958) (xy 110.043423 -274.798536) (xy 110.085439 -274.829062)
			(xy 110.122162 -274.865785) (xy 110.152688 -274.907801) (xy 110.176266 -274.954075) (xy 110.192314 -275.003468)
			(xy 110.200439 -275.054763) (xy 110.200948 -275.08073) (xy 110.200439 -275.106697) (xy 110.192314 -275.157992)
			(xy 110.176266 -275.207385) (xy 110.152688 -275.253659) (xy 110.122162 -275.295675) (xy 110.085439 -275.332398)
			(xy 110.043423 -275.362924) (xy 109.997149 -275.386502) (xy 109.947756 -275.40255) (xy 109.896461 -275.410675)
			(xy 109.844527 -275.410675) (xy 109.793232 -275.40255) (xy 109.743839 -275.386502) (xy 109.697565 -275.362924)
			(xy 109.655549 -275.332398) (xy 109.618826 -275.295675) (xy 109.5883 -275.253659) (xy 109.564722 -275.207385)
			(xy 109.548674 -275.157992) (xy 109.540549 -275.106697) (xy 109.260636 -275.106697) (xy 109.252517 -275.157962)
			(xy 109.236468 -275.207355) (xy 109.21289 -275.253629) (xy 109.182363 -275.295644) (xy 109.14564 -275.332367)
			(xy 109.103624 -275.362893) (xy 109.057349 -275.38647) (xy 109.007956 -275.402518) (xy 108.956661 -275.410642)
			(xy 108.930694 -275.411184) (xy 108.902203 -275.410586) (xy 108.846066 -275.400816) (xy 108.792435 -275.381565)
			(xy 108.767372 -275.368004) (xy 108.753909 -275.360982) (xy 108.724288 -275.354375) (xy 108.694033 -275.356759)
			(xy 108.665814 -275.367925) (xy 108.642118 -275.386887) (xy 108.625037 -275.411973) (xy 108.616078 -275.440969)
			(xy 108.61548 -275.456142) (xy 108.61548 -275.6027) (xy 108.637891 -275.615097) (xy 108.678927 -275.645737)
			(xy 108.714745 -275.682343) (xy 108.744485 -275.724035) (xy 108.767437 -275.769818) (xy 108.783051 -275.818593)
			(xy 108.790953 -275.869193) (xy 108.790953 -275.920407) (xy 108.783051 -275.971007) (xy 108.767437 -276.019782)
			(xy 108.744485 -276.065565) (xy 108.714745 -276.107257) (xy 108.678927 -276.143863) (xy 108.637891 -276.174503)
			(xy 108.61548 -276.1869) (xy 108.61548 -276.333204) (xy 108.616082 -276.348372) (xy 108.625068 -276.377351)
			(xy 108.642158 -276.402419) (xy 108.665849 -276.421372) (xy 108.694058 -276.432543) (xy 108.724302 -276.434948)
			(xy 108.753922 -276.428377) (xy 108.767372 -276.421342) (xy 108.791453 -276.408248) (xy 108.842902 -276.389352)
			(xy 108.869734 -276.38375) (xy 108.892848 -276.379432) (xy 109.096556 -276.026626) (xy 109.088682 -276.004528)
			(xy 109.079889 -275.977954) (xy 109.070439 -275.922786) (xy 109.069886 -275.8948) (xy 109.070395 -275.868833)
			(xy 109.07852 -275.817538) (xy 109.094568 -275.768145) (xy 109.118146 -275.721871) (xy 109.148672 -275.679855)
			(xy 109.185395 -275.643132) (xy 109.227411 -275.612606) (xy 109.273685 -275.589028) (xy 109.323078 -275.57298)
			(xy 109.374373 -275.564855) (xy 109.426307 -275.564855) (xy 109.477602 -275.57298) (xy 109.526995 -275.589028)
			(xy 109.573269 -275.612606) (xy 109.615285 -275.643132) (xy 109.652008 -275.679855) (xy 109.682534 -275.721871)
			(xy 109.706112 -275.768145) (xy 109.72216 -275.817538) (xy 109.730285 -275.868833) (xy 109.730794 -275.8948)
			(xy 109.730318 -275.920245) (xy 109.730237 -275.920767) (xy 110.010449 -275.920767) (xy 110.010449 -275.868833)
			(xy 110.018574 -275.817538) (xy 110.034622 -275.768145) (xy 110.0582 -275.721871) (xy 110.088726 -275.679855)
			(xy 110.125449 -275.643132) (xy 110.167465 -275.612606) (xy 110.213739 -275.589028) (xy 110.263132 -275.57298)
			(xy 110.314427 -275.564855) (xy 110.366361 -275.564855) (xy 110.417656 -275.57298) (xy 110.467049 -275.589028)
			(xy 110.513323 -275.612606) (xy 110.555339 -275.643132) (xy 110.592062 -275.679855) (xy 110.622588 -275.721871)
			(xy 110.646166 -275.768145) (xy 110.662214 -275.817538) (xy 110.670339 -275.868833) (xy 110.670848 -275.8948)
			(xy 110.670339 -275.920767) (xy 110.662214 -275.972062) (xy 110.646166 -276.021455) (xy 110.622588 -276.067729)
			(xy 110.592062 -276.109745) (xy 110.555339 -276.146468) (xy 110.513323 -276.176994) (xy 110.467049 -276.200572)
			(xy 110.417656 -276.21662) (xy 110.366361 -276.224745) (xy 110.314427 -276.224745) (xy 110.263132 -276.21662)
			(xy 110.213739 -276.200572) (xy 110.167465 -276.176994) (xy 110.125449 -276.146468) (xy 110.088726 -276.109745)
			(xy 110.0582 -276.067729) (xy 110.034622 -276.021455) (xy 110.018574 -275.972062) (xy 110.010449 -275.920767)
			(xy 109.730237 -275.920767) (xy 109.722504 -275.970531) (xy 109.707077 -276.019027) (xy 109.6844 -276.064585)
			(xy 109.655009 -276.10613) (xy 109.6196 -276.142681) (xy 109.579007 -276.173373) (xy 109.53419 -276.197482)
			(xy 109.486208 -276.214439) (xy 109.4613 -276.219666) (xy 109.43844 -276.223984) (xy 109.234732 -276.57679)
			(xy 109.242352 -276.598888) (xy 109.251145 -276.625462) (xy 109.260594 -276.68063) (xy 109.261148 -276.708616)
			(xy 109.260638 -276.734582) (xy 109.260638 -276.734583) (xy 109.540549 -276.734583) (xy 109.540549 -276.682649)
			(xy 109.548674 -276.631354) (xy 109.564722 -276.581961) (xy 109.5883 -276.535687) (xy 109.618826 -276.493671)
			(xy 109.655549 -276.456948) (xy 109.697565 -276.426422) (xy 109.743839 -276.402844) (xy 109.793232 -276.386796)
			(xy 109.844527 -276.378671) (xy 109.896461 -276.378671) (xy 109.947756 -276.386796) (xy 109.997149 -276.402844)
			(xy 110.043423 -276.426422) (xy 110.085439 -276.456948) (xy 110.122162 -276.493671) (xy 110.152688 -276.535687)
			(xy 110.176266 -276.581961) (xy 110.192314 -276.631354) (xy 110.200439 -276.682649) (xy 110.200948 -276.708616)
			(xy 110.200439 -276.734583) (xy 110.192314 -276.785878) (xy 110.176266 -276.835271) (xy 110.152688 -276.881545)
			(xy 110.122162 -276.923561) (xy 110.085439 -276.960284) (xy 110.043423 -276.99081) (xy 109.997149 -277.014388)
			(xy 109.947756 -277.030436) (xy 109.896461 -277.038561) (xy 109.844527 -277.038561) (xy 109.793232 -277.030436)
			(xy 109.743839 -277.014388) (xy 109.697565 -276.99081) (xy 109.655549 -276.960284) (xy 109.618826 -276.923561)
			(xy 109.5883 -276.881545) (xy 109.564722 -276.835271) (xy 109.548674 -276.785878) (xy 109.540549 -276.734583)
			(xy 109.260638 -276.734583) (xy 109.252511 -276.785875) (xy 109.236461 -276.835265) (xy 109.212882 -276.881536)
			(xy 109.182356 -276.923549) (xy 109.145633 -276.96027) (xy 109.103617 -276.990794) (xy 109.057345 -277.01437)
			(xy 109.007954 -277.030416) (xy 108.95666 -277.038539) (xy 108.930694 -277.03907) (xy 108.902203 -277.038472)
			(xy 108.846066 -277.028702) (xy 108.792436 -277.00945) (xy 108.767372 -276.99589) (xy 108.753908 -276.988869)
			(xy 108.724287 -276.982262) (xy 108.694031 -276.984647) (xy 108.665811 -276.995813) (xy 108.642114 -277.014774)
			(xy 108.625031 -277.039859) (xy 108.616068 -277.068854) (xy 108.61548 -277.084028) (xy 108.61548 -277.230332)
			(xy 108.636848 -277.24214) (xy 108.676161 -277.271086) (xy 108.71078 -277.305508) (xy 108.725716 -277.32482)
			(xy 109.135672 -277.32482) (xy 109.151394 -277.304587) (xy 109.188029 -277.268764) (xy 109.229748 -277.239017)
			(xy 109.275554 -277.216057) (xy 109.324352 -277.200433) (xy 109.374975 -277.192518) (xy 109.400594 -277.191978)
			(xy 109.426561 -277.19246) (xy 109.477856 -277.200584) (xy 109.527249 -277.216632) (xy 109.573523 -277.240209)
			(xy 109.615538 -277.270734) (xy 109.652262 -277.307457) (xy 109.682788 -277.349472) (xy 109.706366 -277.395746)
			(xy 109.722415 -277.445138) (xy 109.730539 -277.496433) (xy 109.730539 -277.548367) (xy 109.730534 -277.548399)
			(xy 110.010449 -277.548399) (xy 110.010449 -277.496465) (xy 110.018574 -277.44517) (xy 110.034622 -277.395777)
			(xy 110.0582 -277.349503) (xy 110.088726 -277.307487) (xy 110.125449 -277.270764) (xy 110.167465 -277.240238)
			(xy 110.213739 -277.21666) (xy 110.263132 -277.200612) (xy 110.314427 -277.192487) (xy 110.366361 -277.192487)
			(xy 110.417656 -277.200612) (xy 110.467049 -277.21666) (xy 110.513323 -277.240238) (xy 110.555339 -277.270764)
			(xy 110.592062 -277.307487) (xy 110.622588 -277.349503) (xy 110.646166 -277.395777) (xy 110.662214 -277.44517)
			(xy 110.670339 -277.496465) (xy 110.670848 -277.522432) (xy 110.670339 -277.548399) (xy 114.709449 -277.548399)
			(xy 114.709449 -277.496465) (xy 114.717574 -277.44517) (xy 114.733622 -277.395777) (xy 114.7572 -277.349503)
			(xy 114.787726 -277.307487) (xy 114.824449 -277.270764) (xy 114.866465 -277.240238) (xy 114.912739 -277.21666)
			(xy 114.962132 -277.200612) (xy 115.013427 -277.192487) (xy 115.065361 -277.192487) (xy 115.116656 -277.200612)
			(xy 115.166049 -277.21666) (xy 115.212323 -277.240238) (xy 115.254339 -277.270764) (xy 115.291062 -277.307487)
			(xy 115.321588 -277.349503) (xy 115.345166 -277.395777) (xy 115.361214 -277.44517) (xy 115.369339 -277.496465)
			(xy 115.369848 -277.522432) (xy 115.369339 -277.548399) (xy 115.361214 -277.599694) (xy 115.345166 -277.649087)
			(xy 115.321588 -277.695361) (xy 115.291062 -277.737377) (xy 115.254339 -277.7741) (xy 115.212323 -277.804626)
			(xy 115.166049 -277.828204) (xy 115.116656 -277.844252) (xy 115.065361 -277.852377) (xy 115.013427 -277.852377)
			(xy 114.962132 -277.844252) (xy 114.912739 -277.828204) (xy 114.866465 -277.804626) (xy 114.824449 -277.7741)
			(xy 114.787726 -277.737377) (xy 114.7572 -277.695361) (xy 114.733622 -277.649087) (xy 114.717574 -277.599694)
			(xy 114.709449 -277.548399) (xy 110.670339 -277.548399) (xy 110.662214 -277.599694) (xy 110.646166 -277.649087)
			(xy 110.622588 -277.695361) (xy 110.592062 -277.737377) (xy 110.555339 -277.7741) (xy 110.513323 -277.804626)
			(xy 110.467049 -277.828204) (xy 110.417656 -277.844252) (xy 110.366361 -277.852377) (xy 110.314427 -277.852377)
			(xy 110.263132 -277.844252) (xy 110.213739 -277.828204) (xy 110.167465 -277.804626) (xy 110.125449 -277.7741)
			(xy 110.088726 -277.737377) (xy 110.0582 -277.695361) (xy 110.034622 -277.649087) (xy 110.018574 -277.599694)
			(xy 110.010449 -277.548399) (xy 109.730534 -277.548399) (xy 109.722415 -277.599662) (xy 109.706366 -277.649054)
			(xy 109.682788 -277.695328) (xy 109.652262 -277.737343) (xy 109.615538 -277.774066) (xy 109.573523 -277.804591)
			(xy 109.527249 -277.828168) (xy 109.477856 -277.844216) (xy 109.426561 -277.85234) (xy 109.400594 -277.852886)
			(xy 109.374969 -277.852411) (xy 109.324331 -277.844514) (xy 109.275519 -277.828894) (xy 109.229703 -277.805927)
			(xy 109.187982 -277.776162) (xy 109.151356 -277.740314) (xy 109.135672 -277.720044) (xy 108.725716 -277.720044)
			(xy 108.71077 -277.739347) (xy 108.676148 -277.773764) (xy 108.636846 -277.802722) (xy 108.61548 -277.814532)
			(xy 108.61548 -277.96109) (xy 108.61608 -277.97626) (xy 108.625063 -278.005242) (xy 108.642153 -278.030314)
			(xy 108.665846 -278.049271) (xy 108.694057 -278.060443) (xy 108.724305 -278.062848) (xy 108.753927 -278.056275)
			(xy 108.767372 -278.049228) (xy 108.792435 -278.035665) (xy 108.846066 -278.016413) (xy 108.902203 -278.006642)
			(xy 108.930694 -278.006048) (xy 108.956663 -278.00653) (xy 109.007963 -278.014655) (xy 109.05736 -278.030704)
			(xy 109.103638 -278.054283) (xy 109.145658 -278.084811) (xy 109.182385 -278.121537) (xy 109.212914 -278.163557)
			(xy 109.236494 -278.209834) (xy 109.252544 -278.259231) (xy 109.260669 -278.310531) (xy 109.260669 -278.362469)
			(xy 109.540549 -278.362469) (xy 109.540549 -278.310535) (xy 109.548674 -278.25924) (xy 109.564722 -278.209847)
			(xy 109.5883 -278.163573) (xy 109.618826 -278.121557) (xy 109.655549 -278.084834) (xy 109.697565 -278.054308)
			(xy 109.743839 -278.03073) (xy 109.793232 -278.014682) (xy 109.844527 -278.006557) (xy 109.896461 -278.006557)
			(xy 109.947756 -278.014682) (xy 109.997149 -278.03073) (xy 110.043423 -278.054308) (xy 110.085439 -278.084834)
			(xy 110.122162 -278.121557) (xy 110.152688 -278.163573) (xy 110.176266 -278.209847) (xy 110.192314 -278.25924)
			(xy 110.200439 -278.310535) (xy 110.200948 -278.336502) (xy 110.200439 -278.362469) (xy 114.239803 -278.362469)
			(xy 114.239803 -278.310535) (xy 114.247928 -278.25924) (xy 114.263976 -278.209847) (xy 114.287554 -278.163573)
			(xy 114.31808 -278.121557) (xy 114.354803 -278.084834) (xy 114.396819 -278.054308) (xy 114.443093 -278.03073)
			(xy 114.492486 -278.014682) (xy 114.543781 -278.006557) (xy 114.595715 -278.006557) (xy 114.64701 -278.014682)
			(xy 114.696403 -278.03073) (xy 114.742677 -278.054308) (xy 114.784693 -278.084834) (xy 114.821416 -278.121557)
			(xy 114.851942 -278.163573) (xy 114.87552 -278.209847) (xy 114.891568 -278.25924) (xy 114.899693 -278.310535)
			(xy 114.900202 -278.336502) (xy 114.899698 -278.362215) (xy 115.179349 -278.362215) (xy 115.179349 -278.310281)
			(xy 115.187474 -278.258986) (xy 115.203522 -278.209593) (xy 115.2271 -278.163319) (xy 115.257626 -278.121303)
			(xy 115.294349 -278.08458) (xy 115.336365 -278.054054) (xy 115.382639 -278.030476) (xy 115.432032 -278.014428)
			(xy 115.483327 -278.006303) (xy 115.535261 -278.006303) (xy 115.586556 -278.014428) (xy 115.635949 -278.030476)
			(xy 115.682223 -278.054054) (xy 115.724239 -278.08458) (xy 115.760962 -278.121303) (xy 115.791488 -278.163319)
			(xy 115.815066 -278.209593) (xy 115.831114 -278.258986) (xy 115.839239 -278.310281) (xy 115.839748 -278.336248)
			(xy 115.839239 -278.362215) (xy 115.831114 -278.41351) (xy 115.815066 -278.462903) (xy 115.791488 -278.509177)
			(xy 115.760962 -278.551193) (xy 115.724239 -278.587916) (xy 115.682223 -278.618442) (xy 115.635949 -278.64202)
			(xy 115.586556 -278.658068) (xy 115.535261 -278.666193) (xy 115.483327 -278.666193) (xy 115.432032 -278.658068)
			(xy 115.382639 -278.64202) (xy 115.336365 -278.618442) (xy 115.294349 -278.587916) (xy 115.257626 -278.551193)
			(xy 115.2271 -278.509177) (xy 115.203522 -278.462903) (xy 115.187474 -278.41351) (xy 115.179349 -278.362215)
			(xy 114.899698 -278.362215) (xy 114.899693 -278.362469) (xy 114.891568 -278.413764) (xy 114.87552 -278.463157)
			(xy 114.851942 -278.509431) (xy 114.821416 -278.551447) (xy 114.784693 -278.58817) (xy 114.742677 -278.618696)
			(xy 114.696403 -278.642274) (xy 114.64701 -278.658322) (xy 114.595715 -278.666447) (xy 114.543781 -278.666447)
			(xy 114.492486 -278.658322) (xy 114.443093 -278.642274) (xy 114.396819 -278.618696) (xy 114.354803 -278.58817)
			(xy 114.31808 -278.551447) (xy 114.287554 -278.509431) (xy 114.263976 -278.463157) (xy 114.247928 -278.413764)
			(xy 114.239803 -278.362469) (xy 110.200439 -278.362469) (xy 110.192314 -278.413764) (xy 110.176266 -278.463157)
			(xy 110.152688 -278.509431) (xy 110.122162 -278.551447) (xy 110.085439 -278.58817) (xy 110.043423 -278.618696)
			(xy 109.997149 -278.642274) (xy 109.947756 -278.658322) (xy 109.896461 -278.666447) (xy 109.844527 -278.666447)
			(xy 109.793232 -278.658322) (xy 109.743839 -278.642274) (xy 109.697565 -278.618696) (xy 109.655549 -278.58817)
			(xy 109.618826 -278.551447) (xy 109.5883 -278.509431) (xy 109.564722 -278.463157) (xy 109.548674 -278.413764)
			(xy 109.540549 -278.362469) (xy 109.260669 -278.362469) (xy 109.252544 -278.413769) (xy 109.236494 -278.463166)
			(xy 109.212914 -278.509443) (xy 109.182385 -278.551463) (xy 109.145658 -278.588189) (xy 109.103638 -278.618717)
			(xy 109.05736 -278.642296) (xy 109.007963 -278.658345) (xy 108.956663 -278.66647) (xy 108.930694 -278.666956)
			(xy 108.902203 -278.666358) (xy 108.846067 -278.656587) (xy 108.792436 -278.637335) (xy 108.767372 -278.623776)
			(xy 108.753907 -278.616755) (xy 108.724285 -278.61015) (xy 108.694029 -278.612535) (xy 108.665808 -278.6237)
			(xy 108.642109 -278.642661) (xy 108.625024 -278.667745) (xy 108.616058 -278.69674) (xy 108.61548 -278.711914)
			(xy 108.61548 -278.858218) (xy 108.637862 -278.870637) (xy 108.678839 -278.901308) (xy 108.7146 -278.937927)
			(xy 108.744291 -278.97962) (xy 108.767202 -279.02539) (xy 108.782787 -279.074143) (xy 108.790673 -279.124716)
			(xy 108.790672 -279.1759) (xy 108.790612 -279.176285) (xy 114.709449 -279.176285) (xy 114.709449 -279.124351)
			(xy 114.717574 -279.073056) (xy 114.733622 -279.023663) (xy 114.7572 -278.977389) (xy 114.787726 -278.935373)
			(xy 114.824449 -278.89865) (xy 114.866465 -278.868124) (xy 114.912739 -278.844546) (xy 114.962132 -278.828498)
			(xy 115.013427 -278.820373) (xy 115.065361 -278.820373) (xy 115.116656 -278.828498) (xy 115.166049 -278.844546)
			(xy 115.212323 -278.868124) (xy 115.254339 -278.89865) (xy 115.291062 -278.935373) (xy 115.321588 -278.977389)
			(xy 115.345166 -279.023663) (xy 115.361214 -279.073056) (xy 115.369339 -279.124351) (xy 115.369848 -279.150318)
			(xy 115.369339 -279.176285) (xy 115.649249 -279.176285) (xy 115.649249 -279.124351) (xy 115.657374 -279.073056)
			(xy 115.673422 -279.023663) (xy 115.697 -278.977389) (xy 115.727526 -278.935373) (xy 115.764249 -278.89865)
			(xy 115.806265 -278.868124) (xy 115.852539 -278.844546) (xy 115.901932 -278.828498) (xy 115.953227 -278.820373)
			(xy 116.005161 -278.820373) (xy 116.056456 -278.828498) (xy 116.105849 -278.844546) (xy 116.152123 -278.868124)
			(xy 116.194139 -278.89865) (xy 116.230862 -278.935373) (xy 116.261388 -278.977389) (xy 116.284966 -279.023663)
			(xy 116.301014 -279.073056) (xy 116.309139 -279.124351) (xy 116.309648 -279.150318) (xy 116.309144 -279.176031)
			(xy 116.589303 -279.176031) (xy 116.589303 -279.124097) (xy 116.597428 -279.072802) (xy 116.613476 -279.023409)
			(xy 116.637054 -278.977135) (xy 116.66758 -278.935119) (xy 116.704303 -278.898396) (xy 116.746319 -278.86787)
			(xy 116.792593 -278.844292) (xy 116.841986 -278.828244) (xy 116.893281 -278.820119) (xy 116.945215 -278.820119)
			(xy 116.99651 -278.828244) (xy 117.045903 -278.844292) (xy 117.092177 -278.86787) (xy 117.134193 -278.898396)
			(xy 117.170916 -278.935119) (xy 117.201442 -278.977135) (xy 117.22502 -279.023409) (xy 117.241068 -279.072802)
			(xy 117.249193 -279.124097) (xy 117.249702 -279.150064) (xy 117.249193 -279.176031) (xy 117.241068 -279.227326)
			(xy 117.22502 -279.276719) (xy 117.201442 -279.322993) (xy 117.170916 -279.365009) (xy 117.134193 -279.401732)
			(xy 117.092177 -279.432258) (xy 117.045903 -279.455836) (xy 116.99651 -279.471884) (xy 116.945215 -279.480009)
			(xy 116.893281 -279.480009) (xy 116.841986 -279.471884) (xy 116.792593 -279.455836) (xy 116.746319 -279.432258)
			(xy 116.704303 -279.401732) (xy 116.66758 -279.365009) (xy 116.637054 -279.322993) (xy 116.613476 -279.276719)
			(xy 116.597428 -279.227326) (xy 116.589303 -279.176031) (xy 116.309144 -279.176031) (xy 116.309139 -279.176285)
			(xy 116.301014 -279.22758) (xy 116.284966 -279.276973) (xy 116.261388 -279.323247) (xy 116.230862 -279.365263)
			(xy 116.194139 -279.401986) (xy 116.152123 -279.432512) (xy 116.105849 -279.45609) (xy 116.056456 -279.472138)
			(xy 116.005161 -279.480263) (xy 115.953227 -279.480263) (xy 115.901932 -279.472138) (xy 115.852539 -279.45609)
			(xy 115.806265 -279.432512) (xy 115.764249 -279.401986) (xy 115.727526 -279.365263) (xy 115.697 -279.323247)
			(xy 115.673422 -279.276973) (xy 115.657374 -279.22758) (xy 115.649249 -279.176285) (xy 115.369339 -279.176285)
			(xy 115.361214 -279.22758) (xy 115.345166 -279.276973) (xy 115.321588 -279.323247) (xy 115.291062 -279.365263)
			(xy 115.254339 -279.401986) (xy 115.212323 -279.432512) (xy 115.166049 -279.45609) (xy 115.116656 -279.472138)
			(xy 115.065361 -279.480263) (xy 115.013427 -279.480263) (xy 114.962132 -279.472138) (xy 114.912739 -279.45609)
			(xy 114.866465 -279.432512) (xy 114.824449 -279.401986) (xy 114.787726 -279.365263) (xy 114.7572 -279.323247)
			(xy 114.733622 -279.276973) (xy 114.717574 -279.22758) (xy 114.709449 -279.176285) (xy 108.790612 -279.176285)
			(xy 108.782783 -279.226473) (xy 108.767196 -279.275226) (xy 108.744282 -279.320995) (xy 108.714589 -279.362686)
			(xy 108.678826 -279.399303) (xy 108.637848 -279.429972) (xy 108.61548 -279.442418) (xy 108.61548 -279.708356)
			(xy 108.333735 -279.990101) (xy 113.299749 -279.990101) (xy 113.299749 -279.938167) (xy 113.307874 -279.886872)
			(xy 113.323922 -279.837479) (xy 113.3475 -279.791205) (xy 113.378026 -279.749189) (xy 113.414749 -279.712466)
			(xy 113.456765 -279.68194) (xy 113.503039 -279.658362) (xy 113.552432 -279.642314) (xy 113.603727 -279.634189)
			(xy 113.655661 -279.634189) (xy 113.706956 -279.642314) (xy 113.756349 -279.658362) (xy 113.802623 -279.68194)
			(xy 113.844639 -279.712466) (xy 113.881362 -279.749189) (xy 113.911888 -279.791205) (xy 113.935466 -279.837479)
			(xy 113.951514 -279.886872) (xy 113.959639 -279.938167) (xy 113.960148 -279.964134) (xy 113.959639 -279.990101)
			(xy 116.119403 -279.990101) (xy 116.119403 -279.938167) (xy 116.127528 -279.886872) (xy 116.143576 -279.837479)
			(xy 116.167154 -279.791205) (xy 116.19768 -279.749189) (xy 116.234403 -279.712466) (xy 116.276419 -279.68194)
			(xy 116.322693 -279.658362) (xy 116.372086 -279.642314) (xy 116.423381 -279.634189) (xy 116.475315 -279.634189)
			(xy 116.52661 -279.642314) (xy 116.576003 -279.658362) (xy 116.622277 -279.68194) (xy 116.664293 -279.712466)
			(xy 116.701016 -279.749189) (xy 116.731542 -279.791205) (xy 116.75512 -279.837479) (xy 116.771168 -279.886872)
			(xy 116.779293 -279.938167) (xy 116.779802 -279.964134) (xy 116.779293 -279.990101) (xy 116.771168 -280.041396)
			(xy 116.75512 -280.090789) (xy 116.731542 -280.137063) (xy 116.701016 -280.179079) (xy 116.664293 -280.215802)
			(xy 116.622277 -280.246328) (xy 116.576003 -280.269906) (xy 116.52661 -280.285954) (xy 116.475315 -280.294079)
			(xy 116.423381 -280.294079) (xy 116.372086 -280.285954) (xy 116.322693 -280.269906) (xy 116.276419 -280.246328)
			(xy 116.234403 -280.215802) (xy 116.19768 -280.179079) (xy 116.167154 -280.137063) (xy 116.143576 -280.090789)
			(xy 116.127528 -280.041396) (xy 116.119403 -279.990101) (xy 113.959639 -279.990101) (xy 113.951514 -280.041396)
			(xy 113.935466 -280.090789) (xy 113.911888 -280.137063) (xy 113.881362 -280.179079) (xy 113.844639 -280.215802)
			(xy 113.802623 -280.246328) (xy 113.756349 -280.269906) (xy 113.706956 -280.285954) (xy 113.655661 -280.294079)
			(xy 113.603727 -280.294079) (xy 113.552432 -280.285954) (xy 113.503039 -280.269906) (xy 113.456765 -280.246328)
			(xy 113.414749 -280.215802) (xy 113.378026 -280.179079) (xy 113.3475 -280.137063) (xy 113.323922 -280.090789)
			(xy 113.307874 -280.041396) (xy 113.299749 -279.990101) (xy 108.333735 -279.990101) (xy 108.319316 -280.00452)
			(xy 108.316522 -280.020522) (xy 108.311734 -280.045444) (xy 108.295527 -280.093535) (xy 108.27216 -280.138583)
			(xy 108.24218 -280.179529) (xy 108.206293 -280.21541) (xy 108.165343 -280.245384) (xy 108.120292 -280.268745)
			(xy 108.072199 -280.284945) (xy 108.047282 -280.289762) (xy 108.03128 -280.292556) (xy 107.768644 -280.555192)
			(xy 107.792774 -280.590244) (xy 107.806622 -280.611071) (xy 107.828552 -280.656019) (xy 107.843461 -280.703758)
			(xy 107.85101 -280.753198) (xy 107.851448 -280.778204) (xy 107.850965 -280.804171) (xy 110.010449 -280.804171)
			(xy 110.010449 -280.752237) (xy 110.018574 -280.700942) (xy 110.034622 -280.651549) (xy 110.0582 -280.605275)
			(xy 110.088726 -280.563259) (xy 110.125449 -280.526536) (xy 110.167465 -280.49601) (xy 110.213739 -280.472432)
			(xy 110.263132 -280.456384) (xy 110.314427 -280.448259) (xy 110.366361 -280.448259) (xy 110.417656 -280.456384)
			(xy 110.467049 -280.472432) (xy 110.513323 -280.49601) (xy 110.555339 -280.526536) (xy 110.592062 -280.563259)
			(xy 110.622588 -280.605275) (xy 110.646166 -280.651549) (xy 110.662214 -280.700942) (xy 110.670339 -280.752237)
			(xy 110.670848 -280.778204) (xy 110.670339 -280.804171) (xy 116.589303 -280.804171) (xy 116.589303 -280.752237)
			(xy 116.597428 -280.700942) (xy 116.613476 -280.651549) (xy 116.637054 -280.605275) (xy 116.66758 -280.563259)
			(xy 116.704303 -280.526536) (xy 116.746319 -280.49601) (xy 116.792593 -280.472432) (xy 116.841986 -280.456384)
			(xy 116.893281 -280.448259) (xy 116.945215 -280.448259) (xy 116.99651 -280.456384) (xy 117.045903 -280.472432)
			(xy 117.092177 -280.49601) (xy 117.134193 -280.526536) (xy 117.170916 -280.563259) (xy 117.201442 -280.605275)
			(xy 117.22502 -280.651549) (xy 117.241068 -280.700942) (xy 117.249193 -280.752237) (xy 117.249702 -280.778204)
			(xy 117.249193 -280.804171) (xy 117.241068 -280.855466) (xy 117.22502 -280.904859) (xy 117.201442 -280.951133)
			(xy 117.170916 -280.993149) (xy 117.134193 -281.029872) (xy 117.092177 -281.060398) (xy 117.045903 -281.083976)
			(xy 116.99651 -281.100024) (xy 116.945215 -281.108149) (xy 116.893281 -281.108149) (xy 116.841986 -281.100024)
			(xy 116.792593 -281.083976) (xy 116.746319 -281.060398) (xy 116.704303 -281.029872) (xy 116.66758 -280.993149)
			(xy 116.637054 -280.951133) (xy 116.613476 -280.904859) (xy 116.597428 -280.855466) (xy 116.589303 -280.804171)
			(xy 110.670339 -280.804171) (xy 110.662214 -280.855466) (xy 110.646166 -280.904859) (xy 110.622588 -280.951133)
			(xy 110.592062 -280.993149) (xy 110.555339 -281.029872) (xy 110.513323 -281.060398) (xy 110.467049 -281.083976)
			(xy 110.417656 -281.100024) (xy 110.366361 -281.108149) (xy 110.314427 -281.108149) (xy 110.263132 -281.100024)
			(xy 110.213739 -281.083976) (xy 110.167465 -281.060398) (xy 110.125449 -281.029872) (xy 110.088726 -280.993149)
			(xy 110.0582 -280.951133) (xy 110.034622 -280.904859) (xy 110.018574 -280.855466) (xy 110.010449 -280.804171)
			(xy 107.850965 -280.804171) (xy 107.850965 -280.804173) (xy 107.842839 -280.855471) (xy 107.826789 -280.904867)
			(xy 107.803209 -280.951143) (xy 107.77268 -280.993162) (xy 107.735954 -281.029887) (xy 107.693935 -281.060414)
			(xy 107.647658 -281.083993) (xy 107.598261 -281.100042) (xy 107.546963 -281.108166) (xy 107.520994 -281.108658)
			(xy 107.495989 -281.108197) (xy 107.44655 -281.100658) (xy 107.398812 -281.085754) (xy 107.353865 -281.063824)
			(xy 107.333034 -281.049984) (xy 107.297982 -281.025854) (xy 107.18419 -281.139646) (xy 107.174915 -281.149515)
			(xy 107.161471 -281.173014) (xy 107.154678 -281.199221) (xy 107.155014 -281.226292) (xy 107.162456 -281.252323)
			(xy 107.17648 -281.27548) (xy 107.196099 -281.294137) (xy 107.207812 -281.300936) (xy 107.230009 -281.313397)
			(xy 107.270622 -281.344084) (xy 107.306049 -281.380636) (xy 107.335451 -281.422188) (xy 107.358133 -281.467758)
			(xy 107.373558 -281.516268) (xy 107.381361 -281.566569) (xy 107.381802 -281.59202) (xy 107.381291 -281.617987)
			(xy 113.299749 -281.617987) (xy 113.299749 -281.566053) (xy 113.307874 -281.514758) (xy 113.323922 -281.465365)
			(xy 113.3475 -281.419091) (xy 113.378026 -281.377075) (xy 113.414749 -281.340352) (xy 113.456765 -281.309826)
			(xy 113.503039 -281.286248) (xy 113.552432 -281.2702) (xy 113.603727 -281.262075) (xy 113.655661 -281.262075)
			(xy 113.706956 -281.2702) (xy 113.756349 -281.286248) (xy 113.802623 -281.309826) (xy 113.844639 -281.340352)
			(xy 113.881362 -281.377075) (xy 113.911888 -281.419091) (xy 113.935466 -281.465365) (xy 113.951514 -281.514758)
			(xy 113.959639 -281.566053) (xy 113.960148 -281.59202) (xy 113.959639 -281.617987) (xy 113.951514 -281.669282)
			(xy 113.935466 -281.718675) (xy 113.911888 -281.764949) (xy 113.881362 -281.806965) (xy 113.844639 -281.843688)
			(xy 113.802623 -281.874214) (xy 113.756349 -281.897792) (xy 113.706956 -281.91384) (xy 113.655661 -281.921965)
			(xy 113.603727 -281.921965) (xy 113.552432 -281.91384) (xy 113.503039 -281.897792) (xy 113.456765 -281.874214)
			(xy 113.414749 -281.843688) (xy 113.378026 -281.806965) (xy 113.3475 -281.764949) (xy 113.323922 -281.718675)
			(xy 113.307874 -281.669282) (xy 113.299749 -281.617987) (xy 107.381291 -281.617987) (xy 107.381291 -281.617988)
			(xy 107.373165 -281.669283) (xy 107.357115 -281.718676) (xy 107.333537 -281.764951) (xy 107.303011 -281.806968)
			(xy 107.266289 -281.843693) (xy 107.224274 -281.874222) (xy 107.178002 -281.897804) (xy 107.12861 -281.913858)
			(xy 107.077316 -281.921989) (xy 107.051348 -281.922474) (xy 107.0259 -281.922001) (xy 106.975608 -281.91419)
			(xy 106.927108 -281.898761) (xy 106.881546 -281.876079) (xy 106.840001 -281.846679) (xy 106.803455 -281.811258)
			(xy 106.772771 -281.770652) (xy 106.760264 -281.748484) (xy 106.753461 -281.736777) (xy 106.734795 -281.717174)
			(xy 106.711637 -281.703162) (xy 106.685611 -281.695724) (xy 106.658545 -281.695383) (xy 106.63234 -281.702161)
			(xy 106.608835 -281.715584) (xy 106.598974 -281.724862) (xy 106.482896 -281.84094) (xy 106.61904 -282.076652)
			(xy 106.642154 -282.08097) (xy 106.667085 -282.08612) (xy 106.715089 -282.10306) (xy 106.759927 -282.127163)
			(xy 106.800538 -282.157858) (xy 106.835959 -282.194419) (xy 106.865353 -282.235981) (xy 106.888024 -282.28156)
			(xy 106.903436 -282.330076) (xy 106.911224 -282.380383) (xy 106.911648 -282.405836) (xy 106.911139 -282.431803)
			(xy 107.191049 -282.431803) (xy 107.191049 -282.379869) (xy 107.199174 -282.328574) (xy 107.215222 -282.279181)
			(xy 107.2388 -282.232907) (xy 107.269326 -282.190891) (xy 107.306049 -282.154168) (xy 107.348065 -282.123642)
			(xy 107.394339 -282.100064) (xy 107.443732 -282.084016) (xy 107.495027 -282.075891) (xy 107.546961 -282.075891)
			(xy 107.598256 -282.084016) (xy 107.647649 -282.100064) (xy 107.693923 -282.123642) (xy 107.735939 -282.154168)
			(xy 107.772662 -282.190891) (xy 107.803188 -282.232907) (xy 107.826766 -282.279181) (xy 107.842814 -282.328574)
			(xy 107.850939 -282.379869) (xy 107.851448 -282.405836) (xy 107.850939 -282.431803) (xy 110.010449 -282.431803)
			(xy 110.010449 -282.379869) (xy 110.018574 -282.328574) (xy 110.034622 -282.279181) (xy 110.0582 -282.232907)
			(xy 110.088726 -282.190891) (xy 110.125449 -282.154168) (xy 110.167465 -282.123642) (xy 110.213739 -282.100064)
			(xy 110.263132 -282.084016) (xy 110.314427 -282.075891) (xy 110.366361 -282.075891) (xy 110.417656 -282.084016)
			(xy 110.467049 -282.100064) (xy 110.513323 -282.123642) (xy 110.555339 -282.154168) (xy 110.592062 -282.190891)
			(xy 110.622588 -282.232907) (xy 110.646166 -282.279181) (xy 110.662214 -282.328574) (xy 110.670339 -282.379869)
			(xy 110.670848 -282.405836) (xy 110.670339 -282.431803) (xy 110.662214 -282.483098) (xy 110.646166 -282.532491)
			(xy 110.622588 -282.578765) (xy 110.592062 -282.620781) (xy 110.555339 -282.657504) (xy 110.513323 -282.68803)
			(xy 110.467049 -282.711608) (xy 110.417656 -282.727656) (xy 110.366361 -282.735781) (xy 110.314427 -282.735781)
			(xy 110.263132 -282.727656) (xy 110.213739 -282.711608) (xy 110.167465 -282.68803) (xy 110.125449 -282.657504)
			(xy 110.088726 -282.620781) (xy 110.0582 -282.578765) (xy 110.034622 -282.532491) (xy 110.018574 -282.483098)
			(xy 110.010449 -282.431803) (xy 107.850939 -282.431803) (xy 107.842814 -282.483098) (xy 107.826766 -282.532491)
			(xy 107.803188 -282.578765) (xy 107.772662 -282.620781) (xy 107.735939 -282.657504) (xy 107.693923 -282.68803)
			(xy 107.647649 -282.711608) (xy 107.598256 -282.727656) (xy 107.546961 -282.735781) (xy 107.495027 -282.735781)
			(xy 107.443732 -282.727656) (xy 107.394339 -282.711608) (xy 107.348065 -282.68803) (xy 107.306049 -282.657504)
			(xy 107.269326 -282.620781) (xy 107.2388 -282.578765) (xy 107.215222 -282.532491) (xy 107.199174 -282.483098)
			(xy 107.191049 -282.431803) (xy 106.911139 -282.431803) (xy 106.903014 -282.483098) (xy 106.886966 -282.532491)
			(xy 106.863388 -282.578765) (xy 106.832862 -282.620781) (xy 106.796139 -282.657504) (xy 106.754123 -282.68803)
			(xy 106.707849 -282.711608) (xy 106.658456 -282.727656) (xy 106.607161 -282.735781) (xy 106.555227 -282.735781)
			(xy 106.503932 -282.727656) (xy 106.454539 -282.711608) (xy 106.408265 -282.68803) (xy 106.366249 -282.657504)
			(xy 106.329526 -282.620781) (xy 106.299 -282.578765) (xy 106.275422 -282.532491) (xy 106.259374 -282.483098)
			(xy 106.251249 -282.431803) (xy 106.25074 -282.405836) (xy 106.25135 -282.377855) (xy 106.260797 -282.322696)
			(xy 106.269536 -282.296108) (xy 106.277156 -282.27401) (xy 106.260138 -282.244546) (xy 106.253096 -282.233242)
			(xy 106.23426 -282.214428) (xy 106.211202 -282.20112) (xy 106.185489 -282.194222) (xy 106.158866 -282.194202)
			(xy 106.133143 -282.20106) (xy 106.110065 -282.214333) (xy 106.100372 -282.223464) (xy 105.9688 -282.355036)
			(xy 105.970832 -282.378404) (xy 105.971848 -282.405836) (xy 105.971385 -282.431274) (xy 105.9636 -282.48155)
			(xy 105.948203 -282.530039) (xy 105.925559 -282.575597) (xy 105.896201 -282.617147) (xy 105.860824 -282.653709)
			(xy 105.820263 -282.684418) (xy 105.775476 -282.70855) (xy 105.727519 -282.725535) (xy 105.702608 -282.730702)
			(xy 105.679494 -282.73502) (xy 105.475786 -283.08808) (xy 105.483406 -283.110178) (xy 105.492199 -283.136752)
			(xy 105.501648 -283.19192) (xy 105.502202 -283.219906) (xy 105.501692 -283.245873) (xy 105.781349 -283.245873)
			(xy 105.781349 -283.193939) (xy 105.789474 -283.142644) (xy 105.805522 -283.093251) (xy 105.8291 -283.046977)
			(xy 105.859626 -283.004961) (xy 105.896349 -282.968238) (xy 105.938365 -282.937712) (xy 105.984639 -282.914134)
			(xy 106.034032 -282.898086) (xy 106.085327 -282.889961) (xy 106.137261 -282.889961) (xy 106.188556 -282.898086)
			(xy 106.237949 -282.914134) (xy 106.284223 -282.937712) (xy 106.326239 -282.968238) (xy 106.362962 -283.004961)
			(xy 106.393488 -283.046977) (xy 106.417066 -283.093251) (xy 106.433114 -283.142644) (xy 106.441239 -283.193939)
			(xy 106.441748 -283.219906) (xy 106.441239 -283.245873) (xy 106.721403 -283.245873) (xy 106.721403 -283.193939)
			(xy 106.729528 -283.142644) (xy 106.745576 -283.093251) (xy 106.769154 -283.046977) (xy 106.79968 -283.004961)
			(xy 106.836403 -282.968238) (xy 106.878419 -282.937712) (xy 106.924693 -282.914134) (xy 106.974086 -282.898086)
			(xy 107.025381 -282.889961) (xy 107.077315 -282.889961) (xy 107.12861 -282.898086) (xy 107.178003 -282.914134)
			(xy 107.224277 -282.937712) (xy 107.266293 -282.968238) (xy 107.303016 -283.004961) (xy 107.333542 -283.046977)
			(xy 107.35712 -283.093251) (xy 107.373168 -283.142644) (xy 107.381293 -283.193939) (xy 107.381802 -283.219906)
			(xy 107.381293 -283.245873) (xy 113.299749 -283.245873) (xy 113.299749 -283.193939) (xy 113.307874 -283.142644)
			(xy 113.323922 -283.093251) (xy 113.3475 -283.046977) (xy 113.378026 -283.004961) (xy 113.414749 -282.968238)
			(xy 113.456765 -282.937712) (xy 113.503039 -282.914134) (xy 113.552432 -282.898086) (xy 113.603727 -282.889961)
			(xy 113.655661 -282.889961) (xy 113.706956 -282.898086) (xy 113.756349 -282.914134) (xy 113.802623 -282.937712)
			(xy 113.844639 -282.968238) (xy 113.881362 -283.004961) (xy 113.911888 -283.046977) (xy 113.935466 -283.093251)
			(xy 113.951514 -283.142644) (xy 113.959639 -283.193939) (xy 113.960148 -283.219906) (xy 113.959639 -283.245873)
			(xy 116.119403 -283.245873) (xy 116.119403 -283.193939) (xy 116.127528 -283.142644) (xy 116.143576 -283.093251)
			(xy 116.167154 -283.046977) (xy 116.19768 -283.004961) (xy 116.234403 -282.968238) (xy 116.276419 -282.937712)
			(xy 116.322693 -282.914134) (xy 116.372086 -282.898086) (xy 116.423381 -282.889961) (xy 116.475315 -282.889961)
			(xy 116.52661 -282.898086) (xy 116.576003 -282.914134) (xy 116.622277 -282.937712) (xy 116.664293 -282.968238)
			(xy 116.701016 -283.004961) (xy 116.731542 -283.046977) (xy 116.75512 -283.093251) (xy 116.771168 -283.142644)
			(xy 116.779293 -283.193939) (xy 116.779802 -283.219906) (xy 116.779293 -283.245873) (xy 116.771168 -283.297168)
			(xy 116.75512 -283.346561) (xy 116.731542 -283.392835) (xy 116.701016 -283.434851) (xy 116.664293 -283.471574)
			(xy 116.622277 -283.5021) (xy 116.576003 -283.525678) (xy 116.52661 -283.541726) (xy 116.475315 -283.549851)
			(xy 116.423381 -283.549851) (xy 116.372086 -283.541726) (xy 116.322693 -283.525678) (xy 116.276419 -283.5021)
			(xy 116.234403 -283.471574) (xy 116.19768 -283.434851) (xy 116.167154 -283.392835) (xy 116.143576 -283.346561)
			(xy 116.127528 -283.297168) (xy 116.119403 -283.245873) (xy 113.959639 -283.245873) (xy 113.951514 -283.297168)
			(xy 113.935466 -283.346561) (xy 113.911888 -283.392835) (xy 113.881362 -283.434851) (xy 113.844639 -283.471574)
			(xy 113.802623 -283.5021) (xy 113.756349 -283.525678) (xy 113.706956 -283.541726) (xy 113.655661 -283.549851)
			(xy 113.603727 -283.549851) (xy 113.552432 -283.541726) (xy 113.503039 -283.525678) (xy 113.456765 -283.5021)
			(xy 113.414749 -283.471574) (xy 113.378026 -283.434851) (xy 113.3475 -283.392835) (xy 113.323922 -283.346561)
			(xy 113.307874 -283.297168) (xy 113.299749 -283.245873) (xy 107.381293 -283.245873) (xy 107.373168 -283.297168)
			(xy 107.35712 -283.346561) (xy 107.333542 -283.392835) (xy 107.303016 -283.434851) (xy 107.266293 -283.471574)
			(xy 107.224277 -283.5021) (xy 107.178003 -283.525678) (xy 107.12861 -283.541726) (xy 107.077315 -283.549851)
			(xy 107.025381 -283.549851) (xy 106.974086 -283.541726) (xy 106.924693 -283.525678) (xy 106.878419 -283.5021)
			(xy 106.836403 -283.471574) (xy 106.79968 -283.434851) (xy 106.769154 -283.392835) (xy 106.745576 -283.346561)
			(xy 106.729528 -283.297168) (xy 106.721403 -283.245873) (xy 106.441239 -283.245873) (xy 106.433114 -283.297168)
			(xy 106.417066 -283.346561) (xy 106.393488 -283.392835) (xy 106.362962 -283.434851) (xy 106.326239 -283.471574)
			(xy 106.284223 -283.5021) (xy 106.237949 -283.525678) (xy 106.188556 -283.541726) (xy 106.137261 -283.549851)
			(xy 106.085327 -283.549851) (xy 106.034032 -283.541726) (xy 105.984639 -283.525678) (xy 105.938365 -283.5021)
			(xy 105.896349 -283.471574) (xy 105.859626 -283.434851) (xy 105.8291 -283.392835) (xy 105.805522 -283.346561)
			(xy 105.789474 -283.297168) (xy 105.781349 -283.245873) (xy 105.501692 -283.245873) (xy 105.501692 -283.245874)
			(xy 105.493568 -283.297171) (xy 105.477519 -283.346566) (xy 105.453942 -283.392843) (xy 105.423416 -283.434862)
			(xy 105.386694 -283.471589) (xy 105.344679 -283.50212) (xy 105.298405 -283.525703) (xy 105.249012 -283.541758)
			(xy 105.197716 -283.549889) (xy 105.171748 -283.55036) (xy 105.144062 -283.54909) (xy 105.130034 -283.548367)
			(xy 105.102474 -283.553739) (xy 105.07742 -283.566416) (xy 105.056768 -283.585439) (xy 105.04208 -283.609369)
			(xy 105.034466 -283.636396) (xy 105.03408 -283.650436) (xy 105.03408 -284.059689) (xy 105.311449 -284.059689)
			(xy 105.311449 -284.007755) (xy 105.319574 -283.95646) (xy 105.335622 -283.907067) (xy 105.3592 -283.860793)
			(xy 105.389726 -283.818777) (xy 105.426449 -283.782054) (xy 105.468465 -283.751528) (xy 105.514739 -283.72795)
			(xy 105.564132 -283.711902) (xy 105.615427 -283.703777) (xy 105.667361 -283.703777) (xy 105.718656 -283.711902)
			(xy 105.768049 -283.72795) (xy 105.814323 -283.751528) (xy 105.856339 -283.782054) (xy 105.893062 -283.818777)
			(xy 105.923588 -283.860793) (xy 105.947166 -283.907067) (xy 105.963214 -283.95646) (xy 105.971339 -284.007755)
			(xy 105.971848 -284.033722) (xy 105.971339 -284.059689) (xy 107.191049 -284.059689) (xy 107.191049 -284.007755)
			(xy 107.199174 -283.95646) (xy 107.215222 -283.907067) (xy 107.2388 -283.860793) (xy 107.269326 -283.818777)
			(xy 107.306049 -283.782054) (xy 107.348065 -283.751528) (xy 107.394339 -283.72795) (xy 107.443732 -283.711902)
			(xy 107.495027 -283.703777) (xy 107.546961 -283.703777) (xy 107.598256 -283.711902) (xy 107.647649 -283.72795)
			(xy 107.693923 -283.751528) (xy 107.735939 -283.782054) (xy 107.772662 -283.818777) (xy 107.803188 -283.860793)
			(xy 107.826766 -283.907067) (xy 107.842814 -283.95646) (xy 107.850939 -284.007755) (xy 107.851448 -284.033722)
			(xy 107.850939 -284.059689) (xy 110.010449 -284.059689) (xy 110.010449 -284.007755) (xy 110.018574 -283.95646)
			(xy 110.034622 -283.907067) (xy 110.0582 -283.860793) (xy 110.088726 -283.818777) (xy 110.125449 -283.782054)
			(xy 110.167465 -283.751528) (xy 110.213739 -283.72795) (xy 110.263132 -283.711902) (xy 110.314427 -283.703777)
			(xy 110.366361 -283.703777) (xy 110.417656 -283.711902) (xy 110.467049 -283.72795) (xy 110.513323 -283.751528)
			(xy 110.555339 -283.782054) (xy 110.592062 -283.818777) (xy 110.622588 -283.860793) (xy 110.646166 -283.907067)
			(xy 110.662214 -283.95646) (xy 110.670339 -284.007755) (xy 110.670848 -284.033722) (xy 110.670339 -284.059689)
			(xy 110.662214 -284.110984) (xy 110.646166 -284.160377) (xy 110.622588 -284.206651) (xy 110.592062 -284.248667)
			(xy 110.555339 -284.28539) (xy 110.513323 -284.315916) (xy 110.467049 -284.339494) (xy 110.417656 -284.355542)
			(xy 110.366361 -284.363667) (xy 110.314427 -284.363667) (xy 110.263132 -284.355542) (xy 110.213739 -284.339494)
			(xy 110.167465 -284.315916) (xy 110.125449 -284.28539) (xy 110.088726 -284.248667) (xy 110.0582 -284.206651)
			(xy 110.034622 -284.160377) (xy 110.018574 -284.110984) (xy 110.010449 -284.059689) (xy 107.850939 -284.059689)
			(xy 107.842814 -284.110984) (xy 107.826766 -284.160377) (xy 107.803188 -284.206651) (xy 107.772662 -284.248667)
			(xy 107.735939 -284.28539) (xy 107.693923 -284.315916) (xy 107.647649 -284.339494) (xy 107.598256 -284.355542)
			(xy 107.546961 -284.363667) (xy 107.495027 -284.363667) (xy 107.443732 -284.355542) (xy 107.394339 -284.339494)
			(xy 107.348065 -284.315916) (xy 107.306049 -284.28539) (xy 107.269326 -284.248667) (xy 107.2388 -284.206651)
			(xy 107.215222 -284.160377) (xy 107.199174 -284.110984) (xy 107.191049 -284.059689) (xy 105.971339 -284.059689)
			(xy 105.963214 -284.110984) (xy 105.947166 -284.160377) (xy 105.923588 -284.206651) (xy 105.893062 -284.248667)
			(xy 105.856339 -284.28539) (xy 105.814323 -284.315916) (xy 105.768049 -284.339494) (xy 105.718656 -284.355542)
			(xy 105.667361 -284.363667) (xy 105.615427 -284.363667) (xy 105.564132 -284.355542) (xy 105.514739 -284.339494)
			(xy 105.468465 -284.315916) (xy 105.426449 -284.28539) (xy 105.389726 -284.248667) (xy 105.3592 -284.206651)
			(xy 105.335622 -284.160377) (xy 105.319574 -284.110984) (xy 105.311449 -284.059689) (xy 105.03408 -284.059689)
			(xy 105.03408 -284.321504) (xy 105.054079 -284.352619) (xy 105.089783 -284.417402) (xy 105.120395 -284.484742)
			(xy 105.133394 -284.51937) (xy 105.142884 -284.518314) (xy 105.161946 -284.517169) (xy 105.171494 -284.517084)
			(xy 105.197463 -284.517566) (xy 105.24876 -284.525691) (xy 105.298155 -284.541741) (xy 105.344431 -284.565321)
			(xy 105.386448 -284.59585) (xy 105.423171 -284.632577) (xy 105.453696 -284.674597) (xy 105.477272 -284.720875)
			(xy 105.493317 -284.770271) (xy 105.501436 -284.821569) (xy 105.501948 -284.847538) (xy 105.501504 -284.872002)
			(xy 105.50128 -284.873505) (xy 113.299749 -284.873505) (xy 113.299749 -284.821571) (xy 113.307874 -284.770276)
			(xy 113.323922 -284.720883) (xy 113.3475 -284.674609) (xy 113.378026 -284.632593) (xy 113.414749 -284.59587)
			(xy 113.456765 -284.565344) (xy 113.503039 -284.541766) (xy 113.552432 -284.525718) (xy 113.603727 -284.517593)
			(xy 113.655661 -284.517593) (xy 113.706956 -284.525718) (xy 113.756349 -284.541766) (xy 113.802623 -284.565344)
			(xy 113.844639 -284.59587) (xy 113.881362 -284.632593) (xy 113.911888 -284.674609) (xy 113.935466 -284.720883)
			(xy 113.951514 -284.770276) (xy 113.959639 -284.821571) (xy 113.960148 -284.847538) (xy 113.959639 -284.873505)
			(xy 116.119403 -284.873505) (xy 116.119403 -284.821571) (xy 116.127528 -284.770276) (xy 116.143576 -284.720883)
			(xy 116.167154 -284.674609) (xy 116.19768 -284.632593) (xy 116.234403 -284.59587) (xy 116.276419 -284.565344)
			(xy 116.322693 -284.541766) (xy 116.372086 -284.525718) (xy 116.423381 -284.517593) (xy 116.475315 -284.517593)
			(xy 116.52661 -284.525718) (xy 116.576003 -284.541766) (xy 116.622277 -284.565344) (xy 116.664293 -284.59587)
			(xy 116.701016 -284.632593) (xy 116.731542 -284.674609) (xy 116.75512 -284.720883) (xy 116.771168 -284.770276)
			(xy 116.779293 -284.821571) (xy 116.779802 -284.847538) (xy 116.779293 -284.873505) (xy 116.771168 -284.9248)
			(xy 116.75512 -284.974193) (xy 116.731542 -285.020467) (xy 116.701016 -285.062483) (xy 116.664293 -285.099206)
			(xy 116.622277 -285.129732) (xy 116.576003 -285.15331) (xy 116.52661 -285.169358) (xy 116.475315 -285.177483)
			(xy 116.423381 -285.177483) (xy 116.372086 -285.169358) (xy 116.322693 -285.15331) (xy 116.276419 -285.129732)
			(xy 116.234403 -285.099206) (xy 116.19768 -285.062483) (xy 116.167154 -285.020467) (xy 116.143576 -284.974193)
			(xy 116.127528 -284.9248) (xy 116.119403 -284.873505) (xy 113.959639 -284.873505) (xy 113.951514 -284.9248)
			(xy 113.935466 -284.974193) (xy 113.911888 -285.020467) (xy 113.881362 -285.062483) (xy 113.844639 -285.099206)
			(xy 113.802623 -285.129732) (xy 113.756349 -285.15331) (xy 113.706956 -285.169358) (xy 113.655661 -285.177483)
			(xy 113.603727 -285.177483) (xy 113.552432 -285.169358) (xy 113.503039 -285.15331) (xy 113.456765 -285.129732)
			(xy 113.414749 -285.099206) (xy 113.378026 -285.062483) (xy 113.3475 -285.020467) (xy 113.323922 -284.974193)
			(xy 113.307874 -284.9248) (xy 113.299749 -284.873505) (xy 105.50128 -284.873505) (xy 105.494288 -284.920396)
			(xy 105.480018 -284.967198) (xy 105.459008 -285.011387) (xy 105.431715 -285.051996) (xy 105.398736 -285.08814)
			(xy 105.36079 -285.11903) (xy 105.318706 -285.14399) (xy 105.296208 -285.153608) (xy 105.282825 -285.15961)
			(xy 105.259958 -285.177961) (xy 105.24323 -285.202041) (xy 105.234015 -285.229875) (xy 105.233068 -285.259179)
			(xy 105.236264 -285.273496) (xy 105.250611 -285.330221) (xy 105.271598 -285.445341) (xy 105.283691 -285.561733)
			(xy 105.285794 -285.620206) (xy 105.286048 -285.64586) (xy 105.286048 -285.679896) (xy 105.285928 -285.687321)
			(xy 107.191049 -285.687321) (xy 107.191049 -285.635387) (xy 107.199174 -285.584092) (xy 107.215222 -285.534699)
			(xy 107.2388 -285.488425) (xy 107.269326 -285.446409) (xy 107.306049 -285.409686) (xy 107.348065 -285.37916)
			(xy 107.394339 -285.355582) (xy 107.443732 -285.339534) (xy 107.495027 -285.331409) (xy 107.546961 -285.331409)
			(xy 107.598256 -285.339534) (xy 107.647649 -285.355582) (xy 107.693923 -285.37916) (xy 107.735939 -285.409686)
			(xy 107.772662 -285.446409) (xy 107.803188 -285.488425) (xy 107.826766 -285.534699) (xy 107.842814 -285.584092)
			(xy 107.850939 -285.635387) (xy 107.851448 -285.661354) (xy 107.850939 -285.687321) (xy 110.010449 -285.687321)
			(xy 110.010449 -285.635387) (xy 110.018574 -285.584092) (xy 110.034622 -285.534699) (xy 110.0582 -285.488425)
			(xy 110.088726 -285.446409) (xy 110.125449 -285.409686) (xy 110.167465 -285.37916) (xy 110.213739 -285.355582)
			(xy 110.263132 -285.339534) (xy 110.314427 -285.331409) (xy 110.366361 -285.331409) (xy 110.417656 -285.339534)
			(xy 110.467049 -285.355582) (xy 110.513323 -285.37916) (xy 110.555339 -285.409686) (xy 110.592062 -285.446409)
			(xy 110.622588 -285.488425) (xy 110.646166 -285.534699) (xy 110.662214 -285.584092) (xy 110.670339 -285.635387)
			(xy 110.670848 -285.661354) (xy 110.670339 -285.687321) (xy 110.662214 -285.738616) (xy 110.646166 -285.788009)
			(xy 110.622588 -285.834283) (xy 110.592062 -285.876299) (xy 110.555339 -285.913022) (xy 110.513323 -285.943548)
			(xy 110.467049 -285.967126) (xy 110.417656 -285.983174) (xy 110.366361 -285.991299) (xy 110.314427 -285.991299)
			(xy 110.263132 -285.983174) (xy 110.213739 -285.967126) (xy 110.167465 -285.943548) (xy 110.125449 -285.913022)
			(xy 110.088726 -285.876299) (xy 110.0582 -285.834283) (xy 110.034622 -285.788009) (xy 110.018574 -285.738616)
			(xy 110.010449 -285.687321) (xy 107.850939 -285.687321) (xy 107.842814 -285.738616) (xy 107.826766 -285.788009)
			(xy 107.803188 -285.834283) (xy 107.772662 -285.876299) (xy 107.735939 -285.913022) (xy 107.693923 -285.943548)
			(xy 107.647649 -285.967126) (xy 107.598256 -285.983174) (xy 107.546961 -285.991299) (xy 107.495027 -285.991299)
			(xy 107.443732 -285.983174) (xy 107.394339 -285.967126) (xy 107.348065 -285.943548) (xy 107.306049 -285.913022)
			(xy 107.269326 -285.876299) (xy 107.2388 -285.834283) (xy 107.215222 -285.788009) (xy 107.199174 -285.738616)
			(xy 107.191049 -285.687321) (xy 105.285928 -285.687321) (xy 105.28554 -285.711392) (xy 105.283165 -285.768413)
			(xy 105.27094 -285.881892) (xy 105.250269 -285.994141) (xy 105.236264 -286.049466) (xy 105.232982 -286.063778)
			(xy 105.233868 -286.093114) (xy 105.243081 -286.120981) (xy 105.259855 -286.145065) (xy 105.282799 -286.163367)
			(xy 105.296208 -286.169354) (xy 105.318713 -286.178985) (xy 105.36084 -286.203912) (xy 105.39883 -286.23478)
			(xy 105.431851 -286.270914) (xy 105.459182 -286.311523) (xy 105.480224 -286.35572) (xy 105.494517 -286.402536)
			(xy 105.501748 -286.450949) (xy 105.502202 -286.475424) (xy 105.501691 -286.501391) (xy 113.299749 -286.501391)
			(xy 113.299749 -286.449457) (xy 113.307874 -286.398162) (xy 113.323922 -286.348769) (xy 113.3475 -286.302495)
			(xy 113.378026 -286.260479) (xy 113.414749 -286.223756) (xy 113.456765 -286.19323) (xy 113.503039 -286.169652)
			(xy 113.552432 -286.153604) (xy 113.603727 -286.145479) (xy 113.655661 -286.145479) (xy 113.706956 -286.153604)
			(xy 113.756349 -286.169652) (xy 113.802623 -286.19323) (xy 113.844639 -286.223756) (xy 113.881362 -286.260479)
			(xy 113.911888 -286.302495) (xy 113.935466 -286.348769) (xy 113.951514 -286.398162) (xy 113.959639 -286.449457)
			(xy 113.960148 -286.475424) (xy 113.959639 -286.501391) (xy 116.119403 -286.501391) (xy 116.119403 -286.449457)
			(xy 116.127528 -286.398162) (xy 116.143576 -286.348769) (xy 116.167154 -286.302495) (xy 116.19768 -286.260479)
			(xy 116.234403 -286.223756) (xy 116.276419 -286.19323) (xy 116.322693 -286.169652) (xy 116.372086 -286.153604)
			(xy 116.423381 -286.145479) (xy 116.475315 -286.145479) (xy 116.52661 -286.153604) (xy 116.576003 -286.169652)
			(xy 116.622277 -286.19323) (xy 116.664293 -286.223756) (xy 116.701016 -286.260479) (xy 116.731542 -286.302495)
			(xy 116.75512 -286.348769) (xy 116.771168 -286.398162) (xy 116.779293 -286.449457) (xy 116.779802 -286.475424)
			(xy 116.779293 -286.501391) (xy 116.771168 -286.552686) (xy 116.75512 -286.602079) (xy 116.731542 -286.648353)
			(xy 116.701016 -286.690369) (xy 116.664293 -286.727092) (xy 116.622277 -286.757618) (xy 116.576003 -286.781196)
			(xy 116.52661 -286.797244) (xy 116.475315 -286.805369) (xy 116.423381 -286.805369) (xy 116.372086 -286.797244)
			(xy 116.322693 -286.781196) (xy 116.276419 -286.757618) (xy 116.234403 -286.727092) (xy 116.19768 -286.690369)
			(xy 116.167154 -286.648353) (xy 116.143576 -286.602079) (xy 116.127528 -286.552686) (xy 116.119403 -286.501391)
			(xy 113.959639 -286.501391) (xy 113.951514 -286.552686) (xy 113.935466 -286.602079) (xy 113.911888 -286.648353)
			(xy 113.881362 -286.690369) (xy 113.844639 -286.727092) (xy 113.802623 -286.757618) (xy 113.756349 -286.781196)
			(xy 113.706956 -286.797244) (xy 113.655661 -286.805369) (xy 113.603727 -286.805369) (xy 113.552432 -286.797244)
			(xy 113.503039 -286.781196) (xy 113.456765 -286.757618) (xy 113.414749 -286.727092) (xy 113.378026 -286.690369)
			(xy 113.3475 -286.648353) (xy 113.323922 -286.602079) (xy 113.307874 -286.552686) (xy 113.299749 -286.501391)
			(xy 105.501691 -286.501391) (xy 105.493564 -286.552686) (xy 105.477514 -286.602079) (xy 105.453936 -286.648353)
			(xy 105.42341 -286.690369) (xy 105.386688 -286.727094) (xy 105.344673 -286.757623) (xy 105.298401 -286.781205)
			(xy 105.24901 -286.797258) (xy 105.197715 -286.805389) (xy 105.171748 -286.805878) (xy 105.144062 -286.804608)
			(xy 105.130035 -286.803885) (xy 105.102477 -286.809257) (xy 105.077425 -286.821935) (xy 105.056776 -286.840958)
			(xy 105.042091 -286.864889) (xy 105.034482 -286.891915) (xy 105.03408 -286.905954) (xy 105.03408 -287.315207)
			(xy 107.191049 -287.315207) (xy 107.191049 -287.263273) (xy 107.199174 -287.211978) (xy 107.215222 -287.162585)
			(xy 107.2388 -287.116311) (xy 107.269326 -287.074295) (xy 107.306049 -287.037572) (xy 107.348065 -287.007046)
			(xy 107.394339 -286.983468) (xy 107.443732 -286.96742) (xy 107.495027 -286.959295) (xy 107.546961 -286.959295)
			(xy 107.598256 -286.96742) (xy 107.647649 -286.983468) (xy 107.693923 -287.007046) (xy 107.735939 -287.037572)
			(xy 107.772662 -287.074295) (xy 107.803188 -287.116311) (xy 107.826766 -287.162585) (xy 107.842814 -287.211978)
			(xy 107.850939 -287.263273) (xy 107.851448 -287.28924) (xy 107.850939 -287.315207) (xy 110.010449 -287.315207)
			(xy 110.010449 -287.263273) (xy 110.018574 -287.211978) (xy 110.034622 -287.162585) (xy 110.0582 -287.116311)
			(xy 110.088726 -287.074295) (xy 110.125449 -287.037572) (xy 110.167465 -287.007046) (xy 110.213739 -286.983468)
			(xy 110.263132 -286.96742) (xy 110.314427 -286.959295) (xy 110.366361 -286.959295) (xy 110.417656 -286.96742)
			(xy 110.467049 -286.983468) (xy 110.513323 -287.007046) (xy 110.555339 -287.037572) (xy 110.592062 -287.074295)
			(xy 110.622588 -287.116311) (xy 110.646166 -287.162585) (xy 110.662214 -287.211978) (xy 110.670339 -287.263273)
			(xy 110.670848 -287.28924) (xy 110.670339 -287.315207) (xy 110.662214 -287.366502) (xy 110.646166 -287.415895)
			(xy 110.622588 -287.462169) (xy 110.592062 -287.504185) (xy 110.555339 -287.540908) (xy 110.513323 -287.571434)
			(xy 110.467049 -287.595012) (xy 110.417656 -287.61106) (xy 110.366361 -287.619185) (xy 110.314427 -287.619185)
			(xy 110.263132 -287.61106) (xy 110.213739 -287.595012) (xy 110.167465 -287.571434) (xy 110.125449 -287.540908)
			(xy 110.088726 -287.504185) (xy 110.0582 -287.462169) (xy 110.034622 -287.415895) (xy 110.018574 -287.366502)
			(xy 110.010449 -287.315207) (xy 107.850939 -287.315207) (xy 107.842814 -287.366502) (xy 107.826766 -287.415895)
			(xy 107.803188 -287.462169) (xy 107.772662 -287.504185) (xy 107.735939 -287.540908) (xy 107.693923 -287.571434)
			(xy 107.647649 -287.595012) (xy 107.598256 -287.61106) (xy 107.546961 -287.619185) (xy 107.495027 -287.619185)
			(xy 107.443732 -287.61106) (xy 107.394339 -287.595012) (xy 107.348065 -287.571434) (xy 107.306049 -287.540908)
			(xy 107.269326 -287.504185) (xy 107.2388 -287.462169) (xy 107.215222 -287.415895) (xy 107.199174 -287.366502)
			(xy 107.191049 -287.315207) (xy 105.03408 -287.315207) (xy 105.03408 -287.672526) (xy 105.034528 -287.686556)
			(xy 105.042163 -287.713557) (xy 105.05685 -287.737466) (xy 105.077484 -287.756481) (xy 105.10251 -287.769172)
			(xy 105.130043 -287.774581) (xy 105.144062 -287.773872) (xy 105.171748 -287.772602) (xy 105.197716 -287.773115)
			(xy 105.249012 -287.781246) (xy 105.298405 -287.797301) (xy 105.344678 -287.820885) (xy 105.386693 -287.851416)
			(xy 105.423415 -287.888143) (xy 105.45394 -287.930163) (xy 105.477517 -287.976439) (xy 105.493565 -288.025834)
			(xy 105.501689 -288.077132) (xy 105.501689 -288.129023) (xy 113.299749 -288.129023) (xy 113.299749 -288.077089)
			(xy 113.307874 -288.025794) (xy 113.323922 -287.976401) (xy 113.3475 -287.930127) (xy 113.378026 -287.888111)
			(xy 113.414749 -287.851388) (xy 113.456765 -287.820862) (xy 113.503039 -287.797284) (xy 113.552432 -287.781236)
			(xy 113.603727 -287.773111) (xy 113.655661 -287.773111) (xy 113.706956 -287.781236) (xy 113.756349 -287.797284)
			(xy 113.802623 -287.820862) (xy 113.844639 -287.851388) (xy 113.881362 -287.888111) (xy 113.911888 -287.930127)
			(xy 113.935466 -287.976401) (xy 113.951514 -288.025794) (xy 113.959639 -288.077089) (xy 113.960148 -288.103056)
			(xy 113.959639 -288.129023) (xy 116.119403 -288.129023) (xy 116.119403 -288.077089) (xy 116.127528 -288.025794)
			(xy 116.143576 -287.976401) (xy 116.167154 -287.930127) (xy 116.19768 -287.888111) (xy 116.234403 -287.851388)
			(xy 116.276419 -287.820862) (xy 116.322693 -287.797284) (xy 116.372086 -287.781236) (xy 116.423381 -287.773111)
			(xy 116.475315 -287.773111) (xy 116.52661 -287.781236) (xy 116.576003 -287.797284) (xy 116.622277 -287.820862)
			(xy 116.664293 -287.851388) (xy 116.701016 -287.888111) (xy 116.731542 -287.930127) (xy 116.75512 -287.976401)
			(xy 116.771168 -288.025794) (xy 116.779293 -288.077089) (xy 116.779802 -288.103056) (xy 116.779293 -288.129023)
			(xy 116.771168 -288.180318) (xy 116.75512 -288.229711) (xy 116.731542 -288.275985) (xy 116.701016 -288.318001)
			(xy 116.664293 -288.354724) (xy 116.622277 -288.38525) (xy 116.576003 -288.408828) (xy 116.52661 -288.424876)
			(xy 116.475315 -288.433001) (xy 116.423381 -288.433001) (xy 116.372086 -288.424876) (xy 116.322693 -288.408828)
			(xy 116.276419 -288.38525) (xy 116.234403 -288.354724) (xy 116.19768 -288.318001) (xy 116.167154 -288.275985)
			(xy 116.143576 -288.229711) (xy 116.127528 -288.180318) (xy 116.119403 -288.129023) (xy 113.959639 -288.129023)
			(xy 113.951514 -288.180318) (xy 113.935466 -288.229711) (xy 113.911888 -288.275985) (xy 113.881362 -288.318001)
			(xy 113.844639 -288.354724) (xy 113.802623 -288.38525) (xy 113.756349 -288.408828) (xy 113.706956 -288.424876)
			(xy 113.655661 -288.433001) (xy 113.603727 -288.433001) (xy 113.552432 -288.424876) (xy 113.503039 -288.408828)
			(xy 113.456765 -288.38525) (xy 113.414749 -288.354724) (xy 113.378026 -288.318001) (xy 113.3475 -288.275985)
			(xy 113.323922 -288.229711) (xy 113.307874 -288.180318) (xy 113.299749 -288.129023) (xy 105.501689 -288.129023)
			(xy 105.501689 -288.129068) (xy 105.493565 -288.180365) (xy 105.477517 -288.229761) (xy 105.45394 -288.276037)
			(xy 105.423415 -288.318057) (xy 105.386693 -288.354784) (xy 105.344678 -288.385315) (xy 105.298405 -288.408899)
			(xy 105.249012 -288.424954) (xy 105.197716 -288.433085) (xy 105.171748 -288.43351) (xy 105.144062 -288.43224)
			(xy 105.130037 -288.431516) (xy 105.102482 -288.436889) (xy 105.077434 -288.449568) (xy 105.056789 -288.468592)
			(xy 105.042111 -288.492523) (xy 105.034509 -288.519548) (xy 105.03408 -288.533586) (xy 105.03408 -288.943093)
			(xy 107.191303 -288.943093) (xy 107.191303 -288.891159) (xy 107.199428 -288.839864) (xy 107.215476 -288.790471)
			(xy 107.239054 -288.744197) (xy 107.26958 -288.702181) (xy 107.306303 -288.665458) (xy 107.348319 -288.634932)
			(xy 107.394593 -288.611354) (xy 107.443986 -288.595306) (xy 107.495281 -288.587181) (xy 107.547215 -288.587181)
			(xy 107.59851 -288.595306) (xy 107.647903 -288.611354) (xy 107.694177 -288.634932) (xy 107.736193 -288.665458)
			(xy 107.772916 -288.702181) (xy 107.803442 -288.744197) (xy 107.82702 -288.790471) (xy 107.843068 -288.839864)
			(xy 107.851193 -288.891159) (xy 107.851702 -288.917126) (xy 107.851193 -288.943093) (xy 107.843068 -288.994388)
			(xy 107.834976 -289.019293) (xy 110.010703 -289.019293) (xy 110.010703 -288.967359) (xy 110.018828 -288.916064)
			(xy 110.034876 -288.866671) (xy 110.058454 -288.820397) (xy 110.08898 -288.778381) (xy 110.125703 -288.741658)
			(xy 110.167719 -288.711132) (xy 110.213993 -288.687554) (xy 110.263386 -288.671506) (xy 110.314681 -288.663381)
			(xy 110.366615 -288.663381) (xy 110.41791 -288.671506) (xy 110.467303 -288.687554) (xy 110.513577 -288.711132)
			(xy 110.555593 -288.741658) (xy 110.592316 -288.778381) (xy 110.622842 -288.820397) (xy 110.64642 -288.866671)
			(xy 110.662468 -288.916064) (xy 110.670593 -288.967359) (xy 110.671102 -288.993326) (xy 110.670593 -289.019293)
			(xy 110.662468 -289.070588) (xy 110.64642 -289.119981) (xy 110.622842 -289.166255) (xy 110.592316 -289.208271)
			(xy 110.555593 -289.244994) (xy 110.513577 -289.27552) (xy 110.467303 -289.299098) (xy 110.41791 -289.315146)
			(xy 110.366615 -289.323271) (xy 110.314681 -289.323271) (xy 110.263386 -289.315146) (xy 110.213993 -289.299098)
			(xy 110.167719 -289.27552) (xy 110.125703 -289.244994) (xy 110.08898 -289.208271) (xy 110.058454 -289.166255)
			(xy 110.034876 -289.119981) (xy 110.018828 -289.070588) (xy 110.010703 -289.019293) (xy 107.834976 -289.019293)
			(xy 107.82702 -289.043781) (xy 107.803442 -289.090055) (xy 107.772916 -289.132071) (xy 107.736193 -289.168794)
			(xy 107.694177 -289.19932) (xy 107.647903 -289.222898) (xy 107.59851 -289.238946) (xy 107.547215 -289.247071)
			(xy 107.495281 -289.247071) (xy 107.443986 -289.238946) (xy 107.394593 -289.222898) (xy 107.348319 -289.19932)
			(xy 107.306303 -289.168794) (xy 107.26958 -289.132071) (xy 107.239054 -289.090055) (xy 107.215476 -289.043781)
			(xy 107.199428 -288.994388) (xy 107.191303 -288.943093) (xy 105.03408 -288.943093) (xy 105.03408 -292.983252)
			(xy 109.276358 -292.983252) (xy 109.276358 -292.928748) (xy 109.284114 -292.874798) (xy 109.29947 -292.822502)
			(xy 109.322111 -292.772923) (xy 109.351578 -292.727071) (xy 109.38727 -292.685878) (xy 109.428461 -292.650185)
			(xy 109.474312 -292.620717) (xy 109.523891 -292.598074) (xy 109.576187 -292.582717) (xy 109.630136 -292.574959)
			(xy 109.657388 -292.574472) (xy 109.685428 -292.574974) (xy 109.740905 -292.583173) (xy 109.794587 -292.599397)
			(xy 109.84532 -292.623297) (xy 109.892012 -292.654359) (xy 109.913166 -292.67277) (xy 109.924608 -292.682415)
			(xy 109.951651 -292.695195) (xy 109.981238 -292.699581) (xy 110.010825 -292.695195) (xy 110.037868 -292.682415)
			(xy 110.04931 -292.67277) (xy 110.070435 -292.654319) (xy 110.11712 -292.62323) (xy 110.167857 -292.599321)
			(xy 110.221552 -292.583108) (xy 110.277043 -292.574941) (xy 110.305088 -292.574472) (xy 110.333128 -292.574974)
			(xy 110.388605 -292.583173) (xy 110.442287 -292.599397) (xy 110.49302 -292.623297) (xy 110.539712 -292.654359)
			(xy 110.560866 -292.67277) (xy 110.572308 -292.682415) (xy 110.599351 -292.695195) (xy 110.628938 -292.699581)
			(xy 110.658525 -292.695195) (xy 110.685568 -292.682415) (xy 110.69701 -292.67277) (xy 110.718135 -292.654319)
			(xy 110.76482 -292.62323) (xy 110.815557 -292.599321) (xy 110.869252 -292.583108) (xy 110.924743 -292.574941)
			(xy 110.952788 -292.574472) (xy 110.98004 -292.574974) (xy 111.033989 -292.58273) (xy 111.086286 -292.598084)
			(xy 111.135865 -292.620724) (xy 111.181717 -292.650191) (xy 111.222909 -292.685882) (xy 111.258602 -292.727073)
			(xy 111.28807 -292.772924) (xy 111.310712 -292.822503) (xy 111.326068 -292.874799) (xy 111.333825 -292.928748)
			(xy 111.333825 -292.983252) (xy 111.326068 -293.037201) (xy 111.310712 -293.089497) (xy 111.28807 -293.139076)
			(xy 111.258602 -293.184927) (xy 111.222909 -293.226118) (xy 111.181717 -293.261809) (xy 111.135865 -293.291276)
			(xy 111.086286 -293.313916) (xy 111.033989 -293.32927) (xy 110.98004 -293.337026) (xy 110.952788 -293.337488)
			(xy 110.924747 -293.337011) (xy 110.869268 -293.328807) (xy 110.815585 -293.312578) (xy 110.764853 -293.288672)
			(xy 110.718163 -293.257604) (xy 110.69701 -293.23919) (xy 110.685568 -293.229545) (xy 110.658525 -293.216765)
			(xy 110.628938 -293.212379) (xy 110.599351 -293.216765) (xy 110.572308 -293.229545) (xy 110.560866 -293.23919)
			(xy 110.539705 -293.257598) (xy 110.493031 -293.288695) (xy 110.442303 -293.312613) (xy 110.388616 -293.328836)
			(xy 110.333131 -293.337013) (xy 110.305088 -293.337488) (xy 110.277047 -293.337011) (xy 110.221568 -293.328807)
			(xy 110.167885 -293.312578) (xy 110.117153 -293.288672) (xy 110.070463 -293.257604) (xy 110.04931 -293.23919)
			(xy 110.037868 -293.229545) (xy 110.010825 -293.216765) (xy 109.981238 -293.212379) (xy 109.951651 -293.216765)
			(xy 109.924608 -293.229545) (xy 109.913166 -293.23919) (xy 109.892005 -293.257598) (xy 109.845331 -293.288695)
			(xy 109.794603 -293.312613) (xy 109.740916 -293.328836) (xy 109.685431 -293.337013) (xy 109.657388 -293.337488)
			(xy 109.630136 -293.337041) (xy 109.576187 -293.329283) (xy 109.523891 -293.313926) (xy 109.474312 -293.291283)
			(xy 109.428461 -293.261815) (xy 109.38727 -293.226122) (xy 109.351578 -293.184929) (xy 109.322111 -293.139077)
			(xy 109.29947 -293.089498) (xy 109.284114 -293.037202) (xy 109.276358 -292.983252) (xy 105.03408 -292.983252)
			(xy 105.03408 -295.066052) (xy 109.276358 -295.066052) (xy 109.276358 -295.011548) (xy 109.284114 -294.957598)
			(xy 109.29947 -294.905302) (xy 109.322111 -294.855723) (xy 109.351578 -294.809871) (xy 109.38727 -294.768678)
			(xy 109.428461 -294.732985) (xy 109.474312 -294.703517) (xy 109.523891 -294.680874) (xy 109.576187 -294.665517)
			(xy 109.630136 -294.657759) (xy 109.657388 -294.657272) (xy 109.685428 -294.657774) (xy 109.740905 -294.665973)
			(xy 109.794587 -294.682197) (xy 109.84532 -294.706097) (xy 109.892012 -294.737159) (xy 109.913166 -294.75557)
			(xy 109.924608 -294.765215) (xy 109.951651 -294.777995) (xy 109.981238 -294.782381) (xy 110.010825 -294.777995)
			(xy 110.037868 -294.765215) (xy 110.04931 -294.75557) (xy 110.070435 -294.737119) (xy 110.11712 -294.70603)
			(xy 110.167857 -294.682121) (xy 110.221552 -294.665908) (xy 110.277043 -294.657741) (xy 110.305088 -294.657272)
			(xy 110.333128 -294.657774) (xy 110.388605 -294.665973) (xy 110.442287 -294.682197) (xy 110.49302 -294.706097)
			(xy 110.539712 -294.737159) (xy 110.560866 -294.75557) (xy 110.572308 -294.765215) (xy 110.599351 -294.777995)
			(xy 110.628938 -294.782381) (xy 110.658525 -294.777995) (xy 110.685568 -294.765215) (xy 110.69701 -294.75557)
			(xy 110.718135 -294.737119) (xy 110.76482 -294.70603) (xy 110.815557 -294.682121) (xy 110.869252 -294.665908)
			(xy 110.924743 -294.657741) (xy 110.952788 -294.657272) (xy 110.98004 -294.657774) (xy 111.033989 -294.66553)
			(xy 111.086286 -294.680884) (xy 111.135865 -294.703524) (xy 111.181717 -294.732991) (xy 111.222909 -294.768682)
			(xy 111.258602 -294.809873) (xy 111.28807 -294.855724) (xy 111.310712 -294.905303) (xy 111.326068 -294.957599)
			(xy 111.333825 -295.011548) (xy 111.333825 -295.066052) (xy 111.326068 -295.120001) (xy 111.310712 -295.172297)
			(xy 111.28807 -295.221876) (xy 111.258602 -295.267727) (xy 111.222909 -295.308918) (xy 111.181717 -295.344609)
			(xy 111.135865 -295.374076) (xy 111.086286 -295.396716) (xy 111.033989 -295.41207) (xy 110.98004 -295.419826)
			(xy 110.952788 -295.420288) (xy 110.924747 -295.419811) (xy 110.869268 -295.411607) (xy 110.815585 -295.395378)
			(xy 110.764853 -295.371472) (xy 110.718163 -295.340404) (xy 110.69701 -295.32199) (xy 110.685568 -295.312345)
			(xy 110.658525 -295.299565) (xy 110.628938 -295.295179) (xy 110.599351 -295.299565) (xy 110.572308 -295.312345)
			(xy 110.560866 -295.32199) (xy 110.539705 -295.340398) (xy 110.493031 -295.371495) (xy 110.442303 -295.395413)
			(xy 110.388616 -295.411636) (xy 110.333131 -295.419813) (xy 110.305088 -295.420288) (xy 110.277047 -295.419811)
			(xy 110.221568 -295.411607) (xy 110.167885 -295.395378) (xy 110.117153 -295.371472) (xy 110.070463 -295.340404)
			(xy 110.04931 -295.32199) (xy 110.037868 -295.312345) (xy 110.010825 -295.299565) (xy 109.981238 -295.295179)
			(xy 109.951651 -295.299565) (xy 109.924608 -295.312345) (xy 109.913166 -295.32199) (xy 109.892005 -295.340398)
			(xy 109.845331 -295.371495) (xy 109.794603 -295.395413) (xy 109.740916 -295.411636) (xy 109.685431 -295.419813)
			(xy 109.657388 -295.420288) (xy 109.630136 -295.419841) (xy 109.576187 -295.412083) (xy 109.523891 -295.396726)
			(xy 109.474312 -295.374083) (xy 109.428461 -295.344615) (xy 109.38727 -295.308922) (xy 109.351578 -295.267729)
			(xy 109.322111 -295.221877) (xy 109.29947 -295.172298) (xy 109.284114 -295.120002) (xy 109.276358 -295.066052)
			(xy 105.03408 -295.066052) (xy 105.03408 -297.225052) (xy 109.276358 -297.225052) (xy 109.276358 -297.170548)
			(xy 109.284114 -297.116598) (xy 109.29947 -297.064302) (xy 109.322111 -297.014723) (xy 109.351578 -296.968871)
			(xy 109.38727 -296.927678) (xy 109.428461 -296.891985) (xy 109.474312 -296.862517) (xy 109.523891 -296.839874)
			(xy 109.576187 -296.824517) (xy 109.630136 -296.816759) (xy 109.657388 -296.816272) (xy 109.685428 -296.816774)
			(xy 109.740905 -296.824973) (xy 109.794587 -296.841197) (xy 109.84532 -296.865097) (xy 109.892012 -296.896159)
			(xy 109.913166 -296.91457) (xy 109.924608 -296.924215) (xy 109.951651 -296.936995) (xy 109.981238 -296.941381)
			(xy 110.010825 -296.936995) (xy 110.037868 -296.924215) (xy 110.04931 -296.91457) (xy 110.070435 -296.896119)
			(xy 110.11712 -296.86503) (xy 110.167857 -296.841121) (xy 110.221552 -296.824908) (xy 110.277043 -296.816741)
			(xy 110.305088 -296.816272) (xy 110.333128 -296.816774) (xy 110.388605 -296.824973) (xy 110.442287 -296.841197)
			(xy 110.49302 -296.865097) (xy 110.539712 -296.896159) (xy 110.560866 -296.91457) (xy 110.572308 -296.924215)
			(xy 110.599351 -296.936995) (xy 110.628938 -296.941381) (xy 110.658525 -296.936995) (xy 110.685568 -296.924215)
			(xy 110.69701 -296.91457) (xy 110.718135 -296.896119) (xy 110.76482 -296.86503) (xy 110.815557 -296.841121)
			(xy 110.869252 -296.824908) (xy 110.924743 -296.816741) (xy 110.952788 -296.816272) (xy 110.98004 -296.816774)
			(xy 111.033989 -296.82453) (xy 111.086286 -296.839884) (xy 111.135865 -296.862524) (xy 111.181717 -296.891991)
			(xy 111.222909 -296.927682) (xy 111.258602 -296.968873) (xy 111.28807 -297.014724) (xy 111.310712 -297.064303)
			(xy 111.326068 -297.116599) (xy 111.333825 -297.170548) (xy 111.333825 -297.225052) (xy 111.326068 -297.279001)
			(xy 111.310712 -297.331297) (xy 111.28807 -297.380876) (xy 111.258602 -297.426727) (xy 111.222909 -297.467918)
			(xy 111.181717 -297.503609) (xy 111.135865 -297.533076) (xy 111.086286 -297.555716) (xy 111.033989 -297.57107)
			(xy 110.98004 -297.578826) (xy 110.952788 -297.579288) (xy 110.924747 -297.578811) (xy 110.869268 -297.570607)
			(xy 110.815585 -297.554378) (xy 110.764853 -297.530472) (xy 110.718163 -297.499404) (xy 110.69701 -297.48099)
			(xy 110.685568 -297.471345) (xy 110.658525 -297.458565) (xy 110.628938 -297.454179) (xy 110.599351 -297.458565)
			(xy 110.572308 -297.471345) (xy 110.560866 -297.48099) (xy 110.539705 -297.499398) (xy 110.493031 -297.530495)
			(xy 110.442303 -297.554413) (xy 110.388616 -297.570636) (xy 110.333131 -297.578813) (xy 110.305088 -297.579288)
			(xy 110.277047 -297.578811) (xy 110.221568 -297.570607) (xy 110.167885 -297.554378) (xy 110.117153 -297.530472)
			(xy 110.070463 -297.499404) (xy 110.04931 -297.48099) (xy 110.037868 -297.471345) (xy 110.010825 -297.458565)
			(xy 109.981238 -297.454179) (xy 109.951651 -297.458565) (xy 109.924608 -297.471345) (xy 109.913166 -297.48099)
			(xy 109.892005 -297.499398) (xy 109.845331 -297.530495) (xy 109.794603 -297.554413) (xy 109.740916 -297.570636)
			(xy 109.685431 -297.578813) (xy 109.657388 -297.579288) (xy 109.630136 -297.578841) (xy 109.576187 -297.571083)
			(xy 109.523891 -297.555726) (xy 109.474312 -297.533083) (xy 109.428461 -297.503615) (xy 109.38727 -297.467922)
			(xy 109.351578 -297.426729) (xy 109.322111 -297.380877) (xy 109.29947 -297.331298) (xy 109.284114 -297.279002)
			(xy 109.276358 -297.225052) (xy 105.03408 -297.225052) (xy 105.03408 -297.537886) (xy 102.98049 -304.499518)
			(xy 91.77027 -315.709738) (xy 97.636834 -315.709738) (xy 97.636834 -315.625042) (xy 97.644885 -315.540728)
			(xy 97.660914 -315.457562) (xy 97.684775 -315.376295) (xy 97.716254 -315.297665) (xy 97.755065 -315.222384)
			(xy 97.800855 -315.151132) (xy 97.853211 -315.084556) (xy 97.911659 -315.023258) (xy 97.975669 -314.967793)
			(xy 98.044661 -314.918664) (xy 98.118011 -314.876315) (xy 98.195054 -314.841131) (xy 98.275093 -314.813429)
			(xy 98.357402 -314.793461) (xy 98.441237 -314.781408) (xy 98.525838 -314.777378) (xy 98.610439 -314.781408)
			(xy 98.694274 -314.793461) (xy 98.776583 -314.813429) (xy 98.856622 -314.841131) (xy 98.933665 -314.876315)
			(xy 99.007015 -314.918664) (xy 99.076007 -314.967793) (xy 99.140017 -315.023258) (xy 99.198465 -315.084556)
			(xy 99.250821 -315.151132) (xy 99.296611 -315.222384) (xy 99.335422 -315.297665) (xy 99.366901 -315.376295)
			(xy 99.390762 -315.457562) (xy 99.406791 -315.540728) (xy 99.414842 -315.625042) (xy 99.415346 -315.66739)
			(xy 99.610423 -315.66739) (xy 99.614445 -315.58167) (xy 99.626476 -315.496702) (xy 99.646412 -315.413235)
			(xy 99.674075 -315.332001) (xy 99.709224 -315.253715) (xy 99.75155 -315.179064) (xy 99.800679 -315.108705)
			(xy 99.856182 -315.043255) (xy 99.917569 -314.983291) (xy 99.984302 -314.929338) (xy 100.055794 -314.881871)
			(xy 100.131416 -314.841307) (xy 100.210505 -314.808003) (xy 100.292365 -314.782251) (xy 100.376276 -314.764278)
			(xy 100.461502 -314.754242) (xy 100.547294 -314.75223) (xy 100.632896 -314.758261) (xy 100.717558 -314.772281)
			(xy 100.800535 -314.794167) (xy 100.881098 -314.823728) (xy 100.958538 -314.860702) (xy 101.032177 -314.904766)
			(xy 101.101365 -314.955532) (xy 101.165496 -315.012553) (xy 101.224005 -315.075329) (xy 101.276378 -315.143309)
			(xy 101.322156 -315.215894) (xy 101.360936 -315.292446) (xy 101.392377 -315.372294) (xy 101.416203 -315.454735)
			(xy 101.432204 -315.539045) (xy 101.440239 -315.624483) (xy 101.440742 -315.66739) (xy 101.440246 -315.709738)
			(xy 103.834434 -315.709738) (xy 103.834434 -315.625042) (xy 103.842485 -315.540728) (xy 103.858514 -315.457562)
			(xy 103.882375 -315.376295) (xy 103.913854 -315.297665) (xy 103.952665 -315.222384) (xy 103.998455 -315.151132)
			(xy 104.050811 -315.084556) (xy 104.109259 -315.023258) (xy 104.173269 -314.967793) (xy 104.242261 -314.918664)
			(xy 104.315611 -314.876315) (xy 104.392654 -314.841131) (xy 104.472693 -314.813429) (xy 104.555002 -314.793461)
			(xy 104.638837 -314.781408) (xy 104.723438 -314.777378) (xy 104.808039 -314.781408) (xy 104.891874 -314.793461)
			(xy 104.974183 -314.813429) (xy 105.054222 -314.841131) (xy 105.131265 -314.876315) (xy 105.204615 -314.918664)
			(xy 105.273607 -314.967793) (xy 105.337617 -315.023258) (xy 105.396065 -315.084556) (xy 105.448421 -315.151132)
			(xy 105.494211 -315.222384) (xy 105.533022 -315.297665) (xy 105.564501 -315.376295) (xy 105.588362 -315.457562)
			(xy 105.604391 -315.540728) (xy 105.612442 -315.625042) (xy 105.612946 -315.66739) (xy 105.808023 -315.66739)
			(xy 105.812045 -315.58167) (xy 105.824076 -315.496702) (xy 105.844012 -315.413235) (xy 105.871675 -315.332001)
			(xy 105.906824 -315.253715) (xy 105.94915 -315.179064) (xy 105.998279 -315.108705) (xy 106.053782 -315.043255)
			(xy 106.115169 -314.983291) (xy 106.181902 -314.929338) (xy 106.253394 -314.881871) (xy 106.329016 -314.841307)
			(xy 106.408105 -314.808003) (xy 106.489965 -314.782251) (xy 106.573876 -314.764278) (xy 106.659102 -314.754242)
			(xy 106.744894 -314.75223) (xy 106.830496 -314.758261) (xy 106.915158 -314.772281) (xy 106.998135 -314.794167)
			(xy 107.078698 -314.823728) (xy 107.156138 -314.860702) (xy 107.229777 -314.904766) (xy 107.298965 -314.955532)
			(xy 107.363096 -315.012553) (xy 107.421605 -315.075329) (xy 107.473978 -315.143309) (xy 107.519756 -315.215894)
			(xy 107.558536 -315.292446) (xy 107.589977 -315.372294) (xy 107.613803 -315.454735) (xy 107.629804 -315.539045)
			(xy 107.637839 -315.624483) (xy 107.638342 -315.66739) (xy 107.637846 -315.709738) (xy 110.012222 -315.709738)
			(xy 110.012222 -315.625042) (xy 110.020273 -315.540728) (xy 110.036302 -315.457562) (xy 110.060163 -315.376295)
			(xy 110.091642 -315.297665) (xy 110.130453 -315.222384) (xy 110.176243 -315.151132) (xy 110.228599 -315.084556)
			(xy 110.287047 -315.023258) (xy 110.351057 -314.967793) (xy 110.420049 -314.918664) (xy 110.493399 -314.876315)
			(xy 110.570442 -314.841131) (xy 110.650481 -314.813429) (xy 110.73279 -314.793461) (xy 110.816625 -314.781408)
			(xy 110.901226 -314.777378) (xy 110.985827 -314.781408) (xy 111.069662 -314.793461) (xy 111.151971 -314.813429)
			(xy 111.23201 -314.841131) (xy 111.309053 -314.876315) (xy 111.382403 -314.918664) (xy 111.451395 -314.967793)
			(xy 111.515405 -315.023258) (xy 111.573853 -315.084556) (xy 111.626209 -315.151132) (xy 111.671999 -315.222384)
			(xy 111.71081 -315.297665) (xy 111.742289 -315.376295) (xy 111.76615 -315.457562) (xy 111.782179 -315.540728)
			(xy 111.79023 -315.625042) (xy 111.790734 -315.66739) (xy 111.985811 -315.66739) (xy 111.989833 -315.58167)
			(xy 112.001864 -315.496702) (xy 112.0218 -315.413235) (xy 112.049463 -315.332001) (xy 112.084612 -315.253715)
			(xy 112.126938 -315.179064) (xy 112.176067 -315.108705) (xy 112.23157 -315.043255) (xy 112.292957 -314.983291)
			(xy 112.35969 -314.929338) (xy 112.431182 -314.881871) (xy 112.506804 -314.841307) (xy 112.585893 -314.808003)
			(xy 112.667753 -314.782251) (xy 112.751664 -314.764278) (xy 112.83689 -314.754242) (xy 112.922682 -314.75223)
			(xy 113.008284 -314.758261) (xy 113.092946 -314.772281) (xy 113.175923 -314.794167) (xy 113.256486 -314.823728)
			(xy 113.333926 -314.860702) (xy 113.407565 -314.904766) (xy 113.476753 -314.955532) (xy 113.540884 -315.012553)
			(xy 113.599393 -315.075329) (xy 113.651766 -315.143309) (xy 113.697544 -315.215894) (xy 113.736324 -315.292446)
			(xy 113.767765 -315.372294) (xy 113.791591 -315.454735) (xy 113.807592 -315.539045) (xy 113.815627 -315.624483)
			(xy 113.81613 -315.66739) (xy 113.815634 -315.709738) (xy 116.209822 -315.709738) (xy 116.209822 -315.625042)
			(xy 116.217873 -315.540728) (xy 116.233902 -315.457562) (xy 116.257763 -315.376295) (xy 116.289242 -315.297665)
			(xy 116.328053 -315.222384) (xy 116.373843 -315.151132) (xy 116.426199 -315.084556) (xy 116.484647 -315.023258)
			(xy 116.548657 -314.967793) (xy 116.617649 -314.918664) (xy 116.690999 -314.876315) (xy 116.768042 -314.841131)
			(xy 116.848081 -314.813429) (xy 116.93039 -314.793461) (xy 117.014225 -314.781408) (xy 117.098826 -314.777378)
			(xy 117.183427 -314.781408) (xy 117.267262 -314.793461) (xy 117.349571 -314.813429) (xy 117.42961 -314.841131)
			(xy 117.506653 -314.876315) (xy 117.580003 -314.918664) (xy 117.648995 -314.967793) (xy 117.713005 -315.023258)
			(xy 117.771453 -315.084556) (xy 117.823809 -315.151132) (xy 117.869599 -315.222384) (xy 117.90841 -315.297665)
			(xy 117.939889 -315.376295) (xy 117.96375 -315.457562) (xy 117.979779 -315.540728) (xy 117.98783 -315.625042)
			(xy 117.988334 -315.66739) (xy 118.183411 -315.66739) (xy 118.187433 -315.58167) (xy 118.199464 -315.496702)
			(xy 118.2194 -315.413235) (xy 118.247063 -315.332001) (xy 118.282212 -315.253715) (xy 118.324538 -315.179064)
			(xy 118.373667 -315.108705) (xy 118.42917 -315.043255) (xy 118.490557 -314.983291) (xy 118.55729 -314.929338)
			(xy 118.628782 -314.881871) (xy 118.704404 -314.841307) (xy 118.783493 -314.808003) (xy 118.865353 -314.782251)
			(xy 118.949264 -314.764278) (xy 119.03449 -314.754242) (xy 119.120282 -314.75223) (xy 119.205884 -314.758261)
			(xy 119.290546 -314.772281) (xy 119.373523 -314.794167) (xy 119.454086 -314.823728) (xy 119.531526 -314.860702)
			(xy 119.605165 -314.904766) (xy 119.674353 -314.955532) (xy 119.738484 -315.012553) (xy 119.796993 -315.075329)
			(xy 119.849366 -315.143309) (xy 119.895144 -315.215894) (xy 119.933924 -315.292446) (xy 119.965365 -315.372294)
			(xy 119.989191 -315.454735) (xy 120.005192 -315.539045) (xy 120.013227 -315.624483) (xy 120.01373 -315.66739)
			(xy 120.013234 -315.709738) (xy 122.407422 -315.709738) (xy 122.407422 -315.625042) (xy 122.415473 -315.540728)
			(xy 122.431502 -315.457562) (xy 122.455363 -315.376295) (xy 122.486842 -315.297665) (xy 122.525653 -315.222384)
			(xy 122.571443 -315.151132) (xy 122.623799 -315.084556) (xy 122.682247 -315.023258) (xy 122.746257 -314.967793)
			(xy 122.815249 -314.918664) (xy 122.888599 -314.876315) (xy 122.965642 -314.841131) (xy 123.045681 -314.813429)
			(xy 123.12799 -314.793461) (xy 123.211825 -314.781408) (xy 123.296426 -314.777378) (xy 123.381027 -314.781408)
			(xy 123.464862 -314.793461) (xy 123.547171 -314.813429) (xy 123.62721 -314.841131) (xy 123.704253 -314.876315)
			(xy 123.777603 -314.918664) (xy 123.846595 -314.967793) (xy 123.910605 -315.023258) (xy 123.969053 -315.084556)
			(xy 124.021409 -315.151132) (xy 124.067199 -315.222384) (xy 124.10601 -315.297665) (xy 124.137489 -315.376295)
			(xy 124.16135 -315.457562) (xy 124.177379 -315.540728) (xy 124.18543 -315.625042) (xy 124.185934 -315.66739)
			(xy 124.381011 -315.66739) (xy 124.385033 -315.58167) (xy 124.397064 -315.496702) (xy 124.417 -315.413235)
			(xy 124.444663 -315.332001) (xy 124.479812 -315.253715) (xy 124.522138 -315.179064) (xy 124.571267 -315.108705)
			(xy 124.62677 -315.043255) (xy 124.688157 -314.983291) (xy 124.75489 -314.929338) (xy 124.826382 -314.881871)
			(xy 124.902004 -314.841307) (xy 124.981093 -314.808003) (xy 125.062953 -314.782251) (xy 125.146864 -314.764278)
			(xy 125.23209 -314.754242) (xy 125.317882 -314.75223) (xy 125.403484 -314.758261) (xy 125.488146 -314.772281)
			(xy 125.571123 -314.794167) (xy 125.651686 -314.823728) (xy 125.729126 -314.860702) (xy 125.802765 -314.904766)
			(xy 125.871953 -314.955532) (xy 125.936084 -315.012553) (xy 125.994593 -315.075329) (xy 126.046966 -315.143309)
			(xy 126.092744 -315.215894) (xy 126.131524 -315.292446) (xy 126.162965 -315.372294) (xy 126.186791 -315.454735)
			(xy 126.202792 -315.539045) (xy 126.210827 -315.624483) (xy 126.21133 -315.66739) (xy 126.210827 -315.710297)
			(xy 126.202792 -315.795735) (xy 126.186791 -315.880045) (xy 126.162965 -315.962486) (xy 126.131524 -316.042334)
			(xy 126.092744 -316.118886) (xy 126.046966 -316.191471) (xy 125.994593 -316.259451) (xy 125.936084 -316.322227)
			(xy 125.871953 -316.379248) (xy 125.802765 -316.430014) (xy 125.729126 -316.474078) (xy 125.651686 -316.511052)
			(xy 125.571123 -316.540613) (xy 125.488146 -316.562499) (xy 125.403484 -316.576519) (xy 125.317882 -316.58255)
			(xy 125.23209 -316.580538) (xy 125.146864 -316.570502) (xy 125.062953 -316.552529) (xy 124.981093 -316.526777)
			(xy 124.902004 -316.493473) (xy 124.826382 -316.452909) (xy 124.75489 -316.405442) (xy 124.688157 -316.351489)
			(xy 124.62677 -316.291525) (xy 124.571267 -316.226075) (xy 124.522138 -316.155716) (xy 124.479812 -316.081065)
			(xy 124.444663 -316.002779) (xy 124.417 -315.921545) (xy 124.397064 -315.838078) (xy 124.385033 -315.75311)
			(xy 124.381011 -315.66739) (xy 124.185934 -315.66739) (xy 124.18543 -315.709738) (xy 124.177379 -315.794052)
			(xy 124.16135 -315.877218) (xy 124.137489 -315.958485) (xy 124.10601 -316.037115) (xy 124.067199 -316.112396)
			(xy 124.021409 -316.183648) (xy 123.969053 -316.250224) (xy 123.910605 -316.311522) (xy 123.846595 -316.366987)
			(xy 123.777603 -316.416116) (xy 123.704253 -316.458465) (xy 123.62721 -316.493649) (xy 123.547171 -316.521351)
			(xy 123.464862 -316.541319) (xy 123.381027 -316.553372) (xy 123.296426 -316.557403) (xy 123.211825 -316.553372)
			(xy 123.12799 -316.541319) (xy 123.045681 -316.521351) (xy 122.965642 -316.493649) (xy 122.888599 -316.458465)
			(xy 122.815249 -316.416116) (xy 122.746257 -316.366987) (xy 122.682247 -316.311522) (xy 122.623799 -316.250224)
			(xy 122.571443 -316.183648) (xy 122.525653 -316.112396) (xy 122.486842 -316.037115) (xy 122.455363 -315.958485)
			(xy 122.431502 -315.877218) (xy 122.415473 -315.794052) (xy 122.407422 -315.709738) (xy 120.013234 -315.709738)
			(xy 120.013227 -315.710297) (xy 120.005192 -315.795735) (xy 119.989191 -315.880045) (xy 119.965365 -315.962486)
			(xy 119.933924 -316.042334) (xy 119.895144 -316.118886) (xy 119.849366 -316.191471) (xy 119.796993 -316.259451)
			(xy 119.738484 -316.322227) (xy 119.674353 -316.379248) (xy 119.605165 -316.430014) (xy 119.531526 -316.474078)
			(xy 119.454086 -316.511052) (xy 119.373523 -316.540613) (xy 119.290546 -316.562499) (xy 119.205884 -316.576519)
			(xy 119.120282 -316.58255) (xy 119.03449 -316.580538) (xy 118.949264 -316.570502) (xy 118.865353 -316.552529)
			(xy 118.783493 -316.526777) (xy 118.704404 -316.493473) (xy 118.628782 -316.452909) (xy 118.55729 -316.405442)
			(xy 118.490557 -316.351489) (xy 118.42917 -316.291525) (xy 118.373667 -316.226075) (xy 118.324538 -316.155716)
			(xy 118.282212 -316.081065) (xy 118.247063 -316.002779) (xy 118.2194 -315.921545) (xy 118.199464 -315.838078)
			(xy 118.187433 -315.75311) (xy 118.183411 -315.66739) (xy 117.988334 -315.66739) (xy 117.98783 -315.709738)
			(xy 117.979779 -315.794052) (xy 117.96375 -315.877218) (xy 117.939889 -315.958485) (xy 117.90841 -316.037115)
			(xy 117.869599 -316.112396) (xy 117.823809 -316.183648) (xy 117.771453 -316.250224) (xy 117.713005 -316.311522)
			(xy 117.648995 -316.366987) (xy 117.580003 -316.416116) (xy 117.506653 -316.458465) (xy 117.42961 -316.493649)
			(xy 117.349571 -316.521351) (xy 117.267262 -316.541319) (xy 117.183427 -316.553372) (xy 117.098826 -316.557403)
			(xy 117.014225 -316.553372) (xy 116.93039 -316.541319) (xy 116.848081 -316.521351) (xy 116.768042 -316.493649)
			(xy 116.690999 -316.458465) (xy 116.617649 -316.416116) (xy 116.548657 -316.366987) (xy 116.484647 -316.311522)
			(xy 116.426199 -316.250224) (xy 116.373843 -316.183648) (xy 116.328053 -316.112396) (xy 116.289242 -316.037115)
			(xy 116.257763 -315.958485) (xy 116.233902 -315.877218) (xy 116.217873 -315.794052) (xy 116.209822 -315.709738)
			(xy 113.815634 -315.709738) (xy 113.815627 -315.710297) (xy 113.807592 -315.795735) (xy 113.791591 -315.880045)
			(xy 113.767765 -315.962486) (xy 113.736324 -316.042334) (xy 113.697544 -316.118886) (xy 113.651766 -316.191471)
			(xy 113.599393 -316.259451) (xy 113.540884 -316.322227) (xy 113.476753 -316.379248) (xy 113.407565 -316.430014)
			(xy 113.333926 -316.474078) (xy 113.256486 -316.511052) (xy 113.175923 -316.540613) (xy 113.092946 -316.562499)
			(xy 113.008284 -316.576519) (xy 112.922682 -316.58255) (xy 112.83689 -316.580538) (xy 112.751664 -316.570502)
			(xy 112.667753 -316.552529) (xy 112.585893 -316.526777) (xy 112.506804 -316.493473) (xy 112.431182 -316.452909)
			(xy 112.35969 -316.405442) (xy 112.292957 -316.351489) (xy 112.23157 -316.291525) (xy 112.176067 -316.226075)
			(xy 112.126938 -316.155716) (xy 112.084612 -316.081065) (xy 112.049463 -316.002779) (xy 112.0218 -315.921545)
			(xy 112.001864 -315.838078) (xy 111.989833 -315.75311) (xy 111.985811 -315.66739) (xy 111.790734 -315.66739)
			(xy 111.79023 -315.709738) (xy 111.782179 -315.794052) (xy 111.76615 -315.877218) (xy 111.742289 -315.958485)
			(xy 111.71081 -316.037115) (xy 111.671999 -316.112396) (xy 111.626209 -316.183648) (xy 111.573853 -316.250224)
			(xy 111.515405 -316.311522) (xy 111.451395 -316.366987) (xy 111.382403 -316.416116) (xy 111.309053 -316.458465)
			(xy 111.23201 -316.493649) (xy 111.151971 -316.521351) (xy 111.069662 -316.541319) (xy 110.985827 -316.553372)
			(xy 110.901226 -316.557403) (xy 110.816625 -316.553372) (xy 110.73279 -316.541319) (xy 110.650481 -316.521351)
			(xy 110.570442 -316.493649) (xy 110.493399 -316.458465) (xy 110.420049 -316.416116) (xy 110.351057 -316.366987)
			(xy 110.287047 -316.311522) (xy 110.228599 -316.250224) (xy 110.176243 -316.183648) (xy 110.130453 -316.112396)
			(xy 110.091642 -316.037115) (xy 110.060163 -315.958485) (xy 110.036302 -315.877218) (xy 110.020273 -315.794052)
			(xy 110.012222 -315.709738) (xy 107.637846 -315.709738) (xy 107.637839 -315.710297) (xy 107.629804 -315.795735)
			(xy 107.613803 -315.880045) (xy 107.589977 -315.962486) (xy 107.558536 -316.042334) (xy 107.519756 -316.118886)
			(xy 107.473978 -316.191471) (xy 107.421605 -316.259451) (xy 107.363096 -316.322227) (xy 107.298965 -316.379248)
			(xy 107.229777 -316.430014) (xy 107.156138 -316.474078) (xy 107.078698 -316.511052) (xy 106.998135 -316.540613)
			(xy 106.915158 -316.562499) (xy 106.830496 -316.576519) (xy 106.744894 -316.58255) (xy 106.659102 -316.580538)
			(xy 106.573876 -316.570502) (xy 106.489965 -316.552529) (xy 106.408105 -316.526777) (xy 106.329016 -316.493473)
			(xy 106.253394 -316.452909) (xy 106.181902 -316.405442) (xy 106.115169 -316.351489) (xy 106.053782 -316.291525)
			(xy 105.998279 -316.226075) (xy 105.94915 -316.155716) (xy 105.906824 -316.081065) (xy 105.871675 -316.002779)
			(xy 105.844012 -315.921545) (xy 105.824076 -315.838078) (xy 105.812045 -315.75311) (xy 105.808023 -315.66739)
			(xy 105.612946 -315.66739) (xy 105.612442 -315.709738) (xy 105.604391 -315.794052) (xy 105.588362 -315.877218)
			(xy 105.564501 -315.958485) (xy 105.533022 -316.037115) (xy 105.494211 -316.112396) (xy 105.448421 -316.183648)
			(xy 105.396065 -316.250224) (xy 105.337617 -316.311522) (xy 105.273607 -316.366987) (xy 105.204615 -316.416116)
			(xy 105.131265 -316.458465) (xy 105.054222 -316.493649) (xy 104.974183 -316.521351) (xy 104.891874 -316.541319)
			(xy 104.808039 -316.553372) (xy 104.723438 -316.557403) (xy 104.638837 -316.553372) (xy 104.555002 -316.541319)
			(xy 104.472693 -316.521351) (xy 104.392654 -316.493649) (xy 104.315611 -316.458465) (xy 104.242261 -316.416116)
			(xy 104.173269 -316.366987) (xy 104.109259 -316.311522) (xy 104.050811 -316.250224) (xy 103.998455 -316.183648)
			(xy 103.952665 -316.112396) (xy 103.913854 -316.037115) (xy 103.882375 -315.958485) (xy 103.858514 -315.877218)
			(xy 103.842485 -315.794052) (xy 103.834434 -315.709738) (xy 101.440246 -315.709738) (xy 101.440239 -315.710297)
			(xy 101.432204 -315.795735) (xy 101.416203 -315.880045) (xy 101.392377 -315.962486) (xy 101.360936 -316.042334)
			(xy 101.322156 -316.118886) (xy 101.276378 -316.191471) (xy 101.224005 -316.259451) (xy 101.165496 -316.322227)
			(xy 101.101365 -316.379248) (xy 101.032177 -316.430014) (xy 100.958538 -316.474078) (xy 100.881098 -316.511052)
			(xy 100.800535 -316.540613) (xy 100.717558 -316.562499) (xy 100.632896 -316.576519) (xy 100.547294 -316.58255)
			(xy 100.461502 -316.580538) (xy 100.376276 -316.570502) (xy 100.292365 -316.552529) (xy 100.210505 -316.526777)
			(xy 100.131416 -316.493473) (xy 100.055794 -316.452909) (xy 99.984302 -316.405442) (xy 99.917569 -316.351489)
			(xy 99.856182 -316.291525) (xy 99.800679 -316.226075) (xy 99.75155 -316.155716) (xy 99.709224 -316.081065)
			(xy 99.674075 -316.002779) (xy 99.646412 -315.921545) (xy 99.626476 -315.838078) (xy 99.614445 -315.75311)
			(xy 99.610423 -315.66739) (xy 99.415346 -315.66739) (xy 99.414842 -315.709738) (xy 99.406791 -315.794052)
			(xy 99.390762 -315.877218) (xy 99.366901 -315.958485) (xy 99.335422 -316.037115) (xy 99.296611 -316.112396)
			(xy 99.250821 -316.183648) (xy 99.198465 -316.250224) (xy 99.140017 -316.311522) (xy 99.076007 -316.366987)
			(xy 99.007015 -316.416116) (xy 98.933665 -316.458465) (xy 98.856622 -316.493649) (xy 98.776583 -316.521351)
			(xy 98.694274 -316.541319) (xy 98.610439 -316.553372) (xy 98.525838 -316.557403) (xy 98.441237 -316.553372)
			(xy 98.357402 -316.541319) (xy 98.275093 -316.521351) (xy 98.195054 -316.493649) (xy 98.118011 -316.458465)
			(xy 98.044661 -316.416116) (xy 97.975669 -316.366987) (xy 97.911659 -316.311522) (xy 97.853211 -316.250224)
			(xy 97.800855 -316.183648) (xy 97.755065 -316.112396) (xy 97.716254 -316.037115) (xy 97.684775 -315.958485)
			(xy 97.660914 -315.877218) (xy 97.644885 -315.794052) (xy 97.636834 -315.709738) (xy 91.77027 -315.709738)
			(xy 77.86878 -329.611228) (xy 77.86878 -332.684628) (xy 78.0161 -332.831948) (xy 84.12988 -332.831948)
		)
		(stroke
			(width 0)
			(type solid)
		)
		(fill yes)
		(layer "In2.Cu")
		(net "PVCCIN_CPU1")
	)
	(gr_poly
		(pts
			(xy 188.6585 -366.194848) (xy 188.6585 -362.831888) (xy 190.83782 -360.652568) (xy 190.83782 -333.093568)
			(xy 190.6016 -332.857348) (xy 166.1668 -332.857348) (xy 165.669468 -333.35468) (xy 165.669468 -335.51996)
			(xy 170.076618 -335.51996) (xy 170.076618 -335.435264) (xy 170.084669 -335.35095) (xy 170.100698 -335.267784)
			(xy 170.124559 -335.186517) (xy 170.156038 -335.107887) (xy 170.194849 -335.032606) (xy 170.240639 -334.961354)
			(xy 170.292995 -334.894778) (xy 170.351443 -334.83348) (xy 170.415453 -334.778015) (xy 170.484445 -334.728886)
			(xy 170.557795 -334.686537) (xy 170.634838 -334.651353) (xy 170.714877 -334.623651) (xy 170.797186 -334.603683)
			(xy 170.881021 -334.59163) (xy 170.965622 -334.5876) (xy 171.050223 -334.59163) (xy 171.134058 -334.603683)
			(xy 171.216367 -334.623651) (xy 171.296406 -334.651353) (xy 171.373449 -334.686537) (xy 171.446799 -334.728886)
			(xy 171.515791 -334.778015) (xy 171.579801 -334.83348) (xy 171.638249 -334.894778) (xy 171.690605 -334.961354)
			(xy 171.736395 -335.032606) (xy 171.775206 -335.107887) (xy 171.806685 -335.186517) (xy 171.830546 -335.267784)
			(xy 171.846575 -335.35095) (xy 171.854626 -335.435264) (xy 171.85513 -335.477612) (xy 171.854626 -335.51996)
			(xy 171.85402 -335.52631) (xy 176.26736 -335.52631) (xy 176.26736 -335.441614) (xy 176.275411 -335.3573)
			(xy 176.29144 -335.274134) (xy 176.315301 -335.192867) (xy 176.34678 -335.114237) (xy 176.385591 -335.038956)
			(xy 176.431381 -334.967704) (xy 176.483737 -334.901128) (xy 176.542185 -334.83983) (xy 176.606195 -334.784365)
			(xy 176.675187 -334.735236) (xy 176.748537 -334.692887) (xy 176.82558 -334.657703) (xy 176.905619 -334.630001)
			(xy 176.987928 -334.610033) (xy 177.071763 -334.59798) (xy 177.156364 -334.59395) (xy 177.240965 -334.59798)
			(xy 177.3248 -334.610033) (xy 177.407109 -334.630001) (xy 177.487148 -334.657703) (xy 177.564191 -334.692887)
			(xy 177.637541 -334.735236) (xy 177.706533 -334.784365) (xy 177.770543 -334.83983) (xy 177.828991 -334.901128)
			(xy 177.881347 -334.967704) (xy 177.927137 -335.038956) (xy 177.965948 -335.114237) (xy 177.997427 -335.192867)
			(xy 178.021288 -335.274134) (xy 178.037317 -335.3573) (xy 178.045368 -335.441614) (xy 178.045872 -335.483962)
			(xy 178.045368 -335.52631) (xy 182.46496 -335.52631) (xy 182.46496 -335.441614) (xy 182.473011 -335.3573)
			(xy 182.48904 -335.274134) (xy 182.512901 -335.192867) (xy 182.54438 -335.114237) (xy 182.583191 -335.038956)
			(xy 182.628981 -334.967704) (xy 182.681337 -334.901128) (xy 182.739785 -334.83983) (xy 182.803795 -334.784365)
			(xy 182.872787 -334.735236) (xy 182.946137 -334.692887) (xy 183.02318 -334.657703) (xy 183.103219 -334.630001)
			(xy 183.185528 -334.610033) (xy 183.269363 -334.59798) (xy 183.353964 -334.59395) (xy 183.438565 -334.59798)
			(xy 183.5224 -334.610033) (xy 183.604709 -334.630001) (xy 183.684748 -334.657703) (xy 183.761791 -334.692887)
			(xy 183.835141 -334.735236) (xy 183.904133 -334.784365) (xy 183.968143 -334.83983) (xy 184.026591 -334.901128)
			(xy 184.078947 -334.967704) (xy 184.124737 -335.038956) (xy 184.163548 -335.114237) (xy 184.195027 -335.192867)
			(xy 184.218888 -335.274134) (xy 184.234917 -335.3573) (xy 184.242968 -335.441614) (xy 184.243472 -335.483962)
			(xy 184.242968 -335.52631) (xy 184.234917 -335.610624) (xy 184.218888 -335.69379) (xy 184.195027 -335.775057)
			(xy 184.163548 -335.853687) (xy 184.124737 -335.928968) (xy 184.078947 -336.00022) (xy 184.026591 -336.066796)
			(xy 183.968143 -336.128094) (xy 183.904133 -336.183559) (xy 183.835141 -336.232688) (xy 183.761791 -336.275037)
			(xy 183.684748 -336.310221) (xy 183.604709 -336.337923) (xy 183.5224 -336.357891) (xy 183.438565 -336.369944)
			(xy 183.353964 -336.373975) (xy 183.269363 -336.369944) (xy 183.185528 -336.357891) (xy 183.103219 -336.337923)
			(xy 183.02318 -336.310221) (xy 182.946137 -336.275037) (xy 182.872787 -336.232688) (xy 182.803795 -336.183559)
			(xy 182.739785 -336.128094) (xy 182.681337 -336.066796) (xy 182.628981 -336.00022) (xy 182.583191 -335.928968)
			(xy 182.54438 -335.853687) (xy 182.512901 -335.775057) (xy 182.48904 -335.69379) (xy 182.473011 -335.610624)
			(xy 182.46496 -335.52631) (xy 178.045368 -335.52631) (xy 178.037317 -335.610624) (xy 178.021288 -335.69379)
			(xy 177.997427 -335.775057) (xy 177.965948 -335.853687) (xy 177.927137 -335.928968) (xy 177.881347 -336.00022)
			(xy 177.828991 -336.066796) (xy 177.770543 -336.128094) (xy 177.706533 -336.183559) (xy 177.637541 -336.232688)
			(xy 177.564191 -336.275037) (xy 177.487148 -336.310221) (xy 177.407109 -336.337923) (xy 177.3248 -336.357891)
			(xy 177.240965 -336.369944) (xy 177.156364 -336.373975) (xy 177.071763 -336.369944) (xy 176.987928 -336.357891)
			(xy 176.905619 -336.337923) (xy 176.82558 -336.310221) (xy 176.748537 -336.275037) (xy 176.675187 -336.232688)
			(xy 176.606195 -336.183559) (xy 176.542185 -336.128094) (xy 176.483737 -336.066796) (xy 176.431381 -336.00022)
			(xy 176.385591 -335.928968) (xy 176.34678 -335.853687) (xy 176.315301 -335.775057) (xy 176.29144 -335.69379)
			(xy 176.275411 -335.610624) (xy 176.26736 -335.52631) (xy 171.85402 -335.52631) (xy 171.846575 -335.604274)
			(xy 171.830546 -335.68744) (xy 171.806685 -335.768707) (xy 171.775206 -335.847337) (xy 171.736395 -335.922618)
			(xy 171.690605 -335.99387) (xy 171.638249 -336.060446) (xy 171.579801 -336.121744) (xy 171.515791 -336.177209)
			(xy 171.446799 -336.226338) (xy 171.373449 -336.268687) (xy 171.296406 -336.303871) (xy 171.216367 -336.331573)
			(xy 171.134058 -336.351541) (xy 171.050223 -336.363594) (xy 170.965622 -336.367625) (xy 170.881021 -336.363594)
			(xy 170.797186 -336.351541) (xy 170.714877 -336.331573) (xy 170.634838 -336.303871) (xy 170.557795 -336.268687)
			(xy 170.484445 -336.226338) (xy 170.415453 -336.177209) (xy 170.351443 -336.121744) (xy 170.292995 -336.060446)
			(xy 170.240639 -335.99387) (xy 170.194849 -335.922618) (xy 170.156038 -335.847337) (xy 170.124559 -335.768707)
			(xy 170.100698 -335.68744) (xy 170.084669 -335.604274) (xy 170.076618 -335.51996) (xy 165.669468 -335.51996)
			(xy 165.669468 -337.477608) (xy 170.050211 -337.477608) (xy 170.054233 -337.391888) (xy 170.066264 -337.30692)
			(xy 170.0862 -337.223453) (xy 170.113863 -337.142219) (xy 170.149012 -337.063933) (xy 170.191338 -336.989282)
			(xy 170.240467 -336.918923) (xy 170.29597 -336.853473) (xy 170.357357 -336.793509) (xy 170.42409 -336.739556)
			(xy 170.495582 -336.692089) (xy 170.571204 -336.651525) (xy 170.650293 -336.618221) (xy 170.732153 -336.592469)
			(xy 170.816064 -336.574496) (xy 170.90129 -336.56446) (xy 170.987082 -336.562448) (xy 171.072684 -336.568479)
			(xy 171.157346 -336.582499) (xy 171.240323 -336.604385) (xy 171.320886 -336.633946) (xy 171.398326 -336.67092)
			(xy 171.471965 -336.714984) (xy 171.541153 -336.76575) (xy 171.605284 -336.822771) (xy 171.663793 -336.885547)
			(xy 171.716166 -336.953527) (xy 171.761944 -337.026112) (xy 171.800724 -337.102664) (xy 171.832165 -337.182512)
			(xy 171.855991 -337.264953) (xy 171.871992 -337.349263) (xy 171.880027 -337.434701) (xy 171.88053 -337.477608)
			(xy 171.880456 -337.483958) (xy 176.240953 -337.483958) (xy 176.244975 -337.398238) (xy 176.257006 -337.31327)
			(xy 176.276942 -337.229803) (xy 176.304605 -337.148569) (xy 176.339754 -337.070283) (xy 176.38208 -336.995632)
			(xy 176.431209 -336.925273) (xy 176.486712 -336.859823) (xy 176.548099 -336.799859) (xy 176.614832 -336.745906)
			(xy 176.686324 -336.698439) (xy 176.761946 -336.657875) (xy 176.841035 -336.624571) (xy 176.922895 -336.598819)
			(xy 177.006806 -336.580846) (xy 177.092032 -336.57081) (xy 177.177824 -336.568798) (xy 177.263426 -336.574829)
			(xy 177.348088 -336.588849) (xy 177.431065 -336.610735) (xy 177.511628 -336.640296) (xy 177.589068 -336.67727)
			(xy 177.662707 -336.721334) (xy 177.731895 -336.7721) (xy 177.796026 -336.829121) (xy 177.854535 -336.891897)
			(xy 177.906908 -336.959877) (xy 177.952686 -337.032462) (xy 177.991466 -337.109014) (xy 178.022907 -337.188862)
			(xy 178.046733 -337.271303) (xy 178.062734 -337.355613) (xy 178.070769 -337.441051) (xy 178.071272 -337.483958)
			(xy 182.439056 -337.483958) (xy 182.439544 -337.441682) (xy 182.447346 -337.35749) (xy 182.462882 -337.274377)
			(xy 182.486021 -337.193053) (xy 182.516565 -337.11421) (xy 182.554253 -337.038522) (xy 182.598764 -336.966634)
			(xy 182.649718 -336.89916) (xy 182.706681 -336.836675) (xy 182.769166 -336.779712) (xy 182.83664 -336.728758)
			(xy 182.908528 -336.684247) (xy 182.984216 -336.646559) (xy 183.063059 -336.616015) (xy 183.144383 -336.592876)
			(xy 183.227496 -336.57734) (xy 183.311688 -336.569538) (xy 183.39624 -336.569538) (xy 183.480432 -336.57734)
			(xy 183.563545 -336.592876) (xy 183.644869 -336.616015) (xy 183.723712 -336.646559) (xy 183.7994 -336.684247)
			(xy 183.871288 -336.728758) (xy 183.938762 -336.779712) (xy 184.001247 -336.836675) (xy 184.05821 -336.89916)
			(xy 184.109164 -336.966634) (xy 184.153675 -337.038522) (xy 184.191363 -337.11421) (xy 184.221907 -337.193053)
			(xy 184.245046 -337.274377) (xy 184.260582 -337.35749) (xy 184.268384 -337.441682) (xy 184.268872 -337.483958)
			(xy 184.268338 -337.527902) (xy 184.259914 -337.615385) (xy 184.243138 -337.701657) (xy 184.218167 -337.785923)
			(xy 184.185229 -337.867405) (xy 184.144629 -337.945353) (xy 184.096741 -338.019048) (xy 184.042007 -338.087812)
			(xy 183.98093 -338.151009) (xy 183.914074 -338.208057) (xy 183.842055 -338.258431) (xy 183.804052 -338.280502)
			(xy 183.792022 -338.28775) (xy 183.772209 -338.307642) (xy 183.758568 -338.332181) (xy 183.752134 -338.35951)
			(xy 183.753394 -338.387557) (xy 183.762252 -338.414199) (xy 183.778037 -338.437416) (xy 183.799554 -338.455452)
			(xy 183.81218 -338.461604) (xy 183.839112 -338.474322) (xy 183.889 -338.506852) (xy 183.911494 -338.526374)
			(xy 183.922936 -338.536019) (xy 183.949979 -338.548799) (xy 183.979566 -338.553185) (xy 184.009153 -338.548799)
			(xy 184.036196 -338.536019) (xy 184.047638 -338.526374) (xy 184.068792 -338.507958) (xy 184.115469 -338.476864)
			(xy 184.166199 -338.452947) (xy 184.219887 -338.436726) (xy 184.275373 -338.428551) (xy 184.303416 -338.428076)
			(xy 184.330787 -338.428514) (xy 184.384968 -338.436336) (xy 184.437473 -338.45183) (xy 184.487219 -338.474679)
			(xy 184.533184 -338.504411) (xy 184.554114 -338.522056) (xy 184.565442 -338.531292) (xy 184.591999 -338.543468)
			(xy 184.620916 -338.547641) (xy 184.649833 -338.543468) (xy 184.67639 -338.531292) (xy 184.687718 -338.522056)
			(xy 184.708664 -338.504435) (xy 184.754634 -338.474722) (xy 184.804378 -338.451883) (xy 184.856875 -338.436387)
			(xy 184.911048 -338.428553) (xy 184.938416 -338.428076) (xy 184.965667 -338.428563) (xy 185.019614 -338.436321)
			(xy 185.071908 -338.451677) (xy 185.121484 -338.474319) (xy 185.167333 -338.503786) (xy 185.208523 -338.539477)
			(xy 185.244214 -338.580667) (xy 185.273681 -338.626516) (xy 185.296323 -338.676092) (xy 185.311679 -338.728386)
			(xy 185.319437 -338.782333) (xy 185.319924 -338.809584) (xy 185.319467 -338.836955) (xy 185.31165 -338.891135)
			(xy 185.29616 -338.943639) (xy 185.273315 -338.993386) (xy 185.243587 -339.039351) (xy 185.225944 -339.060282)
			(xy 185.216727 -339.071623) (xy 185.204555 -339.098177) (xy 185.200381 -339.127088) (xy 185.204548 -339.156)
			(xy 185.216714 -339.182557) (xy 185.225944 -339.193886) (xy 185.24357 -339.214831) (xy 185.273298 -339.260796)
			(xy 185.296146 -339.31054) (xy 185.311645 -339.36304) (xy 185.319475 -339.417218) (xy 185.319477 -339.471958)
			(xy 185.31165 -339.526136) (xy 185.296154 -339.578637) (xy 185.273309 -339.628383) (xy 185.243585 -339.67435)
			(xy 185.225944 -339.695282) (xy 185.216727 -339.706623) (xy 185.204555 -339.733177) (xy 185.200381 -339.762088)
			(xy 185.204548 -339.791) (xy 185.216714 -339.817557) (xy 185.225944 -339.828886) (xy 185.24357 -339.849831)
			(xy 185.273298 -339.895796) (xy 185.296146 -339.94554) (xy 185.311645 -339.99804) (xy 185.319475 -340.052218)
			(xy 185.319477 -340.106958) (xy 185.31165 -340.161136) (xy 185.296154 -340.213637) (xy 185.273309 -340.263383)
			(xy 185.243585 -340.30935) (xy 185.225944 -340.330282) (xy 185.216727 -340.341623) (xy 185.204555 -340.368177)
			(xy 185.200381 -340.397088) (xy 185.204548 -340.426) (xy 185.216714 -340.452557) (xy 185.225944 -340.463886)
			(xy 185.24357 -340.484831) (xy 185.273298 -340.530796) (xy 185.296146 -340.58054) (xy 185.311645 -340.63304)
			(xy 185.319475 -340.687218) (xy 185.319477 -340.741958) (xy 185.31165 -340.796136) (xy 185.296154 -340.848637)
			(xy 185.273309 -340.898383) (xy 185.243585 -340.94435) (xy 185.225944 -340.965282) (xy 185.216727 -340.976623)
			(xy 185.204555 -341.003177) (xy 185.200381 -341.032088) (xy 185.204548 -341.061) (xy 185.216714 -341.087557)
			(xy 185.225944 -341.098886) (xy 185.24357 -341.119831) (xy 185.273298 -341.165796) (xy 185.296146 -341.21554)
			(xy 185.311645 -341.26804) (xy 185.319475 -341.322218) (xy 185.319477 -341.376958) (xy 185.31165 -341.431136)
			(xy 185.296154 -341.483637) (xy 185.273309 -341.533383) (xy 185.243585 -341.57935) (xy 185.225944 -341.600282)
			(xy 185.216727 -341.611623) (xy 185.204555 -341.638177) (xy 185.200381 -341.667088) (xy 185.204548 -341.696)
			(xy 185.216714 -341.722557) (xy 185.225944 -341.733886) (xy 185.24357 -341.754831) (xy 185.273298 -341.800796)
			(xy 185.296146 -341.85054) (xy 185.311645 -341.90304) (xy 185.319475 -341.957218) (xy 185.319477 -342.011958)
			(xy 185.31165 -342.066136) (xy 185.296154 -342.118637) (xy 185.273309 -342.168383) (xy 185.243585 -342.21435)
			(xy 185.225944 -342.235282) (xy 185.216727 -342.246623) (xy 185.204555 -342.273177) (xy 185.200381 -342.302088)
			(xy 185.204548 -342.331) (xy 185.216714 -342.357557) (xy 185.225944 -342.368886) (xy 185.243597 -342.389807)
			(xy 185.273306 -342.435783) (xy 185.296138 -342.485534) (xy 185.311626 -342.538037) (xy 185.319452 -342.592214)
			(xy 185.319924 -342.619584) (xy 185.319407 -342.646834) (xy 185.311653 -342.70078) (xy 185.296301 -342.753073)
			(xy 185.273663 -342.802649) (xy 185.2442 -342.848499) (xy 185.208511 -342.889689) (xy 185.167324 -342.92538)
			(xy 185.121477 -342.954847) (xy 185.071903 -342.97749) (xy 185.019611 -342.992846) (xy 184.965666 -343.000605)
			(xy 184.938416 -343.001092) (xy 184.911046 -343.000619) (xy 184.856867 -342.992803) (xy 184.804364 -342.977316)
			(xy 184.754617 -342.954475) (xy 184.70865 -342.924752) (xy 184.687718 -342.907112) (xy 184.67639 -342.897876)
			(xy 184.649833 -342.8857) (xy 184.620916 -342.881527) (xy 184.591999 -342.8857) (xy 184.565442 -342.897876)
			(xy 184.554114 -342.907112) (xy 184.533189 -342.92476) (xy 184.487214 -342.95447) (xy 184.437465 -342.977304)
			(xy 184.384963 -342.992793) (xy 184.330786 -343.000619) (xy 184.303416 -343.001092) (xy 184.275376 -343.000597)
			(xy 184.219898 -342.992398) (xy 184.166215 -342.976172) (xy 184.115483 -342.952271) (xy 184.068792 -342.921207)
			(xy 184.047638 -342.902794) (xy 184.036196 -342.893149) (xy 184.009153 -342.880369) (xy 183.979566 -342.875983)
			(xy 183.949979 -342.880369) (xy 183.922936 -342.893149) (xy 183.911494 -342.902794) (xy 183.890362 -342.921237)
			(xy 183.84368 -342.952329) (xy 183.792944 -342.97624) (xy 183.739251 -342.992455) (xy 183.683761 -343.000622)
			(xy 183.655716 -343.001092) (xy 183.628463 -343.00063) (xy 183.574511 -342.992875) (xy 183.522212 -342.97752)
			(xy 183.472631 -342.954878) (xy 183.426777 -342.92541) (xy 183.385584 -342.889716) (xy 183.34989 -342.848523)
			(xy 183.320422 -342.802669) (xy 183.29778 -342.753088) (xy 183.282425 -342.700789) (xy 183.27467 -342.646837)
			(xy 183.274208 -342.619584) (xy 183.274663 -342.592213) (xy 183.282483 -342.538034) (xy 183.297975 -342.48553)
			(xy 183.320819 -342.435784) (xy 183.350546 -342.389817) (xy 183.368188 -342.368886) (xy 183.377441 -342.357571)
			(xy 183.389618 -342.331009) (xy 183.393788 -342.302088) (xy 183.389611 -342.273168) (xy 183.377428 -342.246609)
			(xy 183.368188 -342.235282) (xy 183.350533 -342.214361) (xy 183.320812 -342.16839) (xy 183.29797 -342.118642)
			(xy 183.282477 -342.066138) (xy 183.27465 -342.011959) (xy 183.274652 -341.957217) (xy 183.282482 -341.903038)
			(xy 183.297979 -341.850535) (xy 183.320824 -341.800788) (xy 183.350548 -341.75482) (xy 183.368188 -341.733886)
			(xy 183.377441 -341.722571) (xy 183.389618 -341.696009) (xy 183.393788 -341.667088) (xy 183.389611 -341.638168)
			(xy 183.377428 -341.611609) (xy 183.368188 -341.600282) (xy 183.350533 -341.579361) (xy 183.320812 -341.53339)
			(xy 183.29797 -341.483642) (xy 183.282477 -341.431138) (xy 183.27465 -341.376959) (xy 183.274652 -341.322217)
			(xy 183.282482 -341.268038) (xy 183.297979 -341.215535) (xy 183.320824 -341.165788) (xy 183.350548 -341.11982)
			(xy 183.368188 -341.098886) (xy 183.377441 -341.087571) (xy 183.389618 -341.061009) (xy 183.393788 -341.032088)
			(xy 183.389611 -341.003168) (xy 183.377428 -340.976609) (xy 183.368188 -340.965282) (xy 183.350533 -340.944361)
			(xy 183.320812 -340.89839) (xy 183.29797 -340.848642) (xy 183.282477 -340.796138) (xy 183.27465 -340.741959)
			(xy 183.274652 -340.687217) (xy 183.282482 -340.633038) (xy 183.297979 -340.580535) (xy 183.320824 -340.530788)
			(xy 183.350548 -340.48482) (xy 183.368188 -340.463886) (xy 183.377441 -340.452571) (xy 183.389618 -340.426009)
			(xy 183.393788 -340.397088) (xy 183.389611 -340.368168) (xy 183.377428 -340.341609) (xy 183.368188 -340.330282)
			(xy 183.350533 -340.309361) (xy 183.320812 -340.26339) (xy 183.29797 -340.213642) (xy 183.282477 -340.161138)
			(xy 183.27465 -340.106959) (xy 183.274652 -340.052217) (xy 183.282482 -339.998038) (xy 183.297979 -339.945535)
			(xy 183.320824 -339.895788) (xy 183.350548 -339.84982) (xy 183.368188 -339.828886) (xy 183.377441 -339.817571)
			(xy 183.389618 -339.791009) (xy 183.393788 -339.762088) (xy 183.389611 -339.733168) (xy 183.377428 -339.706609)
			(xy 183.368188 -339.695282) (xy 183.350533 -339.674361) (xy 183.320812 -339.62839) (xy 183.29797 -339.578642)
			(xy 183.282477 -339.526138) (xy 183.27465 -339.471959) (xy 183.274652 -339.417217) (xy 183.282482 -339.363038)
			(xy 183.297979 -339.310535) (xy 183.320824 -339.260788) (xy 183.350548 -339.21482) (xy 183.368188 -339.193886)
			(xy 183.377441 -339.182571) (xy 183.389618 -339.156009) (xy 183.393788 -339.127088) (xy 183.389611 -339.098168)
			(xy 183.377428 -339.071609) (xy 183.368188 -339.060282) (xy 183.350572 -339.039331) (xy 183.320857 -338.993363)
			(xy 183.298017 -338.943621) (xy 183.28252 -338.891124) (xy 183.274686 -338.836952) (xy 183.274208 -338.809584)
			(xy 183.274668 -338.782851) (xy 183.282177 -338.729914) (xy 183.296991 -338.67854) (xy 183.318821 -338.629732)
			(xy 183.347239 -338.584443) (xy 183.364124 -338.563712) (xy 183.372832 -338.552699) (xy 183.384366 -338.527111)
			(xy 183.388505 -338.499351) (xy 183.384937 -338.471511) (xy 183.373932 -338.445692) (xy 183.356318 -338.423839)
			(xy 183.333425 -338.407602) (xy 183.306978 -338.398203) (xy 183.293004 -338.396834) (xy 183.250113 -338.393549)
			(xy 183.165193 -338.379781) (xy 183.081941 -338.358103) (xy 183.001091 -338.328705) (xy 182.923357 -338.291848)
			(xy 182.849427 -338.247857) (xy 182.779952 -338.19712) (xy 182.715547 -338.140086) (xy 182.65678 -338.077258)
			(xy 182.604169 -338.009191) (xy 182.558181 -337.936486) (xy 182.51922 -337.859785) (xy 182.487632 -337.779766)
			(xy 182.463694 -337.697135) (xy 182.447618 -337.612622) (xy 182.439547 -337.526972) (xy 182.439056 -337.483958)
			(xy 178.071272 -337.483958) (xy 178.070769 -337.526865) (xy 178.062734 -337.612303) (xy 178.046733 -337.696613)
			(xy 178.022907 -337.779054) (xy 177.991466 -337.858902) (xy 177.952686 -337.935454) (xy 177.906908 -338.008039)
			(xy 177.854535 -338.076019) (xy 177.796026 -338.138795) (xy 177.731895 -338.195816) (xy 177.662707 -338.246582)
			(xy 177.589068 -338.290646) (xy 177.511628 -338.32762) (xy 177.431065 -338.357181) (xy 177.348088 -338.379067)
			(xy 177.263426 -338.393087) (xy 177.177824 -338.399118) (xy 177.092032 -338.397106) (xy 177.006806 -338.38707)
			(xy 176.922895 -338.369097) (xy 176.841035 -338.343345) (xy 176.761946 -338.310041) (xy 176.686324 -338.269477)
			(xy 176.614832 -338.22201) (xy 176.548099 -338.168057) (xy 176.486712 -338.108093) (xy 176.431209 -338.042643)
			(xy 176.38208 -337.972284) (xy 176.339754 -337.897633) (xy 176.304605 -337.819347) (xy 176.276942 -337.738113)
			(xy 176.257006 -337.654646) (xy 176.244975 -337.569678) (xy 176.240953 -337.483958) (xy 171.880456 -337.483958)
			(xy 171.880027 -337.520515) (xy 171.871992 -337.605953) (xy 171.855991 -337.690263) (xy 171.832165 -337.772704)
			(xy 171.800724 -337.852552) (xy 171.761944 -337.929104) (xy 171.716166 -338.001689) (xy 171.663793 -338.069669)
			(xy 171.605284 -338.132445) (xy 171.541153 -338.189466) (xy 171.471965 -338.240232) (xy 171.398326 -338.284296)
			(xy 171.320886 -338.32127) (xy 171.240323 -338.350831) (xy 171.157346 -338.372717) (xy 171.072684 -338.386737)
			(xy 170.987082 -338.392768) (xy 170.90129 -338.390756) (xy 170.816064 -338.38072) (xy 170.732153 -338.362747)
			(xy 170.650293 -338.336995) (xy 170.571204 -338.303691) (xy 170.495582 -338.263127) (xy 170.42409 -338.21566)
			(xy 170.357357 -338.161707) (xy 170.29597 -338.101743) (xy 170.240467 -338.036293) (xy 170.191338 -337.965934)
			(xy 170.149012 -337.891283) (xy 170.113863 -337.812997) (xy 170.0862 -337.731763) (xy 170.066264 -337.648296)
			(xy 170.054233 -337.563328) (xy 170.050211 -337.477608) (xy 165.669468 -337.477608) (xy 165.669468 -352.996246)
			(xy 165.959028 -353.285806) (xy 165.98392 -353.28225) (xy 165.997184 -353.280475) (xy 166.023879 -353.278566)
			(xy 166.03726 -353.27844) (xy 166.063924 -353.278882) (xy 166.116732 -353.286304) (xy 166.167991 -353.301008)
			(xy 166.216703 -353.322709) (xy 166.261918 -353.350982) (xy 166.302754 -353.385278) (xy 166.338416 -353.424926)
			(xy 166.368208 -353.469156) (xy 166.391549 -353.517103) (xy 166.407985 -353.567834) (xy 166.417195 -353.62036)
			(xy 166.418514 -353.646994) (xy 166.427034 -353.675385) (xy 166.436218 -353.733944) (xy 166.436802 -353.76358)
			(xy 166.436262 -353.792545) (xy 166.427512 -353.84981) (xy 166.410224 -353.905101) (xy 166.384795 -353.957151)
			(xy 166.36873 -353.981258) (xy 166.361311 -353.992713) (xy 166.352245 -354.018445) (xy 166.350317 -354.045658)
			(xy 166.355666 -354.07241) (xy 166.367908 -354.096791) (xy 166.386171 -354.117058) (xy 166.397432 -354.124768)
			(xy 166.426226 -354.143685) (xy 166.479943 -354.186832) (xy 166.50462 -354.210874) (xy 166.854886 -354.56114)
			(xy 166.879769 -354.58669) (xy 166.924252 -354.64244) (xy 166.962209 -354.702824) (xy 166.993163 -354.767079)
			(xy 167.016724 -354.834397) (xy 167.032595 -354.903931) (xy 167.040577 -354.974805) (xy 167.041068 -355.010466)
			(xy 167.041068 -356.359968) (xy 167.169592 -356.359968) (xy 167.169592 -346.88399) (xy 167.170042 -346.859001)
			(xy 167.17787 -346.80964) (xy 167.193333 -346.762114) (xy 167.216047 -346.717595) (xy 167.245453 -346.677184)
			(xy 167.26281 -346.6592) (xy 168.588944 -345.33332) (xy 168.588944 -342.830658) (xy 168.573857 -342.807094)
			(xy 168.550029 -342.756471) (xy 168.533854 -342.70291) (xy 168.52568 -342.647559) (xy 168.52519 -342.619584)
			(xy 168.525649 -342.592214) (xy 168.533469 -342.538034) (xy 168.54896 -342.485531) (xy 168.571803 -342.435784)
			(xy 168.601528 -342.389818) (xy 168.61917 -342.368886) (xy 168.628425 -342.357571) (xy 168.640604 -342.33101)
			(xy 168.644775 -342.302088) (xy 168.640597 -342.273167) (xy 168.628412 -342.246608) (xy 168.61917 -342.235282)
			(xy 168.601512 -342.214363) (xy 168.571784 -342.168394) (xy 168.548937 -342.118645) (xy 168.53344 -342.066141)
			(xy 168.525612 -342.01196) (xy 168.525614 -341.957216) (xy 168.533446 -341.903035) (xy 168.548946 -341.850532)
			(xy 168.571796 -341.800785) (xy 168.601526 -341.754818) (xy 168.61917 -341.733886) (xy 168.628425 -341.722571)
			(xy 168.640604 -341.69601) (xy 168.644775 -341.667088) (xy 168.640597 -341.638167) (xy 168.628412 -341.611608)
			(xy 168.61917 -341.600282) (xy 168.601512 -341.579363) (xy 168.571784 -341.533394) (xy 168.548937 -341.483645)
			(xy 168.53344 -341.431141) (xy 168.525612 -341.37696) (xy 168.525614 -341.322216) (xy 168.533446 -341.268035)
			(xy 168.548946 -341.215532) (xy 168.571796 -341.165785) (xy 168.601526 -341.119818) (xy 168.61917 -341.098886)
			(xy 168.628425 -341.087571) (xy 168.640604 -341.06101) (xy 168.644775 -341.032088) (xy 168.640597 -341.003167)
			(xy 168.628412 -340.976608) (xy 168.61917 -340.965282) (xy 168.601512 -340.944363) (xy 168.571784 -340.898394)
			(xy 168.548937 -340.848645) (xy 168.53344 -340.796141) (xy 168.525612 -340.74196) (xy 168.525614 -340.687216)
			(xy 168.533446 -340.633035) (xy 168.548946 -340.580532) (xy 168.571796 -340.530785) (xy 168.601526 -340.484818)
			(xy 168.61917 -340.463886) (xy 168.628425 -340.452571) (xy 168.640604 -340.42601) (xy 168.644775 -340.397088)
			(xy 168.640597 -340.368167) (xy 168.628412 -340.341608) (xy 168.61917 -340.330282) (xy 168.601512 -340.309363)
			(xy 168.571784 -340.263394) (xy 168.548937 -340.213645) (xy 168.53344 -340.161141) (xy 168.525612 -340.10696)
			(xy 168.525614 -340.052216) (xy 168.533446 -339.998035) (xy 168.548946 -339.945532) (xy 168.571796 -339.895785)
			(xy 168.601526 -339.849818) (xy 168.61917 -339.828886) (xy 168.628425 -339.817571) (xy 168.640604 -339.79101)
			(xy 168.644775 -339.762088) (xy 168.640597 -339.733167) (xy 168.628412 -339.706608) (xy 168.61917 -339.695282)
			(xy 168.601512 -339.674363) (xy 168.571784 -339.628394) (xy 168.548937 -339.578645) (xy 168.53344 -339.526141)
			(xy 168.525612 -339.47196) (xy 168.525614 -339.417216) (xy 168.533446 -339.363035) (xy 168.548946 -339.310532)
			(xy 168.571796 -339.260785) (xy 168.601526 -339.214818) (xy 168.61917 -339.193886) (xy 168.628425 -339.182571)
			(xy 168.640604 -339.15601) (xy 168.644775 -339.127088) (xy 168.640597 -339.098167) (xy 168.628412 -339.071608)
			(xy 168.61917 -339.060282) (xy 168.601551 -339.039334) (xy 168.571837 -338.993365) (xy 168.548998 -338.943621)
			(xy 168.533502 -338.891125) (xy 168.525668 -338.836952) (xy 168.52519 -338.809584) (xy 168.525663 -338.782332)
			(xy 168.533422 -338.728384) (xy 168.548779 -338.676089) (xy 168.571421 -338.626512) (xy 168.600889 -338.580662)
			(xy 168.636582 -338.539472) (xy 168.677773 -338.503781) (xy 168.723625 -338.474315) (xy 168.773203 -338.451674)
			(xy 168.825498 -338.436319) (xy 168.879446 -338.428562) (xy 168.906698 -338.428076) (xy 168.934069 -338.428525)
			(xy 168.98825 -338.436344) (xy 169.040754 -338.451836) (xy 169.0905 -338.474682) (xy 169.136466 -338.504412)
			(xy 169.157396 -338.522056) (xy 169.168724 -338.531292) (xy 169.195281 -338.543468) (xy 169.224198 -338.547641)
			(xy 169.253115 -338.543468) (xy 169.279672 -338.531292) (xy 169.291 -338.522056) (xy 169.311915 -338.504396)
			(xy 169.357893 -338.474689) (xy 169.407645 -338.451858) (xy 169.460149 -338.436371) (xy 169.514328 -338.428547)
			(xy 169.541698 -338.428076) (xy 169.569738 -338.428571) (xy 169.625216 -338.436772) (xy 169.678898 -338.452997)
			(xy 169.72963 -338.476899) (xy 169.776322 -338.507962) (xy 169.797476 -338.526374) (xy 169.808918 -338.536019)
			(xy 169.835961 -338.548799) (xy 169.865548 -338.553185) (xy 169.895135 -338.548799) (xy 169.922178 -338.536019)
			(xy 169.93362 -338.526374) (xy 169.954781 -338.507967) (xy 170.001456 -338.476871) (xy 170.052184 -338.452953)
			(xy 170.105871 -338.43673) (xy 170.161356 -338.428552) (xy 170.189398 -338.428076) (xy 170.216648 -338.42858)
			(xy 170.270595 -338.436335) (xy 170.322888 -338.451689) (xy 170.372464 -338.474329) (xy 170.418314 -338.503794)
			(xy 170.459504 -338.539483) (xy 170.495195 -338.580672) (xy 170.524662 -338.62652) (xy 170.547304 -338.676095)
			(xy 170.562661 -338.728388) (xy 170.570419 -338.782334) (xy 170.570906 -338.809584) (xy 170.570429 -338.836954)
			(xy 170.562614 -338.891132) (xy 170.547127 -338.943635) (xy 170.524288 -338.993382) (xy 170.494566 -339.03935)
			(xy 170.476926 -339.060282) (xy 170.467702 -339.07162) (xy 170.45552 -339.098173) (xy 170.451343 -339.127088)
			(xy 170.455513 -339.156003) (xy 170.467689 -339.18256) (xy 170.476926 -339.193886) (xy 170.494553 -339.214831)
			(xy 170.524282 -339.260795) (xy 170.547131 -339.310539) (xy 170.562631 -339.36304) (xy 170.570462 -339.417218)
			(xy 170.570464 -339.471958) (xy 170.562636 -339.526137) (xy 170.54714 -339.578638) (xy 170.524294 -339.628384)
			(xy 170.494568 -339.67435) (xy 170.476926 -339.695282) (xy 170.467702 -339.70662) (xy 170.45552 -339.733173)
			(xy 170.451343 -339.762088) (xy 170.455513 -339.791003) (xy 170.467689 -339.81756) (xy 170.476926 -339.828886)
			(xy 170.494553 -339.849831) (xy 170.524282 -339.895795) (xy 170.547131 -339.945539) (xy 170.562631 -339.99804)
			(xy 170.570462 -340.052218) (xy 170.570464 -340.106958) (xy 170.562636 -340.161137) (xy 170.54714 -340.213638)
			(xy 170.524294 -340.263384) (xy 170.494568 -340.30935) (xy 170.476926 -340.330282) (xy 170.467702 -340.34162)
			(xy 170.45552 -340.368173) (xy 170.451343 -340.397088) (xy 170.455513 -340.426003) (xy 170.467689 -340.45256)
			(xy 170.476926 -340.463886) (xy 170.494553 -340.484831) (xy 170.524282 -340.530795) (xy 170.547131 -340.580539)
			(xy 170.562631 -340.63304) (xy 170.570462 -340.687218) (xy 170.570464 -340.741958) (xy 170.562636 -340.796137)
			(xy 170.54714 -340.848638) (xy 170.524294 -340.898384) (xy 170.494568 -340.94435) (xy 170.476926 -340.965282)
			(xy 170.467702 -340.97662) (xy 170.45552 -341.003173) (xy 170.451343 -341.032088) (xy 170.455513 -341.061003)
			(xy 170.467689 -341.08756) (xy 170.476926 -341.098886) (xy 170.494553 -341.119831) (xy 170.524282 -341.165795)
			(xy 170.547131 -341.215539) (xy 170.562631 -341.26804) (xy 170.570462 -341.322218) (xy 170.570464 -341.376958)
			(xy 170.562636 -341.431137) (xy 170.54714 -341.483638) (xy 170.524294 -341.533384) (xy 170.494568 -341.57935)
			(xy 170.476926 -341.600282) (xy 170.467702 -341.61162) (xy 170.45552 -341.638173) (xy 170.451343 -341.667088)
			(xy 170.455513 -341.696003) (xy 170.467689 -341.72256) (xy 170.476926 -341.733886) (xy 170.494553 -341.754831)
			(xy 170.524282 -341.800795) (xy 170.547131 -341.850539) (xy 170.562631 -341.90304) (xy 170.570462 -341.957218)
			(xy 170.570464 -342.011958) (xy 170.562636 -342.066137) (xy 170.54714 -342.118638) (xy 170.524294 -342.168384)
			(xy 170.494568 -342.21435) (xy 170.476926 -342.235282) (xy 170.467702 -342.24662) (xy 170.45552 -342.273173)
			(xy 170.451343 -342.302088) (xy 170.455513 -342.331003) (xy 170.467689 -342.35756) (xy 170.476926 -342.368886)
			(xy 170.494576 -342.389809) (xy 170.524285 -342.435785) (xy 170.547119 -342.485535) (xy 170.562607 -342.538037)
			(xy 170.570433 -342.592214) (xy 170.570906 -342.619584) (xy 173.495462 -342.619584) (xy 173.495904 -342.592213)
			(xy 173.503725 -342.538032) (xy 173.519219 -342.485528) (xy 173.542067 -342.435781) (xy 173.571797 -342.389816)
			(xy 173.589442 -342.368886) (xy 173.598691 -342.357569) (xy 173.610861 -342.331007) (xy 173.615029 -342.302088)
			(xy 173.610854 -342.27317) (xy 173.598678 -342.246611) (xy 173.589442 -342.235282) (xy 173.571785 -342.214362)
			(xy 173.54206 -342.168393) (xy 173.519214 -342.118644) (xy 173.503719 -342.06614) (xy 173.495891 -342.011959)
			(xy 173.495893 -341.957216) (xy 173.503724 -341.903036) (xy 173.519223 -341.850533) (xy 173.542071 -341.800786)
			(xy 173.5718 -341.754818) (xy 173.589442 -341.733886) (xy 173.598691 -341.722569) (xy 173.610861 -341.696007)
			(xy 173.615029 -341.667088) (xy 173.610854 -341.63817) (xy 173.598678 -341.611611) (xy 173.589442 -341.600282)
			(xy 173.571785 -341.579362) (xy 173.54206 -341.533393) (xy 173.519214 -341.483644) (xy 173.503719 -341.43114)
			(xy 173.495891 -341.376959) (xy 173.495893 -341.322216) (xy 173.503724 -341.268036) (xy 173.519223 -341.215533)
			(xy 173.542071 -341.165786) (xy 173.5718 -341.119818) (xy 173.589442 -341.098886) (xy 173.598691 -341.087569)
			(xy 173.610861 -341.061007) (xy 173.615029 -341.032088) (xy 173.610854 -341.00317) (xy 173.598678 -340.976611)
			(xy 173.589442 -340.965282) (xy 173.571785 -340.944362) (xy 173.54206 -340.898393) (xy 173.519214 -340.848644)
			(xy 173.503719 -340.79614) (xy 173.495891 -340.741959) (xy 173.495893 -340.687216) (xy 173.503724 -340.633036)
			(xy 173.519223 -340.580533) (xy 173.542071 -340.530786) (xy 173.5718 -340.484818) (xy 173.589442 -340.463886)
			(xy 173.598691 -340.452569) (xy 173.610861 -340.426007) (xy 173.615029 -340.397088) (xy 173.610854 -340.36817)
			(xy 173.598678 -340.341611) (xy 173.589442 -340.330282) (xy 173.571785 -340.309362) (xy 173.54206 -340.263393)
			(xy 173.519214 -340.213644) (xy 173.503719 -340.16114) (xy 173.495891 -340.106959) (xy 173.495893 -340.052216)
			(xy 173.503724 -339.998036) (xy 173.519223 -339.945533) (xy 173.542071 -339.895786) (xy 173.5718 -339.849818)
			(xy 173.589442 -339.828886) (xy 173.598691 -339.817569) (xy 173.610861 -339.791007) (xy 173.615029 -339.762088)
			(xy 173.610854 -339.73317) (xy 173.598678 -339.706611) (xy 173.589442 -339.695282) (xy 173.571785 -339.674362)
			(xy 173.54206 -339.628393) (xy 173.519214 -339.578644) (xy 173.503719 -339.52614) (xy 173.495891 -339.471959)
			(xy 173.495893 -339.417216) (xy 173.503724 -339.363036) (xy 173.519223 -339.310533) (xy 173.542071 -339.260786)
			(xy 173.5718 -339.214818) (xy 173.589442 -339.193886) (xy 173.598691 -339.182569) (xy 173.610861 -339.156007)
			(xy 173.615029 -339.127088) (xy 173.610854 -339.09817) (xy 173.598678 -339.071611) (xy 173.589442 -339.060282)
			(xy 173.571834 -339.039324) (xy 173.542116 -338.993359) (xy 173.519274 -338.943618) (xy 173.503775 -338.891123)
			(xy 173.49594 -338.836952) (xy 173.495462 -338.809584) (xy 173.495963 -338.782334) (xy 173.503721 -338.728388)
			(xy 173.519076 -338.676095) (xy 173.541717 -338.62652) (xy 173.571182 -338.580671) (xy 173.606872 -338.539482)
			(xy 173.64806 -338.503791) (xy 173.693908 -338.474324) (xy 173.743482 -338.451681) (xy 173.795774 -338.436324)
			(xy 173.84972 -338.428564) (xy 173.87697 -338.428076) (xy 173.90501 -338.428587) (xy 173.960487 -338.436784)
			(xy 174.014169 -338.453006) (xy 174.064901 -338.476904) (xy 174.111593 -338.507964) (xy 174.132748 -338.526374)
			(xy 174.14419 -338.536019) (xy 174.171233 -338.548799) (xy 174.20082 -338.553185) (xy 174.230407 -338.548799)
			(xy 174.25745 -338.536019) (xy 174.268892 -338.526374) (xy 174.290025 -338.507932) (xy 174.336707 -338.476842)
			(xy 174.387443 -338.45293) (xy 174.441136 -338.436715) (xy 174.496626 -338.428547) (xy 174.52467 -338.428076)
			(xy 174.55204 -338.428541) (xy 174.60622 -338.436356) (xy 174.658724 -338.451845) (xy 174.708471 -338.474687)
			(xy 174.754437 -338.504413) (xy 174.775368 -338.522056) (xy 174.786696 -338.531292) (xy 174.813253 -338.543468)
			(xy 174.84217 -338.547641) (xy 174.871087 -338.543468) (xy 174.897644 -338.531292) (xy 174.908972 -338.522056)
			(xy 174.929898 -338.504409) (xy 174.975873 -338.4747) (xy 175.025622 -338.451866) (xy 175.078124 -338.436377)
			(xy 175.132301 -338.428549) (xy 175.15967 -338.428076) (xy 175.186921 -338.428583) (xy 175.24087 -338.436336)
			(xy 175.293166 -338.451687) (xy 175.342745 -338.474325) (xy 175.388597 -338.503788) (xy 175.42979 -338.539477)
			(xy 175.465484 -338.580666) (xy 175.494953 -338.626515) (xy 175.517597 -338.676091) (xy 175.532955 -338.728385)
			(xy 175.540714 -338.782333) (xy 175.541178 -338.809584) (xy 175.540708 -338.836954) (xy 175.532892 -338.891133)
			(xy 175.517404 -338.943637) (xy 175.494563 -338.993383) (xy 175.464839 -339.03935) (xy 175.447198 -339.060282)
			(xy 175.437977 -339.071621) (xy 175.425798 -339.098174) (xy 175.421622 -339.127088) (xy 175.425791 -339.156002)
			(xy 175.437964 -339.182559) (xy 175.447198 -339.193886) (xy 175.464822 -339.214832) (xy 175.494546 -339.260798)
			(xy 175.51739 -339.310542) (xy 175.532887 -339.363042) (xy 175.540716 -339.417218) (xy 175.540718 -339.471958)
			(xy 175.532892 -339.526134) (xy 175.517399 -339.578635) (xy 175.494557 -339.628381) (xy 175.464837 -339.674349)
			(xy 175.447198 -339.695282) (xy 175.437977 -339.706621) (xy 175.425798 -339.733174) (xy 175.421622 -339.762088)
			(xy 175.425791 -339.791002) (xy 175.437964 -339.817559) (xy 175.447198 -339.828886) (xy 175.464822 -339.849832)
			(xy 175.494546 -339.895798) (xy 175.51739 -339.945542) (xy 175.532887 -339.998042) (xy 175.540716 -340.052218)
			(xy 175.540718 -340.106958) (xy 175.532892 -340.161134) (xy 175.517399 -340.213635) (xy 175.494557 -340.263381)
			(xy 175.464837 -340.309349) (xy 175.447198 -340.330282) (xy 175.437977 -340.341621) (xy 175.425798 -340.368174)
			(xy 175.421622 -340.397088) (xy 175.425791 -340.426002) (xy 175.437964 -340.452559) (xy 175.447198 -340.463886)
			(xy 175.464822 -340.484832) (xy 175.494546 -340.530798) (xy 175.51739 -340.580542) (xy 175.532887 -340.633042)
			(xy 175.540716 -340.687218) (xy 175.540718 -340.741958) (xy 175.532892 -340.796134) (xy 175.517399 -340.848635)
			(xy 175.494557 -340.898381) (xy 175.464837 -340.944349) (xy 175.447198 -340.965282) (xy 175.437977 -340.976621)
			(xy 175.425798 -341.003174) (xy 175.421622 -341.032088) (xy 175.425791 -341.061002) (xy 175.437964 -341.087559)
			(xy 175.447198 -341.098886) (xy 175.464822 -341.119832) (xy 175.494546 -341.165798) (xy 175.51739 -341.215542)
			(xy 175.532887 -341.268042) (xy 175.540716 -341.322218) (xy 175.540718 -341.376958) (xy 175.532892 -341.431134)
			(xy 175.517399 -341.483635) (xy 175.494557 -341.533381) (xy 175.464837 -341.579349) (xy 175.447198 -341.600282)
			(xy 175.437977 -341.611621) (xy 175.425798 -341.638174) (xy 175.421622 -341.667088) (xy 175.425791 -341.696002)
			(xy 175.437964 -341.722559) (xy 175.447198 -341.733886) (xy 175.464822 -341.754832) (xy 175.494546 -341.800798)
			(xy 175.51739 -341.850542) (xy 175.532887 -341.903042) (xy 175.540716 -341.957218) (xy 175.540718 -342.011958)
			(xy 175.532892 -342.066134) (xy 175.517399 -342.118635) (xy 175.494557 -342.168381) (xy 175.464837 -342.214349)
			(xy 175.447198 -342.235282) (xy 175.437977 -342.246621) (xy 175.425798 -342.273174) (xy 175.421622 -342.302088)
			(xy 175.425791 -342.331002) (xy 175.437964 -342.357559) (xy 175.447198 -342.368886) (xy 175.464844 -342.389813)
			(xy 175.494555 -342.435787) (xy 175.517389 -342.485536) (xy 175.532879 -342.538038) (xy 175.540705 -342.592214)
			(xy 175.541178 -342.619584) (xy 175.54073 -342.646838) (xy 175.532974 -342.700791) (xy 175.517619 -342.753091)
			(xy 175.494976 -342.802673) (xy 175.465507 -342.848528) (xy 175.429811 -342.889721) (xy 175.388616 -342.925415)
			(xy 175.342761 -342.954883) (xy 175.293178 -342.977524) (xy 175.240877 -342.992877) (xy 175.186924 -343.000631)
			(xy 175.15967 -343.001092) (xy 175.132299 -343.000645) (xy 175.078119 -342.992823) (xy 175.025616 -342.97733)
			(xy 174.975869 -342.954484) (xy 174.929903 -342.924755) (xy 174.908972 -342.907112) (xy 174.897644 -342.897876)
			(xy 174.871087 -342.8857) (xy 174.84217 -342.881527) (xy 174.813253 -342.8857) (xy 174.786696 -342.897876)
			(xy 174.775368 -342.907112) (xy 174.754423 -342.924735) (xy 174.708453 -342.954448) (xy 174.658709 -342.977287)
			(xy 174.606211 -342.992782) (xy 174.552038 -343.000615) (xy 174.52467 -343.001092) (xy 174.496629 -343.000624)
			(xy 174.441149 -342.992418) (xy 174.387467 -342.976187) (xy 174.336735 -342.952279) (xy 174.290045 -342.921209)
			(xy 174.268892 -342.902794) (xy 174.25745 -342.893149) (xy 174.230407 -342.880369) (xy 174.20082 -342.875983)
			(xy 174.171233 -342.880369) (xy 174.14419 -342.893149) (xy 174.132748 -342.902794) (xy 174.111595 -342.921212)
			(xy 174.064919 -342.952307) (xy 174.014188 -342.976223) (xy 173.9605 -342.992444) (xy 173.905013 -343.000618)
			(xy 173.87697 -343.001092) (xy 173.849717 -343.00065) (xy 173.795767 -342.992889) (xy 173.743471 -342.977529)
			(xy 173.693892 -342.954883) (xy 173.648041 -342.925413) (xy 173.606851 -342.889717) (xy 173.57116 -342.848522)
			(xy 173.541694 -342.802667) (xy 173.519055 -342.753086) (xy 173.503701 -342.700788) (xy 173.495947 -342.646837)
			(xy 173.495462 -342.619584) (xy 170.570906 -342.619584) (xy 170.57043 -342.646837) (xy 170.562675 -342.700787)
			(xy 170.547321 -342.753085) (xy 170.52468 -342.802665) (xy 170.495214 -342.848518) (xy 170.459521 -342.889711)
			(xy 170.41833 -342.925405) (xy 170.372477 -342.954873) (xy 170.322898 -342.977516) (xy 170.270601 -342.992872)
			(xy 170.216651 -343.000629) (xy 170.189398 -343.001092) (xy 170.161357 -343.000608) (xy 170.105879 -342.992406)
			(xy 170.052196 -342.976178) (xy 170.001464 -342.952274) (xy 169.954773 -342.921208) (xy 169.93362 -342.902794)
			(xy 169.922178 -342.893149) (xy 169.895135 -342.880369) (xy 169.865548 -342.875983) (xy 169.835961 -342.880369)
			(xy 169.808918 -342.893149) (xy 169.797476 -342.902794) (xy 169.776312 -342.921198) (xy 169.729639 -342.952296)
			(xy 169.678911 -342.976215) (xy 169.625225 -342.992438) (xy 169.56974 -343.000616) (xy 169.541698 -343.001092)
			(xy 169.512279 -343.000528) (xy 169.454139 -342.99149) (xy 169.398082 -342.973614) (xy 169.371518 -342.96096)
			(xy 169.358053 -342.9548) (xy 169.328896 -342.949716) (xy 169.299504 -342.953198) (xy 169.272342 -342.964955)
			(xy 169.249687 -342.984) (xy 169.233437 -343.008738) (xy 169.224956 -343.037094) (xy 169.224452 -343.051892)
			(xy 169.224452 -345.464892) (xy 169.223984 -345.489867) (xy 169.21619 -345.539205) (xy 169.200777 -345.586718)
			(xy 169.178125 -345.631236) (xy 169.14879 -345.671664) (xy 169.131488 -345.689682) (xy 167.805608 -347.015562)
			(xy 167.805608 -355.02088) (xy 168.06799 -355.02088) (xy 168.068468 -354.992839) (xy 168.076672 -354.93736)
			(xy 168.092902 -354.883678) (xy 168.116807 -354.832946) (xy 168.147874 -354.786255) (xy 168.166288 -354.765102)
			(xy 168.175903 -354.753637) (xy 168.188686 -354.726603) (xy 168.193077 -354.697022) (xy 168.188699 -354.66744)
			(xy 168.175928 -354.6404) (xy 168.166288 -354.628958) (xy 168.147872 -354.607803) (xy 168.116777 -354.561127)
			(xy 168.092861 -354.510397) (xy 168.07664 -354.456709) (xy 168.068464 -354.401223) (xy 168.06799 -354.37318)
			(xy 168.068476 -354.345929) (xy 168.076232 -354.291981) (xy 168.091587 -354.239686) (xy 168.114229 -354.190109)
			(xy 168.143695 -354.144259) (xy 168.179386 -354.103068) (xy 168.220577 -354.067377) (xy 168.266427 -354.037911)
			(xy 168.316004 -354.015269) (xy 168.368299 -353.999914) (xy 168.422247 -353.992158) (xy 168.476749 -353.992158)
			(xy 168.530697 -353.999914) (xy 168.582992 -354.015269) (xy 168.632569 -354.037911) (xy 168.678419 -354.067377)
			(xy 168.71961 -354.103068) (xy 168.755301 -354.144259) (xy 168.784767 -354.190109) (xy 168.807409 -354.239686)
			(xy 168.822764 -354.291981) (xy 168.83052 -354.345929) (xy 168.831006 -354.37318) (xy 168.830505 -354.40122)
			(xy 168.822306 -354.456698) (xy 168.806083 -354.51038) (xy 168.782182 -354.561112) (xy 168.75112 -354.607804)
			(xy 168.732708 -354.628958) (xy 168.728189 -354.634292) (xy 176.045366 -354.634292) (xy 176.049437 -354.57867)
			(xy 176.061563 -354.524233) (xy 176.081486 -354.472142) (xy 176.108782 -354.423507) (xy 176.142868 -354.379364)
			(xy 176.183017 -354.340655) (xy 176.228375 -354.308204) (xy 176.277975 -354.282703) (xy 176.330759 -354.264696)
			(xy 176.385602 -354.254566) (xy 176.441336 -354.252529) (xy 176.496773 -354.258629) (xy 176.55073 -354.272735)
			(xy 176.602059 -354.294547) (xy 176.649665 -354.323601) (xy 176.692533 -354.359276) (xy 176.72975 -354.400813)
			(xy 176.760523 -354.447326) (xy 176.784195 -354.497823) (xy 176.800263 -354.55123) (xy 176.808383 -354.606406)
			(xy 176.808892 -354.634292) (xy 176.808383 -354.662178) (xy 176.800263 -354.717354) (xy 176.784195 -354.770761)
			(xy 176.760523 -354.821258) (xy 176.72975 -354.867771) (xy 176.692533 -354.909308) (xy 176.649665 -354.944983)
			(xy 176.602059 -354.974037) (xy 176.55073 -354.995849) (xy 176.496773 -355.009955) (xy 176.455195 -355.01453)
			(xy 177.756312 -355.01453) (xy 177.756793 -354.98716) (xy 177.764607 -354.932982) (xy 177.780092 -354.880479)
			(xy 177.802931 -354.830732) (xy 177.832652 -354.784764) (xy 177.850292 -354.763832) (xy 177.859501 -354.752483)
			(xy 177.871683 -354.725934) (xy 177.875861 -354.697023) (xy 177.871695 -354.66811) (xy 177.859525 -354.641555)
			(xy 177.850292 -354.630228) (xy 177.832651 -354.609297) (xy 177.80294 -354.563324) (xy 177.780104 -354.513576)
			(xy 177.764614 -354.461075) (xy 177.756786 -354.406899) (xy 177.756312 -354.37953) (xy 177.756798 -354.352279)
			(xy 177.764554 -354.298331) (xy 177.779909 -354.246036) (xy 177.802551 -354.196459) (xy 177.832017 -354.150609)
			(xy 177.867708 -354.109418) (xy 177.908899 -354.073727) (xy 177.954749 -354.044261) (xy 178.004326 -354.021619)
			(xy 178.056621 -354.006264) (xy 178.110569 -353.998508) (xy 178.165071 -353.998508) (xy 178.219019 -354.006264)
			(xy 178.271314 -354.021619) (xy 178.320891 -354.044261) (xy 178.366741 -354.073727) (xy 178.407932 -354.109418)
			(xy 178.443623 -354.150609) (xy 178.473089 -354.196459) (xy 178.495731 -354.246036) (xy 178.511086 -354.298331)
			(xy 178.518842 -354.352279) (xy 178.519328 -354.37953) (xy 178.518897 -354.406902) (xy 178.511073 -354.461083)
			(xy 178.495577 -354.513587) (xy 178.472727 -354.563334) (xy 178.442994 -354.609298) (xy 178.425348 -354.630228)
			(xy 178.416086 -354.641535) (xy 178.403918 -354.668101) (xy 178.399754 -354.697023) (xy 178.403931 -354.725942)
			(xy 178.416111 -354.752503) (xy 178.425348 -354.763832) (xy 178.442961 -354.784786) (xy 178.472678 -354.830752)
			(xy 178.49552 -354.880494) (xy 178.511017 -354.93299) (xy 178.518851 -354.987162) (xy 178.519328 -355.01453)
			(xy 178.518842 -355.041781) (xy 178.511086 -355.095729) (xy 178.495731 -355.148024) (xy 178.473089 -355.197601)
			(xy 178.443623 -355.243451) (xy 178.407932 -355.284642) (xy 178.366741 -355.320333) (xy 178.320891 -355.349799)
			(xy 178.271314 -355.372441) (xy 178.219019 -355.387796) (xy 178.165071 -355.395552) (xy 178.110569 -355.395552)
			(xy 178.056621 -355.387796) (xy 178.004326 -355.372441) (xy 177.954749 -355.349799) (xy 177.908899 -355.320333)
			(xy 177.867708 -355.284642) (xy 177.832017 -355.243451) (xy 177.802551 -355.197601) (xy 177.779909 -355.148024)
			(xy 177.764554 -355.095729) (xy 177.756798 -355.041781) (xy 177.756312 -355.01453) (xy 176.455195 -355.01453)
			(xy 176.441336 -355.016055) (xy 176.385602 -355.014018) (xy 176.330759 -355.003888) (xy 176.277975 -354.985881)
			(xy 176.228375 -354.96038) (xy 176.183017 -354.927929) (xy 176.142868 -354.88922) (xy 176.108782 -354.845077)
			(xy 176.081486 -354.796442) (xy 176.061563 -354.744351) (xy 176.049437 -354.689914) (xy 176.045366 -354.634292)
			(xy 168.728189 -354.634292) (xy 168.723034 -354.640377) (xy 168.710259 -354.667429) (xy 168.705879 -354.697022)
			(xy 168.710272 -354.726614) (xy 168.723059 -354.75366) (xy 168.732708 -354.765102) (xy 168.751151 -354.786234)
			(xy 168.782243 -354.832916) (xy 168.806154 -354.883652) (xy 168.822368 -354.937345) (xy 168.830536 -354.992835)
			(xy 168.831006 -355.02088) (xy 168.83052 -355.048131) (xy 168.822764 -355.102079) (xy 168.807409 -355.154374)
			(xy 168.784767 -355.203951) (xy 168.755301 -355.249801) (xy 168.71961 -355.290992) (xy 168.678419 -355.326683)
			(xy 168.632569 -355.356149) (xy 168.582992 -355.378791) (xy 168.530697 -355.394146) (xy 168.476749 -355.401902)
			(xy 168.422247 -355.401902) (xy 168.368299 -355.394146) (xy 168.316004 -355.378791) (xy 168.266427 -355.356149)
			(xy 168.220577 -355.326683) (xy 168.179386 -355.290992) (xy 168.143695 -355.249801) (xy 168.114229 -355.203951)
			(xy 168.091587 -355.154374) (xy 168.076232 -355.102079) (xy 168.068476 -355.048131) (xy 168.06799 -355.02088)
			(xy 167.805608 -355.02088) (xy 167.805608 -355.4171) (xy 172.316679 -355.4171) (xy 172.320847 -355.361492)
			(xy 172.333255 -355.307126) (xy 172.353627 -355.255216) (xy 172.381508 -355.206922) (xy 172.416275 -355.163323)
			(xy 172.457152 -355.125392) (xy 172.503225 -355.093977) (xy 172.553465 -355.069779) (xy 172.606751 -355.053339)
			(xy 172.661892 -355.045025) (xy 172.689774 -355.044502) (xy 172.717106 -355.044977) (xy 172.771185 -355.052948)
			(xy 172.823518 -355.068736) (xy 172.872982 -355.092004) (xy 172.918514 -355.122251) (xy 172.959137 -355.158828)
			(xy 172.993977 -355.200949) (xy 173.008544 -355.22408) (xy 173.016453 -355.236315) (xy 173.037926 -355.255989)
			(xy 173.064084 -355.268794) (xy 173.092794 -355.273686) (xy 173.121716 -355.270266) (xy 173.13529 -355.264974)
			(xy 173.158503 -355.255494) (xy 173.206835 -355.24214) (xy 173.256523 -355.235408) (xy 173.281594 -355.235002)
			(xy 173.306663 -355.235442) (xy 173.356345 -355.242185) (xy 173.40468 -355.255511) (xy 173.427898 -355.264974)
			(xy 173.441482 -355.270214) (xy 173.470388 -355.273597) (xy 173.499075 -355.268699) (xy 173.52522 -355.255916)
			(xy 173.546704 -355.236283) (xy 173.554644 -355.22408) (xy 173.569213 -355.200949) (xy 173.604056 -355.158828)
			(xy 173.644679 -355.122249) (xy 173.69021 -355.091998) (xy 173.739672 -355.068722) (xy 173.792003 -355.052922)
			(xy 173.846082 -355.044936) (xy 173.900746 -355.044936) (xy 173.954825 -355.052922) (xy 174.007156 -355.068722)
			(xy 174.056618 -355.091998) (xy 174.102149 -355.122249) (xy 174.142772 -355.158828) (xy 174.177615 -355.200949)
			(xy 174.192184 -355.22408) (xy 174.20015 -355.236274) (xy 174.221608 -355.255948) (xy 174.24775 -355.268758)
			(xy 174.276446 -355.273661) (xy 174.305358 -355.270257) (xy 174.31893 -355.264974) (xy 174.342139 -355.255482)
			(xy 174.390472 -355.242132) (xy 174.440162 -355.235405) (xy 174.465234 -355.235002) (xy 174.492078 -355.23542)
			(xy 174.545211 -355.24313) (xy 174.596686 -355.258385) (xy 174.64544 -355.280868) (xy 174.690463 -355.310116)
			(xy 174.730823 -355.345522) (xy 174.765683 -355.386354) (xy 174.794323 -355.431765) (xy 174.81615 -355.480817)
			(xy 174.823882 -355.506528) (xy 174.828594 -355.521008) (xy 174.845101 -355.546571) (xy 174.868405 -355.566137)
			(xy 174.896439 -355.577971) (xy 174.926716 -355.58102) (xy 174.956547 -355.575016) (xy 174.970186 -355.56825)
			(xy 174.998325 -355.553603) (xy 175.05828 -355.532881) (xy 175.120841 -355.522389) (xy 175.152558 -355.521768)
			(xy 175.170577 -355.521985) (xy 175.206452 -355.525422) (xy 175.224186 -355.528626) (xy 175.239394 -355.530974)
			(xy 175.269951 -355.527449) (xy 175.298072 -355.514987) (xy 175.321208 -355.494718) (xy 175.337261 -355.46848)
			(xy 175.341534 -355.453696) (xy 175.348943 -355.426655) (xy 175.370568 -355.374927) (xy 175.399529 -355.32692)
			(xy 175.435203 -355.283666) (xy 175.476821 -355.246098) (xy 175.523487 -355.215023) (xy 175.574199 -355.191111)
			(xy 175.627863 -355.174875) (xy 175.683325 -355.166666) (xy 175.711358 -355.166168) (xy 175.738609 -355.166694)
			(xy 175.792556 -355.174445) (xy 175.844851 -355.189794) (xy 175.89443 -355.21243) (xy 175.940282 -355.241892)
			(xy 175.981474 -355.277579) (xy 176.017169 -355.318765) (xy 176.046638 -355.364612) (xy 176.069282 -355.414187)
			(xy 176.084641 -355.466479) (xy 176.092401 -355.520425) (xy 176.092866 -355.547676) (xy 176.092396 -355.575251)
			(xy 176.084446 -355.629824) (xy 176.068722 -355.682684) (xy 176.045553 -355.73273) (xy 176.015421 -355.77892)
			(xy 175.978953 -355.820291) (xy 175.958246 -355.838506) (xy 175.947369 -355.848427) (xy 175.931289 -355.873069)
			(xy 175.922898 -355.901272) (xy 175.922894 -355.930697) (xy 175.931276 -355.958903) (xy 175.947348 -355.98355)
			(xy 175.958246 -355.993446) (xy 175.97893 -356.011686) (xy 176.015398 -356.053052) (xy 176.04553 -356.099239)
			(xy 176.068696 -356.149282) (xy 176.084415 -356.202141) (xy 176.092358 -356.256712) (xy 176.092361 -356.311857)
			(xy 176.084422 -356.366429) (xy 176.068707 -356.419288) (xy 176.045545 -356.469334) (xy 176.015417 -356.515523)
			(xy 175.978952 -356.556892) (xy 175.958246 -356.575106) (xy 175.947369 -356.585027) (xy 175.931289 -356.609669)
			(xy 175.922898 -356.637872) (xy 175.922894 -356.667297) (xy 175.931276 -356.695503) (xy 175.947348 -356.72015)
			(xy 175.958246 -356.730046) (xy 175.978943 -356.748272) (xy 176.015413 -356.789639) (xy 176.045546 -356.835826)
			(xy 176.068713 -356.885871) (xy 176.084433 -356.93873) (xy 176.092378 -356.993302) (xy 176.092866 -357.020876)
			(xy 176.092422 -357.04813) (xy 176.085314 -357.097584) (xy 177.583592 -357.097584) (xy 177.583592 -356.479602)
			(xy 177.584049 -356.454613) (xy 177.591876 -356.405252) (xy 177.607337 -356.357726) (xy 177.630049 -356.313208)
			(xy 177.659454 -356.272796) (xy 177.67681 -356.254812) (xy 179.107592 -354.82403) (xy 179.107592 -353.235006)
			(xy 178.766724 -352.894138) (xy 178.749416 -352.876124) (xy 178.720063 -352.835703) (xy 178.697401 -352.791186)
			(xy 178.681988 -352.743669) (xy 178.674206 -352.694325) (xy 178.67376 -352.669348) (xy 178.67376 -347.934788)
			(xy 178.359308 -347.62059) (xy 178.341974 -347.602599) (xy 178.312625 -347.562173) (xy 178.289968 -347.517649)
			(xy 178.274562 -347.470127) (xy 178.266786 -347.420779) (xy 178.266344 -347.3958) (xy 178.266344 -342.830658)
			(xy 178.251257 -342.807094) (xy 178.227429 -342.756471) (xy 178.211254 -342.70291) (xy 178.20308 -342.647559)
			(xy 178.20259 -342.619584) (xy 178.203049 -342.592214) (xy 178.210869 -342.538034) (xy 178.22636 -342.485531)
			(xy 178.249203 -342.435784) (xy 178.278928 -342.389818) (xy 178.29657 -342.368886) (xy 178.305825 -342.357571)
			(xy 178.318004 -342.33101) (xy 178.322175 -342.302088) (xy 178.317997 -342.273167) (xy 178.305812 -342.246608)
			(xy 178.29657 -342.235282) (xy 178.278912 -342.214363) (xy 178.249184 -342.168394) (xy 178.226337 -342.118645)
			(xy 178.21084 -342.066141) (xy 178.203012 -342.01196) (xy 178.203014 -341.957216) (xy 178.210846 -341.903035)
			(xy 178.226346 -341.850532) (xy 178.249196 -341.800785) (xy 178.278926 -341.754818) (xy 178.29657 -341.733886)
			(xy 178.305825 -341.722571) (xy 178.318004 -341.69601) (xy 178.322175 -341.667088) (xy 178.317997 -341.638167)
			(xy 178.305812 -341.611608) (xy 178.29657 -341.600282) (xy 178.278912 -341.579363) (xy 178.249184 -341.533394)
			(xy 178.226337 -341.483645) (xy 178.21084 -341.431141) (xy 178.203012 -341.37696) (xy 178.203014 -341.322216)
			(xy 178.210846 -341.268035) (xy 178.226346 -341.215532) (xy 178.249196 -341.165785) (xy 178.278926 -341.119818)
			(xy 178.29657 -341.098886) (xy 178.305825 -341.087571) (xy 178.318004 -341.06101) (xy 178.322175 -341.032088)
			(xy 178.317997 -341.003167) (xy 178.305812 -340.976608) (xy 178.29657 -340.965282) (xy 178.278912 -340.944363)
			(xy 178.249184 -340.898394) (xy 178.226337 -340.848645) (xy 178.21084 -340.796141) (xy 178.203012 -340.74196)
			(xy 178.203014 -340.687216) (xy 178.210846 -340.633035) (xy 178.226346 -340.580532) (xy 178.249196 -340.530785)
			(xy 178.278926 -340.484818) (xy 178.29657 -340.463886) (xy 178.305825 -340.452571) (xy 178.318004 -340.42601)
			(xy 178.322175 -340.397088) (xy 178.317997 -340.368167) (xy 178.305812 -340.341608) (xy 178.29657 -340.330282)
			(xy 178.278912 -340.309363) (xy 178.249184 -340.263394) (xy 178.226337 -340.213645) (xy 178.21084 -340.161141)
			(xy 178.203012 -340.10696) (xy 178.203014 -340.052216) (xy 178.210846 -339.998035) (xy 178.226346 -339.945532)
			(xy 178.249196 -339.895785) (xy 178.278926 -339.849818) (xy 178.29657 -339.828886) (xy 178.305825 -339.817571)
			(xy 178.318004 -339.79101) (xy 178.322175 -339.762088) (xy 178.317997 -339.733167) (xy 178.305812 -339.706608)
			(xy 178.29657 -339.695282) (xy 178.278912 -339.674363) (xy 178.249184 -339.628394) (xy 178.226337 -339.578645)
			(xy 178.21084 -339.526141) (xy 178.203012 -339.47196) (xy 178.203014 -339.417216) (xy 178.210846 -339.363035)
			(xy 178.226346 -339.310532) (xy 178.249196 -339.260785) (xy 178.278926 -339.214818) (xy 178.29657 -339.193886)
			(xy 178.305825 -339.182571) (xy 178.318004 -339.15601) (xy 178.322175 -339.127088) (xy 178.317997 -339.098167)
			(xy 178.305812 -339.071608) (xy 178.29657 -339.060282) (xy 178.278951 -339.039334) (xy 178.249237 -338.993365)
			(xy 178.226398 -338.943621) (xy 178.210902 -338.891125) (xy 178.203068 -338.836952) (xy 178.20259 -338.809584)
			(xy 178.203063 -338.782332) (xy 178.210822 -338.728384) (xy 178.226179 -338.676089) (xy 178.248821 -338.626512)
			(xy 178.278289 -338.580662) (xy 178.313982 -338.539472) (xy 178.355173 -338.503781) (xy 178.401025 -338.474315)
			(xy 178.450603 -338.451674) (xy 178.502898 -338.436319) (xy 178.556846 -338.428562) (xy 178.584098 -338.428076)
			(xy 178.611469 -338.428525) (xy 178.66565 -338.436344) (xy 178.718154 -338.451836) (xy 178.7679 -338.474682)
			(xy 178.813866 -338.504412) (xy 178.834796 -338.522056) (xy 178.846124 -338.531292) (xy 178.872681 -338.543468)
			(xy 178.901598 -338.547641) (xy 178.930515 -338.543468) (xy 178.957072 -338.531292) (xy 178.9684 -338.522056)
			(xy 178.989315 -338.504396) (xy 179.035293 -338.474689) (xy 179.085045 -338.451858) (xy 179.137549 -338.436371)
			(xy 179.191728 -338.428547) (xy 179.219098 -338.428076) (xy 179.247138 -338.428571) (xy 179.302616 -338.436772)
			(xy 179.356298 -338.452997) (xy 179.40703 -338.476899) (xy 179.453722 -338.507962) (xy 179.474876 -338.526374)
			(xy 179.486318 -338.536019) (xy 179.513361 -338.548799) (xy 179.542948 -338.553185) (xy 179.572535 -338.548799)
			(xy 179.599578 -338.536019) (xy 179.61102 -338.526374) (xy 179.632181 -338.507967) (xy 179.678856 -338.476871)
			(xy 179.729584 -338.452953) (xy 179.783271 -338.43673) (xy 179.838756 -338.428552) (xy 179.866798 -338.428076)
			(xy 179.894048 -338.42858) (xy 179.947995 -338.436335) (xy 180.000288 -338.451689) (xy 180.049864 -338.474329)
			(xy 180.095714 -338.503794) (xy 180.136904 -338.539483) (xy 180.172595 -338.580672) (xy 180.202062 -338.62652)
			(xy 180.224704 -338.676095) (xy 180.240061 -338.728388) (xy 180.247819 -338.782334) (xy 180.248306 -338.809584)
			(xy 180.247829 -338.836954) (xy 180.240014 -338.891132) (xy 180.224527 -338.943635) (xy 180.201688 -338.993382)
			(xy 180.171966 -339.03935) (xy 180.154326 -339.060282) (xy 180.145102 -339.07162) (xy 180.13292 -339.098173)
			(xy 180.128743 -339.127088) (xy 180.132913 -339.156003) (xy 180.145089 -339.18256) (xy 180.154326 -339.193886)
			(xy 180.171953 -339.214831) (xy 180.201682 -339.260795) (xy 180.224531 -339.310539) (xy 180.240031 -339.36304)
			(xy 180.247862 -339.417218) (xy 180.247864 -339.471958) (xy 180.240036 -339.526137) (xy 180.22454 -339.578638)
			(xy 180.201694 -339.628384) (xy 180.171968 -339.67435) (xy 180.154326 -339.695282) (xy 180.145102 -339.70662)
			(xy 180.13292 -339.733173) (xy 180.128743 -339.762088) (xy 180.132913 -339.791003) (xy 180.145089 -339.81756)
			(xy 180.154326 -339.828886) (xy 180.171953 -339.849831) (xy 180.201682 -339.895795) (xy 180.224531 -339.945539)
			(xy 180.240031 -339.99804) (xy 180.247862 -340.052218) (xy 180.247864 -340.106958) (xy 180.240036 -340.161137)
			(xy 180.22454 -340.213638) (xy 180.201694 -340.263384) (xy 180.171968 -340.30935) (xy 180.154326 -340.330282)
			(xy 180.145102 -340.34162) (xy 180.13292 -340.368173) (xy 180.128743 -340.397088) (xy 180.132913 -340.426003)
			(xy 180.145089 -340.45256) (xy 180.154326 -340.463886) (xy 180.171953 -340.484831) (xy 180.201682 -340.530795)
			(xy 180.224531 -340.580539) (xy 180.240031 -340.63304) (xy 180.247862 -340.687218) (xy 180.247864 -340.741958)
			(xy 180.240036 -340.796137) (xy 180.22454 -340.848638) (xy 180.201694 -340.898384) (xy 180.171968 -340.94435)
			(xy 180.154326 -340.965282) (xy 180.145102 -340.97662) (xy 180.13292 -341.003173) (xy 180.128743 -341.032088)
			(xy 180.132913 -341.061003) (xy 180.145089 -341.08756) (xy 180.154326 -341.098886) (xy 180.171953 -341.119831)
			(xy 180.201682 -341.165795) (xy 180.224531 -341.215539) (xy 180.240031 -341.26804) (xy 180.247862 -341.322218)
			(xy 180.247864 -341.376958) (xy 180.240036 -341.431137) (xy 180.22454 -341.483638) (xy 180.201694 -341.533384)
			(xy 180.171968 -341.57935) (xy 180.154326 -341.600282) (xy 180.145102 -341.61162) (xy 180.13292 -341.638173)
			(xy 180.128743 -341.667088) (xy 180.132913 -341.696003) (xy 180.145089 -341.72256) (xy 180.154326 -341.733886)
			(xy 180.171953 -341.754831) (xy 180.201682 -341.800795) (xy 180.224531 -341.850539) (xy 180.240031 -341.90304)
			(xy 180.247862 -341.957218) (xy 180.247864 -342.011958) (xy 180.240036 -342.066137) (xy 180.22454 -342.118638)
			(xy 180.201694 -342.168384) (xy 180.171968 -342.21435) (xy 180.154326 -342.235282) (xy 180.145102 -342.24662)
			(xy 180.13292 -342.273173) (xy 180.128743 -342.302088) (xy 180.132913 -342.331003) (xy 180.145089 -342.35756)
			(xy 180.154326 -342.368886) (xy 180.171976 -342.389809) (xy 180.201685 -342.435785) (xy 180.224519 -342.485535)
			(xy 180.240007 -342.538037) (xy 180.247833 -342.592214) (xy 180.248306 -342.619584) (xy 180.24783 -342.646837)
			(xy 180.240075 -342.700787) (xy 180.224721 -342.753085) (xy 180.20208 -342.802665) (xy 180.172614 -342.848518)
			(xy 180.136921 -342.889711) (xy 180.09573 -342.925405) (xy 180.049877 -342.954873) (xy 180.000298 -342.977516)
			(xy 179.948001 -342.992872) (xy 179.894051 -343.000629) (xy 179.866798 -343.001092) (xy 179.838757 -343.000608)
			(xy 179.783279 -342.992406) (xy 179.729596 -342.976178) (xy 179.678864 -342.952274) (xy 179.632173 -342.921208)
			(xy 179.61102 -342.902794) (xy 179.599578 -342.893149) (xy 179.572535 -342.880369) (xy 179.542948 -342.875983)
			(xy 179.513361 -342.880369) (xy 179.486318 -342.893149) (xy 179.474876 -342.902794) (xy 179.453712 -342.921198)
			(xy 179.407039 -342.952296) (xy 179.356311 -342.976215) (xy 179.302625 -342.992438) (xy 179.24714 -343.000616)
			(xy 179.219098 -343.001092) (xy 179.189679 -343.000528) (xy 179.131539 -342.99149) (xy 179.075482 -342.973614)
			(xy 179.048918 -342.96096) (xy 179.035453 -342.9548) (xy 179.006296 -342.949716) (xy 178.976904 -342.953198)
			(xy 178.949742 -342.964955) (xy 178.927087 -342.984) (xy 178.910837 -343.008738) (xy 178.902356 -343.037094)
			(xy 178.901852 -343.051892) (xy 178.901852 -347.264228) (xy 179.216304 -347.578426) (xy 179.233648 -347.596408)
			(xy 179.262995 -347.636837) (xy 179.28565 -347.681363) (xy 179.301054 -347.728887) (xy 179.308827 -347.778237)
			(xy 179.309268 -347.803216) (xy 179.309268 -352.537776) (xy 179.65039 -352.878644) (xy 179.667702 -352.896663)
			(xy 179.69707 -352.937085) (xy 179.719766 -352.981598) (xy 179.735233 -353.029109) (xy 179.743092 -353.078452)
			(xy 179.743608 -353.103434) (xy 179.743608 -354.637848) (xy 185.603386 -354.637848) (xy 185.607457 -354.582226)
			(xy 185.619583 -354.527789) (xy 185.639506 -354.475698) (xy 185.666802 -354.427063) (xy 185.700888 -354.38292)
			(xy 185.741037 -354.344211) (xy 185.786395 -354.31176) (xy 185.835995 -354.286259) (xy 185.888779 -354.268252)
			(xy 185.943622 -354.258122) (xy 185.999356 -354.256085) (xy 186.054793 -354.262185) (xy 186.10875 -354.276291)
			(xy 186.160079 -354.298103) (xy 186.207685 -354.327157) (xy 186.250553 -354.362832) (xy 186.28777 -354.404369)
			(xy 186.318543 -354.450882) (xy 186.342215 -354.501379) (xy 186.358283 -354.554786) (xy 186.366403 -354.609962)
			(xy 186.366912 -354.637848) (xy 186.366403 -354.665734) (xy 186.358283 -354.72091) (xy 186.342215 -354.774317)
			(xy 186.318543 -354.824814) (xy 186.28777 -354.871327) (xy 186.250553 -354.912864) (xy 186.207685 -354.948539)
			(xy 186.160079 -354.977593) (xy 186.10875 -354.999405) (xy 186.054793 -355.013511) (xy 185.999356 -355.019611)
			(xy 185.943622 -355.017574) (xy 185.888779 -355.007444) (xy 185.835995 -354.989437) (xy 185.786395 -354.963936)
			(xy 185.741037 -354.931485) (xy 185.700888 -354.892776) (xy 185.666802 -354.848633) (xy 185.639506 -354.799998)
			(xy 185.619583 -354.747907) (xy 185.607457 -354.69347) (xy 185.603386 -354.637848) (xy 179.743608 -354.637848)
			(xy 179.743608 -354.955602) (xy 179.743153 -354.980591) (xy 179.735326 -355.029952) (xy 179.719865 -355.077478)
			(xy 179.697151 -355.121996) (xy 179.667746 -355.162408) (xy 179.65039 -355.180392) (xy 179.413682 -355.4171)
			(xy 182.004979 -355.4171) (xy 182.009147 -355.36149) (xy 182.021556 -355.307122) (xy 182.04193 -355.25521)
			(xy 182.069813 -355.206915) (xy 182.104582 -355.163315) (xy 182.145461 -355.125384) (xy 182.191537 -355.09397)
			(xy 182.241781 -355.069773) (xy 182.29507 -355.053335) (xy 182.350213 -355.045023) (xy 182.378096 -355.044502)
			(xy 182.405428 -355.044959) (xy 182.459508 -355.052933) (xy 182.511842 -355.068725) (xy 182.561306 -355.091995)
			(xy 182.606838 -355.122245) (xy 182.64746 -355.158824) (xy 182.6823 -355.200947) (xy 182.696866 -355.22408)
			(xy 182.704754 -355.23633) (xy 182.726233 -355.256004) (xy 182.752397 -355.268807) (xy 182.781111 -355.273695)
			(xy 182.810037 -355.27027) (xy 182.823612 -355.264974) (xy 182.846823 -355.255487) (xy 182.895155 -355.242135)
			(xy 182.944844 -355.235406) (xy 182.969916 -355.235002) (xy 182.994985 -355.235435) (xy 183.044668 -355.242181)
			(xy 183.093002 -355.25551) (xy 183.11622 -355.264974) (xy 183.129796 -355.270237) (xy 183.158706 -355.273615)
			(xy 183.187396 -355.268712) (xy 183.213543 -355.255923) (xy 183.235026 -355.236286) (xy 183.242966 -355.22408)
			(xy 183.257535 -355.200949) (xy 183.292378 -355.158828) (xy 183.333001 -355.122249) (xy 183.378532 -355.091998)
			(xy 183.427994 -355.068722) (xy 183.480325 -355.052922) (xy 183.534404 -355.044936) (xy 183.589068 -355.044936)
			(xy 183.643147 -355.052922) (xy 183.695478 -355.068722) (xy 183.74494 -355.091998) (xy 183.790471 -355.122249)
			(xy 183.831094 -355.158828) (xy 183.865937 -355.200949) (xy 183.880506 -355.22408) (xy 183.888451 -355.236289)
			(xy 183.909915 -355.255963) (xy 183.936063 -355.268771) (xy 183.964764 -355.27367) (xy 183.99368 -355.270261)
			(xy 184.007252 -355.264974) (xy 184.030458 -355.255475) (xy 184.078793 -355.242128) (xy 184.128484 -355.235403)
			(xy 184.153556 -355.235002) (xy 184.180398 -355.23549) (xy 184.233527 -355.243189) (xy 184.285002 -355.258433)
			(xy 184.333755 -355.280907) (xy 184.378778 -355.310146) (xy 184.419139 -355.345544) (xy 184.454001 -355.386368)
			(xy 184.482643 -355.431774) (xy 184.504471 -355.48082) (xy 184.512204 -355.506528) (xy 184.516888 -355.521018)
			(xy 184.533399 -355.546585) (xy 184.55671 -355.566152) (xy 184.58475 -355.577984) (xy 184.615032 -355.58103)
			(xy 184.644867 -355.575019) (xy 184.658508 -355.56825) (xy 184.686661 -355.553631) (xy 184.746609 -355.5329)
			(xy 184.809164 -355.522395) (xy 184.84088 -355.521768) (xy 184.8589 -355.521982) (xy 184.894774 -355.525421)
			(xy 184.912508 -355.528626) (xy 184.927714 -355.530997) (xy 184.958273 -355.527466) (xy 184.986395 -355.514998)
			(xy 185.009532 -355.494724) (xy 185.025584 -355.468482) (xy 185.029856 -355.453696) (xy 185.037245 -355.426649)
			(xy 185.058872 -355.374919) (xy 185.087835 -355.326911) (xy 185.123511 -355.283658) (xy 185.165131 -355.24609)
			(xy 185.211801 -355.215015) (xy 185.262515 -355.191104) (xy 185.316182 -355.174871) (xy 185.371646 -355.166664)
			(xy 185.39968 -355.166168) (xy 185.42693 -355.166697) (xy 185.480875 -355.17445) (xy 185.533167 -355.189801)
			(xy 185.582742 -355.212438) (xy 185.628592 -355.2419) (xy 185.669782 -355.277587) (xy 185.705473 -355.318773)
			(xy 185.734941 -355.364619) (xy 185.757583 -355.414192) (xy 185.772941 -355.466482) (xy 185.7807 -355.520426)
			(xy 185.781188 -355.547676) (xy 185.78071 -355.57525) (xy 185.772761 -355.629823) (xy 185.757038 -355.682682)
			(xy 185.733871 -355.732729) (xy 185.70374 -355.778918) (xy 185.667274 -355.82029) (xy 185.646568 -355.838506)
			(xy 185.635698 -355.848431) (xy 185.61963 -355.873075) (xy 185.611247 -355.901275) (xy 185.611243 -355.930694)
			(xy 185.619617 -355.958897) (xy 185.635678 -355.983546) (xy 185.646568 -355.993446) (xy 185.667251 -356.011687)
			(xy 185.703717 -356.053054) (xy 185.733847 -356.09924) (xy 185.757012 -356.149284) (xy 185.77273 -356.202142)
			(xy 185.780673 -356.256712) (xy 185.780675 -356.311857) (xy 185.772737 -356.366428) (xy 185.757023 -356.419287)
			(xy 185.733862 -356.469333) (xy 185.703736 -356.515521) (xy 185.667273 -356.556891) (xy 185.646568 -356.575106)
			(xy 185.635698 -356.585031) (xy 185.61963 -356.609675) (xy 185.611247 -356.637875) (xy 185.611243 -356.667294)
			(xy 185.619617 -356.695497) (xy 185.635678 -356.720146) (xy 185.646568 -356.730046) (xy 185.66725 -356.748289)
			(xy 185.703724 -356.78965) (xy 185.73386 -356.835833) (xy 185.757032 -356.885875) (xy 185.772754 -356.938732)
			(xy 185.7807 -356.993303) (xy 185.781188 -357.020876) (xy 185.780722 -357.048129) (xy 185.772968 -357.102081)
			(xy 185.757614 -357.15438) (xy 185.734973 -357.203961) (xy 185.705506 -357.249816) (xy 185.669812 -357.291009)
			(xy 185.628619 -357.326703) (xy 185.582765 -357.356171) (xy 185.533184 -357.378813) (xy 185.480885 -357.394167)
			(xy 185.426933 -357.401922) (xy 185.39968 -357.402384) (xy 185.371824 -357.401891) (xy 185.316706 -357.393764)
			(xy 185.263355 -357.377715) (xy 185.212901 -357.354085) (xy 185.166416 -357.323374) (xy 185.124887 -357.286235)
			(xy 185.089195 -357.243456) (xy 185.060097 -357.195945) (xy 185.038211 -357.144711) (xy 185.030618 -357.117904)
			(xy 185.026394 -357.10377) (xy 185.010993 -357.078621) (xy 184.989063 -357.058905) (xy 184.962422 -357.046259)
			(xy 184.933281 -357.041732) (xy 184.918604 -357.043228) (xy 184.905587 -357.044895) (xy 184.879403 -357.046676)
			(xy 184.86628 -357.046784) (xy 184.852131 -357.046693) (xy 184.823908 -357.044657) (xy 184.809892 -357.04272)
			(xy 184.79654 -357.041169) (xy 184.769851 -357.044258) (xy 184.744897 -357.054218) (xy 184.723417 -357.070357)
			(xy 184.706905 -357.091552) (xy 184.696509 -357.116327) (xy 184.694322 -357.129588) (xy 184.690263 -357.156746)
			(xy 184.675284 -357.209576) (xy 184.652888 -357.259714) (xy 184.623536 -357.306124) (xy 184.587835 -357.347847)
			(xy 184.546523 -357.384023) (xy 184.500452 -357.413903) (xy 184.450573 -357.436871) (xy 184.397918 -357.452452)
			(xy 184.343572 -357.460326) (xy 184.316116 -357.460804) (xy 184.288863 -357.46033) (xy 184.234913 -357.452575)
			(xy 184.182615 -357.437221) (xy 184.133034 -357.41458) (xy 184.087181 -357.385113) (xy 184.045988 -357.34942)
			(xy 184.010294 -357.308229) (xy 183.980826 -357.262376) (xy 183.958184 -357.212797) (xy 183.942828 -357.160499)
			(xy 183.935071 -357.106549) (xy 183.934608 -357.079296) (xy 183.935068 -357.051721) (xy 183.943021 -356.997148)
			(xy 183.958747 -356.944288) (xy 183.981918 -356.894242) (xy 184.012052 -356.848052) (xy 184.04852 -356.806682)
			(xy 184.069228 -356.788466) (xy 184.080126 -356.77857) (xy 184.096194 -356.753918) (xy 184.104574 -356.72571)
			(xy 184.104573 -356.696284) (xy 184.096191 -356.668078) (xy 184.080123 -356.643426) (xy 184.069228 -356.633526)
			(xy 184.048532 -356.615298) (xy 184.012059 -356.573934) (xy 183.981924 -356.527748) (xy 183.958756 -356.477703)
			(xy 183.943037 -356.424843) (xy 183.935094 -356.37027) (xy 183.934608 -356.342696) (xy 183.935076 -356.316195)
			(xy 183.942417 -356.263705) (xy 183.956958 -356.212737) (xy 183.978418 -356.164275) (xy 184.006384 -356.119251)
			(xy 184.023 -356.098602) (xy 184.032398 -356.086423) (xy 184.0442 -356.058034) (xy 184.047035 -356.027421)
			(xy 184.040647 -355.997347) (xy 184.025613 -355.970529) (xy 184.003291 -355.949389) (xy 183.989726 -355.942138)
			(xy 183.96604 -355.93003) (xy 183.922058 -355.900108) (xy 183.882776 -355.864239) (xy 183.848991 -355.823151)
			(xy 183.834786 -355.80066) (xy 183.826864 -355.788436) (xy 183.80539 -355.76877) (xy 183.779237 -355.755968)
			(xy 183.750533 -355.751072) (xy 183.721614 -355.754481) (xy 183.70804 -355.759766) (xy 183.684836 -355.76927)
			(xy 183.6365 -355.782615) (xy 183.586808 -355.789337) (xy 183.561736 -355.789738) (xy 183.536666 -355.789326)
			(xy 183.486983 -355.782572) (xy 183.438649 -355.769235) (xy 183.415432 -355.759766) (xy 183.401852 -355.754528)
			(xy 183.372954 -355.751164) (xy 183.344277 -355.756074) (xy 183.318144 -355.76886) (xy 183.296668 -355.788488)
			(xy 183.288686 -355.80066) (xy 183.274117 -355.823791) (xy 183.239274 -355.865912) (xy 183.198651 -355.902491)
			(xy 183.15312 -355.932742) (xy 183.103658 -355.956018) (xy 183.051327 -355.971818) (xy 182.997248 -355.979804)
			(xy 182.942584 -355.979804) (xy 182.888505 -355.971818) (xy 182.836174 -355.956018) (xy 182.786712 -355.932742)
			(xy 182.741181 -355.902491) (xy 182.700558 -355.865912) (xy 182.665715 -355.823791) (xy 182.651146 -355.80066)
			(xy 182.643262 -355.788408) (xy 182.621778 -355.768742) (xy 182.595614 -355.755943) (xy 182.566901 -355.751055)
			(xy 182.537976 -355.754474) (xy 182.5244 -355.759766) (xy 182.501189 -355.769251) (xy 182.452856 -355.782603)
			(xy 182.403167 -355.789333) (xy 182.378096 -355.789738) (xy 182.350213 -355.789177) (xy 182.29507 -355.780865)
			(xy 182.241781 -355.764427) (xy 182.191537 -355.74023) (xy 182.145461 -355.708816) (xy 182.104582 -355.670885)
			(xy 182.069813 -355.627285) (xy 182.04193 -355.57899) (xy 182.021556 -355.527078) (xy 182.009147 -355.47271)
			(xy 182.004979 -355.4171) (xy 179.413682 -355.4171) (xy 178.900836 -355.929946) (xy 178.891006 -355.940489)
			(xy 178.877168 -355.965762) (xy 178.870937 -355.993893) (xy 178.872808 -356.022646) (xy 178.882634 -356.049732)
			(xy 178.899631 -356.072998) (xy 178.922449 -356.090592) (xy 178.949272 -356.101116) (xy 178.963574 -356.10292)
			(xy 178.991681 -356.105916) (xy 179.04661 -356.119257) (xy 179.098969 -356.140556) (xy 179.147614 -356.169346)
			(xy 179.19148 -356.204996) (xy 179.229606 -356.246728) (xy 179.261159 -356.293627) (xy 179.285449 -356.344668)
			(xy 179.301943 -356.398734) (xy 179.310281 -356.454641) (xy 179.310792 -356.482904) (xy 179.310348 -356.510158)
			(xy 179.30259 -356.56411) (xy 179.287233 -356.616409) (xy 179.264589 -356.665991) (xy 179.235119 -356.711844)
			(xy 179.199423 -356.753037) (xy 179.158228 -356.788731) (xy 179.112373 -356.818199) (xy 179.062791 -356.84084)
			(xy 179.010491 -356.856195) (xy 178.956538 -356.86395) (xy 178.929284 -356.864412) (xy 178.901024 -356.863839)
			(xy 178.845122 -356.855512) (xy 178.791061 -356.839026) (xy 178.740023 -356.814744) (xy 178.693128 -356.783197)
			(xy 178.651401 -356.745076) (xy 178.615756 -356.701214) (xy 178.586973 -356.652573) (xy 178.565682 -356.600217)
			(xy 178.55235 -356.545293) (xy 178.5493 -356.517194) (xy 178.547573 -356.502868) (xy 178.537078 -356.476)
			(xy 178.519487 -356.453141) (xy 178.496202 -356.436116) (xy 178.469085 -356.426284) (xy 178.4403 -356.424431)
			(xy 178.412145 -356.430704) (xy 178.38687 -356.444603) (xy 178.376326 -356.454456) (xy 178.219608 -356.611174)
			(xy 178.219608 -356.966012) (xy 178.340004 -357.086408) (xy 178.353974 -357.089964) (xy 178.381359 -357.097124)
			(xy 178.433838 -357.118328) (xy 178.482607 -357.147054) (xy 178.526596 -357.182672) (xy 178.564838 -357.224399)
			(xy 178.596494 -357.271319) (xy 178.620869 -357.322402) (xy 178.637428 -357.376527) (xy 178.645806 -357.432504)
			(xy 178.646328 -357.460804) (xy 178.645826 -357.488054) (xy 178.638069 -357.542001) (xy 178.622715 -357.594294)
			(xy 178.600075 -357.64387) (xy 178.57061 -357.689719) (xy 178.53492 -357.730909) (xy 178.493732 -357.7666)
			(xy 178.447884 -357.796067) (xy 178.398309 -357.818709) (xy 178.346016 -357.834066) (xy 178.29207 -357.841825)
			(xy 178.26482 -357.842312) (xy 178.236513 -357.8418) (xy 178.180518 -357.833457) (xy 178.126374 -357.816922)
			(xy 178.075271 -357.79256) (xy 178.028335 -357.760906) (xy 177.986598 -357.722656) (xy 177.950978 -357.678654)
			(xy 177.92226 -357.629865) (xy 177.901075 -357.577366) (xy 177.89398 -357.549958) (xy 177.890424 -357.535988)
			(xy 177.67681 -357.322374) (xy 177.659507 -357.304347) (xy 177.630137 -357.263927) (xy 177.60744 -357.219416)
			(xy 177.59197 -357.171907) (xy 177.584109 -357.122565) (xy 177.583592 -357.097584) (xy 176.085314 -357.097584)
			(xy 176.084667 -357.102084) (xy 176.069312 -357.154385) (xy 176.04667 -357.203968) (xy 176.0172 -357.249823)
			(xy 175.981504 -357.291017) (xy 175.940308 -357.326711) (xy 175.894452 -357.356178) (xy 175.844868 -357.378819)
			(xy 175.792566 -357.394171) (xy 175.738612 -357.401924) (xy 175.711358 -357.402384) (xy 175.683501 -357.401911)
			(xy 175.628383 -357.393781) (xy 175.575031 -357.377729) (xy 175.524577 -357.354095) (xy 175.478092 -357.323382)
			(xy 175.436563 -357.286241) (xy 175.400871 -357.24346) (xy 175.371774 -357.195948) (xy 175.349889 -357.144711)
			(xy 175.342296 -357.117904) (xy 175.337994 -357.103798) (xy 175.322609 -357.078656) (xy 175.300697 -357.058941)
			(xy 175.274076 -357.046287) (xy 175.244953 -357.041743) (xy 175.230282 -357.043228) (xy 175.217265 -357.044897)
			(xy 175.191081 -357.046677) (xy 175.177958 -357.046784) (xy 175.163809 -357.046695) (xy 175.135586 -357.044658)
			(xy 175.12157 -357.04272) (xy 175.10822 -357.041147) (xy 175.081529 -357.044241) (xy 175.056574 -357.054206)
			(xy 175.035094 -357.070349) (xy 175.018582 -357.091547) (xy 175.008187 -357.116326) (xy 175.006 -357.129588)
			(xy 175.001962 -357.15675) (xy 174.986983 -357.209582) (xy 174.964584 -357.259721) (xy 174.935231 -357.306132)
			(xy 174.899527 -357.347855) (xy 174.858212 -357.384031) (xy 174.812138 -357.41391) (xy 174.762257 -357.436877)
			(xy 174.709599 -357.452457) (xy 174.655251 -357.460327) (xy 174.627794 -357.460804) (xy 174.600542 -357.460328)
			(xy 174.546594 -357.45257) (xy 174.494299 -357.437214) (xy 174.444721 -357.414572) (xy 174.398871 -357.385105)
			(xy 174.357681 -357.349412) (xy 174.321989 -357.308221) (xy 174.292523 -357.26237) (xy 174.269882 -357.212792)
			(xy 174.254528 -357.160496) (xy 174.246772 -357.106548) (xy 174.246286 -357.079296) (xy 174.246754 -357.051722)
			(xy 174.254707 -356.997149) (xy 174.270432 -356.944289) (xy 174.293601 -356.894244) (xy 174.323733 -356.848054)
			(xy 174.3602 -356.806682) (xy 174.380906 -356.788466) (xy 174.391806 -356.778571) (xy 174.407877 -356.753919)
			(xy 174.41626 -356.725711) (xy 174.416259 -356.696284) (xy 174.407875 -356.668076) (xy 174.391803 -356.643425)
			(xy 174.380906 -356.633526) (xy 174.360205 -356.615303) (xy 174.323734 -356.573937) (xy 174.2936 -356.52775)
			(xy 174.270433 -356.477704) (xy 174.254714 -356.424843) (xy 174.246772 -356.37027) (xy 174.246286 -356.342696)
			(xy 174.246759 -356.316196) (xy 174.2541 -356.263705) (xy 174.26864 -356.212738) (xy 174.290099 -356.164275)
			(xy 174.318063 -356.119252) (xy 174.334678 -356.098602) (xy 174.344049 -356.086407) (xy 174.355839 -356.058023)
			(xy 174.35867 -356.027419) (xy 174.352287 -355.997354) (xy 174.337266 -355.97054) (xy 174.31496 -355.949395)
			(xy 174.301404 -355.942138) (xy 174.277714 -355.930037) (xy 174.233734 -355.900113) (xy 174.194453 -355.864242)
			(xy 174.160669 -355.823152) (xy 174.146464 -355.80066) (xy 174.138563 -355.788421) (xy 174.117083 -355.768755)
			(xy 174.090924 -355.755954) (xy 174.062215 -355.751063) (xy 174.033293 -355.754477) (xy 174.019718 -355.759766)
			(xy 173.996504 -355.769246) (xy 173.948173 -355.7826) (xy 173.898485 -355.789332) (xy 173.873414 -355.789738)
			(xy 173.848345 -355.7893) (xy 173.798662 -355.782557) (xy 173.750328 -355.76923) (xy 173.72711 -355.759766)
			(xy 173.713502 -355.75461) (xy 173.684618 -355.751229) (xy 173.655952 -355.756121) (xy 173.629823 -355.768887)
			(xy 173.608347 -355.788496) (xy 173.600364 -355.80066) (xy 173.585795 -355.823791) (xy 173.550952 -355.865912)
			(xy 173.510329 -355.902491) (xy 173.464798 -355.932742) (xy 173.415336 -355.956018) (xy 173.363005 -355.971818)
			(xy 173.308926 -355.979804) (xy 173.254262 -355.979804) (xy 173.200183 -355.971818) (xy 173.147852 -355.956018)
			(xy 173.09839 -355.932742) (xy 173.052859 -355.902491) (xy 173.012236 -355.865912) (xy 172.977393 -355.823791)
			(xy 172.962824 -355.80066) (xy 172.954866 -355.788462) (xy 172.933402 -355.768796) (xy 172.907258 -355.75599)
			(xy 172.878563 -355.751087) (xy 172.849651 -355.754487) (xy 172.836078 -355.759766) (xy 172.812869 -355.769258)
			(xy 172.764536 -355.782607) (xy 172.714846 -355.789335) (xy 172.689774 -355.789738) (xy 172.661892 -355.789175)
			(xy 172.606751 -355.780861) (xy 172.553465 -355.764421) (xy 172.503225 -355.740223) (xy 172.457152 -355.708808)
			(xy 172.416275 -355.670877) (xy 172.381508 -355.627278) (xy 172.353627 -355.578984) (xy 172.333255 -355.527074)
			(xy 172.320847 -355.472708) (xy 172.316679 -355.4171) (xy 167.805608 -355.4171) (xy 167.805608 -356.228396)
			(xy 168.060116 -356.482904) (xy 168.858944 -356.482904) (xy 168.863015 -356.427282) (xy 168.875141 -356.372845)
			(xy 168.895064 -356.320754) (xy 168.92236 -356.272119) (xy 168.956446 -356.227976) (xy 168.996595 -356.189267)
			(xy 169.041953 -356.156816) (xy 169.091553 -356.131315) (xy 169.144337 -356.113308) (xy 169.19918 -356.103178)
			(xy 169.254914 -356.101141) (xy 169.310351 -356.107241) (xy 169.364308 -356.121347) (xy 169.415637 -356.143159)
			(xy 169.463243 -356.172213) (xy 169.506111 -356.207888) (xy 169.543328 -356.249425) (xy 169.574101 -356.295938)
			(xy 169.597773 -356.346435) (xy 169.613841 -356.399842) (xy 169.621961 -356.455018) (xy 169.62247 -356.482904)
			(xy 169.621961 -356.51079) (xy 169.613841 -356.565966) (xy 169.597773 -356.619373) (xy 169.574101 -356.66987)
			(xy 169.543328 -356.716383) (xy 169.506111 -356.75792) (xy 169.463243 -356.793595) (xy 169.415637 -356.822649)
			(xy 169.364308 -356.844461) (xy 169.310351 -356.858567) (xy 169.254914 -356.864667) (xy 169.19918 -356.86263)
			(xy 169.144337 -356.8525) (xy 169.091553 -356.834493) (xy 169.041953 -356.808992) (xy 168.996595 -356.776541)
			(xy 168.956446 -356.737832) (xy 168.92236 -356.693689) (xy 168.895064 -356.645054) (xy 168.875141 -356.592963)
			(xy 168.863015 -356.538526) (xy 168.858944 -356.482904) (xy 168.060116 -356.482904) (xy 168.651682 -357.07447)
			(xy 168.665652 -357.078026) (xy 168.693068 -357.085077) (xy 168.74555 -357.106296) (xy 168.79432 -357.135037)
			(xy 168.838307 -357.170669) (xy 168.876547 -357.212411) (xy 168.908198 -357.259344) (xy 168.932567 -357.310439)
			(xy 168.949119 -357.364575) (xy 168.957489 -357.420562) (xy 168.958006 -357.448866) (xy 168.957513 -357.476118)
			(xy 168.949761 -357.530068) (xy 168.934409 -357.582366) (xy 168.91177 -357.631946) (xy 168.882306 -357.677799)
			(xy 168.846615 -357.718992) (xy 168.805425 -357.754686) (xy 168.759574 -357.784155) (xy 168.709996 -357.806798)
			(xy 168.657699 -357.822154) (xy 168.60375 -357.829911) (xy 168.576498 -357.830374) (xy 168.548193 -357.829834)
			(xy 168.492202 -357.82149) (xy 168.43806 -357.804956) (xy 168.38696 -357.780595) (xy 168.340026 -357.748944)
			(xy 168.298289 -357.710699) (xy 168.262668 -357.666702) (xy 168.233946 -357.617919) (xy 168.212756 -357.565425)
			(xy 168.205658 -357.53802) (xy 168.202102 -357.52405) (xy 167.26281 -356.584758) (xy 167.245499 -356.566738)
			(xy 167.216131 -356.526316) (xy 167.193434 -356.481803) (xy 167.177967 -356.434293) (xy 167.170108 -356.38495)
			(xy 167.169592 -356.359968) (xy 167.041068 -356.359968) (xy 167.041068 -357.825294) (xy 167.13962 -357.9241)
			(xy 167.13962 -357.99141) (xy 169.66565 -357.99141) (xy 169.666086 -357.966072) (xy 169.672793 -357.915843)
			(xy 169.686091 -357.866943) (xy 169.705744 -357.820235) (xy 169.731409 -357.776539) (xy 169.762632 -357.736625)
			(xy 169.780458 -357.718614) (xy 169.789846 -357.708834) (xy 169.803642 -357.685512) (xy 169.810797 -357.659378)
			(xy 169.810805 -357.632282) (xy 169.803665 -357.606143) (xy 169.789883 -357.582814) (xy 169.780458 -357.573072)
			(xy 169.762627 -357.555065) (xy 169.731397 -357.515153) (xy 169.705728 -357.471458) (xy 169.68607 -357.424748)
			(xy 169.67277 -357.375847) (xy 169.666063 -357.325615) (xy 169.66565 -357.300276) (xy 169.666136 -357.273025)
			(xy 169.673892 -357.219077) (xy 169.689247 -357.166782) (xy 169.711889 -357.117205) (xy 169.741355 -357.071355)
			(xy 169.777046 -357.030164) (xy 169.818237 -356.994473) (xy 169.864087 -356.965007) (xy 169.913664 -356.942365)
			(xy 169.965959 -356.92701) (xy 170.019907 -356.919254) (xy 170.074409 -356.919254) (xy 170.128357 -356.92701)
			(xy 170.180652 -356.942365) (xy 170.230229 -356.965007) (xy 170.276079 -356.994473) (xy 170.31727 -357.030164)
			(xy 170.352961 -357.071355) (xy 170.382427 -357.117205) (xy 170.405069 -357.166782) (xy 170.420424 -357.219077)
			(xy 170.42818 -357.273025) (xy 170.428326 -357.281226) (xy 171.290996 -357.281226) (xy 171.291482 -357.253975)
			(xy 171.299238 -357.200027) (xy 171.314593 -357.147732) (xy 171.337235 -357.098155) (xy 171.366701 -357.052305)
			(xy 171.402392 -357.011114) (xy 171.443583 -356.975423) (xy 171.489433 -356.945957) (xy 171.53901 -356.923315)
			(xy 171.591305 -356.90796) (xy 171.645253 -356.900204) (xy 171.699755 -356.900204) (xy 171.753703 -356.90796)
			(xy 171.805998 -356.923315) (xy 171.855575 -356.945957) (xy 171.901425 -356.975423) (xy 171.942616 -357.011114)
			(xy 171.978307 -357.052305) (xy 172.007773 -357.098155) (xy 172.030415 -357.147732) (xy 172.04577 -357.200027)
			(xy 172.053526 -357.253975) (xy 172.054012 -357.281226) (xy 172.05377 -357.299893) (xy 172.050079 -357.337044)
			(xy 172.046646 -357.355394) (xy 172.044279 -357.369658) (xy 172.046811 -357.398451) (xy 172.057314 -357.425379)
			(xy 172.074943 -357.448283) (xy 172.098287 -357.465328) (xy 172.125472 -357.475145) (xy 172.139864 -357.476552)
			(xy 172.168516 -357.478943) (xy 172.224682 -357.491225) (xy 172.278369 -357.511796) (xy 172.328362 -357.54019)
			(xy 172.373528 -357.575762) (xy 172.412846 -357.61771) (xy 172.445425 -357.665081) (xy 172.470528 -357.716805)
			(xy 172.487586 -357.771709) (xy 172.496212 -357.828551) (xy 172.496734 -357.857298) (xy 172.496248 -357.884549)
			(xy 172.488492 -357.938497) (xy 172.473137 -357.990792) (xy 172.450495 -358.040369) (xy 172.441966 -358.05364)
			(xy 179.353972 -358.05364) (xy 179.35445 -358.025192) (xy 179.362913 -357.96893) (xy 179.379643 -357.91455)
			(xy 179.404268 -357.86326) (xy 179.436242 -357.816198) (xy 179.474853 -357.77441) (xy 179.49672 -357.756206)
			(xy 179.508238 -357.746308) (xy 179.525265 -357.721175) (xy 179.534167 -357.692153) (xy 179.534159 -357.661795)
			(xy 179.525242 -357.632777) (xy 179.508202 -357.607653) (xy 179.49672 -357.59771) (xy 179.474849 -357.579513)
			(xy 179.436246 -357.537721) (xy 179.404282 -357.490657) (xy 179.379667 -357.439365) (xy 179.362948 -357.384984)
			(xy 179.354497 -357.328722) (xy 179.353972 -357.300276) (xy 179.354458 -357.273025) (xy 179.362214 -357.219077)
			(xy 179.377569 -357.166782) (xy 179.400211 -357.117205) (xy 179.429677 -357.071355) (xy 179.465368 -357.030164)
			(xy 179.506559 -356.994473) (xy 179.552409 -356.965007) (xy 179.601986 -356.942365) (xy 179.654281 -356.92701)
			(xy 179.708229 -356.919254) (xy 179.762731 -356.919254) (xy 179.816679 -356.92701) (xy 179.868974 -356.942365)
			(xy 179.918551 -356.965007) (xy 179.964401 -356.994473) (xy 180.005592 -357.030164) (xy 180.041283 -357.071355)
			(xy 180.070749 -357.117205) (xy 180.093391 -357.166782) (xy 180.108746 -357.219077) (xy 180.116502 -357.273025)
			(xy 180.116648 -357.281226) (xy 180.979318 -357.281226) (xy 180.979804 -357.253975) (xy 180.98756 -357.200027)
			(xy 181.002915 -357.147732) (xy 181.025557 -357.098155) (xy 181.055023 -357.052305) (xy 181.090714 -357.011114)
			(xy 181.131905 -356.975423) (xy 181.177755 -356.945957) (xy 181.227332 -356.923315) (xy 181.279627 -356.90796)
			(xy 181.333575 -356.900204) (xy 181.388077 -356.900204) (xy 181.442025 -356.90796) (xy 181.49432 -356.923315)
			(xy 181.543897 -356.945957) (xy 181.589747 -356.975423) (xy 181.630938 -357.011114) (xy 181.666629 -357.052305)
			(xy 181.696095 -357.098155) (xy 181.718737 -357.147732) (xy 181.734092 -357.200027) (xy 181.741848 -357.253975)
			(xy 181.742334 -357.281226) (xy 181.742101 -357.299893) (xy 181.738409 -357.337045) (xy 181.734968 -357.355394)
			(xy 181.73258 -357.369656) (xy 181.735113 -357.398452) (xy 181.745618 -357.425384) (xy 181.763252 -357.44829)
			(xy 181.786601 -357.465334) (xy 181.813792 -357.475148) (xy 181.828186 -357.476552) (xy 181.85684 -357.478924)
			(xy 181.913006 -357.49121) (xy 181.966693 -357.511783) (xy 182.016686 -357.540179) (xy 182.061852 -357.575754)
			(xy 182.10117 -357.617703) (xy 182.133748 -357.665077) (xy 182.158851 -357.716802) (xy 182.175908 -357.771707)
			(xy 182.184534 -357.828551) (xy 182.185056 -357.857298) (xy 182.18457 -357.884549) (xy 182.176814 -357.938497)
			(xy 182.161459 -357.990792) (xy 182.138817 -358.040369) (xy 182.109351 -358.086219) (xy 182.07366 -358.12741)
			(xy 182.032469 -358.163101) (xy 181.986619 -358.192567) (xy 181.937042 -358.215209) (xy 181.884747 -358.230564)
			(xy 181.830799 -358.23832) (xy 181.776297 -358.23832) (xy 181.722349 -358.230564) (xy 181.670054 -358.215209)
			(xy 181.620477 -358.192567) (xy 181.574627 -358.163101) (xy 181.533436 -358.12741) (xy 181.497745 -358.086219)
			(xy 181.468279 -358.040369) (xy 181.445637 -357.990792) (xy 181.430282 -357.938497) (xy 181.422526 -357.884549)
			(xy 181.42204 -357.857298) (xy 181.422277 -357.838631) (xy 181.425967 -357.801479) (xy 181.429406 -357.78313)
			(xy 181.431793 -357.768867) (xy 181.429265 -357.740068) (xy 181.418763 -357.713134) (xy 181.401128 -357.690227)
			(xy 181.377777 -357.673184) (xy 181.350583 -357.663373) (xy 181.336188 -357.661972) (xy 181.307535 -357.659599)
			(xy 181.25137 -357.64731) (xy 181.197685 -357.626735) (xy 181.147693 -357.598338) (xy 181.102528 -357.562763)
			(xy 181.063211 -357.520815) (xy 181.030633 -357.473442) (xy 181.00553 -357.421719) (xy 180.98847 -357.366815)
			(xy 180.979841 -357.309973) (xy 180.979318 -357.281226) (xy 180.116648 -357.281226) (xy 180.116988 -357.300276)
			(xy 180.116428 -357.32872) (xy 180.107979 -357.384978) (xy 180.091264 -357.439356) (xy 180.066654 -357.490646)
			(xy 180.034696 -357.53771) (xy 179.9961 -357.579502) (xy 179.97424 -357.59771) (xy 179.96281 -357.6077)
			(xy 179.945787 -357.632808) (xy 179.93688 -357.661806) (xy 179.936872 -357.692141) (xy 179.945764 -357.721144)
			(xy 179.962774 -357.746261) (xy 179.97424 -357.756206) (xy 179.99611 -357.774404) (xy 180.034716 -357.816194)
			(xy 180.066681 -357.863258) (xy 180.091296 -357.914551) (xy 180.108014 -357.968932) (xy 180.110284 -357.984044)
			(xy 180.369462 -357.984044) (xy 180.373533 -357.928422) (xy 180.385659 -357.873985) (xy 180.405582 -357.821894)
			(xy 180.432878 -357.773259) (xy 180.466964 -357.729116) (xy 180.507113 -357.690407) (xy 180.552471 -357.657956)
			(xy 180.602071 -357.632455) (xy 180.654855 -357.614448) (xy 180.709698 -357.604318) (xy 180.765432 -357.602281)
			(xy 180.820869 -357.608381) (xy 180.874826 -357.622487) (xy 180.926155 -357.644299) (xy 180.973761 -357.673353)
			(xy 181.016629 -357.709028) (xy 181.053846 -357.750565) (xy 181.084619 -357.797078) (xy 181.108291 -357.847575)
			(xy 181.124359 -357.900982) (xy 181.132479 -357.956158) (xy 181.132988 -357.984044) (xy 181.132479 -358.01193)
			(xy 181.124359 -358.067106) (xy 181.108291 -358.120513) (xy 181.084619 -358.17101) (xy 181.053846 -358.217523)
			(xy 181.016629 -358.25906) (xy 180.973761 -358.294735) (xy 180.926155 -358.323789) (xy 180.874826 -358.345601)
			(xy 180.820869 -358.359707) (xy 180.765432 -358.365807) (xy 180.709698 -358.36377) (xy 180.654855 -358.35364)
			(xy 180.602071 -358.335633) (xy 180.552471 -358.310132) (xy 180.507113 -358.277681) (xy 180.466964 -358.238972)
			(xy 180.432878 -358.194829) (xy 180.405582 -358.146194) (xy 180.385659 -358.094103) (xy 180.373533 -358.039666)
			(xy 180.369462 -357.984044) (xy 180.110284 -357.984044) (xy 180.116464 -358.025193) (xy 180.116988 -358.05364)
			(xy 180.116502 -358.080891) (xy 180.108746 -358.134839) (xy 180.093391 -358.187134) (xy 180.070749 -358.236711)
			(xy 180.041283 -358.282561) (xy 180.005592 -358.323752) (xy 179.964401 -358.359443) (xy 179.918551 -358.388909)
			(xy 179.868974 -358.411551) (xy 179.816679 -358.426906) (xy 179.762731 -358.434662) (xy 179.708229 -358.434662)
			(xy 179.654281 -358.426906) (xy 179.601986 -358.411551) (xy 179.552409 -358.388909) (xy 179.506559 -358.359443)
			(xy 179.465368 -358.323752) (xy 179.429677 -358.282561) (xy 179.400211 -358.236711) (xy 179.377569 -358.187134)
			(xy 179.362214 -358.134839) (xy 179.354458 -358.080891) (xy 179.353972 -358.05364) (xy 172.441966 -358.05364)
			(xy 172.421029 -358.086219) (xy 172.385338 -358.12741) (xy 172.344147 -358.163101) (xy 172.298297 -358.192567)
			(xy 172.24872 -358.215209) (xy 172.196425 -358.230564) (xy 172.142477 -358.23832) (xy 172.087975 -358.23832)
			(xy 172.034027 -358.230564) (xy 171.981732 -358.215209) (xy 171.932155 -358.192567) (xy 171.886305 -358.163101)
			(xy 171.845114 -358.12741) (xy 171.809423 -358.086219) (xy 171.779957 -358.040369) (xy 171.757315 -357.990792)
			(xy 171.74196 -357.938497) (xy 171.734204 -357.884549) (xy 171.733718 -357.857298) (xy 171.733956 -357.838631)
			(xy 171.737645 -357.801479) (xy 171.741084 -357.78313) (xy 171.743398 -357.76886) (xy 171.740872 -357.740075)
			(xy 171.730379 -357.713153) (xy 171.71276 -357.690251) (xy 171.689428 -357.673205) (xy 171.662253 -357.663383)
			(xy 171.647866 -357.661972) (xy 171.619211 -357.659618) (xy 171.563046 -357.647326) (xy 171.50936 -357.626748)
			(xy 171.459369 -357.598348) (xy 171.414205 -357.562771) (xy 171.374888 -357.520821) (xy 171.34231 -357.473447)
			(xy 171.317207 -357.421722) (xy 171.300148 -357.366816) (xy 171.291519 -357.309973) (xy 171.290996 -357.281226)
			(xy 170.428326 -357.281226) (xy 170.428666 -357.300276) (xy 170.428216 -357.325613) (xy 170.421511 -357.375842)
			(xy 170.408216 -357.424741) (xy 170.388565 -357.47145) (xy 170.362903 -357.515146) (xy 170.331683 -357.555061)
			(xy 170.313858 -357.573072) (xy 170.30443 -357.582799) (xy 170.290719 -357.606154) (xy 170.283619 -357.632289)
			(xy 170.283627 -357.659371) (xy 170.290743 -357.685502) (xy 170.304467 -357.708849) (xy 170.313858 -357.718614)
			(xy 170.331685 -357.736625) (xy 170.362915 -357.776536) (xy 170.388585 -357.820231) (xy 170.408243 -357.86694)
			(xy 170.421543 -357.91584) (xy 170.428252 -357.966071) (xy 170.428546 -357.984044) (xy 170.68114 -357.984044)
			(xy 170.685211 -357.928422) (xy 170.697337 -357.873985) (xy 170.71726 -357.821894) (xy 170.744556 -357.773259)
			(xy 170.778642 -357.729116) (xy 170.818791 -357.690407) (xy 170.864149 -357.657956) (xy 170.913749 -357.632455)
			(xy 170.966533 -357.614448) (xy 171.021376 -357.604318) (xy 171.07711 -357.602281) (xy 171.132547 -357.608381)
			(xy 171.186504 -357.622487) (xy 171.237833 -357.644299) (xy 171.285439 -357.673353) (xy 171.328307 -357.709028)
			(xy 171.365524 -357.750565) (xy 171.396297 -357.797078) (xy 171.419969 -357.847575) (xy 171.436037 -357.900982)
			(xy 171.444157 -357.956158) (xy 171.444666 -357.984044) (xy 171.444157 -358.01193) (xy 171.436037 -358.067106)
			(xy 171.419969 -358.120513) (xy 171.396297 -358.17101) (xy 171.365524 -358.217523) (xy 171.328307 -358.25906)
			(xy 171.285439 -358.294735) (xy 171.237833 -358.323789) (xy 171.186504 -358.345601) (xy 171.132547 -358.359707)
			(xy 171.07711 -358.365807) (xy 171.021376 -358.36377) (xy 170.966533 -358.35364) (xy 170.913749 -358.335633)
			(xy 170.864149 -358.310132) (xy 170.818791 -358.277681) (xy 170.778642 -358.238972) (xy 170.744556 -358.194829)
			(xy 170.71726 -358.146194) (xy 170.697337 -358.094103) (xy 170.685211 -358.039666) (xy 170.68114 -357.984044)
			(xy 170.428546 -357.984044) (xy 170.428666 -357.99141) (xy 170.42818 -358.018661) (xy 170.420424 -358.072609)
			(xy 170.405069 -358.124904) (xy 170.382427 -358.174481) (xy 170.352961 -358.220331) (xy 170.31727 -358.261522)
			(xy 170.276079 -358.297213) (xy 170.230229 -358.326679) (xy 170.180652 -358.349321) (xy 170.128357 -358.364676)
			(xy 170.074409 -358.372432) (xy 170.019907 -358.372432) (xy 169.965959 -358.364676) (xy 169.913664 -358.349321)
			(xy 169.864087 -358.326679) (xy 169.818237 -358.297213) (xy 169.777046 -358.261522) (xy 169.741355 -358.220331)
			(xy 169.711889 -358.174481) (xy 169.689247 -358.124904) (xy 169.673892 -358.072609) (xy 169.666136 -358.018661)
			(xy 169.66565 -357.99141) (xy 167.13962 -357.99141) (xy 167.13962 -359.271062) (xy 168.462706 -360.594148)
			(xy 168.487588 -360.619698) (xy 168.532068 -360.67545) (xy 168.570024 -360.735833) (xy 168.600976 -360.800088)
			(xy 168.624535 -360.867406) (xy 168.640405 -360.93694) (xy 168.648386 -361.007813) (xy 168.648888 -361.043474)
			(xy 168.648888 -361.518962) (xy 175.165258 -361.518962) (xy 175.165781 -361.489792) (xy 175.174688 -361.432135)
			(xy 175.192271 -361.376507) (xy 175.218122 -361.324205) (xy 175.251636 -361.276451) (xy 175.292033 -361.234359)
			(xy 175.314864 -361.216194) (xy 175.325211 -361.207738) (xy 175.341501 -361.186567) (xy 175.351744 -361.161896)
			(xy 175.355241 -361.135413) (xy 175.351751 -361.10893) (xy 175.341514 -361.084257) (xy 175.32523 -361.063081)
			(xy 175.314864 -361.05465) (xy 175.292028 -361.036491) (xy 175.251629 -360.994402) (xy 175.218116 -360.946647)
			(xy 175.192271 -360.894343) (xy 175.1747 -360.838712) (xy 175.165812 -360.781052) (xy 175.165258 -360.751882)
			(xy 175.165761 -360.724632) (xy 175.173519 -360.670687) (xy 175.188875 -360.618394) (xy 175.211515 -360.568819)
			(xy 175.24098 -360.52297) (xy 175.27667 -360.481781) (xy 175.317858 -360.44609) (xy 175.363705 -360.416623)
			(xy 175.413279 -360.39398) (xy 175.465571 -360.378622) (xy 175.519516 -360.370862) (xy 175.546766 -360.370374)
			(xy 175.575683 -360.370889) (xy 175.632856 -360.379614) (xy 175.688056 -360.396871) (xy 175.740019 -360.422263)
			(xy 175.787552 -360.455209) (xy 175.829567 -360.494953) (xy 175.847756 -360.51744) (xy 175.857653 -360.529245)
			(xy 175.882977 -360.546764) (xy 175.91237 -360.55594) (xy 175.943162 -360.55594) (xy 175.972555 -360.546764)
			(xy 175.997879 -360.529245) (xy 176.007776 -360.51744) (xy 176.025991 -360.494976) (xy 176.068004 -360.455238)
			(xy 176.115534 -360.422296) (xy 176.167491 -360.396903) (xy 176.222685 -360.379643) (xy 176.279851 -360.370911)
			(xy 176.308766 -360.370374) (xy 176.337312 -360.37093) (xy 176.393765 -360.379443) (xy 176.44832 -360.396269)
			(xy 176.499761 -360.421033) (xy 176.52365 -360.436668) (xy 176.534772 -360.443765) (xy 176.559632 -360.452568)
			(xy 176.585919 -360.45469) (xy 176.61187 -360.449989) (xy 176.635742 -360.438781) (xy 176.655935 -360.421817)
			(xy 176.663858 -360.411268) (xy 176.679265 -360.390252) (xy 176.714864 -360.352198) (xy 176.75531 -360.31934)
			(xy 176.799849 -360.29229) (xy 176.847654 -360.27155) (xy 176.897835 -360.257507) (xy 176.949461 -360.25042)
			(xy 176.975516 -360.249978) (xy 177.004432 -360.250527) (xy 177.061603 -360.259246) (xy 177.116803 -360.276496)
			(xy 177.168765 -360.301881) (xy 177.2163 -360.334821) (xy 177.258316 -360.37456) (xy 177.276506 -360.397044)
			(xy 177.286403 -360.408849) (xy 177.311727 -360.426368) (xy 177.34112 -360.435544) (xy 177.371912 -360.435544)
			(xy 177.401305 -360.426368) (xy 177.426629 -360.408849) (xy 177.436526 -360.397044) (xy 177.454713 -360.374557)
			(xy 177.496733 -360.33482) (xy 177.544268 -360.30188) (xy 177.59623 -360.276492) (xy 177.651429 -360.259237)
			(xy 177.7086 -360.250511) (xy 177.737516 -360.249978) (xy 177.764767 -360.250463) (xy 177.818714 -360.258221)
			(xy 177.871008 -360.273578) (xy 177.920584 -360.29622) (xy 177.966434 -360.325686) (xy 178.007624 -360.361378)
			(xy 178.043315 -360.402568) (xy 178.072781 -360.448417) (xy 178.095423 -360.497994) (xy 178.110779 -360.550288)
			(xy 178.118537 -360.604235) (xy 178.119024 -360.631486) (xy 178.118573 -360.657529) (xy 178.111489 -360.70913)
			(xy 178.097451 -360.759287) (xy 178.076719 -360.807069) (xy 178.04968 -360.851586) (xy 178.016836 -360.89201)
			(xy 177.99812 -360.910124) (xy 177.988141 -360.920052) (xy 177.973673 -360.94419) (xy 177.966332 -360.971357)
			(xy 177.966673 -360.999497) (xy 177.97467 -361.026479) (xy 177.989718 -361.050259) (xy 177.999898 -361.059984)
			(xy 178.019495 -361.07813) (xy 178.053888 -361.118993) (xy 178.082244 -361.164254) (xy 178.104009 -361.213028)
			(xy 178.118757 -361.264362) (xy 178.1262 -361.317251) (xy 178.126644 -361.343956) (xy 178.126102 -361.371724)
			(xy 178.118056 -361.426674) (xy 178.102127 -361.479877) (xy 178.078653 -361.530208) (xy 178.048129 -361.576604)
			(xy 178.011201 -361.618083) (xy 177.990246 -361.63631) (xy 177.979642 -361.645881) (xy 177.963652 -361.66953)
			(xy 177.954852 -361.696687) (xy 177.953933 -361.725219) (xy 177.960967 -361.752886) (xy 177.975402 -361.777515)
			(xy 177.98542 -361.787694) (xy 178.003747 -361.805801) (xy 178.035923 -361.846035) (xy 178.062396 -361.890231)
			(xy 178.082685 -361.937585) (xy 178.096422 -361.987238) (xy 178.103357 -362.038287) (xy 178.103784 -362.064046)
			(xy 178.10329 -362.091415) (xy 178.09548 -362.145593) (xy 178.079997 -362.198096) (xy 178.057162 -362.247844)
			(xy 178.027443 -362.293812) (xy 178.009804 -362.314744) (xy 178.000523 -362.326038) (xy 177.98835 -362.352608)
			(xy 177.984186 -362.381535) (xy 177.98837 -362.410459) (xy 178.00056 -362.437021) (xy 178.009804 -362.448348)
			(xy 178.027488 -362.469245) (xy 178.057209 -362.51522) (xy 178.08005 -362.564972) (xy 178.095541 -362.617479)
			(xy 178.103365 -362.671662) (xy 178.10336 -362.726407) (xy 178.095526 -362.780589) (xy 178.080025 -362.833093)
			(xy 178.057176 -362.882841) (xy 178.027447 -362.928811) (xy 178.009804 -362.949744) (xy 178.000523 -362.961038)
			(xy 177.98835 -362.987608) (xy 177.984186 -363.016535) (xy 177.98837 -363.045459) (xy 178.00056 -363.072021)
			(xy 178.009804 -363.083348) (xy 178.027433 -363.104288) (xy 178.057146 -363.150259) (xy 178.059513 -363.155414)
			(xy 179.144926 -363.155414) (xy 179.144926 -363.070718) (xy 179.152977 -362.986404) (xy 179.169006 -362.903238)
			(xy 179.192867 -362.821971) (xy 179.224346 -362.743341) (xy 179.263157 -362.66806) (xy 179.308947 -362.596808)
			(xy 179.361303 -362.530232) (xy 179.419751 -362.468934) (xy 179.483761 -362.413469) (xy 179.552753 -362.36434)
			(xy 179.626103 -362.321991) (xy 179.703146 -362.286807) (xy 179.783185 -362.259105) (xy 179.865494 -362.239137)
			(xy 179.949329 -362.227084) (xy 180.03393 -362.223054) (xy 180.118531 -362.227084) (xy 180.202366 -362.239137)
			(xy 180.284675 -362.259105) (xy 180.364714 -362.286807) (xy 180.441757 -362.321991) (xy 180.515107 -362.36434)
			(xy 180.584099 -362.413469) (xy 180.648109 -362.468934) (xy 180.706557 -362.530232) (xy 180.758913 -362.596808)
			(xy 180.804703 -362.66806) (xy 180.843514 -362.743341) (xy 180.874993 -362.821971) (xy 180.898854 -362.903238)
			(xy 180.914883 -362.986404) (xy 180.922934 -363.070718) (xy 180.923438 -363.113066) (xy 181.669439 -363.113066)
			(xy 181.673475 -363.029619) (xy 181.685547 -362.946951) (xy 181.70554 -362.865834) (xy 181.733269 -362.787025)
			(xy 181.768475 -362.71126) (xy 181.810829 -362.639247) (xy 181.859935 -362.571658) (xy 181.915336 -362.509124)
			(xy 181.976513 -362.452229) (xy 182.042896 -362.401503) (xy 182.113864 -362.357422) (xy 182.188756 -362.320396)
			(xy 182.266872 -362.29077) (xy 182.347482 -362.268822) (xy 182.429834 -362.254757) (xy 182.51316 -362.248705)
			(xy 182.59668 -362.250724) (xy 182.679616 -362.260794) (xy 182.761192 -362.278822) (xy 182.840648 -362.304639)
			(xy 182.917241 -362.338004) (xy 182.990257 -362.378605) (xy 183.059013 -362.426064) (xy 183.122867 -362.479937)
			(xy 183.181224 -362.539722) (xy 183.233539 -362.604859) (xy 183.279322 -362.674742) (xy 183.318147 -362.748717)
			(xy 183.349652 -362.826094) (xy 183.373541 -362.906151) (xy 183.389592 -362.988139) (xy 183.397655 -363.071294)
			(xy 183.39816 -363.113066) (xy 183.397655 -363.154838) (xy 183.389592 -363.237993) (xy 183.373541 -363.319981)
			(xy 183.349652 -363.400038) (xy 183.318147 -363.477415) (xy 183.279322 -363.55139) (xy 183.233539 -363.621273)
			(xy 183.181224 -363.68641) (xy 183.122867 -363.746195) (xy 183.059013 -363.800068) (xy 182.990257 -363.847527)
			(xy 182.917241 -363.888128) (xy 182.840648 -363.921493) (xy 182.761192 -363.94731) (xy 182.679616 -363.965338)
			(xy 182.59668 -363.975408) (xy 182.51316 -363.977427) (xy 182.429834 -363.971375) (xy 182.347482 -363.95731)
			(xy 182.266872 -363.935362) (xy 182.188756 -363.905736) (xy 182.113864 -363.86871) (xy 182.042896 -363.824629)
			(xy 181.976513 -363.773903) (xy 181.915336 -363.717008) (xy 181.859935 -363.654474) (xy 181.810829 -363.586885)
			(xy 181.768475 -363.514872) (xy 181.733269 -363.439107) (xy 181.70554 -363.360298) (xy 181.685547 -363.279181)
			(xy 181.673475 -363.196513) (xy 181.669439 -363.113066) (xy 180.923438 -363.113066) (xy 180.922934 -363.155414)
			(xy 180.914883 -363.239728) (xy 180.898854 -363.322894) (xy 180.874993 -363.404161) (xy 180.843514 -363.482791)
			(xy 180.804703 -363.558072) (xy 180.758913 -363.629324) (xy 180.706557 -363.6959) (xy 180.648109 -363.757198)
			(xy 180.584099 -363.812663) (xy 180.515107 -363.861792) (xy 180.441757 -363.904141) (xy 180.364714 -363.939325)
			(xy 180.284675 -363.967027) (xy 180.202366 -363.986995) (xy 180.118531 -363.999048) (xy 180.03393 -364.003079)
			(xy 179.949329 -363.999048) (xy 179.865494 -363.986995) (xy 179.783185 -363.967027) (xy 179.703146 -363.939325)
			(xy 179.626103 -363.904141) (xy 179.552753 -363.861792) (xy 179.483761 -363.812663) (xy 179.419751 -363.757198)
			(xy 179.361303 -363.6959) (xy 179.308947 -363.629324) (xy 179.263157 -363.558072) (xy 179.224346 -363.482791)
			(xy 179.192867 -363.404161) (xy 179.169006 -363.322894) (xy 179.152977 -363.239728) (xy 179.144926 -363.155414)
			(xy 178.059513 -363.155414) (xy 178.079984 -363.200004) (xy 178.095477 -363.252503) (xy 178.103308 -363.306677)
			(xy 178.103784 -363.334046) (xy 178.103365 -363.361299) (xy 178.095601 -363.415251) (xy 178.080239 -363.467548)
			(xy 178.057591 -363.517127) (xy 178.028118 -363.562979) (xy 177.992419 -363.604169) (xy 177.951222 -363.63986)
			(xy 177.905366 -363.669325) (xy 177.855783 -363.691964) (xy 177.803482 -363.707316) (xy 177.74953 -363.71507)
			(xy 177.722276 -363.715554) (xy 177.69336 -363.714998) (xy 177.63619 -363.706279) (xy 177.580991 -363.68903)
			(xy 177.529029 -363.663645) (xy 177.481494 -363.630708) (xy 177.439477 -363.590971) (xy 177.421286 -363.568488)
			(xy 177.411389 -363.556683) (xy 177.386065 -363.539164) (xy 177.356672 -363.529988) (xy 177.32588 -363.529988)
			(xy 177.296487 -363.539164) (xy 177.271163 -363.556683) (xy 177.261266 -363.568488) (xy 177.243091 -363.590985)
			(xy 177.201068 -363.63072) (xy 177.15353 -363.663658) (xy 177.101566 -363.689044) (xy 177.046365 -363.706297)
			(xy 176.989193 -363.715022) (xy 176.960276 -363.715554) (xy 176.933026 -363.715045) (xy 176.879082 -363.707286)
			(xy 176.82679 -363.69193) (xy 176.777216 -363.66929) (xy 176.731368 -363.639825) (xy 176.690179 -363.604136)
			(xy 176.654488 -363.56295) (xy 176.625021 -363.517103) (xy 176.602377 -363.46753) (xy 176.587019 -363.41524)
			(xy 176.579257 -363.361296) (xy 176.578768 -363.334046) (xy 176.579244 -363.306676) (xy 176.587057 -363.252497)
			(xy 176.602543 -363.199993) (xy 176.625383 -363.150246) (xy 176.655107 -363.104279) (xy 176.672748 -363.083348)
			(xy 176.681937 -363.071986) (xy 176.694114 -363.04544) (xy 176.698293 -363.016535) (xy 176.694133 -362.987627)
			(xy 176.681975 -362.961073) (xy 176.672748 -362.949744) (xy 176.655151 -362.928775) (xy 176.625423 -362.882814)
			(xy 176.602574 -362.833074) (xy 176.587073 -362.780577) (xy 176.57924 -362.726403) (xy 176.579235 -362.671666)
			(xy 176.587058 -362.617491) (xy 176.60255 -362.564991) (xy 176.62539 -362.515247) (xy 176.65511 -362.46928)
			(xy 176.672748 -362.448348) (xy 176.681937 -362.436986) (xy 176.694114 -362.41044) (xy 176.698293 -362.381535)
			(xy 176.694133 -362.352627) (xy 176.681975 -362.326073) (xy 176.672748 -362.314744) (xy 176.655124 -362.2938)
			(xy 176.625408 -362.247831) (xy 176.602568 -362.198087) (xy 176.587074 -362.145589) (xy 176.579243 -362.091414)
			(xy 176.578768 -362.064046) (xy 176.578999 -362.044991) (xy 176.582819 -362.007073) (xy 176.586388 -361.988354)
			(xy 176.588705 -361.97488) (xy 176.586854 -361.947611) (xy 176.577837 -361.92181) (xy 176.562301 -361.899324)
			(xy 176.541357 -361.881763) (xy 176.516507 -361.870386) (xy 176.489529 -361.866007) (xy 176.462355 -361.868939)
			(xy 176.449482 -361.873546) (xy 176.427016 -361.882082) (xy 176.380475 -361.894068) (xy 176.332796 -361.900107)
			(xy 176.308766 -361.90047) (xy 176.27985 -361.899916) (xy 176.22268 -361.891196) (xy 176.167482 -361.873946)
			(xy 176.115519 -361.848561) (xy 176.067985 -361.815623) (xy 176.025967 -361.775887) (xy 176.007776 -361.753404)
			(xy 175.997879 -361.741599) (xy 175.972555 -361.72408) (xy 175.943162 -361.714904) (xy 175.91237 -361.714904)
			(xy 175.882977 -361.72408) (xy 175.857653 -361.741599) (xy 175.847756 -361.753404) (xy 175.829591 -361.775909)
			(xy 175.787566 -361.815643) (xy 175.740025 -361.848579) (xy 175.688059 -361.873964) (xy 175.632857 -361.891215)
			(xy 175.575684 -361.899938) (xy 175.546766 -361.90047) (xy 175.519511 -361.900077) (xy 175.465555 -361.892314)
			(xy 175.413254 -361.876952) (xy 175.363671 -361.854303) (xy 175.317816 -361.824827) (xy 175.276623 -361.789126)
			(xy 175.240929 -361.747926) (xy 175.211463 -361.702066) (xy 175.188823 -361.652479) (xy 175.173471 -361.600174)
			(xy 175.165718 -361.546218) (xy 175.165258 -361.518962) (xy 168.648888 -361.518962) (xy 168.648888 -364.273846)
			(xy 169.455338 -364.273846) (xy 169.455875 -364.24493) (xy 169.464598 -364.187759) (xy 169.481851 -364.13256)
			(xy 169.507239 -364.080597) (xy 169.54018 -364.033063) (xy 169.579919 -363.991046) (xy 169.602404 -363.972856)
			(xy 169.614161 -363.962907) (xy 169.631677 -363.937597) (xy 169.640856 -363.908218) (xy 169.640864 -363.877438)
			(xy 169.631702 -363.848054) (xy 169.614201 -363.822734) (xy 169.602404 -363.812836) (xy 169.579939 -363.794624)
			(xy 169.540202 -363.752608) (xy 169.507261 -363.705078) (xy 169.481869 -363.653121) (xy 169.464609 -363.597927)
			(xy 169.455876 -363.540761) (xy 169.455338 -363.511846) (xy 169.455822 -363.484476) (xy 169.463634 -363.430298)
			(xy 169.479118 -363.377794) (xy 169.501956 -363.328047) (xy 169.531678 -363.28208) (xy 169.549318 -363.261148)
			(xy 169.558509 -363.249787) (xy 169.57069 -363.223241) (xy 169.57487 -363.194335) (xy 169.570709 -363.165426)
			(xy 169.558547 -363.138872) (xy 169.549318 -363.127544) (xy 169.531723 -363.106575) (xy 169.501997 -363.060613)
			(xy 169.479149 -363.010873) (xy 169.46365 -362.958376) (xy 169.455817 -362.904203) (xy 169.455812 -362.849466)
			(xy 169.463635 -362.795292) (xy 169.479125 -362.742792) (xy 169.501963 -362.693048) (xy 169.531681 -362.647081)
			(xy 169.549318 -362.626148) (xy 169.558509 -362.614787) (xy 169.57069 -362.588241) (xy 169.57487 -362.559335)
			(xy 169.570709 -362.530426) (xy 169.558547 -362.503872) (xy 169.549318 -362.492544) (xy 169.531689 -362.471604)
			(xy 169.501975 -362.425634) (xy 169.479137 -362.375888) (xy 169.463643 -362.323389) (xy 169.455813 -362.269215)
			(xy 169.455338 -362.241846) (xy 169.455798 -362.214592) (xy 169.46355 -362.160639) (xy 169.478903 -362.108338)
			(xy 169.501543 -362.058755) (xy 169.531011 -362.012899) (xy 169.566705 -361.971705) (xy 169.607899 -361.936011)
			(xy 169.653755 -361.906543) (xy 169.703338 -361.883903) (xy 169.755639 -361.86855) (xy 169.809592 -361.860798)
			(xy 169.836846 -361.860338) (xy 169.864216 -361.860826) (xy 169.918394 -361.868637) (xy 169.970897 -361.884121)
			(xy 170.020645 -361.906958) (xy 170.066612 -361.936678) (xy 170.087544 -361.954318) (xy 170.098872 -361.963554)
			(xy 170.125429 -361.97573) (xy 170.154346 -361.979903) (xy 170.183263 -361.97573) (xy 170.20982 -361.963554)
			(xy 170.221148 -361.954318) (xy 170.242091 -361.936693) (xy 170.288061 -361.906978) (xy 170.337805 -361.884139)
			(xy 170.390304 -361.868645) (xy 170.444478 -361.860814) (xy 170.471846 -361.860338) (xy 170.500762 -361.860881)
			(xy 170.557933 -361.869602) (xy 170.613132 -361.886855) (xy 170.665094 -361.912242) (xy 170.712628 -361.945182)
			(xy 170.754646 -361.98492) (xy 170.772836 -362.007404) (xy 170.782733 -362.019209) (xy 170.808057 -362.036728)
			(xy 170.83745 -362.045904) (xy 170.868242 -362.045904) (xy 170.897635 -362.036728) (xy 170.922959 -362.019209)
			(xy 170.932856 -362.007404) (xy 170.951073 -361.984942) (xy 170.993087 -361.945206) (xy 171.040617 -361.912264)
			(xy 171.092573 -361.886872) (xy 171.147766 -361.869611) (xy 171.204932 -361.860876) (xy 171.233846 -361.860338)
			(xy 171.2611 -361.860735) (xy 171.315054 -361.868499) (xy 171.367353 -361.883862) (xy 171.416933 -361.906512)
			(xy 171.462786 -361.935988) (xy 171.503977 -361.971688) (xy 171.539668 -362.012888) (xy 171.569132 -362.058747)
			(xy 171.59177 -362.108333) (xy 171.60712 -362.160636) (xy 171.614871 -362.214591) (xy 171.615354 -362.241846)
			(xy 171.614867 -362.269216) (xy 171.607056 -362.323394) (xy 171.591573 -362.375898) (xy 171.568735 -362.425645)
			(xy 171.539014 -362.471612) (xy 171.521374 -362.492544) (xy 171.512095 -362.503839) (xy 171.499926 -362.530409)
			(xy 171.495763 -362.559335) (xy 171.499946 -362.588258) (xy 171.512133 -362.61482) (xy 171.521374 -362.626148)
			(xy 171.532804 -362.639864) (xy 171.542155 -362.650819) (xy 171.565655 -362.667446) (xy 171.592863 -362.676855)
			(xy 171.621615 -362.678296) (xy 171.649627 -362.671655) (xy 171.674673 -362.657461) (xy 171.694761 -362.63684)
			(xy 171.701968 -362.62437) (xy 171.716343 -362.59857) (xy 171.751735 -362.551293) (xy 171.793987 -362.510033)
			(xy 171.842091 -362.475774) (xy 171.894898 -362.449334) (xy 171.951148 -362.431345) (xy 172.009498 -362.422236)
			(xy 172.039026 -362.421678) (xy 172.066277 -362.422154) (xy 172.120225 -362.429913) (xy 172.172519 -362.445271)
			(xy 172.222095 -362.467914) (xy 172.267945 -362.497382) (xy 172.309134 -362.533074) (xy 172.344825 -362.574265)
			(xy 172.374292 -362.620115) (xy 172.396933 -362.669693) (xy 172.412289 -362.721987) (xy 172.420047 -362.775935)
			(xy 172.420534 -362.803186) (xy 172.420076 -362.830557) (xy 172.412259 -362.884737) (xy 172.396769 -362.937241)
			(xy 172.373925 -362.986987) (xy 172.344197 -363.032953) (xy 172.326554 -363.053884) (xy 172.317334 -363.065223)
			(xy 172.305161 -363.091777) (xy 172.300988 -363.120689) (xy 172.305155 -363.149602) (xy 172.317323 -363.176159)
			(xy 172.326554 -363.187488) (xy 172.344182 -363.208431) (xy 172.373909 -363.254397) (xy 172.396756 -363.304141)
			(xy 172.412254 -363.356642) (xy 172.420084 -363.410819) (xy 172.420086 -363.46556) (xy 172.412259 -363.519737)
			(xy 172.396763 -363.572239) (xy 172.373919 -363.621985) (xy 172.344194 -363.667952) (xy 172.326554 -363.688884)
			(xy 172.317334 -363.700223) (xy 172.305161 -363.726777) (xy 172.300988 -363.755689) (xy 172.305155 -363.784602)
			(xy 172.317323 -363.811159) (xy 172.326554 -363.822488) (xy 172.344194 -363.84342) (xy 172.373907 -363.889392)
			(xy 172.396744 -363.939139) (xy 172.412234 -363.99164) (xy 172.420061 -364.045817) (xy 172.420534 -364.073186)
			(xy 172.420009 -364.100436) (xy 172.412255 -364.154381) (xy 172.396903 -364.206673) (xy 172.377828 -364.248446)
			(xy 172.820838 -364.248446) (xy 172.821375 -364.21953) (xy 172.830098 -364.162359) (xy 172.847351 -364.10716)
			(xy 172.872739 -364.055197) (xy 172.90568 -364.007663) (xy 172.945419 -363.965646) (xy 172.967904 -363.947456)
			(xy 172.979661 -363.937507) (xy 172.997177 -363.912197) (xy 173.006356 -363.882818) (xy 173.006364 -363.852038)
			(xy 172.997202 -363.822654) (xy 172.979701 -363.797334) (xy 172.967904 -363.787436) (xy 172.945439 -363.769224)
			(xy 172.905702 -363.727208) (xy 172.872761 -363.679678) (xy 172.847369 -363.627721) (xy 172.830109 -363.572527)
			(xy 172.821376 -363.515361) (xy 172.820838 -363.486446) (xy 172.821322 -363.459076) (xy 172.829134 -363.404898)
			(xy 172.844618 -363.352394) (xy 172.867456 -363.302647) (xy 172.897178 -363.25668) (xy 172.914818 -363.235748)
			(xy 172.924009 -363.224387) (xy 172.93619 -363.197841) (xy 172.94037 -363.168935) (xy 172.936209 -363.140026)
			(xy 172.924047 -363.113472) (xy 172.914818 -363.102144) (xy 172.897223 -363.081175) (xy 172.867497 -363.035213)
			(xy 172.844649 -362.985473) (xy 172.82915 -362.932976) (xy 172.821317 -362.878803) (xy 172.821312 -362.824066)
			(xy 172.829135 -362.769892) (xy 172.844625 -362.717392) (xy 172.867463 -362.667648) (xy 172.897181 -362.621681)
			(xy 172.914818 -362.600748) (xy 172.924009 -362.589387) (xy 172.93619 -362.562841) (xy 172.94037 -362.533935)
			(xy 172.936209 -362.505026) (xy 172.924047 -362.478472) (xy 172.914818 -362.467144) (xy 172.897189 -362.446204)
			(xy 172.867475 -362.400234) (xy 172.844637 -362.350488) (xy 172.829143 -362.297989) (xy 172.821313 -362.243815)
			(xy 172.820838 -362.216446) (xy 172.821324 -362.189195) (xy 172.82908 -362.135247) (xy 172.844435 -362.082952)
			(xy 172.867077 -362.033375) (xy 172.896543 -361.987525) (xy 172.932234 -361.946334) (xy 172.973425 -361.910643)
			(xy 173.019275 -361.881177) (xy 173.068852 -361.858535) (xy 173.121147 -361.84318) (xy 173.175095 -361.835424)
			(xy 173.229597 -361.835424) (xy 173.283545 -361.84318) (xy 173.33584 -361.858535) (xy 173.385417 -361.881177)
			(xy 173.431267 -361.910643) (xy 173.472458 -361.946334) (xy 173.508149 -361.987525) (xy 173.537615 -362.033375)
			(xy 173.560257 -362.082952) (xy 173.575612 -362.135247) (xy 173.583368 -362.189195) (xy 173.583854 -362.216446)
			(xy 173.583367 -362.243816) (xy 173.575556 -362.297994) (xy 173.560073 -362.350498) (xy 173.537235 -362.400245)
			(xy 173.507514 -362.446212) (xy 173.489874 -362.467144) (xy 173.480595 -362.478439) (xy 173.468426 -362.505009)
			(xy 173.464263 -362.533935) (xy 173.468446 -362.562858) (xy 173.480633 -362.58942) (xy 173.489874 -362.600748)
			(xy 173.50756 -362.621644) (xy 173.537283 -362.667618) (xy 173.560125 -362.717371) (xy 173.575618 -362.769878)
			(xy 173.583442 -362.824062) (xy 173.583437 -362.878807) (xy 173.575603 -362.932989) (xy 173.560101 -362.985494)
			(xy 173.537249 -363.035242) (xy 173.507518 -363.081211) (xy 173.489874 -363.102144) (xy 173.480595 -363.113439)
			(xy 173.468426 -363.140009) (xy 173.464263 -363.168935) (xy 173.468446 -363.197858) (xy 173.480633 -363.22442)
			(xy 173.489874 -363.235748) (xy 173.507498 -363.256692) (xy 173.537213 -363.302661) (xy 173.560052 -363.352406)
			(xy 173.575547 -363.404904) (xy 173.583378 -363.459078) (xy 173.583854 -363.486446) (xy 173.583314 -363.515362)
			(xy 173.574592 -363.572533) (xy 173.55734 -363.627733) (xy 173.531952 -363.679695) (xy 173.499012 -363.727229)
			(xy 173.459273 -363.769246) (xy 173.436788 -363.787436) (xy 173.424939 -363.797285) (xy 173.407427 -363.822623)
			(xy 173.398258 -363.852028) (xy 173.398267 -363.882829) (xy 173.407452 -363.912229) (xy 173.424978 -363.937557)
			(xy 173.436788 -363.947456) (xy 173.459248 -363.965675) (xy 173.498985 -364.007688) (xy 173.531927 -364.055217)
			(xy 173.55732 -364.107173) (xy 173.574581 -364.162366) (xy 173.583316 -364.219532) (xy 173.583854 -364.248446)
			(xy 173.583368 -364.275697) (xy 173.575612 -364.329645) (xy 173.560257 -364.38194) (xy 173.537615 -364.431517)
			(xy 173.508149 -364.477367) (xy 173.472458 -364.518558) (xy 173.431267 -364.554249) (xy 173.385417 -364.583715)
			(xy 173.33584 -364.606357) (xy 173.283545 -364.621712) (xy 173.229597 -364.629468) (xy 173.175095 -364.629468)
			(xy 173.121147 -364.621712) (xy 173.068852 -364.606357) (xy 173.019275 -364.583715) (xy 172.973425 -364.554249)
			(xy 172.932234 -364.518558) (xy 172.896543 -364.477367) (xy 172.867077 -364.431517) (xy 172.844435 -364.38194)
			(xy 172.82908 -364.329645) (xy 172.821324 -364.275697) (xy 172.820838 -364.248446) (xy 172.377828 -364.248446)
			(xy 172.374265 -364.256248) (xy 172.344803 -364.302098) (xy 172.309116 -364.343287) (xy 172.26793 -364.378979)
			(xy 172.222084 -364.408446) (xy 172.172511 -364.431089) (xy 172.12022 -364.446446) (xy 172.066276 -364.454206)
			(xy 172.039026 -364.454694) (xy 172.008913 -364.454148) (xy 171.949431 -364.44471) (xy 171.892169 -364.426048)
			(xy 171.838548 -364.398626) (xy 171.789899 -364.363123) (xy 171.768262 -364.342172) (xy 171.757249 -364.331965)
			(xy 171.730832 -364.31774) (xy 171.701418 -364.311816) (xy 171.671553 -364.314704) (xy 171.64382 -364.326156)
			(xy 171.620618 -364.34518) (xy 171.603954 -364.370131) (xy 171.599098 -364.384336) (xy 171.590828 -364.410127)
			(xy 171.567947 -364.459219) (xy 171.538357 -364.504584) (xy 171.502652 -364.545312) (xy 171.461549 -364.580584)
			(xy 171.415873 -364.609692) (xy 171.366542 -364.632053) (xy 171.314545 -364.647216) (xy 171.260927 -364.654878)
			(xy 171.233846 -364.655354) (xy 171.204929 -364.65482) (xy 171.147758 -364.646097) (xy 171.092559 -364.628843)
			(xy 171.040597 -364.603455) (xy 170.993063 -364.570513) (xy 170.951046 -364.530773) (xy 170.932856 -364.508288)
			(xy 170.922959 -364.496483) (xy 170.897635 -364.478964) (xy 170.868242 -364.469788) (xy 170.83745 -364.469788)
			(xy 170.808057 -364.478964) (xy 170.782733 -364.496483) (xy 170.772836 -364.508288) (xy 170.754622 -364.530752)
			(xy 170.712607 -364.570489) (xy 170.665077 -364.60343) (xy 170.61312 -364.628822) (xy 170.557927 -364.646083)
			(xy 170.500761 -364.654816) (xy 170.471846 -364.655354) (xy 170.444476 -364.654872) (xy 170.390297 -364.64706)
			(xy 170.337794 -364.631575) (xy 170.288047 -364.608737) (xy 170.24208 -364.579014) (xy 170.221148 -364.561374)
			(xy 170.20982 -364.552138) (xy 170.183263 -364.539962) (xy 170.154346 -364.535789) (xy 170.125429 -364.539962)
			(xy 170.098872 -364.552138) (xy 170.087544 -364.561374) (xy 170.066603 -364.579002) (xy 170.020633 -364.608716)
			(xy 169.970888 -364.631555) (xy 169.918389 -364.647048) (xy 169.864215 -364.654879) (xy 169.836846 -364.655354)
			(xy 169.809598 -364.654779) (xy 169.755656 -364.64703) (xy 169.703366 -364.631683) (xy 169.653792 -364.609051)
			(xy 169.607943 -364.579594) (xy 169.566754 -364.543911) (xy 169.531062 -364.50273) (xy 169.501593 -364.456889)
			(xy 169.478949 -364.407321) (xy 169.46359 -364.355034) (xy 169.455827 -364.301094) (xy 169.455338 -364.273846)
			(xy 168.648888 -364.273846) (xy 168.648888 -368.463068) (xy 168.648408 -368.49873) (xy 168.640423 -368.569605)
			(xy 168.624551 -368.63914) (xy 168.60099 -368.706459) (xy 168.570037 -368.770717) (xy 168.532083 -368.831103)
			(xy 168.487604 -368.886858) (xy 168.462706 -368.912394) (xy 168.368726 -369.006374) (xy 168.343178 -369.03126)
			(xy 168.287429 -369.075749) (xy 168.227047 -369.113713) (xy 168.162792 -369.144675) (xy 168.095473 -369.168243)
			(xy 168.025939 -369.184122) (xy 167.955062 -369.192112) (xy 167.9194 -369.192556) (xy 167.883738 -369.192056)
			(xy 167.812862 -369.184071) (xy 167.743325 -369.1682) (xy 167.676003 -369.144644) (xy 167.611741 -369.113699)
			(xy 167.551348 -369.075754) (xy 167.495583 -369.031285) (xy 167.445147 -368.980853) (xy 167.400674 -368.925091)
			(xy 167.362724 -368.864701) (xy 167.331774 -368.800442) (xy 167.308213 -368.733121) (xy 167.292338 -368.663586)
			(xy 167.284347 -368.59271) (xy 167.283892 -368.557048) (xy 167.284349 -368.522045) (xy 167.292035 -368.452461)
			(xy 167.307331 -368.384146) (xy 167.33005 -368.317928) (xy 167.359917 -368.254613) (xy 167.377872 -368.224562)
			(xy 167.377872 -361.306618) (xy 167.313102 -361.241594) (xy 167.302123 -361.231355) (xy 167.275666 -361.217197)
			(xy 167.246237 -361.211333) (xy 167.216374 -361.21427) (xy 167.188652 -361.225755) (xy 167.165461 -361.244796)
			(xy 167.148799 -361.269752) (xy 167.140105 -361.298472) (xy 167.13962 -361.313476) (xy 167.13962 -373.327168)
			(xy 168.0972 -374.284748) (xy 180.5686 -374.284748)
		)
		(stroke
			(width 0)
			(type solid)
		)
		(fill yes)
		(layer "In2.Cu")
		(net "GND")
	)
	(gr_poly
		(pts
			(xy 55.483506 -366.872266) (xy 55.465218 -366.846866) (xy 55.448354 -366.822399) (xy 55.421604 -366.769339)
			(xy 55.4034 -366.712775) (xy 55.394182 -366.654073) (xy 55.39359 -366.624362) (xy 55.39359 -366.616742)
			(xy 55.394572 -366.589836) (xy 55.403169 -366.536688) (xy 55.419153 -366.485276) (xy 55.442207 -366.436622)
			(xy 55.471872 -366.391693) (xy 55.50756 -366.351381) (xy 55.548562 -366.316488) (xy 55.594062 -366.287706)
			(xy 55.643157 -366.265607) (xy 55.694872 -366.250631) (xy 55.748178 -366.243075) (xy 55.775098 -366.2426)
			(xy 55.803056 -366.243108) (xy 55.85837 -366.251297) (xy 55.911901 -366.267455) (xy 55.937404 -366.278922)
			(xy 55.945532 -366.282732) (xy 55.962296 -366.291114) (xy 55.994808 -366.286034) (xy 56.313578 -365.967264)
			(xy 56.409844 -365.734854) (xy 56.409844 -364.329218) (xy 56.096916 -364.016544) (xy 55.595012 -363.51464)
			(xy 55.57779 -363.49653) (xy 55.550051 -363.45497) (xy 55.530945 -363.4088) (xy 55.521204 -363.359792)
			(xy 55.52059 -363.334808) (xy 55.520844 -362.318046) (xy 55.520844 -361.023916) (xy 52.790852 -358.293924)
			(xy 51.286664 -358.293924) (xy 51.268507 -358.313565) (xy 51.227642 -358.348077) (xy 51.182356 -358.376539)
			(xy 51.133537 -358.398395) (xy 51.082143 -358.413215) (xy 51.029182 -358.420708) (xy 51.002438 -358.421178)
			(xy 50.975366 -358.4207) (xy 50.921768 -358.413033) (xy 50.869792 -358.397864) (xy 50.820485 -358.375495)
			(xy 50.774837 -358.346379) (xy 50.733766 -358.311098) (xy 50.698097 -358.270364) (xy 50.682906 -358.24795)
			(xy 50.66919 -358.227122) (xy 50.588672 -358.220264) (xy 50.571908 -358.237282) (xy 50.56886 -358.24033)
			(xy 50.546508 -358.26192) (xy 50.546508 -358.773476) (xy 50.884328 -359.111296) (xy 53.151278 -359.111296)
			(xy 53.175343 -359.112501) (xy 53.222399 -359.122829) (xy 53.26667 -359.14183) (xy 53.306572 -359.168825)
			(xy 53.323998 -359.185464) (xy 55.193184 -361.05465) (xy 55.210407 -361.072759) (xy 55.238148 -361.114319)
			(xy 55.257256 -361.160489) (xy 55.266999 -361.209498) (xy 55.267606 -361.234482) (xy 55.267352 -362.330746)
			(xy 55.267352 -363.724698) (xy 55.753254 -364.2106) (xy 55.77459 -364.2106) (xy 55.801866 -364.211029)
			(xy 55.855872 -364.218727) (xy 55.908231 -364.234038) (xy 55.957875 -364.256652) (xy 56.003791 -364.286106)
			(xy 56.045044 -364.3218) (xy 56.080793 -364.363006) (xy 56.110307 -364.408884) (xy 56.132986 -364.458498)
			(xy 56.148367 -364.510837) (xy 56.156136 -364.564832) (xy 56.156606 -364.592108) (xy 56.156141 -364.619372)
			(xy 56.148377 -364.673344) (xy 56.133007 -364.725661) (xy 56.110346 -364.775257) (xy 56.080854 -364.821121)
			(xy 56.045133 -364.862319) (xy 56.003911 -364.898012) (xy 55.958026 -364.927472) (xy 55.908415 -364.950099)
			(xy 55.856088 -364.965433) (xy 55.80211 -364.97316) (xy 55.747582 -364.973124) (xy 55.693615 -364.965324)
			(xy 55.641308 -364.949921) (xy 55.591727 -364.927228) (xy 55.545882 -364.897707) (xy 55.504707 -364.861959)
			(xy 55.469041 -364.820713) (xy 55.43961 -364.77481) (xy 55.417015 -364.725184) (xy 55.401715 -364.672847)
			(xy 55.394023 -364.618864) (xy 55.39359 -364.5916) (xy 55.39359 -364.570264) (xy 55.179976 -364.356904)
			(xy 54.833012 -364.00994) (xy 54.81579 -363.99183) (xy 54.788051 -363.95027) (xy 54.768945 -363.9041)
			(xy 54.759204 -363.855092) (xy 54.75859 -363.830108) (xy 54.758844 -362.733844) (xy 54.758844 -361.339892)
			(xy 53.038756 -359.619804) (xy 50.771806 -359.619804) (xy 50.747742 -359.618597) (xy 50.700688 -359.608267)
			(xy 50.656419 -359.589264) (xy 50.616519 -359.562268) (xy 50.599086 -359.545636) (xy 50.112168 -359.058718)
			(xy 50.09495 -359.040607) (xy 50.067219 -358.999044) (xy 50.04812 -358.952875) (xy 50.038385 -358.903868)
			(xy 50.037746 -358.878886) (xy 50.038 -358.729788) (xy 50.038 -358.507284) (xy 49.880774 -358.44988)
			(xy 49.856744 -358.480324) (xy 49.803449 -358.53668) (xy 49.744711 -358.587338) (xy 49.681137 -358.631774)
			(xy 49.613382 -358.669531) (xy 49.542146 -358.700218) (xy 49.468164 -358.723519) (xy 49.392199 -358.739193)
			(xy 49.315036 -358.747078) (xy 49.276254 -358.747568) (xy 49.236322 -358.747043) (xy 49.156897 -358.73869)
			(xy 49.07878 -358.722081) (xy 49.002827 -358.697397) (xy 48.92987 -358.66491) (xy 48.860709 -358.624974)
			(xy 48.7961 -358.578028) (xy 48.736753 -358.524586) (xy 48.683318 -358.465233) (xy 48.636379 -358.400619)
			(xy 48.596451 -358.331453) (xy 48.563972 -358.258493) (xy 48.539297 -358.182537) (xy 48.522696 -358.104418)
			(xy 48.514353 -358.024992) (xy 48.513746 -357.98506) (xy 48.513746 -357.984298) (xy 48.514291 -357.943178)
			(xy 48.523139 -357.861414) (xy 48.540742 -357.78108) (xy 48.566896 -357.703108) (xy 48.583596 -357.665528)
			(xy 48.585882 -357.660702) (xy 48.590708 -357.63962) (xy 48.585882 -357.618538) (xy 48.583596 -357.613712)
			(xy 48.56691 -357.576126) (xy 48.540772 -357.498152) (xy 48.523165 -357.41782) (xy 48.514291 -357.336061)
			(xy 48.513746 -357.294942) (xy 48.513746 -357.293926) (xy 48.514212 -357.256035) (xy 48.521726 -357.180626)
			(xy 48.536684 -357.106334) (xy 48.558938 -357.033893) (xy 48.573182 -356.998778) (xy 48.58385 -356.973378)
			(xy 48.50511 -356.857554) (xy 48.477424 -356.858062) (xy 48.470058 -356.858062) (xy 48.442808 -356.857596)
			(xy 48.388864 -356.849834) (xy 48.336574 -356.834474) (xy 48.287002 -356.811828) (xy 48.241158 -356.782358)
			(xy 48.199974 -356.746664) (xy 48.164289 -356.705472) (xy 48.13483 -356.65962) (xy 48.112196 -356.610043)
			(xy 48.096848 -356.55775) (xy 48.089098 -356.503804) (xy 48.08855 -356.476554) (xy 48.089566 -356.449884)
			(xy 48.092106 -356.414578) (xy 47.94123 -356.345744) (xy 47.836328 -356.4509) (xy 47.836328 -356.880668)
			(xy 47.880778 -356.925118) (xy 47.894748 -356.928674) (xy 47.922156 -356.935768) (xy 47.974658 -356.956952)
			(xy 48.023448 -356.98567) (xy 48.067452 -357.021289) (xy 48.105703 -357.063026) (xy 48.137359 -357.109963)
			(xy 48.161723 -357.161066) (xy 48.178259 -357.215211) (xy 48.186603 -357.271207) (xy 48.187102 -357.299514)
			(xy 48.187102 -357.300276) (xy 48.186833 -357.31959) (xy 48.182892 -357.358018) (xy 48.179228 -357.376984)
			(xy 48.182907 -357.395947) (xy 48.186852 -357.434377) (xy 48.187102 -357.453692) (xy 48.187102 -357.454454)
			(xy 48.186642 -357.481709) (xy 48.17889 -357.535664) (xy 48.163538 -357.587967) (xy 48.140898 -357.637553)
			(xy 48.111431 -357.683411) (xy 48.075737 -357.724609) (xy 48.034544 -357.760307) (xy 47.988688 -357.789779)
			(xy 47.939105 -357.812424) (xy 47.886804 -357.827782) (xy 47.832849 -357.835539) (xy 47.805594 -357.835962)
			(xy 47.777305 -357.835447) (xy 47.721348 -357.827087) (xy 47.66724 -357.810551) (xy 47.616169 -357.786203)
			(xy 47.569256 -357.754577) (xy 47.52753 -357.716367) (xy 47.491907 -357.672411) (xy 47.463169 -357.623675)
			(xy 47.441948 -357.571227) (xy 47.434754 -357.543862) (xy 47.431452 -357.529892) (xy 47.272448 -357.370888)
			(xy 47.255161 -357.352891) (xy 47.225845 -357.312509) (xy 47.203198 -357.268044) (xy 47.187775 -357.220586)
			(xy 47.179956 -357.171302) (xy 47.179484 -357.146352) (xy 47.179484 -356.339902) (xy 47.179973 -356.314953)
			(xy 47.187778 -356.265668) (xy 47.203197 -356.218211) (xy 47.225849 -356.17375) (xy 47.255178 -356.13338)
			(xy 47.272448 -356.115366) (xy 48.561244 -354.82657) (xy 48.561244 -353.487736) (xy 48.339248 -353.26574)
			(xy 48.321964 -353.247742) (xy 48.292654 -353.207359) (xy 48.270013 -353.162893) (xy 48.254598 -353.115436)
			(xy 48.246786 -353.066153) (xy 48.246284 -353.041204) (xy 48.246284 -347.960442) (xy 47.366428 -347.080586)
			(xy 47.349142 -347.062588) (xy 47.319828 -347.022206) (xy 47.297183 -346.977741) (xy 47.281761 -346.930283)
			(xy 47.273943 -346.881) (xy 47.273464 -346.85605) (xy 47.273464 -343.253568) (xy 47.273948 -343.228616)
			(xy 47.281744 -343.179326) (xy 47.297154 -343.131862) (xy 47.3198 -343.087393) (xy 47.349123 -343.047014)
			(xy 47.366428 -343.029032) (xy 47.727616 -342.667844) (xy 47.730918 -342.653874) (xy 47.738668 -342.6243)
			(xy 47.762285 -342.567913) (xy 47.79459 -342.516013) (xy 47.81423 -342.492584) (xy 47.826676 -342.47836)
			(xy 47.826676 -342.373204) (xy 47.81423 -342.35898) (xy 47.79659 -342.338047) (xy 47.766868 -342.29208)
			(xy 47.744025 -342.242334) (xy 47.728531 -342.189833) (xy 47.720704 -342.135656) (xy 47.720706 -342.080917)
			(xy 47.728537 -342.02674) (xy 47.744034 -341.97424) (xy 47.766881 -341.924496) (xy 47.796607 -341.878531)
			(xy 47.81423 -341.857584) (xy 47.826676 -341.84336) (xy 47.826676 -341.738204) (xy 47.81423 -341.72398)
			(xy 47.79659 -341.703047) (xy 47.766868 -341.65708) (xy 47.744025 -341.607334) (xy 47.728531 -341.554833)
			(xy 47.720704 -341.500656) (xy 47.720706 -341.445917) (xy 47.728537 -341.39174) (xy 47.744034 -341.33924)
			(xy 47.766881 -341.289496) (xy 47.796607 -341.243531) (xy 47.81423 -341.222584) (xy 47.826676 -341.20836)
			(xy 47.826676 -341.103204) (xy 47.81423 -341.08898) (xy 47.79659 -341.068047) (xy 47.766868 -341.02208)
			(xy 47.744025 -340.972334) (xy 47.728531 -340.919833) (xy 47.720704 -340.865656) (xy 47.720706 -340.810917)
			(xy 47.728537 -340.75674) (xy 47.744034 -340.70424) (xy 47.766881 -340.654496) (xy 47.796607 -340.608531)
			(xy 47.81423 -340.587584) (xy 47.826676 -340.57336) (xy 47.826676 -340.468204) (xy 47.81423 -340.45398)
			(xy 47.798414 -340.435282) (xy 47.771205 -340.394563) (xy 47.749433 -340.350695) (xy 47.733457 -340.3044)
			(xy 47.728124 -340.280498) (xy 47.720876 -340.254231) (xy 47.713096 -340.2003) (xy 47.71263 -340.173056)
			(xy 47.71263 -340.172802) (xy 47.71311 -340.145637) (xy 47.720818 -340.091855) (xy 47.736079 -340.039712)
			(xy 47.758584 -339.990261) (xy 47.787878 -339.944504) (xy 47.823367 -339.903366) (xy 47.864334 -339.867679)
			(xy 47.886874 -339.852508) (xy 47.886874 -339.78215) (xy 47.886254 -339.770596) (xy 47.876064 -339.749847)
			(xy 47.867316 -339.742272) (xy 47.844829 -339.724083) (xy 47.805086 -339.682067) (xy 47.77214 -339.634534)
			(xy 47.746748 -339.582571) (xy 47.72949 -339.527372) (xy 47.720762 -339.470199) (xy 47.72025 -339.441282)
			(xy 47.720772 -339.412544) (xy 47.729398 -339.355718) (xy 47.746452 -339.30083) (xy 47.771548 -339.249122)
			(xy 47.804118 -339.201764) (xy 47.823374 -339.180424) (xy 47.83709 -339.165692) (xy 47.83709 -339.056472)
			(xy 47.823374 -339.04174) (xy 47.804106 -339.020412) (xy 47.771548 -338.973048) (xy 47.746462 -338.921335)
			(xy 47.729417 -338.866446) (xy 47.720798 -338.80962) (xy 47.72025 -338.780882) (xy 47.720737 -338.753631)
			(xy 47.728495 -338.699682) (xy 47.743852 -338.647387) (xy 47.766493 -338.59781) (xy 47.795959 -338.551959)
			(xy 47.83165 -338.510767) (xy 47.872839 -338.475074) (xy 47.918689 -338.445605) (xy 47.968265 -338.42296)
			(xy 48.020559 -338.4076) (xy 48.074507 -338.399839) (xy 48.101758 -338.399374) (xy 48.130498 -338.399893)
			(xy 48.187327 -338.408511) (xy 48.24222 -338.425559) (xy 48.293934 -338.450651) (xy 48.341297 -338.483218)
			(xy 48.362616 -338.502498) (xy 48.377348 -338.516214) (xy 48.486568 -338.516214) (xy 48.5013 -338.502498)
			(xy 48.522627 -338.483228) (xy 48.56999 -338.450663) (xy 48.621701 -338.425572) (xy 48.676592 -338.408522)
			(xy 48.733419 -338.3999) (xy 48.790897 -338.3999) (xy 48.847724 -338.408522) (xy 48.902615 -338.425572)
			(xy 48.954326 -338.450663) (xy 49.001689 -338.483228) (xy 49.023016 -338.502498) (xy 49.037748 -338.516214)
			(xy 49.146968 -338.516214) (xy 49.1617 -338.502498) (xy 49.183027 -338.483226) (xy 49.230389 -338.450658)
			(xy 49.2821 -338.425562) (xy 49.336991 -338.408507) (xy 49.393818 -338.399879) (xy 49.422558 -338.399374)
			(xy 49.449813 -338.399834) (xy 49.50377 -338.407586) (xy 49.556074 -338.422938) (xy 49.60566 -338.445578)
			(xy 49.65152 -338.475045) (xy 49.692719 -338.510738) (xy 49.728419 -338.551932) (xy 49.757893 -338.597787)
			(xy 49.780541 -338.64737) (xy 49.795901 -338.699671) (xy 49.803662 -338.753627) (xy 49.804066 -338.780882)
			(xy 49.803546 -338.809621) (xy 49.794925 -338.86645) (xy 49.777876 -338.921342) (xy 49.752784 -338.973055)
			(xy 49.720218 -339.020417) (xy 49.700942 -339.04174) (xy 49.687226 -339.056472) (xy 49.687226 -339.165692)
			(xy 49.700942 -339.180424) (xy 49.720211 -339.201752) (xy 49.752773 -339.249116) (xy 49.777862 -339.300827)
			(xy 49.794912 -339.355717) (xy 49.803536 -339.412544) (xy 49.804066 -339.441282) (xy 49.803612 -339.467793)
			(xy 49.796271 -339.520305) (xy 49.781729 -339.571293) (xy 49.760266 -339.619777) (xy 49.732294 -339.664821)
			(xy 49.698354 -339.705557) (xy 49.6591 -339.7412) (xy 49.637442 -339.756496) (xy 49.637442 -339.862922)
			(xy 49.660209 -339.879918) (xy 49.70093 -339.919537) (xy 49.735331 -339.964752) (xy 49.762651 -340.014565)
			(xy 49.782288 -340.067878) (xy 49.788572 -340.095586) (xy 49.795822 -340.121853) (xy 49.803603 -340.175783)
			(xy 49.804066 -340.203028) (xy 49.804066 -340.203282) (xy 49.803588 -340.23065) (xy 49.795754 -340.284822)
			(xy 49.780256 -340.337318) (xy 49.757415 -340.38706) (xy 49.727699 -340.433027) (xy 49.710086 -340.45398)
			(xy 49.69764 -340.468204) (xy 49.69764 -340.57336) (xy 49.710086 -340.587584) (xy 49.727727 -340.608517)
			(xy 49.757454 -340.654485) (xy 49.780301 -340.704232) (xy 49.795799 -340.756735) (xy 49.803629 -340.810915)
			(xy 49.803631 -340.865658) (xy 49.795805 -340.919838) (xy 49.78031 -340.972342) (xy 49.757467 -341.022091)
			(xy 49.727744 -341.068061) (xy 49.710086 -341.08898) (xy 49.69764 -341.103204) (xy 49.69764 -341.20836)
			(xy 49.710086 -341.222584) (xy 49.727727 -341.243517) (xy 49.757454 -341.289485) (xy 49.780301 -341.339232)
			(xy 49.795799 -341.391735) (xy 49.803629 -341.445915) (xy 49.803631 -341.500658) (xy 49.795805 -341.554838)
			(xy 49.78031 -341.607342) (xy 49.757467 -341.657091) (xy 49.727744 -341.703061) (xy 49.710086 -341.72398)
			(xy 49.69764 -341.738204) (xy 49.69764 -341.84336) (xy 49.710086 -341.857584) (xy 49.727727 -341.878517)
			(xy 49.757454 -341.924485) (xy 49.780301 -341.974232) (xy 49.795799 -342.026735) (xy 49.803629 -342.080915)
			(xy 49.803631 -342.135658) (xy 49.795805 -342.189838) (xy 49.78031 -342.242342) (xy 49.757467 -342.292091)
			(xy 49.727744 -342.338061) (xy 49.710086 -342.35898) (xy 49.69764 -342.373204) (xy 49.69764 -342.47836)
			(xy 49.710086 -342.492584) (xy 49.727729 -342.513515) (xy 49.757459 -342.559481) (xy 49.780305 -342.609227)
			(xy 49.795798 -342.661731) (xy 49.803619 -342.715911) (xy 49.804066 -342.743282) (xy 49.803604 -342.770535)
			(xy 49.795849 -342.824485) (xy 49.780494 -342.876783) (xy 49.757852 -342.926363) (xy 49.728384 -342.972215)
			(xy 49.692689 -343.013406) (xy 49.651496 -343.049098) (xy 49.605641 -343.078563) (xy 49.55606 -343.101202)
			(xy 49.503762 -343.116554) (xy 49.449811 -343.124306) (xy 49.422558 -343.12479) (xy 49.393817 -343.124273)
			(xy 49.336985 -343.115658) (xy 49.282089 -343.098614) (xy 49.230371 -343.073527) (xy 49.183003 -343.040965)
			(xy 49.1617 -343.021666) (xy 49.146968 -343.00795) (xy 49.037748 -343.00795) (xy 49.023016 -343.021666)
			(xy 49.001689 -343.040936) (xy 48.954326 -343.073501) (xy 48.902615 -343.098592) (xy 48.847724 -343.115642)
			(xy 48.790897 -343.124264) (xy 48.733419 -343.124264) (xy 48.676592 -343.115642) (xy 48.621701 -343.098592)
			(xy 48.56999 -343.073501) (xy 48.522627 -343.040936) (xy 48.5013 -343.021666) (xy 48.486568 -343.00795)
			(xy 48.377348 -343.00795) (xy 48.362616 -343.021666) (xy 48.344347 -343.038233) (xy 48.304297 -343.067013)
			(xy 48.260873 -343.090393) (xy 48.214798 -343.107982) (xy 48.190912 -343.114122) (xy 48.176942 -343.117678)
			(xy 47.908972 -343.385648) (xy 47.908972 -346.72397) (xy 48.788828 -347.603826) (xy 48.806116 -347.621823)
			(xy 48.835432 -347.662204) (xy 48.858079 -347.70667) (xy 48.873501 -347.754127) (xy 48.881318 -347.803412)
			(xy 48.881792 -347.828362) (xy 48.881792 -352.909124) (xy 49.103788 -353.13112) (xy 49.121073 -353.149118)
			(xy 49.150385 -353.189501) (xy 49.173028 -353.233967) (xy 49.188448 -353.281424) (xy 49.196265 -353.330707)
			(xy 49.196752 -353.355656) (xy 49.196752 -354.95865) (xy 49.196267 -354.983601) (xy 49.188469 -355.032891)
			(xy 49.173057 -355.080353) (xy 49.150411 -355.124821) (xy 49.121087 -355.165199) (xy 49.103788 -355.183186)
			(xy 48.876174 -355.4108) (xy 51.545729 -355.4108) (xy 51.549897 -355.355185) (xy 51.562307 -355.300812)
			(xy 51.582681 -355.248895) (xy 51.610566 -355.200595) (xy 51.645337 -355.15699) (xy 51.686219 -355.119054)
			(xy 51.732297 -355.087635) (xy 51.782544 -355.063434) (xy 51.835837 -355.046991) (xy 51.890984 -355.038675)
			(xy 51.91887 -355.038152) (xy 51.946203 -355.038606) (xy 52.000284 -355.046577) (xy 52.052619 -355.062368)
			(xy 52.102083 -355.085639) (xy 52.147616 -355.115889) (xy 52.188237 -355.15247) (xy 52.223075 -355.194596)
			(xy 52.23764 -355.21773) (xy 52.24554 -355.22997) (xy 52.267019 -355.249638) (xy 52.293179 -355.262438)
			(xy 52.321888 -355.26733) (xy 52.350811 -355.263914) (xy 52.364386 -355.258624) (xy 52.387599 -355.249143)
			(xy 52.43593 -355.235789) (xy 52.485619 -355.229058) (xy 52.51069 -355.228652) (xy 52.535759 -355.229089)
			(xy 52.585442 -355.235833) (xy 52.633776 -355.24916) (xy 52.656994 -355.258624) (xy 52.670599 -355.263789)
			(xy 52.699485 -355.267169) (xy 52.728153 -355.262276) (xy 52.754282 -355.249507) (xy 52.775757 -355.229895)
			(xy 52.78374 -355.21773) (xy 52.798309 -355.194599) (xy 52.833152 -355.152478) (xy 52.873775 -355.115899)
			(xy 52.919306 -355.085648) (xy 52.968768 -355.062372) (xy 53.021099 -355.046572) (xy 53.075178 -355.038586)
			(xy 53.129842 -355.038586) (xy 53.183921 -355.046572) (xy 53.236252 -355.062372) (xy 53.285714 -355.085648)
			(xy 53.331245 -355.115899) (xy 53.371868 -355.152478) (xy 53.406711 -355.194599) (xy 53.42128 -355.21773)
			(xy 53.429237 -355.229929) (xy 53.450701 -355.249597) (xy 53.476845 -355.262403) (xy 53.505541 -355.267305)
			(xy 53.534453 -355.263904) (xy 53.548026 -355.258624) (xy 53.571234 -355.24913) (xy 53.619568 -355.235782)
			(xy 53.669258 -355.229055) (xy 53.69433 -355.228652) (xy 53.721172 -355.22911) (xy 53.774301 -355.236818)
			(xy 53.825774 -355.25207) (xy 53.874526 -355.27455) (xy 53.919548 -355.303792) (xy 53.959907 -355.339193)
			(xy 53.994769 -355.380018) (xy 54.023412 -355.425424) (xy 54.045244 -355.47447) (xy 54.052978 -355.500178)
			(xy 54.057673 -355.514662) (xy 54.074188 -355.540221) (xy 54.097497 -355.559782) (xy 54.125532 -355.571613)
			(xy 54.155809 -355.574663) (xy 54.185641 -355.568663) (xy 54.199282 -355.5619) (xy 54.227424 -355.547258)
			(xy 54.287377 -355.526534) (xy 54.349937 -355.516039) (xy 54.381654 -355.515418) (xy 54.409825 -355.515918)
			(xy 54.465554 -355.524209) (xy 54.492652 -355.531928) (xy 54.506084 -355.535519) (xy 54.533869 -355.53613)
			(xy 54.56079 -355.529225) (xy 54.584851 -355.515317) (xy 54.60427 -355.495435) (xy 54.617608 -355.471053)
			(xy 54.623877 -355.443977) (xy 54.623716 -355.430074) (xy 54.623208 -355.413056) (xy 54.623208 -355.412802)
			(xy 54.623654 -355.385561) (xy 54.631447 -355.331638) (xy 54.64683 -355.279371) (xy 54.669492 -355.229825)
			(xy 54.698971 -355.184006) (xy 54.734668 -355.142846) (xy 54.775858 -355.107183) (xy 54.821701 -355.077741)
			(xy 54.871266 -355.05512) (xy 54.923545 -355.03978) (xy 54.977474 -355.032032) (xy 55.004716 -355.031548)
			(xy 55.031966 -355.032063) (xy 55.08591 -355.03982) (xy 55.138202 -355.055175) (xy 55.187776 -355.077815)
			(xy 55.233624 -355.107279) (xy 55.274813 -355.142967) (xy 55.310504 -355.184153) (xy 55.339972 -355.229999)
			(xy 55.362615 -355.279572) (xy 55.377974 -355.331863) (xy 55.385735 -355.385806) (xy 55.386224 -355.413056)
			(xy 55.38572 -355.440629) (xy 55.377774 -355.4952) (xy 55.362056 -355.548059) (xy 55.338893 -355.598105)
			(xy 55.308768 -355.644295) (xy 55.272308 -355.685669) (xy 55.251604 -355.703886) (xy 55.240751 -355.713829)
			(xy 55.224677 -355.738467) (xy 55.216288 -355.766663) (xy 55.216279 -355.79608) (xy 55.224653 -355.824281)
			(xy 55.240713 -355.848928) (xy 55.251604 -355.858826) (xy 55.272265 -355.87709) (xy 55.308728 -355.918455)
			(xy 55.338855 -355.964639) (xy 55.362019 -356.01468) (xy 55.377736 -356.067534) (xy 55.38568 -356.122101)
			(xy 55.385684 -356.177242) (xy 55.377749 -356.23181) (xy 55.362039 -356.284667) (xy 55.338883 -356.334711)
			(xy 55.308763 -356.3809) (xy 55.272306 -356.42227) (xy 55.251604 -356.440486) (xy 55.240751 -356.450429)
			(xy 55.224677 -356.475067) (xy 55.216288 -356.503263) (xy 55.216279 -356.53268) (xy 55.224653 -356.560881)
			(xy 55.240713 -356.585528) (xy 55.251604 -356.595426) (xy 55.272332 -356.613619) (xy 55.308801 -356.654992)
			(xy 55.338931 -356.701185) (xy 55.362093 -356.751237) (xy 55.377806 -356.804103) (xy 55.385741 -356.85868)
			(xy 55.386224 -356.886256) (xy 55.385704 -356.913507) (xy 55.377953 -356.967455) (xy 55.362604 -357.019751)
			(xy 55.339967 -357.06933) (xy 55.310505 -357.115182) (xy 55.274818 -357.156375) (xy 55.23363 -357.192069)
			(xy 55.187783 -357.221539) (xy 55.138207 -357.244183) (xy 55.085914 -357.25954) (xy 55.031967 -357.2673)
			(xy 55.004716 -357.267764) (xy 54.978798 -357.267319) (xy 54.927439 -357.26031) (xy 54.877503 -357.246404)
			(xy 54.829912 -357.22586) (xy 54.785546 -357.199055) (xy 54.745221 -357.166484) (xy 54.709682 -357.128749)
			(xy 54.679585 -357.086546) (xy 54.66715 -357.063802) (xy 54.659833 -357.051012) (xy 54.639245 -357.029952)
			(xy 54.613507 -357.015635) (xy 54.584755 -357.009251) (xy 54.555377 -357.011328) (xy 54.54142 -357.01605)
			(xy 54.509071 -357.027446) (xy 54.441598 -357.039713) (xy 54.407308 -357.040434) (xy 54.407054 -357.040434)
			(xy 54.392905 -357.040345) (xy 54.364682 -357.038308) (xy 54.350666 -357.03637) (xy 54.337314 -357.034836)
			(xy 54.31063 -357.037929) (xy 54.285681 -357.04789) (xy 54.264204 -357.064025) (xy 54.24769 -357.085213)
			(xy 54.237288 -357.10998) (xy 54.235096 -357.123238) (xy 54.231023 -357.150394) (xy 54.21605 -357.203226)
			(xy 54.193657 -357.253366) (xy 54.164308 -357.299777) (xy 54.12861 -357.341502) (xy 54.087298 -357.377679)
			(xy 54.041227 -357.407559) (xy 53.991348 -357.430527) (xy 53.938692 -357.446107) (xy 53.884346 -357.453977)
			(xy 53.85689 -357.454454) (xy 53.829641 -357.453932) (xy 53.775697 -357.446175) (xy 53.723405 -357.430821)
			(xy 53.673831 -357.408182) (xy 53.627983 -357.378719) (xy 53.586794 -357.343031) (xy 53.551103 -357.301846)
			(xy 53.521635 -357.256001) (xy 53.498992 -357.206428) (xy 53.483633 -357.154139) (xy 53.475871 -357.100195)
			(xy 53.475382 -357.072946) (xy 53.475886 -357.045373) (xy 53.483831 -356.990802) (xy 53.499549 -356.937943)
			(xy 53.522712 -356.887897) (xy 53.552838 -356.841707) (xy 53.589298 -356.800333) (xy 53.610002 -356.782116)
			(xy 53.620852 -356.77217) (xy 53.636926 -356.747533) (xy 53.645315 -356.719338) (xy 53.645323 -356.689921)
			(xy 53.636951 -356.661721) (xy 53.620892 -356.637075) (xy 53.610002 -356.627176) (xy 53.589276 -356.608981)
			(xy 53.552807 -356.567609) (xy 53.522677 -356.521415) (xy 53.499513 -356.471364) (xy 53.4838 -356.418499)
			(xy 53.475865 -356.363922) (xy 53.475382 -356.336346) (xy 53.475827 -356.309845) (xy 53.483175 -356.257353)
			(xy 53.497722 -356.206386) (xy 53.519187 -356.157924) (xy 53.547156 -356.112901) (xy 53.563774 -356.092252)
			(xy 53.573204 -356.080099) (xy 53.584989 -356.051701) (xy 53.587811 -356.021084) (xy 53.581417 -355.991011)
			(xy 53.566382 -355.964191) (xy 53.544063 -355.943044) (xy 53.5305 -355.935788) (xy 53.506801 -355.923703)
			(xy 53.462822 -355.893775) (xy 53.423543 -355.857899) (xy 53.389762 -355.816804) (xy 53.37556 -355.79431)
			(xy 53.36765 -355.782076) (xy 53.346176 -355.762403) (xy 53.320019 -355.749599) (xy 53.29131 -355.744707)
			(xy 53.262388 -355.748125) (xy 53.248814 -355.753416) (xy 53.2256 -355.762894) (xy 53.177269 -355.776249)
			(xy 53.127581 -355.782982) (xy 53.10251 -355.783388) (xy 53.077441 -355.782948) (xy 53.027759 -355.776205)
			(xy 52.979424 -355.762879) (xy 52.956206 -355.753416) (xy 52.942619 -355.748185) (xy 52.913715 -355.744801)
			(xy 52.885029 -355.749698) (xy 52.858885 -355.762479) (xy 52.837401 -355.782108) (xy 52.82946 -355.79431)
			(xy 52.814891 -355.817441) (xy 52.780048 -355.859562) (xy 52.739425 -355.896141) (xy 52.693894 -355.926392)
			(xy 52.644432 -355.949668) (xy 52.592101 -355.965468) (xy 52.538022 -355.973454) (xy 52.483358 -355.973454)
			(xy 52.429279 -355.965468) (xy 52.376948 -355.949668) (xy 52.327486 -355.926392) (xy 52.281955 -355.896141)
			(xy 52.241332 -355.859562) (xy 52.206489 -355.817441) (xy 52.19192 -355.79431) (xy 52.183953 -355.782117)
			(xy 52.162494 -355.762445) (xy 52.136353 -355.749635) (xy 52.107657 -355.744732) (xy 52.078746 -355.748134)
			(xy 52.065174 -355.753416) (xy 52.041965 -355.762907) (xy 51.993631 -355.776257) (xy 51.943942 -355.782985)
			(xy 51.91887 -355.783388) (xy 51.890984 -355.782925) (xy 51.835837 -355.774609) (xy 51.782544 -355.758166)
			(xy 51.732297 -355.733965) (xy 51.686219 -355.702546) (xy 51.645337 -355.66461) (xy 51.610566 -355.621005)
			(xy 51.582681 -355.572705) (xy 51.562307 -355.520788) (xy 51.549897 -355.466415) (xy 51.545729 -355.4108)
			(xy 48.876174 -355.4108) (xy 48.339248 -355.947726) (xy 48.408082 -356.098602) (xy 48.443388 -356.096062)
			(xy 48.470058 -356.095046) (xy 48.497312 -356.095529) (xy 48.551267 -356.10328) (xy 48.60357 -356.118631)
			(xy 48.653155 -356.141269) (xy 48.699014 -356.170734) (xy 48.740213 -356.206425) (xy 48.775913 -356.247615)
			(xy 48.805388 -356.293468) (xy 48.828038 -356.343048) (xy 48.843401 -356.395347) (xy 48.851165 -356.4493)
			(xy 48.851566 -356.476554) (xy 48.851312 -356.482904) (xy 48.851312 -356.483412) (xy 48.85055 -356.51694)
			(xy 48.965104 -356.59695) (xy 48.991774 -356.586536) (xy 49.000664 -356.58298) (xy 49.033676 -356.570604)
			(xy 49.101488 -356.551295) (xy 49.170794 -356.538332) (xy 49.241 -356.531825) (xy 49.276254 -356.531418)
			(xy 49.31619 -356.53192) (xy 49.395625 -356.540265) (xy 49.473752 -356.556868) (xy 49.549716 -356.581546)
			(xy 49.622683 -356.61403) (xy 49.691856 -356.653964) (xy 49.756474 -356.70091) (xy 49.815832 -356.754354)
			(xy 49.869277 -356.81371) (xy 49.916225 -356.878328) (xy 49.95616 -356.947499) (xy 49.988647 -357.020466)
			(xy 50.013327 -357.096429) (xy 50.029932 -357.174555) (xy 50.038279 -357.25399) (xy 50.038762 -357.293926)
			(xy 50.038762 -357.294688) (xy 50.038242 -357.334696) (xy 50.029835 -357.414269) (xy 50.013133 -357.492522)
			(xy 49.988321 -357.568593) (xy 49.972468 -357.60533) (xy 49.970436 -357.609902) (xy 49.95799 -357.664258)
			(xy 50.042064 -357.683562) (xy 50.062384 -357.672894) (xy 50.065686 -357.670608) (xy 50.090345 -357.65315)
			(xy 50.14402 -357.625416) (xy 50.201393 -357.60648) (xy 50.261031 -357.596816) (xy 50.291238 -357.596186)
			(xy 50.292762 -357.596186) (xy 50.321875 -357.596778) (xy 50.379414 -357.605708) (xy 50.434928 -357.623276)
			(xy 50.487129 -357.649074) (xy 50.534805 -357.682502) (xy 50.57685 -357.722785) (xy 50.595022 -357.745538)
			(xy 50.608738 -357.763318) (xy 50.71618 -357.772716) (xy 50.737008 -357.76535) (xy 50.744882 -357.758238)
			(xy 50.74793 -357.755444) (xy 50.756058 -357.748332) (xy 50.773584 -357.709724) (xy 50.769774 -357.673148)
			(xy 50.743612 -357.634032) (xy 50.733452 -357.62819) (xy 50.70908 -357.613432) (xy 50.664607 -357.577821)
			(xy 50.625923 -357.535993) (xy 50.593889 -357.488878) (xy 50.569217 -357.437523) (xy 50.552455 -357.38307)
			(xy 50.543977 -357.326731) (xy 50.54346 -357.298244) (xy 50.543946 -357.270993) (xy 50.551702 -357.217045)
			(xy 50.567057 -357.16475) (xy 50.589699 -357.115173) (xy 50.619165 -357.069323) (xy 50.654856 -357.028132)
			(xy 50.696047 -356.992441) (xy 50.741897 -356.962975) (xy 50.791474 -356.940333) (xy 50.843769 -356.924978)
			(xy 50.897717 -356.917222) (xy 50.952219 -356.917222) (xy 51.006167 -356.924978) (xy 51.058462 -356.940333)
			(xy 51.108039 -356.962975) (xy 51.153889 -356.992441) (xy 51.19508 -357.028132) (xy 51.230771 -357.069323)
			(xy 51.260237 -357.115173) (xy 51.282879 -357.16475) (xy 51.298234 -357.217045) (xy 51.30599 -357.270993)
			(xy 51.306476 -357.298244) (xy 51.305917 -357.327901) (xy 51.296743 -357.386501) (xy 51.278607 -357.442974)
			(xy 51.251947 -357.495958) (xy 51.217405 -357.544176) (xy 51.197002 -357.565706) (xy 51.180238 -357.582724)
			(xy 51.193192 -357.708454) (xy 51.213512 -357.721916) (xy 51.233522 -357.735694) (xy 51.270205 -357.767546)
			(xy 51.286664 -357.785416) (xy 52.903374 -357.785416) (xy 52.927438 -357.786621) (xy 52.974495 -357.796949)
			(xy 53.018765 -357.81595) (xy 53.058667 -357.842947) (xy 53.076094 -357.859584) (xy 55.955184 -360.738674)
			(xy 55.972405 -360.756784) (xy 56.000142 -360.798345) (xy 56.019246 -360.844515) (xy 56.028985 -360.893523)
			(xy 56.029606 -360.918506) (xy 56.029352 -361.935268) (xy 56.029352 -363.229398) (xy 56.475122 -363.675168)
			(xy 56.486107 -363.685349) (xy 56.512539 -363.699405) (xy 56.541909 -363.705201) (xy 56.571699 -363.702239)
			(xy 56.599353 -363.690774) (xy 56.6225 -363.671788) (xy 56.639153 -363.646911) (xy 56.644032 -363.63275)
			(xy 56.652236 -363.607323) (xy 56.675194 -363.55908) (xy 56.705102 -363.514808) (xy 56.741289 -363.475502)
			(xy 56.782943 -363.442043) (xy 56.829128 -363.415184) (xy 56.878807 -363.395526) (xy 56.930866 -363.383512)
			(xy 56.957468 -363.381036) (xy 57.000648 -363.377734) (xy 57.11698 -361.959398) (xy 57.208166 -360.848148)
			(xy 57.101994 -350.661732) (xy 56.984646 -339.380322) (xy 56.984646 -339.379052) (xy 56.893206 -336.909156)
			(xy 56.77662 -333.76108) (xy 56.776112 -333.724504) (xy 56.776112 -333.713582) (xy 56.805322 -331.06487)
			(xy 55.8038 -330.063348) (xy 35.179 -330.063348) (xy 34.7726 -330.469748) (xy 34.7726 -335.51361)
			(xy 39.617392 -335.51361) (xy 39.617392 -335.428914) (xy 39.625443 -335.3446) (xy 39.641472 -335.261434)
			(xy 39.665333 -335.180167) (xy 39.696812 -335.101537) (xy 39.735623 -335.026256) (xy 39.781413 -334.955004)
			(xy 39.833769 -334.888428) (xy 39.892217 -334.82713) (xy 39.956227 -334.771665) (xy 40.025219 -334.722536)
			(xy 40.098569 -334.680187) (xy 40.175612 -334.645003) (xy 40.255651 -334.617301) (xy 40.33796 -334.597333)
			(xy 40.421795 -334.58528) (xy 40.506396 -334.58125) (xy 40.590997 -334.58528) (xy 40.674832 -334.597333)
			(xy 40.757141 -334.617301) (xy 40.83718 -334.645003) (xy 40.914223 -334.680187) (xy 40.987573 -334.722536)
			(xy 41.056565 -334.771665) (xy 41.120575 -334.82713) (xy 41.179023 -334.888428) (xy 41.231379 -334.955004)
			(xy 41.277169 -335.026256) (xy 41.31598 -335.101537) (xy 41.347459 -335.180167) (xy 41.37132 -335.261434)
			(xy 41.387349 -335.3446) (xy 41.3954 -335.428914) (xy 41.395904 -335.471262) (xy 41.3954 -335.51361)
			(xy 41.394794 -335.51996) (xy 45.808134 -335.51996) (xy 45.808134 -335.435264) (xy 45.816185 -335.35095)
			(xy 45.832214 -335.267784) (xy 45.856075 -335.186517) (xy 45.887554 -335.107887) (xy 45.926365 -335.032606)
			(xy 45.972155 -334.961354) (xy 46.024511 -334.894778) (xy 46.082959 -334.83348) (xy 46.146969 -334.778015)
			(xy 46.215961 -334.728886) (xy 46.289311 -334.686537) (xy 46.366354 -334.651353) (xy 46.446393 -334.623651)
			(xy 46.528702 -334.603683) (xy 46.612537 -334.59163) (xy 46.697138 -334.5876) (xy 46.781739 -334.59163)
			(xy 46.865574 -334.603683) (xy 46.947883 -334.623651) (xy 47.027922 -334.651353) (xy 47.104965 -334.686537)
			(xy 47.178315 -334.728886) (xy 47.247307 -334.778015) (xy 47.311317 -334.83348) (xy 47.369765 -334.894778)
			(xy 47.422121 -334.961354) (xy 47.467911 -335.032606) (xy 47.506722 -335.107887) (xy 47.538201 -335.186517)
			(xy 47.562062 -335.267784) (xy 47.578091 -335.35095) (xy 47.586142 -335.435264) (xy 47.586646 -335.477612)
			(xy 47.586142 -335.51996) (xy 52.005734 -335.51996) (xy 52.005734 -335.435264) (xy 52.013785 -335.35095)
			(xy 52.029814 -335.267784) (xy 52.053675 -335.186517) (xy 52.085154 -335.107887) (xy 52.123965 -335.032606)
			(xy 52.169755 -334.961354) (xy 52.222111 -334.894778) (xy 52.280559 -334.83348) (xy 52.344569 -334.778015)
			(xy 52.413561 -334.728886) (xy 52.486911 -334.686537) (xy 52.563954 -334.651353) (xy 52.643993 -334.623651)
			(xy 52.726302 -334.603683) (xy 52.810137 -334.59163) (xy 52.894738 -334.5876) (xy 52.979339 -334.59163)
			(xy 53.063174 -334.603683) (xy 53.145483 -334.623651) (xy 53.225522 -334.651353) (xy 53.302565 -334.686537)
			(xy 53.375915 -334.728886) (xy 53.444907 -334.778015) (xy 53.508917 -334.83348) (xy 53.567365 -334.894778)
			(xy 53.619721 -334.961354) (xy 53.665511 -335.032606) (xy 53.704322 -335.107887) (xy 53.735801 -335.186517)
			(xy 53.759662 -335.267784) (xy 53.775691 -335.35095) (xy 53.783742 -335.435264) (xy 53.784246 -335.477612)
			(xy 53.783742 -335.51996) (xy 53.775691 -335.604274) (xy 53.759662 -335.68744) (xy 53.735801 -335.768707)
			(xy 53.704322 -335.847337) (xy 53.665511 -335.922618) (xy 53.619721 -335.99387) (xy 53.567365 -336.060446)
			(xy 53.508917 -336.121744) (xy 53.444907 -336.177209) (xy 53.375915 -336.226338) (xy 53.302565 -336.268687)
			(xy 53.225522 -336.303871) (xy 53.145483 -336.331573) (xy 53.063174 -336.351541) (xy 52.979339 -336.363594)
			(xy 52.894738 -336.367625) (xy 52.810137 -336.363594) (xy 52.726302 -336.351541) (xy 52.643993 -336.331573)
			(xy 52.563954 -336.303871) (xy 52.486911 -336.268687) (xy 52.413561 -336.226338) (xy 52.344569 -336.177209)
			(xy 52.280559 -336.121744) (xy 52.222111 -336.060446) (xy 52.169755 -335.99387) (xy 52.123965 -335.922618)
			(xy 52.085154 -335.847337) (xy 52.053675 -335.768707) (xy 52.029814 -335.68744) (xy 52.013785 -335.604274)
			(xy 52.005734 -335.51996) (xy 47.586142 -335.51996) (xy 47.578091 -335.604274) (xy 47.562062 -335.68744)
			(xy 47.538201 -335.768707) (xy 47.506722 -335.847337) (xy 47.467911 -335.922618) (xy 47.422121 -335.99387)
			(xy 47.369765 -336.060446) (xy 47.311317 -336.121744) (xy 47.247307 -336.177209) (xy 47.178315 -336.226338)
			(xy 47.104965 -336.268687) (xy 47.027922 -336.303871) (xy 46.947883 -336.331573) (xy 46.865574 -336.351541)
			(xy 46.781739 -336.363594) (xy 46.697138 -336.367625) (xy 46.612537 -336.363594) (xy 46.528702 -336.351541)
			(xy 46.446393 -336.331573) (xy 46.366354 -336.303871) (xy 46.289311 -336.268687) (xy 46.215961 -336.226338)
			(xy 46.146969 -336.177209) (xy 46.082959 -336.121744) (xy 46.024511 -336.060446) (xy 45.972155 -335.99387)
			(xy 45.926365 -335.922618) (xy 45.887554 -335.847337) (xy 45.856075 -335.768707) (xy 45.832214 -335.68744)
			(xy 45.816185 -335.604274) (xy 45.808134 -335.51996) (xy 41.394794 -335.51996) (xy 41.387349 -335.597924)
			(xy 41.37132 -335.68109) (xy 41.347459 -335.762357) (xy 41.31598 -335.840987) (xy 41.277169 -335.916268)
			(xy 41.231379 -335.98752) (xy 41.179023 -336.054096) (xy 41.120575 -336.115394) (xy 41.056565 -336.170859)
			(xy 40.987573 -336.219988) (xy 40.914223 -336.262337) (xy 40.83718 -336.297521) (xy 40.757141 -336.325223)
			(xy 40.674832 -336.345191) (xy 40.590997 -336.357244) (xy 40.506396 -336.361275) (xy 40.421795 -336.357244)
			(xy 40.33796 -336.345191) (xy 40.255651 -336.325223) (xy 40.175612 -336.297521) (xy 40.098569 -336.262337)
			(xy 40.025219 -336.219988) (xy 39.956227 -336.170859) (xy 39.892217 -336.115394) (xy 39.833769 -336.054096)
			(xy 39.781413 -335.98752) (xy 39.735623 -335.916268) (xy 39.696812 -335.840987) (xy 39.665333 -335.762357)
			(xy 39.641472 -335.68109) (xy 39.625443 -335.597924) (xy 39.617392 -335.51361) (xy 34.7726 -335.51361)
			(xy 34.7726 -337.471258) (xy 39.590985 -337.471258) (xy 39.595007 -337.385538) (xy 39.607038 -337.30057)
			(xy 39.626974 -337.217103) (xy 39.654637 -337.135869) (xy 39.689786 -337.057583) (xy 39.732112 -336.982932)
			(xy 39.781241 -336.912573) (xy 39.836744 -336.847123) (xy 39.898131 -336.787159) (xy 39.964864 -336.733206)
			(xy 40.036356 -336.685739) (xy 40.111978 -336.645175) (xy 40.191067 -336.611871) (xy 40.272927 -336.586119)
			(xy 40.356838 -336.568146) (xy 40.442064 -336.55811) (xy 40.527856 -336.556098) (xy 40.613458 -336.562129)
			(xy 40.69812 -336.576149) (xy 40.781097 -336.598035) (xy 40.86166 -336.627596) (xy 40.9391 -336.66457)
			(xy 41.012739 -336.708634) (xy 41.081927 -336.7594) (xy 41.146058 -336.816421) (xy 41.204567 -336.879197)
			(xy 41.25694 -336.947177) (xy 41.302718 -337.019762) (xy 41.341498 -337.096314) (xy 41.372939 -337.176162)
			(xy 41.396765 -337.258603) (xy 41.412766 -337.342913) (xy 41.420801 -337.428351) (xy 41.421304 -337.471258)
			(xy 41.42123 -337.477608) (xy 45.781727 -337.477608) (xy 45.785749 -337.391888) (xy 45.79778 -337.30692)
			(xy 45.817716 -337.223453) (xy 45.845379 -337.142219) (xy 45.880528 -337.063933) (xy 45.922854 -336.989282)
			(xy 45.971983 -336.918923) (xy 46.027486 -336.853473) (xy 46.088873 -336.793509) (xy 46.155606 -336.739556)
			(xy 46.227098 -336.692089) (xy 46.30272 -336.651525) (xy 46.381809 -336.618221) (xy 46.463669 -336.592469)
			(xy 46.54758 -336.574496) (xy 46.632806 -336.56446) (xy 46.718598 -336.562448) (xy 46.8042 -336.568479)
			(xy 46.888862 -336.582499) (xy 46.971839 -336.604385) (xy 47.052402 -336.633946) (xy 47.129842 -336.67092)
			(xy 47.203481 -336.714984) (xy 47.272669 -336.76575) (xy 47.3368 -336.822771) (xy 47.395309 -336.885547)
			(xy 47.447682 -336.953527) (xy 47.49346 -337.026112) (xy 47.53224 -337.102664) (xy 47.563681 -337.182512)
			(xy 47.587507 -337.264953) (xy 47.603508 -337.349263) (xy 47.611543 -337.434701) (xy 47.612046 -337.477608)
			(xy 51.97983 -337.477608) (xy 51.980318 -337.435332) (xy 51.98812 -337.35114) (xy 52.003656 -337.268027)
			(xy 52.026795 -337.186703) (xy 52.057339 -337.10786) (xy 52.095027 -337.032172) (xy 52.139538 -336.960284)
			(xy 52.190492 -336.89281) (xy 52.247455 -336.830325) (xy 52.30994 -336.773362) (xy 52.377414 -336.722408)
			(xy 52.449302 -336.677897) (xy 52.52499 -336.640209) (xy 52.603833 -336.609665) (xy 52.685157 -336.586526)
			(xy 52.76827 -336.57099) (xy 52.852462 -336.563188) (xy 52.937014 -336.563188) (xy 53.021206 -336.57099)
			(xy 53.104319 -336.586526) (xy 53.185643 -336.609665) (xy 53.264486 -336.640209) (xy 53.340174 -336.677897)
			(xy 53.412062 -336.722408) (xy 53.479536 -336.773362) (xy 53.542021 -336.830325) (xy 53.598984 -336.89281)
			(xy 53.649938 -336.960284) (xy 53.694449 -337.032172) (xy 53.732137 -337.10786) (xy 53.762681 -337.186703)
			(xy 53.78582 -337.268027) (xy 53.801356 -337.35114) (xy 53.809158 -337.435332) (xy 53.809646 -337.477608)
			(xy 53.809142 -337.519569) (xy 53.801456 -337.603139) (xy 53.786148 -337.685654) (xy 53.763347 -337.766421)
			(xy 53.733246 -337.844759) (xy 53.696097 -337.920012) (xy 53.652212 -337.991547) (xy 53.60196 -338.058761)
			(xy 53.545764 -338.121091) (xy 53.484096 -338.178013) (xy 53.417474 -338.229047) (xy 53.346458 -338.273766)
			(xy 53.309266 -338.293202) (xy 53.296167 -338.300524) (xy 53.274558 -338.321321) (xy 53.259912 -338.347494)
			(xy 53.25349 -338.37679) (xy 53.255844 -338.406689) (xy 53.266772 -338.434619) (xy 53.285333 -338.458177)
			(xy 53.297328 -338.467192) (xy 53.308811 -338.475301) (xy 53.330676 -338.492974) (xy 53.341016 -338.502498)
			(xy 53.35255 -338.51257) (xy 53.380096 -338.525912) (xy 53.410358 -338.530497) (xy 53.44062 -338.525912)
			(xy 53.468166 -338.51257) (xy 53.4797 -338.502498) (xy 53.501027 -338.483228) (xy 53.54839 -338.450663)
			(xy 53.600101 -338.425572) (xy 53.654992 -338.408522) (xy 53.711819 -338.3999) (xy 53.769297 -338.3999)
			(xy 53.826124 -338.408522) (xy 53.881015 -338.425572) (xy 53.932726 -338.450663) (xy 53.980089 -338.483228)
			(xy 54.001416 -338.502498) (xy 54.01295 -338.51257) (xy 54.040496 -338.525912) (xy 54.070758 -338.530497)
			(xy 54.10102 -338.525912) (xy 54.128566 -338.51257) (xy 54.1401 -338.502498) (xy 54.161412 -338.48321)
			(xy 54.208777 -338.450644) (xy 54.260493 -338.425554) (xy 54.315387 -338.408508) (xy 54.372218 -338.399891)
			(xy 54.400958 -338.399374) (xy 54.428209 -338.399894) (xy 54.482157 -338.407645) (xy 54.534453 -338.422995)
			(xy 54.584031 -338.445631) (xy 54.629884 -338.475093) (xy 54.671077 -338.510781) (xy 54.706771 -338.551968)
			(xy 54.73624 -338.597816) (xy 54.758884 -338.647391) (xy 54.774242 -338.699684) (xy 54.782001 -338.753631)
			(xy 54.782466 -338.780882) (xy 54.781914 -338.80962) (xy 54.773295 -338.866445) (xy 54.756251 -338.921335)
			(xy 54.731166 -338.973047) (xy 54.698609 -339.020411) (xy 54.679342 -339.04174) (xy 54.669287 -339.053288)
			(xy 54.655941 -339.080829) (xy 54.651353 -339.111087) (xy 54.655934 -339.141346) (xy 54.669272 -339.16889)
			(xy 54.679342 -339.180424) (xy 54.698601 -339.201761) (xy 54.73117 -339.24912) (xy 54.756265 -339.300829)
			(xy 54.773318 -339.355718) (xy 54.781944 -339.412544) (xy 54.782466 -339.441282) (xy 54.782015 -339.468272)
			(xy 54.774408 -339.521712) (xy 54.759344 -339.573547) (xy 54.737124 -339.622741) (xy 54.70819 -339.668311)
			(xy 54.673122 -339.709347) (xy 54.65318 -339.72754) (xy 54.642465 -339.737466) (xy 54.626852 -339.762143)
			(xy 54.618868 -339.790231) (xy 54.619166 -339.819431) (xy 54.627722 -339.84735) (xy 54.643835 -339.871703)
			(xy 54.654704 -339.881464) (xy 54.675503 -339.899686) (xy 54.712176 -339.941068) (xy 54.742483 -339.987316)
			(xy 54.765788 -340.037458) (xy 54.781602 -340.090442) (xy 54.789593 -340.145155) (xy 54.790086 -340.172802)
			(xy 54.789559 -340.202244) (xy 54.780511 -340.26043) (xy 54.76263 -340.316534) (xy 54.736341 -340.369224)
			(xy 54.702268 -340.417249) (xy 54.682136 -340.43874) (xy 54.671747 -340.450216) (xy 54.657858 -340.477865)
			(xy 54.652857 -340.508401) (xy 54.657201 -340.539036) (xy 54.670494 -340.566978) (xy 54.680612 -340.578694)
			(xy 54.699625 -340.600011) (xy 54.731799 -340.647204) (xy 54.75658 -340.698665) (xy 54.773417 -340.753245)
			(xy 54.781931 -340.809723) (xy 54.782466 -340.838282) (xy 54.781998 -340.865652) (xy 54.774182 -340.919832)
			(xy 54.758694 -340.972335) (xy 54.735852 -341.022082) (xy 54.706127 -341.068049) (xy 54.688486 -341.08898)
			(xy 54.679268 -341.100321) (xy 54.66709 -341.126874) (xy 54.662914 -341.155786) (xy 54.667082 -341.1847)
			(xy 54.679253 -341.211256) (xy 54.688486 -341.222584) (xy 54.706109 -341.243531) (xy 54.735833 -341.289497)
			(xy 54.758679 -341.339241) (xy 54.774176 -341.391741) (xy 54.782006 -341.445917) (xy 54.782008 -341.500656)
			(xy 54.774182 -341.554833) (xy 54.758688 -341.607334) (xy 54.735846 -341.657079) (xy 54.706125 -341.703047)
			(xy 54.688486 -341.72398) (xy 54.679268 -341.735321) (xy 54.66709 -341.761874) (xy 54.662914 -341.790786)
			(xy 54.667082 -341.8197) (xy 54.679253 -341.846256) (xy 54.688486 -341.857584) (xy 54.706109 -341.878531)
			(xy 54.735833 -341.924497) (xy 54.758679 -341.974241) (xy 54.774176 -342.026741) (xy 54.782006 -342.080917)
			(xy 54.782008 -342.135656) (xy 54.774182 -342.189833) (xy 54.758688 -342.242334) (xy 54.735846 -342.292079)
			(xy 54.706125 -342.338047) (xy 54.688486 -342.35898) (xy 54.679268 -342.370321) (xy 54.66709 -342.396874)
			(xy 54.662914 -342.425786) (xy 54.667082 -342.4547) (xy 54.679253 -342.481256) (xy 54.688486 -342.492584)
			(xy 54.706129 -342.513513) (xy 54.735841 -342.559486) (xy 54.758676 -342.609235) (xy 54.774166 -342.661736)
			(xy 54.781993 -342.715913) (xy 54.782466 -342.743282) (xy 54.782028 -342.770536) (xy 54.774272 -342.82449)
			(xy 54.758916 -342.876791) (xy 54.736273 -342.926374) (xy 54.706803 -342.972229) (xy 54.671106 -343.013423)
			(xy 54.62991 -343.049117) (xy 54.584053 -343.078584) (xy 54.534469 -343.101225) (xy 54.482167 -343.116577)
			(xy 54.428212 -343.12433) (xy 54.400958 -343.12479) (xy 54.372218 -343.124294) (xy 54.315389 -343.115665)
			(xy 54.260498 -343.098609) (xy 54.208787 -343.073511) (xy 54.161426 -343.04094) (xy 54.1401 -343.021666)
			(xy 54.128566 -343.011594) (xy 54.10102 -342.998252) (xy 54.070758 -342.993667) (xy 54.040496 -342.998252)
			(xy 54.01295 -343.011594) (xy 54.001416 -343.021666) (xy 53.980089 -343.040936) (xy 53.932726 -343.073501)
			(xy 53.881015 -343.098592) (xy 53.826124 -343.115642) (xy 53.769297 -343.124264) (xy 53.711819 -343.124264)
			(xy 53.654992 -343.115642) (xy 53.600101 -343.098592) (xy 53.54839 -343.073501) (xy 53.501027 -343.040936)
			(xy 53.4797 -343.021666) (xy 53.468166 -343.011594) (xy 53.44062 -342.998252) (xy 53.410358 -342.993667)
			(xy 53.380096 -342.998252) (xy 53.35255 -343.011594) (xy 53.341016 -343.021666) (xy 53.319707 -343.040957)
			(xy 53.27234 -343.073521) (xy 53.220624 -343.098609) (xy 53.165729 -343.115655) (xy 53.108898 -343.124272)
			(xy 53.080158 -343.12479) (xy 53.052905 -343.124361) (xy 52.998954 -343.116599) (xy 52.946657 -343.101237)
			(xy 52.897079 -343.07859) (xy 52.851228 -343.049117) (xy 52.810037 -343.01342) (xy 52.774347 -342.972224)
			(xy 52.744881 -342.926369) (xy 52.722242 -342.876786) (xy 52.706889 -342.824487) (xy 52.699135 -342.770535)
			(xy 52.69865 -342.743282) (xy 52.699093 -342.715911) (xy 52.706915 -342.66173) (xy 52.722408 -342.609226)
			(xy 52.745256 -342.55948) (xy 52.774986 -342.513514) (xy 52.79263 -342.492584) (xy 52.801882 -342.481269)
			(xy 52.814053 -342.454706) (xy 52.818221 -342.425786) (xy 52.814046 -342.396868) (xy 52.801867 -342.370308)
			(xy 52.79263 -342.35898) (xy 52.774972 -342.338062) (xy 52.745247 -342.292091) (xy 52.722403 -342.242343)
			(xy 52.706908 -342.189839) (xy 52.699081 -342.135658) (xy 52.699083 -342.080915) (xy 52.706914 -342.026735)
			(xy 52.722412 -341.974232) (xy 52.74526 -341.924485) (xy 52.774988 -341.878517) (xy 52.79263 -341.857584)
			(xy 52.801882 -341.846269) (xy 52.814053 -341.819706) (xy 52.818221 -341.790786) (xy 52.814046 -341.761868)
			(xy 52.801867 -341.735308) (xy 52.79263 -341.72398) (xy 52.774972 -341.703062) (xy 52.745247 -341.657091)
			(xy 52.722403 -341.607343) (xy 52.706908 -341.554839) (xy 52.699081 -341.500658) (xy 52.699083 -341.445915)
			(xy 52.706914 -341.391735) (xy 52.722412 -341.339232) (xy 52.74526 -341.289485) (xy 52.774988 -341.243517)
			(xy 52.79263 -341.222584) (xy 52.801882 -341.211269) (xy 52.814053 -341.184706) (xy 52.818221 -341.155786)
			(xy 52.814046 -341.126868) (xy 52.801867 -341.100308) (xy 52.79263 -341.08898) (xy 52.77502 -341.068025)
			(xy 52.745302 -341.022059) (xy 52.72246 -340.972317) (xy 52.706963 -340.919822) (xy 52.699128 -340.86565)
			(xy 52.69865 -340.838282) (xy 52.69922 -340.808841) (xy 52.708256 -340.750657) (xy 52.726126 -340.694554)
			(xy 52.752406 -340.641862) (xy 52.786471 -340.593836) (xy 52.8066 -340.572344) (xy 52.817009 -340.560883)
			(xy 52.830906 -340.53323) (xy 52.835907 -340.502688) (xy 52.831556 -340.472046) (xy 52.81825 -340.444104)
			(xy 52.808124 -340.43239) (xy 52.789093 -340.411088) (xy 52.756924 -340.36389) (xy 52.732147 -340.312425)
			(xy 52.715315 -340.257843) (xy 52.706803 -340.201361) (xy 52.70627 -340.172802) (xy 52.706698 -340.145811)
			(xy 52.714308 -340.092369) (xy 52.729376 -340.040533) (xy 52.7516 -339.99134) (xy 52.780538 -339.94577)
			(xy 52.815611 -339.904735) (xy 52.835556 -339.886544) (xy 52.846182 -339.876532) (xy 52.861793 -339.851879)
			(xy 52.869785 -339.823814) (xy 52.869503 -339.794635) (xy 52.86097 -339.766729) (xy 52.844886 -339.742382)
			(xy 52.834032 -339.73262) (xy 52.813233 -339.714399) (xy 52.776559 -339.673017) (xy 52.74625 -339.62677)
			(xy 52.722945 -339.576627) (xy 52.707131 -339.523643) (xy 52.699142 -339.468929) (xy 52.69865 -339.441282)
			(xy 52.699176 -339.412543) (xy 52.7078 -339.355717) (xy 52.72485 -339.300827) (xy 52.749941 -339.249115)
			(xy 52.782504 -339.201752) (xy 52.801774 -339.180424) (xy 52.811863 -339.168904) (xy 52.825203 -339.141353)
			(xy 52.829784 -339.111087) (xy 52.825195 -339.080822) (xy 52.811848 -339.053274) (xy 52.801774 -339.04174)
			(xy 52.782501 -339.020415) (xy 52.749933 -338.973053) (xy 52.724841 -338.921341) (xy 52.707791 -338.86645)
			(xy 52.69917 -338.809621) (xy 52.69865 -338.780882) (xy 52.699093 -338.754848) (xy 52.706182 -338.703265)
			(xy 52.720212 -338.653124) (xy 52.740924 -338.605353) (xy 52.767933 -338.560838) (xy 52.783994 -338.540344)
			(xy 52.792995 -338.528305) (xy 52.804369 -338.500505) (xy 52.807153 -338.470597) (xy 52.801105 -338.441174)
			(xy 52.78675 -338.414789) (xy 52.765333 -338.393729) (xy 52.73871 -338.37982) (xy 52.72405 -338.376514)
			(xy 52.682679 -338.368223) (xy 52.601583 -338.344902) (xy 52.522979 -338.314214) (xy 52.447534 -338.276419)
			(xy 52.375889 -338.231838) (xy 52.308653 -338.180851) (xy 52.246397 -338.12389) (xy 52.189649 -338.061439)
			(xy 52.138892 -337.994029) (xy 52.094557 -337.922232) (xy 52.05702 -337.846659) (xy 52.0266 -337.76795)
			(xy 52.003557 -337.686775) (xy 51.988084 -337.603823) (xy 51.980315 -337.519799) (xy 51.97983 -337.477608)
			(xy 47.612046 -337.477608) (xy 47.611543 -337.520515) (xy 47.603508 -337.605953) (xy 47.587507 -337.690263)
			(xy 47.563681 -337.772704) (xy 47.53224 -337.852552) (xy 47.49346 -337.929104) (xy 47.447682 -338.001689)
			(xy 47.395309 -338.069669) (xy 47.3368 -338.132445) (xy 47.272669 -338.189466) (xy 47.203481 -338.240232)
			(xy 47.129842 -338.284296) (xy 47.052402 -338.32127) (xy 46.971839 -338.350831) (xy 46.888862 -338.372717)
			(xy 46.8042 -338.386737) (xy 46.718598 -338.392768) (xy 46.632806 -338.390756) (xy 46.54758 -338.38072)
			(xy 46.463669 -338.362747) (xy 46.381809 -338.336995) (xy 46.30272 -338.303691) (xy 46.227098 -338.263127)
			(xy 46.155606 -338.21566) (xy 46.088873 -338.161707) (xy 46.027486 -338.101743) (xy 45.971983 -338.036293)
			(xy 45.922854 -337.965934) (xy 45.880528 -337.891283) (xy 45.845379 -337.812997) (xy 45.817716 -337.731763)
			(xy 45.79778 -337.648296) (xy 45.785749 -337.563328) (xy 45.781727 -337.477608) (xy 41.42123 -337.477608)
			(xy 41.420801 -337.514165) (xy 41.412766 -337.599603) (xy 41.396765 -337.683913) (xy 41.372939 -337.766354)
			(xy 41.341498 -337.846202) (xy 41.302718 -337.922754) (xy 41.25694 -337.995339) (xy 41.204567 -338.063319)
			(xy 41.146058 -338.126095) (xy 41.081927 -338.183116) (xy 41.012739 -338.233882) (xy 40.9391 -338.277946)
			(xy 40.86166 -338.31492) (xy 40.781097 -338.344481) (xy 40.69812 -338.366367) (xy 40.613458 -338.380387)
			(xy 40.527856 -338.386418) (xy 40.442064 -338.384406) (xy 40.356838 -338.37437) (xy 40.272927 -338.356397)
			(xy 40.191067 -338.330645) (xy 40.111978 -338.297341) (xy 40.036356 -338.256777) (xy 39.964864 -338.20931)
			(xy 39.898131 -338.155357) (xy 39.836744 -338.095393) (xy 39.781241 -338.029943) (xy 39.732112 -337.959584)
			(xy 39.689786 -337.884933) (xy 39.654637 -337.806647) (xy 39.626974 -337.725413) (xy 39.607038 -337.641946)
			(xy 39.595007 -337.556978) (xy 39.590985 -337.471258) (xy 34.7726 -337.471258) (xy 34.7726 -354.333556)
			(xy 34.773139 -354.348542) (xy 34.781852 -354.37722) (xy 34.798512 -354.402135) (xy 34.821684 -354.421145)
			(xy 34.849376 -354.432613) (xy 34.879204 -354.435551) (xy 34.908601 -354.429709) (xy 34.935038 -354.415587)
			(xy 34.946082 -354.405438) (xy 35.146742 -354.204524) (xy 35.176304 -354.175885) (xy 35.241537 -354.125693)
			(xy 35.27679 -354.104448) (xy 35.289307 -354.09661) (xy 35.309533 -354.075109) (xy 35.322755 -354.048717)
			(xy 35.327868 -354.019644) (xy 35.324441 -353.990324) (xy 35.312763 -353.963213) (xy 35.303714 -353.95154)
			(xy 35.286956 -353.930838) (xy 35.258739 -353.885664) (xy 35.237081 -353.837004) (xy 35.222402 -353.785805)
			(xy 35.214989 -353.733061) (xy 35.21456 -353.70643) (xy 35.215046 -353.679179) (xy 35.222802 -353.625231)
			(xy 35.238157 -353.572936) (xy 35.260799 -353.523359) (xy 35.290265 -353.477509) (xy 35.325956 -353.436318)
			(xy 35.367147 -353.400627) (xy 35.412997 -353.371161) (xy 35.462574 -353.348519) (xy 35.514869 -353.333164)
			(xy 35.568817 -353.325408) (xy 35.623319 -353.325408) (xy 35.677267 -353.333164) (xy 35.729562 -353.348519)
			(xy 35.779139 -353.371161) (xy 35.824989 -353.400627) (xy 35.86618 -353.436318) (xy 35.901871 -353.477509)
			(xy 35.931337 -353.523359) (xy 35.953979 -353.572936) (xy 35.969334 -353.625231) (xy 35.97709 -353.679179)
			(xy 35.977576 -353.70643) (xy 35.977111 -353.733059) (xy 35.969698 -353.785798) (xy 35.955022 -353.836993)
			(xy 35.933368 -353.885649) (xy 35.905156 -353.93082) (xy 35.888422 -353.95154) (xy 35.879366 -353.963195)
			(xy 35.867752 -353.990316) (xy 35.864362 -354.019623) (xy 35.869478 -354.048679) (xy 35.882674 -354.075066)
			(xy 35.902853 -354.096588) (xy 35.915346 -354.104448) (xy 35.946977 -354.123426) (xy 36.006053 -354.167603)
			(xy 36.059613 -354.218326) (xy 36.106936 -354.274913) (xy 36.147384 -354.336602) (xy 36.180412 -354.402562)
			(xy 36.205577 -354.471904) (xy 36.222537 -354.543694) (xy 36.231067 -354.616966) (xy 36.231576 -354.65385)
			(xy 36.231091 -354.68951) (xy 36.223098 -354.760381) (xy 36.207218 -354.82991) (xy 36.18365 -354.897224)
			(xy 36.152692 -354.961474) (xy 36.114733 -355.021853) (xy 36.07025 -355.077601) (xy 36.045394 -355.103176)
			(xy 35.725608 -355.422708) (xy 35.725608 -356.419912) (xy 36.712652 -356.419912) (xy 36.712652 -344.13698)
			(xy 36.713153 -344.112031) (xy 36.720967 -344.062749) (xy 36.736383 -344.015292) (xy 36.759023 -343.970826)
			(xy 36.788332 -343.930443) (xy 36.805616 -343.912444) (xy 38.050216 -342.667844) (xy 38.053518 -342.654128)
			(xy 38.061246 -342.624507) (xy 38.084838 -342.568024) (xy 38.117171 -342.516049) (xy 38.13683 -342.492584)
			(xy 38.146082 -342.481269) (xy 38.158253 -342.454706) (xy 38.162421 -342.425786) (xy 38.158246 -342.396868)
			(xy 38.146067 -342.370308) (xy 38.13683 -342.35898) (xy 38.119172 -342.338062) (xy 38.089447 -342.292091)
			(xy 38.066603 -342.242343) (xy 38.051108 -342.189839) (xy 38.043281 -342.135658) (xy 38.043283 -342.080915)
			(xy 38.051114 -342.026735) (xy 38.066612 -341.974232) (xy 38.08946 -341.924485) (xy 38.119188 -341.878517)
			(xy 38.13683 -341.857584) (xy 38.146082 -341.846269) (xy 38.158253 -341.819706) (xy 38.162421 -341.790786)
			(xy 38.158246 -341.761868) (xy 38.146067 -341.735308) (xy 38.13683 -341.72398) (xy 38.119172 -341.703062)
			(xy 38.089447 -341.657091) (xy 38.066603 -341.607343) (xy 38.051108 -341.554839) (xy 38.043281 -341.500658)
			(xy 38.043283 -341.445915) (xy 38.051114 -341.391735) (xy 38.066612 -341.339232) (xy 38.08946 -341.289485)
			(xy 38.119188 -341.243517) (xy 38.13683 -341.222584) (xy 38.146082 -341.211269) (xy 38.158253 -341.184706)
			(xy 38.162421 -341.155786) (xy 38.158246 -341.126868) (xy 38.146067 -341.100308) (xy 38.13683 -341.08898)
			(xy 38.11922 -341.068025) (xy 38.089502 -341.022059) (xy 38.06666 -340.972317) (xy 38.051163 -340.919822)
			(xy 38.043328 -340.86565) (xy 38.04285 -340.838282) (xy 38.043409 -340.808158) (xy 38.052893 -340.748661)
			(xy 38.071607 -340.691393) (xy 38.099085 -340.637776) (xy 38.134646 -340.589142) (xy 38.155626 -340.567518)
			(xy 38.164862 -340.557812) (xy 38.178306 -340.534645) (xy 38.185266 -340.50878) (xy 38.185263 -340.481995)
			(xy 38.178297 -340.456131) (xy 38.164846 -340.432968) (xy 38.155626 -340.423246) (xy 38.134647 -340.40162)
			(xy 38.099078 -340.352992) (xy 38.071597 -340.299376) (xy 38.052888 -340.242106) (xy 38.043418 -340.182606)
			(xy 38.04285 -340.152482) (xy 38.043236 -340.126961) (xy 38.050033 -340.076373) (xy 38.063518 -340.027143)
			(xy 38.083448 -339.980152) (xy 38.109469 -339.93624) (xy 38.141114 -339.896191) (xy 38.159182 -339.878162)
			(xy 38.168936 -339.868167) (xy 38.182971 -339.844031) (xy 38.189938 -339.816994) (xy 38.189313 -339.789081)
			(xy 38.181143 -339.762383) (xy 38.166041 -339.7389) (xy 38.15588 -339.729318) (xy 38.136067 -339.711138)
			(xy 38.101279 -339.670134) (xy 38.072584 -339.624658) (xy 38.05055 -339.575606) (xy 38.035614 -339.523949)
			(xy 38.02807 -339.470708) (xy 38.02761 -339.443822) (xy 38.028087 -339.416452) (xy 38.035901 -339.362273)
			(xy 38.051388 -339.30977) (xy 38.074227 -339.260023) (xy 38.10395 -339.214056) (xy 38.12159 -339.193124)
			(xy 38.130806 -339.181781) (xy 38.142988 -339.155229) (xy 38.147165 -339.126317) (xy 38.142997 -339.097403)
			(xy 38.130825 -339.070847) (xy 38.12159 -339.05952) (xy 38.103945 -339.038593) (xy 38.074235 -338.992618)
			(xy 38.0514 -338.94287) (xy 38.03591 -338.890368) (xy 38.028083 -338.836191) (xy 38.02761 -338.808822)
			(xy 38.028076 -338.781569) (xy 38.03583 -338.727617) (xy 38.051184 -338.675318) (xy 38.073826 -338.625737)
			(xy 38.103293 -338.579883) (xy 38.138987 -338.538689) (xy 38.18018 -338.502995) (xy 38.226033 -338.473528)
			(xy 38.275614 -338.450886) (xy 38.327913 -338.435531) (xy 38.381865 -338.427776) (xy 38.409118 -338.427314)
			(xy 38.437856 -338.42785) (xy 38.494682 -338.436473) (xy 38.549572 -338.453521) (xy 38.601284 -338.47861)
			(xy 38.648648 -338.51117) (xy 38.669976 -338.530438) (xy 38.68151 -338.54051) (xy 38.709056 -338.553852)
			(xy 38.739318 -338.558437) (xy 38.76958 -338.553852) (xy 38.797126 -338.54051) (xy 38.80866 -338.530438)
			(xy 38.829987 -338.511168) (xy 38.87735 -338.478603) (xy 38.929061 -338.453512) (xy 38.983952 -338.436462)
			(xy 39.040779 -338.42784) (xy 39.098257 -338.42784) (xy 39.155084 -338.436462) (xy 39.209975 -338.453512)
			(xy 39.261686 -338.478603) (xy 39.309049 -338.511168) (xy 39.330376 -338.530438) (xy 39.341283 -338.539936)
			(xy 39.367057 -338.553021) (xy 39.395469 -338.558337) (xy 39.42423 -338.555455) (xy 39.437818 -338.550504)
			(xy 39.456048 -338.52959) (xy 39.497498 -338.492717) (xy 39.543854 -338.462239) (xy 39.594137 -338.4388)
			(xy 39.647286 -338.422894) (xy 39.702179 -338.414858) (xy 39.729918 -338.41436) (xy 39.75719 -338.414785)
			(xy 39.81118 -338.42255) (xy 39.863515 -338.43792) (xy 39.913129 -338.460581) (xy 39.959014 -338.490072)
			(xy 40.000234 -338.525794) (xy 40.035952 -338.567018) (xy 40.065438 -338.612906) (xy 40.088094 -338.662523)
			(xy 40.103459 -338.714859) (xy 40.111218 -338.768849) (xy 40.11168 -338.796122) (xy 40.111426 -338.810092)
			(xy 40.110907 -338.837335) (xy 40.102977 -338.891244) (xy 40.087449 -338.943474) (xy 40.06464 -338.99296)
			(xy 40.035015 -339.038692) (xy 40.017446 -339.05952) (xy 40.009031 -339.069826) (xy 39.997353 -339.093722)
			(xy 39.992231 -339.119822) (xy 39.994012 -339.146359) (xy 39.997888 -339.159088) (xy 40.019063 -339.180757)
			(xy 40.054942 -339.229573) (xy 40.082668 -339.283439) (xy 40.101546 -339.341006) (xy 40.111103 -339.40083)
			(xy 40.11168 -339.431122) (xy 40.111426 -339.445092) (xy 40.110952 -339.470505) (xy 40.104043 -339.520863)
			(xy 40.090504 -339.569857) (xy 40.070578 -339.616618) (xy 40.044616 -339.660317) (xy 40.013079 -339.70018)
			(xy 39.995094 -339.718142) (xy 39.985339 -339.728135) (xy 39.971307 -339.752272) (xy 39.964343 -339.779309)
			(xy 39.964969 -339.807221) (xy 39.973137 -339.833919) (xy 39.988236 -339.857403) (xy 39.998396 -339.866986)
			(xy 40.018206 -339.885169) (xy 40.052996 -339.926171) (xy 40.081692 -339.971647) (xy 40.103726 -340.020698)
			(xy 40.118662 -340.072355) (xy 40.126207 -340.125596) (xy 40.126666 -340.152482) (xy 40.126079 -340.182605)
			(xy 40.116601 -340.2421) (xy 40.097894 -340.299368) (xy 40.070422 -340.352985) (xy 40.034867 -340.40162)
			(xy 40.01389 -340.423246) (xy 40.004689 -340.432983) (xy 39.99124 -340.45614) (xy 39.984274 -340.481998)
			(xy 39.984271 -340.508777) (xy 39.99123 -340.534636) (xy 40.004673 -340.557797) (xy 40.01389 -340.567518)
			(xy 40.034854 -340.589158) (xy 40.070425 -340.637782) (xy 40.097908 -340.691395) (xy 40.11662 -340.748662)
			(xy 40.126095 -340.808159) (xy 40.126666 -340.838282) (xy 40.126198 -340.865652) (xy 40.118382 -340.919832)
			(xy 40.102894 -340.972335) (xy 40.080052 -341.022082) (xy 40.050327 -341.068049) (xy 40.032686 -341.08898)
			(xy 40.023468 -341.100321) (xy 40.01129 -341.126874) (xy 40.007114 -341.155786) (xy 40.011282 -341.1847)
			(xy 40.023453 -341.211256) (xy 40.032686 -341.222584) (xy 40.050309 -341.243531) (xy 40.080033 -341.289497)
			(xy 40.102879 -341.339241) (xy 40.118376 -341.391741) (xy 40.126206 -341.445917) (xy 40.126208 -341.500656)
			(xy 40.118382 -341.554833) (xy 40.102888 -341.607334) (xy 40.080046 -341.657079) (xy 40.050325 -341.703047)
			(xy 40.032686 -341.72398) (xy 40.023468 -341.735321) (xy 40.01129 -341.761874) (xy 40.007114 -341.790786)
			(xy 40.011282 -341.8197) (xy 40.023453 -341.846256) (xy 40.032686 -341.857584) (xy 40.050309 -341.878531)
			(xy 40.080033 -341.924497) (xy 40.102879 -341.974241) (xy 40.118376 -342.026741) (xy 40.126206 -342.080917)
			(xy 40.126208 -342.135656) (xy 40.118382 -342.189833) (xy 40.102888 -342.242334) (xy 40.080046 -342.292079)
			(xy 40.050325 -342.338047) (xy 40.032686 -342.35898) (xy 40.023468 -342.370321) (xy 40.01129 -342.396874)
			(xy 40.007114 -342.425786) (xy 40.011282 -342.4547) (xy 40.023453 -342.481256) (xy 40.032686 -342.492584)
			(xy 40.050329 -342.513513) (xy 40.080041 -342.559486) (xy 40.102876 -342.609235) (xy 40.118366 -342.661736)
			(xy 40.126193 -342.715913) (xy 40.126666 -342.743282) (xy 43.02125 -342.743282) (xy 43.021693 -342.715911)
			(xy 43.029515 -342.66173) (xy 43.045008 -342.609226) (xy 43.067856 -342.55948) (xy 43.097586 -342.513514)
			(xy 43.11523 -342.492584) (xy 43.124482 -342.481269) (xy 43.136653 -342.454706) (xy 43.140821 -342.425786)
			(xy 43.136646 -342.396868) (xy 43.124467 -342.370308) (xy 43.11523 -342.35898) (xy 43.097572 -342.338062)
			(xy 43.067847 -342.292091) (xy 43.045003 -342.242343) (xy 43.029508 -342.189839) (xy 43.021681 -342.135658)
			(xy 43.021683 -342.080915) (xy 43.029514 -342.026735) (xy 43.045012 -341.974232) (xy 43.06786 -341.924485)
			(xy 43.097588 -341.878517) (xy 43.11523 -341.857584) (xy 43.124482 -341.846269) (xy 43.136653 -341.819706)
			(xy 43.140821 -341.790786) (xy 43.136646 -341.761868) (xy 43.124467 -341.735308) (xy 43.11523 -341.72398)
			(xy 43.097572 -341.703062) (xy 43.067847 -341.657091) (xy 43.045003 -341.607343) (xy 43.029508 -341.554839)
			(xy 43.021681 -341.500658) (xy 43.021683 -341.445915) (xy 43.029514 -341.391735) (xy 43.045012 -341.339232)
			(xy 43.06786 -341.289485) (xy 43.097588 -341.243517) (xy 43.11523 -341.222584) (xy 43.124482 -341.211269)
			(xy 43.136653 -341.184706) (xy 43.140821 -341.155786) (xy 43.136646 -341.126868) (xy 43.124467 -341.100308)
			(xy 43.11523 -341.08898) (xy 43.09762 -341.068025) (xy 43.067902 -341.022059) (xy 43.04506 -340.972317)
			(xy 43.029563 -340.919822) (xy 43.021728 -340.86565) (xy 43.02125 -340.838282) (xy 43.02125 -340.838028)
			(xy 43.021846 -340.808195) (xy 43.031143 -340.749256) (xy 43.049499 -340.692483) (xy 43.076467 -340.639258)
			(xy 43.11139 -340.590879) (xy 43.131994 -340.569296) (xy 43.142625 -340.557741) (xy 43.157002 -340.529852)
			(xy 43.162226 -340.498914) (xy 43.157801 -340.467851) (xy 43.144146 -340.439601) (xy 43.133772 -340.427818)
			(xy 43.114184 -340.406442) (xy 43.081067 -340.358854) (xy 43.055538 -340.3068) (xy 43.038186 -340.25148)
			(xy 43.02941 -340.194171) (xy 43.02887 -340.165182) (xy 43.029319 -340.138581) (xy 43.036697 -340.085893)
			(xy 43.051322 -340.034741) (xy 43.07291 -339.986116) (xy 43.101043 -339.940961) (xy 43.135174 -339.900151)
			(xy 43.1546 -339.881972) (xy 43.164941 -339.872005) (xy 43.180033 -339.847581) (xy 43.187736 -339.819924)
			(xy 43.187444 -339.791215) (xy 43.179179 -339.76372) (xy 43.163593 -339.739609) (xy 43.153076 -339.729826)
			(xy 43.132762 -339.711618) (xy 43.097025 -339.670401) (xy 43.067521 -339.624515) (xy 43.044852 -339.574896)
			(xy 43.029478 -339.522555) (xy 43.021713 -339.468558) (xy 43.02125 -339.441282) (xy 43.021776 -339.412543)
			(xy 43.0304 -339.355717) (xy 43.04745 -339.300827) (xy 43.072541 -339.249115) (xy 43.105104 -339.201752)
			(xy 43.124374 -339.180424) (xy 43.134463 -339.168904) (xy 43.147803 -339.141353) (xy 43.152384 -339.111087)
			(xy 43.147795 -339.080822) (xy 43.134448 -339.053274) (xy 43.124374 -339.04174) (xy 43.105101 -339.020415)
			(xy 43.072533 -338.973053) (xy 43.047441 -338.921341) (xy 43.030391 -338.86645) (xy 43.02177 -338.809621)
			(xy 43.02125 -338.780882) (xy 43.021761 -338.753632) (xy 43.029519 -338.699688) (xy 43.044874 -338.647396)
			(xy 43.067514 -338.597821) (xy 43.096979 -338.551973) (xy 43.132667 -338.510784) (xy 43.173854 -338.475093)
			(xy 43.2197 -338.445626) (xy 43.269273 -338.422982) (xy 43.321564 -338.407624) (xy 43.375508 -338.399863)
			(xy 43.402758 -338.399374) (xy 43.431498 -338.399869) (xy 43.488326 -338.4085) (xy 43.543217 -338.425557)
			(xy 43.594928 -338.450655) (xy 43.64229 -338.483225) (xy 43.663616 -338.502498) (xy 43.67515 -338.51257)
			(xy 43.702696 -338.525912) (xy 43.732958 -338.530497) (xy 43.76322 -338.525912) (xy 43.790766 -338.51257)
			(xy 43.8023 -338.502498) (xy 43.823627 -338.483228) (xy 43.87099 -338.450663) (xy 43.922701 -338.425572)
			(xy 43.977592 -338.408522) (xy 44.034419 -338.3999) (xy 44.091897 -338.3999) (xy 44.148724 -338.408522)
			(xy 44.203615 -338.425572) (xy 44.255326 -338.450663) (xy 44.302689 -338.483228) (xy 44.324016 -338.502498)
			(xy 44.33555 -338.51257) (xy 44.363096 -338.525912) (xy 44.393358 -338.530497) (xy 44.42362 -338.525912)
			(xy 44.451166 -338.51257) (xy 44.4627 -338.502498) (xy 44.484012 -338.48321) (xy 44.531377 -338.450644)
			(xy 44.583093 -338.425554) (xy 44.637987 -338.408508) (xy 44.694818 -338.399891) (xy 44.723558 -338.399374)
			(xy 44.750809 -338.399894) (xy 44.804757 -338.407645) (xy 44.857053 -338.422995) (xy 44.906631 -338.445631)
			(xy 44.952484 -338.475093) (xy 44.993677 -338.510781) (xy 45.029371 -338.551968) (xy 45.05884 -338.597816)
			(xy 45.081484 -338.647391) (xy 45.096842 -338.699684) (xy 45.104601 -338.753631) (xy 45.105066 -338.780882)
			(xy 45.104514 -338.80962) (xy 45.095895 -338.866445) (xy 45.078851 -338.921335) (xy 45.053766 -338.973047)
			(xy 45.021209 -339.020411) (xy 45.001942 -339.04174) (xy 44.991887 -339.053288) (xy 44.978541 -339.080829)
			(xy 44.973953 -339.111087) (xy 44.978534 -339.141346) (xy 44.991872 -339.16889) (xy 45.001942 -339.180424)
			(xy 45.021201 -339.201761) (xy 45.05377 -339.24912) (xy 45.078865 -339.300829) (xy 45.095918 -339.355718)
			(xy 45.104544 -339.412544) (xy 45.105066 -339.441282) (xy 45.104581 -339.467882) (xy 45.097208 -339.520567)
			(xy 45.08259 -339.571718) (xy 45.061009 -339.620343) (xy 45.032883 -339.665499) (xy 44.998758 -339.706312)
			(xy 44.979336 -339.724492) (xy 44.969028 -339.734492) (xy 44.953929 -339.758905) (xy 44.946218 -339.786555)
			(xy 44.946504 -339.815258) (xy 44.954764 -339.842749) (xy 44.970345 -339.866857) (xy 44.98086 -339.876638)
			(xy 45.001164 -339.894857) (xy 45.0369 -339.936073) (xy 45.066404 -339.981956) (xy 45.089075 -340.031573)
			(xy 45.104452 -340.083912) (xy 45.112221 -340.137907) (xy 45.112686 -340.165182) (xy 45.112686 -340.165436)
			(xy 45.11212 -340.19527) (xy 45.102814 -340.254209) (xy 45.08445 -340.310983) (xy 45.057476 -340.364207)
			(xy 45.022548 -340.412585) (xy 45.001942 -340.434168) (xy 44.991253 -340.445671) (xy 44.976891 -340.47358)
			(xy 44.971683 -340.504532) (xy 44.976121 -340.535604) (xy 44.989785 -340.56386) (xy 45.000164 -340.575646)
			(xy 45.019724 -340.597046) (xy 45.052847 -340.644627) (xy 45.078382 -340.696675) (xy 45.095741 -340.751989)
			(xy 45.104523 -340.809295) (xy 45.105066 -340.838282) (xy 45.104598 -340.865652) (xy 45.096782 -340.919832)
			(xy 45.081294 -340.972335) (xy 45.058452 -341.022082) (xy 45.028727 -341.068049) (xy 45.011086 -341.08898)
			(xy 45.001868 -341.100321) (xy 44.98969 -341.126874) (xy 44.985514 -341.155786) (xy 44.989682 -341.1847)
			(xy 45.001853 -341.211256) (xy 45.011086 -341.222584) (xy 45.028709 -341.243531) (xy 45.058433 -341.289497)
			(xy 45.081279 -341.339241) (xy 45.096776 -341.391741) (xy 45.104606 -341.445917) (xy 45.104608 -341.500656)
			(xy 45.096782 -341.554833) (xy 45.081288 -341.607334) (xy 45.058446 -341.657079) (xy 45.028725 -341.703047)
			(xy 45.011086 -341.72398) (xy 45.001868 -341.735321) (xy 44.98969 -341.761874) (xy 44.985514 -341.790786)
			(xy 44.989682 -341.8197) (xy 45.001853 -341.846256) (xy 45.011086 -341.857584) (xy 45.028709 -341.878531)
			(xy 45.058433 -341.924497) (xy 45.081279 -341.974241) (xy 45.096776 -342.026741) (xy 45.104606 -342.080917)
			(xy 45.104608 -342.135656) (xy 45.096782 -342.189833) (xy 45.081288 -342.242334) (xy 45.058446 -342.292079)
			(xy 45.028725 -342.338047) (xy 45.011086 -342.35898) (xy 45.001868 -342.370321) (xy 44.98969 -342.396874)
			(xy 44.985514 -342.425786) (xy 44.989682 -342.4547) (xy 45.001853 -342.481256) (xy 45.011086 -342.492584)
			(xy 45.028729 -342.513513) (xy 45.058441 -342.559486) (xy 45.081276 -342.609235) (xy 45.096766 -342.661736)
			(xy 45.104593 -342.715913) (xy 45.105066 -342.743282) (xy 45.104628 -342.770536) (xy 45.096872 -342.82449)
			(xy 45.081516 -342.876791) (xy 45.058873 -342.926374) (xy 45.029403 -342.972229) (xy 44.993706 -343.013423)
			(xy 44.95251 -343.049117) (xy 44.906653 -343.078584) (xy 44.857069 -343.101225) (xy 44.804767 -343.116577)
			(xy 44.750812 -343.12433) (xy 44.723558 -343.12479) (xy 44.694818 -343.124294) (xy 44.637989 -343.115665)
			(xy 44.583098 -343.098609) (xy 44.531387 -343.073511) (xy 44.484026 -343.04094) (xy 44.4627 -343.021666)
			(xy 44.451166 -343.011594) (xy 44.42362 -342.998252) (xy 44.393358 -342.993667) (xy 44.363096 -342.998252)
			(xy 44.33555 -343.011594) (xy 44.324016 -343.021666) (xy 44.302689 -343.040936) (xy 44.255326 -343.073501)
			(xy 44.203615 -343.098592) (xy 44.148724 -343.115642) (xy 44.091897 -343.124264) (xy 44.034419 -343.124264)
			(xy 43.977592 -343.115642) (xy 43.922701 -343.098592) (xy 43.87099 -343.073501) (xy 43.823627 -343.040936)
			(xy 43.8023 -343.021666) (xy 43.790766 -343.011594) (xy 43.76322 -342.998252) (xy 43.732958 -342.993667)
			(xy 43.702696 -342.998252) (xy 43.67515 -343.011594) (xy 43.663616 -343.021666) (xy 43.642307 -343.040957)
			(xy 43.59494 -343.073521) (xy 43.543224 -343.098609) (xy 43.488329 -343.115655) (xy 43.431498 -343.124272)
			(xy 43.402758 -343.12479) (xy 43.375505 -343.124361) (xy 43.321554 -343.116599) (xy 43.269257 -343.101237)
			(xy 43.219679 -343.07859) (xy 43.173828 -343.049117) (xy 43.132637 -343.01342) (xy 43.096947 -342.972224)
			(xy 43.067481 -342.926369) (xy 43.044842 -342.876786) (xy 43.029489 -342.824487) (xy 43.021735 -342.770535)
			(xy 43.02125 -342.743282) (xy 40.126666 -342.743282) (xy 40.126228 -342.770536) (xy 40.118472 -342.82449)
			(xy 40.103116 -342.876791) (xy 40.080473 -342.926374) (xy 40.051003 -342.972229) (xy 40.015306 -343.013423)
			(xy 39.97411 -343.049117) (xy 39.928253 -343.078584) (xy 39.878669 -343.101225) (xy 39.826367 -343.116577)
			(xy 39.772412 -343.12433) (xy 39.745158 -343.12479) (xy 39.716418 -343.124294) (xy 39.659589 -343.115665)
			(xy 39.604698 -343.098609) (xy 39.552987 -343.073511) (xy 39.505626 -343.04094) (xy 39.4843 -343.021666)
			(xy 39.472766 -343.011594) (xy 39.44522 -342.998252) (xy 39.414958 -342.993667) (xy 39.384696 -342.998252)
			(xy 39.35715 -343.011594) (xy 39.345616 -343.021666) (xy 39.324289 -343.040936) (xy 39.276926 -343.073501)
			(xy 39.225215 -343.098592) (xy 39.170324 -343.115642) (xy 39.113497 -343.124264) (xy 39.056019 -343.124264)
			(xy 38.999192 -343.115642) (xy 38.944301 -343.098592) (xy 38.89259 -343.073501) (xy 38.845227 -343.040936)
			(xy 38.8239 -343.021666) (xy 38.812366 -343.011594) (xy 38.78482 -342.998252) (xy 38.754558 -342.993667)
			(xy 38.724296 -342.998252) (xy 38.69675 -343.011594) (xy 38.685216 -343.021666) (xy 38.666954 -343.038242)
			(xy 38.626908 -343.067031) (xy 38.583482 -343.090413) (xy 38.537403 -343.107997) (xy 38.513512 -343.114122)
			(xy 38.499542 -343.117678) (xy 37.34816 -344.268806) (xy 37.34816 -355.01453) (xy 37.608764 -355.01453)
			(xy 37.608764 -355.014276) (xy 37.609295 -354.986262) (xy 37.617514 -354.93084) (xy 37.633742 -354.877213)
			(xy 37.657631 -354.826533) (xy 37.688668 -354.779887) (xy 37.707062 -354.758752) (xy 37.716729 -354.747326)
			(xy 37.729509 -354.720278) (xy 37.733892 -354.690685) (xy 37.7295 -354.661093) (xy 37.716712 -354.634049)
			(xy 37.707062 -354.622608) (xy 37.688634 -354.601497) (xy 37.657566 -354.55486) (xy 37.633664 -354.504176)
			(xy 37.617442 -354.450538) (xy 37.609252 -354.395103) (xy 37.608764 -354.367084) (xy 37.608764 -354.36683)
			(xy 37.60925 -354.339579) (xy 37.617006 -354.285631) (xy 37.632361 -354.233336) (xy 37.655003 -354.183759)
			(xy 37.684469 -354.137909) (xy 37.72016 -354.096718) (xy 37.761351 -354.061027) (xy 37.807201 -354.031561)
			(xy 37.856778 -354.008919) (xy 37.909073 -353.993564) (xy 37.963021 -353.985808) (xy 38.017523 -353.985808)
			(xy 38.071471 -353.993564) (xy 38.123766 -354.008919) (xy 38.173343 -354.031561) (xy 38.219193 -354.061027)
			(xy 38.260384 -354.096718) (xy 38.296075 -354.137909) (xy 38.325541 -354.183759) (xy 38.348183 -354.233336)
			(xy 38.363538 -354.285631) (xy 38.371294 -354.339579) (xy 38.37178 -354.36683) (xy 38.37178 -354.367084)
			(xy 38.371299 -354.3951) (xy 38.36307 -354.450525) (xy 38.346831 -354.504153) (xy 38.322931 -354.554832)
			(xy 38.291882 -354.601475) (xy 38.273482 -354.622608) (xy 38.269002 -354.627942) (xy 45.58614 -354.627942)
			(xy 45.590211 -354.57232) (xy 45.602337 -354.517883) (xy 45.62226 -354.465792) (xy 45.649556 -354.417157)
			(xy 45.683642 -354.373014) (xy 45.723791 -354.334305) (xy 45.769149 -354.301854) (xy 45.818749 -354.276353)
			(xy 45.871533 -354.258346) (xy 45.926376 -354.248216) (xy 45.98211 -354.246179) (xy 46.037547 -354.252279)
			(xy 46.091504 -354.266385) (xy 46.142833 -354.288197) (xy 46.190439 -354.317251) (xy 46.233307 -354.352926)
			(xy 46.270524 -354.394463) (xy 46.301297 -354.440976) (xy 46.324969 -354.491473) (xy 46.341037 -354.54488)
			(xy 46.349157 -354.600056) (xy 46.349666 -354.627942) (xy 46.349157 -354.655828) (xy 46.341037 -354.711004)
			(xy 46.324969 -354.764411) (xy 46.301297 -354.814908) (xy 46.270524 -354.861421) (xy 46.233307 -354.902958)
			(xy 46.190439 -354.938633) (xy 46.142833 -354.967687) (xy 46.091504 -354.989499) (xy 46.037547 -355.003605)
			(xy 45.995969 -355.00818) (xy 47.297086 -355.00818) (xy 47.297544 -354.98081) (xy 47.305364 -354.92663)
			(xy 47.320855 -354.874127) (xy 47.343699 -354.82438) (xy 47.373424 -354.778414) (xy 47.391066 -354.757482)
			(xy 47.400325 -354.74617) (xy 47.412504 -354.719608) (xy 47.416674 -354.690685) (xy 47.412495 -354.661763)
			(xy 47.400308 -354.635204) (xy 47.391066 -354.623878) (xy 47.373445 -354.602932) (xy 47.343731 -354.556962)
			(xy 47.320893 -354.507218) (xy 47.305397 -354.454721) (xy 47.297563 -354.400548) (xy 47.297086 -354.37318)
			(xy 47.297572 -354.345929) (xy 47.305328 -354.291981) (xy 47.320683 -354.239686) (xy 47.343325 -354.190109)
			(xy 47.372791 -354.144259) (xy 47.408482 -354.103068) (xy 47.449673 -354.067377) (xy 47.495523 -354.037911)
			(xy 47.5451 -354.015269) (xy 47.597395 -353.999914) (xy 47.651343 -353.992158) (xy 47.705845 -353.992158)
			(xy 47.759793 -353.999914) (xy 47.812088 -354.015269) (xy 47.861665 -354.037911) (xy 47.907515 -354.067377)
			(xy 47.948706 -354.103068) (xy 47.984397 -354.144259) (xy 48.013863 -354.190109) (xy 48.036505 -354.239686)
			(xy 48.05186 -354.291981) (xy 48.059616 -354.345929) (xy 48.060102 -354.37318) (xy 48.059624 -354.40055)
			(xy 48.051809 -354.454728) (xy 48.036323 -354.507231) (xy 48.013484 -354.556978) (xy 47.983762 -354.602946)
			(xy 47.966122 -354.623878) (xy 47.956903 -354.635219) (xy 47.94472 -354.661771) (xy 47.940543 -354.690685)
			(xy 47.944712 -354.7196) (xy 47.956886 -354.746156) (xy 47.966122 -354.757482) (xy 47.98377 -354.778407)
			(xy 48.013479 -354.824382) (xy 48.036313 -354.874132) (xy 48.051802 -354.926634) (xy 48.059629 -354.98081)
			(xy 48.060102 -355.00818) (xy 48.059616 -355.035431) (xy 48.05186 -355.089379) (xy 48.036505 -355.141674)
			(xy 48.013863 -355.191251) (xy 47.984397 -355.237101) (xy 47.948706 -355.278292) (xy 47.907515 -355.313983)
			(xy 47.861665 -355.343449) (xy 47.812088 -355.366091) (xy 47.759793 -355.381446) (xy 47.705845 -355.389202)
			(xy 47.651343 -355.389202) (xy 47.597395 -355.381446) (xy 47.5451 -355.366091) (xy 47.495523 -355.343449)
			(xy 47.449673 -355.313983) (xy 47.408482 -355.278292) (xy 47.372791 -355.237101) (xy 47.343325 -355.191251)
			(xy 47.320683 -355.141674) (xy 47.305328 -355.089379) (xy 47.297572 -355.035431) (xy 47.297086 -355.00818)
			(xy 45.995969 -355.00818) (xy 45.98211 -355.009705) (xy 45.926376 -355.007668) (xy 45.871533 -354.997538)
			(xy 45.818749 -354.979531) (xy 45.769149 -354.95403) (xy 45.723791 -354.921579) (xy 45.683642 -354.88287)
			(xy 45.649556 -354.838727) (xy 45.62226 -354.790092) (xy 45.602337 -354.738001) (xy 45.590211 -354.683564)
			(xy 45.58614 -354.627942) (xy 38.269002 -354.627942) (xy 38.263859 -354.634066) (xy 38.251081 -354.661104)
			(xy 38.246693 -354.690685) (xy 38.251072 -354.720268) (xy 38.263843 -354.747309) (xy 38.273482 -354.758752)
			(xy 38.291898 -354.779873) (xy 38.322967 -354.826507) (xy 38.346871 -354.877189) (xy 38.363095 -354.930825)
			(xy 38.37129 -354.986258) (xy 38.37178 -355.014276) (xy 38.37178 -355.01453) (xy 38.371294 -355.041781)
			(xy 38.363538 -355.095729) (xy 38.348183 -355.148024) (xy 38.325541 -355.197601) (xy 38.296075 -355.243451)
			(xy 38.260384 -355.284642) (xy 38.219193 -355.320333) (xy 38.173343 -355.349799) (xy 38.123766 -355.372441)
			(xy 38.071471 -355.387796) (xy 38.017523 -355.395552) (xy 37.963021 -355.395552) (xy 37.909073 -355.387796)
			(xy 37.856778 -355.372441) (xy 37.807201 -355.349799) (xy 37.761351 -355.320333) (xy 37.72016 -355.284642)
			(xy 37.684469 -355.243451) (xy 37.655003 -355.197601) (xy 37.632361 -355.148024) (xy 37.617006 -355.095729)
			(xy 37.60925 -355.041781) (xy 37.608764 -355.01453) (xy 37.34816 -355.01453) (xy 37.34816 -355.4108)
			(xy 41.857303 -355.4108) (xy 41.861472 -355.355173) (xy 41.873886 -355.30079) (xy 41.894268 -355.248864)
			(xy 41.922161 -355.200556) (xy 41.956943 -355.156945) (xy 41.997837 -355.119006) (xy 42.04393 -355.087586)
			(xy 42.09419 -355.063388) (xy 42.147496 -355.046951) (xy 42.202657 -355.038644) (xy 42.230548 -355.038152)
			(xy 42.25788 -355.038623) (xy 42.31196 -355.046592) (xy 42.364295 -355.062379) (xy 42.41376 -355.085647)
			(xy 42.459292 -355.115895) (xy 42.499914 -355.152474) (xy 42.534753 -355.194597) (xy 42.549318 -355.21773)
			(xy 42.557239 -355.229955) (xy 42.578713 -355.249623) (xy 42.604866 -355.262425) (xy 42.633571 -355.267321)
			(xy 42.66249 -355.26391) (xy 42.676064 -355.258624) (xy 42.69928 -355.249149) (xy 42.74761 -355.235794)
			(xy 42.797297 -355.229059) (xy 42.822368 -355.228652) (xy 42.847438 -355.229064) (xy 42.897121 -355.235818)
			(xy 42.945455 -355.249155) (xy 42.968672 -355.258624) (xy 42.982249 -355.263871) (xy 43.011149 -355.267234)
			(xy 43.039827 -355.262322) (xy 43.065961 -355.249534) (xy 43.087437 -355.229904) (xy 43.095418 -355.21773)
			(xy 43.109987 -355.194599) (xy 43.14483 -355.152478) (xy 43.185453 -355.115899) (xy 43.230984 -355.085648)
			(xy 43.280446 -355.062372) (xy 43.332777 -355.046572) (xy 43.386856 -355.038586) (xy 43.44152 -355.038586)
			(xy 43.495599 -355.046572) (xy 43.54793 -355.062372) (xy 43.597392 -355.085648) (xy 43.642923 -355.115899)
			(xy 43.683546 -355.152478) (xy 43.718389 -355.194599) (xy 43.732958 -355.21773) (xy 43.740841 -355.229983)
			(xy 43.762325 -355.24965) (xy 43.788489 -355.262449) (xy 43.817203 -355.267337) (xy 43.846128 -355.263916)
			(xy 43.859704 -355.258624) (xy 43.882915 -355.249137) (xy 43.931247 -355.235786) (xy 43.980937 -355.229057)
			(xy 44.006008 -355.228652) (xy 44.033193 -355.229125) (xy 44.086987 -355.237015) (xy 44.139062 -355.252639)
			(xy 44.188314 -355.275667) (xy 44.233695 -355.305609) (xy 44.274243 -355.34183) (xy 44.309095 -355.383559)
			(xy 44.337512 -355.429911) (xy 44.348654 -355.454712) (xy 44.354556 -355.467303) (xy 44.371962 -355.48897)
			(xy 44.394568 -355.50514) (xy 44.420697 -355.514612) (xy 44.448413 -355.516686) (xy 44.475661 -355.511206)
			(xy 44.500421 -355.498581) (xy 44.51096 -355.48951) (xy 44.532202 -355.470607) (xy 44.579249 -355.438674)
			(xy 44.630518 -355.414084) (xy 44.684871 -355.397383) (xy 44.741102 -355.388941) (xy 44.769532 -355.388418)
			(xy 44.787551 -355.38864) (xy 44.823426 -355.392074) (xy 44.84116 -355.395276) (xy 44.856375 -355.397561)
			(xy 44.88692 -355.394044) (xy 44.915035 -355.381595) (xy 44.93817 -355.361343) (xy 44.954229 -355.335122)
			(xy 44.958508 -355.320346) (xy 44.965907 -355.293302) (xy 44.987537 -355.241577) (xy 45.016502 -355.193572)
			(xy 45.052177 -355.15032) (xy 45.093796 -355.112754) (xy 45.140463 -355.081679) (xy 45.191174 -355.057766)
			(xy 45.244838 -355.041529) (xy 45.300299 -355.033317) (xy 45.328332 -355.032818) (xy 45.355585 -355.033248)
			(xy 45.409536 -355.04101) (xy 45.461834 -355.05637) (xy 45.511413 -355.079017) (xy 45.557264 -355.108489)
			(xy 45.598455 -355.144186) (xy 45.634146 -355.185382) (xy 45.663611 -355.231238) (xy 45.68625 -355.280821)
			(xy 45.701603 -355.33312) (xy 45.709356 -355.387073) (xy 45.70984 -355.414326) (xy 45.709344 -355.4419)
			(xy 45.701401 -355.496472) (xy 45.685683 -355.549332) (xy 45.662519 -355.599379) (xy 45.632391 -355.645569)
			(xy 45.595926 -355.68694) (xy 45.57522 -355.705156) (xy 45.564295 -355.715027) (xy 45.548221 -355.739685)
			(xy 45.539839 -355.7679) (xy 45.539844 -355.797334) (xy 45.548235 -355.825546) (xy 45.564318 -355.850198)
			(xy 45.57522 -355.860096) (xy 45.595951 -355.878284) (xy 45.632412 -355.91966) (xy 45.662537 -355.965854)
			(xy 45.685697 -356.015904) (xy 45.70141 -356.068768) (xy 45.709347 -356.123342) (xy 45.709345 -356.178491)
			(xy 45.701402 -356.233065) (xy 45.685685 -356.285927) (xy 45.662521 -356.335976) (xy 45.632392 -356.382167)
			(xy 45.595927 -356.42354) (xy 45.57522 -356.441756) (xy 45.564295 -356.451627) (xy 45.548221 -356.476285)
			(xy 45.539839 -356.5045) (xy 45.539844 -356.533934) (xy 45.548235 -356.562146) (xy 45.564318 -356.586798)
			(xy 45.57522 -356.596696) (xy 45.595936 -356.614901) (xy 45.632405 -356.656272) (xy 45.662536 -356.702463)
			(xy 45.685701 -356.752512) (xy 45.701417 -356.805375) (xy 45.709355 -356.859951) (xy 45.70984 -356.887526)
			(xy 45.709346 -356.914776) (xy 45.701587 -356.968722) (xy 45.68623 -357.021015) (xy 45.663589 -357.07059)
			(xy 45.634123 -357.116439) (xy 45.598432 -357.157628) (xy 45.557244 -357.193319) (xy 45.511395 -357.222786)
			(xy 45.46182 -357.245428) (xy 45.409528 -357.260786) (xy 45.355582 -357.268546) (xy 45.328332 -357.269034)
			(xy 45.300479 -357.268457) (xy 45.245367 -357.260339) (xy 45.192019 -357.244299) (xy 45.141568 -357.220679)
			(xy 45.095084 -357.189979) (xy 45.053555 -357.15285) (xy 45.01786 -357.110082) (xy 44.988758 -357.062581)
			(xy 44.966867 -357.011356) (xy 44.95927 -356.984554) (xy 44.955023 -356.97043) (xy 44.939621 -356.945288)
			(xy 44.917696 -356.925576) (xy 44.891063 -356.912927) (xy 44.861931 -356.90839) (xy 44.847256 -356.909878)
			(xy 44.834303 -356.911544) (xy 44.808245 -356.913321) (xy 44.795186 -356.913434) (xy 44.794932 -356.913434)
			(xy 44.794678 -356.913434) (xy 44.765642 -356.912893) (xy 44.708242 -356.90409) (xy 44.680378 -356.895908)
			(xy 44.66662 -356.892054) (xy 44.638072 -356.891306) (xy 44.610434 -356.898498) (xy 44.58587 -356.913066)
			(xy 44.566305 -356.933869) (xy 44.553269 -356.959279) (xy 44.547784 -356.987305) (xy 44.548552 -357.001572)
			(xy 44.550076 -357.034846) (xy 44.549665 -357.0621) (xy 44.541901 -357.116052) (xy 44.526539 -357.16835)
			(xy 44.50389 -357.21793) (xy 44.474416 -357.263781) (xy 44.438717 -357.304972) (xy 44.397519 -357.340663)
			(xy 44.351661 -357.370127) (xy 44.302077 -357.392766) (xy 44.249776 -357.408118) (xy 44.195822 -357.41587)
			(xy 44.168568 -357.416354) (xy 44.141318 -357.415852) (xy 44.087373 -357.408092) (xy 44.035082 -357.392736)
			(xy 43.985507 -357.370094) (xy 43.939659 -357.340629) (xy 43.898471 -357.304939) (xy 43.86278 -357.263752)
			(xy 43.833313 -357.217905) (xy 43.810669 -357.168331) (xy 43.795311 -357.11604) (xy 43.787549 -357.062096)
			(xy 43.78706 -357.034846) (xy 43.787536 -357.007272) (xy 43.795484 -356.952698) (xy 43.811205 -356.899838)
			(xy 43.834373 -356.849791) (xy 43.864505 -356.803602) (xy 43.900973 -356.762231) (xy 43.92168 -356.744016)
			(xy 43.932533 -356.734071) (xy 43.948609 -356.709435) (xy 43.957 -356.681239) (xy 43.957009 -356.651821)
			(xy 43.948635 -356.623619) (xy 43.932572 -356.598973) (xy 43.92168 -356.589076) (xy 43.90095 -356.570885)
			(xy 43.864482 -356.529512) (xy 43.834353 -356.483317) (xy 43.81119 -356.433265) (xy 43.795478 -356.3804)
			(xy 43.787543 -356.325822) (xy 43.78706 -356.298246) (xy 43.787663 -356.268495) (xy 43.796938 -356.209719)
			(xy 43.81521 -356.15309) (xy 43.842036 -356.099976) (xy 43.858942 -356.075488) (xy 43.866861 -356.063559)
			(xy 43.87646 -356.036601) (xy 43.878193 -356.008037) (xy 43.871925 -355.980115) (xy 43.85815 -355.955033)
			(xy 43.83795 -355.934763) (xy 43.825668 -355.927406) (xy 43.804606 -355.915307) (xy 43.765515 -355.886475)
			(xy 43.7305 -355.852809) (xy 43.700154 -355.814881) (xy 43.687238 -355.79431) (xy 43.679349 -355.782061)
			(xy 43.657869 -355.762388) (xy 43.631706 -355.749586) (xy 43.602992 -355.744698) (xy 43.574067 -355.748121)
			(xy 43.560492 -355.753416) (xy 43.53728 -355.762901) (xy 43.488948 -355.776254) (xy 43.439259 -355.782984)
			(xy 43.414188 -355.783388) (xy 43.389119 -355.782955) (xy 43.339436 -355.776209) (xy 43.291102 -355.76288)
			(xy 43.267884 -355.753416) (xy 43.254305 -355.748162) (xy 43.225397 -355.744783) (xy 43.196708 -355.749685)
			(xy 43.170562 -355.762471) (xy 43.149078 -355.782106) (xy 43.141138 -355.79431) (xy 43.126569 -355.817441)
			(xy 43.091726 -355.859562) (xy 43.051103 -355.896141) (xy 43.005572 -355.926392) (xy 42.95611 -355.949668)
			(xy 42.903779 -355.965468) (xy 42.8497 -355.973454) (xy 42.795036 -355.973454) (xy 42.740957 -355.965468)
			(xy 42.688626 -355.949668) (xy 42.639164 -355.926392) (xy 42.593633 -355.896141) (xy 42.55301 -355.859562)
			(xy 42.518167 -355.817441) (xy 42.503598 -355.79431) (xy 42.495652 -355.782102) (xy 42.474188 -355.76243)
			(xy 42.44804 -355.749622) (xy 42.41934 -355.744723) (xy 42.390425 -355.748131) (xy 42.376852 -355.753416)
			(xy 42.353645 -355.762913) (xy 42.305311 -355.776261) (xy 42.25562 -355.782986) (xy 42.230548 -355.783388)
			(xy 42.202657 -355.782956) (xy 42.147496 -355.774649) (xy 42.09419 -355.758212) (xy 42.04393 -355.734014)
			(xy 41.997837 -355.702594) (xy 41.956943 -355.664655) (xy 41.922161 -355.621044) (xy 41.894268 -355.572736)
			(xy 41.873886 -355.52081) (xy 41.861472 -355.466427) (xy 41.857303 -355.4108) (xy 37.34816 -355.4108)
			(xy 37.34816 -356.288086) (xy 37.491162 -356.430834) (xy 37.505132 -356.43439) (xy 37.532535 -356.441487)
			(xy 37.585015 -356.462701) (xy 37.608526 -356.476554) (xy 38.399718 -356.476554) (xy 38.403789 -356.420932)
			(xy 38.415915 -356.366495) (xy 38.435838 -356.314404) (xy 38.463134 -356.265769) (xy 38.49722 -356.221626)
			(xy 38.537369 -356.182917) (xy 38.582727 -356.150466) (xy 38.632327 -356.124965) (xy 38.685111 -356.106958)
			(xy 38.739954 -356.096828) (xy 38.795688 -356.094791) (xy 38.851125 -356.100891) (xy 38.905082 -356.114997)
			(xy 38.956411 -356.136809) (xy 39.004017 -356.165863) (xy 39.046885 -356.201538) (xy 39.084102 -356.243075)
			(xy 39.114875 -356.289588) (xy 39.138547 -356.340085) (xy 39.154615 -356.393492) (xy 39.162735 -356.448668)
			(xy 39.163244 -356.476554) (xy 39.162735 -356.50444) (xy 39.154615 -356.559616) (xy 39.138547 -356.613023)
			(xy 39.114875 -356.66352) (xy 39.084102 -356.710033) (xy 39.046885 -356.75157) (xy 39.004017 -356.787245)
			(xy 38.956411 -356.816299) (xy 38.905082 -356.838111) (xy 38.851125 -356.852217) (xy 38.795688 -356.858317)
			(xy 38.739954 -356.85628) (xy 38.685111 -356.84615) (xy 38.632327 -356.828143) (xy 38.582727 -356.802642)
			(xy 38.537369 -356.770191) (xy 38.49722 -356.731482) (xy 38.463134 -356.687339) (xy 38.435838 -356.638704)
			(xy 38.415915 -356.586613) (xy 38.403789 -356.532176) (xy 38.399718 -356.476554) (xy 37.608526 -356.476554)
			(xy 37.633784 -356.491436) (xy 37.677771 -356.527063) (xy 37.716011 -356.568798) (xy 37.747665 -356.615725)
			(xy 37.772037 -356.666815) (xy 37.788591 -356.720945) (xy 37.796966 -356.776928) (xy 37.797486 -356.80523)
			(xy 37.79705 -356.832483) (xy 37.789289 -356.886434) (xy 37.773929 -356.938731) (xy 37.751283 -356.988309)
			(xy 37.721811 -357.034161) (xy 37.686114 -357.075351) (xy 37.644919 -357.111042) (xy 37.599064 -357.140508)
			(xy 37.549482 -357.163147) (xy 37.497183 -357.1785) (xy 37.443231 -357.186254) (xy 37.415978 -357.186738)
			(xy 37.387671 -357.186243) (xy 37.331676 -357.177895) (xy 37.277533 -357.161357) (xy 37.226431 -357.136991)
			(xy 37.179495 -357.105334) (xy 37.137759 -357.067084) (xy 37.102139 -357.02308) (xy 37.07342 -356.974291)
			(xy 37.052234 -356.921792) (xy 37.045138 -356.894384) (xy 37.041836 -356.880668) (xy 36.805616 -356.644448)
			(xy 36.788299 -356.626477) (xy 36.758978 -356.586095) (xy 36.736335 -356.541623) (xy 36.720927 -356.494157)
			(xy 36.713134 -356.444864) (xy 36.712652 -356.419912) (xy 35.725608 -356.419912) (xy 35.725608 -357.98506)
			(xy 39.206424 -357.98506) (xy 39.206805 -357.95972) (xy 39.21352 -357.909488) (xy 39.226827 -357.860586)
			(xy 39.246491 -357.813877) (xy 39.272166 -357.770183) (xy 39.3034 -357.730272) (xy 39.321232 -357.712264)
			(xy 39.330672 -357.702529) (xy 39.344468 -357.679196) (xy 39.351619 -357.653049) (xy 39.351618 -357.625942)
			(xy 39.344464 -357.599795) (xy 39.330666 -357.576463) (xy 39.321232 -357.566722) (xy 39.30342 -357.548696)
			(xy 39.27219 -357.508788) (xy 39.246518 -357.465096) (xy 39.226857 -357.41839) (xy 39.213553 -357.369493)
			(xy 39.20684 -357.319264) (xy 39.206424 -357.293926) (xy 39.20691 -357.266675) (xy 39.214666 -357.212727)
			(xy 39.230021 -357.160432) (xy 39.252663 -357.110855) (xy 39.282129 -357.065005) (xy 39.31782 -357.023814)
			(xy 39.359011 -356.988123) (xy 39.404861 -356.958657) (xy 39.454438 -356.936015) (xy 39.506733 -356.92066)
			(xy 39.560681 -356.912904) (xy 39.615183 -356.912904) (xy 39.669131 -356.92066) (xy 39.721426 -356.936015)
			(xy 39.771003 -356.958657) (xy 39.816853 -356.988123) (xy 39.858044 -357.023814) (xy 39.893735 -357.065005)
			(xy 39.923201 -357.110855) (xy 39.945843 -357.160432) (xy 39.961198 -357.212727) (xy 39.968954 -357.266675)
			(xy 39.9691 -357.274876) (xy 40.83177 -357.274876) (xy 40.832255 -357.247625) (xy 40.840015 -357.193679)
			(xy 40.855372 -357.141385) (xy 40.878014 -357.091809) (xy 40.907481 -357.04596) (xy 40.943172 -357.004771)
			(xy 40.984362 -356.96908) (xy 41.030211 -356.939613) (xy 41.079787 -356.916971) (xy 41.132081 -356.901614)
			(xy 41.186027 -356.893855) (xy 41.213278 -356.893368) (xy 41.240528 -356.893899) (xy 41.294472 -356.901652)
			(xy 41.346765 -356.917003) (xy 41.39634 -356.939639) (xy 41.44219 -356.969101) (xy 41.483379 -357.004788)
			(xy 41.519071 -357.045974) (xy 41.548538 -357.091819) (xy 41.571181 -357.141392) (xy 41.586539 -357.193683)
			(xy 41.594298 -357.247626) (xy 41.594786 -357.274876) (xy 41.594544 -357.293543) (xy 41.590858 -357.330695)
			(xy 41.58742 -357.349044) (xy 41.585129 -357.363318) (xy 41.587649 -357.3921) (xy 41.598137 -357.419022)
			(xy 41.615752 -357.441924) (xy 41.63908 -357.458969) (xy 41.666252 -357.468792) (xy 41.680638 -357.470202)
			(xy 41.709316 -357.472582) (xy 41.765527 -357.484891) (xy 41.819252 -357.505501) (xy 41.869274 -357.533943)
			(xy 41.914459 -357.569574) (xy 41.953782 -357.611584) (xy 41.986352 -357.659023) (xy 42.01143 -357.710814)
			(xy 42.028448 -357.765783) (xy 42.037019 -357.822684) (xy 42.037508 -357.851456) (xy 42.037508 -357.872792)
			(xy 42.253916 -358.0892) (xy 47.082202 -358.0892) (xy 47.107184 -358.089843) (xy 47.156189 -358.099579)
			(xy 47.202359 -358.118677) (xy 47.243922 -358.146406) (xy 47.262034 -358.163622) (xy 49.080928 -359.982516)
			(xy 52.937664 -359.982516) (xy 52.962648 -359.983117) (xy 53.011656 -359.992865) (xy 53.057825 -360.011976)
			(xy 53.099386 -360.039716) (xy 53.117496 -360.056938) (xy 54.43093 -361.370372) (xy 54.44815 -361.388484)
			(xy 54.475892 -361.430042) (xy 54.495001 -361.476212) (xy 54.504741 -361.52522) (xy 54.505352 -361.550204)
			(xy 54.505352 -364.480602) (xy 55.378604 -365.3536) (xy 55.49011 -365.3536) (xy 55.505096 -365.338614)
			(xy 55.526715 -365.317783) (xy 55.575243 -365.282446) (xy 55.62871 -365.25515) (xy 55.685793 -365.236568)
			(xy 55.745082 -365.227161) (xy 55.775098 -365.2266) (xy 55.802352 -365.227047) (xy 55.856304 -365.234804)
			(xy 55.908603 -365.25016) (xy 55.958184 -365.272803) (xy 56.004039 -365.302272) (xy 56.045232 -365.337966)
			(xy 56.080927 -365.37916) (xy 56.110396 -365.425014) (xy 56.133039 -365.474595) (xy 56.148395 -365.526894)
			(xy 56.156153 -365.580846) (xy 56.156153 -365.635354) (xy 56.148395 -365.689306) (xy 56.133039 -365.741605)
			(xy 56.110396 -365.791186) (xy 56.080927 -365.83704) (xy 56.045232 -365.878234) (xy 56.004039 -365.913928)
			(xy 55.958184 -365.943397) (xy 55.908603 -365.96604) (xy 55.856304 -365.981396) (xy 55.802352 -365.989153)
			(xy 55.775098 -365.989616) (xy 55.748362 -365.989212) (xy 55.695413 -365.981744) (xy 55.644027 -365.966954)
			(xy 55.595209 -365.945133) (xy 55.549917 -365.916709) (xy 55.509039 -365.882237) (xy 55.490872 -365.862616)
			(xy 55.273194 -365.862616) (xy 55.248197 -365.862001) (xy 55.199172 -365.852193) (xy 55.153001 -365.833014)
			(xy 55.111456 -365.805199) (xy 55.093362 -365.78794) (xy 54.071266 -364.765844) (xy 54.054053 -364.747726)
			(xy 54.026309 -364.70617) (xy 54.007199 -364.660002) (xy 53.997456 -364.610995) (xy 53.996844 -364.586012)
			(xy 53.996844 -361.655614) (xy 52.832254 -360.491024) (xy 48.975518 -360.491024) (xy 48.950535 -360.49039)
			(xy 48.901528 -360.480655) (xy 48.855358 -360.461554) (xy 48.813797 -360.433821) (xy 48.795686 -360.416602)
			(xy 46.976792 -358.597708) (xy 42.148506 -358.597708) (xy 42.123523 -358.597086) (xy 42.074515 -358.587348)
			(xy 42.028345 -358.568244) (xy 41.986784 -358.540507) (xy 41.968674 -358.523286) (xy 41.677844 -358.232456)
			(xy 41.656508 -358.232456) (xy 41.629234 -358.231979) (xy 41.575232 -358.224282) (xy 41.522877 -358.208973)
			(xy 41.473236 -358.186363) (xy 41.427322 -358.156913) (xy 41.386069 -358.121224) (xy 41.350321 -358.080024)
			(xy 41.320804 -358.034153) (xy 41.298122 -357.984545) (xy 41.282736 -357.932212) (xy 41.27496 -357.878222)
			(xy 41.274492 -357.850948) (xy 41.27473 -357.832281) (xy 41.278424 -357.79513) (xy 41.281858 -357.77678)
			(xy 41.284144 -357.762505) (xy 41.28163 -357.733721) (xy 41.271145 -357.706797) (xy 41.25353 -357.683894)
			(xy 41.2302 -357.666849) (xy 41.203027 -357.65703) (xy 41.18864 -357.655622) (xy 41.159985 -357.653254)
			(xy 41.103817 -357.64097) (xy 41.050129 -357.620398) (xy 41.000134 -357.592003) (xy 40.954967 -357.556428)
			(xy 40.915648 -357.514478) (xy 40.88307 -357.467103) (xy 40.857969 -357.415376) (xy 40.840913 -357.360469)
			(xy 40.83229 -357.303624) (xy 40.83177 -357.274876) (xy 39.9691 -357.274876) (xy 39.96944 -357.293926)
			(xy 39.969031 -357.319265) (xy 39.962318 -357.369495) (xy 39.949016 -357.418395) (xy 39.929357 -357.465104)
			(xy 39.903688 -357.508799) (xy 39.87246 -357.548712) (xy 39.854632 -357.566722) (xy 39.845256 -357.576494)
			(xy 39.831545 -357.599837) (xy 39.82444 -357.625959) (xy 39.824439 -357.653031) (xy 39.831541 -357.679154)
			(xy 39.84525 -357.702498) (xy 39.854632 -357.712264) (xy 39.872449 -357.730285) (xy 39.903676 -357.770195)
			(xy 39.929346 -357.813888) (xy 39.949006 -357.860595) (xy 39.962309 -357.909493) (xy 39.969023 -357.959722)
			(xy 39.969319 -357.977694) (xy 40.221914 -357.977694) (xy 40.225985 -357.922072) (xy 40.238111 -357.867635)
			(xy 40.258034 -357.815544) (xy 40.28533 -357.766909) (xy 40.319416 -357.722766) (xy 40.359565 -357.684057)
			(xy 40.404923 -357.651606) (xy 40.454523 -357.626105) (xy 40.507307 -357.608098) (xy 40.56215 -357.597968)
			(xy 40.617884 -357.595931) (xy 40.673321 -357.602031) (xy 40.727278 -357.616137) (xy 40.778607 -357.637949)
			(xy 40.826213 -357.667003) (xy 40.869081 -357.702678) (xy 40.906298 -357.744215) (xy 40.937071 -357.790728)
			(xy 40.960743 -357.841225) (xy 40.976811 -357.894632) (xy 40.984931 -357.949808) (xy 40.98544 -357.977694)
			(xy 40.984931 -358.00558) (xy 40.976811 -358.060756) (xy 40.960743 -358.114163) (xy 40.937071 -358.16466)
			(xy 40.906298 -358.211173) (xy 40.869081 -358.25271) (xy 40.826213 -358.288385) (xy 40.778607 -358.317439)
			(xy 40.727278 -358.339251) (xy 40.673321 -358.353357) (xy 40.617884 -358.359457) (xy 40.56215 -358.35742)
			(xy 40.507307 -358.34729) (xy 40.454523 -358.329283) (xy 40.404923 -358.303782) (xy 40.359565 -358.271331)
			(xy 40.319416 -358.232622) (xy 40.28533 -358.188479) (xy 40.258034 -358.139844) (xy 40.238111 -358.087753)
			(xy 40.225985 -358.033316) (xy 40.221914 -357.977694) (xy 39.969319 -357.977694) (xy 39.96944 -357.98506)
			(xy 39.968954 -358.012311) (xy 39.961198 -358.066259) (xy 39.945843 -358.118554) (xy 39.923201 -358.168131)
			(xy 39.893735 -358.213981) (xy 39.858044 -358.255172) (xy 39.816853 -358.290863) (xy 39.771003 -358.320329)
			(xy 39.721426 -358.342971) (xy 39.669131 -358.358326) (xy 39.615183 -358.366082) (xy 39.560681 -358.366082)
			(xy 39.506733 -358.358326) (xy 39.454438 -358.342971) (xy 39.404861 -358.320329) (xy 39.359011 -358.290863)
			(xy 39.31782 -358.255172) (xy 39.282129 -358.213981) (xy 39.252663 -358.168131) (xy 39.230021 -358.118554)
			(xy 39.214666 -358.066259) (xy 39.20691 -358.012311) (xy 39.206424 -357.98506) (xy 35.725608 -357.98506)
			(xy 35.725608 -361.049316) (xy 38.985952 -361.049316) (xy 38.986493 -361.022067) (xy 38.994246 -360.968123)
			(xy 39.009597 -360.915832) (xy 39.032234 -360.866258) (xy 39.061695 -360.820409) (xy 39.09738 -360.77922)
			(xy 39.138564 -360.743528) (xy 39.184409 -360.714061) (xy 39.23398 -360.691417) (xy 39.286269 -360.676058)
			(xy 39.340211 -360.668297) (xy 39.36746 -360.667808) (xy 39.394829 -360.668296) (xy 39.449008 -360.676108)
			(xy 39.501511 -360.691592) (xy 39.551258 -360.714429) (xy 39.597226 -360.744149) (xy 39.618158 -360.761788)
			(xy 39.629486 -360.771024) (xy 39.656043 -360.7832) (xy 39.68496 -360.787373) (xy 39.713877 -360.7832)
			(xy 39.740434 -360.771024) (xy 39.751762 -360.761788) (xy 39.772696 -360.744151) (xy 39.818668 -360.71444)
			(xy 39.868416 -360.691603) (xy 39.920916 -360.676112) (xy 39.975091 -360.668283) (xy 40.00246 -360.667808)
			(xy 40.031376 -360.668352) (xy 40.088546 -360.677075) (xy 40.143745 -360.694328) (xy 40.195706 -360.719715)
			(xy 40.243241 -360.752654) (xy 40.285259 -360.792391) (xy 40.30345 -360.814874) (xy 40.313347 -360.826679)
			(xy 40.338671 -360.844198) (xy 40.368064 -360.853374) (xy 40.398856 -360.853374) (xy 40.428249 -360.844198)
			(xy 40.453573 -360.826679) (xy 40.46347 -360.814874) (xy 40.481671 -360.792399) (xy 40.52369 -360.752665)
			(xy 40.571223 -360.719726) (xy 40.623182 -360.694336) (xy 40.678377 -360.677077) (xy 40.735545 -360.668345)
			(xy 40.76446 -360.667808) (xy 40.791713 -360.668293) (xy 40.845664 -360.676045) (xy 40.897962 -360.691396)
			(xy 40.947543 -360.714035) (xy 40.993397 -360.743501) (xy 41.034591 -360.779192) (xy 41.070285 -360.820384)
			(xy 41.099753 -360.866236) (xy 41.122395 -360.915815) (xy 41.13775 -360.968113) (xy 41.145506 -361.022063)
			(xy 41.145968 -361.049316) (xy 41.145407 -361.078446) (xy 41.136539 -361.136027) (xy 41.119011 -361.191589)
			(xy 41.093232 -361.243835) (xy 41.059802 -361.29155) (xy 41.04005 -361.312968) (xy 41.031213 -361.322807)
			(xy 41.018431 -361.345945) (xy 41.012034 -361.371593) (xy 41.012456 -361.398024) (xy 41.019666 -361.423456)
			(xy 41.033179 -361.446175) (xy 41.042336 -361.455716) (xy 41.063488 -361.477374) (xy 41.089422 -361.512612)
			(xy 44.706032 -361.512612) (xy 44.706601 -361.483444) (xy 44.715499 -361.425789) (xy 44.733074 -361.370162)
			(xy 44.758916 -361.317861) (xy 44.792423 -361.270106) (xy 44.832811 -361.228011) (xy 44.855638 -361.209844)
			(xy 44.866037 -361.201446) (xy 44.882331 -361.180263) (xy 44.892574 -361.155579) (xy 44.896065 -361.129083)
			(xy 44.892565 -361.102588) (xy 44.882314 -361.077908) (xy 44.866013 -361.05673) (xy 44.855638 -361.0483)
			(xy 44.832794 -361.03015) (xy 44.792392 -360.988061) (xy 44.758878 -360.940306) (xy 44.733034 -360.888)
			(xy 44.715466 -360.832365) (xy 44.706583 -360.774703) (xy 44.706032 -360.745532) (xy 44.706485 -360.718278)
			(xy 44.714239 -360.664325) (xy 44.729593 -360.612024) (xy 44.752235 -360.562442) (xy 44.781703 -360.516586)
			(xy 44.817398 -360.475392) (xy 44.858593 -360.439698) (xy 44.904449 -360.410231) (xy 44.954032 -360.38759)
			(xy 45.006333 -360.372237) (xy 45.060286 -360.364485) (xy 45.08754 -360.364024) (xy 45.116456 -360.364576)
			(xy 45.173626 -360.373297) (xy 45.228824 -360.390547) (xy 45.280786 -360.415933) (xy 45.328321 -360.448871)
			(xy 45.370339 -360.488607) (xy 45.38853 -360.51109) (xy 45.398427 -360.522895) (xy 45.423751 -360.540414)
			(xy 45.453144 -360.54959) (xy 45.483936 -360.54959) (xy 45.513329 -360.540414) (xy 45.538653 -360.522895)
			(xy 45.54855 -360.51109) (xy 45.566767 -360.488628) (xy 45.608781 -360.448892) (xy 45.656311 -360.415951)
			(xy 45.708267 -360.390559) (xy 45.76346 -360.373298) (xy 45.820626 -360.364563) (xy 45.84954 -360.364024)
			(xy 45.878086 -360.364584) (xy 45.934539 -360.373094) (xy 45.989094 -360.389919) (xy 46.040535 -360.414683)
			(xy 46.064424 -360.430318) (xy 46.075556 -360.4374) (xy 46.100412 -360.446212) (xy 46.126699 -360.448341)
			(xy 46.152649 -360.443643) (xy 46.176521 -360.432435) (xy 46.196711 -360.415469) (xy 46.204632 -360.404918)
			(xy 46.22004 -360.383903) (xy 46.255641 -360.345851) (xy 46.296087 -360.312995) (xy 46.340626 -360.285946)
			(xy 46.38843 -360.265206) (xy 46.438611 -360.251161) (xy 46.490235 -360.244072) (xy 46.51629 -360.243628)
			(xy 46.545207 -360.244143) (xy 46.602379 -360.252871) (xy 46.657578 -360.270129) (xy 46.70954 -360.295521)
			(xy 46.757074 -360.328466) (xy 46.79909 -360.368208) (xy 46.81728 -360.390694) (xy 46.827177 -360.402499)
			(xy 46.852501 -360.420018) (xy 46.881894 -360.429194) (xy 46.912686 -360.429194) (xy 46.942079 -360.420018)
			(xy 46.967403 -360.402499) (xy 46.9773 -360.390694) (xy 46.995489 -360.368209) (xy 47.03751 -360.328474)
			(xy 47.085045 -360.295536) (xy 47.137007 -360.270148) (xy 47.192204 -360.252892) (xy 47.249374 -360.244163)
			(xy 47.27829 -360.243628) (xy 47.305544 -360.244065) (xy 47.359498 -360.251821) (xy 47.411799 -360.267178)
			(xy 47.461381 -360.289822) (xy 47.507236 -360.319292) (xy 47.54843 -360.354989) (xy 47.584123 -360.396185)
			(xy 47.613591 -360.442042) (xy 47.636231 -360.491626) (xy 47.651584 -360.543927) (xy 47.659337 -360.597882)
			(xy 47.659798 -360.625136) (xy 47.659322 -360.651178) (xy 47.652244 -360.702778) (xy 47.638212 -360.752936)
			(xy 47.617485 -360.800718) (xy 47.59045 -360.845235) (xy 47.557609 -360.88566) (xy 47.538894 -360.903774)
			(xy 47.528968 -360.91375) (xy 47.514501 -360.937875) (xy 47.507156 -360.965029) (xy 47.507487 -360.993157)
			(xy 47.515471 -361.020131) (xy 47.530501 -361.043909) (xy 47.540672 -361.053634) (xy 47.56026 -361.07179)
			(xy 47.59465 -361.112652) (xy 47.623006 -361.157912) (xy 47.644772 -361.206684) (xy 47.659523 -361.258015)
			(xy 47.666971 -361.310902) (xy 47.667418 -361.337606) (xy 47.66692 -361.365376) (xy 47.658866 -361.420328)
			(xy 47.64293 -361.473533) (xy 47.619447 -361.523864) (xy 47.588915 -361.570258) (xy 47.551979 -361.611735)
			(xy 47.53102 -361.62996) (xy 47.520368 -361.639481) (xy 47.504384 -361.663145) (xy 47.495592 -361.690314)
			(xy 47.494682 -361.718856) (xy 47.501726 -361.74653) (xy 47.516171 -361.771164) (xy 47.526194 -361.781344)
			(xy 47.544559 -361.799414) (xy 47.576728 -361.839658) (xy 47.603195 -361.883862) (xy 47.623477 -361.931223)
			(xy 47.637207 -361.980882) (xy 47.644135 -362.031935) (xy 47.644558 -362.057696) (xy 47.6441 -362.085067)
			(xy 47.636282 -362.139246) (xy 47.620791 -362.19175) (xy 47.597948 -362.241497) (xy 47.568221 -362.287463)
			(xy 47.550578 -362.308394) (xy 47.541347 -362.319725) (xy 47.529172 -362.346282) (xy 47.524999 -362.375197)
			(xy 47.52917 -362.404112) (xy 47.541343 -362.43067) (xy 47.550578 -362.441998) (xy 47.568215 -362.462934)
			(xy 47.597939 -362.508901) (xy 47.620784 -362.558647) (xy 47.636281 -362.611149) (xy 47.64411 -362.665327)
			(xy 47.64411 -362.720067) (xy 47.636282 -362.774245) (xy 47.620787 -362.826747) (xy 47.597942 -362.876493)
			(xy 47.568218 -362.922461) (xy 47.550578 -362.943394) (xy 47.541347 -362.954725) (xy 47.529172 -362.981282)
			(xy 47.524999 -363.010197) (xy 47.52917 -363.039112) (xy 47.541343 -363.06567) (xy 47.550578 -363.076998)
			(xy 47.568215 -363.097934) (xy 47.597939 -363.143901) (xy 47.620784 -363.193647) (xy 47.636281 -363.246149)
			(xy 47.63987 -363.270984) (xy 48.72126 -363.270984) (xy 48.72126 -363.186288) (xy 48.729311 -363.101974)
			(xy 48.74534 -363.018808) (xy 48.769201 -362.937541) (xy 48.80068 -362.858911) (xy 48.839491 -362.78363)
			(xy 48.885281 -362.712378) (xy 48.937637 -362.645802) (xy 48.996085 -362.584504) (xy 49.060095 -362.529039)
			(xy 49.129087 -362.47991) (xy 49.202437 -362.437561) (xy 49.27948 -362.402377) (xy 49.359519 -362.374675)
			(xy 49.441828 -362.354707) (xy 49.525663 -362.342654) (xy 49.610264 -362.338624) (xy 49.694865 -362.342654)
			(xy 49.7787 -362.354707) (xy 49.861009 -362.374675) (xy 49.941048 -362.402377) (xy 50.018091 -362.437561)
			(xy 50.091441 -362.47991) (xy 50.160433 -362.529039) (xy 50.224443 -362.584504) (xy 50.282891 -362.645802)
			(xy 50.335247 -362.712378) (xy 50.381037 -362.78363) (xy 50.419848 -362.858911) (xy 50.451327 -362.937541)
			(xy 50.475188 -363.018808) (xy 50.491217 -363.101974) (xy 50.499268 -363.186288) (xy 50.499772 -363.228636)
			(xy 51.245773 -363.228636) (xy 51.249809 -363.145189) (xy 51.261881 -363.062521) (xy 51.281874 -362.981404)
			(xy 51.309603 -362.902595) (xy 51.344809 -362.82683) (xy 51.387163 -362.754817) (xy 51.436269 -362.687228)
			(xy 51.49167 -362.624694) (xy 51.552847 -362.567799) (xy 51.61923 -362.517073) (xy 51.690198 -362.472992)
			(xy 51.76509 -362.435966) (xy 51.843206 -362.40634) (xy 51.923816 -362.384392) (xy 52.006168 -362.370327)
			(xy 52.089494 -362.364275) (xy 52.173014 -362.366294) (xy 52.25595 -362.376364) (xy 52.337526 -362.394392)
			(xy 52.416982 -362.420209) (xy 52.493575 -362.453574) (xy 52.566591 -362.494175) (xy 52.635347 -362.541634)
			(xy 52.699201 -362.595507) (xy 52.757558 -362.655292) (xy 52.809873 -362.720429) (xy 52.855656 -362.790312)
			(xy 52.894481 -362.864287) (xy 52.925986 -362.941664) (xy 52.949875 -363.021721) (xy 52.965926 -363.103709)
			(xy 52.973989 -363.186864) (xy 52.974494 -363.228636) (xy 52.973989 -363.270408) (xy 52.965926 -363.353563)
			(xy 52.949875 -363.435551) (xy 52.925986 -363.515608) (xy 52.894481 -363.592985) (xy 52.855656 -363.66696)
			(xy 52.809873 -363.736843) (xy 52.757558 -363.80198) (xy 52.699201 -363.861765) (xy 52.635347 -363.915638)
			(xy 52.566591 -363.963097) (xy 52.493575 -364.003698) (xy 52.416982 -364.037063) (xy 52.337526 -364.06288)
			(xy 52.25595 -364.080908) (xy 52.173014 -364.090978) (xy 52.089494 -364.092997) (xy 52.006168 -364.086945)
			(xy 51.923816 -364.07288) (xy 51.843206 -364.050932) (xy 51.76509 -364.021306) (xy 51.690198 -363.98428)
			(xy 51.61923 -363.940199) (xy 51.552847 -363.889473) (xy 51.49167 -363.832578) (xy 51.436269 -363.770044)
			(xy 51.387163 -363.702455) (xy 51.344809 -363.630442) (xy 51.309603 -363.554677) (xy 51.281874 -363.475868)
			(xy 51.261881 -363.394751) (xy 51.249809 -363.312083) (xy 51.245773 -363.228636) (xy 50.499772 -363.228636)
			(xy 50.499268 -363.270984) (xy 50.491217 -363.355298) (xy 50.475188 -363.438464) (xy 50.451327 -363.519731)
			(xy 50.419848 -363.598361) (xy 50.381037 -363.673642) (xy 50.335247 -363.744894) (xy 50.282891 -363.81147)
			(xy 50.224443 -363.872768) (xy 50.160433 -363.928233) (xy 50.091441 -363.977362) (xy 50.018091 -364.019711)
			(xy 49.941048 -364.054895) (xy 49.861009 -364.082597) (xy 49.7787 -364.102565) (xy 49.694865 -364.114618)
			(xy 49.610264 -364.118649) (xy 49.525663 -364.114618) (xy 49.441828 -364.102565) (xy 49.359519 -364.082597)
			(xy 49.27948 -364.054895) (xy 49.202437 -364.019711) (xy 49.129087 -363.977362) (xy 49.060095 -363.928233)
			(xy 48.996085 -363.872768) (xy 48.937637 -363.81147) (xy 48.885281 -363.744894) (xy 48.839491 -363.673642)
			(xy 48.80068 -363.598361) (xy 48.769201 -363.519731) (xy 48.74534 -363.438464) (xy 48.729311 -363.355298)
			(xy 48.72126 -363.270984) (xy 47.63987 -363.270984) (xy 47.64411 -363.300327) (xy 47.64411 -363.355067)
			(xy 47.636282 -363.409245) (xy 47.620787 -363.461747) (xy 47.597942 -363.511493) (xy 47.568218 -363.557461)
			(xy 47.550578 -363.578394) (xy 47.541347 -363.589725) (xy 47.529172 -363.616282) (xy 47.524999 -363.645197)
			(xy 47.52917 -363.674112) (xy 47.541343 -363.70067) (xy 47.550578 -363.711998) (xy 47.568226 -363.732923)
			(xy 47.597937 -363.778897) (xy 47.620772 -363.828647) (xy 47.636261 -363.881149) (xy 47.644086 -363.935326)
			(xy 47.644558 -363.962696) (xy 47.644141 -363.989951) (xy 47.636383 -364.043906) (xy 47.621025 -364.096208)
			(xy 47.598379 -364.145791) (xy 47.568907 -364.191647) (xy 47.533208 -364.232841) (xy 47.49201 -364.268535)
			(xy 47.446151 -364.298001) (xy 47.396565 -364.320641) (xy 47.344261 -364.335993) (xy 47.290305 -364.343744)
			(xy 47.26305 -364.344204) (xy 47.234133 -364.343686) (xy 47.17696 -364.334962) (xy 47.121759 -364.317706)
			(xy 47.069797 -364.292315) (xy 47.022263 -364.259369) (xy 46.980249 -364.219625) (xy 46.96206 -364.197138)
			(xy 46.952163 -364.185333) (xy 46.926839 -364.167814) (xy 46.897446 -364.158638) (xy 46.866654 -364.158638)
			(xy 46.837261 -364.167814) (xy 46.811937 -364.185333) (xy 46.80204 -364.197138) (xy 46.783836 -364.21961)
			(xy 46.741818 -364.259344) (xy 46.694285 -364.292284) (xy 46.642327 -364.317674) (xy 46.587132 -364.334933)
			(xy 46.529965 -364.343666) (xy 46.50105 -364.344204) (xy 46.473798 -364.343698) (xy 46.419849 -364.335948)
			(xy 46.367551 -364.320598) (xy 46.317971 -364.297961) (xy 46.272117 -364.268498) (xy 46.230924 -364.232808)
			(xy 46.19523 -364.191619) (xy 46.165761 -364.145769) (xy 46.143118 -364.096192) (xy 46.127762 -364.043896)
			(xy 46.120005 -363.989948) (xy 46.119542 -363.962696) (xy 46.119995 -363.935325) (xy 46.127815 -363.881145)
			(xy 46.143306 -363.828642) (xy 46.166151 -363.778895) (xy 46.195879 -363.732929) (xy 46.213522 -363.711998)
			(xy 46.222761 -363.700673) (xy 46.234935 -363.674114) (xy 46.239106 -363.645197) (xy 46.234933 -363.61628)
			(xy 46.222758 -363.589722) (xy 46.213522 -363.578394) (xy 46.195878 -363.557464) (xy 46.166153 -363.511496)
			(xy 46.143309 -363.461749) (xy 46.127813 -363.409247) (xy 46.119985 -363.355068) (xy 46.119985 -363.300326)
			(xy 46.127814 -363.246148) (xy 46.143311 -363.193645) (xy 46.166156 -363.143899) (xy 46.195881 -363.097931)
			(xy 46.213522 -363.076998) (xy 46.222761 -363.065673) (xy 46.234935 -363.039114) (xy 46.239106 -363.010197)
			(xy 46.234933 -362.98128) (xy 46.222758 -362.954722) (xy 46.213522 -362.943394) (xy 46.195878 -362.922464)
			(xy 46.166153 -362.876496) (xy 46.143309 -362.826749) (xy 46.127813 -362.774247) (xy 46.119985 -362.720068)
			(xy 46.119985 -362.665326) (xy 46.127814 -362.611148) (xy 46.143311 -362.558645) (xy 46.166156 -362.508899)
			(xy 46.195881 -362.462931) (xy 46.213522 -362.441998) (xy 46.222761 -362.430673) (xy 46.234935 -362.404114)
			(xy 46.239106 -362.375197) (xy 46.234933 -362.34628) (xy 46.222758 -362.319722) (xy 46.213522 -362.308394)
			(xy 46.19587 -362.287472) (xy 46.166159 -362.241497) (xy 46.143326 -362.191747) (xy 46.127838 -362.139244)
			(xy 46.120014 -362.085066) (xy 46.119542 -362.057696) (xy 46.119779 -362.038641) (xy 46.123595 -362.000723)
			(xy 46.127162 -361.982004) (xy 46.129464 -361.968526) (xy 46.127624 -361.941254) (xy 46.118615 -361.915448)
			(xy 46.103081 -361.892958) (xy 46.082137 -361.875395) (xy 46.057284 -361.864018) (xy 46.030303 -361.859643)
			(xy 46.003128 -361.862584) (xy 45.990256 -361.867196) (xy 45.967794 -361.875742) (xy 45.921251 -361.887724)
			(xy 45.87357 -361.893759) (xy 45.84954 -361.89412) (xy 45.820623 -361.893603) (xy 45.76345 -361.884878)
			(xy 45.70825 -361.867622) (xy 45.656288 -361.84223) (xy 45.608754 -361.809285) (xy 45.566739 -361.769541)
			(xy 45.54855 -361.747054) (xy 45.538653 -361.735249) (xy 45.513329 -361.71773) (xy 45.483936 -361.708554)
			(xy 45.453144 -361.708554) (xy 45.423751 -361.71773) (xy 45.398427 -361.735249) (xy 45.38853 -361.747054)
			(xy 45.370336 -361.769534) (xy 45.328315 -361.809267) (xy 45.28078 -361.842205) (xy 45.22882 -361.867593)
			(xy 45.173624 -361.884851) (xy 45.116456 -361.893583) (xy 45.08754 -361.89412) (xy 45.060289 -361.893608)
			(xy 45.00634 -361.885856) (xy 44.954044 -361.870506) (xy 44.904465 -361.847869) (xy 44.858612 -361.818406)
			(xy 44.817419 -361.782718) (xy 44.781725 -361.74153) (xy 44.752256 -361.695681) (xy 44.729612 -361.646105)
			(xy 44.714255 -361.593811) (xy 44.706496 -361.539863) (xy 44.706032 -361.512612) (xy 41.089422 -361.512612)
			(xy 41.09937 -361.526129) (xy 41.127101 -361.579939) (xy 41.145985 -361.637453) (xy 41.155547 -361.697228)
			(xy 41.156128 -361.727496) (xy 41.155677 -361.754867) (xy 41.147858 -361.809047) (xy 41.132367 -361.861551)
			(xy 41.109521 -361.911298) (xy 41.079792 -361.957264) (xy 41.062148 -361.978194) (xy 41.052919 -361.989526)
			(xy 41.040748 -362.016083) (xy 41.036577 -362.044997) (xy 41.040746 -362.073911) (xy 41.052916 -362.100469)
			(xy 41.062148 -362.111798) (xy 41.079786 -362.132733) (xy 41.109513 -362.1787) (xy 41.13236 -362.228446)
			(xy 41.147857 -362.280948) (xy 41.155687 -362.335126) (xy 41.155687 -362.389868) (xy 41.147859 -362.444046)
			(xy 41.132362 -362.496549) (xy 41.109516 -362.546295) (xy 41.079789 -362.592262) (xy 41.062148 -362.613194)
			(xy 41.052919 -362.624526) (xy 41.040748 -362.651083) (xy 41.036577 -362.679997) (xy 41.040746 -362.708911)
			(xy 41.052916 -362.735469) (xy 41.062148 -362.746798) (xy 41.079792 -362.767727) (xy 41.109504 -362.8137)
			(xy 41.13234 -362.863448) (xy 41.14783 -362.91595) (xy 41.155656 -362.970126) (xy 41.156128 -362.997496)
			(xy 41.155634 -363.026414) (xy 41.146904 -363.083588) (xy 41.129643 -363.138788) (xy 41.104247 -363.19075)
			(xy 41.071298 -363.238283) (xy 41.031551 -363.280298) (xy 41.009062 -363.298486) (xy 40.997256 -363.308385)
			(xy 40.97973 -363.333706) (xy 40.970549 -363.3631) (xy 40.970548 -363.393895) (xy 40.979728 -363.42329)
			(xy 40.997253 -363.448611) (xy 41.009062 -363.458506) (xy 41.02984 -363.475265) (xy 41.066968 -363.513618)
			(xy 41.098388 -363.556773) (xy 41.123486 -363.603885) (xy 41.141771 -363.654037) (xy 41.152887 -363.706247)
			(xy 41.156617 -363.759498) (xy 41.152888 -363.812748) (xy 41.141773 -363.864959) (xy 41.123488 -363.91511)
			(xy 41.098391 -363.962223) (xy 41.066972 -364.005378) (xy 41.029844 -364.043732) (xy 41.009062 -364.060486)
			(xy 40.997256 -364.070385) (xy 40.97973 -364.095706) (xy 40.970549 -364.1251) (xy 40.970548 -364.155895)
			(xy 40.979728 -364.18529) (xy 40.997253 -364.210611) (xy 41.009062 -364.220506) (xy 41.03154 -364.238703)
			(xy 41.071278 -364.280721) (xy 41.104218 -364.328254) (xy 41.129608 -364.380214) (xy 41.146865 -364.435411)
			(xy 41.155593 -364.49258) (xy 41.156128 -364.521496) (xy 41.155566 -364.550626) (xy 41.146699 -364.608208)
			(xy 41.129172 -364.66377) (xy 41.103393 -364.716016) (xy 41.069963 -364.763731) (xy 41.05021 -364.785148)
			(xy 41.039828 -364.796775) (xy 41.026037 -364.824712) (xy 41.021295 -364.855504) (xy 41.02604 -364.886296)
			(xy 41.039833 -364.914232) (xy 41.05021 -364.925864) (xy 41.069921 -364.947315) (xy 41.10333 -364.995035)
			(xy 41.129104 -365.047275) (xy 41.146646 -365.102823) (xy 41.15555 -365.16039) (xy 41.156128 -365.189516)
			(xy 41.155637 -365.216767) (xy 41.147879 -365.270713) (xy 41.132523 -365.323007) (xy 41.109881 -365.372583)
			(xy 41.080415 -365.418432) (xy 41.044724 -365.459622) (xy 41.003535 -365.495313) (xy 40.957686 -365.524779)
			(xy 40.90811 -365.547421) (xy 40.855817 -365.562778) (xy 40.801871 -365.570537) (xy 40.77462 -365.571024)
			(xy 40.745702 -365.57052) (xy 40.688529 -365.561792) (xy 40.633329 -365.544533) (xy 40.581366 -365.519139)
			(xy 40.533833 -365.486192) (xy 40.491818 -365.446446) (xy 40.47363 -365.423958) (xy 40.463733 -365.412153)
			(xy 40.438409 -365.394634) (xy 40.409016 -365.385458) (xy 40.378224 -365.385458) (xy 40.348831 -365.394634)
			(xy 40.323507 -365.412153) (xy 40.31361 -365.423958) (xy 40.295403 -365.446428) (xy 40.253388 -365.486166)
			(xy 40.205856 -365.519108) (xy 40.153898 -365.544499) (xy 40.098703 -365.561757) (xy 40.041535 -365.570488)
			(xy 40.01262 -365.571024) (xy 39.985249 -365.570565) (xy 39.931069 -365.562748) (xy 39.878565 -365.547258)
			(xy 39.828818 -365.524415) (xy 39.782853 -365.494687) (xy 39.761922 -365.477044) (xy 39.750594 -365.467808)
			(xy 39.724037 -365.455632) (xy 39.69512 -365.451459) (xy 39.666203 -365.455632) (xy 39.639646 -365.467808)
			(xy 39.628318 -365.477044) (xy 39.607396 -365.494695) (xy 39.56142 -365.524404) (xy 39.51167 -365.547237)
			(xy 39.459167 -365.562725) (xy 39.40499 -365.570551) (xy 39.37762 -365.571024) (xy 39.350368 -365.570526)
			(xy 39.29642 -365.562772) (xy 39.244123 -365.54742) (xy 39.194544 -365.524781) (xy 39.148692 -365.495316)
			(xy 39.107499 -365.459626) (xy 39.071805 -365.418437) (xy 39.042337 -365.372587) (xy 39.019693 -365.32301)
			(xy 39.004335 -365.270716) (xy 38.996576 -365.216768) (xy 38.996112 -365.189516) (xy 38.996698 -365.160387)
			(xy 39.005561 -365.102807) (xy 39.023083 -365.047246) (xy 39.048857 -364.994999) (xy 39.082281 -364.947283)
			(xy 39.10203 -364.925864) (xy 39.112397 -364.914226) (xy 39.126184 -364.886292) (xy 39.130927 -364.855504)
			(xy 39.126186 -364.824716) (xy 39.112402 -364.796781) (xy 39.10203 -364.785148) (xy 39.082267 -364.763743)
			(xy 39.048868 -364.71601) (xy 39.023104 -364.663758) (xy 39.005574 -364.6082) (xy 38.996683 -364.550625)
			(xy 38.996112 -364.521496) (xy 38.996623 -364.492579) (xy 39.005353 -364.435407) (xy 39.022612 -364.380208)
			(xy 39.048005 -364.328246) (xy 39.08095 -364.280713) (xy 39.120692 -364.238696) (xy 39.143178 -364.220506)
			(xy 39.154988 -364.210613) (xy 39.172507 -364.185289) (xy 39.181683 -364.155894) (xy 39.181682 -364.125101)
			(xy 39.172505 -364.095707) (xy 39.154984 -364.070383) (xy 39.143178 -364.060486) (xy 39.12239 -364.043738)
			(xy 39.085258 -364.005385) (xy 39.053835 -363.96223) (xy 39.028735 -363.915116) (xy 39.010448 -363.864963)
			(xy 38.999331 -363.81275) (xy 38.995601 -363.759498) (xy 38.999331 -363.706245) (xy 39.010449 -363.654032)
			(xy 39.028737 -363.60388) (xy 39.053838 -363.556766) (xy 39.085261 -363.513611) (xy 39.122394 -363.475259)
			(xy 39.143178 -363.458506) (xy 39.154988 -363.448613) (xy 39.172507 -363.423289) (xy 39.181683 -363.393894)
			(xy 39.181682 -363.363101) (xy 39.172505 -363.333707) (xy 39.154984 -363.308383) (xy 39.143178 -363.298486)
			(xy 39.120683 -363.280308) (xy 39.08095 -363.238285) (xy 39.048013 -363.190747) (xy 39.022626 -363.138784)
			(xy 39.005372 -363.083584) (xy 38.996646 -363.026413) (xy 38.996112 -362.997496) (xy 38.996573 -362.970126)
			(xy 39.004391 -362.915946) (xy 39.019882 -362.863443) (xy 39.042725 -362.813696) (xy 39.07245 -362.767729)
			(xy 39.090092 -362.746798) (xy 39.099333 -362.735474) (xy 39.111511 -362.708915) (xy 39.115683 -362.679997)
			(xy 39.11151 -362.651079) (xy 39.09933 -362.624521) (xy 39.090092 -362.613194) (xy 39.072449 -362.592264)
			(xy 39.042727 -362.546295) (xy 39.019884 -362.496548) (xy 39.004389 -362.444046) (xy 38.996562 -362.389867)
			(xy 38.996562 -362.335127) (xy 39.004391 -362.280948) (xy 39.019886 -362.228447) (xy 39.04273 -362.1787)
			(xy 39.072452 -362.132731) (xy 39.090092 -362.111798) (xy 39.099333 -362.100474) (xy 39.111511 -362.073915)
			(xy 39.115683 -362.044997) (xy 39.11151 -362.016079) (xy 39.09933 -361.989521) (xy 39.090092 -361.978194)
			(xy 39.072435 -361.957276) (xy 39.042726 -361.911299) (xy 39.019894 -361.861548) (xy 39.004407 -361.809044)
			(xy 38.996584 -361.754866) (xy 38.996112 -361.727496) (xy 38.996686 -361.698366) (xy 39.005552 -361.640786)
			(xy 39.023077 -361.585225) (xy 39.048853 -361.532978) (xy 39.08228 -361.485263) (xy 39.10203 -361.463844)
			(xy 39.110857 -361.453996) (xy 39.123643 -361.430861) (xy 39.130042 -361.405215) (xy 39.129623 -361.378785)
			(xy 39.122414 -361.353354) (xy 39.108901 -361.330636) (xy 39.099744 -361.321096) (xy 39.078595 -361.299436)
			(xy 39.042713 -361.250681) (xy 39.014981 -361.196872) (xy 38.996097 -361.139358) (xy 38.986534 -361.079583)
			(xy 38.985952 -361.049316) (xy 35.725608 -361.049316) (xy 35.725608 -365.592614) (xy 35.984989 -365.851948)
			(xy 41.654982 -365.851948) (xy 41.659053 -365.796326) (xy 41.671179 -365.741889) (xy 41.691102 -365.689798)
			(xy 41.718398 -365.641163) (xy 41.752484 -365.59702) (xy 41.792633 -365.558311) (xy 41.837991 -365.52586)
			(xy 41.887591 -365.500359) (xy 41.940375 -365.482352) (xy 41.995218 -365.472222) (xy 42.050952 -365.470185)
			(xy 42.106389 -365.476285) (xy 42.160346 -365.490391) (xy 42.211675 -365.512203) (xy 42.259281 -365.541257)
			(xy 42.302149 -365.576932) (xy 42.339366 -365.618469) (xy 42.370139 -365.664982) (xy 42.393811 -365.715479)
			(xy 42.409879 -365.768886) (xy 42.417999 -365.824062) (xy 42.418508 -365.851948) (xy 42.417999 -365.879834)
			(xy 42.409879 -365.93501) (xy 42.393811 -365.988417) (xy 42.370139 -366.038914) (xy 42.339366 -366.085427)
			(xy 42.302149 -366.126964) (xy 42.259281 -366.162639) (xy 42.211675 -366.191693) (xy 42.160346 -366.213505)
			(xy 42.106389 -366.227611) (xy 42.050952 -366.233711) (xy 41.995218 -366.231674) (xy 41.940375 -366.221544)
			(xy 41.887591 -366.203537) (xy 41.837991 -366.178036) (xy 41.792633 -366.145585) (xy 41.752484 -366.106876)
			(xy 41.718398 -366.062733) (xy 41.691102 -366.014098) (xy 41.671179 -365.962007) (xy 41.659053 -365.90757)
			(xy 41.654982 -365.851948) (xy 35.984989 -365.851948) (xy 37.140896 -367.007648) (xy 55.41391 -367.007648)
		)
		(stroke
			(width 0)
			(type solid)
		)
		(fill yes)
		(layer "In2.Cu")
		(net "GND")
	)
	(gr_poly
		(pts
			(xy 304.02022 -381.185928) (xy 304.02022 -366.45596) (xy 304.004957 -366.435563) (xy 303.97994 -366.391185)
			(xy 303.961677 -366.343628) (xy 303.950559 -366.293913) (xy 303.946826 -366.243106) (xy 303.950557 -366.1923)
			(xy 303.961673 -366.142584) (xy 303.979935 -366.095026) (xy 304.00495 -366.050648) (xy 304.02022 -366.030256)
			(xy 304.02022 -364.185708) (xy 303.999025 -364.170656) (xy 303.960934 -364.135283) (xy 303.928537 -364.09463)
			(xy 303.902557 -364.049605) (xy 303.883575 -364.001212) (xy 303.872015 -363.950531) (xy 303.868133 -363.898693)
			(xy 303.872017 -363.846856) (xy 303.883579 -363.796175) (xy 303.902563 -363.747783) (xy 303.928544 -363.702759)
			(xy 303.960943 -363.662107) (xy 303.999036 -363.626736) (xy 304.02022 -363.611668) (xy 304.02022 -359.668318)
			(xy 302.380142 -345.77782) (xy 302.028352 -343.781634) (xy 302.021249 -343.739063) (xy 302.013615 -343.653087)
			(xy 302.013112 -343.60993) (xy 302.013112 -341.599012) (xy 301.555404 -337.888072) (xy 301.08652 -337.419188)
			(xy 301.08652 -335.443068) (xy 299.3644 -333.720948) (xy 271.8562 -333.720948) (xy 270.383 -335.194148)
			(xy 270.383 -344.7427) (xy 286.410396 -344.7427) (xy 286.410396 -344.658004) (xy 286.418447 -344.57369)
			(xy 286.434476 -344.490524) (xy 286.458337 -344.409257) (xy 286.489816 -344.330627) (xy 286.528627 -344.255346)
			(xy 286.574417 -344.184094) (xy 286.626773 -344.117518) (xy 286.685221 -344.05622) (xy 286.749231 -344.000755)
			(xy 286.818223 -343.951626) (xy 286.891573 -343.909277) (xy 286.968616 -343.874093) (xy 287.048655 -343.846391)
			(xy 287.130964 -343.826423) (xy 287.214799 -343.81437) (xy 287.2994 -343.81034) (xy 287.384001 -343.81437)
			(xy 287.467836 -343.826423) (xy 287.550145 -343.846391) (xy 287.630184 -343.874093) (xy 287.707227 -343.909277)
			(xy 287.780577 -343.951626) (xy 287.849569 -344.000755) (xy 287.913579 -344.05622) (xy 287.972027 -344.117518)
			(xy 288.024383 -344.184094) (xy 288.070173 -344.255346) (xy 288.108984 -344.330627) (xy 288.140463 -344.409257)
			(xy 288.164324 -344.490524) (xy 288.180353 -344.57369) (xy 288.188404 -344.658004) (xy 288.188908 -344.700352)
			(xy 288.188404 -344.7427) (xy 292.607996 -344.7427) (xy 292.607996 -344.658004) (xy 292.616047 -344.57369)
			(xy 292.632076 -344.490524) (xy 292.655937 -344.409257) (xy 292.687416 -344.330627) (xy 292.726227 -344.255346)
			(xy 292.772017 -344.184094) (xy 292.824373 -344.117518) (xy 292.882821 -344.05622) (xy 292.946831 -344.000755)
			(xy 293.015823 -343.951626) (xy 293.089173 -343.909277) (xy 293.166216 -343.874093) (xy 293.246255 -343.846391)
			(xy 293.328564 -343.826423) (xy 293.412399 -343.81437) (xy 293.497 -343.81034) (xy 293.581601 -343.81437)
			(xy 293.665436 -343.826423) (xy 293.747745 -343.846391) (xy 293.827784 -343.874093) (xy 293.904827 -343.909277)
			(xy 293.978177 -343.951626) (xy 294.047169 -344.000755) (xy 294.111179 -344.05622) (xy 294.169627 -344.117518)
			(xy 294.221983 -344.184094) (xy 294.267773 -344.255346) (xy 294.306584 -344.330627) (xy 294.338063 -344.409257)
			(xy 294.361924 -344.490524) (xy 294.377953 -344.57369) (xy 294.386004 -344.658004) (xy 294.386508 -344.700352)
			(xy 294.386004 -344.7427) (xy 298.805596 -344.7427) (xy 298.805596 -344.658004) (xy 298.813647 -344.57369)
			(xy 298.829676 -344.490524) (xy 298.853537 -344.409257) (xy 298.885016 -344.330627) (xy 298.923827 -344.255346)
			(xy 298.969617 -344.184094) (xy 299.021973 -344.117518) (xy 299.080421 -344.05622) (xy 299.144431 -344.000755)
			(xy 299.213423 -343.951626) (xy 299.286773 -343.909277) (xy 299.363816 -343.874093) (xy 299.443855 -343.846391)
			(xy 299.526164 -343.826423) (xy 299.609999 -343.81437) (xy 299.6946 -343.81034) (xy 299.779201 -343.81437)
			(xy 299.863036 -343.826423) (xy 299.945345 -343.846391) (xy 300.025384 -343.874093) (xy 300.102427 -343.909277)
			(xy 300.175777 -343.951626) (xy 300.244769 -344.000755) (xy 300.308779 -344.05622) (xy 300.367227 -344.117518)
			(xy 300.419583 -344.184094) (xy 300.465373 -344.255346) (xy 300.504184 -344.330627) (xy 300.535663 -344.409257)
			(xy 300.559524 -344.490524) (xy 300.575553 -344.57369) (xy 300.583604 -344.658004) (xy 300.584108 -344.700352)
			(xy 300.583604 -344.7427) (xy 300.575553 -344.827014) (xy 300.559524 -344.91018) (xy 300.535663 -344.991447)
			(xy 300.504184 -345.070077) (xy 300.465373 -345.145358) (xy 300.419583 -345.21661) (xy 300.367227 -345.283186)
			(xy 300.308779 -345.344484) (xy 300.244769 -345.399949) (xy 300.175777 -345.449078) (xy 300.102427 -345.491427)
			(xy 300.025384 -345.526611) (xy 299.945345 -345.554313) (xy 299.863036 -345.574281) (xy 299.779201 -345.586334)
			(xy 299.6946 -345.590365) (xy 299.609999 -345.586334) (xy 299.526164 -345.574281) (xy 299.443855 -345.554313)
			(xy 299.363816 -345.526611) (xy 299.286773 -345.491427) (xy 299.213423 -345.449078) (xy 299.144431 -345.399949)
			(xy 299.080421 -345.344484) (xy 299.021973 -345.283186) (xy 298.969617 -345.21661) (xy 298.923827 -345.145358)
			(xy 298.885016 -345.070077) (xy 298.853537 -344.991447) (xy 298.829676 -344.91018) (xy 298.813647 -344.827014)
			(xy 298.805596 -344.7427) (xy 294.386004 -344.7427) (xy 294.377953 -344.827014) (xy 294.361924 -344.91018)
			(xy 294.338063 -344.991447) (xy 294.306584 -345.070077) (xy 294.267773 -345.145358) (xy 294.221983 -345.21661)
			(xy 294.169627 -345.283186) (xy 294.111179 -345.344484) (xy 294.047169 -345.399949) (xy 293.978177 -345.449078)
			(xy 293.904827 -345.491427) (xy 293.827784 -345.526611) (xy 293.747745 -345.554313) (xy 293.665436 -345.574281)
			(xy 293.581601 -345.586334) (xy 293.497 -345.590365) (xy 293.412399 -345.586334) (xy 293.328564 -345.574281)
			(xy 293.246255 -345.554313) (xy 293.166216 -345.526611) (xy 293.089173 -345.491427) (xy 293.015823 -345.449078)
			(xy 292.946831 -345.399949) (xy 292.882821 -345.344484) (xy 292.824373 -345.283186) (xy 292.772017 -345.21661)
			(xy 292.726227 -345.145358) (xy 292.687416 -345.070077) (xy 292.655937 -344.991447) (xy 292.632076 -344.91018)
			(xy 292.616047 -344.827014) (xy 292.607996 -344.7427) (xy 288.188404 -344.7427) (xy 288.180353 -344.827014)
			(xy 288.164324 -344.91018) (xy 288.140463 -344.991447) (xy 288.108984 -345.070077) (xy 288.070173 -345.145358)
			(xy 288.024383 -345.21661) (xy 287.972027 -345.283186) (xy 287.913579 -345.344484) (xy 287.849569 -345.399949)
			(xy 287.780577 -345.449078) (xy 287.707227 -345.491427) (xy 287.630184 -345.526611) (xy 287.550145 -345.554313)
			(xy 287.467836 -345.574281) (xy 287.384001 -345.586334) (xy 287.2994 -345.590365) (xy 287.214799 -345.586334)
			(xy 287.130964 -345.574281) (xy 287.048655 -345.554313) (xy 286.968616 -345.526611) (xy 286.891573 -345.491427)
			(xy 286.818223 -345.449078) (xy 286.749231 -345.399949) (xy 286.685221 -345.344484) (xy 286.626773 -345.283186)
			(xy 286.574417 -345.21661) (xy 286.528627 -345.145358) (xy 286.489816 -345.070077) (xy 286.458337 -344.991447)
			(xy 286.434476 -344.91018) (xy 286.418447 -344.827014) (xy 286.410396 -344.7427) (xy 270.383 -344.7427)
			(xy 270.383 -362.290868) (xy 283.044644 -362.290868) (xy 283.048715 -362.235246) (xy 283.060841 -362.180809)
			(xy 283.080764 -362.128718) (xy 283.10806 -362.080083) (xy 283.142146 -362.03594) (xy 283.182295 -361.997231)
			(xy 283.227653 -361.96478) (xy 283.277253 -361.939279) (xy 283.330037 -361.921272) (xy 283.38488 -361.911142)
			(xy 283.440614 -361.909105) (xy 283.496051 -361.915205) (xy 283.550008 -361.929311) (xy 283.601337 -361.951123)
			(xy 283.648943 -361.980177) (xy 283.691811 -362.015852) (xy 283.729028 -362.057389) (xy 283.759801 -362.103902)
			(xy 283.783473 -362.154399) (xy 283.799541 -362.207806) (xy 283.807661 -362.262982) (xy 283.80817 -362.290868)
			(xy 283.807661 -362.318754) (xy 283.799541 -362.37393) (xy 283.783473 -362.427337) (xy 283.759801 -362.477834)
			(xy 283.729028 -362.524347) (xy 283.691811 -362.565884) (xy 283.648943 -362.601559) (xy 283.601337 -362.630613)
			(xy 283.550008 -362.652425) (xy 283.496051 -362.666531) (xy 283.440614 -362.672631) (xy 283.38488 -362.670594)
			(xy 283.330037 -362.660464) (xy 283.277253 -362.642457) (xy 283.227653 -362.616956) (xy 283.182295 -362.584505)
			(xy 283.142146 -362.545796) (xy 283.10806 -362.501653) (xy 283.080764 -362.453018) (xy 283.060841 -362.400927)
			(xy 283.048715 -362.34649) (xy 283.044644 -362.290868) (xy 270.383 -362.290868) (xy 270.383 -364.242096)
			(xy 284.829758 -364.242096) (xy 284.829758 -364.241842) (xy 284.830271 -364.213827) (xy 284.838494 -364.158405)
			(xy 284.854726 -364.104778) (xy 284.878619 -364.054098) (xy 284.90966 -364.007452) (xy 284.928056 -363.986318)
			(xy 284.937658 -363.974842) (xy 284.950447 -363.947812) (xy 284.954843 -363.918234) (xy 284.950467 -363.888653)
			(xy 284.937697 -363.861615) (xy 284.928056 -363.850174) (xy 284.909658 -363.829037) (xy 284.878586 -363.782408)
			(xy 284.854678 -363.73173) (xy 284.838449 -363.678098) (xy 284.83025 -363.622667) (xy 284.829758 -363.59465)
			(xy 284.829758 -363.594396) (xy 284.830244 -363.567145) (xy 284.838 -363.513197) (xy 284.853355 -363.460902)
			(xy 284.875997 -363.411325) (xy 284.905463 -363.365475) (xy 284.941154 -363.324284) (xy 284.982345 -363.288593)
			(xy 285.028195 -363.259127) (xy 285.077772 -363.236485) (xy 285.130067 -363.22113) (xy 285.184015 -363.213374)
			(xy 285.238517 -363.213374) (xy 285.292465 -363.22113) (xy 285.34476 -363.236485) (xy 285.394337 -363.259127)
			(xy 285.440187 -363.288593) (xy 285.481378 -363.324284) (xy 285.517069 -363.365475) (xy 285.546535 -363.411325)
			(xy 285.569177 -363.460902) (xy 285.584532 -363.513197) (xy 285.592288 -363.567145) (xy 285.592774 -363.594396)
			(xy 285.592774 -363.59465) (xy 285.592274 -363.622665) (xy 285.58405 -363.678089) (xy 285.567816 -363.731717)
			(xy 285.54392 -363.782397) (xy 285.512874 -363.829041) (xy 285.494476 -363.850174) (xy 285.484789 -363.861583)
			(xy 285.47202 -363.888638) (xy 285.467644 -363.918234) (xy 285.47204 -363.947827) (xy 285.484827 -363.974874)
			(xy 285.494476 -363.986318) (xy 285.512875 -364.007453) (xy 285.543946 -364.054084) (xy 285.567854 -364.104761)
			(xy 285.584082 -364.158394) (xy 285.592282 -364.213825) (xy 285.592774 -364.241842) (xy 285.592774 -364.242096)
			(xy 285.592288 -364.269347) (xy 285.584532 -364.323295) (xy 285.569177 -364.37559) (xy 285.546535 -364.425167)
			(xy 285.517069 -364.471017) (xy 285.481378 -364.512208) (xy 285.440187 -364.547899) (xy 285.394337 -364.577365)
			(xy 285.34476 -364.600007) (xy 285.292465 -364.615362) (xy 285.238517 -364.623118) (xy 285.184015 -364.623118)
			(xy 285.130067 -364.615362) (xy 285.077772 -364.600007) (xy 285.028195 -364.577365) (xy 284.982345 -364.547899)
			(xy 284.941154 -364.512208) (xy 284.905463 -364.471017) (xy 284.875997 -364.425167) (xy 284.853355 -364.37559)
			(xy 284.838 -364.323295) (xy 284.830244 -364.269347) (xy 284.829758 -364.242096) (xy 270.383 -364.242096)
			(xy 270.383 -364.625128) (xy 283.044644 -364.625128) (xy 283.048715 -364.569506) (xy 283.060841 -364.515069)
			(xy 283.080764 -364.462978) (xy 283.10806 -364.414343) (xy 283.142146 -364.3702) (xy 283.182295 -364.331491)
			(xy 283.227653 -364.29904) (xy 283.277253 -364.273539) (xy 283.330037 -364.255532) (xy 283.38488 -364.245402)
			(xy 283.440614 -364.243365) (xy 283.496051 -364.249465) (xy 283.550008 -364.263571) (xy 283.601337 -364.285383)
			(xy 283.648943 -364.314437) (xy 283.691811 -364.350112) (xy 283.729028 -364.391649) (xy 283.759801 -364.438162)
			(xy 283.783473 -364.488659) (xy 283.799541 -364.542066) (xy 283.807661 -364.597242) (xy 283.80817 -364.625128)
			(xy 283.807661 -364.653014) (xy 283.799541 -364.70819) (xy 283.783473 -364.761597) (xy 283.759801 -364.812094)
			(xy 283.729028 -364.858607) (xy 283.691811 -364.900144) (xy 283.648943 -364.935819) (xy 283.601337 -364.964873)
			(xy 283.550008 -364.986685) (xy 283.496051 -365.000791) (xy 283.440614 -365.006891) (xy 283.38488 -365.004854)
			(xy 283.330037 -364.994724) (xy 283.277253 -364.976717) (xy 283.227653 -364.951216) (xy 283.182295 -364.918765)
			(xy 283.142146 -364.880056) (xy 283.10806 -364.835913) (xy 283.080764 -364.787278) (xy 283.060841 -364.735187)
			(xy 283.048715 -364.68075) (xy 283.044644 -364.625128) (xy 270.383 -364.625128) (xy 270.383 -366.320324)
			(xy 284.6705 -366.320324) (xy 284.6705 -365.669068) (xy 284.670957 -365.64408) (xy 284.678797 -365.594723)
			(xy 284.694262 -365.547201) (xy 284.716972 -365.502683) (xy 284.746368 -365.462267) (xy 284.763718 -365.444278)
			(xy 286.05988 -364.148116) (xy 286.05988 -362.72978) (xy 285.855918 -362.525818) (xy 285.838554 -362.507841)
			(xy 285.809148 -362.467429) (xy 285.786436 -362.422909) (xy 285.77098 -362.37538) (xy 285.763161 -362.326017)
			(xy 285.7627 -362.301028) (xy 285.7627 -358.940862) (xy 285.443676 -358.621838) (xy 285.426395 -358.603834)
			(xy 285.397071 -358.56346) (xy 285.374422 -358.518996) (xy 285.359006 -358.471538) (xy 285.351201 -358.422252)
			(xy 285.350712 -358.397302) (xy 285.350712 -352.051874) (xy 285.335629 -352.028309) (xy 285.3118 -351.977686)
			(xy 285.295625 -351.924125) (xy 285.28745 -351.868775) (xy 285.286958 -351.8408) (xy 285.28741 -351.813429)
			(xy 285.295229 -351.759249) (xy 285.310721 -351.706745) (xy 285.333566 -351.656998) (xy 285.363295 -351.611033)
			(xy 285.380938 -351.590102) (xy 285.390172 -351.578773) (xy 285.402345 -351.552215) (xy 285.406515 -351.5233)
			(xy 285.402345 -351.494385) (xy 285.390172 -351.467827) (xy 285.380938 -351.456498) (xy 285.363297 -351.435565)
			(xy 285.333571 -351.389598) (xy 285.310725 -351.339852) (xy 285.295228 -351.28735) (xy 285.2874 -351.233171)
			(xy 285.2874 -351.178429) (xy 285.295228 -351.12425) (xy 285.310725 -351.071748) (xy 285.333571 -351.022002)
			(xy 285.363297 -350.976035) (xy 285.380938 -350.955102) (xy 285.390172 -350.943773) (xy 285.402345 -350.917215)
			(xy 285.406515 -350.8883) (xy 285.402345 -350.859385) (xy 285.390172 -350.832827) (xy 285.380938 -350.821498)
			(xy 285.363297 -350.800565) (xy 285.333571 -350.754598) (xy 285.310725 -350.704852) (xy 285.295228 -350.65235)
			(xy 285.2874 -350.598171) (xy 285.2874 -350.543429) (xy 285.295228 -350.48925) (xy 285.310725 -350.436748)
			(xy 285.333571 -350.387002) (xy 285.363297 -350.341035) (xy 285.380938 -350.320102) (xy 285.390172 -350.308773)
			(xy 285.402345 -350.282215) (xy 285.406515 -350.2533) (xy 285.402345 -350.224385) (xy 285.390172 -350.197827)
			(xy 285.380938 -350.186498) (xy 285.363297 -350.165565) (xy 285.333571 -350.119598) (xy 285.310725 -350.069852)
			(xy 285.295228 -350.01735) (xy 285.2874 -349.963171) (xy 285.2874 -349.908429) (xy 285.295228 -349.85425)
			(xy 285.310725 -349.801748) (xy 285.333571 -349.752002) (xy 285.363297 -349.706035) (xy 285.380938 -349.685102)
			(xy 285.390172 -349.673773) (xy 285.402345 -349.647215) (xy 285.406515 -349.6183) (xy 285.402345 -349.589385)
			(xy 285.390172 -349.562827) (xy 285.380938 -349.551498) (xy 285.363297 -349.530565) (xy 285.333571 -349.484598)
			(xy 285.310725 -349.434852) (xy 285.295228 -349.38235) (xy 285.2874 -349.328171) (xy 285.2874 -349.273429)
			(xy 285.295228 -349.21925) (xy 285.310725 -349.166748) (xy 285.333571 -349.117002) (xy 285.363297 -349.071035)
			(xy 285.380938 -349.050102) (xy 285.390172 -349.038773) (xy 285.402345 -349.012215) (xy 285.406515 -348.9833)
			(xy 285.402345 -348.954385) (xy 285.390172 -348.927827) (xy 285.380938 -348.916498) (xy 285.363297 -348.895565)
			(xy 285.333571 -348.849598) (xy 285.310725 -348.799852) (xy 285.295228 -348.74735) (xy 285.2874 -348.693171)
			(xy 285.2874 -348.638429) (xy 285.295228 -348.58425) (xy 285.310725 -348.531748) (xy 285.333571 -348.482002)
			(xy 285.363297 -348.436035) (xy 285.380938 -348.415102) (xy 285.390172 -348.403773) (xy 285.402345 -348.377215)
			(xy 285.406515 -348.3483) (xy 285.402345 -348.319385) (xy 285.390172 -348.292827) (xy 285.380938 -348.281498)
			(xy 285.36329 -348.260573) (xy 285.333579 -348.214599) (xy 285.310744 -348.164849) (xy 285.295255 -348.112347)
			(xy 285.28743 -348.05817) (xy 285.286958 -348.0308) (xy 285.287478 -348.00355) (xy 285.295233 -347.949606)
			(xy 285.310587 -347.897314) (xy 285.333225 -347.847739) (xy 285.362689 -347.80189) (xy 285.398376 -347.7607)
			(xy 285.439563 -347.725009) (xy 285.485409 -347.695542) (xy 285.534982 -347.672899) (xy 285.587272 -347.657541)
			(xy 285.641216 -347.64978) (xy 285.668466 -347.649292) (xy 285.695835 -347.64978) (xy 285.750013 -347.657593)
			(xy 285.802516 -347.673077) (xy 285.852263 -347.695914) (xy 285.898231 -347.725633) (xy 285.919164 -347.743272)
			(xy 285.930492 -347.752508) (xy 285.957049 -347.764684) (xy 285.985966 -347.768857) (xy 286.014883 -347.764684)
			(xy 286.04144 -347.752508) (xy 286.052768 -347.743272) (xy 286.073698 -347.72563) (xy 286.119672 -347.69592)
			(xy 286.16942 -347.673085) (xy 286.221921 -347.657594) (xy 286.276097 -347.649766) (xy 286.303466 -347.649292)
			(xy 286.30372 -347.649292) (xy 286.331734 -347.649819) (xy 286.387157 -347.658037) (xy 286.440784 -347.674266)
			(xy 286.491464 -347.698156) (xy 286.53811 -347.729195) (xy 286.559244 -347.74759) (xy 286.570686 -347.757235)
			(xy 286.597729 -347.770015) (xy 286.627316 -347.774401) (xy 286.656903 -347.770015) (xy 286.683946 -347.757235)
			(xy 286.695388 -347.74759) (xy 286.71379 -347.731553) (xy 286.753943 -347.703798) (xy 286.797303 -347.68138)
			(xy 286.820102 -347.67266) (xy 286.833437 -347.667262) (xy 286.856596 -347.650215) (xy 286.874094 -347.627394)
			(xy 286.884546 -347.600604) (xy 286.887126 -347.571964) (xy 286.88163 -347.543737) (xy 286.868493 -347.518156)
			(xy 286.848753 -347.497245) (xy 286.836612 -347.489526) (xy 286.799538 -347.467197) (xy 286.729339 -347.416569)
			(xy 286.664236 -347.359536) (xy 286.604811 -347.296608) (xy 286.551597 -347.228348) (xy 286.505069 -347.155367)
			(xy 286.465642 -347.078317) (xy 286.433671 -346.997887) (xy 286.40944 -346.914797) (xy 286.393166 -346.829789)
			(xy 286.384995 -346.743624) (xy 286.384492 -346.700348) (xy 286.38498 -346.658072) (xy 286.392782 -346.57388)
			(xy 286.408318 -346.490767) (xy 286.431457 -346.409443) (xy 286.462001 -346.3306) (xy 286.499689 -346.254912)
			(xy 286.5442 -346.183024) (xy 286.595154 -346.11555) (xy 286.652117 -346.053065) (xy 286.714602 -345.996102)
			(xy 286.782076 -345.945148) (xy 286.853964 -345.900637) (xy 286.929652 -345.862949) (xy 287.008495 -345.832405)
			(xy 287.089819 -345.809266) (xy 287.172932 -345.79373) (xy 287.257124 -345.785928) (xy 287.341676 -345.785928)
			(xy 287.425868 -345.79373) (xy 287.508981 -345.809266) (xy 287.590305 -345.832405) (xy 287.669148 -345.862949)
			(xy 287.744836 -345.900637) (xy 287.816724 -345.945148) (xy 287.884198 -345.996102) (xy 287.946683 -346.053065)
			(xy 288.003646 -346.11555) (xy 288.0546 -346.183024) (xy 288.099111 -346.254912) (xy 288.136799 -346.3306)
			(xy 288.167343 -346.409443) (xy 288.190482 -346.490767) (xy 288.206018 -346.57388) (xy 288.21382 -346.658072)
			(xy 288.214308 -346.700348) (xy 292.581589 -346.700348) (xy 292.585611 -346.614628) (xy 292.597642 -346.52966)
			(xy 292.617578 -346.446193) (xy 292.645241 -346.364959) (xy 292.68039 -346.286673) (xy 292.722716 -346.212022)
			(xy 292.771845 -346.141663) (xy 292.827348 -346.076213) (xy 292.888735 -346.016249) (xy 292.955468 -345.962296)
			(xy 293.02696 -345.914829) (xy 293.102582 -345.874265) (xy 293.181671 -345.840961) (xy 293.263531 -345.815209)
			(xy 293.347442 -345.797236) (xy 293.432668 -345.7872) (xy 293.51846 -345.785188) (xy 293.604062 -345.791219)
			(xy 293.688724 -345.805239) (xy 293.771701 -345.827125) (xy 293.852264 -345.856686) (xy 293.929704 -345.89366)
			(xy 294.003343 -345.937724) (xy 294.072531 -345.98849) (xy 294.136662 -346.045511) (xy 294.195171 -346.108287)
			(xy 294.247544 -346.176267) (xy 294.293322 -346.248852) (xy 294.332102 -346.325404) (xy 294.363543 -346.405252)
			(xy 294.387369 -346.487693) (xy 294.40337 -346.572003) (xy 294.411405 -346.657441) (xy 294.411908 -346.700348)
			(xy 298.779189 -346.700348) (xy 298.783211 -346.614628) (xy 298.795242 -346.52966) (xy 298.815178 -346.446193)
			(xy 298.842841 -346.364959) (xy 298.87799 -346.286673) (xy 298.920316 -346.212022) (xy 298.969445 -346.141663)
			(xy 299.024948 -346.076213) (xy 299.086335 -346.016249) (xy 299.153068 -345.962296) (xy 299.22456 -345.914829)
			(xy 299.300182 -345.874265) (xy 299.379271 -345.840961) (xy 299.461131 -345.815209) (xy 299.545042 -345.797236)
			(xy 299.630268 -345.7872) (xy 299.71606 -345.785188) (xy 299.801662 -345.791219) (xy 299.886324 -345.805239)
			(xy 299.969301 -345.827125) (xy 300.049864 -345.856686) (xy 300.127304 -345.89366) (xy 300.200943 -345.937724)
			(xy 300.270131 -345.98849) (xy 300.334262 -346.045511) (xy 300.392771 -346.108287) (xy 300.445144 -346.176267)
			(xy 300.490922 -346.248852) (xy 300.529702 -346.325404) (xy 300.561143 -346.405252) (xy 300.584969 -346.487693)
			(xy 300.60097 -346.572003) (xy 300.609005 -346.657441) (xy 300.609508 -346.700348) (xy 300.609005 -346.743255)
			(xy 300.60097 -346.828693) (xy 300.584969 -346.913003) (xy 300.561143 -346.995444) (xy 300.529702 -347.075292)
			(xy 300.490922 -347.151844) (xy 300.445144 -347.224429) (xy 300.392771 -347.292409) (xy 300.334262 -347.355185)
			(xy 300.270131 -347.412206) (xy 300.200943 -347.462972) (xy 300.127304 -347.507036) (xy 300.049864 -347.54401)
			(xy 299.969301 -347.573571) (xy 299.886324 -347.595457) (xy 299.801662 -347.609477) (xy 299.71606 -347.615508)
			(xy 299.630268 -347.613496) (xy 299.545042 -347.60346) (xy 299.461131 -347.585487) (xy 299.379271 -347.559735)
			(xy 299.300182 -347.526431) (xy 299.22456 -347.485867) (xy 299.153068 -347.4384) (xy 299.086335 -347.384447)
			(xy 299.024948 -347.324483) (xy 298.969445 -347.259033) (xy 298.920316 -347.188674) (xy 298.87799 -347.114023)
			(xy 298.842841 -347.035737) (xy 298.815178 -346.954503) (xy 298.795242 -346.871036) (xy 298.783211 -346.786068)
			(xy 298.779189 -346.700348) (xy 294.411908 -346.700348) (xy 294.411405 -346.743255) (xy 294.40337 -346.828693)
			(xy 294.387369 -346.913003) (xy 294.363543 -346.995444) (xy 294.332102 -347.075292) (xy 294.293322 -347.151844)
			(xy 294.247544 -347.224429) (xy 294.195171 -347.292409) (xy 294.136662 -347.355185) (xy 294.072531 -347.412206)
			(xy 294.003343 -347.462972) (xy 293.929704 -347.507036) (xy 293.852264 -347.54401) (xy 293.771701 -347.573571)
			(xy 293.688724 -347.595457) (xy 293.604062 -347.609477) (xy 293.51846 -347.615508) (xy 293.432668 -347.613496)
			(xy 293.347442 -347.60346) (xy 293.263531 -347.585487) (xy 293.181671 -347.559735) (xy 293.102582 -347.526431)
			(xy 293.02696 -347.485867) (xy 292.955468 -347.4384) (xy 292.888735 -347.384447) (xy 292.827348 -347.324483)
			(xy 292.771845 -347.259033) (xy 292.722716 -347.188674) (xy 292.68039 -347.114023) (xy 292.645241 -347.035737)
			(xy 292.617578 -346.954503) (xy 292.597642 -346.871036) (xy 292.585611 -346.786068) (xy 292.581589 -346.700348)
			(xy 288.214308 -346.700348) (xy 288.21379 -346.742119) (xy 288.206161 -346.825312) (xy 288.190979 -346.907463)
			(xy 288.168372 -346.987888) (xy 288.138526 -347.065917) (xy 288.101692 -347.140901) (xy 288.058175 -347.212214)
			(xy 288.008338 -347.279263) (xy 287.952597 -347.34149) (xy 287.891415 -347.398376) (xy 287.825301 -347.449448)
			(xy 287.754807 -347.49428) (xy 287.68052 -347.532499) (xy 287.603058 -347.563786) (xy 287.523066 -347.587882)
			(xy 287.44121 -347.604585) (xy 287.358173 -347.613756) (xy 287.316418 -347.615002) (xy 287.302046 -347.615754)
			(xy 287.274565 -347.624259) (xy 287.250547 -347.640089) (xy 287.231895 -347.661989) (xy 287.22009 -347.688222)
			(xy 287.216068 -347.716706) (xy 287.220149 -347.745181) (xy 287.232008 -347.771389) (xy 287.24098 -347.782642)
			(xy 287.258186 -347.803491) (xy 287.287192 -347.849105) (xy 287.309471 -347.898356) (xy 287.324576 -347.950258)
			(xy 287.332204 -348.003772) (xy 287.332674 -348.0308) (xy 287.332214 -348.058171) (xy 287.324396 -348.11235)
			(xy 287.308906 -348.164854) (xy 287.286062 -348.2146) (xy 287.256336 -348.260567) (xy 287.238694 -348.281498)
			(xy 287.229458 -348.292825) (xy 287.217281 -348.319383) (xy 287.213109 -348.3483) (xy 287.217281 -348.377217)
			(xy 287.229458 -348.403775) (xy 287.238694 -348.415102) (xy 287.256334 -348.436035) (xy 287.286057 -348.482003)
			(xy 287.308901 -348.53175) (xy 287.324396 -348.584252) (xy 287.332225 -348.63843) (xy 287.332225 -348.69317)
			(xy 287.324396 -348.747348) (xy 287.308901 -348.79985) (xy 287.286057 -348.849597) (xy 287.256334 -348.895565)
			(xy 287.238694 -348.916498) (xy 287.229458 -348.927825) (xy 287.217281 -348.954383) (xy 287.213109 -348.9833)
			(xy 287.217281 -349.012217) (xy 287.229458 -349.038775) (xy 287.238694 -349.050102) (xy 287.256334 -349.071035)
			(xy 287.286057 -349.117003) (xy 287.308901 -349.16675) (xy 287.324396 -349.219252) (xy 287.332225 -349.27343)
			(xy 287.332225 -349.32817) (xy 287.324396 -349.382348) (xy 287.308901 -349.43485) (xy 287.286057 -349.484597)
			(xy 287.256334 -349.530565) (xy 287.238694 -349.551498) (xy 287.229458 -349.562825) (xy 287.217281 -349.589383)
			(xy 287.213109 -349.6183) (xy 287.217281 -349.647217) (xy 287.229458 -349.673775) (xy 287.238694 -349.685102)
			(xy 287.256334 -349.706035) (xy 287.286057 -349.752003) (xy 287.308901 -349.80175) (xy 287.324396 -349.854252)
			(xy 287.332225 -349.90843) (xy 287.332225 -349.96317) (xy 287.324396 -350.017348) (xy 287.308901 -350.06985)
			(xy 287.286057 -350.119597) (xy 287.256334 -350.165565) (xy 287.238694 -350.186498) (xy 287.229458 -350.197825)
			(xy 287.217281 -350.224383) (xy 287.213109 -350.2533) (xy 287.217281 -350.282217) (xy 287.229458 -350.308775)
			(xy 287.238694 -350.320102) (xy 287.256334 -350.341035) (xy 287.286057 -350.387003) (xy 287.308901 -350.43675)
			(xy 287.324396 -350.489252) (xy 287.332225 -350.54343) (xy 287.332225 -350.59817) (xy 287.324396 -350.652348)
			(xy 287.308901 -350.70485) (xy 287.286057 -350.754597) (xy 287.256334 -350.800565) (xy 287.238694 -350.821498)
			(xy 287.229458 -350.832825) (xy 287.217281 -350.859383) (xy 287.213109 -350.8883) (xy 287.217281 -350.917217)
			(xy 287.229458 -350.943775) (xy 287.238694 -350.955102) (xy 287.256334 -350.976035) (xy 287.286057 -351.022003)
			(xy 287.308901 -351.07175) (xy 287.324396 -351.124252) (xy 287.332225 -351.17843) (xy 287.332225 -351.23317)
			(xy 287.324396 -351.287348) (xy 287.308901 -351.33985) (xy 287.286057 -351.389597) (xy 287.256334 -351.435565)
			(xy 287.238694 -351.456498) (xy 287.229458 -351.467825) (xy 287.217281 -351.494383) (xy 287.213109 -351.5233)
			(xy 287.217281 -351.552217) (xy 287.229458 -351.578775) (xy 287.238694 -351.590102) (xy 287.256347 -351.611023)
			(xy 287.286057 -351.656999) (xy 287.30889 -351.706749) (xy 287.324378 -351.759252) (xy 287.332202 -351.81343)
			(xy 287.332674 -351.8408) (xy 290.25723 -351.8408) (xy 290.257689 -351.813429) (xy 290.265507 -351.75925)
			(xy 290.280998 -351.706746) (xy 290.303841 -351.656999) (xy 290.333568 -351.611033) (xy 290.35121 -351.590102)
			(xy 290.360446 -351.578774) (xy 290.372622 -351.552217) (xy 290.376794 -351.5233) (xy 290.372622 -351.494383)
			(xy 290.360446 -351.467826) (xy 290.35121 -351.456498) (xy 290.33357 -351.435565) (xy 290.303847 -351.389597)
			(xy 290.281002 -351.33985) (xy 290.265507 -351.287349) (xy 290.257678 -351.23317) (xy 290.257678 -351.17843)
			(xy 290.265507 -351.124251) (xy 290.281002 -351.07175) (xy 290.303847 -351.022003) (xy 290.33357 -350.976035)
			(xy 290.35121 -350.955102) (xy 290.360446 -350.943774) (xy 290.372622 -350.917217) (xy 290.376794 -350.8883)
			(xy 290.372622 -350.859383) (xy 290.360446 -350.832826) (xy 290.35121 -350.821498) (xy 290.33357 -350.800565)
			(xy 290.303847 -350.754597) (xy 290.281002 -350.70485) (xy 290.265507 -350.652349) (xy 290.257678 -350.59817)
			(xy 290.257678 -350.54343) (xy 290.265507 -350.489251) (xy 290.281002 -350.43675) (xy 290.303847 -350.387003)
			(xy 290.33357 -350.341035) (xy 290.35121 -350.320102) (xy 290.360446 -350.308774) (xy 290.372622 -350.282217)
			(xy 290.376794 -350.2533) (xy 290.372622 -350.224383) (xy 290.360446 -350.197826) (xy 290.35121 -350.186498)
			(xy 290.33357 -350.165565) (xy 290.303847 -350.119597) (xy 290.281002 -350.06985) (xy 290.265507 -350.017349)
			(xy 290.257678 -349.96317) (xy 290.257678 -349.90843) (xy 290.265507 -349.854251) (xy 290.281002 -349.80175)
			(xy 290.303847 -349.752003) (xy 290.33357 -349.706035) (xy 290.35121 -349.685102) (xy 290.360446 -349.673774)
			(xy 290.372622 -349.647217) (xy 290.376794 -349.6183) (xy 290.372622 -349.589383) (xy 290.360446 -349.562826)
			(xy 290.35121 -349.551498) (xy 290.33357 -349.530565) (xy 290.303847 -349.484597) (xy 290.281002 -349.43485)
			(xy 290.265507 -349.382349) (xy 290.257678 -349.32817) (xy 290.257678 -349.27343) (xy 290.265507 -349.219251)
			(xy 290.281002 -349.16675) (xy 290.303847 -349.117003) (xy 290.33357 -349.071035) (xy 290.35121 -349.050102)
			(xy 290.360446 -349.038774) (xy 290.372622 -349.012217) (xy 290.376794 -348.9833) (xy 290.372622 -348.954383)
			(xy 290.360446 -348.927826) (xy 290.35121 -348.916498) (xy 290.33357 -348.895565) (xy 290.303847 -348.849597)
			(xy 290.281002 -348.79985) (xy 290.265507 -348.747349) (xy 290.257678 -348.69317) (xy 290.257678 -348.63843)
			(xy 290.265507 -348.584251) (xy 290.281002 -348.53175) (xy 290.303847 -348.482003) (xy 290.33357 -348.436035)
			(xy 290.35121 -348.415102) (xy 290.360446 -348.403774) (xy 290.372622 -348.377217) (xy 290.376794 -348.3483)
			(xy 290.372622 -348.319383) (xy 290.360446 -348.292826) (xy 290.35121 -348.281498) (xy 290.333558 -348.260576)
			(xy 290.303848 -348.214601) (xy 290.281014 -348.164851) (xy 290.265526 -348.112348) (xy 290.257702 -348.05817)
			(xy 290.25723 -348.0308) (xy 290.257655 -348.003545) (xy 290.265413 -347.949591) (xy 290.280771 -347.89729)
			(xy 290.303417 -347.847708) (xy 290.332888 -347.801853) (xy 290.368586 -347.760659) (xy 290.409783 -347.724965)
			(xy 290.455641 -347.695498) (xy 290.505226 -347.672858) (xy 290.557528 -347.657505) (xy 290.611483 -347.649753)
			(xy 290.638738 -347.649292) (xy 290.638992 -347.649292) (xy 290.667008 -347.649776) (xy 290.722432 -347.658005)
			(xy 290.77606 -347.674243) (xy 290.826739 -347.698143) (xy 290.873383 -347.729191) (xy 290.894516 -347.74759)
			(xy 290.905958 -347.757235) (xy 290.933001 -347.770015) (xy 290.962588 -347.774401) (xy 290.992175 -347.770015)
			(xy 291.019218 -347.757235) (xy 291.03066 -347.74759) (xy 291.051788 -347.729182) (xy 291.098419 -347.69811)
			(xy 291.149099 -347.674203) (xy 291.202733 -347.657977) (xy 291.258166 -347.649782) (xy 291.286184 -347.649292)
			(xy 291.286438 -347.649292) (xy 291.313807 -347.649796) (xy 291.367984 -347.657605) (xy 291.420487 -347.673085)
			(xy 291.470234 -347.695919) (xy 291.516203 -347.725635) (xy 291.537136 -347.743272) (xy 291.548464 -347.752508)
			(xy 291.575021 -347.764684) (xy 291.603938 -347.768857) (xy 291.632855 -347.764684) (xy 291.659412 -347.752508)
			(xy 291.67074 -347.743272) (xy 291.69168 -347.725643) (xy 291.737651 -347.695931) (xy 291.787397 -347.673093)
			(xy 291.839895 -347.6576) (xy 291.894069 -347.649768) (xy 291.921438 -347.649292) (xy 291.94869 -347.649742)
			(xy 292.002639 -347.657504) (xy 292.054935 -347.672864) (xy 292.104512 -347.69551) (xy 292.150362 -347.72498)
			(xy 292.191552 -347.760675) (xy 292.227243 -347.801868) (xy 292.256709 -347.847721) (xy 292.279349 -347.897301)
			(xy 292.294704 -347.949598) (xy 292.30246 -348.003548) (xy 292.302946 -348.0308) (xy 292.302493 -348.058171)
			(xy 292.294674 -348.112351) (xy 292.279183 -348.164855) (xy 292.256338 -348.214602) (xy 292.226609 -348.260567)
			(xy 292.208966 -348.281498) (xy 292.199732 -348.292826) (xy 292.187559 -348.319384) (xy 292.183388 -348.3483)
			(xy 292.187559 -348.377216) (xy 292.199732 -348.403774) (xy 292.208966 -348.415102) (xy 292.226607 -348.436035)
			(xy 292.256332 -348.482002) (xy 292.279178 -348.531748) (xy 292.294675 -348.584251) (xy 292.302503 -348.638429)
			(xy 292.302503 -348.693171) (xy 292.294675 -348.747349) (xy 292.279178 -348.799852) (xy 292.256332 -348.849598)
			(xy 292.226607 -348.895565) (xy 292.208966 -348.916498) (xy 292.199732 -348.927826) (xy 292.187559 -348.954384)
			(xy 292.183388 -348.9833) (xy 292.187559 -349.012216) (xy 292.199732 -349.038774) (xy 292.208966 -349.050102)
			(xy 292.226607 -349.071035) (xy 292.256332 -349.117002) (xy 292.279178 -349.166748) (xy 292.294675 -349.219251)
			(xy 292.302503 -349.273429) (xy 292.302503 -349.328171) (xy 292.294675 -349.382349) (xy 292.279178 -349.434852)
			(xy 292.256332 -349.484598) (xy 292.226607 -349.530565) (xy 292.208966 -349.551498) (xy 292.199732 -349.562826)
			(xy 292.187559 -349.589384) (xy 292.183388 -349.6183) (xy 292.187559 -349.647216) (xy 292.199732 -349.673774)
			(xy 292.208966 -349.685102) (xy 292.226607 -349.706035) (xy 292.256332 -349.752002) (xy 292.279178 -349.801748)
			(xy 292.294675 -349.854251) (xy 292.302503 -349.908429) (xy 292.302503 -349.963171) (xy 292.294675 -350.017349)
			(xy 292.279178 -350.069852) (xy 292.256332 -350.119598) (xy 292.226607 -350.165565) (xy 292.208966 -350.186498)
			(xy 292.199732 -350.197826) (xy 292.187559 -350.224384) (xy 292.183388 -350.2533) (xy 292.187559 -350.282216)
			(xy 292.199732 -350.308774) (xy 292.208966 -350.320102) (xy 292.226607 -350.341035) (xy 292.256332 -350.387002)
			(xy 292.279178 -350.436748) (xy 292.294675 -350.489251) (xy 292.302503 -350.543429) (xy 292.302503 -350.598171)
			(xy 292.294675 -350.652349) (xy 292.279178 -350.704852) (xy 292.256332 -350.754598) (xy 292.226607 -350.800565)
			(xy 292.208966 -350.821498) (xy 292.199732 -350.832826) (xy 292.187559 -350.859384) (xy 292.183388 -350.8883)
			(xy 292.187559 -350.917216) (xy 292.199732 -350.943774) (xy 292.208966 -350.955102) (xy 292.226607 -350.976035)
			(xy 292.256332 -351.022002) (xy 292.279178 -351.071748) (xy 292.294675 -351.124251) (xy 292.302503 -351.178429)
			(xy 292.302503 -351.233171) (xy 292.294675 -351.287349) (xy 292.279178 -351.339852) (xy 292.256332 -351.389598)
			(xy 292.226607 -351.435565) (xy 292.208966 -351.456498) (xy 292.199732 -351.467826) (xy 292.187559 -351.494384)
			(xy 292.183388 -351.5233) (xy 292.187559 -351.552216) (xy 292.199732 -351.578774) (xy 292.208966 -351.590102)
			(xy 292.226614 -351.611027) (xy 292.256326 -351.657001) (xy 292.279161 -351.70675) (xy 292.294649 -351.759253)
			(xy 292.302474 -351.81343) (xy 292.302946 -351.8408) (xy 292.302422 -351.86805) (xy 292.294667 -351.921994)
			(xy 292.279314 -351.974286) (xy 292.256675 -352.02386) (xy 292.227212 -352.069709) (xy 292.191525 -352.110898)
			(xy 292.150339 -352.14659) (xy 292.104494 -352.176057) (xy 292.054921 -352.1987) (xy 292.002631 -352.214059)
			(xy 291.948687 -352.22182) (xy 291.921438 -352.222308) (xy 291.894069 -352.221818) (xy 291.839891 -352.214005)
			(xy 291.787388 -352.198522) (xy 291.737641 -352.175686) (xy 291.691673 -352.145967) (xy 291.67074 -352.128328)
			(xy 291.659412 -352.119092) (xy 291.632855 -352.106916) (xy 291.603938 -352.102743) (xy 291.575021 -352.106916)
			(xy 291.548464 -352.119092) (xy 291.537136 -352.128328) (xy 291.516205 -352.145968) (xy 291.470231 -352.175679)
			(xy 291.420484 -352.198514) (xy 291.367983 -352.214005) (xy 291.313807 -352.221834) (xy 291.286438 -352.222308)
			(xy 291.286184 -352.222308) (xy 291.25817 -352.221779) (xy 291.202747 -352.213561) (xy 291.14912 -352.197333)
			(xy 291.09844 -352.173443) (xy 291.051794 -352.142405) (xy 291.03066 -352.12401) (xy 291.019218 -352.114365)
			(xy 290.992175 -352.101585) (xy 290.962588 -352.097199) (xy 290.933001 -352.101585) (xy 290.905958 -352.114365)
			(xy 290.894516 -352.12401) (xy 290.873398 -352.142429) (xy 290.826764 -352.1735) (xy 290.776082 -352.197404)
			(xy 290.722445 -352.213628) (xy 290.66701 -352.22182) (xy 290.638992 -352.222308) (xy 290.638738 -352.222308)
			(xy 290.611486 -352.221809) (xy 290.557536 -352.214058) (xy 290.505239 -352.198706) (xy 290.455659 -352.176068)
			(xy 290.409806 -352.146604) (xy 290.368613 -352.110914) (xy 290.332919 -352.069725) (xy 290.30345 -352.023874)
			(xy 290.280807 -351.974296) (xy 290.265451 -351.922001) (xy 290.257693 -351.868052) (xy 290.25723 -351.8408)
			(xy 287.332674 -351.8408) (xy 287.332245 -351.868054) (xy 287.324487 -351.922008) (xy 287.309129 -351.974309)
			(xy 287.286484 -352.023891) (xy 287.257013 -352.069746) (xy 287.221315 -352.11094) (xy 287.180119 -352.146633)
			(xy 287.134261 -352.1761) (xy 287.084677 -352.198741) (xy 287.032375 -352.214094) (xy 286.97842 -352.221847)
			(xy 286.951166 -352.222308) (xy 286.950912 -352.222308) (xy 286.922896 -352.221822) (xy 286.867472 -352.213593)
			(xy 286.813844 -352.197355) (xy 286.763165 -352.173456) (xy 286.716521 -352.142409) (xy 286.695388 -352.12401)
			(xy 286.683946 -352.114365) (xy 286.656903 -352.101585) (xy 286.627316 -352.097199) (xy 286.597729 -352.101585)
			(xy 286.570686 -352.114365) (xy 286.559244 -352.12401) (xy 286.538115 -352.142416) (xy 286.491484 -352.173488)
			(xy 286.440804 -352.197396) (xy 286.38717 -352.213622) (xy 286.331738 -352.221818) (xy 286.30372 -352.222308)
			(xy 286.303466 -352.222308) (xy 286.274046 -352.221755) (xy 286.215906 -352.212712) (xy 286.15985 -352.194832)
			(xy 286.133286 -352.182176) (xy 286.119843 -352.175963) (xy 286.090676 -352.170883) (xy 286.061277 -352.174372)
			(xy 286.034109 -352.186137) (xy 286.011451 -352.205192) (xy 285.995201 -352.22994) (xy 285.986721 -352.258305)
			(xy 285.98622 -352.273108) (xy 285.98622 -358.265476) (xy 286.305498 -358.5845) (xy 286.322873 -358.602466)
			(xy 286.352277 -358.642882) (xy 286.374986 -358.687404) (xy 286.39044 -358.734935) (xy 286.398256 -358.7843)
			(xy 286.398716 -358.80929) (xy 286.398716 -362.169456) (xy 286.602678 -362.373418) (xy 286.62001 -362.391424)
			(xy 286.649421 -362.431828) (xy 286.672138 -362.476341) (xy 286.687602 -362.523863) (xy 286.69543 -362.573221)
			(xy 286.695896 -362.598208) (xy 286.695896 -363.855508) (xy 292.807134 -363.855508) (xy 292.811205 -363.799886)
			(xy 292.823331 -363.745449) (xy 292.843254 -363.693358) (xy 292.87055 -363.644723) (xy 292.904636 -363.60058)
			(xy 292.944785 -363.561871) (xy 292.990143 -363.52942) (xy 293.039743 -363.503919) (xy 293.092527 -363.485912)
			(xy 293.14737 -363.475782) (xy 293.203104 -363.473745) (xy 293.258541 -363.479845) (xy 293.312498 -363.493951)
			(xy 293.363827 -363.515763) (xy 293.411433 -363.544817) (xy 293.454301 -363.580492) (xy 293.491518 -363.622029)
			(xy 293.522291 -363.668542) (xy 293.545963 -363.719039) (xy 293.562031 -363.772446) (xy 293.570151 -363.827622)
			(xy 293.57066 -363.855508) (xy 293.570151 -363.883394) (xy 293.562031 -363.93857) (xy 293.545963 -363.991977)
			(xy 293.522291 -364.042474) (xy 293.491518 -364.088987) (xy 293.454301 -364.130524) (xy 293.411433 -364.166199)
			(xy 293.363827 -364.195253) (xy 293.312498 -364.217065) (xy 293.258541 -364.231171) (xy 293.203104 -364.237271)
			(xy 293.14737 -364.235234) (xy 293.092527 -364.225104) (xy 293.039743 -364.207097) (xy 292.990143 -364.181596)
			(xy 292.944785 -364.149145) (xy 292.904636 -364.110436) (xy 292.87055 -364.066293) (xy 292.843254 -364.017658)
			(xy 292.823331 -363.965567) (xy 292.811205 -363.91113) (xy 292.807134 -363.855508) (xy 286.695896 -363.855508)
			(xy 286.695896 -364.279688) (xy 286.695412 -364.304675) (xy 286.687579 -364.354031) (xy 286.67212 -364.401553)
			(xy 286.649416 -364.446071) (xy 286.620026 -364.486489) (xy 286.602678 -364.504478) (xy 286.468856 -364.6383)
			(xy 289.07837 -364.6383) (xy 289.082538 -364.582684) (xy 289.094949 -364.52831) (xy 289.115327 -364.476394)
			(xy 289.143215 -364.428095) (xy 289.17799 -364.384492) (xy 289.218876 -364.34656) (xy 289.264959 -364.315146)
			(xy 289.31521 -364.290951) (xy 289.368506 -364.274517) (xy 289.423656 -364.26621) (xy 289.451542 -364.265718)
			(xy 289.478873 -364.26621) (xy 289.532952 -364.274177) (xy 289.585285 -364.289962) (xy 289.634749 -364.313227)
			(xy 289.680282 -364.343471) (xy 289.720905 -364.380046) (xy 289.755745 -364.422165) (xy 289.770312 -364.445296)
			(xy 289.778247 -364.457512) (xy 289.799715 -364.477184) (xy 289.825865 -364.48999) (xy 289.854568 -364.494887)
			(xy 289.883485 -364.491477) (xy 289.897058 -364.48619) (xy 289.920264 -364.47669) (xy 289.968599 -364.463343)
			(xy 290.01829 -364.456619) (xy 290.043362 -364.456218) (xy 290.068432 -364.456634) (xy 290.118115 -364.463387)
			(xy 290.166449 -364.476723) (xy 290.189666 -364.48619) (xy 290.203241 -364.491445) (xy 290.232143 -364.494811)
			(xy 290.260823 -364.4899) (xy 290.286959 -364.477108) (xy 290.308433 -364.457473) (xy 290.316412 -364.445296)
			(xy 290.330981 -364.422165) (xy 290.365824 -364.380044) (xy 290.406447 -364.343465) (xy 290.451978 -364.313214)
			(xy 290.50144 -364.289938) (xy 290.553771 -364.274138) (xy 290.60785 -364.266152) (xy 290.662514 -364.266152)
			(xy 290.716593 -364.274138) (xy 290.768924 -364.289938) (xy 290.818386 -364.313214) (xy 290.863917 -364.343465)
			(xy 290.90454 -364.380044) (xy 290.939383 -364.422165) (xy 290.953952 -364.445296) (xy 290.961849 -364.457539)
			(xy 290.983327 -364.477211) (xy 291.009488 -364.490013) (xy 291.038199 -364.494904) (xy 291.067123 -364.491483)
			(xy 291.080698 -364.48619) (xy 291.103911 -364.476708) (xy 291.152242 -364.463354) (xy 291.201931 -364.456623)
			(xy 291.227002 -364.456218) (xy 291.254319 -364.456686) (xy 291.308365 -364.464677) (xy 291.360665 -364.480472)
			(xy 291.410099 -364.503733) (xy 291.455607 -364.533963) (xy 291.496215 -364.570512) (xy 291.531052 -364.612598)
			(xy 291.559371 -364.659318) (xy 291.57041 -364.68431) (xy 291.575959 -364.69653) (xy 291.592461 -364.717688)
			(xy 291.613901 -364.733822) (xy 291.638801 -364.74382) (xy 291.665445 -364.746992) (xy 291.691997 -364.743119)
			(xy 291.716625 -364.73247) (xy 291.727382 -364.724442) (xy 291.747719 -364.708764) (xy 291.791824 -364.682466)
			(xy 291.839056 -364.662316) (xy 291.888563 -364.648679) (xy 291.939451 -364.641799) (xy 291.965126 -364.641384)
			(xy 291.983145 -364.641606) (xy 292.01902 -364.645039) (xy 292.036754 -364.648242) (xy 292.051967 -364.650546)
			(xy 292.082518 -364.64703) (xy 292.110636 -364.634578) (xy 292.133772 -364.614319) (xy 292.149827 -364.588091)
			(xy 292.154102 -364.573312) (xy 292.161484 -364.546264) (xy 292.183118 -364.494539) (xy 292.212086 -364.446535)
			(xy 292.247764 -364.403285) (xy 292.289385 -364.365719) (xy 292.336054 -364.334645) (xy 292.386766 -364.310733)
			(xy 292.44043 -364.294496) (xy 292.495893 -364.286284) (xy 292.523926 -364.285784) (xy 292.551178 -364.286254)
			(xy 292.605125 -364.294013) (xy 292.65742 -364.309371) (xy 292.706997 -364.332015) (xy 292.752847 -364.361483)
			(xy 292.794036 -364.397176) (xy 292.829728 -364.438368) (xy 292.859194 -364.484219) (xy 292.881835 -364.533797)
			(xy 292.89719 -364.586092) (xy 292.904948 -364.64004) (xy 292.905434 -364.667292) (xy 292.904986 -364.694867)
			(xy 292.897033 -364.749442) (xy 292.881306 -364.802303) (xy 292.858133 -364.85235) (xy 292.827996 -364.898539)
			(xy 292.791524 -364.939908) (xy 292.770814 -364.958122) (xy 292.759924 -364.968028) (xy 292.743849 -364.992676)
			(xy 292.735464 -365.020882) (xy 292.735462 -365.050308) (xy 292.743845 -365.078515) (xy 292.759917 -365.103164)
			(xy 292.770814 -365.113062) (xy 292.791511 -365.131287) (xy 292.827973 -365.172658) (xy 292.858099 -365.218847)
			(xy 292.88126 -365.268892) (xy 292.896975 -365.321751) (xy 292.904916 -365.376322) (xy 292.904916 -365.431468)
			(xy 292.896977 -365.486038) (xy 292.881264 -365.538898) (xy 292.858104 -365.588944) (xy 292.827979 -365.635134)
			(xy 292.791518 -365.676506) (xy 292.770814 -365.694722) (xy 292.759924 -365.704628) (xy 292.743849 -365.729276)
			(xy 292.735464 -365.757482) (xy 292.735462 -365.786908) (xy 292.743845 -365.815115) (xy 292.759917 -365.839764)
			(xy 292.770814 -365.849662) (xy 292.791513 -365.867886) (xy 292.827983 -365.909253) (xy 292.858117 -365.95544)
			(xy 292.881285 -366.005485) (xy 292.897004 -366.058345) (xy 292.904947 -366.112918) (xy 292.905434 -366.140492)
			(xy 292.904915 -366.167742) (xy 292.89716 -366.221687) (xy 292.881807 -366.27398) (xy 292.86598 -366.30864)
			(xy 294.3352 -366.30864) (xy 294.3352 -365.551974) (xy 294.335661 -365.526986) (xy 294.3435 -365.47763)
			(xy 294.358964 -365.430107) (xy 294.381674 -365.385589) (xy 294.411068 -365.345173) (xy 294.428418 -365.327184)
			(xy 294.964866 -364.790736) (xy 294.975016 -364.779789) (xy 294.989193 -364.753541) (xy 294.995172 -364.724315)
			(xy 294.992441 -364.694608) (xy 294.981234 -364.666961) (xy 294.96251 -364.643738) (xy 294.937868 -364.626923)
			(xy 294.909417 -364.617955) (xy 294.894508 -364.617254) (xy 294.867499 -364.616356) (xy 294.814108 -364.608018)
			(xy 294.762428 -364.59223) (xy 294.713493 -364.569307) (xy 294.668282 -364.539709) (xy 294.6277 -364.504028)
			(xy 294.592558 -364.462978) (xy 294.563561 -364.417379) (xy 294.541287 -364.368145) (xy 294.526184 -364.316261)
			(xy 294.518552 -364.262765) (xy 294.51808 -364.235746) (xy 294.518554 -364.208376) (xy 294.526367 -364.154196)
			(xy 294.541853 -364.101692) (xy 294.564693 -364.051945) (xy 294.594418 -364.005979) (xy 294.61206 -363.985048)
			(xy 294.621255 -363.973689) (xy 294.633443 -363.947143) (xy 294.637626 -363.918235) (xy 294.633463 -363.889324)
			(xy 294.621293 -363.86277) (xy 294.61206 -363.851444) (xy 294.594421 -363.830512) (xy 294.564711 -363.784538)
			(xy 294.541875 -363.734791) (xy 294.526384 -363.68229) (xy 294.518554 -363.628115) (xy 294.51808 -363.600746)
			(xy 294.518566 -363.573495) (xy 294.526322 -363.519547) (xy 294.541677 -363.467252) (xy 294.564319 -363.417675)
			(xy 294.593785 -363.371825) (xy 294.629476 -363.330634) (xy 294.670667 -363.294943) (xy 294.716517 -363.265477)
			(xy 294.766094 -363.242835) (xy 294.818389 -363.22748) (xy 294.872337 -363.219724) (xy 294.926839 -363.219724)
			(xy 294.980787 -363.22748) (xy 295.033082 -363.242835) (xy 295.082659 -363.265477) (xy 295.128509 -363.294943)
			(xy 295.1697 -363.330634) (xy 295.205391 -363.371825) (xy 295.234857 -363.417675) (xy 295.257499 -363.467252)
			(xy 295.272854 -363.519547) (xy 295.28061 -363.573495) (xy 295.281096 -363.600746) (xy 295.280599 -363.628115)
			(xy 295.272789 -363.682293) (xy 295.257307 -363.734796) (xy 295.234472 -363.784543) (xy 295.204754 -363.830511)
			(xy 295.187116 -363.851444) (xy 295.177834 -363.862738) (xy 295.16566 -363.889307) (xy 295.161495 -363.918235)
			(xy 295.165679 -363.94716) (xy 295.177871 -363.973721) (xy 295.187116 -363.985048) (xy 295.204448 -364.005577)
			(xy 295.23375 -364.05061) (xy 295.256434 -364.099313) (xy 295.27205 -364.15072) (xy 295.280287 -364.203811)
			(xy 295.281096 -364.230666) (xy 295.281888 -364.245562) (xy 295.29088 -364.273984) (xy 295.307698 -364.298598)
			(xy 295.330907 -364.317306) (xy 295.358531 -364.328514) (xy 295.388214 -364.331267) (xy 295.417428 -364.325329)
			(xy 295.443681 -364.311208) (xy 295.454578 -364.301024) (xy 295.79316 -363.962442) (xy 295.79316 -362.56214)
			(xy 295.573958 -362.342938) (xy 295.556593 -362.324962) (xy 295.52719 -362.284549) (xy 295.504479 -362.240028)
			(xy 295.489023 -362.1925) (xy 295.481203 -362.143137) (xy 295.48074 -362.118148) (xy 295.48074 -357.165656)
			(xy 294.799258 -356.484174) (xy 294.781911 -356.466182) (xy 294.752505 -356.425773) (xy 294.729791 -356.381257)
			(xy 294.714331 -356.333732) (xy 294.706505 -356.284372) (xy 294.70604 -356.259384) (xy 294.70604 -352.162618)
			(xy 294.706546 -352.137632) (xy 294.714376 -352.088278) (xy 294.729831 -352.040757) (xy 294.75253 -351.996238)
			(xy 294.781914 -351.955819) (xy 294.799258 -351.937828) (xy 294.97147 -351.765616) (xy 294.975026 -351.751646)
			(xy 294.975026 -351.751392) (xy 294.982791 -351.721823) (xy 295.006403 -351.665436) (xy 295.038708 -351.613539)
			(xy 295.058338 -351.590102) (xy 295.067572 -351.578773) (xy 295.079745 -351.552215) (xy 295.083915 -351.5233)
			(xy 295.079745 -351.494385) (xy 295.067572 -351.467827) (xy 295.058338 -351.456498) (xy 295.040697 -351.435565)
			(xy 295.010971 -351.389598) (xy 294.988125 -351.339852) (xy 294.972628 -351.28735) (xy 294.9648 -351.233171)
			(xy 294.9648 -351.178429) (xy 294.972628 -351.12425) (xy 294.988125 -351.071748) (xy 295.010971 -351.022002)
			(xy 295.040697 -350.976035) (xy 295.058338 -350.955102) (xy 295.067572 -350.943773) (xy 295.079745 -350.917215)
			(xy 295.083915 -350.8883) (xy 295.079745 -350.859385) (xy 295.067572 -350.832827) (xy 295.058338 -350.821498)
			(xy 295.040697 -350.800565) (xy 295.010971 -350.754598) (xy 294.988125 -350.704852) (xy 294.972628 -350.65235)
			(xy 294.9648 -350.598171) (xy 294.9648 -350.543429) (xy 294.972628 -350.48925) (xy 294.988125 -350.436748)
			(xy 295.010971 -350.387002) (xy 295.040697 -350.341035) (xy 295.058338 -350.320102) (xy 295.067572 -350.308773)
			(xy 295.079745 -350.282215) (xy 295.083915 -350.2533) (xy 295.079745 -350.224385) (xy 295.067572 -350.197827)
			(xy 295.058338 -350.186498) (xy 295.040697 -350.165565) (xy 295.010971 -350.119598) (xy 294.988125 -350.069852)
			(xy 294.972628 -350.01735) (xy 294.9648 -349.963171) (xy 294.9648 -349.908429) (xy 294.972628 -349.85425)
			(xy 294.988125 -349.801748) (xy 295.010971 -349.752002) (xy 295.040697 -349.706035) (xy 295.058338 -349.685102)
			(xy 295.067572 -349.673773) (xy 295.079745 -349.647215) (xy 295.083915 -349.6183) (xy 295.079745 -349.589385)
			(xy 295.067572 -349.562827) (xy 295.058338 -349.551498) (xy 295.040697 -349.530565) (xy 295.010971 -349.484598)
			(xy 294.988125 -349.434852) (xy 294.972628 -349.38235) (xy 294.9648 -349.328171) (xy 294.9648 -349.273429)
			(xy 294.972628 -349.21925) (xy 294.988125 -349.166748) (xy 295.010971 -349.117002) (xy 295.040697 -349.071035)
			(xy 295.058338 -349.050102) (xy 295.067572 -349.038773) (xy 295.079745 -349.012215) (xy 295.083915 -348.9833)
			(xy 295.079745 -348.954385) (xy 295.067572 -348.927827) (xy 295.058338 -348.916498) (xy 295.040697 -348.895565)
			(xy 295.010971 -348.849598) (xy 294.988125 -348.799852) (xy 294.972628 -348.74735) (xy 294.9648 -348.693171)
			(xy 294.9648 -348.638429) (xy 294.972628 -348.58425) (xy 294.988125 -348.531748) (xy 295.010971 -348.482002)
			(xy 295.040697 -348.436035) (xy 295.058338 -348.415102) (xy 295.067572 -348.403773) (xy 295.079745 -348.377215)
			(xy 295.083915 -348.3483) (xy 295.079745 -348.319385) (xy 295.067572 -348.292827) (xy 295.058338 -348.281498)
			(xy 295.04069 -348.260573) (xy 295.010979 -348.214599) (xy 294.988144 -348.164849) (xy 294.972655 -348.112347)
			(xy 294.96483 -348.05817) (xy 294.964358 -348.0308) (xy 294.964878 -348.00355) (xy 294.972633 -347.949606)
			(xy 294.987987 -347.897314) (xy 295.010625 -347.847739) (xy 295.040089 -347.80189) (xy 295.075776 -347.7607)
			(xy 295.116963 -347.725009) (xy 295.162809 -347.695542) (xy 295.212382 -347.672899) (xy 295.264672 -347.657541)
			(xy 295.318616 -347.64978) (xy 295.345866 -347.649292) (xy 295.373235 -347.64978) (xy 295.427413 -347.657593)
			(xy 295.479916 -347.673077) (xy 295.529663 -347.695914) (xy 295.575631 -347.725633) (xy 295.596564 -347.743272)
			(xy 295.607892 -347.752508) (xy 295.634449 -347.764684) (xy 295.663366 -347.768857) (xy 295.692283 -347.764684)
			(xy 295.71884 -347.752508) (xy 295.730168 -347.743272) (xy 295.751098 -347.72563) (xy 295.797072 -347.69592)
			(xy 295.84682 -347.673085) (xy 295.899321 -347.657594) (xy 295.953497 -347.649766) (xy 295.980866 -347.649292)
			(xy 295.98112 -347.649292) (xy 296.009134 -347.649819) (xy 296.064557 -347.658037) (xy 296.118184 -347.674266)
			(xy 296.168864 -347.698156) (xy 296.21551 -347.729195) (xy 296.236644 -347.74759) (xy 296.248086 -347.757235)
			(xy 296.275129 -347.770015) (xy 296.304716 -347.774401) (xy 296.334303 -347.770015) (xy 296.361346 -347.757235)
			(xy 296.372788 -347.74759) (xy 296.393905 -347.729169) (xy 296.440539 -347.698099) (xy 296.491222 -347.674194)
			(xy 296.544859 -347.657971) (xy 296.600293 -347.64978) (xy 296.628312 -347.649292) (xy 296.628566 -347.649292)
			(xy 296.655818 -347.649787) (xy 296.709768 -347.657539) (xy 296.762065 -347.672891) (xy 296.811645 -347.69553)
			(xy 296.857498 -347.724994) (xy 296.898691 -347.760684) (xy 296.934386 -347.801874) (xy 296.963854 -347.847725)
			(xy 296.986497 -347.897303) (xy 297.001853 -347.949599) (xy 297.009611 -348.003548) (xy 297.010074 -348.0308)
			(xy 297.009614 -348.058171) (xy 297.001796 -348.11235) (xy 296.986306 -348.164854) (xy 296.963462 -348.2146)
			(xy 296.933736 -348.260567) (xy 296.916094 -348.281498) (xy 296.906858 -348.292825) (xy 296.894681 -348.319383)
			(xy 296.890509 -348.3483) (xy 296.894681 -348.377217) (xy 296.906858 -348.403775) (xy 296.916094 -348.415102)
			(xy 296.933734 -348.436035) (xy 296.963457 -348.482003) (xy 296.986301 -348.53175) (xy 297.001796 -348.584252)
			(xy 297.009625 -348.63843) (xy 297.009625 -348.69317) (xy 297.001796 -348.747348) (xy 296.986301 -348.79985)
			(xy 296.963457 -348.849597) (xy 296.933734 -348.895565) (xy 296.916094 -348.916498) (xy 296.906858 -348.927825)
			(xy 296.894681 -348.954383) (xy 296.890509 -348.9833) (xy 296.894681 -349.012217) (xy 296.906858 -349.038775)
			(xy 296.916094 -349.050102) (xy 296.933734 -349.071035) (xy 296.963457 -349.117003) (xy 296.986301 -349.16675)
			(xy 297.001796 -349.219252) (xy 297.009625 -349.27343) (xy 297.009625 -349.32817) (xy 297.001796 -349.382348)
			(xy 296.986301 -349.43485) (xy 296.963457 -349.484597) (xy 296.933734 -349.530565) (xy 296.916094 -349.551498)
			(xy 296.906858 -349.562825) (xy 296.894681 -349.589383) (xy 296.890509 -349.6183) (xy 296.894681 -349.647217)
			(xy 296.906858 -349.673775) (xy 296.916094 -349.685102) (xy 296.933734 -349.706035) (xy 296.963457 -349.752003)
			(xy 296.986301 -349.80175) (xy 297.001796 -349.854252) (xy 297.009625 -349.90843) (xy 297.009625 -349.96317)
			(xy 297.001796 -350.017348) (xy 296.986301 -350.06985) (xy 296.963457 -350.119597) (xy 296.933734 -350.165565)
			(xy 296.916094 -350.186498) (xy 296.906858 -350.197825) (xy 296.894681 -350.224383) (xy 296.890509 -350.2533)
			(xy 296.894681 -350.282217) (xy 296.906858 -350.308775) (xy 296.916094 -350.320102) (xy 296.933734 -350.341035)
			(xy 296.963457 -350.387003) (xy 296.986301 -350.43675) (xy 297.001796 -350.489252) (xy 297.009625 -350.54343)
			(xy 297.009625 -350.59817) (xy 297.001796 -350.652348) (xy 296.986301 -350.70485) (xy 296.963457 -350.754597)
			(xy 296.933734 -350.800565) (xy 296.916094 -350.821498) (xy 296.906858 -350.832825) (xy 296.894681 -350.859383)
			(xy 296.890509 -350.8883) (xy 296.894681 -350.917217) (xy 296.906858 -350.943775) (xy 296.916094 -350.955102)
			(xy 296.933734 -350.976035) (xy 296.963457 -351.022003) (xy 296.986301 -351.07175) (xy 297.001796 -351.124252)
			(xy 297.009625 -351.17843) (xy 297.009625 -351.23317) (xy 297.001796 -351.287348) (xy 296.986301 -351.33985)
			(xy 296.963457 -351.389597) (xy 296.933734 -351.435565) (xy 296.916094 -351.456498) (xy 296.906858 -351.467825)
			(xy 296.894681 -351.494383) (xy 296.890509 -351.5233) (xy 296.894681 -351.552217) (xy 296.906858 -351.578775)
			(xy 296.916094 -351.590102) (xy 296.933747 -351.611023) (xy 296.963457 -351.656999) (xy 296.98629 -351.706749)
			(xy 297.001778 -351.759252) (xy 297.009602 -351.81343) (xy 297.010074 -351.8408) (xy 300.03623 -351.8408)
			(xy 300.036689 -351.813429) (xy 300.044507 -351.75925) (xy 300.059998 -351.706746) (xy 300.082841 -351.656999)
			(xy 300.112568 -351.611033) (xy 300.13021 -351.590102) (xy 300.139446 -351.578774) (xy 300.151622 -351.552217)
			(xy 300.155794 -351.5233) (xy 300.151622 -351.494383) (xy 300.139446 -351.467826) (xy 300.13021 -351.456498)
			(xy 300.11257 -351.435565) (xy 300.082847 -351.389597) (xy 300.060002 -351.33985) (xy 300.044507 -351.287349)
			(xy 300.036678 -351.23317) (xy 300.036678 -351.17843) (xy 300.044507 -351.124251) (xy 300.060002 -351.07175)
			(xy 300.082847 -351.022003) (xy 300.11257 -350.976035) (xy 300.13021 -350.955102) (xy 300.139446 -350.943774)
			(xy 300.151622 -350.917217) (xy 300.155794 -350.8883) (xy 300.151622 -350.859383) (xy 300.139446 -350.832826)
			(xy 300.13021 -350.821498) (xy 300.11257 -350.800565) (xy 300.082847 -350.754597) (xy 300.060002 -350.70485)
			(xy 300.044507 -350.652349) (xy 300.036678 -350.59817) (xy 300.036678 -350.54343) (xy 300.044507 -350.489251)
			(xy 300.060002 -350.43675) (xy 300.082847 -350.387003) (xy 300.11257 -350.341035) (xy 300.13021 -350.320102)
			(xy 300.139446 -350.308774) (xy 300.151622 -350.282217) (xy 300.155794 -350.2533) (xy 300.151622 -350.224383)
			(xy 300.139446 -350.197826) (xy 300.13021 -350.186498) (xy 300.11257 -350.165565) (xy 300.082847 -350.119597)
			(xy 300.060002 -350.06985) (xy 300.044507 -350.017349) (xy 300.036678 -349.96317) (xy 300.036678 -349.90843)
			(xy 300.044507 -349.854251) (xy 300.060002 -349.80175) (xy 300.082847 -349.752003) (xy 300.11257 -349.706035)
			(xy 300.13021 -349.685102) (xy 300.139446 -349.673774) (xy 300.151622 -349.647217) (xy 300.155794 -349.6183)
			(xy 300.151622 -349.589383) (xy 300.139446 -349.562826) (xy 300.13021 -349.551498) (xy 300.11257 -349.530565)
			(xy 300.082847 -349.484597) (xy 300.060002 -349.43485) (xy 300.044507 -349.382349) (xy 300.036678 -349.32817)
			(xy 300.036678 -349.27343) (xy 300.044507 -349.219251) (xy 300.060002 -349.16675) (xy 300.082847 -349.117003)
			(xy 300.11257 -349.071035) (xy 300.13021 -349.050102) (xy 300.139446 -349.038774) (xy 300.151622 -349.012217)
			(xy 300.155794 -348.9833) (xy 300.151622 -348.954383) (xy 300.139446 -348.927826) (xy 300.13021 -348.916498)
			(xy 300.11257 -348.895565) (xy 300.082847 -348.849597) (xy 300.060002 -348.79985) (xy 300.044507 -348.747349)
			(xy 300.036678 -348.69317) (xy 300.036678 -348.63843) (xy 300.044507 -348.584251) (xy 300.060002 -348.53175)
			(xy 300.082847 -348.482003) (xy 300.11257 -348.436035) (xy 300.13021 -348.415102) (xy 300.139446 -348.403774)
			(xy 300.151622 -348.377217) (xy 300.155794 -348.3483) (xy 300.151622 -348.319383) (xy 300.139446 -348.292826)
			(xy 300.13021 -348.281498) (xy 300.112558 -348.260576) (xy 300.082848 -348.214601) (xy 300.060014 -348.164851)
			(xy 300.044526 -348.112348) (xy 300.036702 -348.05817) (xy 300.03623 -348.0308) (xy 300.036655 -348.003545)
			(xy 300.044413 -347.949591) (xy 300.059771 -347.89729) (xy 300.082417 -347.847708) (xy 300.111888 -347.801853)
			(xy 300.147586 -347.760659) (xy 300.188783 -347.724965) (xy 300.234641 -347.695498) (xy 300.284226 -347.672858)
			(xy 300.336528 -347.657505) (xy 300.390483 -347.649753) (xy 300.417738 -347.649292) (xy 300.417992 -347.649292)
			(xy 300.446008 -347.649776) (xy 300.501432 -347.658005) (xy 300.55506 -347.674243) (xy 300.605739 -347.698143)
			(xy 300.652383 -347.729191) (xy 300.673516 -347.74759) (xy 300.684958 -347.757235) (xy 300.712001 -347.770015)
			(xy 300.741588 -347.774401) (xy 300.771175 -347.770015) (xy 300.798218 -347.757235) (xy 300.80966 -347.74759)
			(xy 300.830788 -347.729182) (xy 300.877419 -347.69811) (xy 300.928099 -347.674203) (xy 300.981733 -347.657977)
			(xy 301.037166 -347.649782) (xy 301.065184 -347.649292) (xy 301.065438 -347.649292) (xy 301.092807 -347.649796)
			(xy 301.146984 -347.657605) (xy 301.199487 -347.673085) (xy 301.249234 -347.695919) (xy 301.295203 -347.725635)
			(xy 301.316136 -347.743272) (xy 301.327464 -347.752508) (xy 301.354021 -347.764684) (xy 301.382938 -347.768857)
			(xy 301.411855 -347.764684) (xy 301.438412 -347.752508) (xy 301.44974 -347.743272) (xy 301.47068 -347.725643)
			(xy 301.516651 -347.695931) (xy 301.566397 -347.673093) (xy 301.618895 -347.6576) (xy 301.673069 -347.649768)
			(xy 301.700438 -347.649292) (xy 301.72769 -347.649742) (xy 301.781639 -347.657504) (xy 301.833935 -347.672864)
			(xy 301.883512 -347.69551) (xy 301.929362 -347.72498) (xy 301.970552 -347.760675) (xy 302.006243 -347.801868)
			(xy 302.035709 -347.847721) (xy 302.058349 -347.897301) (xy 302.073704 -347.949598) (xy 302.08146 -348.003548)
			(xy 302.081946 -348.0308) (xy 302.081493 -348.058171) (xy 302.073674 -348.112351) (xy 302.058183 -348.164855)
			(xy 302.035338 -348.214602) (xy 302.005609 -348.260567) (xy 301.987966 -348.281498) (xy 301.978732 -348.292826)
			(xy 301.966559 -348.319384) (xy 301.962388 -348.3483) (xy 301.966559 -348.377216) (xy 301.978732 -348.403774)
			(xy 301.987966 -348.415102) (xy 302.005607 -348.436035) (xy 302.035332 -348.482002) (xy 302.058178 -348.531748)
			(xy 302.073675 -348.584251) (xy 302.081503 -348.638429) (xy 302.081503 -348.693171) (xy 302.073675 -348.747349)
			(xy 302.058178 -348.799852) (xy 302.035332 -348.849598) (xy 302.005607 -348.895565) (xy 301.987966 -348.916498)
			(xy 301.978732 -348.927826) (xy 301.966559 -348.954384) (xy 301.962388 -348.9833) (xy 301.966559 -349.012216)
			(xy 301.978732 -349.038774) (xy 301.987966 -349.050102) (xy 302.005607 -349.071035) (xy 302.035332 -349.117002)
			(xy 302.058178 -349.166748) (xy 302.073675 -349.219251) (xy 302.081503 -349.273429) (xy 302.081503 -349.328171)
			(xy 302.073675 -349.382349) (xy 302.058178 -349.434852) (xy 302.035332 -349.484598) (xy 302.005607 -349.530565)
			(xy 301.987966 -349.551498) (xy 301.978732 -349.562826) (xy 301.966559 -349.589384) (xy 301.962388 -349.6183)
			(xy 301.966559 -349.647216) (xy 301.978732 -349.673774) (xy 301.987966 -349.685102) (xy 302.005607 -349.706035)
			(xy 302.035332 -349.752002) (xy 302.058178 -349.801748) (xy 302.073675 -349.854251) (xy 302.081503 -349.908429)
			(xy 302.081503 -349.963171) (xy 302.073675 -350.017349) (xy 302.058178 -350.069852) (xy 302.035332 -350.119598)
			(xy 302.005607 -350.165565) (xy 301.987966 -350.186498) (xy 301.978732 -350.197826) (xy 301.966559 -350.224384)
			(xy 301.962388 -350.2533) (xy 301.966559 -350.282216) (xy 301.978732 -350.308774) (xy 301.987966 -350.320102)
			(xy 302.005607 -350.341035) (xy 302.035332 -350.387002) (xy 302.058178 -350.436748) (xy 302.073675 -350.489251)
			(xy 302.081503 -350.543429) (xy 302.081503 -350.598171) (xy 302.073675 -350.652349) (xy 302.058178 -350.704852)
			(xy 302.035332 -350.754598) (xy 302.005607 -350.800565) (xy 301.987966 -350.821498) (xy 301.978732 -350.832826)
			(xy 301.966559 -350.859384) (xy 301.962388 -350.8883) (xy 301.966559 -350.917216) (xy 301.978732 -350.943774)
			(xy 301.987966 -350.955102) (xy 302.005607 -350.976035) (xy 302.035332 -351.022002) (xy 302.058178 -351.071748)
			(xy 302.073675 -351.124251) (xy 302.081503 -351.178429) (xy 302.081503 -351.233171) (xy 302.073675 -351.287349)
			(xy 302.058178 -351.339852) (xy 302.035332 -351.389598) (xy 302.005607 -351.435565) (xy 301.987966 -351.456498)
			(xy 301.978732 -351.467826) (xy 301.966559 -351.494384) (xy 301.962388 -351.5233) (xy 301.966559 -351.552216)
			(xy 301.978732 -351.578774) (xy 301.987966 -351.590102) (xy 302.005614 -351.611027) (xy 302.035326 -351.657001)
			(xy 302.058161 -351.70675) (xy 302.073649 -351.759253) (xy 302.081474 -351.81343) (xy 302.081946 -351.8408)
			(xy 302.081422 -351.86805) (xy 302.073667 -351.921994) (xy 302.058314 -351.974286) (xy 302.035675 -352.02386)
			(xy 302.006212 -352.069709) (xy 301.970525 -352.110898) (xy 301.929339 -352.14659) (xy 301.883494 -352.176057)
			(xy 301.833921 -352.1987) (xy 301.781631 -352.214059) (xy 301.727687 -352.22182) (xy 301.700438 -352.222308)
			(xy 301.673069 -352.221818) (xy 301.618891 -352.214005) (xy 301.566388 -352.198522) (xy 301.516641 -352.175686)
			(xy 301.470673 -352.145967) (xy 301.44974 -352.128328) (xy 301.438412 -352.119092) (xy 301.411855 -352.106916)
			(xy 301.382938 -352.102743) (xy 301.354021 -352.106916) (xy 301.327464 -352.119092) (xy 301.316136 -352.128328)
			(xy 301.295205 -352.145968) (xy 301.249231 -352.175679) (xy 301.199484 -352.198514) (xy 301.146983 -352.214005)
			(xy 301.092807 -352.221834) (xy 301.065438 -352.222308) (xy 301.065184 -352.222308) (xy 301.03717 -352.221779)
			(xy 300.981747 -352.213561) (xy 300.92812 -352.197333) (xy 300.87744 -352.173443) (xy 300.830794 -352.142405)
			(xy 300.80966 -352.12401) (xy 300.798218 -352.114365) (xy 300.771175 -352.101585) (xy 300.741588 -352.097199)
			(xy 300.712001 -352.101585) (xy 300.684958 -352.114365) (xy 300.673516 -352.12401) (xy 300.652398 -352.142429)
			(xy 300.605764 -352.1735) (xy 300.555082 -352.197404) (xy 300.501445 -352.213628) (xy 300.44601 -352.22182)
			(xy 300.417992 -352.222308) (xy 300.417738 -352.222308) (xy 300.390486 -352.221809) (xy 300.336536 -352.214058)
			(xy 300.284239 -352.198706) (xy 300.234659 -352.176068) (xy 300.188806 -352.146604) (xy 300.147613 -352.110914)
			(xy 300.111919 -352.069725) (xy 300.08245 -352.023874) (xy 300.059807 -351.974296) (xy 300.044451 -351.922001)
			(xy 300.036693 -351.868052) (xy 300.03623 -351.8408) (xy 297.010074 -351.8408) (xy 297.009645 -351.868054)
			(xy 297.001887 -351.922008) (xy 296.986529 -351.974309) (xy 296.963884 -352.023891) (xy 296.934413 -352.069746)
			(xy 296.898715 -352.11094) (xy 296.857519 -352.146633) (xy 296.811661 -352.1761) (xy 296.762077 -352.198741)
			(xy 296.709775 -352.214094) (xy 296.65582 -352.221847) (xy 296.628566 -352.222308) (xy 296.628312 -352.222308)
			(xy 296.600296 -352.221822) (xy 296.544872 -352.213593) (xy 296.491244 -352.197355) (xy 296.440565 -352.173456)
			(xy 296.393921 -352.142409) (xy 296.372788 -352.12401) (xy 296.361346 -352.114365) (xy 296.334303 -352.101585)
			(xy 296.304716 -352.097199) (xy 296.275129 -352.101585) (xy 296.248086 -352.114365) (xy 296.236644 -352.12401)
			(xy 296.215515 -352.142416) (xy 296.168884 -352.173488) (xy 296.118204 -352.197396) (xy 296.06457 -352.213622)
			(xy 296.009138 -352.221818) (xy 295.98112 -352.222308) (xy 295.980866 -352.222308) (xy 295.953495 -352.22186)
			(xy 295.899315 -352.214037) (xy 295.846812 -352.198544) (xy 295.797066 -352.175698) (xy 295.751099 -352.145971)
			(xy 295.730168 -352.128328) (xy 295.71884 -352.119092) (xy 295.692283 -352.106916) (xy 295.663366 -352.102743)
			(xy 295.634449 -352.106916) (xy 295.607892 -352.119092) (xy 295.596564 -352.128328) (xy 295.573091 -352.147973)
			(xy 295.521102 -352.180278) (xy 295.464633 -352.203894) (xy 295.43502 -352.21164) (xy 295.42105 -352.215196)
			(xy 295.342056 -352.29419) (xy 295.342056 -356.127812) (xy 296.023538 -356.809294) (xy 296.040917 -356.827256)
			(xy 296.070319 -356.867674) (xy 296.093027 -356.912197) (xy 296.10848 -356.959729) (xy 296.116296 -357.009094)
			(xy 296.116756 -357.034084) (xy 296.116756 -361.986576) (xy 296.335958 -362.205778) (xy 296.353333 -362.223744)
			(xy 296.382735 -362.264161) (xy 296.405443 -362.308684) (xy 296.420897 -362.356214) (xy 296.428715 -362.405578)
			(xy 296.429176 -362.430568) (xy 296.429176 -363.859064) (xy 302.365154 -363.859064) (xy 302.369225 -363.803442)
			(xy 302.381351 -363.749005) (xy 302.401274 -363.696914) (xy 302.42857 -363.648279) (xy 302.462656 -363.604136)
			(xy 302.502805 -363.565427) (xy 302.548163 -363.532976) (xy 302.597763 -363.507475) (xy 302.650547 -363.489468)
			(xy 302.70539 -363.479338) (xy 302.761124 -363.477301) (xy 302.816561 -363.483401) (xy 302.870518 -363.497507)
			(xy 302.921847 -363.519319) (xy 302.969453 -363.548373) (xy 303.012321 -363.584048) (xy 303.049538 -363.625585)
			(xy 303.080311 -363.672098) (xy 303.103983 -363.722595) (xy 303.120051 -363.776002) (xy 303.128171 -363.831178)
			(xy 303.12868 -363.859064) (xy 303.128171 -363.88695) (xy 303.120051 -363.942126) (xy 303.103983 -363.995533)
			(xy 303.080311 -364.04603) (xy 303.049538 -364.092543) (xy 303.012321 -364.13408) (xy 302.969453 -364.169755)
			(xy 302.921847 -364.198809) (xy 302.870518 -364.220621) (xy 302.816561 -364.234727) (xy 302.761124 -364.240827)
			(xy 302.70539 -364.23879) (xy 302.650547 -364.22866) (xy 302.597763 -364.210653) (xy 302.548163 -364.185152)
			(xy 302.502805 -364.152701) (xy 302.462656 -364.113992) (xy 302.42857 -364.069849) (xy 302.401274 -364.021214)
			(xy 302.381351 -363.969123) (xy 302.369225 -363.914686) (xy 302.365154 -363.859064) (xy 296.429176 -363.859064)
			(xy 296.429176 -364.094014) (xy 296.42866 -364.118998) (xy 296.420826 -364.168349) (xy 296.405368 -364.215866)
			(xy 296.382668 -364.260381) (xy 296.353284 -364.300797) (xy 296.335958 -364.318804) (xy 296.016462 -364.6383)
			(xy 298.766795 -364.6383) (xy 298.770962 -364.582695) (xy 298.783369 -364.528332) (xy 298.80374 -364.476425)
			(xy 298.831619 -364.428134) (xy 298.866383 -364.384537) (xy 298.907257 -364.346608) (xy 298.953327 -364.315194)
			(xy 299.003564 -364.290997) (xy 299.056846 -364.274557) (xy 299.111984 -364.266241) (xy 299.139864 -364.265718)
			(xy 299.167196 -364.266193) (xy 299.221275 -364.274163) (xy 299.273609 -364.289951) (xy 299.323073 -364.313218)
			(xy 299.368605 -364.343465) (xy 299.409228 -364.380043) (xy 299.444068 -364.422164) (xy 299.458634 -364.445296)
			(xy 299.466548 -364.457527) (xy 299.488021 -364.477199) (xy 299.514177 -364.490003) (xy 299.542885 -364.494896)
			(xy 299.571806 -364.49148) (xy 299.58538 -364.48619) (xy 299.608595 -364.476714) (xy 299.656925 -364.463358)
			(xy 299.706613 -364.456624) (xy 299.731684 -364.456218) (xy 299.756753 -364.45666) (xy 299.806435 -364.463402)
			(xy 299.85477 -364.476727) (xy 299.877988 -364.48619) (xy 299.891578 -364.491412) (xy 299.92048 -364.494797)
			(xy 299.949165 -364.489902) (xy 299.975309 -364.477123) (xy 299.996793 -364.457496) (xy 300.004734 -364.445296)
			(xy 300.019303 -364.422165) (xy 300.054146 -364.380044) (xy 300.094769 -364.343465) (xy 300.1403 -364.313214)
			(xy 300.189762 -364.289938) (xy 300.242093 -364.274138) (xy 300.296172 -364.266152) (xy 300.350836 -364.266152)
			(xy 300.404915 -364.274138) (xy 300.457246 -364.289938) (xy 300.506708 -364.313214) (xy 300.552239 -364.343465)
			(xy 300.592862 -364.380044) (xy 300.627705 -364.422165) (xy 300.642274 -364.445296) (xy 300.650245 -364.457486)
			(xy 300.671703 -364.477157) (xy 300.697843 -364.489967) (xy 300.726538 -364.494871) (xy 300.755449 -364.491471)
			(xy 300.76902 -364.48619) (xy 300.79223 -364.476701) (xy 300.840563 -364.46335) (xy 300.890252 -364.456622)
			(xy 300.915324 -364.456218) (xy 300.942169 -364.456634) (xy 300.995301 -364.464342) (xy 301.046778 -364.479596)
			(xy 301.095533 -364.50208) (xy 301.140556 -364.531328) (xy 301.180915 -364.566735) (xy 301.215776 -364.607567)
			(xy 301.244415 -364.65298) (xy 301.266241 -364.702032) (xy 301.273972 -364.727744) (xy 301.27869 -364.742221)
			(xy 301.295197 -364.767781) (xy 301.318501 -364.787346) (xy 301.346533 -364.799179) (xy 301.376807 -364.80223)
			(xy 301.406637 -364.796229) (xy 301.420276 -364.789466) (xy 301.448418 -364.774824) (xy 301.508371 -364.7541)
			(xy 301.570931 -364.743605) (xy 301.602648 -364.742984) (xy 301.620667 -364.743202) (xy 301.656542 -364.746638)
			(xy 301.674276 -364.749842) (xy 301.689487 -364.752168) (xy 301.720039 -364.748646) (xy 301.748159 -364.736189)
			(xy 301.771295 -364.715925) (xy 301.787349 -364.689693) (xy 301.791624 -364.674912) (xy 301.798986 -364.647858)
			(xy 301.820622 -364.596131) (xy 301.849592 -364.548127) (xy 301.885273 -364.504876) (xy 301.926896 -364.46731)
			(xy 301.973568 -364.436238) (xy 302.024282 -364.412327) (xy 302.077949 -364.396092) (xy 302.133414 -364.387882)
			(xy 302.161448 -364.387384) (xy 302.1887 -364.387833) (xy 302.242649 -364.395596) (xy 302.294944 -364.410957)
			(xy 302.34452 -364.433603) (xy 302.39037 -364.463073) (xy 302.43156 -364.498769) (xy 302.467251 -364.539962)
			(xy 302.496716 -364.585815) (xy 302.519357 -364.635394) (xy 302.534713 -364.68769) (xy 302.54247 -364.74164)
			(xy 302.542956 -364.768892) (xy 302.5425 -364.796467) (xy 302.534548 -364.851041) (xy 302.518822 -364.903902)
			(xy 302.49565 -364.953948) (xy 302.465515 -365.000137) (xy 302.429045 -365.041507) (xy 302.408336 -365.059722)
			(xy 302.397444 -365.069627) (xy 302.381366 -365.094274) (xy 302.372978 -365.122481) (xy 302.372977 -365.151909)
			(xy 302.381361 -365.180116) (xy 302.397437 -365.204765) (xy 302.408336 -365.214662) (xy 302.429032 -365.232888)
			(xy 302.465492 -365.274259) (xy 302.495616 -365.320449) (xy 302.518776 -365.370494) (xy 302.53449 -365.423352)
			(xy 302.54243 -365.477922) (xy 302.542431 -365.533067) (xy 302.534492 -365.587637) (xy 302.51878 -365.640496)
			(xy 302.495621 -365.690542) (xy 302.465498 -365.736733) (xy 302.429039 -365.778105) (xy 302.408336 -365.796322)
			(xy 302.397444 -365.806227) (xy 302.381366 -365.830874) (xy 302.372978 -365.859081) (xy 302.372977 -365.888509)
			(xy 302.381361 -365.916716) (xy 302.397437 -365.941365) (xy 302.408336 -365.951262) (xy 302.429039 -365.969482)
			(xy 302.465509 -366.010849) (xy 302.495641 -366.057038) (xy 302.518808 -366.107084) (xy 302.534526 -366.159945)
			(xy 302.542469 -366.214518) (xy 302.542956 -366.242092) (xy 302.542415 -366.269341) (xy 302.534661 -366.323284)
			(xy 302.519309 -366.375575) (xy 302.496672 -366.425149) (xy 302.467211 -366.470997) (xy 302.431526 -366.512186)
			(xy 302.390342 -366.547878) (xy 302.344498 -366.577345) (xy 302.294927 -366.599989) (xy 302.242639 -366.615349)
			(xy 302.188697 -366.623111) (xy 302.161448 -366.6236) (xy 302.133594 -366.623034) (xy 302.07848 -366.614917)
			(xy 302.025131 -366.598878) (xy 301.974679 -366.575257) (xy 301.928194 -366.544555) (xy 301.886664 -366.507425)
			(xy 301.85097 -366.464655) (xy 301.82187 -366.417151) (xy 301.799981 -366.365923) (xy 301.792386 -366.33912)
			(xy 301.788085 -366.325013) (xy 301.772701 -366.29987) (xy 301.75079 -366.280153) (xy 301.724168 -366.2675)
			(xy 301.695043 -366.262958) (xy 301.680372 -366.264444) (xy 301.667419 -366.266108) (xy 301.641361 -366.267887)
			(xy 301.628302 -366.268) (xy 301.628048 -366.268) (xy 301.613899 -366.267901) (xy 301.585676 -366.26587)
			(xy 301.57166 -366.263936) (xy 301.558312 -366.262339) (xy 301.531617 -366.265436) (xy 301.506661 -366.275405)
			(xy 301.485179 -366.291553) (xy 301.468668 -366.312756) (xy 301.458275 -366.337539) (xy 301.45609 -366.350804)
			(xy 301.451996 -366.377957) (xy 301.437027 -366.430789) (xy 301.414638 -366.480929) (xy 301.385293 -366.527342)
			(xy 301.349596 -366.569067) (xy 301.308286 -366.605245) (xy 301.262217 -366.635126) (xy 301.21234 -366.658094)
			(xy 301.159685 -366.673674) (xy 301.10534 -366.681544) (xy 301.077884 -366.68202) (xy 301.050633 -366.681537)
			(xy 300.996686 -366.673779) (xy 300.944392 -366.658422) (xy 300.894815 -366.63578) (xy 300.848965 -366.606313)
			(xy 300.807776 -366.570622) (xy 300.772084 -366.529431) (xy 300.742618 -366.483581) (xy 300.719976 -366.434005)
			(xy 300.70462 -366.38171) (xy 300.696863 -366.327763) (xy 300.696376 -366.300512) (xy 300.696858 -366.272938)
			(xy 300.704809 -366.218366) (xy 300.720531 -366.165507) (xy 300.743698 -366.115461) (xy 300.773827 -366.069271)
			(xy 300.810291 -366.027899) (xy 300.830996 -366.009682) (xy 300.841881 -365.999771) (xy 300.857954 -365.975124)
			(xy 300.866339 -365.94692) (xy 300.866342 -365.917495) (xy 300.857961 -365.88929) (xy 300.841891 -365.864641)
			(xy 300.830996 -365.854742) (xy 300.810301 -365.836513) (xy 300.77383 -365.795148) (xy 300.743696 -365.748962)
			(xy 300.720527 -365.698917) (xy 300.704807 -365.646058) (xy 300.696864 -365.591486) (xy 300.696376 -365.563912)
			(xy 300.69686 -365.537412) (xy 300.704199 -365.484922) (xy 300.718737 -365.433955) (xy 300.740193 -365.385492)
			(xy 300.768154 -365.340468) (xy 300.784768 -365.319818) (xy 300.79424 -365.307695) (xy 300.806022 -365.279286)
			(xy 300.808838 -365.248661) (xy 300.802436 -365.218581) (xy 300.787392 -365.191757) (xy 300.765062 -365.170609)
			(xy 300.751494 -365.163354) (xy 300.727822 -365.15122) (xy 300.683837 -365.121307) (xy 300.644551 -365.085446)
			(xy 300.610762 -365.044364) (xy 300.596554 -365.021876) (xy 300.588658 -365.009633) (xy 300.567178 -364.989964)
			(xy 300.541017 -364.977164) (xy 300.512307 -364.972273) (xy 300.483383 -364.975691) (xy 300.469808 -364.980982)
			(xy 300.446594 -364.99046) (xy 300.398263 -365.003816) (xy 300.348575 -365.010548) (xy 300.323504 -365.010954)
			(xy 300.298435 -365.010518) (xy 300.248752 -365.003774) (xy 300.200418 -364.990446) (xy 300.1772 -364.980982)
			(xy 300.163598 -364.975809) (xy 300.13471 -364.972429) (xy 300.106041 -364.977324) (xy 300.079911 -364.990095)
			(xy 300.058436 -365.009709) (xy 300.050454 -365.021876) (xy 300.035885 -365.045007) (xy 300.001042 -365.087128)
			(xy 299.960419 -365.123707) (xy 299.914888 -365.153958) (xy 299.865426 -365.177234) (xy 299.813095 -365.193034)
			(xy 299.759016 -365.20102) (xy 299.704352 -365.20102) (xy 299.650273 -365.193034) (xy 299.597942 -365.177234)
			(xy 299.54848 -365.153958) (xy 299.502949 -365.123707) (xy 299.462326 -365.087128) (xy 299.427483 -365.045007)
			(xy 299.412914 -365.021876) (xy 299.404961 -365.009674) (xy 299.383497 -364.990005) (xy 299.357351 -364.977199)
			(xy 299.328654 -364.972298) (xy 299.299741 -364.9757) (xy 299.286168 -364.980982) (xy 299.262959 -364.990473)
			(xy 299.214626 -365.003824) (xy 299.164936 -365.010551) (xy 299.139864 -365.010954) (xy 299.111984 -365.010359)
			(xy 299.056846 -365.002043) (xy 299.003564 -364.985603) (xy 298.953327 -364.961406) (xy 298.907257 -364.929992)
			(xy 298.866383 -364.892063) (xy 298.831619 -364.848466) (xy 298.80374 -364.800175) (xy 298.783369 -364.748268)
			(xy 298.770962 -364.693905) (xy 298.766795 -364.6383) (xy 296.016462 -364.6383) (xy 294.971216 -365.683546)
			(xy 294.971216 -365.70412) (xy 295.309034 -365.70412) (xy 295.313105 -365.648498) (xy 295.325231 -365.594061)
			(xy 295.345154 -365.54197) (xy 295.37245 -365.493335) (xy 295.406536 -365.449192) (xy 295.446685 -365.410483)
			(xy 295.492043 -365.378032) (xy 295.541643 -365.352531) (xy 295.594427 -365.334524) (xy 295.64927 -365.324394)
			(xy 295.705004 -365.322357) (xy 295.760441 -365.328457) (xy 295.814398 -365.342563) (xy 295.865727 -365.364375)
			(xy 295.913333 -365.393429) (xy 295.956201 -365.429104) (xy 295.993418 -365.470641) (xy 296.024191 -365.517154)
			(xy 296.047863 -365.567651) (xy 296.063931 -365.621058) (xy 296.072051 -365.676234) (xy 296.07256 -365.70412)
			(xy 296.072051 -365.732006) (xy 296.063931 -365.787182) (xy 296.047863 -365.840589) (xy 296.024191 -365.891086)
			(xy 295.993418 -365.937599) (xy 295.956201 -365.979136) (xy 295.913333 -366.014811) (xy 295.865727 -366.043865)
			(xy 295.814398 -366.065677) (xy 295.760441 -366.079783) (xy 295.705004 -366.085883) (xy 295.64927 -366.083846)
			(xy 295.594427 -366.073716) (xy 295.541643 -366.055709) (xy 295.492043 -366.030208) (xy 295.446685 -365.997757)
			(xy 295.406536 -365.959048) (xy 295.37245 -365.914905) (xy 295.345154 -365.86627) (xy 295.325231 -365.814179)
			(xy 295.313105 -365.759742) (xy 295.309034 -365.70412) (xy 294.971216 -365.70412) (xy 294.971216 -366.177068)
			(xy 295.101772 -366.307624) (xy 295.115742 -366.31118) (xy 295.143144 -366.31828) (xy 295.195623 -366.339494)
			(xy 295.244391 -366.36823) (xy 295.288378 -366.403856) (xy 295.326618 -366.445591) (xy 295.358272 -366.492518)
			(xy 295.382644 -366.543607) (xy 295.3992 -366.597736) (xy 295.407575 -366.653718) (xy 295.408096 -366.68202)
			(xy 295.407641 -366.709272) (xy 295.399881 -366.763222) (xy 295.384523 -366.815518) (xy 295.361879 -366.865096)
			(xy 295.332409 -366.910947) (xy 295.296714 -366.952137) (xy 295.255521 -366.987828) (xy 295.209668 -367.017294)
			(xy 295.160088 -367.039934) (xy 295.10779 -367.055288) (xy 295.05384 -367.063043) (xy 295.026588 -367.063528)
			(xy 294.998296 -367.063057) (xy 294.942336 -367.054685) (xy 294.888225 -367.03814) (xy 294.837151 -367.013787)
			(xy 294.790233 -366.982158) (xy 294.7485 -366.943947) (xy 294.712868 -366.899992) (xy 294.684117 -366.851258)
			(xy 294.662878 -366.798811) (xy 294.655748 -366.771428) (xy 294.655748 -366.771174) (xy 294.652192 -366.757204)
			(xy 294.428418 -366.53343) (xy 294.41106 -366.515448) (xy 294.381653 -366.475037) (xy 294.35894 -366.430518)
			(xy 294.343483 -366.382991) (xy 294.335662 -366.333629) (xy 294.3352 -366.30864) (xy 292.86598 -366.30864)
			(xy 292.859169 -366.323555) (xy 292.829706 -366.369404) (xy 292.794018 -366.410594) (xy 292.752832 -366.446286)
			(xy 292.706985 -366.475753) (xy 292.657412 -366.498395) (xy 292.60512 -366.513753) (xy 292.551176 -366.521512)
			(xy 292.523926 -366.522) (xy 292.496072 -366.521453) (xy 292.440957 -366.513334) (xy 292.387607 -366.497291)
			(xy 292.337155 -366.473668) (xy 292.29067 -366.442964) (xy 292.24914 -366.405831) (xy 292.213447 -366.363059)
			(xy 292.184347 -366.315553) (xy 292.162459 -366.264324) (xy 292.154864 -366.23752) (xy 292.150585 -366.223406)
			(xy 292.135197 -366.19826) (xy 292.11328 -366.178543) (xy 292.086652 -366.165892) (xy 292.057523 -366.161355)
			(xy 292.04285 -366.162844) (xy 292.029897 -366.16451) (xy 292.003839 -366.166288) (xy 291.99078 -366.1664)
			(xy 291.990526 -366.1664) (xy 291.966978 -366.166093) (xy 291.920234 -366.160356) (xy 291.897308 -366.15497)
			(xy 291.884306 -366.152198) (xy 291.857736 -366.152613) (xy 291.832177 -366.159878) (xy 291.809361 -366.1735)
			(xy 291.79084 -366.192554) (xy 291.77787 -366.215746) (xy 291.771332 -366.241501) (xy 291.77107 -366.254792)
			(xy 291.77107 -366.259872) (xy 291.770584 -366.287123) (xy 291.762828 -366.341071) (xy 291.747473 -366.393366)
			(xy 291.724831 -366.442943) (xy 291.695365 -366.488793) (xy 291.659674 -366.529984) (xy 291.618483 -366.565675)
			(xy 291.572633 -366.595141) (xy 291.523056 -366.617783) (xy 291.470761 -366.633138) (xy 291.416813 -366.640894)
			(xy 291.362311 -366.640894) (xy 291.308363 -366.633138) (xy 291.256068 -366.617783) (xy 291.206491 -366.595141)
			(xy 291.160641 -366.565675) (xy 291.11945 -366.529984) (xy 291.083759 -366.488793) (xy 291.054293 -366.442943)
			(xy 291.031651 -366.393366) (xy 291.016296 -366.341071) (xy 291.00854 -366.287123) (xy 291.008054 -366.259872)
			(xy 291.00855 -366.232298) (xy 291.016494 -366.177726) (xy 291.032212 -366.124866) (xy 291.055376 -366.074819)
			(xy 291.085504 -366.028629) (xy 291.121968 -365.987258) (xy 291.142674 -365.969042) (xy 291.153601 -365.959173)
			(xy 291.169676 -365.934515) (xy 291.178059 -365.906299) (xy 291.178054 -365.876865) (xy 291.169661 -365.848652)
			(xy 291.153577 -365.824) (xy 291.142674 -365.814102) (xy 291.121955 -365.795899) (xy 291.085487 -365.754528)
			(xy 291.055356 -365.708336) (xy 291.032192 -365.658287) (xy 291.016477 -365.605423) (xy 291.008539 -365.550847)
			(xy 291.008054 -365.523272) (xy 291.008619 -365.493749) (xy 291.017752 -365.435413) (xy 291.035766 -365.379181)
			(xy 291.062229 -365.326397) (xy 291.07892 -365.302038) (xy 291.08686 -365.290159) (xy 291.096379 -365.263229)
			(xy 291.098067 -365.234716) (xy 291.09179 -365.206852) (xy 291.078041 -365.181816) (xy 291.057895 -365.161568)
			(xy 291.045646 -365.15421) (xy 291.024749 -365.14215) (xy 290.985971 -365.113443) (xy 290.951219 -365.079973)
			(xy 290.921074 -365.042301) (xy 290.908232 -365.021876) (xy 290.900357 -365.009618) (xy 290.878871 -364.989949)
			(xy 290.852705 -364.977151) (xy 290.823989 -364.972264) (xy 290.795062 -364.975688) (xy 290.781486 -364.980982)
			(xy 290.758274 -364.990467) (xy 290.709942 -365.00382) (xy 290.660253 -365.01055) (xy 290.635182 -365.010954)
			(xy 290.610113 -365.010525) (xy 290.56043 -365.003778) (xy 290.512095 -364.990447) (xy 290.488878 -364.980982)
			(xy 290.475284 -364.975785) (xy 290.446392 -364.972411) (xy 290.41772 -364.977311) (xy 290.391589 -364.990088)
			(xy 290.370114 -365.009707) (xy 290.362132 -365.021876) (xy 290.347563 -365.045007) (xy 290.31272 -365.087128)
			(xy 290.272097 -365.123707) (xy 290.226566 -365.153958) (xy 290.177104 -365.177234) (xy 290.124773 -365.193034)
			(xy 290.070694 -365.20102) (xy 290.01603 -365.20102) (xy 289.961951 -365.193034) (xy 289.90962 -365.177234)
			(xy 289.860158 -365.153958) (xy 289.814627 -365.123707) (xy 289.774004 -365.087128) (xy 289.739161 -365.045007)
			(xy 289.724592 -365.021876) (xy 289.71666 -365.009659) (xy 289.69519 -364.98999) (xy 289.669039 -364.977186)
			(xy 289.640337 -364.972289) (xy 289.61142 -364.975697) (xy 289.597846 -364.980982) (xy 289.574639 -364.99048)
			(xy 289.526305 -365.003828) (xy 289.476614 -365.010553) (xy 289.451542 -365.010954) (xy 289.423656 -365.01039)
			(xy 289.368506 -365.002083) (xy 289.31521 -364.985649) (xy 289.264959 -364.961454) (xy 289.218876 -364.93004)
			(xy 289.17799 -364.892108) (xy 289.143215 -364.848505) (xy 289.115327 -364.800206) (xy 289.094949 -364.74829)
			(xy 289.082538 -364.693916) (xy 289.07837 -364.6383) (xy 286.468856 -364.6383) (xy 285.957264 -365.149892)
			(xy 285.947192 -365.160527) (xy 285.933245 -365.186276) (xy 285.927168 -365.214923) (xy 285.92946 -365.244118)
			(xy 285.939933 -365.271465) (xy 285.957728 -365.294723) (xy 285.981385 -365.311982) (xy 286.008965 -365.321828)
			(xy 286.023558 -365.32312) (xy 286.05242 -365.325261) (xy 286.109063 -365.337128) (xy 286.163265 -365.35741)
			(xy 286.213783 -365.385644) (xy 286.259459 -365.421181) (xy 286.299246 -365.463207) (xy 286.332232 -365.510759)
			(xy 286.35766 -365.562746) (xy 286.374947 -365.617977) (xy 286.383696 -365.675184) (xy 286.384238 -365.70412)
			(xy 286.383741 -365.73137) (xy 286.375982 -365.785316) (xy 286.360626 -365.837609) (xy 286.337985 -365.887184)
			(xy 286.308519 -365.933033) (xy 286.272829 -365.974222) (xy 286.231641 -366.009913) (xy 286.185793 -366.03938)
			(xy 286.136218 -366.062023) (xy 286.083926 -366.07738) (xy 286.02998 -366.08514) (xy 286.00273 -366.085628)
			(xy 285.973789 -366.085108) (xy 285.916568 -366.076382) (xy 285.861322 -366.05911) (xy 285.80932 -366.03369)
			(xy 285.761756 -366.000705) (xy 285.719722 -365.960912) (xy 285.684183 -365.915224) (xy 285.655955 -365.864692)
			(xy 285.635685 -365.810475) (xy 285.62384 -365.753817) (xy 285.62173 -365.724948) (xy 285.620555 -365.710335)
			(xy 285.610734 -365.68272) (xy 285.593475 -365.65903) (xy 285.570199 -365.641217) (xy 285.542823 -365.630746)
			(xy 285.513601 -365.628481) (xy 285.484938 -365.634608) (xy 285.459196 -365.648622) (xy 285.448502 -365.658654)
			(xy 285.306516 -365.80064) (xy 285.306516 -366.188752) (xy 285.41345 -366.295686) (xy 285.42742 -366.299242)
			(xy 285.454808 -366.306391) (xy 285.507285 -366.3276) (xy 285.556052 -366.356329) (xy 285.600039 -366.391949)
			(xy 285.63828 -366.433677) (xy 285.669935 -366.480598) (xy 285.69431 -366.531681) (xy 285.71087 -366.585805)
			(xy 285.719251 -366.641782) (xy 285.719774 -366.670082) (xy 285.719328 -366.697336) (xy 285.711572 -366.751289)
			(xy 285.696217 -366.80359) (xy 285.673574 -366.853172) (xy 285.644105 -366.899027) (xy 285.608409 -366.94022)
			(xy 285.567214 -366.975914) (xy 285.521358 -367.005382) (xy 285.471775 -367.028023) (xy 285.419474 -367.043376)
			(xy 285.36552 -367.051129) (xy 285.338266 -367.05159) (xy 285.309976 -367.051092) (xy 285.254019 -367.042718)
			(xy 285.199912 -367.026174) (xy 285.14884 -367.001822) (xy 285.101924 -366.970196) (xy 285.060191 -366.93199)
			(xy 285.024557 -366.88804) (xy 284.995803 -366.839311) (xy 284.974559 -366.786871) (xy 284.967426 -366.75949)
			(xy 284.967426 -366.759236) (xy 284.96387 -366.745266) (xy 284.763718 -366.545114) (xy 284.746352 -366.527139)
			(xy 284.716946 -366.486726) (xy 284.694235 -366.442206) (xy 284.678779 -366.394677) (xy 284.670961 -366.345313)
			(xy 284.6705 -366.320324) (xy 270.383 -366.320324) (xy 270.383 -367.212626) (xy 286.427418 -367.212626)
			(xy 286.427844 -367.187288) (xy 286.43455 -367.137057) (xy 286.447848 -367.088157) (xy 286.467504 -367.041447)
			(xy 286.493171 -366.997752) (xy 286.524398 -366.95784) (xy 286.542226 -366.93983) (xy 286.5517 -366.930126)
			(xy 286.565495 -366.906784) (xy 286.572642 -366.880629) (xy 286.572634 -366.853515) (xy 286.565473 -366.827364)
			(xy 286.551665 -366.804029) (xy 286.542226 -366.794288) (xy 286.524397 -366.776279) (xy 286.493168 -366.736367)
			(xy 286.467499 -366.692672) (xy 286.447841 -366.645963) (xy 286.434541 -366.597062) (xy 286.427832 -366.546831)
			(xy 286.427418 -366.521492) (xy 286.427904 -366.494241) (xy 286.43566 -366.440293) (xy 286.451015 -366.387998)
			(xy 286.473657 -366.338421) (xy 286.503123 -366.292571) (xy 286.538814 -366.25138) (xy 286.580005 -366.215689)
			(xy 286.625855 -366.186223) (xy 286.675432 -366.163581) (xy 286.727727 -366.148226) (xy 286.781675 -366.14047)
			(xy 286.836177 -366.14047) (xy 286.890125 -366.148226) (xy 286.94242 -366.163581) (xy 286.991997 -366.186223)
			(xy 287.037847 -366.215689) (xy 287.079038 -366.25138) (xy 287.114729 -366.292571) (xy 287.144195 -366.338421)
			(xy 287.166837 -366.387998) (xy 287.182192 -366.440293) (xy 287.189948 -366.494241) (xy 287.190094 -366.502442)
			(xy 288.052764 -366.502442) (xy 288.05325 -366.475191) (xy 288.061006 -366.421243) (xy 288.076361 -366.368948)
			(xy 288.099003 -366.319371) (xy 288.128469 -366.273521) (xy 288.16416 -366.23233) (xy 288.205351 -366.196639)
			(xy 288.251201 -366.167173) (xy 288.300778 -366.144531) (xy 288.353073 -366.129176) (xy 288.407021 -366.12142)
			(xy 288.461523 -366.12142) (xy 288.515471 -366.129176) (xy 288.567766 -366.144531) (xy 288.617343 -366.167173)
			(xy 288.663193 -366.196639) (xy 288.704384 -366.23233) (xy 288.740075 -366.273521) (xy 288.769541 -366.319371)
			(xy 288.792183 -366.368948) (xy 288.807538 -366.421243) (xy 288.815294 -366.475191) (xy 288.81578 -366.502442)
			(xy 288.815548 -366.521109) (xy 288.811855 -366.558261) (xy 288.808414 -366.57661) (xy 288.806165 -366.590889)
			(xy 288.808676 -366.619667) (xy 288.819156 -366.646586) (xy 288.836762 -366.669487) (xy 288.860084 -366.686533)
			(xy 288.887249 -366.696356) (xy 288.901632 -366.697768) (xy 288.930291 -366.700084) (xy 288.98646 -366.712378)
			(xy 289.040148 -366.732959) (xy 289.090142 -366.761361) (xy 289.135308 -366.796943) (xy 289.174624 -366.838898)
			(xy 289.207202 -366.886277) (xy 289.232302 -366.938007) (xy 289.249357 -366.992917) (xy 289.257982 -367.049765)
			(xy 289.258502 -367.078514) (xy 289.258016 -367.105765) (xy 289.25026 -367.159713) (xy 289.234905 -367.212008)
			(xy 289.212263 -367.261585) (xy 289.203734 -367.274856) (xy 296.11574 -367.274856) (xy 296.116241 -367.246409)
			(xy 296.124701 -367.190149) (xy 296.141428 -367.13577) (xy 296.166048 -367.084479) (xy 296.198017 -367.037417)
			(xy 296.236624 -366.995627) (xy 296.258488 -366.977422) (xy 296.269983 -366.967503) (xy 296.287 -366.942374)
			(xy 296.295897 -366.913358) (xy 296.295892 -366.883009) (xy 296.286985 -366.853997) (xy 296.269961 -366.828873)
			(xy 296.258488 -366.818926) (xy 296.236618 -366.800728) (xy 296.198016 -366.758936) (xy 296.166053 -366.711871)
			(xy 296.141438 -366.660579) (xy 296.124719 -366.606199) (xy 296.116266 -366.549938) (xy 296.11574 -366.521492)
			(xy 296.116226 -366.494241) (xy 296.123982 -366.440293) (xy 296.139337 -366.387998) (xy 296.161979 -366.338421)
			(xy 296.191445 -366.292571) (xy 296.227136 -366.25138) (xy 296.268327 -366.215689) (xy 296.314177 -366.186223)
			(xy 296.363754 -366.163581) (xy 296.416049 -366.148226) (xy 296.469997 -366.14047) (xy 296.524499 -366.14047)
			(xy 296.578447 -366.148226) (xy 296.630742 -366.163581) (xy 296.680319 -366.186223) (xy 296.726169 -366.215689)
			(xy 296.76736 -366.25138) (xy 296.803051 -366.292571) (xy 296.832517 -366.338421) (xy 296.855159 -366.387998)
			(xy 296.870514 -366.440293) (xy 296.87827 -366.494241) (xy 296.878416 -366.502442) (xy 297.741086 -366.502442)
			(xy 297.741572 -366.475191) (xy 297.749328 -366.421243) (xy 297.764683 -366.368948) (xy 297.787325 -366.319371)
			(xy 297.816791 -366.273521) (xy 297.852482 -366.23233) (xy 297.893673 -366.196639) (xy 297.939523 -366.167173)
			(xy 297.9891 -366.144531) (xy 298.041395 -366.129176) (xy 298.095343 -366.12142) (xy 298.149845 -366.12142)
			(xy 298.203793 -366.129176) (xy 298.256088 -366.144531) (xy 298.305665 -366.167173) (xy 298.351515 -366.196639)
			(xy 298.392706 -366.23233) (xy 298.428397 -366.273521) (xy 298.457863 -366.319371) (xy 298.480505 -366.368948)
			(xy 298.49586 -366.421243) (xy 298.503616 -366.475191) (xy 298.504102 -366.502442) (xy 298.503863 -366.521109)
			(xy 298.50017 -366.55826) (xy 298.496736 -366.57661) (xy 298.494466 -366.590887) (xy 298.496978 -366.619669)
			(xy 298.50746 -366.646591) (xy 298.525071 -366.669494) (xy 298.548398 -366.686539) (xy 298.575569 -366.696359)
			(xy 298.589954 -366.697768) (xy 298.618607 -366.700151) (xy 298.674774 -366.712433) (xy 298.728462 -366.733004)
			(xy 298.778456 -366.761398) (xy 298.823623 -366.796971) (xy 298.862942 -366.83892) (xy 298.895521 -366.886292)
			(xy 298.920622 -366.938017) (xy 298.937679 -366.992923) (xy 298.946304 -367.049767) (xy 298.946824 -367.078514)
			(xy 298.946338 -367.105765) (xy 298.938582 -367.159713) (xy 298.923227 -367.212008) (xy 298.900585 -367.261585)
			(xy 298.871119 -367.307435) (xy 298.835428 -367.348626) (xy 298.794237 -367.384317) (xy 298.748387 -367.413783)
			(xy 298.69881 -367.436425) (xy 298.646515 -367.45178) (xy 298.592567 -367.459536) (xy 298.538065 -367.459536)
			(xy 298.484117 -367.45178) (xy 298.431822 -367.436425) (xy 298.382245 -367.413783) (xy 298.336395 -367.384317)
			(xy 298.295204 -367.348626) (xy 298.259513 -367.307435) (xy 298.230047 -367.261585) (xy 298.207405 -367.212008)
			(xy 298.19205 -367.159713) (xy 298.184294 -367.105765) (xy 298.183808 -367.078514) (xy 298.184048 -367.059847)
			(xy 298.187736 -367.022695) (xy 298.191174 -367.004346) (xy 298.193481 -366.990074) (xy 298.190958 -366.96129)
			(xy 298.180467 -366.934367) (xy 298.16285 -366.911464) (xy 298.139518 -366.894419) (xy 298.112343 -366.884598)
			(xy 298.097956 -366.883188) (xy 298.069302 -366.880827) (xy 298.013138 -366.868534) (xy 297.959454 -366.847956)
			(xy 297.909464 -366.819557) (xy 297.864299 -366.78398) (xy 297.824983 -366.742031) (xy 297.792405 -366.694658)
			(xy 297.767301 -366.642935) (xy 297.750241 -366.588031) (xy 297.74161 -366.531189) (xy 297.741086 -366.502442)
			(xy 296.878416 -366.502442) (xy 296.878756 -366.521492) (xy 296.87822 -366.549937) (xy 296.869767 -366.606197)
			(xy 296.853048 -366.660575) (xy 296.828434 -366.711865) (xy 296.796471 -366.758929) (xy 296.75787 -366.80072)
			(xy 296.736008 -366.818926) (xy 296.724565 -366.8289) (xy 296.707548 -366.854015) (xy 296.698646 -366.883016)
			(xy 296.698641 -366.913352) (xy 296.707534 -366.942356) (xy 296.724543 -366.967475) (xy 296.736008 -366.977422)
			(xy 296.757852 -366.995649) (xy 296.796456 -367.037436) (xy 296.828422 -367.084494) (xy 296.853041 -367.13578)
			(xy 296.869766 -367.190155) (xy 296.87051 -367.1951) (xy 297.13885 -367.1951) (xy 297.142921 -367.139478)
			(xy 297.155047 -367.085041) (xy 297.17497 -367.03295) (xy 297.202266 -366.984315) (xy 297.236352 -366.940172)
			(xy 297.276501 -366.901463) (xy 297.321859 -366.869012) (xy 297.371459 -366.843511) (xy 297.424243 -366.825504)
			(xy 297.479086 -366.815374) (xy 297.53482 -366.813337) (xy 297.590257 -366.819437) (xy 297.644214 -366.833543)
			(xy 297.695543 -366.855355) (xy 297.743149 -366.884409) (xy 297.786017 -366.920084) (xy 297.823234 -366.961621)
			(xy 297.854007 -367.008134) (xy 297.877679 -367.058631) (xy 297.893747 -367.112038) (xy 297.901867 -367.167214)
			(xy 297.902376 -367.1951) (xy 297.901867 -367.222986) (xy 297.893747 -367.278162) (xy 297.877679 -367.331569)
			(xy 297.854007 -367.382066) (xy 297.823234 -367.428579) (xy 297.786017 -367.470116) (xy 297.743149 -367.505791)
			(xy 297.695543 -367.534845) (xy 297.644214 -367.556657) (xy 297.590257 -367.570763) (xy 297.53482 -367.576863)
			(xy 297.479086 -367.574826) (xy 297.424243 -367.564696) (xy 297.371459 -367.546689) (xy 297.321859 -367.521188)
			(xy 297.276501 -367.488737) (xy 297.236352 -367.450028) (xy 297.202266 -367.405885) (xy 297.17497 -367.35725)
			(xy 297.155047 -367.305159) (xy 297.142921 -367.250722) (xy 297.13885 -367.1951) (xy 296.87051 -367.1951)
			(xy 296.878226 -367.246412) (xy 296.878756 -367.274856) (xy 296.87827 -367.302107) (xy 296.870514 -367.356055)
			(xy 296.855159 -367.40835) (xy 296.832517 -367.457927) (xy 296.803051 -367.503777) (xy 296.76736 -367.544968)
			(xy 296.726169 -367.580659) (xy 296.680319 -367.610125) (xy 296.630742 -367.632767) (xy 296.578447 -367.648122)
			(xy 296.524499 -367.655878) (xy 296.469997 -367.655878) (xy 296.416049 -367.648122) (xy 296.363754 -367.632767)
			(xy 296.314177 -367.610125) (xy 296.268327 -367.580659) (xy 296.227136 -367.544968) (xy 296.191445 -367.503777)
			(xy 296.161979 -367.457927) (xy 296.139337 -367.40835) (xy 296.123982 -367.356055) (xy 296.116226 -367.302107)
			(xy 296.11574 -367.274856) (xy 289.203734 -367.274856) (xy 289.182797 -367.307435) (xy 289.147106 -367.348626)
			(xy 289.105915 -367.384317) (xy 289.060065 -367.413783) (xy 289.010488 -367.436425) (xy 288.958193 -367.45178)
			(xy 288.904245 -367.459536) (xy 288.849743 -367.459536) (xy 288.795795 -367.45178) (xy 288.7435 -367.436425)
			(xy 288.693923 -367.413783) (xy 288.648073 -367.384317) (xy 288.606882 -367.348626) (xy 288.571191 -367.307435)
			(xy 288.541725 -367.261585) (xy 288.519083 -367.212008) (xy 288.503728 -367.159713) (xy 288.495972 -367.105765)
			(xy 288.495486 -367.078514) (xy 288.495734 -367.059847) (xy 288.499421 -367.022696) (xy 288.502852 -367.004346)
			(xy 288.505179 -366.990076) (xy 288.502656 -366.961288) (xy 288.492163 -366.934361) (xy 288.474541 -366.911457)
			(xy 288.451204 -366.894413) (xy 288.424024 -366.884595) (xy 288.409634 -366.883188) (xy 288.380986 -366.88076)
			(xy 288.324824 -366.868479) (xy 288.27114 -366.84791) (xy 288.221149 -366.81952) (xy 288.175984 -366.783951)
			(xy 288.136666 -366.742009) (xy 288.104086 -366.694643) (xy 288.078981 -366.642924) (xy 288.06192 -366.588025)
			(xy 288.053288 -366.531187) (xy 288.052764 -366.502442) (xy 287.190094 -366.502442) (xy 287.190434 -366.521492)
			(xy 287.190004 -366.54683) (xy 287.183297 -366.59706) (xy 287.169998 -366.64596) (xy 287.150343 -366.692669)
			(xy 287.124677 -366.736364) (xy 287.093453 -366.776278) (xy 287.075626 -366.794288) (xy 287.066284 -366.80409)
			(xy 287.052572 -366.827425) (xy 287.045463 -366.853539) (xy 287.045456 -366.880604) (xy 287.05255 -366.906722)
			(xy 287.066249 -366.930064) (xy 287.075626 -366.93983) (xy 287.093474 -366.957822) (xy 287.124698 -366.997738)
			(xy 287.150364 -367.041438) (xy 287.170018 -367.08815) (xy 287.183315 -367.137053) (xy 287.190021 -367.187287)
			(xy 287.190314 -367.20526) (xy 287.442908 -367.20526) (xy 287.446979 -367.149638) (xy 287.459105 -367.095201)
			(xy 287.479028 -367.04311) (xy 287.506324 -366.994475) (xy 287.54041 -366.950332) (xy 287.580559 -366.911623)
			(xy 287.625917 -366.879172) (xy 287.675517 -366.853671) (xy 287.728301 -366.835664) (xy 287.783144 -366.825534)
			(xy 287.838878 -366.823497) (xy 287.894315 -366.829597) (xy 287.948272 -366.843703) (xy 287.999601 -366.865515)
			(xy 288.047207 -366.894569) (xy 288.090075 -366.930244) (xy 288.127292 -366.971781) (xy 288.158065 -367.018294)
			(xy 288.181737 -367.068791) (xy 288.197805 -367.122198) (xy 288.205925 -367.177374) (xy 288.206434 -367.20526)
			(xy 288.205925 -367.233146) (xy 288.197805 -367.288322) (xy 288.181737 -367.341729) (xy 288.158065 -367.392226)
			(xy 288.127292 -367.438739) (xy 288.090075 -367.480276) (xy 288.047207 -367.515951) (xy 287.999601 -367.545005)
			(xy 287.948272 -367.566817) (xy 287.894315 -367.580923) (xy 287.838878 -367.587023) (xy 287.783144 -367.584986)
			(xy 287.728301 -367.574856) (xy 287.675517 -367.556849) (xy 287.625917 -367.531348) (xy 287.580559 -367.498897)
			(xy 287.54041 -367.460188) (xy 287.506324 -367.416045) (xy 287.479028 -367.36741) (xy 287.459105 -367.315319)
			(xy 287.446979 -367.260882) (xy 287.442908 -367.20526) (xy 287.190314 -367.20526) (xy 287.190434 -367.212626)
			(xy 287.189948 -367.239877) (xy 287.182192 -367.293825) (xy 287.166837 -367.34612) (xy 287.144195 -367.395697)
			(xy 287.114729 -367.441547) (xy 287.079038 -367.482738) (xy 287.037847 -367.518429) (xy 286.991997 -367.547895)
			(xy 286.94242 -367.570537) (xy 286.890125 -367.585892) (xy 286.836177 -367.593648) (xy 286.781675 -367.593648)
			(xy 286.727727 -367.585892) (xy 286.675432 -367.570537) (xy 286.625855 -367.547895) (xy 286.580005 -367.518429)
			(xy 286.538814 -367.482738) (xy 286.503123 -367.441547) (xy 286.473657 -367.395697) (xy 286.451015 -367.34612)
			(xy 286.43566 -367.293825) (xy 286.427904 -367.239877) (xy 286.427418 -367.212626) (xy 270.383 -367.212626)
			(xy 270.383 -372.987077) (xy 286.21657 -372.987077) (xy 286.220304 -372.933821) (xy 286.231425 -372.881605)
			(xy 286.249717 -372.83145) (xy 286.274821 -372.784334) (xy 286.306249 -372.741178) (xy 286.343386 -372.702825)
			(xy 286.364172 -372.686072) (xy 286.376017 -372.676217) (xy 286.393536 -372.650882) (xy 286.402709 -372.621478)
			(xy 286.402702 -372.590676) (xy 286.393516 -372.561275) (xy 286.375984 -372.535949) (xy 286.364172 -372.526052)
			(xy 286.341708 -372.507839) (xy 286.301972 -372.465823) (xy 286.269032 -372.418292) (xy 286.243641 -372.366335)
			(xy 286.22638 -372.311142) (xy 286.217645 -372.253977) (xy 286.217106 -372.225062) (xy 286.217607 -372.197693)
			(xy 286.225416 -372.143515) (xy 286.240897 -372.091013) (xy 286.263731 -372.041265) (xy 286.293448 -371.995297)
			(xy 286.311086 -371.974364) (xy 286.320361 -371.963065) (xy 286.332535 -371.936497) (xy 286.336701 -371.907571)
			(xy 286.332519 -371.878648) (xy 286.320329 -371.852087) (xy 286.311086 -371.84076) (xy 286.29341 -371.819857)
			(xy 286.26369 -371.773883) (xy 286.240849 -371.724131) (xy 286.225357 -371.671625) (xy 286.217533 -371.617443)
			(xy 286.217537 -371.562699) (xy 286.22537 -371.508519) (xy 286.240869 -371.456015) (xy 286.263717 -371.406267)
			(xy 286.293444 -371.360298) (xy 286.311086 -371.339364) (xy 286.320361 -371.328065) (xy 286.332535 -371.301497)
			(xy 286.336701 -371.272571) (xy 286.332519 -371.243648) (xy 286.320329 -371.217087) (xy 286.311086 -371.20576)
			(xy 286.293459 -371.184818) (xy 286.263746 -371.138848) (xy 286.240908 -371.089103) (xy 286.225414 -371.036604)
			(xy 286.217582 -370.98243) (xy 286.217106 -370.955062) (xy 286.217543 -370.927809) (xy 286.225305 -370.873859)
			(xy 286.240665 -370.821562) (xy 286.263312 -370.771984) (xy 286.292783 -370.726133) (xy 286.32848 -370.684943)
			(xy 286.369675 -370.649252) (xy 286.41553 -370.619787) (xy 286.465111 -370.597147) (xy 286.51741 -370.581793)
			(xy 286.571361 -370.574039) (xy 286.598614 -370.573554) (xy 286.625985 -370.573999) (xy 286.680166 -370.58182)
			(xy 286.73267 -370.597313) (xy 286.782416 -370.62016) (xy 286.828382 -370.64989) (xy 286.849312 -370.667534)
			(xy 286.86064 -370.67677) (xy 286.887197 -370.688946) (xy 286.916114 -370.693119) (xy 286.945031 -370.688946)
			(xy 286.971588 -370.67677) (xy 286.982916 -370.667534) (xy 287.003873 -370.649926) (xy 287.049839 -370.620208)
			(xy 287.09958 -370.597366) (xy 287.152075 -370.581868) (xy 287.206246 -370.574032) (xy 287.233614 -370.573554)
			(xy 287.26253 -370.574114) (xy 287.3197 -370.582831) (xy 287.374899 -370.60008) (xy 287.426861 -370.625464)
			(xy 287.474396 -370.658401) (xy 287.516413 -370.698137) (xy 287.534604 -370.72062) (xy 287.544501 -370.732425)
			(xy 287.569825 -370.749944) (xy 287.599218 -370.75912) (xy 287.63001 -370.75912) (xy 287.659403 -370.749944)
			(xy 287.684727 -370.732425) (xy 287.694624 -370.72062) (xy 287.712807 -370.698129) (xy 287.754827 -370.658394)
			(xy 287.802364 -370.625455) (xy 287.854327 -370.600068) (xy 287.909526 -370.582813) (xy 287.966697 -370.574087)
			(xy 287.995614 -370.573554) (xy 288.022864 -370.574065) (xy 288.076809 -370.581822) (xy 288.129101 -370.597177)
			(xy 288.178675 -370.619817) (xy 288.224524 -370.649281) (xy 288.265713 -370.68497) (xy 288.301404 -370.726157)
			(xy 288.330871 -370.772003) (xy 288.353515 -370.821577) (xy 288.368873 -370.873868) (xy 288.376634 -370.927812)
			(xy 288.377122 -370.955062) (xy 288.376653 -370.982432) (xy 288.368839 -371.036612) (xy 288.353351 -371.089116)
			(xy 288.33051 -371.138863) (xy 288.300784 -371.184829) (xy 288.283142 -371.20576) (xy 288.273946 -371.217117)
			(xy 288.261772 -371.243665) (xy 288.257594 -371.272571) (xy 288.261755 -371.30148) (xy 288.273915 -371.328035)
			(xy 288.283142 -371.339364) (xy 288.300747 -371.360326) (xy 288.330475 -371.406288) (xy 288.353325 -371.456029)
			(xy 288.368825 -371.508527) (xy 288.376658 -371.562702) (xy 288.376662 -371.617441) (xy 288.368838 -371.671617)
			(xy 288.353345 -371.724117) (xy 288.330503 -371.773862) (xy 288.300781 -371.819828) (xy 288.283142 -371.84076)
			(xy 288.273946 -371.852117) (xy 288.261772 -371.878665) (xy 288.257594 -371.907571) (xy 288.261755 -371.93648)
			(xy 288.273915 -371.963035) (xy 288.283142 -371.974364) (xy 288.300785 -371.995293) (xy 288.330495 -372.041267)
			(xy 288.353329 -372.091016) (xy 288.36882 -372.143517) (xy 288.376648 -372.197693) (xy 288.377122 -372.225062)
			(xy 288.376606 -372.253979) (xy 288.367881 -372.311152) (xy 288.350624 -372.366352) (xy 288.325232 -372.418315)
			(xy 288.292287 -372.465848) (xy 288.252543 -372.507863) (xy 288.230056 -372.526052) (xy 288.218285 -372.535989)
			(xy 288.200759 -372.561299) (xy 288.191575 -372.590684) (xy 288.191568 -372.62147) (xy 288.200738 -372.650858)
			(xy 288.218252 -372.676177) (xy 288.230056 -372.686072) (xy 288.250801 -372.702871) (xy 288.287929 -372.741219)
			(xy 288.319349 -372.784369) (xy 288.344448 -372.831477) (xy 288.362735 -372.881624) (xy 288.373854 -372.93383)
			(xy 288.375806 -372.961677) (xy 289.58207 -372.961677) (xy 289.585804 -372.908421) (xy 289.596925 -372.856205)
			(xy 289.615217 -372.80605) (xy 289.640321 -372.758934) (xy 289.671749 -372.715778) (xy 289.708886 -372.677425)
			(xy 289.729672 -372.660672) (xy 289.741517 -372.650817) (xy 289.759036 -372.625482) (xy 289.768209 -372.596078)
			(xy 289.768202 -372.565276) (xy 289.759016 -372.535875) (xy 289.741484 -372.510549) (xy 289.729672 -372.500652)
			(xy 289.707208 -372.482439) (xy 289.667472 -372.440423) (xy 289.634532 -372.392892) (xy 289.609141 -372.340935)
			(xy 289.59188 -372.285742) (xy 289.583145 -372.228577) (xy 289.582606 -372.199662) (xy 289.583107 -372.172293)
			(xy 289.590916 -372.118115) (xy 289.606397 -372.065613) (xy 289.629231 -372.015865) (xy 289.658948 -371.969897)
			(xy 289.676586 -371.948964) (xy 289.685861 -371.937665) (xy 289.698035 -371.911097) (xy 289.702201 -371.882171)
			(xy 289.698019 -371.853248) (xy 289.685829 -371.826687) (xy 289.676586 -371.81536) (xy 289.65891 -371.794457)
			(xy 289.62919 -371.748483) (xy 289.606349 -371.698731) (xy 289.590857 -371.646225) (xy 289.583033 -371.592043)
			(xy 289.583037 -371.537299) (xy 289.59087 -371.483119) (xy 289.606369 -371.430615) (xy 289.629217 -371.380867)
			(xy 289.658944 -371.334898) (xy 289.676586 -371.313964) (xy 289.685861 -371.302665) (xy 289.698035 -371.276097)
			(xy 289.702201 -371.247171) (xy 289.698019 -371.218248) (xy 289.685829 -371.191687) (xy 289.676586 -371.18036)
			(xy 289.658959 -371.159418) (xy 289.629246 -371.113448) (xy 289.606408 -371.063703) (xy 289.590914 -371.011204)
			(xy 289.583082 -370.95703) (xy 289.582606 -370.929662) (xy 289.583092 -370.902411) (xy 289.590848 -370.848463)
			(xy 289.606203 -370.796168) (xy 289.628845 -370.746591) (xy 289.658311 -370.700741) (xy 289.694002 -370.65955)
			(xy 289.735193 -370.623859) (xy 289.781043 -370.594393) (xy 289.83062 -370.571751) (xy 289.882915 -370.556396)
			(xy 289.936863 -370.54864) (xy 289.991365 -370.54864) (xy 290.045313 -370.556396) (xy 290.097608 -370.571751)
			(xy 290.147185 -370.594393) (xy 290.193035 -370.623859) (xy 290.234226 -370.65955) (xy 290.269917 -370.700741)
			(xy 290.295262 -370.740178) (xy 291.927026 -370.740178) (xy 291.927573 -370.711009) (xy 291.936476 -370.653353)
			(xy 291.954056 -370.597726) (xy 291.979902 -370.545425) (xy 292.013412 -370.497671) (xy 292.053803 -370.455576)
			(xy 292.076632 -370.43741) (xy 292.086966 -370.428937) (xy 292.103261 -370.407771) (xy 292.113508 -370.383104)
			(xy 292.117008 -370.356623) (xy 292.113521 -370.330141) (xy 292.103284 -370.305469) (xy 292.086999 -370.284296)
			(xy 292.076632 -370.275866) (xy 292.053819 -370.25768) (xy 292.013415 -370.215598) (xy 291.979897 -370.16785)
			(xy 291.954048 -370.115551) (xy 291.936473 -370.059924) (xy 291.927582 -370.002267) (xy 291.927026 -369.973098)
			(xy 291.927454 -369.945844) (xy 291.935212 -369.89189) (xy 291.95057 -369.839589) (xy 291.973215 -369.790007)
			(xy 292.002686 -369.744152) (xy 292.038384 -369.702958) (xy 292.079581 -369.667265) (xy 292.125438 -369.637798)
			(xy 292.175023 -369.615157) (xy 292.227325 -369.599804) (xy 292.28128 -369.592051) (xy 292.308534 -369.59159)
			(xy 292.337451 -369.592122) (xy 292.394623 -369.600843) (xy 292.449823 -369.618096) (xy 292.501786 -369.643485)
			(xy 292.549319 -369.676428) (xy 292.591335 -369.71617) (xy 292.609524 -369.738656) (xy 292.619421 -369.750461)
			(xy 292.644745 -369.76798) (xy 292.674138 -369.777156) (xy 292.70493 -369.777156) (xy 292.734323 -369.76798)
			(xy 292.759647 -369.750461) (xy 292.769544 -369.738656) (xy 292.787699 -369.716142) (xy 292.829728 -369.676411)
			(xy 292.87727 -369.643477) (xy 292.929239 -369.618094) (xy 292.984442 -369.600844) (xy 293.041616 -369.592122)
			(xy 293.070534 -369.59159) (xy 293.099081 -369.59211) (xy 293.155536 -369.600633) (xy 293.210091 -369.61747)
			(xy 293.26153 -369.642244) (xy 293.285418 -369.657884) (xy 293.296563 -369.664941) (xy 293.321415 -369.673747)
			(xy 293.347695 -369.675874) (xy 293.37364 -369.671181) (xy 293.39751 -369.659982) (xy 293.417702 -369.643028)
			(xy 293.425626 -369.632484) (xy 293.441057 -369.611486) (xy 293.476652 -369.573431) (xy 293.517093 -369.540572)
			(xy 293.561628 -369.513519) (xy 293.609429 -369.492776) (xy 293.659607 -369.478729) (xy 293.71123 -369.471638)
			(xy 293.737284 -369.471194) (xy 293.766202 -369.471688) (xy 293.823376 -369.480417) (xy 293.878577 -369.497677)
			(xy 293.93054 -369.523073) (xy 293.978072 -369.556023) (xy 294.020086 -369.595771) (xy 294.038274 -369.61826)
			(xy 294.048171 -369.630065) (xy 294.073495 -369.647584) (xy 294.102888 -369.65676) (xy 294.13368 -369.65676)
			(xy 294.163073 -369.647584) (xy 294.188397 -369.630065) (xy 294.198294 -369.61826) (xy 294.216478 -369.595771)
			(xy 294.258501 -369.556038) (xy 294.306037 -369.523101) (xy 294.358 -369.497714) (xy 294.413198 -369.480458)
			(xy 294.470368 -369.471729) (xy 294.499284 -369.471194) (xy 294.526537 -369.47167) (xy 294.580487 -369.479425)
			(xy 294.632785 -369.494779) (xy 294.682365 -369.51742) (xy 294.728218 -369.546886) (xy 294.769411 -369.582579)
			(xy 294.805105 -369.62377) (xy 294.834573 -369.669623) (xy 294.857216 -369.719202) (xy 294.872572 -369.771499)
			(xy 294.880329 -369.825449) (xy 294.880792 -369.852702) (xy 294.880362 -369.878745) (xy 294.873275 -369.930348)
			(xy 294.859233 -369.980506) (xy 294.838498 -370.028288) (xy 294.811455 -370.072804) (xy 294.778606 -370.113227)
			(xy 294.759888 -370.13134) (xy 294.749997 -370.141348) (xy 294.735529 -370.165464) (xy 294.72818 -370.19261)
			(xy 294.728505 -370.220731) (xy 294.73648 -370.247699) (xy 294.7515 -370.271474) (xy 294.761666 -370.2812)
			(xy 294.781236 -370.299374) (xy 294.815628 -370.340233) (xy 294.843987 -370.385488) (xy 294.865756 -370.434257)
			(xy 294.880511 -370.485585) (xy 294.887963 -370.538469) (xy 294.888412 -370.565172) (xy 294.887892 -370.592941)
			(xy 294.879843 -370.647893) (xy 294.863911 -370.701096) (xy 294.840433 -370.751428) (xy 294.809904 -370.797823)
			(xy 294.772971 -370.8393) (xy 294.752014 -370.857526) (xy 294.741396 -370.867082) (xy 294.725411 -370.890736)
			(xy 294.716616 -370.917896) (xy 294.7157 -370.94643) (xy 294.722736 -370.974099) (xy 294.737171 -370.998729)
			(xy 294.747188 -371.00891) (xy 294.765535 -371.026997) (xy 294.797707 -371.067237) (xy 294.824176 -371.111437)
			(xy 294.844461 -371.158796) (xy 294.858194 -371.208451) (xy 294.865127 -371.259502) (xy 294.865552 -371.285262)
			(xy 294.865075 -371.312632) (xy 294.857262 -371.366811) (xy 294.841776 -371.419315) (xy 294.818936 -371.469062)
			(xy 294.789213 -371.515028) (xy 294.771572 -371.53596) (xy 294.762374 -371.547316) (xy 294.750196 -371.573864)
			(xy 294.746017 -371.602771) (xy 294.750179 -371.631681) (xy 294.762343 -371.658236) (xy 294.771572 -371.669564)
			(xy 294.789176 -371.690527) (xy 294.818902 -371.736489) (xy 294.84175 -371.786231) (xy 294.857249 -371.838728)
			(xy 294.865081 -371.892903) (xy 294.865085 -371.94764) (xy 294.857261 -372.001816) (xy 294.84177 -372.054316)
			(xy 294.81893 -372.10406) (xy 294.78921 -372.150027) (xy 294.771572 -372.17096) (xy 294.762374 -372.182316)
			(xy 294.750196 -372.208864) (xy 294.746017 -372.237771) (xy 294.750179 -372.266681) (xy 294.762343 -372.293236)
			(xy 294.771572 -372.304564) (xy 294.789176 -372.325527) (xy 294.818902 -372.371489) (xy 294.84175 -372.421231)
			(xy 294.857249 -372.473728) (xy 294.860837 -372.49855) (xy 295.942254 -372.49855) (xy 295.942254 -372.413854)
			(xy 295.950305 -372.32954) (xy 295.966334 -372.246374) (xy 295.990195 -372.165107) (xy 296.021674 -372.086477)
			(xy 296.060485 -372.011196) (xy 296.106275 -371.939944) (xy 296.158631 -371.873368) (xy 296.217079 -371.81207)
			(xy 296.281089 -371.756605) (xy 296.350081 -371.707476) (xy 296.423431 -371.665127) (xy 296.500474 -371.629943)
			(xy 296.580513 -371.602241) (xy 296.662822 -371.582273) (xy 296.746657 -371.57022) (xy 296.831258 -371.56619)
			(xy 296.915859 -371.57022) (xy 296.999694 -371.582273) (xy 297.082003 -371.602241) (xy 297.162042 -371.629943)
			(xy 297.239085 -371.665127) (xy 297.312435 -371.707476) (xy 297.381427 -371.756605) (xy 297.445437 -371.81207)
			(xy 297.503885 -371.873368) (xy 297.556241 -371.939944) (xy 297.602031 -372.011196) (xy 297.640842 -372.086477)
			(xy 297.672321 -372.165107) (xy 297.696182 -372.246374) (xy 297.712211 -372.32954) (xy 297.720262 -372.413854)
			(xy 297.720766 -372.456202) (xy 298.466767 -372.456202) (xy 298.470803 -372.372755) (xy 298.482875 -372.290087)
			(xy 298.502868 -372.20897) (xy 298.530597 -372.130161) (xy 298.565803 -372.054396) (xy 298.608157 -371.982383)
			(xy 298.657263 -371.914794) (xy 298.712664 -371.85226) (xy 298.773841 -371.795365) (xy 298.840224 -371.744639)
			(xy 298.911192 -371.700558) (xy 298.986084 -371.663532) (xy 299.0642 -371.633906) (xy 299.14481 -371.611958)
			(xy 299.227162 -371.597893) (xy 299.310488 -371.591841) (xy 299.394008 -371.59386) (xy 299.476944 -371.60393)
			(xy 299.55852 -371.621958) (xy 299.637976 -371.647775) (xy 299.714569 -371.68114) (xy 299.787585 -371.721741)
			(xy 299.856341 -371.7692) (xy 299.920195 -371.823073) (xy 299.978552 -371.882858) (xy 300.030867 -371.947995)
			(xy 300.07665 -372.017878) (xy 300.115475 -372.091853) (xy 300.14698 -372.16923) (xy 300.170869 -372.249287)
			(xy 300.18692 -372.331275) (xy 300.194983 -372.41443) (xy 300.195488 -372.456202) (xy 300.194983 -372.497974)
			(xy 300.18692 -372.581129) (xy 300.170869 -372.663117) (xy 300.14698 -372.743174) (xy 300.115475 -372.820551)
			(xy 300.07665 -372.894526) (xy 300.030867 -372.964409) (xy 299.978552 -373.029546) (xy 299.920195 -373.089331)
			(xy 299.856341 -373.143204) (xy 299.787585 -373.190663) (xy 299.714569 -373.231264) (xy 299.637976 -373.264629)
			(xy 299.55852 -373.290446) (xy 299.476944 -373.308474) (xy 299.394008 -373.318544) (xy 299.310488 -373.320563)
			(xy 299.227162 -373.314511) (xy 299.14481 -373.300446) (xy 299.0642 -373.278498) (xy 298.986084 -373.248872)
			(xy 298.911192 -373.211846) (xy 298.840224 -373.167765) (xy 298.773841 -373.117039) (xy 298.712664 -373.060144)
			(xy 298.657263 -372.99761) (xy 298.608157 -372.930021) (xy 298.565803 -372.858008) (xy 298.530597 -372.782243)
			(xy 298.502868 -372.703434) (xy 298.482875 -372.622317) (xy 298.470803 -372.539649) (xy 298.466767 -372.456202)
			(xy 297.720766 -372.456202) (xy 297.720262 -372.49855) (xy 297.712211 -372.582864) (xy 297.696182 -372.66603)
			(xy 297.672321 -372.747297) (xy 297.640842 -372.825927) (xy 297.602031 -372.901208) (xy 297.556241 -372.97246)
			(xy 297.503885 -373.039036) (xy 297.445437 -373.100334) (xy 297.381427 -373.155799) (xy 297.312435 -373.204928)
			(xy 297.239085 -373.247277) (xy 297.162042 -373.282461) (xy 297.082003 -373.310163) (xy 296.999694 -373.330131)
			(xy 296.915859 -373.342184) (xy 296.831258 -373.346215) (xy 296.746657 -373.342184) (xy 296.662822 -373.330131)
			(xy 296.580513 -373.310163) (xy 296.500474 -373.282461) (xy 296.423431 -373.247277) (xy 296.350081 -373.204928)
			(xy 296.281089 -373.155799) (xy 296.217079 -373.100334) (xy 296.158631 -373.039036) (xy 296.106275 -372.97246)
			(xy 296.060485 -372.901208) (xy 296.021674 -372.825927) (xy 295.990195 -372.747297) (xy 295.966334 -372.66603)
			(xy 295.950305 -372.582864) (xy 295.942254 -372.49855) (xy 294.860837 -372.49855) (xy 294.865081 -372.527903)
			(xy 294.865085 -372.58264) (xy 294.857261 -372.636816) (xy 294.84177 -372.689316) (xy 294.81893 -372.73906)
			(xy 294.78921 -372.785027) (xy 294.771572 -372.80596) (xy 294.762374 -372.817316) (xy 294.750196 -372.843864)
			(xy 294.746017 -372.872771) (xy 294.750179 -372.901681) (xy 294.762343 -372.928236) (xy 294.771572 -372.939564)
			(xy 294.789203 -372.960502) (xy 294.818917 -373.006473) (xy 294.841755 -373.056219) (xy 294.857248 -373.108718)
			(xy 294.865077 -373.162893) (xy 294.865552 -373.190262) (xy 294.864987 -373.21751) (xy 294.857236 -373.271453)
			(xy 294.841888 -373.323743) (xy 294.819255 -373.373317) (xy 294.789797 -373.419166) (xy 294.754113 -373.460355)
			(xy 294.712932 -373.496047) (xy 294.667089 -373.525515) (xy 294.61752 -373.54816) (xy 294.565233 -373.563519)
			(xy 294.511292 -373.571281) (xy 294.484044 -373.57177) (xy 294.455128 -373.571232) (xy 294.397957 -373.562508)
			(xy 294.342758 -373.545255) (xy 294.290796 -373.519867) (xy 294.243262 -373.486927) (xy 294.201244 -373.447188)
			(xy 294.183054 -373.424704) (xy 294.173157 -373.412899) (xy 294.147833 -373.39538) (xy 294.11844 -373.386204)
			(xy 294.087648 -373.386204) (xy 294.058255 -373.39538) (xy 294.032931 -373.412899) (xy 294.023034 -373.424704)
			(xy 294.004825 -373.447172) (xy 293.962809 -373.486908) (xy 293.915278 -373.519849) (xy 293.86332 -373.54524)
			(xy 293.808126 -373.562499) (xy 293.750959 -373.571233) (xy 293.722044 -373.57177) (xy 293.694791 -373.571304)
			(xy 293.640838 -373.563552) (xy 293.588538 -373.548199) (xy 293.538955 -373.525559) (xy 293.4931 -373.496092)
			(xy 293.451906 -373.460399) (xy 293.416211 -373.419205) (xy 293.386744 -373.37335) (xy 293.364103 -373.323768)
			(xy 293.34875 -373.271468) (xy 293.340997 -373.217515) (xy 293.340536 -373.190262) (xy 293.34103 -373.162893)
			(xy 293.348839 -373.108714) (xy 293.364322 -373.056211) (xy 293.387157 -373.006464) (xy 293.416877 -372.960496)
			(xy 293.434516 -372.939564) (xy 293.443788 -372.928264) (xy 293.455959 -372.901696) (xy 293.460124 -372.872771)
			(xy 293.455943 -372.843849) (xy 293.443757 -372.817288) (xy 293.434516 -372.80596) (xy 293.416839 -372.785057)
			(xy 293.387116 -372.739084) (xy 293.364274 -372.689333) (xy 293.348781 -372.636826) (xy 293.340956 -372.582644)
			(xy 293.34096 -372.527899) (xy 293.348793 -372.473718) (xy 293.364294 -372.421214) (xy 293.387144 -372.371466)
			(xy 293.416873 -372.325497) (xy 293.434516 -372.304564) (xy 293.443788 -372.293264) (xy 293.455959 -372.266696)
			(xy 293.460124 -372.237771) (xy 293.455943 -372.208849) (xy 293.443757 -372.182288) (xy 293.434516 -372.17096)
			(xy 293.416839 -372.150057) (xy 293.387116 -372.104084) (xy 293.364274 -372.054333) (xy 293.348781 -372.001826)
			(xy 293.340956 -371.947644) (xy 293.34096 -371.892899) (xy 293.348793 -371.838718) (xy 293.364294 -371.786214)
			(xy 293.387144 -371.736466) (xy 293.416873 -371.690497) (xy 293.434516 -371.669564) (xy 293.443788 -371.658264)
			(xy 293.455959 -371.631696) (xy 293.460124 -371.602771) (xy 293.455943 -371.573849) (xy 293.443757 -371.547288)
			(xy 293.434516 -371.53596) (xy 293.416894 -371.515014) (xy 293.387179 -371.469045) (xy 293.36434 -371.419301)
			(xy 293.348845 -371.366804) (xy 293.341012 -371.31263) (xy 293.340536 -371.285262) (xy 293.340768 -371.266207)
			(xy 293.344587 -371.228289) (xy 293.348156 -371.20957) (xy 293.3505 -371.196098) (xy 293.348653 -371.168823)
			(xy 293.339636 -371.143015) (xy 293.324096 -371.120524) (xy 293.303147 -371.102961) (xy 293.278289 -371.091584)
			(xy 293.251304 -371.087209) (xy 293.224125 -371.09015) (xy 293.21125 -371.094762) (xy 293.188788 -371.103308)
			(xy 293.142245 -371.11529) (xy 293.094564 -371.121325) (xy 293.070534 -371.121686) (xy 293.041618 -371.121149)
			(xy 292.984447 -371.112424) (xy 292.929249 -371.09517) (xy 292.877287 -371.069782) (xy 292.829752 -371.036842)
			(xy 292.787735 -370.997104) (xy 292.769544 -370.97462) (xy 292.759647 -370.962815) (xy 292.734323 -370.945296)
			(xy 292.70493 -370.93612) (xy 292.674138 -370.93612) (xy 292.644745 -370.945296) (xy 292.619421 -370.962815)
			(xy 292.609524 -370.97462) (xy 292.591324 -370.997096) (xy 292.549306 -371.036831) (xy 292.501773 -371.06977)
			(xy 292.449813 -371.09516) (xy 292.394617 -371.112418) (xy 292.337449 -371.121149) (xy 292.308534 -371.121686)
			(xy 292.281281 -371.121213) (xy 292.227329 -371.11346) (xy 292.17503 -371.098107) (xy 292.125449 -371.075467)
			(xy 292.079594 -371.046001) (xy 292.038401 -371.010308) (xy 292.002707 -370.969115) (xy 291.973239 -370.923262)
			(xy 291.950597 -370.873681) (xy 291.935242 -370.821382) (xy 291.927488 -370.767431) (xy 291.927026 -370.740178)
			(xy 290.295262 -370.740178) (xy 290.299383 -370.746591) (xy 290.322025 -370.796168) (xy 290.33738 -370.848463)
			(xy 290.345136 -370.902411) (xy 290.345622 -370.929662) (xy 290.345153 -370.957032) (xy 290.337339 -371.011212)
			(xy 290.321851 -371.063716) (xy 290.29901 -371.113463) (xy 290.269284 -371.159429) (xy 290.251642 -371.18036)
			(xy 290.242446 -371.191717) (xy 290.230272 -371.218265) (xy 290.226094 -371.247171) (xy 290.230255 -371.27608)
			(xy 290.242415 -371.302635) (xy 290.251642 -371.313964) (xy 290.269247 -371.334926) (xy 290.298975 -371.380888)
			(xy 290.321825 -371.430629) (xy 290.337325 -371.483127) (xy 290.345158 -371.537302) (xy 290.345162 -371.592041)
			(xy 290.337338 -371.646217) (xy 290.321845 -371.698717) (xy 290.299003 -371.748462) (xy 290.269281 -371.794428)
			(xy 290.251642 -371.81536) (xy 290.242446 -371.826717) (xy 290.230272 -371.853265) (xy 290.226094 -371.882171)
			(xy 290.230255 -371.91108) (xy 290.242415 -371.937635) (xy 290.251642 -371.948964) (xy 290.269285 -371.969893)
			(xy 290.298995 -372.015867) (xy 290.321829 -372.065616) (xy 290.33732 -372.118117) (xy 290.345148 -372.172293)
			(xy 290.345622 -372.199662) (xy 290.345106 -372.228579) (xy 290.336381 -372.285752) (xy 290.319124 -372.340952)
			(xy 290.293732 -372.392915) (xy 290.260787 -372.440448) (xy 290.221043 -372.482463) (xy 290.198556 -372.500652)
			(xy 290.186785 -372.510589) (xy 290.169259 -372.535899) (xy 290.160075 -372.565284) (xy 290.160068 -372.59607)
			(xy 290.169238 -372.625458) (xy 290.186752 -372.650777) (xy 290.198556 -372.660672) (xy 290.219301 -372.677471)
			(xy 290.256429 -372.715819) (xy 290.287849 -372.758969) (xy 290.312948 -372.806077) (xy 290.331235 -372.856224)
			(xy 290.342354 -372.90843) (xy 290.346086 -372.961677) (xy 290.34236 -373.014924) (xy 290.331248 -373.067131)
			(xy 290.312967 -373.11728) (xy 290.287874 -373.164392) (xy 290.256459 -373.207545) (xy 290.219335 -373.245898)
			(xy 290.198556 -373.262652) (xy 290.186785 -373.272589) (xy 290.169259 -373.297899) (xy 290.160075 -373.327284)
			(xy 290.160068 -373.35807) (xy 290.169238 -373.387458) (xy 290.186752 -373.412777) (xy 290.198556 -373.422672)
			(xy 290.221017 -373.44089) (xy 290.260756 -373.482903) (xy 290.293698 -373.530432) (xy 290.319091 -373.582388)
			(xy 290.336352 -373.637581) (xy 290.345085 -373.694747) (xy 290.345622 -373.723662) (xy 290.345136 -373.750913)
			(xy 290.33738 -373.804861) (xy 290.322025 -373.857156) (xy 290.299383 -373.906733) (xy 290.269917 -373.952583)
			(xy 290.234226 -373.993774) (xy 290.193035 -374.029465) (xy 290.147185 -374.058931) (xy 290.097608 -374.081573)
			(xy 290.045313 -374.096928) (xy 289.991365 -374.104684) (xy 289.936863 -374.104684) (xy 289.882915 -374.096928)
			(xy 289.83062 -374.081573) (xy 289.781043 -374.058931) (xy 289.735193 -374.029465) (xy 289.694002 -373.993774)
			(xy 289.658311 -373.952583) (xy 289.628845 -373.906733) (xy 289.606203 -373.857156) (xy 289.590848 -373.804861)
			(xy 289.583092 -373.750913) (xy 289.582606 -373.723662) (xy 289.583167 -373.694747) (xy 289.591886 -373.637577)
			(xy 289.609136 -373.582379) (xy 289.63452 -373.530417) (xy 289.667456 -373.482882) (xy 289.70719 -373.440863)
			(xy 289.729672 -373.422672) (xy 289.741517 -373.412817) (xy 289.759036 -373.387482) (xy 289.768209 -373.358078)
			(xy 289.768202 -373.327276) (xy 289.759016 -373.297875) (xy 289.741484 -373.272549) (xy 289.729672 -373.262652)
			(xy 289.708851 -373.245944) (xy 289.671719 -373.207586) (xy 289.640296 -373.164426) (xy 289.615197 -373.117307)
			(xy 289.596912 -373.06715) (xy 289.585797 -373.014933) (xy 289.58207 -372.961677) (xy 288.375806 -372.961677)
			(xy 288.377586 -372.987077) (xy 288.37386 -373.040324) (xy 288.362748 -373.092531) (xy 288.344467 -373.14268)
			(xy 288.319374 -373.189792) (xy 288.287959 -373.232945) (xy 288.250835 -373.271298) (xy 288.230056 -373.288052)
			(xy 288.218285 -373.297989) (xy 288.200759 -373.323299) (xy 288.191575 -373.352684) (xy 288.191568 -373.38347)
			(xy 288.200738 -373.412858) (xy 288.218252 -373.438177) (xy 288.230056 -373.448072) (xy 288.252517 -373.46629)
			(xy 288.292256 -373.508303) (xy 288.325198 -373.555832) (xy 288.350591 -373.607788) (xy 288.367852 -373.662981)
			(xy 288.376585 -373.720147) (xy 288.377122 -373.749062) (xy 288.376609 -373.776313) (xy 288.368858 -373.830262)
			(xy 288.353507 -373.882558) (xy 288.33087 -373.932137) (xy 288.301408 -373.977989) (xy 288.265719 -374.019182)
			(xy 288.224531 -374.054876) (xy 288.178683 -374.084345) (xy 288.129107 -374.106989) (xy 288.076813 -374.122347)
			(xy 288.022865 -374.130106) (xy 287.995614 -374.13057) (xy 287.966697 -374.130053) (xy 287.909525 -374.121325)
			(xy 287.854326 -374.104068) (xy 287.802364 -374.078676) (xy 287.75483 -374.045732) (xy 287.712814 -374.00599)
			(xy 287.694624 -373.983504) (xy 287.684727 -373.971699) (xy 287.659403 -373.95418) (xy 287.63001 -373.945004)
			(xy 287.599218 -373.945004) (xy 287.569825 -373.95418) (xy 287.544501 -373.971699) (xy 287.534604 -373.983504)
			(xy 287.516412 -374.005986) (xy 287.474392 -374.045721) (xy 287.426857 -374.07866) (xy 287.374896 -374.104049)
			(xy 287.319699 -374.121306) (xy 287.26253 -374.130035) (xy 287.233614 -374.13057) (xy 287.206244 -374.130103)
			(xy 287.152064 -374.122287) (xy 287.099561 -374.106798) (xy 287.049814 -374.083956) (xy 287.003847 -374.054232)
			(xy 286.982916 -374.03659) (xy 286.971588 -374.027354) (xy 286.945031 -374.015178) (xy 286.916114 -374.011005)
			(xy 286.887197 -374.015178) (xy 286.86064 -374.027354) (xy 286.849312 -374.03659) (xy 286.828385 -374.054235)
			(xy 286.782411 -374.083947) (xy 286.732662 -374.106782) (xy 286.68016 -374.122271) (xy 286.625984 -374.130097)
			(xy 286.598614 -374.13057) (xy 286.57136 -374.130132) (xy 286.517406 -374.122375) (xy 286.465105 -374.107019)
			(xy 286.415523 -374.084376) (xy 286.369668 -374.054906) (xy 286.328474 -374.019209) (xy 286.29278 -373.978013)
			(xy 286.263313 -373.932156) (xy 286.240672 -373.882572) (xy 286.225319 -373.830271) (xy 286.217567 -373.776316)
			(xy 286.217106 -373.749062) (xy 286.217667 -373.720147) (xy 286.226386 -373.662977) (xy 286.243636 -373.607779)
			(xy 286.26902 -373.555817) (xy 286.301956 -373.508282) (xy 286.34169 -373.466263) (xy 286.364172 -373.448072)
			(xy 286.376017 -373.438217) (xy 286.393536 -373.412882) (xy 286.402709 -373.383478) (xy 286.402702 -373.352676)
			(xy 286.393516 -373.323275) (xy 286.375984 -373.297949) (xy 286.364172 -373.288052) (xy 286.343351 -373.271344)
			(xy 286.306219 -373.232986) (xy 286.274796 -373.189826) (xy 286.249697 -373.142707) (xy 286.231412 -373.09255)
			(xy 286.220297 -373.040333) (xy 286.21657 -372.987077) (xy 270.383 -372.987077) (xy 270.383 -378.776644)
			(xy 278.905204 -378.776644) (xy 278.905204 -378.691996) (xy 278.91325 -378.60773) (xy 278.92927 -378.524611)
			(xy 278.953118 -378.443392) (xy 278.984579 -378.364807) (xy 279.023367 -378.289568) (xy 279.069131 -378.218357)
			(xy 279.121458 -378.151819) (xy 279.179872 -378.090556) (xy 279.243845 -378.035123) (xy 279.312798 -377.986022)
			(xy 279.386106 -377.943697) (xy 279.463105 -377.908533) (xy 279.543098 -377.880847) (xy 279.62536 -377.86089)
			(xy 279.709147 -377.848844) (xy 279.7937 -377.844816) (xy 279.878253 -377.848844) (xy 279.96204 -377.86089)
			(xy 280.044302 -377.880847) (xy 280.124295 -377.908533) (xy 280.201294 -377.943697) (xy 280.274602 -377.986022)
			(xy 280.343555 -378.035123) (xy 280.407528 -378.090556) (xy 280.465942 -378.151819) (xy 280.518269 -378.218357)
			(xy 280.564033 -378.289568) (xy 280.602821 -378.364807) (xy 280.634282 -378.443392) (xy 280.65813 -378.524611)
			(xy 280.67415 -378.60773) (xy 280.682196 -378.691996) (xy 280.6827 -378.73432) (xy 280.682196 -378.776644)
			(xy 280.67415 -378.86091) (xy 280.65813 -378.944029) (xy 280.634282 -379.025248) (xy 280.602821 -379.103833)
			(xy 280.564033 -379.179072) (xy 280.518269 -379.250283) (xy 280.465942 -379.316821) (xy 280.407528 -379.378084)
			(xy 280.343555 -379.433517) (xy 280.274602 -379.482618) (xy 280.201294 -379.524943) (xy 280.124295 -379.560107)
			(xy 280.044302 -379.587793) (xy 279.96204 -379.60775) (xy 279.878253 -379.619796) (xy 279.7937 -379.623824)
			(xy 279.709147 -379.619796) (xy 279.62536 -379.60775) (xy 279.543098 -379.587793) (xy 279.463105 -379.560107)
			(xy 279.386106 -379.524943) (xy 279.312798 -379.482618) (xy 279.243845 -379.433517) (xy 279.179872 -379.378084)
			(xy 279.121458 -379.316821) (xy 279.069131 -379.250283) (xy 279.023367 -379.179072) (xy 278.984579 -379.103833)
			(xy 278.953118 -379.025248) (xy 278.92927 -378.944029) (xy 278.91325 -378.86091) (xy 278.905204 -378.776644)
			(xy 270.383 -378.776644) (xy 270.383 -380.406148) (xy 272.3134 -382.336548) (xy 302.8696 -382.336548)
		)
		(stroke
			(width 0)
			(type solid)
		)
		(fill yes)
		(layer "In2.Cu")
		(net "GND")
	)
	(gr_poly
		(pts
			(xy 436.9054 -370.083842) (xy 436.9054 -340.223348) (xy 435.2036 -338.521548) (xy 409.5496 -338.521548)
			(xy 408.964384 -339.106764) (xy 408.964384 -344.053344) (xy 414.212782 -344.053344) (xy 414.212782 -343.968648)
			(xy 414.220833 -343.884334) (xy 414.236862 -343.801168) (xy 414.260723 -343.719901) (xy 414.292202 -343.641271)
			(xy 414.331013 -343.56599) (xy 414.376803 -343.494738) (xy 414.429159 -343.428162) (xy 414.487607 -343.366864)
			(xy 414.551617 -343.311399) (xy 414.620609 -343.26227) (xy 414.693959 -343.219921) (xy 414.771002 -343.184737)
			(xy 414.851041 -343.157035) (xy 414.93335 -343.137067) (xy 415.017185 -343.125014) (xy 415.101786 -343.120984)
			(xy 415.186387 -343.125014) (xy 415.270222 -343.137067) (xy 415.352531 -343.157035) (xy 415.43257 -343.184737)
			(xy 415.509613 -343.219921) (xy 415.582963 -343.26227) (xy 415.651955 -343.311399) (xy 415.715965 -343.366864)
			(xy 415.774413 -343.428162) (xy 415.826769 -343.494738) (xy 415.872559 -343.56599) (xy 415.91137 -343.641271)
			(xy 415.942849 -343.719901) (xy 415.96671 -343.801168) (xy 415.982739 -343.884334) (xy 415.99079 -343.968648)
			(xy 415.991294 -344.010996) (xy 415.99079 -344.053344) (xy 415.990184 -344.059694) (xy 420.403524 -344.059694)
			(xy 420.403524 -343.974998) (xy 420.411575 -343.890684) (xy 420.427604 -343.807518) (xy 420.451465 -343.726251)
			(xy 420.482944 -343.647621) (xy 420.521755 -343.57234) (xy 420.567545 -343.501088) (xy 420.619901 -343.434512)
			(xy 420.678349 -343.373214) (xy 420.742359 -343.317749) (xy 420.811351 -343.26862) (xy 420.884701 -343.226271)
			(xy 420.961744 -343.191087) (xy 421.041783 -343.163385) (xy 421.124092 -343.143417) (xy 421.207927 -343.131364)
			(xy 421.292528 -343.127334) (xy 421.377129 -343.131364) (xy 421.460964 -343.143417) (xy 421.543273 -343.163385)
			(xy 421.623312 -343.191087) (xy 421.700355 -343.226271) (xy 421.773705 -343.26862) (xy 421.842697 -343.317749)
			(xy 421.906707 -343.373214) (xy 421.965155 -343.434512) (xy 422.017511 -343.501088) (xy 422.063301 -343.57234)
			(xy 422.102112 -343.647621) (xy 422.133591 -343.726251) (xy 422.157452 -343.807518) (xy 422.173481 -343.890684)
			(xy 422.181532 -343.974998) (xy 422.182036 -344.017346) (xy 422.181532 -344.059694) (xy 426.601124 -344.059694)
			(xy 426.601124 -343.974998) (xy 426.609175 -343.890684) (xy 426.625204 -343.807518) (xy 426.649065 -343.726251)
			(xy 426.680544 -343.647621) (xy 426.719355 -343.57234) (xy 426.765145 -343.501088) (xy 426.817501 -343.434512)
			(xy 426.875949 -343.373214) (xy 426.939959 -343.317749) (xy 427.008951 -343.26862) (xy 427.082301 -343.226271)
			(xy 427.159344 -343.191087) (xy 427.239383 -343.163385) (xy 427.321692 -343.143417) (xy 427.405527 -343.131364)
			(xy 427.490128 -343.127334) (xy 427.574729 -343.131364) (xy 427.658564 -343.143417) (xy 427.740873 -343.163385)
			(xy 427.820912 -343.191087) (xy 427.897955 -343.226271) (xy 427.971305 -343.26862) (xy 428.040297 -343.317749)
			(xy 428.104307 -343.373214) (xy 428.162755 -343.434512) (xy 428.215111 -343.501088) (xy 428.260901 -343.57234)
			(xy 428.299712 -343.647621) (xy 428.331191 -343.726251) (xy 428.355052 -343.807518) (xy 428.371081 -343.890684)
			(xy 428.379132 -343.974998) (xy 428.379636 -344.017346) (xy 428.379132 -344.059694) (xy 428.371081 -344.144008)
			(xy 428.355052 -344.227174) (xy 428.331191 -344.308441) (xy 428.299712 -344.387071) (xy 428.260901 -344.462352)
			(xy 428.215111 -344.533604) (xy 428.162755 -344.60018) (xy 428.104307 -344.661478) (xy 428.040297 -344.716943)
			(xy 427.971305 -344.766072) (xy 427.897955 -344.808421) (xy 427.820912 -344.843605) (xy 427.740873 -344.871307)
			(xy 427.658564 -344.891275) (xy 427.574729 -344.903328) (xy 427.490128 -344.907359) (xy 427.405527 -344.903328)
			(xy 427.321692 -344.891275) (xy 427.239383 -344.871307) (xy 427.159344 -344.843605) (xy 427.082301 -344.808421)
			(xy 427.008951 -344.766072) (xy 426.939959 -344.716943) (xy 426.875949 -344.661478) (xy 426.817501 -344.60018)
			(xy 426.765145 -344.533604) (xy 426.719355 -344.462352) (xy 426.680544 -344.387071) (xy 426.649065 -344.308441)
			(xy 426.625204 -344.227174) (xy 426.609175 -344.144008) (xy 426.601124 -344.059694) (xy 422.181532 -344.059694)
			(xy 422.173481 -344.144008) (xy 422.157452 -344.227174) (xy 422.133591 -344.308441) (xy 422.102112 -344.387071)
			(xy 422.063301 -344.462352) (xy 422.017511 -344.533604) (xy 421.965155 -344.60018) (xy 421.906707 -344.661478)
			(xy 421.842697 -344.716943) (xy 421.773705 -344.766072) (xy 421.700355 -344.808421) (xy 421.623312 -344.843605)
			(xy 421.543273 -344.871307) (xy 421.460964 -344.891275) (xy 421.377129 -344.903328) (xy 421.292528 -344.907359)
			(xy 421.207927 -344.903328) (xy 421.124092 -344.891275) (xy 421.041783 -344.871307) (xy 420.961744 -344.843605)
			(xy 420.884701 -344.808421) (xy 420.811351 -344.766072) (xy 420.742359 -344.716943) (xy 420.678349 -344.661478)
			(xy 420.619901 -344.60018) (xy 420.567545 -344.533604) (xy 420.521755 -344.462352) (xy 420.482944 -344.387071)
			(xy 420.451465 -344.308441) (xy 420.427604 -344.227174) (xy 420.411575 -344.144008) (xy 420.403524 -344.059694)
			(xy 415.990184 -344.059694) (xy 415.982739 -344.137658) (xy 415.96671 -344.220824) (xy 415.942849 -344.302091)
			(xy 415.91137 -344.380721) (xy 415.872559 -344.456002) (xy 415.826769 -344.527254) (xy 415.774413 -344.59383)
			(xy 415.715965 -344.655128) (xy 415.651955 -344.710593) (xy 415.582963 -344.759722) (xy 415.509613 -344.802071)
			(xy 415.43257 -344.837255) (xy 415.352531 -344.864957) (xy 415.270222 -344.884925) (xy 415.186387 -344.896978)
			(xy 415.101786 -344.901009) (xy 415.017185 -344.896978) (xy 414.93335 -344.884925) (xy 414.851041 -344.864957)
			(xy 414.771002 -344.837255) (xy 414.693959 -344.802071) (xy 414.620609 -344.759722) (xy 414.551617 -344.710593)
			(xy 414.487607 -344.655128) (xy 414.429159 -344.59383) (xy 414.376803 -344.527254) (xy 414.331013 -344.456002)
			(xy 414.292202 -344.380721) (xy 414.260723 -344.302091) (xy 414.236862 -344.220824) (xy 414.220833 -344.137658)
			(xy 414.212782 -344.053344) (xy 408.964384 -344.053344) (xy 408.964384 -346.010992) (xy 414.186375 -346.010992)
			(xy 414.190397 -345.925272) (xy 414.202428 -345.840304) (xy 414.222364 -345.756837) (xy 414.250027 -345.675603)
			(xy 414.285176 -345.597317) (xy 414.327502 -345.522666) (xy 414.376631 -345.452307) (xy 414.432134 -345.386857)
			(xy 414.493521 -345.326893) (xy 414.560254 -345.27294) (xy 414.631746 -345.225473) (xy 414.707368 -345.184909)
			(xy 414.786457 -345.151605) (xy 414.868317 -345.125853) (xy 414.952228 -345.10788) (xy 415.037454 -345.097844)
			(xy 415.123246 -345.095832) (xy 415.208848 -345.101863) (xy 415.29351 -345.115883) (xy 415.376487 -345.137769)
			(xy 415.45705 -345.16733) (xy 415.53449 -345.204304) (xy 415.608129 -345.248368) (xy 415.677317 -345.299134)
			(xy 415.741448 -345.356155) (xy 415.799957 -345.418931) (xy 415.85233 -345.486911) (xy 415.898108 -345.559496)
			(xy 415.936888 -345.636048) (xy 415.968329 -345.715896) (xy 415.992155 -345.798337) (xy 416.008156 -345.882647)
			(xy 416.016191 -345.968085) (xy 416.016694 -346.010992) (xy 416.01662 -346.017342) (xy 420.377117 -346.017342)
			(xy 420.381139 -345.931622) (xy 420.39317 -345.846654) (xy 420.413106 -345.763187) (xy 420.440769 -345.681953)
			(xy 420.475918 -345.603667) (xy 420.518244 -345.529016) (xy 420.567373 -345.458657) (xy 420.622876 -345.393207)
			(xy 420.684263 -345.333243) (xy 420.750996 -345.27929) (xy 420.822488 -345.231823) (xy 420.89811 -345.191259)
			(xy 420.977199 -345.157955) (xy 421.059059 -345.132203) (xy 421.14297 -345.11423) (xy 421.228196 -345.104194)
			(xy 421.313988 -345.102182) (xy 421.39959 -345.108213) (xy 421.484252 -345.122233) (xy 421.567229 -345.144119)
			(xy 421.647792 -345.17368) (xy 421.725232 -345.210654) (xy 421.798871 -345.254718) (xy 421.868059 -345.305484)
			(xy 421.93219 -345.362505) (xy 421.990699 -345.425281) (xy 422.043072 -345.493261) (xy 422.08885 -345.565846)
			(xy 422.12763 -345.642398) (xy 422.159071 -345.722246) (xy 422.182897 -345.804687) (xy 422.198898 -345.888997)
			(xy 422.206933 -345.974435) (xy 422.207436 -346.017342) (xy 426.574717 -346.017342) (xy 426.578739 -345.931622)
			(xy 426.59077 -345.846654) (xy 426.610706 -345.763187) (xy 426.638369 -345.681953) (xy 426.673518 -345.603667)
			(xy 426.715844 -345.529016) (xy 426.764973 -345.458657) (xy 426.820476 -345.393207) (xy 426.881863 -345.333243)
			(xy 426.948596 -345.27929) (xy 427.020088 -345.231823) (xy 427.09571 -345.191259) (xy 427.174799 -345.157955)
			(xy 427.256659 -345.132203) (xy 427.34057 -345.11423) (xy 427.425796 -345.104194) (xy 427.511588 -345.102182)
			(xy 427.59719 -345.108213) (xy 427.681852 -345.122233) (xy 427.764829 -345.144119) (xy 427.845392 -345.17368)
			(xy 427.922832 -345.210654) (xy 427.996471 -345.254718) (xy 428.065659 -345.305484) (xy 428.12979 -345.362505)
			(xy 428.188299 -345.425281) (xy 428.240672 -345.493261) (xy 428.28645 -345.565846) (xy 428.32523 -345.642398)
			(xy 428.356671 -345.722246) (xy 428.380497 -345.804687) (xy 428.396498 -345.888997) (xy 428.404533 -345.974435)
			(xy 428.405036 -346.017342) (xy 428.404533 -346.060249) (xy 428.396498 -346.145687) (xy 428.380497 -346.229997)
			(xy 428.356671 -346.312438) (xy 428.32523 -346.392286) (xy 428.28645 -346.468838) (xy 428.240672 -346.541423)
			(xy 428.188299 -346.609403) (xy 428.12979 -346.672179) (xy 428.065659 -346.7292) (xy 427.996471 -346.779966)
			(xy 427.922832 -346.82403) (xy 427.845392 -346.861004) (xy 427.764829 -346.890565) (xy 427.681852 -346.912451)
			(xy 427.59719 -346.926471) (xy 427.511588 -346.932502) (xy 427.425796 -346.93049) (xy 427.34057 -346.920454)
			(xy 427.256659 -346.902481) (xy 427.174799 -346.876729) (xy 427.09571 -346.843425) (xy 427.020088 -346.802861)
			(xy 426.948596 -346.755394) (xy 426.881863 -346.701441) (xy 426.820476 -346.641477) (xy 426.764973 -346.576027)
			(xy 426.715844 -346.505668) (xy 426.673518 -346.431017) (xy 426.638369 -346.352731) (xy 426.610706 -346.271497)
			(xy 426.59077 -346.18803) (xy 426.578739 -346.103062) (xy 426.574717 -346.017342) (xy 422.207436 -346.017342)
			(xy 422.206933 -346.060249) (xy 422.198898 -346.145687) (xy 422.182897 -346.229997) (xy 422.159071 -346.312438)
			(xy 422.12763 -346.392286) (xy 422.08885 -346.468838) (xy 422.043072 -346.541423) (xy 421.990699 -346.609403)
			(xy 421.93219 -346.672179) (xy 421.868059 -346.7292) (xy 421.798871 -346.779966) (xy 421.725232 -346.82403)
			(xy 421.647792 -346.861004) (xy 421.567229 -346.890565) (xy 421.484252 -346.912451) (xy 421.39959 -346.926471)
			(xy 421.313988 -346.932502) (xy 421.228196 -346.93049) (xy 421.14297 -346.920454) (xy 421.059059 -346.902481)
			(xy 420.977199 -346.876729) (xy 420.89811 -346.843425) (xy 420.822488 -346.802861) (xy 420.750996 -346.755394)
			(xy 420.684263 -346.701441) (xy 420.622876 -346.641477) (xy 420.567373 -346.576027) (xy 420.518244 -346.505668)
			(xy 420.475918 -346.431017) (xy 420.440769 -346.352731) (xy 420.413106 -346.271497) (xy 420.39317 -346.18803)
			(xy 420.381139 -346.103062) (xy 420.377117 -346.017342) (xy 416.01662 -346.017342) (xy 416.016191 -346.053899)
			(xy 416.008156 -346.139337) (xy 415.992155 -346.223647) (xy 415.968329 -346.306088) (xy 415.936888 -346.385936)
			(xy 415.898108 -346.462488) (xy 415.85233 -346.535073) (xy 415.799957 -346.603053) (xy 415.741448 -346.665829)
			(xy 415.677317 -346.72285) (xy 415.608129 -346.773616) (xy 415.53449 -346.81768) (xy 415.45705 -346.854654)
			(xy 415.376487 -346.884215) (xy 415.29351 -346.906101) (xy 415.208848 -346.920121) (xy 415.123246 -346.926152)
			(xy 415.037454 -346.92414) (xy 414.952228 -346.914104) (xy 414.868317 -346.896131) (xy 414.786457 -346.870379)
			(xy 414.707368 -346.837075) (xy 414.631746 -346.796511) (xy 414.560254 -346.749044) (xy 414.493521 -346.695091)
			(xy 414.432134 -346.635127) (xy 414.376631 -346.569677) (xy 414.327502 -346.499318) (xy 414.285176 -346.424667)
			(xy 414.250027 -346.346381) (xy 414.222364 -346.265147) (xy 414.202428 -346.18168) (xy 414.190397 -346.096712)
			(xy 414.186375 -346.010992) (xy 408.964384 -346.010992) (xy 408.964384 -351.152968) (xy 412.661354 -351.152968)
			(xy 412.661788 -351.125596) (xy 412.669612 -351.071415) (xy 412.685107 -351.018912) (xy 412.707957 -350.969165)
			(xy 412.737689 -350.9232) (xy 412.755334 -350.90227) (xy 412.764599 -350.890965) (xy 412.776768 -350.864398)
			(xy 412.780933 -350.835476) (xy 412.776755 -350.806555) (xy 412.764573 -350.779995) (xy 412.755334 -350.768666)
			(xy 412.737662 -350.747759) (xy 412.707938 -350.701787) (xy 412.685094 -350.652036) (xy 412.6696 -350.59953)
			(xy 412.661774 -350.545348) (xy 412.661777 -350.490604) (xy 412.66961 -350.436423) (xy 412.685111 -350.383918)
			(xy 412.707961 -350.334171) (xy 412.737691 -350.288203) (xy 412.755334 -350.26727) (xy 412.764599 -350.255965)
			(xy 412.776768 -350.229398) (xy 412.780933 -350.200476) (xy 412.776755 -350.171555) (xy 412.764573 -350.144995)
			(xy 412.755334 -350.133666) (xy 412.737662 -350.112759) (xy 412.707938 -350.066787) (xy 412.685094 -350.017036)
			(xy 412.6696 -349.96453) (xy 412.661774 -349.910348) (xy 412.661777 -349.855604) (xy 412.66961 -349.801423)
			(xy 412.685111 -349.748918) (xy 412.707961 -349.699171) (xy 412.737691 -349.653203) (xy 412.755334 -349.63227)
			(xy 412.764599 -349.620965) (xy 412.776768 -349.594398) (xy 412.780933 -349.565476) (xy 412.776755 -349.536555)
			(xy 412.764573 -349.509995) (xy 412.755334 -349.498666) (xy 412.737662 -349.477759) (xy 412.707938 -349.431787)
			(xy 412.685094 -349.382036) (xy 412.6696 -349.32953) (xy 412.661774 -349.275348) (xy 412.661777 -349.220604)
			(xy 412.66961 -349.166423) (xy 412.685111 -349.113918) (xy 412.707961 -349.064171) (xy 412.737691 -349.018203)
			(xy 412.755334 -348.99727) (xy 412.764599 -348.985965) (xy 412.776768 -348.959398) (xy 412.780933 -348.930476)
			(xy 412.776755 -348.901555) (xy 412.764573 -348.874995) (xy 412.755334 -348.863666) (xy 412.737662 -348.842759)
			(xy 412.707938 -348.796787) (xy 412.685094 -348.747036) (xy 412.6696 -348.69453) (xy 412.661774 -348.640348)
			(xy 412.661777 -348.585604) (xy 412.66961 -348.531423) (xy 412.685111 -348.478918) (xy 412.707961 -348.429171)
			(xy 412.737691 -348.383203) (xy 412.755334 -348.36227) (xy 412.764599 -348.350965) (xy 412.776768 -348.324398)
			(xy 412.780933 -348.295476) (xy 412.776755 -348.266555) (xy 412.764573 -348.239995) (xy 412.755334 -348.228666)
			(xy 412.737662 -348.207759) (xy 412.707938 -348.161787) (xy 412.685094 -348.112036) (xy 412.6696 -348.05953)
			(xy 412.661774 -348.005348) (xy 412.661777 -347.950604) (xy 412.66961 -347.896423) (xy 412.685111 -347.843918)
			(xy 412.707961 -347.794171) (xy 412.737691 -347.748203) (xy 412.755334 -347.72727) (xy 412.764599 -347.715965)
			(xy 412.776768 -347.689398) (xy 412.780933 -347.660476) (xy 412.776755 -347.631555) (xy 412.764573 -347.604995)
			(xy 412.755334 -347.593666) (xy 412.737718 -347.572715) (xy 412.708001 -347.526748) (xy 412.68516 -347.477006)
			(xy 412.669664 -347.424509) (xy 412.661831 -347.370336) (xy 412.661354 -347.342968) (xy 412.661848 -347.315718)
			(xy 412.669608 -347.261772) (xy 412.684965 -347.20948) (xy 412.707607 -347.159905) (xy 412.737073 -347.114057)
			(xy 412.772764 -347.072868) (xy 412.813952 -347.037177) (xy 412.8598 -347.00771) (xy 412.909374 -346.985067)
			(xy 412.961666 -346.969709) (xy 413.015612 -346.961948) (xy 413.042862 -346.96146) (xy 413.070232 -346.961934)
			(xy 413.124411 -346.969747) (xy 413.176915 -346.985234) (xy 413.226662 -347.008074) (xy 413.272629 -347.037799)
			(xy 413.29356 -347.05544) (xy 413.304888 -347.064676) (xy 413.331445 -347.076852) (xy 413.360362 -347.081025)
			(xy 413.389279 -347.076852) (xy 413.415836 -347.064676) (xy 413.427164 -347.05544) (xy 413.448104 -347.037811)
			(xy 413.494074 -347.008096) (xy 413.543819 -346.985257) (xy 413.596319 -346.969764) (xy 413.650493 -346.961935)
			(xy 413.677862 -346.96146) (xy 413.705901 -346.96198) (xy 413.761378 -346.970176) (xy 413.815059 -346.986395)
			(xy 413.865792 -347.010291) (xy 413.912485 -347.041349) (xy 413.93364 -347.059758) (xy 413.945082 -347.069403)
			(xy 413.972125 -347.082183) (xy 414.001712 -347.086569) (xy 414.031299 -347.082183) (xy 414.058342 -347.069403)
			(xy 414.069784 -347.059758) (xy 414.090918 -347.041318) (xy 414.1376 -347.010227) (xy 414.188336 -346.986316)
			(xy 414.242028 -346.970101) (xy 414.297518 -346.961931) (xy 414.325562 -346.96146) (xy 414.352812 -346.961991)
			(xy 414.406759 -346.969742) (xy 414.459054 -346.985091) (xy 414.508632 -347.007727) (xy 414.554484 -347.037188)
			(xy 414.595676 -347.072875) (xy 414.63137 -347.11406) (xy 414.66084 -347.159907) (xy 414.683484 -347.20948)
			(xy 414.698844 -347.261772) (xy 414.706604 -347.315718) (xy 414.70707 -347.342968) (xy 414.706592 -347.370338)
			(xy 414.698779 -347.424517) (xy 414.683293 -347.47702) (xy 414.660453 -347.526767) (xy 414.63073 -347.572734)
			(xy 414.61309 -347.593666) (xy 414.603885 -347.605017) (xy 414.591705 -347.631566) (xy 414.587527 -347.660476)
			(xy 414.591691 -347.689387) (xy 414.603858 -347.715943) (xy 414.61309 -347.72727) (xy 414.630699 -347.748228)
			(xy 414.660423 -347.794192) (xy 414.68327 -347.843934) (xy 414.698768 -347.896432) (xy 414.706599 -347.950607)
			(xy 414.706602 -348.005345) (xy 414.698778 -348.059521) (xy 414.683287 -348.11202) (xy 414.660447 -348.161765)
			(xy 414.630728 -348.207733) (xy 414.61309 -348.228666) (xy 414.603885 -348.240017) (xy 414.591705 -348.266566)
			(xy 414.587527 -348.295476) (xy 414.591691 -348.324387) (xy 414.603858 -348.350943) (xy 414.61309 -348.36227)
			(xy 414.630699 -348.383228) (xy 414.660423 -348.429192) (xy 414.68327 -348.478934) (xy 414.698768 -348.531432)
			(xy 414.706599 -348.585607) (xy 414.706602 -348.640345) (xy 414.698778 -348.694521) (xy 414.683287 -348.74702)
			(xy 414.660447 -348.796765) (xy 414.630728 -348.842733) (xy 414.61309 -348.863666) (xy 414.603885 -348.875017)
			(xy 414.591705 -348.901566) (xy 414.587527 -348.930476) (xy 414.591691 -348.959387) (xy 414.603858 -348.985943)
			(xy 414.61309 -348.99727) (xy 414.630699 -349.018228) (xy 414.660423 -349.064192) (xy 414.68327 -349.113934)
			(xy 414.698768 -349.166432) (xy 414.706599 -349.220607) (xy 414.706602 -349.275345) (xy 414.698778 -349.329521)
			(xy 414.683287 -349.38202) (xy 414.660447 -349.431765) (xy 414.630728 -349.477733) (xy 414.61309 -349.498666)
			(xy 414.603885 -349.510017) (xy 414.591705 -349.536566) (xy 414.587527 -349.565476) (xy 414.591691 -349.594387)
			(xy 414.603858 -349.620943) (xy 414.61309 -349.63227) (xy 414.630699 -349.653228) (xy 414.660423 -349.699192)
			(xy 414.68327 -349.748934) (xy 414.698768 -349.801432) (xy 414.706599 -349.855607) (xy 414.706602 -349.910345)
			(xy 414.698778 -349.964521) (xy 414.683287 -350.01702) (xy 414.660447 -350.066765) (xy 414.630728 -350.112733)
			(xy 414.61309 -350.133666) (xy 414.603885 -350.145017) (xy 414.591705 -350.171566) (xy 414.587527 -350.200476)
			(xy 414.591691 -350.229387) (xy 414.603858 -350.255943) (xy 414.61309 -350.26727) (xy 414.630699 -350.288228)
			(xy 414.660423 -350.334192) (xy 414.68327 -350.383934) (xy 414.698768 -350.436432) (xy 414.706599 -350.490607)
			(xy 414.706602 -350.545345) (xy 414.698778 -350.599521) (xy 414.683287 -350.65202) (xy 414.660447 -350.701765)
			(xy 414.630728 -350.747733) (xy 414.61309 -350.768666) (xy 414.603885 -350.780017) (xy 414.591705 -350.806566)
			(xy 414.587527 -350.835476) (xy 414.591691 -350.864387) (xy 414.603858 -350.890943) (xy 414.61309 -350.90227)
			(xy 414.630727 -350.923204) (xy 414.660439 -350.969176) (xy 414.683276 -351.018923) (xy 414.698767 -351.071423)
			(xy 414.706596 -351.125599) (xy 414.70707 -351.152968) (xy 417.631626 -351.152968) (xy 417.632067 -351.125597)
			(xy 417.63989 -351.071416) (xy 417.655384 -351.018913) (xy 417.678232 -350.969166) (xy 417.707962 -350.923201)
			(xy 417.725606 -350.90227) (xy 417.734873 -350.890966) (xy 417.747046 -350.864399) (xy 417.751212 -350.835476)
			(xy 417.747032 -350.806554) (xy 417.734847 -350.779994) (xy 417.725606 -350.768666) (xy 417.707935 -350.747758)
			(xy 417.678213 -350.701786) (xy 417.655371 -350.652035) (xy 417.639878 -350.599529) (xy 417.632053 -350.545348)
			(xy 417.632056 -350.490604) (xy 417.639888 -350.436423) (xy 417.655388 -350.38392) (xy 417.678236 -350.334172)
			(xy 417.707964 -350.288203) (xy 417.725606 -350.26727) (xy 417.734873 -350.255966) (xy 417.747046 -350.229399)
			(xy 417.751212 -350.200476) (xy 417.747032 -350.171554) (xy 417.734847 -350.144994) (xy 417.725606 -350.133666)
			(xy 417.707935 -350.112758) (xy 417.678213 -350.066786) (xy 417.655371 -350.017035) (xy 417.639878 -349.964529)
			(xy 417.632053 -349.910348) (xy 417.632056 -349.855604) (xy 417.639888 -349.801423) (xy 417.655388 -349.74892)
			(xy 417.678236 -349.699172) (xy 417.707964 -349.653203) (xy 417.725606 -349.63227) (xy 417.734873 -349.620966)
			(xy 417.747046 -349.594399) (xy 417.751212 -349.565476) (xy 417.747032 -349.536554) (xy 417.734847 -349.509994)
			(xy 417.725606 -349.498666) (xy 417.707935 -349.477758) (xy 417.678213 -349.431786) (xy 417.655371 -349.382035)
			(xy 417.639878 -349.329529) (xy 417.632053 -349.275348) (xy 417.632056 -349.220604) (xy 417.639888 -349.166423)
			(xy 417.655388 -349.11392) (xy 417.678236 -349.064172) (xy 417.707964 -349.018203) (xy 417.725606 -348.99727)
			(xy 417.734873 -348.985966) (xy 417.747046 -348.959399) (xy 417.751212 -348.930476) (xy 417.747032 -348.901554)
			(xy 417.734847 -348.874994) (xy 417.725606 -348.863666) (xy 417.707935 -348.842758) (xy 417.678213 -348.796786)
			(xy 417.655371 -348.747035) (xy 417.639878 -348.694529) (xy 417.632053 -348.640348) (xy 417.632056 -348.585604)
			(xy 417.639888 -348.531423) (xy 417.655388 -348.47892) (xy 417.678236 -348.429172) (xy 417.707964 -348.383203)
			(xy 417.725606 -348.36227) (xy 417.734873 -348.350966) (xy 417.747046 -348.324399) (xy 417.751212 -348.295476)
			(xy 417.747032 -348.266554) (xy 417.734847 -348.239994) (xy 417.725606 -348.228666) (xy 417.707935 -348.207758)
			(xy 417.678213 -348.161786) (xy 417.655371 -348.112035) (xy 417.639878 -348.059529) (xy 417.632053 -348.005348)
			(xy 417.632056 -347.950604) (xy 417.639888 -347.896423) (xy 417.655388 -347.84392) (xy 417.678236 -347.794172)
			(xy 417.707964 -347.748203) (xy 417.725606 -347.72727) (xy 417.734873 -347.715966) (xy 417.747046 -347.689399)
			(xy 417.751212 -347.660476) (xy 417.747032 -347.631554) (xy 417.734847 -347.604994) (xy 417.725606 -347.593666)
			(xy 417.707985 -347.572719) (xy 417.678271 -347.52675) (xy 417.655431 -347.477007) (xy 417.639936 -347.424509)
			(xy 417.632103 -347.370336) (xy 417.631626 -347.342968) (xy 417.632025 -347.315713) (xy 417.639787 -347.261758)
			(xy 417.655149 -347.209457) (xy 417.677798 -347.159874) (xy 417.707273 -347.114019) (xy 417.742973 -347.072826)
			(xy 417.784172 -347.037133) (xy 417.830032 -347.007666) (xy 417.879619 -346.985026) (xy 417.931922 -346.969673)
			(xy 417.985879 -346.96192) (xy 418.013134 -346.96146) (xy 418.041175 -346.961937) (xy 418.096653 -346.970143)
			(xy 418.150335 -346.986373) (xy 418.201067 -347.010278) (xy 418.247758 -347.041345) (xy 418.268912 -347.059758)
			(xy 418.280354 -347.069403) (xy 418.307397 -347.082183) (xy 418.336984 -347.086569) (xy 418.366571 -347.082183)
			(xy 418.393614 -347.069403) (xy 418.405056 -347.059758) (xy 418.426201 -347.041331) (xy 418.47288 -347.010239)
			(xy 418.523613 -346.986325) (xy 418.577303 -346.970106) (xy 418.63279 -346.961933) (xy 418.660834 -346.96146)
			(xy 418.688206 -346.961892) (xy 418.742387 -346.969715) (xy 418.794891 -346.985212) (xy 418.844637 -347.008062)
			(xy 418.890602 -347.037795) (xy 418.911532 -347.05544) (xy 418.92286 -347.064676) (xy 418.949417 -347.076852)
			(xy 418.978334 -347.081025) (xy 419.007251 -347.076852) (xy 419.033808 -347.064676) (xy 419.045136 -347.05544)
			(xy 419.066087 -347.037824) (xy 419.112054 -347.008107) (xy 419.161796 -346.985266) (xy 419.214293 -346.96977)
			(xy 419.268466 -346.961937) (xy 419.295834 -346.96146) (xy 419.323085 -346.961946) (xy 419.377031 -346.969706)
			(xy 419.429323 -346.985064) (xy 419.478899 -347.007707) (xy 419.524747 -347.037174) (xy 419.565936 -347.072865)
			(xy 419.601627 -347.114054) (xy 419.631094 -347.159903) (xy 419.653736 -347.209478) (xy 419.669094 -347.261771)
			(xy 419.676854 -347.315717) (xy 419.677342 -347.342968) (xy 419.676871 -347.370338) (xy 419.669057 -347.424518)
			(xy 419.65357 -347.477021) (xy 419.630728 -347.526768) (xy 419.601004 -347.572735) (xy 419.583362 -347.593666)
			(xy 419.574159 -347.605018) (xy 419.561982 -347.631567) (xy 419.557806 -347.660476) (xy 419.561969 -347.689386)
			(xy 419.574133 -347.715942) (xy 419.583362 -347.72727) (xy 419.600972 -347.748228) (xy 419.630699 -347.794191)
			(xy 419.653547 -347.843933) (xy 419.669046 -347.896431) (xy 419.676878 -347.950607) (xy 419.676881 -348.005345)
			(xy 419.669056 -348.059521) (xy 419.653564 -348.112022) (xy 419.630722 -348.161767) (xy 419.601001 -348.207734)
			(xy 419.583362 -348.228666) (xy 419.574159 -348.240018) (xy 419.561982 -348.266567) (xy 419.557806 -348.295476)
			(xy 419.561969 -348.324386) (xy 419.574133 -348.350942) (xy 419.583362 -348.36227) (xy 419.600972 -348.383228)
			(xy 419.630699 -348.429191) (xy 419.653547 -348.478933) (xy 419.669046 -348.531431) (xy 419.676878 -348.585607)
			(xy 419.676881 -348.640345) (xy 419.669056 -348.694521) (xy 419.653564 -348.747022) (xy 419.630722 -348.796767)
			(xy 419.601001 -348.842734) (xy 419.583362 -348.863666) (xy 419.574159 -348.875018) (xy 419.561982 -348.901567)
			(xy 419.557806 -348.930476) (xy 419.561969 -348.959386) (xy 419.574133 -348.985942) (xy 419.583362 -348.99727)
			(xy 419.600972 -349.018228) (xy 419.630699 -349.064191) (xy 419.653547 -349.113933) (xy 419.669046 -349.166431)
			(xy 419.676878 -349.220607) (xy 419.676881 -349.275345) (xy 419.669056 -349.329521) (xy 419.653564 -349.382022)
			(xy 419.630722 -349.431767) (xy 419.601001 -349.477734) (xy 419.583362 -349.498666) (xy 419.574159 -349.510018)
			(xy 419.561982 -349.536567) (xy 419.557806 -349.565476) (xy 419.561969 -349.594386) (xy 419.574133 -349.620942)
			(xy 419.583362 -349.63227) (xy 419.600972 -349.653228) (xy 419.630699 -349.699191) (xy 419.653547 -349.748933)
			(xy 419.669046 -349.801431) (xy 419.676878 -349.855607) (xy 419.676881 -349.910345) (xy 419.669056 -349.964521)
			(xy 419.653564 -350.017022) (xy 419.630722 -350.066767) (xy 419.601001 -350.112734) (xy 419.583362 -350.133666)
			(xy 419.574159 -350.145018) (xy 419.561982 -350.171567) (xy 419.557806 -350.200476) (xy 419.561969 -350.229386)
			(xy 419.574133 -350.255942) (xy 419.583362 -350.26727) (xy 419.600972 -350.288228) (xy 419.630699 -350.334191)
			(xy 419.653547 -350.383933) (xy 419.669046 -350.436431) (xy 419.676878 -350.490607) (xy 419.676881 -350.545345)
			(xy 419.669056 -350.599521) (xy 419.653564 -350.652022) (xy 419.630722 -350.701767) (xy 419.601001 -350.747734)
			(xy 419.583362 -350.768666) (xy 419.574159 -350.780018) (xy 419.561982 -350.806567) (xy 419.557806 -350.835476)
			(xy 419.561969 -350.864386) (xy 419.574133 -350.890942) (xy 419.583362 -350.90227) (xy 419.600995 -350.923207)
			(xy 419.630709 -350.969178) (xy 419.653547 -351.018924) (xy 419.669039 -351.071424) (xy 419.676868 -351.125599)
			(xy 419.677342 -351.152968) (xy 422.338754 -351.152968) (xy 422.339188 -351.125596) (xy 422.347012 -351.071415)
			(xy 422.362507 -351.018912) (xy 422.385357 -350.969165) (xy 422.415089 -350.9232) (xy 422.432734 -350.90227)
			(xy 422.441999 -350.890965) (xy 422.454168 -350.864398) (xy 422.458333 -350.835476) (xy 422.454155 -350.806555)
			(xy 422.441973 -350.779995) (xy 422.432734 -350.768666) (xy 422.415062 -350.747759) (xy 422.385338 -350.701787)
			(xy 422.362494 -350.652036) (xy 422.347 -350.59953) (xy 422.339174 -350.545348) (xy 422.339177 -350.490604)
			(xy 422.34701 -350.436423) (xy 422.362511 -350.383918) (xy 422.385361 -350.334171) (xy 422.415091 -350.288203)
			(xy 422.432734 -350.26727) (xy 422.441999 -350.255965) (xy 422.454168 -350.229398) (xy 422.458333 -350.200476)
			(xy 422.454155 -350.171555) (xy 422.441973 -350.144995) (xy 422.432734 -350.133666) (xy 422.415062 -350.112759)
			(xy 422.385338 -350.066787) (xy 422.362494 -350.017036) (xy 422.347 -349.96453) (xy 422.339174 -349.910348)
			(xy 422.339177 -349.855604) (xy 422.34701 -349.801423) (xy 422.362511 -349.748918) (xy 422.385361 -349.699171)
			(xy 422.415091 -349.653203) (xy 422.432734 -349.63227) (xy 422.441999 -349.620965) (xy 422.454168 -349.594398)
			(xy 422.458333 -349.565476) (xy 422.454155 -349.536555) (xy 422.441973 -349.509995) (xy 422.432734 -349.498666)
			(xy 422.415062 -349.477759) (xy 422.385338 -349.431787) (xy 422.362494 -349.382036) (xy 422.347 -349.32953)
			(xy 422.339174 -349.275348) (xy 422.339177 -349.220604) (xy 422.34701 -349.166423) (xy 422.362511 -349.113918)
			(xy 422.385361 -349.064171) (xy 422.415091 -349.018203) (xy 422.432734 -348.99727) (xy 422.441999 -348.985965)
			(xy 422.454168 -348.959398) (xy 422.458333 -348.930476) (xy 422.454155 -348.901555) (xy 422.441973 -348.874995)
			(xy 422.432734 -348.863666) (xy 422.415062 -348.842759) (xy 422.385338 -348.796787) (xy 422.362494 -348.747036)
			(xy 422.347 -348.69453) (xy 422.339174 -348.640348) (xy 422.339177 -348.585604) (xy 422.34701 -348.531423)
			(xy 422.362511 -348.478918) (xy 422.385361 -348.429171) (xy 422.415091 -348.383203) (xy 422.432734 -348.36227)
			(xy 422.441999 -348.350965) (xy 422.454168 -348.324398) (xy 422.458333 -348.295476) (xy 422.454155 -348.266555)
			(xy 422.441973 -348.239995) (xy 422.432734 -348.228666) (xy 422.415062 -348.207759) (xy 422.385338 -348.161787)
			(xy 422.362494 -348.112036) (xy 422.347 -348.05953) (xy 422.339174 -348.005348) (xy 422.339177 -347.950604)
			(xy 422.34701 -347.896423) (xy 422.362511 -347.843918) (xy 422.385361 -347.794171) (xy 422.415091 -347.748203)
			(xy 422.432734 -347.72727) (xy 422.441999 -347.715965) (xy 422.454168 -347.689398) (xy 422.458333 -347.660476)
			(xy 422.454155 -347.631555) (xy 422.441973 -347.604995) (xy 422.432734 -347.593666) (xy 422.415118 -347.572715)
			(xy 422.385401 -347.526748) (xy 422.36256 -347.477006) (xy 422.347064 -347.424509) (xy 422.339231 -347.370336)
			(xy 422.338754 -347.342968) (xy 422.339248 -347.315718) (xy 422.347008 -347.261772) (xy 422.362365 -347.20948)
			(xy 422.385007 -347.159905) (xy 422.414473 -347.114057) (xy 422.450164 -347.072868) (xy 422.491352 -347.037177)
			(xy 422.5372 -347.00771) (xy 422.586774 -346.985067) (xy 422.639066 -346.969709) (xy 422.693012 -346.961948)
			(xy 422.720262 -346.96146) (xy 422.747632 -346.961934) (xy 422.801811 -346.969747) (xy 422.854315 -346.985234)
			(xy 422.904062 -347.008074) (xy 422.950029 -347.037799) (xy 422.97096 -347.05544) (xy 422.982288 -347.064676)
			(xy 423.008845 -347.076852) (xy 423.037762 -347.081025) (xy 423.066679 -347.076852) (xy 423.093236 -347.064676)
			(xy 423.104564 -347.05544) (xy 423.125504 -347.037811) (xy 423.171474 -347.008096) (xy 423.221219 -346.985257)
			(xy 423.273719 -346.969764) (xy 423.327893 -346.961935) (xy 423.355262 -346.96146) (xy 423.383301 -346.96198)
			(xy 423.438778 -346.970176) (xy 423.492459 -346.986395) (xy 423.543192 -347.010291) (xy 423.589885 -347.041349)
			(xy 423.61104 -347.059758) (xy 423.622482 -347.069403) (xy 423.649525 -347.082183) (xy 423.679112 -347.086569)
			(xy 423.708699 -347.082183) (xy 423.735742 -347.069403) (xy 423.747184 -347.059758) (xy 423.768318 -347.041318)
			(xy 423.815 -347.010227) (xy 423.865736 -346.986316) (xy 423.919428 -346.970101) (xy 423.974918 -346.961931)
			(xy 424.002962 -346.96146) (xy 424.030212 -346.961991) (xy 424.084159 -346.969742) (xy 424.136454 -346.985091)
			(xy 424.186032 -347.007727) (xy 424.231884 -347.037188) (xy 424.273076 -347.072875) (xy 424.30877 -347.11406)
			(xy 424.33824 -347.159907) (xy 424.360884 -347.20948) (xy 424.376244 -347.261772) (xy 424.384004 -347.315718)
			(xy 424.38447 -347.342968) (xy 424.383992 -347.370338) (xy 424.376179 -347.424517) (xy 424.360693 -347.47702)
			(xy 424.337853 -347.526767) (xy 424.30813 -347.572734) (xy 424.29049 -347.593666) (xy 424.281285 -347.605017)
			(xy 424.269105 -347.631566) (xy 424.264927 -347.660476) (xy 424.269091 -347.689387) (xy 424.281258 -347.715943)
			(xy 424.29049 -347.72727) (xy 424.308099 -347.748228) (xy 424.337823 -347.794192) (xy 424.36067 -347.843934)
			(xy 424.376168 -347.896432) (xy 424.383999 -347.950607) (xy 424.384002 -348.005345) (xy 424.376178 -348.059521)
			(xy 424.360687 -348.11202) (xy 424.337847 -348.161765) (xy 424.308128 -348.207733) (xy 424.29049 -348.228666)
			(xy 424.281285 -348.240017) (xy 424.269105 -348.266566) (xy 424.264927 -348.295476) (xy 424.269091 -348.324387)
			(xy 424.281258 -348.350943) (xy 424.29049 -348.36227) (xy 424.308099 -348.383228) (xy 424.337823 -348.429192)
			(xy 424.36067 -348.478934) (xy 424.376168 -348.531432) (xy 424.383999 -348.585607) (xy 424.384002 -348.640345)
			(xy 424.376178 -348.694521) (xy 424.360687 -348.74702) (xy 424.337847 -348.796765) (xy 424.308128 -348.842733)
			(xy 424.29049 -348.863666) (xy 424.281285 -348.875017) (xy 424.269105 -348.901566) (xy 424.264927 -348.930476)
			(xy 424.269091 -348.959387) (xy 424.281258 -348.985943) (xy 424.29049 -348.99727) (xy 424.308099 -349.018228)
			(xy 424.337823 -349.064192) (xy 424.36067 -349.113934) (xy 424.376168 -349.166432) (xy 424.383999 -349.220607)
			(xy 424.384002 -349.275345) (xy 424.376178 -349.329521) (xy 424.360687 -349.38202) (xy 424.337847 -349.431765)
			(xy 424.308128 -349.477733) (xy 424.29049 -349.498666) (xy 424.281285 -349.510017) (xy 424.269105 -349.536566)
			(xy 424.264927 -349.565476) (xy 424.269091 -349.594387) (xy 424.281258 -349.620943) (xy 424.29049 -349.63227)
			(xy 424.308099 -349.653228) (xy 424.337823 -349.699192) (xy 424.36067 -349.748934) (xy 424.376168 -349.801432)
			(xy 424.383999 -349.855607) (xy 424.384002 -349.910345) (xy 424.376178 -349.964521) (xy 424.360687 -350.01702)
			(xy 424.337847 -350.066765) (xy 424.308128 -350.112733) (xy 424.29049 -350.133666) (xy 424.281285 -350.145017)
			(xy 424.269105 -350.171566) (xy 424.264927 -350.200476) (xy 424.269091 -350.229387) (xy 424.281258 -350.255943)
			(xy 424.29049 -350.26727) (xy 424.308099 -350.288228) (xy 424.337823 -350.334192) (xy 424.36067 -350.383934)
			(xy 424.376168 -350.436432) (xy 424.383999 -350.490607) (xy 424.384002 -350.545345) (xy 424.376178 -350.599521)
			(xy 424.360687 -350.65202) (xy 424.337847 -350.701765) (xy 424.308128 -350.747733) (xy 424.29049 -350.768666)
			(xy 424.281285 -350.780017) (xy 424.269105 -350.806566) (xy 424.264927 -350.835476) (xy 424.269091 -350.864387)
			(xy 424.281258 -350.890943) (xy 424.29049 -350.90227) (xy 424.308127 -350.923204) (xy 424.337839 -350.969176)
			(xy 424.360676 -351.018923) (xy 424.376167 -351.071423) (xy 424.383996 -351.125599) (xy 424.38447 -351.152968)
			(xy 427.95444 -351.152968) (xy 427.954878 -351.125597) (xy 427.962701 -351.071416) (xy 427.978196 -351.018912)
			(xy 428.001044 -350.969166) (xy 428.030775 -350.9232) (xy 428.04842 -350.90227) (xy 428.057686 -350.890965)
			(xy 428.069857 -350.864399) (xy 428.074023 -350.835476) (xy 428.069843 -350.806555) (xy 428.05766 -350.779994)
			(xy 428.04842 -350.768666) (xy 428.030748 -350.747758) (xy 428.001025 -350.701786) (xy 427.978182 -350.652036)
			(xy 427.962689 -350.59953) (xy 427.954863 -350.545348) (xy 427.954867 -350.490604) (xy 427.962699 -350.436423)
			(xy 427.978199 -350.383919) (xy 428.001049 -350.334172) (xy 428.030777 -350.288203) (xy 428.04842 -350.26727)
			(xy 428.057686 -350.255965) (xy 428.069857 -350.229399) (xy 428.074023 -350.200476) (xy 428.069843 -350.171555)
			(xy 428.05766 -350.144994) (xy 428.04842 -350.133666) (xy 428.030748 -350.112758) (xy 428.001025 -350.066786)
			(xy 427.978182 -350.017036) (xy 427.962689 -349.96453) (xy 427.954863 -349.910348) (xy 427.954867 -349.855604)
			(xy 427.962699 -349.801423) (xy 427.978199 -349.748919) (xy 428.001049 -349.699172) (xy 428.030777 -349.653203)
			(xy 428.04842 -349.63227) (xy 428.057686 -349.620965) (xy 428.069857 -349.594399) (xy 428.074023 -349.565476)
			(xy 428.069843 -349.536555) (xy 428.05766 -349.509994) (xy 428.04842 -349.498666) (xy 428.030748 -349.477758)
			(xy 428.001025 -349.431786) (xy 427.978182 -349.382036) (xy 427.962689 -349.32953) (xy 427.954863 -349.275348)
			(xy 427.954867 -349.220604) (xy 427.962699 -349.166423) (xy 427.978199 -349.113919) (xy 428.001049 -349.064172)
			(xy 428.030777 -349.018203) (xy 428.04842 -348.99727) (xy 428.057686 -348.985965) (xy 428.069857 -348.959399)
			(xy 428.074023 -348.930476) (xy 428.069843 -348.901555) (xy 428.05766 -348.874994) (xy 428.04842 -348.863666)
			(xy 428.030748 -348.842758) (xy 428.001025 -348.796786) (xy 427.978182 -348.747036) (xy 427.962689 -348.69453)
			(xy 427.954863 -348.640348) (xy 427.954867 -348.585604) (xy 427.962699 -348.531423) (xy 427.978199 -348.478919)
			(xy 428.001049 -348.429172) (xy 428.030777 -348.383203) (xy 428.04842 -348.36227) (xy 428.057686 -348.350965)
			(xy 428.069857 -348.324399) (xy 428.074023 -348.295476) (xy 428.069843 -348.266555) (xy 428.05766 -348.239994)
			(xy 428.04842 -348.228666) (xy 428.030748 -348.207758) (xy 428.001025 -348.161786) (xy 427.978182 -348.112036)
			(xy 427.962689 -348.05953) (xy 427.954863 -348.005348) (xy 427.954867 -347.950604) (xy 427.962699 -347.896423)
			(xy 427.978199 -347.843919) (xy 428.001049 -347.794172) (xy 428.030777 -347.748203) (xy 428.04842 -347.72727)
			(xy 428.057686 -347.715965) (xy 428.069857 -347.689399) (xy 428.074023 -347.660476) (xy 428.069843 -347.631555)
			(xy 428.05766 -347.604994) (xy 428.04842 -347.593666) (xy 428.030801 -347.572717) (xy 428.001086 -347.526749)
			(xy 427.978246 -347.477006) (xy 427.96275 -347.424509) (xy 427.954917 -347.370336) (xy 427.95444 -347.342968)
			(xy 427.954825 -347.315712) (xy 427.962588 -347.261756) (xy 427.97795 -347.209454) (xy 428.0006 -347.15987)
			(xy 428.030076 -347.114015) (xy 428.065778 -347.072821) (xy 428.106979 -347.037128) (xy 428.15284 -347.007662)
			(xy 428.202429 -346.985022) (xy 428.254734 -346.969671) (xy 428.308692 -346.96192) (xy 428.335948 -346.96146)
			(xy 428.363987 -346.961989) (xy 428.419463 -346.970182) (xy 428.473145 -346.9864) (xy 428.523877 -347.010293)
			(xy 428.570571 -347.041349) (xy 428.591726 -347.059758) (xy 428.603168 -347.069403) (xy 428.630211 -347.082183)
			(xy 428.659798 -347.086569) (xy 428.689385 -347.082183) (xy 428.716428 -347.069403) (xy 428.72787 -347.059758)
			(xy 428.74901 -347.041324) (xy 428.79569 -347.010233) (xy 428.846424 -346.98632) (xy 428.900115 -346.970103)
			(xy 428.955604 -346.961932) (xy 428.983648 -346.96146) (xy 429.011018 -346.961942) (xy 429.065197 -346.969754)
			(xy 429.1177 -346.985238) (xy 429.167448 -347.008077) (xy 429.213414 -347.037799) (xy 429.234346 -347.05544)
			(xy 429.245674 -347.064676) (xy 429.272231 -347.076852) (xy 429.301148 -347.081025) (xy 429.330065 -347.076852)
			(xy 429.356622 -347.064676) (xy 429.36795 -347.05544) (xy 429.388895 -347.037817) (xy 429.434864 -347.008101)
			(xy 429.484608 -346.985262) (xy 429.537106 -346.969767) (xy 429.59128 -346.961936) (xy 429.618648 -346.96146)
			(xy 429.645899 -346.961933) (xy 429.699845 -346.969695) (xy 429.752138 -346.985055) (xy 429.801714 -347.007699)
			(xy 429.847562 -347.037168) (xy 429.888751 -347.07286) (xy 429.924442 -347.11405) (xy 429.953908 -347.1599)
			(xy 429.976551 -347.209477) (xy 429.991908 -347.26177) (xy 429.999668 -347.315717) (xy 430.000156 -347.342968)
			(xy 429.999682 -347.370338) (xy 429.991868 -347.424517) (xy 429.976381 -347.477021) (xy 429.953541 -347.526768)
			(xy 429.923817 -347.572734) (xy 429.906176 -347.593666) (xy 429.896972 -347.605017) (xy 429.884794 -347.631567)
			(xy 429.880616 -347.660476) (xy 429.88478 -347.689387) (xy 429.896946 -347.715942) (xy 429.906176 -347.72727)
			(xy 429.923785 -347.748228) (xy 429.953511 -347.794192) (xy 429.976358 -347.843934) (xy 429.991857 -347.896432)
			(xy 429.999688 -347.950607) (xy 429.999692 -348.005345) (xy 429.991867 -348.059521) (xy 429.976375 -348.112021)
			(xy 429.953534 -348.161766) (xy 429.923814 -348.207733) (xy 429.906176 -348.228666) (xy 429.896972 -348.240017)
			(xy 429.884794 -348.266567) (xy 429.880616 -348.295476) (xy 429.88478 -348.324387) (xy 429.896946 -348.350942)
			(xy 429.906176 -348.36227) (xy 429.923785 -348.383228) (xy 429.953511 -348.429192) (xy 429.976358 -348.478934)
			(xy 429.991857 -348.531432) (xy 429.999688 -348.585607) (xy 429.999692 -348.640345) (xy 429.991867 -348.694521)
			(xy 429.976375 -348.747021) (xy 429.953534 -348.796766) (xy 429.923814 -348.842733) (xy 429.906176 -348.863666)
			(xy 429.896972 -348.875017) (xy 429.884794 -348.901567) (xy 429.880616 -348.930476) (xy 429.88478 -348.959387)
			(xy 429.896946 -348.985942) (xy 429.906176 -348.99727) (xy 429.923785 -349.018228) (xy 429.953511 -349.064192)
			(xy 429.976358 -349.113934) (xy 429.991857 -349.166432) (xy 429.999688 -349.220607) (xy 429.999692 -349.275345)
			(xy 429.991867 -349.329521) (xy 429.976375 -349.382021) (xy 429.953534 -349.431766) (xy 429.923814 -349.477733)
			(xy 429.906176 -349.498666) (xy 429.896972 -349.510017) (xy 429.884794 -349.536567) (xy 429.880616 -349.565476)
			(xy 429.88478 -349.594387) (xy 429.896946 -349.620942) (xy 429.906176 -349.63227) (xy 429.923785 -349.653228)
			(xy 429.953511 -349.699192) (xy 429.976358 -349.748934) (xy 429.991857 -349.801432) (xy 429.999688 -349.855607)
			(xy 429.999692 -349.910345) (xy 429.991867 -349.964521) (xy 429.976375 -350.017021) (xy 429.953534 -350.066766)
			(xy 429.923814 -350.112733) (xy 429.906176 -350.133666) (xy 429.896972 -350.145017) (xy 429.884794 -350.171567)
			(xy 429.880616 -350.200476) (xy 429.88478 -350.229387) (xy 429.896946 -350.255942) (xy 429.906176 -350.26727)
			(xy 429.923785 -350.288228) (xy 429.953511 -350.334192) (xy 429.976358 -350.383934) (xy 429.991857 -350.436432)
			(xy 429.999688 -350.490607) (xy 429.999692 -350.545345) (xy 429.991867 -350.599521) (xy 429.976375 -350.652021)
			(xy 429.953534 -350.701766) (xy 429.923814 -350.747733) (xy 429.906176 -350.768666) (xy 429.896972 -350.780017)
			(xy 429.884794 -350.806567) (xy 429.880616 -350.835476) (xy 429.88478 -350.864387) (xy 429.896946 -350.890942)
			(xy 429.906176 -350.90227) (xy 429.923811 -350.923206) (xy 429.953524 -350.969177) (xy 429.976361 -351.018924)
			(xy 429.991853 -351.071424) (xy 429.999682 -351.125599) (xy 430.000156 -351.152968) (xy 429.999592 -351.180216)
			(xy 429.991841 -351.234159) (xy 429.976493 -351.286449) (xy 429.953859 -351.336023) (xy 429.9244 -351.381871)
			(xy 429.888717 -351.42306) (xy 429.847535 -351.458752) (xy 429.801693 -351.48822) (xy 429.752124 -351.510865)
			(xy 429.699837 -351.526224) (xy 429.645896 -351.533986) (xy 429.618648 -351.534476) (xy 429.591279 -351.533988)
			(xy 429.5371 -351.526176) (xy 429.484597 -351.510693) (xy 429.43485 -351.487856) (xy 429.388882 -351.458135)
			(xy 429.36795 -351.440496) (xy 429.356622 -351.43126) (xy 429.330065 -351.419084) (xy 429.301148 -351.414911)
			(xy 429.272231 -351.419084) (xy 429.245674 -351.43126) (xy 429.234346 -351.440496) (xy 429.213407 -351.458126)
			(xy 429.167436 -351.48784) (xy 429.11769 -351.510677) (xy 429.065191 -351.52617) (xy 429.011017 -351.534001)
			(xy 428.983648 -351.534476) (xy 428.955608 -351.533966) (xy 428.900131 -351.525771) (xy 428.846448 -351.509549)
			(xy 428.795716 -351.485651) (xy 428.749024 -351.45459) (xy 428.72787 -351.436178) (xy 428.716428 -351.426533)
			(xy 428.689385 -351.413753) (xy 428.659798 -351.409367) (xy 428.630211 -351.413753) (xy 428.603168 -351.426533)
			(xy 428.591726 -351.436178) (xy 428.570593 -351.45462) (xy 428.52391 -351.485709) (xy 428.473174 -351.509619)
			(xy 428.419482 -351.525835) (xy 428.363992 -351.534005) (xy 428.335948 -351.534476) (xy 428.308695 -351.534)
			(xy 428.254743 -351.526249) (xy 428.202443 -351.510897) (xy 428.152861 -351.488258) (xy 428.107006 -351.458792)
			(xy 428.065812 -351.423099) (xy 428.030118 -351.381907) (xy 428.00065 -351.336053) (xy 427.978008 -351.286472)
			(xy 427.962655 -351.234173) (xy 427.954901 -351.180221) (xy 427.95444 -351.152968) (xy 424.38447 -351.152968)
			(xy 424.384015 -351.180222) (xy 424.376261 -351.234175) (xy 424.360907 -351.286475) (xy 424.338266 -351.336058)
			(xy 424.308798 -351.381913) (xy 424.273103 -351.423107) (xy 424.231908 -351.458801) (xy 424.186053 -351.488269)
			(xy 424.13647 -351.510909) (xy 424.084169 -351.526262) (xy 424.030216 -351.534015) (xy 424.002962 -351.534476)
			(xy 423.97492 -351.534017) (xy 423.91944 -351.52581) (xy 423.865757 -351.509576) (xy 423.815026 -351.485667)
			(xy 423.768336 -351.454594) (xy 423.747184 -351.436178) (xy 423.735742 -351.426533) (xy 423.708699 -351.413753)
			(xy 423.679112 -351.409367) (xy 423.649525 -351.413753) (xy 423.622482 -351.426533) (xy 423.61104 -351.436178)
			(xy 423.589902 -351.454613) (xy 423.54322 -351.485703) (xy 423.492486 -351.509615) (xy 423.438794 -351.525832)
			(xy 423.383306 -351.534004) (xy 423.355262 -351.534476) (xy 423.327893 -351.533979) (xy 423.273715 -351.52617)
			(xy 423.221212 -351.510688) (xy 423.171464 -351.487853) (xy 423.125496 -351.458135) (xy 423.104564 -351.440496)
			(xy 423.093236 -351.43126) (xy 423.066679 -351.419084) (xy 423.037762 -351.414911) (xy 423.008845 -351.419084)
			(xy 422.982288 -351.43126) (xy 422.97096 -351.440496) (xy 422.950016 -351.45812) (xy 422.904046 -351.487834)
			(xy 422.854302 -351.510673) (xy 422.801804 -351.526168) (xy 422.74763 -351.534) (xy 422.720262 -351.534476)
			(xy 422.693008 -351.534057) (xy 422.639057 -351.526295) (xy 422.586759 -351.510933) (xy 422.537179 -351.488285)
			(xy 422.491327 -351.458812) (xy 422.450137 -351.423114) (xy 422.414446 -351.381917) (xy 422.384981 -351.336059)
			(xy 422.362342 -351.286476) (xy 422.34699 -351.234175) (xy 422.339238 -351.180222) (xy 422.338754 -351.152968)
			(xy 419.677342 -351.152968) (xy 419.676792 -351.180217) (xy 419.669041 -351.234161) (xy 419.653691 -351.286452)
			(xy 419.631057 -351.336027) (xy 419.601597 -351.381876) (xy 419.565912 -351.423065) (xy 419.524728 -351.458757)
			(xy 419.478885 -351.488225) (xy 419.429314 -351.510868) (xy 419.377025 -351.526227) (xy 419.323083 -351.533987)
			(xy 419.295834 -351.534476) (xy 419.268464 -351.533996) (xy 419.214285 -351.526182) (xy 419.161782 -351.510697)
			(xy 419.112035 -351.487858) (xy 419.066068 -351.458136) (xy 419.045136 -351.440496) (xy 419.033808 -351.43126)
			(xy 419.007251 -351.419084) (xy 418.978334 -351.414911) (xy 418.949417 -351.419084) (xy 418.92286 -351.43126)
			(xy 418.911532 -351.440496) (xy 418.890598 -351.458133) (xy 418.844626 -351.487845) (xy 418.794879 -351.510682)
			(xy 418.742379 -351.526173) (xy 418.688203 -351.534002) (xy 418.660834 -351.534476) (xy 418.632794 -351.533974)
			(xy 418.577316 -351.525777) (xy 418.523633 -351.509554) (xy 418.472901 -351.485654) (xy 418.42621 -351.45459)
			(xy 418.405056 -351.436178) (xy 418.393614 -351.426533) (xy 418.366571 -351.413753) (xy 418.336984 -351.409367)
			(xy 418.307397 -351.413753) (xy 418.280354 -351.426533) (xy 418.268912 -351.436178) (xy 418.247785 -351.454626)
			(xy 418.2011 -351.485714) (xy 418.150363 -351.509624) (xy 418.096669 -351.525837) (xy 418.041179 -351.534006)
			(xy 418.013134 -351.534476) (xy 417.985881 -351.534013) (xy 417.931928 -351.52626) (xy 417.879628 -351.510906)
			(xy 417.830046 -351.488266) (xy 417.784191 -351.458798) (xy 417.742997 -351.423104) (xy 417.707303 -351.38191)
			(xy 417.677835 -351.336056) (xy 417.655194 -351.286474) (xy 417.639841 -351.234174) (xy 417.632087 -351.180221)
			(xy 417.631626 -351.152968) (xy 414.70707 -351.152968) (xy 414.706615 -351.180222) (xy 414.698861 -351.234175)
			(xy 414.683507 -351.286475) (xy 414.660866 -351.336058) (xy 414.631398 -351.381913) (xy 414.595703 -351.423107)
			(xy 414.554508 -351.458801) (xy 414.508653 -351.488269) (xy 414.45907 -351.510909) (xy 414.406769 -351.526262)
			(xy 414.352816 -351.534015) (xy 414.325562 -351.534476) (xy 414.29752 -351.534017) (xy 414.24204 -351.52581)
			(xy 414.188357 -351.509576) (xy 414.137626 -351.485667) (xy 414.090936 -351.454594) (xy 414.069784 -351.436178)
			(xy 414.058342 -351.426533) (xy 414.031299 -351.413753) (xy 414.001712 -351.409367) (xy 413.972125 -351.413753)
			(xy 413.945082 -351.426533) (xy 413.93364 -351.436178) (xy 413.912502 -351.454613) (xy 413.86582 -351.485703)
			(xy 413.815086 -351.509615) (xy 413.761394 -351.525832) (xy 413.705906 -351.534004) (xy 413.677862 -351.534476)
			(xy 413.650493 -351.533979) (xy 413.596315 -351.52617) (xy 413.543812 -351.510688) (xy 413.494064 -351.487853)
			(xy 413.448096 -351.458135) (xy 413.427164 -351.440496) (xy 413.415836 -351.43126) (xy 413.389279 -351.419084)
			(xy 413.360362 -351.414911) (xy 413.331445 -351.419084) (xy 413.304888 -351.43126) (xy 413.29356 -351.440496)
			(xy 413.272616 -351.45812) (xy 413.226646 -351.487834) (xy 413.176902 -351.510673) (xy 413.124404 -351.526168)
			(xy 413.07023 -351.534) (xy 413.042862 -351.534476) (xy 413.015608 -351.534057) (xy 412.961657 -351.526295)
			(xy 412.909359 -351.510933) (xy 412.859779 -351.488285) (xy 412.813927 -351.458812) (xy 412.772737 -351.423114)
			(xy 412.737046 -351.381917) (xy 412.707581 -351.336059) (xy 412.684942 -351.286476) (xy 412.66959 -351.234175)
			(xy 412.661838 -351.180222) (xy 412.661354 -351.152968) (xy 408.964384 -351.152968) (xy 408.964384 -359.579926)
			(xy 409.33192 -359.579926) (xy 409.335991 -359.524304) (xy 409.348117 -359.469867) (xy 409.36804 -359.417776)
			(xy 409.395336 -359.369141) (xy 409.429422 -359.324998) (xy 409.469571 -359.286289) (xy 409.514929 -359.253838)
			(xy 409.564529 -359.228337) (xy 409.617313 -359.21033) (xy 409.672156 -359.2002) (xy 409.72789 -359.198163)
			(xy 409.783327 -359.204263) (xy 409.837284 -359.218369) (xy 409.888613 -359.240181) (xy 409.936219 -359.269235)
			(xy 409.979087 -359.30491) (xy 410.016304 -359.346447) (xy 410.047077 -359.39296) (xy 410.070749 -359.443457)
			(xy 410.086817 -359.496864) (xy 410.094937 -359.55204) (xy 410.095446 -359.579926) (xy 410.094937 -359.607812)
			(xy 410.086817 -359.662988) (xy 410.070749 -359.716395) (xy 410.047077 -359.766892) (xy 410.016304 -359.813405)
			(xy 409.979087 -359.854942) (xy 409.936219 -359.890617) (xy 409.888613 -359.919671) (xy 409.837284 -359.941483)
			(xy 409.783327 -359.955589) (xy 409.72789 -359.961689) (xy 409.672156 -359.959652) (xy 409.617313 -359.949522)
			(xy 409.564529 -359.931515) (xy 409.514929 -359.906014) (xy 409.469571 -359.873563) (xy 409.429422 -359.834854)
			(xy 409.395336 -359.790711) (xy 409.36804 -359.742076) (xy 409.348117 -359.689985) (xy 409.335991 -359.635548)
			(xy 409.33192 -359.579926) (xy 408.964384 -359.579926) (xy 408.964384 -360.995214) (xy 409.84373 -360.995214)
			(xy 409.847801 -360.939592) (xy 409.859927 -360.885155) (xy 409.87985 -360.833064) (xy 409.907146 -360.784429)
			(xy 409.941232 -360.740286) (xy 409.981381 -360.701577) (xy 410.026739 -360.669126) (xy 410.076339 -360.643625)
			(xy 410.129123 -360.625618) (xy 410.183966 -360.615488) (xy 410.2397 -360.613451) (xy 410.295137 -360.619551)
			(xy 410.349094 -360.633657) (xy 410.400423 -360.655469) (xy 410.448029 -360.684523) (xy 410.490897 -360.720198)
			(xy 410.528114 -360.761735) (xy 410.558887 -360.808248) (xy 410.582559 -360.858745) (xy 410.598627 -360.912152)
			(xy 410.606747 -360.967328) (xy 410.607256 -360.995214) (xy 410.606747 -361.0231) (xy 410.598627 -361.078276)
			(xy 410.582559 -361.131683) (xy 410.558887 -361.18218) (xy 410.528114 -361.228693) (xy 410.490897 -361.27023)
			(xy 410.448029 -361.305905) (xy 410.400423 -361.334959) (xy 410.349094 -361.356771) (xy 410.295137 -361.370877)
			(xy 410.2397 -361.376977) (xy 410.183966 -361.37494) (xy 410.129123 -361.36481) (xy 410.076339 -361.346803)
			(xy 410.026739 -361.321302) (xy 409.981381 -361.288851) (xy 409.941232 -361.250142) (xy 409.907146 -361.205999)
			(xy 409.87985 -361.157364) (xy 409.859927 -361.105273) (xy 409.847801 -361.050836) (xy 409.84373 -360.995214)
			(xy 408.964384 -360.995214) (xy 408.964384 -371.494304) (xy 409.529788 -372.9101) (xy 410.958792 -374.339104)
			(xy 410.96953 -374.349088) (xy 410.995333 -374.362989) (xy 411.02402 -374.368995) (xy 411.053232 -374.366611)
			(xy 411.080566 -374.356034) (xy 411.103773 -374.338134) (xy 411.120946 -374.314383) (xy 411.130671 -374.286734)
			(xy 411.132148 -374.257462) (xy 411.129226 -374.243092) (xy 411.120806 -374.2062) (xy 411.11177 -374.131068)
			(xy 411.111192 -374.093232) (xy 411.111192 -366.389666) (xy 411.110644 -366.374517) (xy 411.101769 -366.345548)
			(xy 411.084781 -366.320462) (xy 411.061177 -366.301467) (xy 411.033037 -366.290239) (xy 411.00284 -366.287766)
			(xy 410.973248 -366.294266) (xy 410.959808 -366.301274) (xy 410.938307 -366.312957) (xy 410.892949 -366.33132)
			(xy 410.845613 -366.343721) (xy 410.797077 -366.349954) (xy 410.77261 -366.350296) (xy 410.745358 -366.349833)
			(xy 410.691407 -366.342078) (xy 410.63911 -366.326723) (xy 410.58953 -366.304082) (xy 410.543677 -366.274615)
			(xy 410.502485 -366.238923) (xy 410.466791 -366.197731) (xy 410.437323 -366.151879) (xy 410.41468 -366.1023)
			(xy 410.399324 -366.050003) (xy 410.391567 -365.996052) (xy 410.391567 -365.941548) (xy 410.399324 -365.887597)
			(xy 410.41468 -365.8353) (xy 410.437323 -365.785721) (xy 410.466791 -365.739869) (xy 410.502485 -365.698677)
			(xy 410.543677 -365.662985) (xy 410.58953 -365.633518) (xy 410.63911 -365.610877) (xy 410.691407 -365.595522)
			(xy 410.745358 -365.587767) (xy 410.77261 -365.58728) (xy 410.797073 -365.587676) (xy 410.845598 -365.593932)
			(xy 410.892927 -365.606328) (xy 410.938289 -365.62466) (xy 410.959808 -365.636302) (xy 410.973273 -365.643235)
			(xy 411.002847 -365.649685) (xy 411.033013 -365.647191) (xy 411.061126 -365.63597) (xy 411.08472 -365.617008)
			(xy 411.101725 -365.591967) (xy 411.11065 -365.563044) (xy 411.111192 -365.54791) (xy 411.111192 -365.172752)
			(xy 410.554678 -363.829092) (xy 410.191458 -363.829092) (xy 410.155802 -363.828608) (xy 410.084938 -363.820617)
			(xy 410.015415 -363.804742) (xy 409.948107 -363.78118) (xy 409.88386 -363.750229) (xy 409.823484 -363.712279)
			(xy 409.767738 -363.667806) (xy 409.717322 -363.61737) (xy 409.672872 -363.561605) (xy 409.634946 -363.501214)
			(xy 409.604021 -363.436955) (xy 409.580487 -363.369637) (xy 409.564639 -363.300108) (xy 409.556678 -363.229241)
			(xy 409.556204 -363.193584) (xy 409.556758 -363.155987) (xy 409.565634 -363.081319) (xy 409.583259 -363.00822)
			(xy 409.609388 -362.937711) (xy 409.643655 -362.870779) (xy 409.685582 -362.808359) (xy 409.734582 -362.751323)
			(xy 409.789971 -362.700468) (xy 409.850974 -362.656505) (xy 409.88361 -362.637832) (xy 409.896778 -362.629962)
			(xy 409.918017 -362.607845) (xy 409.931742 -362.580424) (xy 409.936716 -362.550167) (xy 409.932493 -362.519795)
			(xy 409.919453 -362.492043) (xy 409.909518 -362.480352) (xy 409.890881 -362.459158) (xy 409.859416 -362.412308)
			(xy 409.835199 -362.361332) (xy 409.818759 -362.307344) (xy 409.810456 -362.251522) (xy 409.80995 -362.223304)
			(xy 409.810436 -362.196053) (xy 409.818192 -362.142105) (xy 409.833547 -362.08981) (xy 409.856189 -362.040233)
			(xy 409.885655 -361.994383) (xy 409.921346 -361.953192) (xy 409.962537 -361.917501) (xy 410.008387 -361.888035)
			(xy 410.057964 -361.865393) (xy 410.110259 -361.850038) (xy 410.164207 -361.842282) (xy 410.218709 -361.842282)
			(xy 410.272657 -361.850038) (xy 410.324952 -361.865393) (xy 410.374529 -361.888035) (xy 410.420379 -361.917501)
			(xy 410.46157 -361.953192) (xy 410.497261 -361.994383) (xy 410.526727 -362.040233) (xy 410.549369 -362.08981)
			(xy 410.564724 -362.142105) (xy 410.57248 -362.196053) (xy 410.572966 -362.223304) (xy 410.572286 -362.255357)
			(xy 410.561534 -362.318556) (xy 410.540381 -362.379073) (xy 410.525468 -362.407454) (xy 410.518668 -362.420926)
			(xy 410.512458 -362.450442) (xy 410.515132 -362.480485) (xy 410.526457 -362.50844) (xy 410.545448 -362.531873)
			(xy 410.57045 -362.548743) (xy 410.599288 -362.557583) (xy 410.614368 -362.558076) (xy 410.979366 -362.558076)
			(xy 411.013406 -362.55852) (xy 411.081097 -362.565797) (xy 411.147621 -362.580271) (xy 411.212216 -362.601777)
			(xy 411.274141 -362.630068) (xy 411.332684 -362.664819) (xy 411.387176 -362.705631) (xy 411.436991 -362.752037)
			(xy 411.481557 -362.803504) (xy 411.520363 -362.859442) (xy 411.552965 -362.919209) (xy 411.56636 -362.950506)
			(xy 411.816388 -363.554264) (xy 412.204154 -363.554264) (xy 412.204632 -363.526223) (xy 412.212837 -363.470745)
			(xy 412.229067 -363.417063) (xy 412.252972 -363.366331) (xy 412.284039 -363.31964) (xy 412.302452 -363.298486)
			(xy 412.312086 -363.287035) (xy 412.324872 -363.259996) (xy 412.329261 -363.23041) (xy 412.324878 -363.200824)
			(xy 412.312097 -363.173783) (xy 412.302452 -363.162342) (xy 412.284023 -363.141199) (xy 412.252931 -363.094519)
			(xy 412.229018 -363.043786) (xy 412.2128 -362.990095) (xy 412.204627 -362.934608) (xy 412.204154 -362.906564)
			(xy 412.20464 -362.879313) (xy 412.212396 -362.825365) (xy 412.227751 -362.77307) (xy 412.250393 -362.723493)
			(xy 412.279859 -362.677643) (xy 412.31555 -362.636452) (xy 412.356741 -362.600761) (xy 412.402591 -362.571295)
			(xy 412.452168 -362.548653) (xy 412.504463 -362.533298) (xy 412.558411 -362.525542) (xy 412.612913 -362.525542)
			(xy 412.666861 -362.533298) (xy 412.719156 -362.548653) (xy 412.768733 -362.571295) (xy 412.814583 -362.600761)
			(xy 412.855774 -362.636452) (xy 412.891465 -362.677643) (xy 412.920931 -362.723493) (xy 412.943573 -362.77307)
			(xy 412.958928 -362.825365) (xy 412.966684 -362.879313) (xy 412.96717 -362.906564) (xy 412.966669 -362.934604)
			(xy 412.958472 -362.990082) (xy 412.942248 -363.043765) (xy 412.918348 -363.094497) (xy 412.887284 -363.141188)
			(xy 412.868872 -363.162342) (xy 412.864368 -363.167676) (xy 420.18153 -363.167676) (xy 420.185601 -363.112054)
			(xy 420.197727 -363.057617) (xy 420.21765 -363.005526) (xy 420.244946 -362.956891) (xy 420.279032 -362.912748)
			(xy 420.319181 -362.874039) (xy 420.364539 -362.841588) (xy 420.414139 -362.816087) (xy 420.466923 -362.79808)
			(xy 420.521766 -362.78795) (xy 420.5775 -362.785913) (xy 420.632937 -362.792013) (xy 420.686894 -362.806119)
			(xy 420.738223 -362.827931) (xy 420.785829 -362.856985) (xy 420.828697 -362.89266) (xy 420.865914 -362.934197)
			(xy 420.896687 -362.98071) (xy 420.920359 -363.031207) (xy 420.936427 -363.084614) (xy 420.944547 -363.13979)
			(xy 420.945056 -363.167676) (xy 420.944547 -363.195562) (xy 420.936427 -363.250738) (xy 420.920359 -363.304145)
			(xy 420.896687 -363.354642) (xy 420.865914 -363.401155) (xy 420.828697 -363.442692) (xy 420.785829 -363.478367)
			(xy 420.738223 -363.507421) (xy 420.686894 -363.529233) (xy 420.632937 -363.543339) (xy 420.591359 -363.547914)
			(xy 421.892476 -363.547914) (xy 421.892932 -363.520543) (xy 421.900749 -363.466363) (xy 421.91624 -363.413859)
			(xy 421.939084 -363.364112) (xy 421.968813 -363.318147) (xy 421.986456 -363.297216) (xy 421.995675 -363.285877)
			(xy 422.007847 -363.259322) (xy 422.01202 -363.230411) (xy 422.007853 -363.201498) (xy 421.995686 -363.174941)
			(xy 421.986456 -363.163612) (xy 421.968802 -363.142692) (xy 421.939094 -363.096715) (xy 421.916261 -363.046965)
			(xy 421.900773 -362.994462) (xy 421.892948 -362.940284) (xy 421.892476 -362.912914) (xy 421.892962 -362.885663)
			(xy 421.900718 -362.831715) (xy 421.916073 -362.77942) (xy 421.938715 -362.729843) (xy 421.968181 -362.683993)
			(xy 422.003872 -362.642802) (xy 422.045063 -362.607111) (xy 422.090913 -362.577645) (xy 422.14049 -362.555003)
			(xy 422.192785 -362.539648) (xy 422.246733 -362.531892) (xy 422.301235 -362.531892) (xy 422.355183 -362.539648)
			(xy 422.407478 -362.555003) (xy 422.457055 -362.577645) (xy 422.502905 -362.607111) (xy 422.544096 -362.642802)
			(xy 422.579787 -362.683993) (xy 422.609253 -362.729843) (xy 422.631895 -362.77942) (xy 422.64725 -362.831715)
			(xy 422.655006 -362.885663) (xy 422.655492 -362.912914) (xy 422.655036 -362.940285) (xy 422.647216 -362.994464)
			(xy 422.631725 -363.046968) (xy 422.608881 -363.096714) (xy 422.579154 -363.142681) (xy 422.561512 -363.163612)
			(xy 422.555283 -363.171232) (xy 429.73955 -363.171232) (xy 429.743621 -363.11561) (xy 429.755747 -363.061173)
			(xy 429.77567 -363.009082) (xy 429.802966 -362.960447) (xy 429.837052 -362.916304) (xy 429.877201 -362.877595)
			(xy 429.922559 -362.845144) (xy 429.972159 -362.819643) (xy 430.024943 -362.801636) (xy 430.079786 -362.791506)
			(xy 430.13552 -362.789469) (xy 430.190957 -362.795569) (xy 430.244914 -362.809675) (xy 430.296243 -362.831487)
			(xy 430.343849 -362.860541) (xy 430.386717 -362.896216) (xy 430.423934 -362.937753) (xy 430.454707 -362.984266)
			(xy 430.478379 -363.034763) (xy 430.494447 -363.08817) (xy 430.502567 -363.143346) (xy 430.503076 -363.171232)
			(xy 430.502567 -363.199118) (xy 430.494447 -363.254294) (xy 430.478379 -363.307701) (xy 430.454707 -363.358198)
			(xy 430.423934 -363.404711) (xy 430.386717 -363.446248) (xy 430.343849 -363.481923) (xy 430.296243 -363.510977)
			(xy 430.244914 -363.532789) (xy 430.190957 -363.546895) (xy 430.13552 -363.552995) (xy 430.079786 -363.550958)
			(xy 430.024943 -363.540828) (xy 429.972159 -363.522821) (xy 429.922559 -363.49732) (xy 429.877201 -363.464869)
			(xy 429.837052 -363.42616) (xy 429.802966 -363.382017) (xy 429.77567 -363.333382) (xy 429.755747 -363.281291)
			(xy 429.743621 -363.226854) (xy 429.73955 -363.171232) (xy 422.555283 -363.171232) (xy 422.552261 -363.174929)
			(xy 422.540084 -363.20149) (xy 422.535913 -363.230411) (xy 422.54009 -363.25933) (xy 422.552272 -363.285889)
			(xy 422.561512 -363.297216) (xy 422.579127 -363.318167) (xy 422.608842 -363.364135) (xy 422.631682 -363.413878)
			(xy 422.647179 -363.466374) (xy 422.655014 -363.520546) (xy 422.655492 -363.547914) (xy 422.655006 -363.575165)
			(xy 422.64725 -363.629113) (xy 422.631895 -363.681408) (xy 422.609253 -363.730985) (xy 422.579787 -363.776835)
			(xy 422.544096 -363.818026) (xy 422.502905 -363.853717) (xy 422.457055 -363.883183) (xy 422.407478 -363.905825)
			(xy 422.355183 -363.92118) (xy 422.301235 -363.928936) (xy 422.246733 -363.928936) (xy 422.192785 -363.92118)
			(xy 422.14049 -363.905825) (xy 422.090913 -363.883183) (xy 422.045063 -363.853717) (xy 422.003872 -363.818026)
			(xy 421.968181 -363.776835) (xy 421.938715 -363.730985) (xy 421.916073 -363.681408) (xy 421.900718 -363.629113)
			(xy 421.892962 -363.575165) (xy 421.892476 -363.547914) (xy 420.591359 -363.547914) (xy 420.5775 -363.549439)
			(xy 420.521766 -363.547402) (xy 420.466923 -363.537272) (xy 420.414139 -363.519265) (xy 420.364539 -363.493764)
			(xy 420.319181 -363.461313) (xy 420.279032 -363.422604) (xy 420.244946 -363.378461) (xy 420.21765 -363.329826)
			(xy 420.197727 -363.277735) (xy 420.185601 -363.223298) (xy 420.18153 -363.167676) (xy 412.864368 -363.167676)
			(xy 412.859217 -363.173775) (xy 412.846444 -363.200822) (xy 412.842063 -363.23041) (xy 412.84645 -363.259998)
			(xy 412.859228 -363.287043) (xy 412.868872 -363.298486) (xy 412.887318 -363.319615) (xy 412.918407 -363.366299)
			(xy 412.942317 -363.417036) (xy 412.958531 -363.470729) (xy 412.966699 -363.526219) (xy 412.96717 -363.554264)
			(xy 412.966684 -363.581515) (xy 412.958928 -363.635463) (xy 412.943573 -363.687758) (xy 412.920931 -363.737335)
			(xy 412.891465 -363.783185) (xy 412.855774 -363.824376) (xy 412.814583 -363.860067) (xy 412.768733 -363.889533)
			(xy 412.719156 -363.912175) (xy 412.666861 -363.92753) (xy 412.612913 -363.935286) (xy 412.558411 -363.935286)
			(xy 412.504463 -363.92753) (xy 412.452168 -363.912175) (xy 412.402591 -363.889533) (xy 412.356741 -363.860067)
			(xy 412.31555 -363.824376) (xy 412.279859 -363.783185) (xy 412.250393 -363.737335) (xy 412.227751 -363.687758)
			(xy 412.212396 -363.635463) (xy 412.20464 -363.581515) (xy 412.204154 -363.554264) (xy 411.816388 -363.554264)
			(xy 411.980477 -363.9505) (xy 416.452737 -363.9505) (xy 416.456906 -363.894879) (xy 416.469318 -363.840501)
			(xy 416.489697 -363.788581) (xy 416.517587 -363.740278) (xy 416.552365 -363.696672) (xy 416.593254 -363.658736)
			(xy 416.639341 -363.627319) (xy 416.689595 -363.603122) (xy 416.742895 -363.586686) (xy 416.79805 -363.578378)
			(xy 416.825938 -363.577886) (xy 416.853268 -363.578397) (xy 416.907345 -363.586362) (xy 416.959677 -363.602145)
			(xy 417.009141 -363.625407) (xy 417.054673 -363.655648) (xy 417.095297 -363.692219) (xy 417.13014 -363.734335)
			(xy 417.144708 -363.757464) (xy 417.152655 -363.769672) (xy 417.174117 -363.789348) (xy 417.200265 -363.802157)
			(xy 417.228966 -363.807056) (xy 417.257882 -363.803645) (xy 417.271454 -363.798358) (xy 417.29466 -363.788857)
			(xy 417.342995 -363.775511) (xy 417.392686 -363.768787) (xy 417.417758 -363.768386) (xy 417.442827 -363.768806)
			(xy 417.49251 -363.775558) (xy 417.540845 -363.788892) (xy 417.564062 -363.798358) (xy 417.577647 -363.803579)
			(xy 417.606542 -363.806943) (xy 417.635215 -363.802036) (xy 417.661347 -363.789254) (xy 417.682824 -363.769633)
			(xy 417.690808 -363.757464) (xy 417.705377 -363.734333) (xy 417.74022 -363.692212) (xy 417.780843 -363.655633)
			(xy 417.826374 -363.625382) (xy 417.875836 -363.602106) (xy 417.928167 -363.586306) (xy 417.982246 -363.57832)
			(xy 418.03691 -363.57832) (xy 418.090989 -363.586306) (xy 418.14332 -363.602106) (xy 418.192782 -363.625382)
			(xy 418.238313 -363.655633) (xy 418.278936 -363.692212) (xy 418.313779 -363.734333) (xy 418.328348 -363.757464)
			(xy 418.336257 -363.7697) (xy 418.35773 -363.789375) (xy 418.383887 -363.802181) (xy 418.412598 -363.807072)
			(xy 418.44152 -363.803652) (xy 418.455094 -363.798358) (xy 418.478307 -363.788876) (xy 418.526638 -363.775523)
			(xy 418.576327 -363.768791) (xy 418.601398 -363.768386) (xy 418.627622 -363.768832) (xy 418.679552 -363.776174)
			(xy 418.72994 -363.790728) (xy 418.777787 -363.812206) (xy 418.822149 -363.840183) (xy 418.862149 -363.874105)
			(xy 418.896994 -363.913303) (xy 418.925997 -363.957001) (xy 418.937694 -363.980476) (xy 418.9441 -363.992667)
			(xy 418.962164 -364.013433) (xy 418.985123 -364.028613) (xy 419.011303 -364.037104) (xy 419.038801 -364.038288)
			(xy 419.065615 -364.032078) (xy 419.089792 -364.018927) (xy 419.1 -364.009686) (xy 419.121475 -363.98975)
			(xy 419.169373 -363.956) (xy 419.221866 -363.929965) (xy 419.277721 -363.912257) (xy 419.335625 -363.903292)
			(xy 419.364922 -363.902752) (xy 419.382941 -363.902975) (xy 419.418816 -363.906408) (xy 419.43655 -363.90961)
			(xy 419.451762 -363.911934) (xy 419.482317 -363.908418) (xy 419.510438 -363.895963) (xy 419.533574 -363.875698)
			(xy 419.549626 -363.849463) (xy 419.553898 -363.83468) (xy 419.561329 -363.807646) (xy 419.582954 -363.75592)
			(xy 419.611913 -363.707915) (xy 419.647584 -363.664662) (xy 419.689199 -363.627094) (xy 419.735863 -363.596019)
			(xy 419.78657 -363.572104) (xy 419.840231 -363.555866) (xy 419.89569 -363.547652) (xy 419.923722 -363.547152)
			(xy 419.950972 -363.547657) (xy 420.004917 -363.555416) (xy 420.057209 -363.570772) (xy 420.106783 -363.593412)
			(xy 420.152632 -363.622877) (xy 420.193821 -363.658566) (xy 420.229512 -363.699754) (xy 420.258979 -363.745601)
			(xy 420.281622 -363.795174) (xy 420.29698 -363.847465) (xy 420.304742 -363.90141) (xy 420.30523 -363.92866)
			(xy 420.304831 -363.9505) (xy 426.141163 -363.9505) (xy 426.145331 -363.894891) (xy 426.157739 -363.840523)
			(xy 426.178111 -363.788612) (xy 426.205992 -363.740317) (xy 426.240759 -363.696717) (xy 426.281635 -363.658784)
			(xy 426.327709 -363.627368) (xy 426.37795 -363.603168) (xy 426.431236 -363.586726) (xy 426.486377 -363.57841)
			(xy 426.51426 -363.577886) (xy 426.541591 -363.57838) (xy 426.595669 -363.586348) (xy 426.648001 -363.602134)
			(xy 426.697465 -363.625399) (xy 426.742997 -363.655643) (xy 426.78362 -363.692216) (xy 426.818463 -363.734334)
			(xy 426.83303 -363.757464) (xy 426.840956 -363.769687) (xy 426.862424 -363.789363) (xy 426.888577 -363.80217)
			(xy 426.917283 -363.807065) (xy 426.946203 -363.803649) (xy 426.959776 -363.798358) (xy 426.982991 -363.788881)
			(xy 427.031321 -363.775526) (xy 427.081009 -363.768793) (xy 427.10608 -363.768386) (xy 427.131148 -363.768832)
			(xy 427.180831 -363.775573) (xy 427.229166 -363.788896) (xy 427.252384 -363.798358) (xy 427.265997 -363.803497)
			(xy 427.294878 -363.806878) (xy 427.323541 -363.801989) (xy 427.349668 -363.789227) (xy 427.371145 -363.769625)
			(xy 427.37913 -363.757464) (xy 427.393699 -363.734333) (xy 427.428542 -363.692212) (xy 427.469165 -363.655633)
			(xy 427.514696 -363.625382) (xy 427.564158 -363.602106) (xy 427.616489 -363.586306) (xy 427.670568 -363.57832)
			(xy 427.725232 -363.57832) (xy 427.779311 -363.586306) (xy 427.831642 -363.602106) (xy 427.881104 -363.625382)
			(xy 427.926635 -363.655633) (xy 427.967258 -363.692212) (xy 428.002101 -363.734333) (xy 428.01667 -363.757464)
			(xy 428.024558 -363.769715) (xy 428.046036 -363.78939) (xy 428.0722 -363.802194) (xy 428.100915 -363.807082)
			(xy 428.129841 -363.803655) (xy 428.143416 -363.798358) (xy 428.166626 -363.788869) (xy 428.214959 -363.775518)
			(xy 428.264648 -363.76879) (xy 428.28972 -363.768386) (xy 428.316563 -363.768828) (xy 428.369694 -363.776536)
			(xy 428.421169 -363.791788) (xy 428.469922 -363.814269) (xy 428.514944 -363.843513) (xy 428.555304 -363.878916)
			(xy 428.590165 -363.919745) (xy 428.618807 -363.965153) (xy 428.640635 -364.014202) (xy 428.648368 -364.039912)
			(xy 428.653106 -364.054383) (xy 428.669606 -364.079945) (xy 428.692905 -364.099513) (xy 428.720934 -364.111348)
			(xy 428.751206 -364.1144) (xy 428.781034 -364.108398) (xy 428.794672 -364.101634) (xy 428.822813 -364.086991)
			(xy 428.882767 -364.066268) (xy 428.945327 -364.055774) (xy 428.977044 -364.055152) (xy 428.995063 -364.055372)
			(xy 429.030938 -364.058807) (xy 429.048672 -364.06201) (xy 429.063881 -364.064356) (xy 429.094438 -364.060834)
			(xy 429.122561 -364.048373) (xy 429.145697 -364.028104) (xy 429.161749 -364.001864) (xy 429.16602 -363.98708)
			(xy 429.173431 -363.960039) (xy 429.195057 -363.908313) (xy 429.224019 -363.860306) (xy 429.259692 -363.817054)
			(xy 429.30131 -363.779486) (xy 429.347976 -363.748411) (xy 429.398687 -363.724498) (xy 429.45235 -363.708261)
			(xy 429.507811 -363.700051) (xy 429.535844 -363.699552) (xy 429.563095 -363.700037) (xy 429.61704 -363.707798)
			(xy 429.669332 -363.723157) (xy 429.718907 -363.7458) (xy 429.764755 -363.775267) (xy 429.805944 -363.810959)
			(xy 429.841635 -363.852148) (xy 429.871102 -363.897996) (xy 429.893744 -363.947571) (xy 429.909103 -363.999864)
			(xy 429.916864 -364.053809) (xy 429.917352 -364.08106) (xy 429.916876 -364.108634) (xy 429.908928 -364.163207)
			(xy 429.893206 -364.216068) (xy 429.870038 -364.266114) (xy 429.839906 -364.312304) (xy 429.803439 -364.353675)
			(xy 429.782732 -364.37189) (xy 429.771872 -364.381828) (xy 429.755794 -364.406466) (xy 429.747403 -364.434664)
			(xy 429.747395 -364.464084) (xy 429.755772 -364.492287) (xy 429.771838 -364.516933) (xy 429.782732 -364.52683)
			(xy 429.803396 -364.54509) (xy 429.839856 -364.586457) (xy 429.869981 -364.632642) (xy 429.893143 -364.682683)
			(xy 429.908859 -364.735537) (xy 429.916801 -364.790103) (xy 429.916805 -364.845245) (xy 429.90887 -364.899812)
			(xy 429.893161 -364.952669) (xy 429.870006 -365.002713) (xy 429.839888 -365.048902) (xy 429.803433 -365.090273)
			(xy 429.782732 -365.10849) (xy 429.771872 -365.118428) (xy 429.755794 -365.143066) (xy 429.747403 -365.171264)
			(xy 429.747395 -365.200684) (xy 429.755772 -365.228887) (xy 429.771838 -365.253533) (xy 429.782732 -365.26343)
			(xy 429.803467 -365.281615) (xy 429.839934 -365.32299) (xy 429.870063 -365.369186) (xy 429.893224 -365.419239)
			(xy 429.908935 -365.472105) (xy 429.91687 -365.526684) (xy 429.917352 -365.55426) (xy 429.916785 -365.581508)
			(xy 429.909035 -365.635451) (xy 429.893687 -365.687741) (xy 429.871054 -365.737315) (xy 429.841596 -365.783164)
			(xy 429.805913 -365.824353) (xy 429.764731 -365.860045) (xy 429.718889 -365.889513) (xy 429.66932 -365.912158)
			(xy 429.617033 -365.927517) (xy 429.563092 -365.935279) (xy 429.535844 -365.935768) (xy 429.507989 -365.935229)
			(xy 429.452873 -365.927111) (xy 429.399522 -365.91107) (xy 429.349068 -365.887446) (xy 429.302582 -365.856741)
			(xy 429.261052 -365.819607) (xy 429.225359 -365.776832) (xy 429.196261 -365.729325) (xy 429.174375 -365.678093)
			(xy 429.166782 -365.651288) (xy 429.162503 -365.637174) (xy 429.147112 -365.612032) (xy 429.125194 -365.592318)
			(xy 429.098568 -365.579666) (xy 429.069441 -365.575125) (xy 429.054768 -365.576612) (xy 429.041752 -365.578282)
			(xy 429.015567 -365.580061) (xy 429.002444 -365.580168) (xy 428.988295 -365.58007) (xy 428.960072 -365.578039)
			(xy 428.946056 -365.576104) (xy 428.932707 -365.574531) (xy 428.906016 -365.577627) (xy 428.881063 -365.587594)
			(xy 428.859584 -365.603737) (xy 428.843071 -365.624934) (xy 428.832675 -365.64971) (xy 428.830486 -365.662972)
			(xy 428.826449 -365.690134) (xy 428.811471 -365.742967) (xy 428.789074 -365.793107) (xy 428.75972 -365.839519)
			(xy 428.724017 -365.881243) (xy 428.682701 -365.917419) (xy 428.636627 -365.947298) (xy 428.586745 -365.970264)
			(xy 428.534086 -365.985843) (xy 428.479738 -365.993712) (xy 428.45228 -365.994188) (xy 428.425027 -365.993741)
			(xy 428.371077 -365.985981) (xy 428.318781 -365.970622) (xy 428.269202 -365.947977) (xy 428.223351 -365.918507)
			(xy 428.18216 -365.882812) (xy 428.146469 -365.841617) (xy 428.117003 -365.795763) (xy 428.094364 -365.746182)
			(xy 428.07901 -365.693884) (xy 428.071256 -365.639933) (xy 428.070772 -365.61268) (xy 428.071303 -365.585108)
			(xy 428.079243 -365.530538) (xy 428.094956 -365.47768) (xy 428.118114 -365.427634) (xy 428.148235 -365.381443)
			(xy 428.18469 -365.340068) (xy 428.205392 -365.32185) (xy 428.21631 -365.311972) (xy 428.232382 -365.287316)
			(xy 428.240764 -365.259103) (xy 428.24076 -365.229671) (xy 428.232371 -365.20146) (xy 428.216292 -365.176809)
			(xy 428.205392 -365.16691) (xy 428.184681 -365.148699) (xy 428.148211 -365.10733) (xy 428.118079 -365.06114)
			(xy 428.094913 -365.011092) (xy 428.079197 -364.95823) (xy 428.071257 -364.903655) (xy 428.070772 -364.87608)
			(xy 428.071239 -364.849579) (xy 428.078582 -364.797089) (xy 428.093124 -364.746122) (xy 428.114584 -364.697659)
			(xy 428.142548 -364.652636) (xy 428.159164 -364.631986) (xy 428.168558 -364.619807) (xy 428.180349 -364.591418)
			(xy 428.183178 -364.560808) (xy 428.17679 -364.530739) (xy 428.161762 -364.503922) (xy 428.13945 -364.482778)
			(xy 428.12589 -364.475522) (xy 428.102212 -364.463399) (xy 428.058228 -364.433483) (xy 428.018943 -364.397619)
			(xy 427.985156 -364.356534) (xy 427.97095 -364.334044) (xy 427.963041 -364.321808) (xy 427.941569 -364.302132)
			(xy 427.915411 -364.289326) (xy 427.8867 -364.284434) (xy 427.857778 -364.287856) (xy 427.844204 -364.29315)
			(xy 427.820992 -364.302633) (xy 427.77266 -364.315986) (xy 427.722971 -364.322717) (xy 427.6979 -364.323122)
			(xy 427.672831 -364.32269) (xy 427.623148 -364.315945) (xy 427.574814 -364.302615) (xy 427.551596 -364.29315)
			(xy 427.537991 -364.287986) (xy 427.509106 -364.28461) (xy 427.480439 -364.289503) (xy 427.45431 -364.302271)
			(xy 427.432834 -364.32188) (xy 427.42485 -364.334044) (xy 427.410281 -364.357175) (xy 427.375438 -364.399296)
			(xy 427.334815 -364.435875) (xy 427.289284 -364.466126) (xy 427.239822 -364.489402) (xy 427.187491 -364.505202)
			(xy 427.133412 -364.513188) (xy 427.078748 -364.513188) (xy 427.024669 -364.505202) (xy 426.972338 -364.489402)
			(xy 426.922876 -364.466126) (xy 426.877345 -364.435875) (xy 426.836722 -364.399296) (xy 426.801879 -364.357175)
			(xy 426.78731 -364.334044) (xy 426.779344 -364.321849) (xy 426.757887 -364.302173) (xy 426.731745 -364.289362)
			(xy 426.703048 -364.284459) (xy 426.674135 -364.287865) (xy 426.660564 -364.29315) (xy 426.637357 -364.302646)
			(xy 426.589022 -364.315994) (xy 426.539332 -364.32272) (xy 426.51426 -364.323122) (xy 426.486377 -364.32259)
			(xy 426.431236 -364.314274) (xy 426.37795 -364.297832) (xy 426.327709 -364.273632) (xy 426.281635 -364.242216)
			(xy 426.240759 -364.204283) (xy 426.205992 -364.160683) (xy 426.178111 -364.112388) (xy 426.157739 -364.060477)
			(xy 426.145331 -364.006109) (xy 426.141163 -363.9505) (xy 420.304831 -363.9505) (xy 420.304726 -363.956233)
			(xy 420.29678 -364.010804) (xy 420.281062 -364.063662) (xy 420.257899 -364.113708) (xy 420.227774 -364.159899)
			(xy 420.191314 -364.201273) (xy 420.17061 -364.21949) (xy 420.159752 -364.229429) (xy 420.143677 -364.254067)
			(xy 420.135288 -364.282265) (xy 420.135281 -364.311684) (xy 420.143655 -364.339885) (xy 420.159718 -364.364532)
			(xy 420.17061 -364.37443) (xy 420.191275 -364.39269) (xy 420.227737 -364.434056) (xy 420.257864 -364.48024)
			(xy 420.281027 -364.530281) (xy 420.296744 -364.583136) (xy 420.304687 -364.637703) (xy 420.304691 -364.692845)
			(xy 420.296755 -364.747413) (xy 420.281046 -364.80027) (xy 420.257889 -364.850314) (xy 420.227769 -364.896503)
			(xy 420.191312 -364.937874) (xy 420.17061 -364.95609) (xy 420.159752 -364.966029) (xy 420.143677 -364.990667)
			(xy 420.136055 -365.016288) (xy 422.68343 -365.016288) (xy 422.687501 -364.960666) (xy 422.699627 -364.906229)
			(xy 422.71955 -364.854138) (xy 422.746846 -364.805503) (xy 422.780932 -364.76136) (xy 422.821081 -364.722651)
			(xy 422.866439 -364.6902) (xy 422.916039 -364.664699) (xy 422.968823 -364.646692) (xy 423.023666 -364.636562)
			(xy 423.0794 -364.634525) (xy 423.134837 -364.640625) (xy 423.188794 -364.654731) (xy 423.240123 -364.676543)
			(xy 423.287729 -364.705597) (xy 423.330597 -364.741272) (xy 423.367814 -364.782809) (xy 423.398587 -364.829322)
			(xy 423.422259 -364.879819) (xy 423.438327 -364.933226) (xy 423.446447 -364.988402) (xy 423.446956 -365.016288)
			(xy 423.446447 -365.044174) (xy 423.438327 -365.09935) (xy 423.422259 -365.152757) (xy 423.398587 -365.203254)
			(xy 423.367814 -365.249767) (xy 423.330597 -365.291304) (xy 423.287729 -365.326979) (xy 423.240123 -365.356033)
			(xy 423.188794 -365.377845) (xy 423.134837 -365.391951) (xy 423.0794 -365.398051) (xy 423.023666 -365.396014)
			(xy 422.968823 -365.385884) (xy 422.916039 -365.367877) (xy 422.866439 -365.342376) (xy 422.821081 -365.309925)
			(xy 422.780932 -365.271216) (xy 422.746846 -365.227073) (xy 422.71955 -365.178438) (xy 422.699627 -365.126347)
			(xy 422.687501 -365.07191) (xy 422.68343 -365.016288) (xy 420.136055 -365.016288) (xy 420.135288 -365.018865)
			(xy 420.135281 -365.048284) (xy 420.143655 -365.076485) (xy 420.159718 -365.101132) (xy 420.17061 -365.11103)
			(xy 420.191341 -365.12922) (xy 420.227809 -365.170593) (xy 420.257939 -365.216788) (xy 420.281101 -365.26684)
			(xy 420.296813 -365.319706) (xy 420.304748 -365.374284) (xy 420.30523 -365.40186) (xy 420.304708 -365.429111)
			(xy 420.296957 -365.483059) (xy 420.281607 -365.535354) (xy 420.258971 -365.584932) (xy 420.229509 -365.630785)
			(xy 420.193821 -365.671977) (xy 420.152634 -365.707672) (xy 420.106787 -365.737141) (xy 420.057212 -365.759785)
			(xy 420.004919 -365.775143) (xy 419.950973 -365.782903) (xy 419.923722 -365.783368) (xy 419.895866 -365.782849)
			(xy 419.840749 -365.774727) (xy 419.787398 -365.758683) (xy 419.736944 -365.735057) (xy 419.690459 -365.704349)
			(xy 419.648929 -365.667213) (xy 419.613236 -365.624437) (xy 419.584138 -365.576927) (xy 419.562253 -365.525694)
			(xy 419.55466 -365.498888) (xy 419.550403 -365.484766) (xy 419.535007 -365.459622) (xy 419.513085 -365.439908)
			(xy 419.486453 -365.427258) (xy 419.45732 -365.422722) (xy 419.442646 -365.424212) (xy 419.42963 -365.425885)
			(xy 419.403445 -365.427662) (xy 419.390322 -365.427768) (xy 419.361422 -365.427257) (xy 419.304278 -365.418587)
			(xy 419.27653 -365.410496) (xy 419.262999 -365.40669) (xy 419.234907 -365.405954) (xy 419.207676 -365.412891)
			(xy 419.183359 -365.426976) (xy 419.163794 -365.447148) (xy 419.150457 -365.471882) (xy 419.144354 -365.499313)
			(xy 419.144704 -365.513366) (xy 419.145466 -365.53648) (xy 419.14498 -365.563731) (xy 419.137224 -365.617679)
			(xy 419.121869 -365.669974) (xy 419.099227 -365.719551) (xy 419.069761 -365.765401) (xy 419.03407 -365.806592)
			(xy 418.992879 -365.842283) (xy 418.947029 -365.871749) (xy 418.897452 -365.894391) (xy 418.845157 -365.909746)
			(xy 418.791209 -365.917502) (xy 418.736707 -365.917502) (xy 418.682759 -365.909746) (xy 418.630464 -365.894391)
			(xy 418.580887 -365.871749) (xy 418.535037 -365.842283) (xy 418.493846 -365.806592) (xy 418.458155 -365.765401)
			(xy 418.428689 -365.719551) (xy 418.406047 -365.669974) (xy 418.390692 -365.617679) (xy 418.382936 -365.563731)
			(xy 418.38245 -365.53648) (xy 418.382953 -365.508907) (xy 418.390896 -365.454335) (xy 418.406612 -365.401475)
			(xy 418.429775 -365.351428) (xy 418.459902 -365.305238) (xy 418.496365 -365.263866) (xy 418.51707 -365.24565)
			(xy 418.52799 -365.235773) (xy 418.544066 -365.211118) (xy 418.552449 -365.182904) (xy 418.552446 -365.15347)
			(xy 418.544055 -365.125259) (xy 418.527972 -365.100607) (xy 418.51707 -365.09071) (xy 418.496354 -365.072504)
			(xy 418.459886 -365.031133) (xy 418.429755 -364.984942) (xy 418.40659 -364.934893) (xy 418.390874 -364.88203)
			(xy 418.382935 -364.827455) (xy 418.38245 -364.79988) (xy 418.38292 -364.77338) (xy 418.390262 -364.720892)
			(xy 418.404802 -364.669925) (xy 418.42626 -364.621464) (xy 418.439854 -364.598712) (xy 418.446578 -364.587148)
			(xy 418.454271 -364.561535) (xy 418.455055 -364.534802) (xy 418.448875 -364.508782) (xy 418.436156 -364.485257)
			(xy 418.417769 -364.465837) (xy 418.40658 -364.458504) (xy 418.381664 -364.442569) (xy 418.336742 -364.404103)
			(xy 418.298456 -364.359028) (xy 418.282628 -364.334044) (xy 418.27474 -364.321793) (xy 418.253262 -364.302117)
			(xy 418.227099 -364.289313) (xy 418.198383 -364.284425) (xy 418.169457 -364.287852) (xy 418.155882 -364.29315)
			(xy 418.132672 -364.30264) (xy 418.084339 -364.31599) (xy 418.03465 -364.322718) (xy 418.009578 -364.323122)
			(xy 417.984509 -364.322697) (xy 417.934826 -364.315949) (xy 417.886491 -364.302616) (xy 417.863274 -364.29315)
			(xy 417.849677 -364.287963) (xy 417.820788 -364.284591) (xy 417.792118 -364.28949) (xy 417.765988 -364.302264)
			(xy 417.744512 -364.321878) (xy 417.736528 -364.334044) (xy 417.721959 -364.357175) (xy 417.687116 -364.399296)
			(xy 417.646493 -364.435875) (xy 417.600962 -364.466126) (xy 417.5515 -364.489402) (xy 417.499169 -364.505202)
			(xy 417.44509 -364.513188) (xy 417.390426 -364.513188) (xy 417.336347 -364.505202) (xy 417.284016 -364.489402)
			(xy 417.234554 -364.466126) (xy 417.189023 -364.435875) (xy 417.1484 -364.399296) (xy 417.113557 -364.357175)
			(xy 417.098988 -364.334044) (xy 417.091043 -364.321834) (xy 417.06958 -364.302158) (xy 417.043432 -364.289349)
			(xy 417.014731 -364.28445) (xy 416.985814 -364.287862) (xy 416.972242 -364.29315) (xy 416.949037 -364.302652)
			(xy 416.900702 -364.315998) (xy 416.85101 -364.322721) (xy 416.825938 -364.323122) (xy 416.79805 -364.322622)
			(xy 416.742895 -364.314314) (xy 416.689595 -364.297878) (xy 416.639341 -364.273681) (xy 416.593254 -364.242264)
			(xy 416.552365 -364.204328) (xy 416.517587 -364.160722) (xy 416.489697 -364.112419) (xy 416.469318 -364.060499)
			(xy 416.456906 -364.006121) (xy 416.452737 -363.9505) (xy 411.980477 -363.9505) (xy 412.333694 -364.803436)
			(xy 412.34904 -364.842103) (xy 412.370629 -364.922445) (xy 412.381542 -365.004918) (xy 412.381724 -365.016288)
			(xy 412.995108 -365.016288) (xy 412.999179 -364.960666) (xy 413.011305 -364.906229) (xy 413.031228 -364.854138)
			(xy 413.058524 -364.805503) (xy 413.09261 -364.76136) (xy 413.132759 -364.722651) (xy 413.178117 -364.6902)
			(xy 413.227717 -364.664699) (xy 413.280501 -364.646692) (xy 413.335344 -364.636562) (xy 413.391078 -364.634525)
			(xy 413.446515 -364.640625) (xy 413.500472 -364.654731) (xy 413.551801 -364.676543) (xy 413.599407 -364.705597)
			(xy 413.642275 -364.741272) (xy 413.679492 -364.782809) (xy 413.710265 -364.829322) (xy 413.733937 -364.879819)
			(xy 413.750005 -364.933226) (xy 413.758125 -364.988402) (xy 413.758634 -365.016288) (xy 413.758125 -365.044174)
			(xy 413.750005 -365.09935) (xy 413.733937 -365.152757) (xy 413.710265 -365.203254) (xy 413.679492 -365.249767)
			(xy 413.642275 -365.291304) (xy 413.599407 -365.326979) (xy 413.551801 -365.356033) (xy 413.500472 -365.377845)
			(xy 413.446515 -365.391951) (xy 413.391078 -365.398051) (xy 413.335344 -365.396014) (xy 413.280501 -365.385884)
			(xy 413.227717 -365.367877) (xy 413.178117 -365.342376) (xy 413.132759 -365.309925) (xy 413.09261 -365.271216)
			(xy 413.058524 -365.227073) (xy 413.031228 -365.178438) (xy 413.011305 -365.126347) (xy 412.999179 -365.07191)
			(xy 412.995108 -365.016288) (xy 412.381724 -365.016288) (xy 412.382208 -365.046514) (xy 412.382208 -365.5568)
			(xy 412.382729 -365.571807) (xy 412.391431 -365.600532) (xy 412.408112 -365.625484) (xy 412.431329 -365.644504)
			(xy 412.459075 -365.65595) (xy 412.48895 -365.65883) (xy 412.518371 -365.652896) (xy 412.531814 -365.646208)
			(xy 412.55979 -365.631902) (xy 412.61926 -365.611628) (xy 412.681247 -365.601367) (xy 412.712662 -365.600742)
			(xy 412.739913 -365.601203) (xy 412.793861 -365.608954) (xy 412.846157 -365.624305) (xy 412.895735 -365.646942)
			(xy 412.941587 -365.676405) (xy 412.982779 -365.712094) (xy 413.018472 -365.753283) (xy 413.047939 -365.799132)
			(xy 413.070582 -365.848708) (xy 413.085938 -365.901002) (xy 413.093695 -365.954949) (xy 413.093695 -366.009451)
			(xy 413.085938 -366.063398) (xy 413.070582 -366.115692) (xy 413.047939 -366.165268) (xy 413.018472 -366.211117)
			(xy 412.982779 -366.252306) (xy 412.941587 -366.287995) (xy 412.895735 -366.317458) (xy 412.846157 -366.340095)
			(xy 412.793861 -366.355446) (xy 412.739913 -366.363197) (xy 412.712662 -366.363758) (xy 412.681246 -366.363139)
			(xy 412.619258 -366.35288) (xy 412.559792 -366.332596) (xy 412.531814 -366.318292) (xy 412.518351 -366.311675)
			(xy 412.488953 -366.305784) (xy 412.45911 -366.308683) (xy 412.431395 -366.320121) (xy 412.408194 -366.339115)
			(xy 412.391509 -366.364026) (xy 412.382775 -366.392709) (xy 412.382208 -366.4077) (xy 412.382208 -366.54486)
			(xy 413.801814 -366.54486) (xy 413.802256 -366.518544) (xy 413.809478 -366.466409) (xy 413.823793 -366.41576)
			(xy 413.844929 -366.367558) (xy 413.872487 -366.322717) (xy 413.905943 -366.282086) (xy 413.925004 -366.263936)
			(xy 413.935064 -366.254162) (xy 413.949759 -366.230278) (xy 413.957391 -366.203294) (xy 413.957384 -366.175252)
			(xy 413.949737 -366.148272) (xy 413.935029 -366.124396) (xy 413.925004 -366.114584) (xy 413.905918 -366.096456)
			(xy 413.87244 -366.055834) (xy 413.84487 -366.010993) (xy 413.823733 -365.962784) (xy 413.80943 -365.912125)
			(xy 413.802234 -365.85998) (xy 413.801814 -365.83366) (xy 413.8023 -365.806409) (xy 413.810056 -365.752461)
			(xy 413.825411 -365.700166) (xy 413.848053 -365.650589) (xy 413.877519 -365.604739) (xy 413.91321 -365.563548)
			(xy 413.954401 -365.527857) (xy 414.000251 -365.498391) (xy 414.049828 -365.475749) (xy 414.102123 -365.460394)
			(xy 414.156071 -365.452638) (xy 414.210573 -365.452638) (xy 414.264521 -365.460394) (xy 414.316816 -365.475749)
			(xy 414.366393 -365.498391) (xy 414.412243 -365.527857) (xy 414.453434 -365.563548) (xy 414.489125 -365.604739)
			(xy 414.518591 -365.650589) (xy 414.541233 -365.700166) (xy 414.556588 -365.752461) (xy 414.564344 -365.806409)
			(xy 414.56449 -365.81461) (xy 415.42716 -365.81461) (xy 415.427646 -365.787359) (xy 415.435402 -365.733411)
			(xy 415.450757 -365.681116) (xy 415.473399 -365.631539) (xy 415.502865 -365.585689) (xy 415.538556 -365.544498)
			(xy 415.579747 -365.508807) (xy 415.625597 -365.479341) (xy 415.675174 -365.456699) (xy 415.727469 -365.441344)
			(xy 415.781417 -365.433588) (xy 415.835919 -365.433588) (xy 415.889867 -365.441344) (xy 415.942162 -365.456699)
			(xy 415.991739 -365.479341) (xy 416.037589 -365.508807) (xy 416.07878 -365.544498) (xy 416.114471 -365.585689)
			(xy 416.143937 -365.631539) (xy 416.166579 -365.681116) (xy 416.181934 -365.733411) (xy 416.18969 -365.787359)
			(xy 416.190176 -365.81461) (xy 416.189939 -365.833277) (xy 416.18625 -365.870429) (xy 416.18281 -365.888778)
			(xy 416.180493 -365.903048) (xy 416.183021 -365.931832) (xy 416.193516 -365.958754) (xy 416.211135 -365.981656)
			(xy 416.228289 -365.994188) (xy 422.018966 -365.994188) (xy 422.023037 -365.938566) (xy 422.035163 -365.884129)
			(xy 422.055086 -365.832038) (xy 422.082382 -365.783403) (xy 422.116468 -365.73926) (xy 422.156617 -365.700551)
			(xy 422.201975 -365.6681) (xy 422.251575 -365.642599) (xy 422.304359 -365.624592) (xy 422.359202 -365.614462)
			(xy 422.414936 -365.612425) (xy 422.470373 -365.618525) (xy 422.52433 -365.632631) (xy 422.575659 -365.654443)
			(xy 422.623265 -365.683497) (xy 422.666133 -365.719172) (xy 422.70335 -365.760709) (xy 422.734123 -365.807222)
			(xy 422.757795 -365.857719) (xy 422.773863 -365.911126) (xy 422.781983 -365.966302) (xy 422.782492 -365.994188)
			(xy 422.781983 -366.022074) (xy 422.773863 -366.07725) (xy 422.757795 -366.130657) (xy 422.734123 -366.181154)
			(xy 422.70335 -366.227667) (xy 422.666133 -366.269204) (xy 422.623265 -366.304879) (xy 422.575659 -366.333933)
			(xy 422.52433 -366.355745) (xy 422.470373 -366.369851) (xy 422.414936 -366.375951) (xy 422.359202 -366.373914)
			(xy 422.304359 -366.363784) (xy 422.251575 -366.345777) (xy 422.201975 -366.320276) (xy 422.156617 -366.287825)
			(xy 422.116468 -366.249116) (xy 422.082382 -366.204973) (xy 422.055086 -366.156338) (xy 422.035163 -366.104247)
			(xy 422.023037 -366.04981) (xy 422.018966 -365.994188) (xy 416.228289 -365.994188) (xy 416.234467 -365.998701)
			(xy 416.261641 -366.008525) (xy 416.276028 -366.009936) (xy 416.304683 -366.012287) (xy 416.360849 -366.024579)
			(xy 416.414535 -366.045157) (xy 416.464527 -366.073556) (xy 416.509692 -366.109134) (xy 416.549008 -366.151085)
			(xy 416.581587 -366.198459) (xy 416.606689 -366.250185) (xy 416.623747 -366.305091) (xy 416.632375 -366.361935)
			(xy 416.632898 -366.390682) (xy 416.632412 -366.417933) (xy 416.624656 -366.471881) (xy 416.609301 -366.524176)
			(xy 416.586659 -366.573753) (xy 416.57813 -366.587024) (xy 423.490136 -366.587024) (xy 423.490687 -366.558579)
			(xy 423.499137 -366.502321) (xy 423.515853 -366.447943) (xy 423.540465 -366.396652) (xy 423.572425 -366.349589)
			(xy 423.611023 -366.307797) (xy 423.632884 -366.28959) (xy 423.644312 -366.279599) (xy 423.66133 -366.25449)
			(xy 423.670235 -366.225493) (xy 423.670243 -366.19516) (xy 423.661353 -366.166158) (xy 423.644348 -366.14104)
			(xy 423.632884 -366.131094) (xy 423.610998 -366.112915) (xy 423.572397 -366.071118) (xy 423.540436 -366.02405)
			(xy 423.515824 -365.972754) (xy 423.499109 -365.918371) (xy 423.49066 -365.862107) (xy 423.490136 -365.83366)
			(xy 423.490622 -365.806409) (xy 423.498378 -365.752461) (xy 423.513733 -365.700166) (xy 423.536375 -365.650589)
			(xy 423.565841 -365.604739) (xy 423.601532 -365.563548) (xy 423.642723 -365.527857) (xy 423.688573 -365.498391)
			(xy 423.73815 -365.475749) (xy 423.790445 -365.460394) (xy 423.844393 -365.452638) (xy 423.898895 -365.452638)
			(xy 423.952843 -365.460394) (xy 424.005138 -365.475749) (xy 424.054715 -365.498391) (xy 424.100565 -365.527857)
			(xy 424.141756 -365.563548) (xy 424.177447 -365.604739) (xy 424.206913 -365.650589) (xy 424.229555 -365.700166)
			(xy 424.24491 -365.752461) (xy 424.252666 -365.806409) (xy 424.252812 -365.81461) (xy 425.115482 -365.81461)
			(xy 425.115968 -365.787359) (xy 425.123724 -365.733411) (xy 425.139079 -365.681116) (xy 425.161721 -365.631539)
			(xy 425.191187 -365.585689) (xy 425.226878 -365.544498) (xy 425.268069 -365.508807) (xy 425.313919 -365.479341)
			(xy 425.363496 -365.456699) (xy 425.415791 -365.441344) (xy 425.469739 -365.433588) (xy 425.524241 -365.433588)
			(xy 425.578189 -365.441344) (xy 425.630484 -365.456699) (xy 425.680061 -365.479341) (xy 425.725911 -365.508807)
			(xy 425.767102 -365.544498) (xy 425.802793 -365.585689) (xy 425.832259 -365.631539) (xy 425.854901 -365.681116)
			(xy 425.870256 -365.733411) (xy 425.878012 -365.787359) (xy 425.878498 -365.81461) (xy 425.878261 -365.833277)
			(xy 425.874571 -365.870429) (xy 425.871132 -365.888778) (xy 425.868794 -365.903046) (xy 425.871323 -365.931834)
			(xy 425.88182 -365.958759) (xy 425.899444 -365.981662) (xy 425.922781 -365.998707) (xy 425.94996 -366.008527)
			(xy 425.96435 -366.009936) (xy 425.993007 -366.012269) (xy 426.049173 -366.024563) (xy 426.10286 -366.045144)
			(xy 426.152851 -366.073546) (xy 426.198016 -366.109126) (xy 426.237332 -366.151079) (xy 426.26991 -366.198455)
			(xy 426.295011 -366.250182) (xy 426.312069 -366.305089) (xy 426.320697 -366.361934) (xy 426.32122 -366.390682)
			(xy 426.320734 -366.417933) (xy 426.312978 -366.471881) (xy 426.297623 -366.524176) (xy 426.274981 -366.573753)
			(xy 426.245515 -366.619603) (xy 426.209824 -366.660794) (xy 426.168633 -366.696485) (xy 426.122783 -366.725951)
			(xy 426.073206 -366.748593) (xy 426.020911 -366.763948) (xy 425.966963 -366.771704) (xy 425.912461 -366.771704)
			(xy 425.858513 -366.763948) (xy 425.806218 -366.748593) (xy 425.756641 -366.725951) (xy 425.710791 -366.696485)
			(xy 425.6696 -366.660794) (xy 425.633909 -366.619603) (xy 425.604443 -366.573753) (xy 425.581801 -366.524176)
			(xy 425.566446 -366.471881) (xy 425.55869 -366.417933) (xy 425.558204 -366.390682) (xy 425.55844 -366.372015)
			(xy 425.56213 -366.334863) (xy 425.56557 -366.316514) (xy 425.567914 -366.302247) (xy 425.565383 -366.273459)
			(xy 425.554885 -366.246533) (xy 425.53726 -366.22363) (xy 425.513922 -366.206585) (xy 425.486742 -366.196765)
			(xy 425.472352 -366.195356) (xy 425.443694 -366.19303) (xy 425.387527 -366.180735) (xy 425.33384 -366.160154)
			(xy 425.283849 -366.131752) (xy 425.238684 -366.096171) (xy 425.199367 -366.054217) (xy 425.16679 -366.00684)
			(xy 425.141688 -365.955112) (xy 425.124631 -365.900204) (xy 425.116004 -365.843358) (xy 425.115482 -365.81461)
			(xy 424.252812 -365.81461) (xy 424.253152 -365.83366) (xy 424.252665 -365.862107) (xy 424.244202 -365.918369)
			(xy 424.227473 -365.972748) (xy 424.20285 -366.024038) (xy 424.170879 -366.0711) (xy 424.13227 -366.112889)
			(xy 424.110404 -366.131094) (xy 424.098893 -366.140996) (xy 424.081878 -366.166131) (xy 424.072984 -366.19515)
			(xy 424.072992 -366.225502) (xy 424.081901 -366.254517) (xy 424.098929 -366.279643) (xy 424.110404 -366.28959)
			(xy 424.13228 -366.307781) (xy 424.170882 -366.349575) (xy 424.202845 -366.396641) (xy 424.227458 -366.447934)
			(xy 424.244176 -366.502315) (xy 424.246446 -366.517428) (xy 424.505626 -366.517428) (xy 424.509697 -366.461806)
			(xy 424.521823 -366.407369) (xy 424.541746 -366.355278) (xy 424.569042 -366.306643) (xy 424.603128 -366.2625)
			(xy 424.643277 -366.223791) (xy 424.688635 -366.19134) (xy 424.738235 -366.165839) (xy 424.791019 -366.147832)
			(xy 424.845862 -366.137702) (xy 424.901596 -366.135665) (xy 424.957033 -366.141765) (xy 425.01099 -366.155871)
			(xy 425.062319 -366.177683) (xy 425.109925 -366.206737) (xy 425.152793 -366.242412) (xy 425.19001 -366.283949)
			(xy 425.220783 -366.330462) (xy 425.244455 -366.380959) (xy 425.260523 -366.434366) (xy 425.268643 -366.489542)
			(xy 425.269152 -366.517428) (xy 425.268643 -366.545314) (xy 425.260523 -366.60049) (xy 425.244455 -366.653897)
			(xy 425.220783 -366.704394) (xy 425.19001 -366.750907) (xy 425.152793 -366.792444) (xy 425.109925 -366.828119)
			(xy 425.062319 -366.857173) (xy 425.01099 -366.878985) (xy 424.957033 -366.893091) (xy 424.901596 -366.899191)
			(xy 424.845862 -366.897154) (xy 424.791019 -366.887024) (xy 424.738235 -366.869017) (xy 424.688635 -366.843516)
			(xy 424.643277 -366.811065) (xy 424.603128 -366.772356) (xy 424.569042 -366.728213) (xy 424.541746 -366.679578)
			(xy 424.521823 -366.627487) (xy 424.509697 -366.57305) (xy 424.505626 -366.517428) (xy 424.246446 -366.517428)
			(xy 424.252627 -366.558577) (xy 424.253152 -366.587024) (xy 424.252666 -366.614275) (xy 424.24491 -366.668223)
			(xy 424.229555 -366.720518) (xy 424.206913 -366.770095) (xy 424.177447 -366.815945) (xy 424.141756 -366.857136)
			(xy 424.100565 -366.892827) (xy 424.054715 -366.922293) (xy 424.005138 -366.944935) (xy 423.952843 -366.96029)
			(xy 423.898895 -366.968046) (xy 423.844393 -366.968046) (xy 423.790445 -366.96029) (xy 423.73815 -366.944935)
			(xy 423.688573 -366.922293) (xy 423.642723 -366.892827) (xy 423.601532 -366.857136) (xy 423.565841 -366.815945)
			(xy 423.536375 -366.770095) (xy 423.513733 -366.720518) (xy 423.498378 -366.668223) (xy 423.490622 -366.614275)
			(xy 423.490136 -366.587024) (xy 416.57813 -366.587024) (xy 416.557193 -366.619603) (xy 416.521502 -366.660794)
			(xy 416.480311 -366.696485) (xy 416.434461 -366.725951) (xy 416.384884 -366.748593) (xy 416.332589 -366.763948)
			(xy 416.278641 -366.771704) (xy 416.224139 -366.771704) (xy 416.170191 -366.763948) (xy 416.117896 -366.748593)
			(xy 416.068319 -366.725951) (xy 416.022469 -366.696485) (xy 415.981278 -366.660794) (xy 415.945587 -366.619603)
			(xy 415.916121 -366.573753) (xy 415.893479 -366.524176) (xy 415.878124 -366.471881) (xy 415.870368 -366.417933)
			(xy 415.869882 -366.390682) (xy 415.870116 -366.372015) (xy 415.873808 -366.334863) (xy 415.877248 -366.316514)
			(xy 415.879613 -366.302249) (xy 415.877082 -366.273457) (xy 415.86658 -366.246528) (xy 415.848951 -366.223623)
			(xy 415.825608 -366.206579) (xy 415.798422 -366.196762) (xy 415.78403 -366.195356) (xy 415.755378 -366.192963)
			(xy 415.699213 -366.180679) (xy 415.645527 -366.160108) (xy 415.595534 -366.131715) (xy 415.550368 -366.096142)
			(xy 415.51105 -366.054196) (xy 415.478471 -366.006825) (xy 415.453368 -365.955102) (xy 415.43631 -365.900198)
			(xy 415.427682 -365.843356) (xy 415.42716 -365.81461) (xy 414.56449 -365.81461) (xy 414.56483 -365.83366)
			(xy 414.564387 -365.859976) (xy 414.557164 -365.91211) (xy 414.542848 -365.962758) (xy 414.521711 -366.01096)
			(xy 414.494155 -366.055802) (xy 414.4607 -366.096434) (xy 414.44164 -366.114584) (xy 414.431657 -366.124432)
			(xy 414.416951 -366.148293) (xy 414.409305 -366.175259) (xy 414.409298 -366.203287) (xy 414.416929 -366.230257)
			(xy 414.431622 -366.254126) (xy 414.44164 -366.263936) (xy 414.460725 -366.282065) (xy 414.494205 -366.322685)
			(xy 414.521776 -366.367527) (xy 414.542914 -366.415735) (xy 414.557217 -366.466394) (xy 414.564259 -366.517428)
			(xy 414.817304 -366.517428) (xy 414.821375 -366.461806) (xy 414.833501 -366.407369) (xy 414.853424 -366.355278)
			(xy 414.88072 -366.306643) (xy 414.914806 -366.2625) (xy 414.954955 -366.223791) (xy 415.000313 -366.19134)
			(xy 415.049913 -366.165839) (xy 415.102697 -366.147832) (xy 415.15754 -366.137702) (xy 415.213274 -366.135665)
			(xy 415.268711 -366.141765) (xy 415.322668 -366.155871) (xy 415.373997 -366.177683) (xy 415.421603 -366.206737)
			(xy 415.464471 -366.242412) (xy 415.501688 -366.283949) (xy 415.532461 -366.330462) (xy 415.556133 -366.380959)
			(xy 415.572201 -366.434366) (xy 415.580321 -366.489542) (xy 415.58083 -366.517428) (xy 415.580321 -366.545314)
			(xy 415.572201 -366.60049) (xy 415.556133 -366.653897) (xy 415.532461 -366.704394) (xy 415.501688 -366.750907)
			(xy 415.464471 -366.792444) (xy 415.421603 -366.828119) (xy 415.373997 -366.857173) (xy 415.322668 -366.878985)
			(xy 415.268711 -366.893091) (xy 415.213274 -366.899191) (xy 415.15754 -366.897154) (xy 415.102697 -366.887024)
			(xy 415.049913 -366.869017) (xy 415.000313 -366.843516) (xy 414.954955 -366.811065) (xy 414.914806 -366.772356)
			(xy 414.88072 -366.728213) (xy 414.853424 -366.679578) (xy 414.833501 -366.627487) (xy 414.821375 -366.57305)
			(xy 414.817304 -366.517428) (xy 414.564259 -366.517428) (xy 414.564412 -366.51854) (xy 414.56483 -366.54486)
			(xy 414.564344 -366.572111) (xy 414.556588 -366.626059) (xy 414.541233 -366.678354) (xy 414.518591 -366.727931)
			(xy 414.489125 -366.773781) (xy 414.453434 -366.814972) (xy 414.412243 -366.850663) (xy 414.366393 -366.880129)
			(xy 414.316816 -366.902771) (xy 414.264521 -366.918126) (xy 414.210573 -366.925882) (xy 414.156071 -366.925882)
			(xy 414.102123 -366.918126) (xy 414.049828 -366.902771) (xy 414.000251 -366.880129) (xy 413.954401 -366.850663)
			(xy 413.91321 -366.814972) (xy 413.877519 -366.773781) (xy 413.848053 -366.727931) (xy 413.825411 -366.678354)
			(xy 413.810056 -366.626059) (xy 413.8023 -366.572111) (xy 413.801814 -366.54486) (xy 412.382208 -366.54486)
			(xy 412.382208 -372.299218) (xy 413.591022 -372.299218) (xy 413.594749 -372.24597) (xy 413.605863 -372.193761)
			(xy 413.624146 -372.143611) (xy 413.649242 -372.096499) (xy 413.68066 -372.053346) (xy 413.717787 -372.014993)
			(xy 413.738568 -371.99824) (xy 413.750345 -371.988311) (xy 413.767866 -371.962997) (xy 413.777047 -371.933611)
			(xy 413.777053 -371.902825) (xy 413.767883 -371.873436) (xy 413.75037 -371.848116) (xy 413.738568 -371.83822)
			(xy 413.716087 -371.820026) (xy 413.676354 -371.778006) (xy 413.643415 -371.730471) (xy 413.618027 -371.678511)
			(xy 413.600769 -371.623314) (xy 413.592038 -371.566146) (xy 413.591502 -371.53723) (xy 413.591985 -371.50986)
			(xy 413.599799 -371.455682) (xy 413.615284 -371.403179) (xy 413.638122 -371.353432) (xy 413.667843 -371.307464)
			(xy 413.685482 -371.286532) (xy 413.694691 -371.275184) (xy 413.706874 -371.248634) (xy 413.711053 -371.219723)
			(xy 413.706887 -371.19081) (xy 413.694716 -371.164255) (xy 413.685482 -371.152928) (xy 413.667873 -371.131971)
			(xy 413.63815 -371.086006) (xy 413.615306 -371.036264) (xy 413.599809 -370.983766) (xy 413.591979 -370.929591)
			(xy 413.591975 -370.874854) (xy 413.599799 -370.820679) (xy 413.61529 -370.768179) (xy 413.638128 -370.718434)
			(xy 413.667845 -370.672466) (xy 413.685482 -370.651532) (xy 413.694691 -370.640184) (xy 413.706874 -370.613634)
			(xy 413.711053 -370.584723) (xy 413.706887 -370.55581) (xy 413.694716 -370.529255) (xy 413.685482 -370.517928)
			(xy 413.66784 -370.496999) (xy 413.638129 -370.451025) (xy 413.615294 -370.401277) (xy 413.599804 -370.348775)
			(xy 413.591976 -370.294599) (xy 413.591502 -370.26723) (xy 413.591983 -370.239977) (xy 413.599736 -370.186027)
			(xy 413.615089 -370.133728) (xy 413.637729 -370.084148) (xy 413.667195 -370.038294) (xy 413.702887 -369.997101)
			(xy 413.744078 -369.961407) (xy 413.78993 -369.931938) (xy 413.83951 -369.909296) (xy 413.891807 -369.893941)
			(xy 413.945757 -369.886185) (xy 413.97301 -369.885722) (xy 414.000381 -369.886177) (xy 414.05456 -369.893997)
			(xy 414.107064 -369.909488) (xy 414.156811 -369.932332) (xy 414.202777 -369.962059) (xy 414.223708 -369.979702)
			(xy 414.235036 -369.988938) (xy 414.261593 -370.001114) (xy 414.29051 -370.005287) (xy 414.319427 -370.001114)
			(xy 414.345984 -369.988938) (xy 414.357312 -369.979702) (xy 414.378267 -369.962091) (xy 414.424233 -369.932375)
			(xy 414.473975 -369.909533) (xy 414.526471 -369.894036) (xy 414.580642 -369.8862) (xy 414.60801 -369.885722)
			(xy 414.636925 -369.886297) (xy 414.694094 -369.895013) (xy 414.749292 -369.912259) (xy 414.801254 -369.93764)
			(xy 414.848789 -369.970574) (xy 414.890808 -370.010307) (xy 414.909 -370.032788) (xy 414.918897 -370.044593)
			(xy 414.944221 -370.062112) (xy 414.973614 -370.071288) (xy 415.004406 -370.071288) (xy 415.033799 -370.062112)
			(xy 415.059123 -370.044593) (xy 415.06902 -370.032788) (xy 415.087197 -370.010292) (xy 415.12922 -369.970559)
			(xy 415.176758 -369.937621) (xy 415.228722 -369.912235) (xy 415.283922 -369.894981) (xy 415.341093 -369.886255)
			(xy 415.37001 -369.885722) (xy 415.397264 -369.886146) (xy 415.451218 -369.893905) (xy 415.503519 -369.909264)
			(xy 415.553101 -369.931909) (xy 415.598956 -369.961381) (xy 415.640149 -369.997079) (xy 415.675843 -370.038276)
			(xy 415.70531 -370.084134) (xy 415.72795 -370.133719) (xy 415.743304 -370.186021) (xy 415.751057 -370.239975)
			(xy 415.751518 -370.26723) (xy 415.75109 -370.294602) (xy 415.743266 -370.348783) (xy 415.727769 -370.401288)
			(xy 415.704918 -370.451034) (xy 415.675184 -370.496998) (xy 415.657538 -370.517928) (xy 415.648269 -370.529232)
			(xy 415.636091 -370.555798) (xy 415.631922 -370.584723) (xy 415.636104 -370.613646) (xy 415.648294 -370.640206)
			(xy 415.657538 -370.651532) (xy 415.67521 -370.67244) (xy 415.704936 -370.718411) (xy 415.727782 -370.768162)
			(xy 415.743277 -370.820668) (xy 415.751104 -370.87485) (xy 415.7511 -370.929595) (xy 415.743267 -370.983777)
			(xy 415.727766 -371.036281) (xy 415.704914 -371.086028) (xy 415.675182 -371.131996) (xy 415.657538 -371.152928)
			(xy 415.648269 -371.164232) (xy 415.636091 -371.190798) (xy 415.631922 -371.219723) (xy 415.636104 -371.248646)
			(xy 415.648294 -371.275206) (xy 415.657538 -371.286532) (xy 415.675165 -371.307474) (xy 415.704877 -371.353444)
			(xy 415.727715 -371.40319) (xy 415.743209 -371.455688) (xy 415.751042 -371.509862) (xy 415.751518 -371.53723)
			(xy 415.75098 -371.566147) (xy 415.74226 -371.623318) (xy 415.725008 -371.678518) (xy 415.69962 -371.730481)
			(xy 415.666678 -371.778015) (xy 415.626937 -371.820031) (xy 415.604452 -371.83822) (xy 415.592613 -371.848083)
			(xy 415.575089 -371.873414) (xy 415.565913 -371.902817) (xy 415.565919 -371.933619) (xy 415.575106 -371.963019)
			(xy 415.592639 -371.988344) (xy 415.604452 -371.99824) (xy 415.625264 -372.014958) (xy 415.662394 -372.053316)
			(xy 415.693814 -372.096475) (xy 415.718912 -372.143593) (xy 415.737196 -372.193749) (xy 415.748311 -372.245964)
			(xy 415.75026 -372.273818) (xy 416.956522 -372.273818) (xy 416.960249 -372.22057) (xy 416.971363 -372.168361)
			(xy 416.989646 -372.118211) (xy 417.014742 -372.071099) (xy 417.04616 -372.027946) (xy 417.083287 -371.989593)
			(xy 417.104068 -371.97284) (xy 417.115845 -371.962911) (xy 417.133366 -371.937597) (xy 417.142547 -371.908211)
			(xy 417.142553 -371.877425) (xy 417.133383 -371.848036) (xy 417.11587 -371.822716) (xy 417.104068 -371.81282)
			(xy 417.081587 -371.794626) (xy 417.041854 -371.752606) (xy 417.008915 -371.705071) (xy 416.983527 -371.653111)
			(xy 416.966269 -371.597914) (xy 416.957538 -371.540746) (xy 416.957002 -371.51183) (xy 416.957485 -371.48446)
			(xy 416.965299 -371.430282) (xy 416.980784 -371.377779) (xy 417.003622 -371.328032) (xy 417.033343 -371.282064)
			(xy 417.050982 -371.261132) (xy 417.060191 -371.249784) (xy 417.072374 -371.223234) (xy 417.076553 -371.194323)
			(xy 417.072387 -371.16541) (xy 417.060216 -371.138855) (xy 417.050982 -371.127528) (xy 417.033373 -371.106571)
			(xy 417.00365 -371.060606) (xy 416.980806 -371.010864) (xy 416.965309 -370.958366) (xy 416.957479 -370.904191)
			(xy 416.957475 -370.849454) (xy 416.965299 -370.795279) (xy 416.98079 -370.742779) (xy 417.003628 -370.693034)
			(xy 417.033345 -370.647066) (xy 417.050982 -370.626132) (xy 417.060191 -370.614784) (xy 417.072374 -370.588234)
			(xy 417.076553 -370.559323) (xy 417.072387 -370.53041) (xy 417.060216 -370.503855) (xy 417.050982 -370.492528)
			(xy 417.03334 -370.471599) (xy 417.003629 -370.425625) (xy 416.980794 -370.375877) (xy 416.965304 -370.323375)
			(xy 416.957476 -370.269199) (xy 416.957002 -370.24183) (xy 416.957488 -370.214579) (xy 416.965244 -370.160631)
			(xy 416.980599 -370.108336) (xy 417.003241 -370.058759) (xy 417.032707 -370.012909) (xy 417.068398 -369.971718)
			(xy 417.109589 -369.936027) (xy 417.155439 -369.906561) (xy 417.205016 -369.883919) (xy 417.257311 -369.868564)
			(xy 417.311259 -369.860808) (xy 417.365761 -369.860808) (xy 417.419709 -369.868564) (xy 417.472004 -369.883919)
			(xy 417.521581 -369.906561) (xy 417.567431 -369.936027) (xy 417.608622 -369.971718) (xy 417.644313 -370.012909)
			(xy 417.669658 -370.052346) (xy 419.301422 -370.052346) (xy 419.301948 -370.023176) (xy 419.310856 -369.96552)
			(xy 419.32844 -369.909892) (xy 419.35429 -369.857592) (xy 419.387803 -369.809837) (xy 419.428198 -369.767744)
			(xy 419.451028 -369.749578) (xy 419.461394 -369.741142) (xy 419.47769 -369.719968) (xy 419.487936 -369.695292)
			(xy 419.491432 -369.668804) (xy 419.487938 -369.642315) (xy 419.477693 -369.617638) (xy 419.4614 -369.596464)
			(xy 419.451028 -369.588034) (xy 419.428198 -369.569867) (xy 419.387796 -369.527782) (xy 419.35428 -369.480029)
			(xy 419.328434 -369.427727) (xy 419.310862 -369.372096) (xy 419.301975 -369.314436) (xy 419.301422 -369.285266)
			(xy 419.301846 -369.258013) (xy 419.309608 -369.204061) (xy 419.324969 -369.151763) (xy 419.347616 -369.102184)
			(xy 419.377089 -369.056332) (xy 419.412787 -369.015142) (xy 419.453984 -368.979451) (xy 419.49984 -368.949986)
			(xy 419.549423 -368.927347) (xy 419.601724 -368.911995) (xy 419.655676 -368.904242) (xy 419.68293 -368.903758)
			(xy 419.711846 -368.904305) (xy 419.769017 -368.913025) (xy 419.824216 -368.930276) (xy 419.876178 -368.955662)
			(xy 419.923713 -368.988602) (xy 419.96573 -369.02834) (xy 419.98392 -369.050824) (xy 419.993817 -369.062629)
			(xy 420.019141 -369.080148) (xy 420.048534 -369.089324) (xy 420.079326 -369.089324) (xy 420.108719 -369.080148)
			(xy 420.134043 -369.062629) (xy 420.14394 -369.050824) (xy 420.162115 -369.028326) (xy 420.204137 -368.988591)
			(xy 420.251675 -368.955653) (xy 420.30364 -368.930267) (xy 420.358841 -368.913014) (xy 420.416013 -368.90429)
			(xy 420.44493 -368.903758) (xy 420.473478 -368.904268) (xy 420.529933 -368.912792) (xy 420.584489 -368.929632)
			(xy 420.635927 -368.95441) (xy 420.659814 -368.970052) (xy 420.670957 -368.977114) (xy 420.69581 -368.985923)
			(xy 420.722092 -368.988052) (xy 420.748038 -368.983358) (xy 420.771908 -368.972156) (xy 420.792099 -368.955198)
			(xy 420.800022 -368.944652) (xy 420.815446 -368.923649) (xy 420.851043 -368.885595) (xy 420.891486 -368.852737)
			(xy 420.936022 -368.825686) (xy 420.983824 -368.804944) (xy 421.034003 -368.790897) (xy 421.085626 -368.783806)
			(xy 421.11168 -368.783362) (xy 421.140598 -368.783871) (xy 421.19777 -368.792599) (xy 421.25297 -368.809857)
			(xy 421.304932 -368.83525) (xy 421.352466 -368.868197) (xy 421.394481 -368.907941) (xy 421.41267 -368.930428)
			(xy 421.422567 -368.942233) (xy 421.447891 -368.959752) (xy 421.477284 -368.968928) (xy 421.508076 -368.968928)
			(xy 421.537469 -368.959752) (xy 421.562793 -368.942233) (xy 421.57269 -368.930428) (xy 421.590894 -368.907955)
			(xy 421.63291 -368.868218) (xy 421.680442 -368.835277) (xy 421.732401 -368.809886) (xy 421.787597 -368.792628)
			(xy 421.844765 -368.783898) (xy 421.87368 -368.783362) (xy 421.900929 -368.783897) (xy 421.954874 -368.79165)
			(xy 422.007166 -368.807001) (xy 422.056741 -368.829637) (xy 422.10259 -368.859099) (xy 422.143779 -368.894785)
			(xy 422.179471 -368.93597) (xy 422.208939 -368.981815) (xy 422.231582 -369.031387) (xy 422.24694 -369.083677)
			(xy 422.2547 -369.137621) (xy 422.255188 -369.16487) (xy 422.254738 -369.190913) (xy 422.247655 -369.242514)
			(xy 422.233618 -369.292672) (xy 422.212886 -369.340454) (xy 422.185846 -369.384971) (xy 422.153001 -369.425395)
			(xy 422.134284 -369.443508) (xy 422.124324 -369.453453) (xy 422.109861 -369.477587) (xy 422.102521 -369.504749)
			(xy 422.102859 -369.532884) (xy 422.110849 -369.559862) (xy 422.125888 -369.583642) (xy 422.136062 -369.593368)
			(xy 422.155664 -369.611509) (xy 422.190054 -369.652374) (xy 422.218408 -369.697637) (xy 422.240172 -369.746412)
			(xy 422.25492 -369.797746) (xy 422.262364 -369.850635) (xy 422.262808 -369.87734) (xy 422.262337 -369.905111)
			(xy 422.254279 -369.960065) (xy 422.238337 -370.01327) (xy 422.214849 -370.063601) (xy 422.184312 -370.109994)
			(xy 422.147371 -370.15147) (xy 422.12641 -370.169694) (xy 422.115726 -370.179181) (xy 422.099744 -370.202854)
			(xy 422.090956 -370.230032) (xy 422.090053 -370.258581) (xy 422.097104 -370.28626) (xy 422.111557 -370.310897)
			(xy 422.121584 -370.321078) (xy 422.139964 -370.339133) (xy 422.172132 -370.37938) (xy 422.198597 -370.423587)
			(xy 422.218876 -370.470952) (xy 422.232603 -370.520613) (xy 422.239527 -370.571668) (xy 422.239948 -370.59743)
			(xy 422.239512 -370.624801) (xy 422.231689 -370.678982) (xy 422.216194 -370.731486) (xy 422.193345 -370.781233)
			(xy 422.163613 -370.827198) (xy 422.145968 -370.848128) (xy 422.136705 -370.859435) (xy 422.124535 -370.886001)
			(xy 422.120369 -370.914923) (xy 422.124548 -370.943843) (xy 422.136729 -370.970403) (xy 422.145968 -370.981732)
			(xy 422.163638 -371.002641) (xy 422.193362 -371.048613) (xy 422.216206 -371.098363) (xy 422.2317 -371.150869)
			(xy 422.239526 -371.20505) (xy 422.239523 -371.259795) (xy 422.231691 -371.313976) (xy 422.21619 -371.36648)
			(xy 422.19334 -371.416227) (xy 422.163611 -371.462195) (xy 422.145968 -371.483128) (xy 422.136705 -371.494435)
			(xy 422.124535 -371.521001) (xy 422.120369 -371.549923) (xy 422.124548 -371.578843) (xy 422.136729 -371.605403)
			(xy 422.145968 -371.616732) (xy 422.163638 -371.637641) (xy 422.193362 -371.683613) (xy 422.216206 -371.733363)
			(xy 422.2317 -371.785869) (xy 422.235289 -371.810718) (xy 423.31665 -371.810718) (xy 423.31665 -371.726022)
			(xy 423.324701 -371.641708) (xy 423.34073 -371.558542) (xy 423.364591 -371.477275) (xy 423.39607 -371.398645)
			(xy 423.434881 -371.323364) (xy 423.480671 -371.252112) (xy 423.533027 -371.185536) (xy 423.591475 -371.124238)
			(xy 423.655485 -371.068773) (xy 423.724477 -371.019644) (xy 423.797827 -370.977295) (xy 423.87487 -370.942111)
			(xy 423.954909 -370.914409) (xy 424.037218 -370.894441) (xy 424.121053 -370.882388) (xy 424.205654 -370.878358)
			(xy 424.290255 -370.882388) (xy 424.37409 -370.894441) (xy 424.456399 -370.914409) (xy 424.536438 -370.942111)
			(xy 424.613481 -370.977295) (xy 424.686831 -371.019644) (xy 424.755823 -371.068773) (xy 424.819833 -371.124238)
			(xy 424.878281 -371.185536) (xy 424.930637 -371.252112) (xy 424.976427 -371.323364) (xy 425.015238 -371.398645)
			(xy 425.046717 -371.477275) (xy 425.070578 -371.558542) (xy 425.086607 -371.641708) (xy 425.094658 -371.726022)
			(xy 425.095162 -371.76837) (xy 425.841163 -371.76837) (xy 425.845199 -371.684923) (xy 425.857271 -371.602255)
			(xy 425.877264 -371.521138) (xy 425.904993 -371.442329) (xy 425.940199 -371.366564) (xy 425.982553 -371.294551)
			(xy 426.031659 -371.226962) (xy 426.08706 -371.164428) (xy 426.148237 -371.107533) (xy 426.21462 -371.056807)
			(xy 426.285588 -371.012726) (xy 426.36048 -370.9757) (xy 426.438596 -370.946074) (xy 426.519206 -370.924126)
			(xy 426.601558 -370.910061) (xy 426.684884 -370.904009) (xy 426.768404 -370.906028) (xy 426.85134 -370.916098)
			(xy 426.932916 -370.934126) (xy 427.012372 -370.959943) (xy 427.088965 -370.993308) (xy 427.161981 -371.033909)
			(xy 427.230737 -371.081368) (xy 427.294591 -371.135241) (xy 427.352948 -371.195026) (xy 427.405263 -371.260163)
			(xy 427.451046 -371.330046) (xy 427.489871 -371.404021) (xy 427.521376 -371.481398) (xy 427.545265 -371.561455)
			(xy 427.561316 -371.643443) (xy 427.569379 -371.726598) (xy 427.569884 -371.76837) (xy 427.569379 -371.810142)
			(xy 427.561316 -371.893297) (xy 427.545265 -371.975285) (xy 427.521376 -372.055342) (xy 427.489871 -372.132719)
			(xy 427.451046 -372.206694) (xy 427.405263 -372.276577) (xy 427.352948 -372.341714) (xy 427.294591 -372.401499)
			(xy 427.230737 -372.455372) (xy 427.161981 -372.502831) (xy 427.088965 -372.543432) (xy 427.012372 -372.576797)
			(xy 426.932916 -372.602614) (xy 426.85134 -372.620642) (xy 426.768404 -372.630712) (xy 426.684884 -372.632731)
			(xy 426.601558 -372.626679) (xy 426.519206 -372.612614) (xy 426.438596 -372.590666) (xy 426.36048 -372.56104)
			(xy 426.285588 -372.524014) (xy 426.21462 -372.479933) (xy 426.148237 -372.429207) (xy 426.08706 -372.372312)
			(xy 426.031659 -372.309778) (xy 425.982553 -372.242189) (xy 425.940199 -372.170176) (xy 425.904993 -372.094411)
			(xy 425.877264 -372.015602) (xy 425.857271 -371.934485) (xy 425.845199 -371.851817) (xy 425.841163 -371.76837)
			(xy 425.095162 -371.76837) (xy 425.094658 -371.810718) (xy 425.086607 -371.895032) (xy 425.070578 -371.978198)
			(xy 425.046717 -372.059465) (xy 425.015238 -372.138095) (xy 424.976427 -372.213376) (xy 424.930637 -372.284628)
			(xy 424.878281 -372.351204) (xy 424.819833 -372.412502) (xy 424.755823 -372.467967) (xy 424.686831 -372.517096)
			(xy 424.613481 -372.559445) (xy 424.536438 -372.594629) (xy 424.456399 -372.622331) (xy 424.37409 -372.642299)
			(xy 424.290255 -372.654352) (xy 424.205654 -372.658383) (xy 424.121053 -372.654352) (xy 424.037218 -372.642299)
			(xy 423.954909 -372.622331) (xy 423.87487 -372.594629) (xy 423.797827 -372.559445) (xy 423.724477 -372.517096)
			(xy 423.655485 -372.467967) (xy 423.591475 -372.412502) (xy 423.533027 -372.351204) (xy 423.480671 -372.284628)
			(xy 423.434881 -372.213376) (xy 423.39607 -372.138095) (xy 423.364591 -372.059465) (xy 423.34073 -371.978198)
			(xy 423.324701 -371.895032) (xy 423.31665 -371.810718) (xy 422.235289 -371.810718) (xy 422.239526 -371.84005)
			(xy 422.239523 -371.894795) (xy 422.231691 -371.948976) (xy 422.21619 -372.00148) (xy 422.19334 -372.051227)
			(xy 422.163611 -372.097195) (xy 422.145968 -372.118128) (xy 422.136705 -372.129435) (xy 422.124535 -372.156001)
			(xy 422.120369 -372.184923) (xy 422.124548 -372.213843) (xy 422.136729 -372.240403) (xy 422.145968 -372.251732)
			(xy 422.163584 -372.272683) (xy 422.1933 -372.31865) (xy 422.216141 -372.368393) (xy 422.231638 -372.420889)
			(xy 422.239471 -372.475062) (xy 422.239948 -372.50243) (xy 422.23945 -372.52968) (xy 422.231691 -372.583625)
			(xy 422.216334 -372.635917) (xy 422.193692 -372.685492) (xy 422.164226 -372.73134) (xy 422.128536 -372.772529)
			(xy 422.087348 -372.80822) (xy 422.041501 -372.837687) (xy 421.991927 -372.86033) (xy 421.939635 -372.875689)
			(xy 421.88569 -372.88345) (xy 421.85844 -372.883938) (xy 421.829523 -372.883415) (xy 421.772351 -372.87469)
			(xy 421.717151 -372.857435) (xy 421.665189 -372.832044) (xy 421.617655 -372.7991) (xy 421.575639 -372.759358)
			(xy 421.55745 -372.736872) (xy 421.547553 -372.725067) (xy 421.522229 -372.707548) (xy 421.492836 -372.698372)
			(xy 421.462044 -372.698372) (xy 421.432651 -372.707548) (xy 421.407327 -372.725067) (xy 421.39743 -372.736872)
			(xy 421.379215 -372.759335) (xy 421.337201 -372.799073) (xy 421.289671 -372.832015) (xy 421.237715 -372.857407)
			(xy 421.182521 -372.874668) (xy 421.125355 -372.883401) (xy 421.09644 -372.883938) (xy 421.069189 -372.883408)
			(xy 421.015243 -372.875657) (xy 420.962948 -372.860307) (xy 420.91337 -372.837672) (xy 420.867518 -372.808211)
			(xy 420.826326 -372.772524) (xy 420.790631 -372.731338) (xy 420.761162 -372.685492) (xy 420.738517 -372.635918)
			(xy 420.723158 -372.583626) (xy 420.715397 -372.52968) (xy 420.714932 -372.50243) (xy 420.715408 -372.47506)
			(xy 420.723222 -372.420881) (xy 420.738708 -372.368378) (xy 420.761548 -372.318631) (xy 420.791271 -372.272664)
			(xy 420.808912 -372.251732) (xy 420.818119 -372.240383) (xy 420.830298 -372.213833) (xy 420.834476 -372.184923)
			(xy 420.830311 -372.156011) (xy 420.818144 -372.129455) (xy 420.808912 -372.118128) (xy 420.791301 -372.097171)
			(xy 420.761576 -372.051207) (xy 420.73873 -372.001465) (xy 420.723232 -371.948967) (xy 420.715401 -371.894792)
			(xy 420.715398 -371.840054) (xy 420.723223 -371.785878) (xy 420.738714 -371.733378) (xy 420.761555 -371.683632)
			(xy 420.791274 -371.637665) (xy 420.808912 -371.616732) (xy 420.818119 -371.605383) (xy 420.830298 -371.578833)
			(xy 420.834476 -371.549923) (xy 420.830311 -371.521011) (xy 420.818144 -371.494455) (xy 420.808912 -371.483128)
			(xy 420.791301 -371.462171) (xy 420.761576 -371.416207) (xy 420.73873 -371.366465) (xy 420.723232 -371.313967)
			(xy 420.715401 -371.259792) (xy 420.715398 -371.205054) (xy 420.723223 -371.150878) (xy 420.738714 -371.098378)
			(xy 420.761555 -371.048632) (xy 420.791274 -371.002665) (xy 420.808912 -370.981732) (xy 420.818119 -370.970383)
			(xy 420.830298 -370.943833) (xy 420.834476 -370.914923) (xy 420.830311 -370.886011) (xy 420.818144 -370.859455)
			(xy 420.808912 -370.848128) (xy 420.791274 -370.827195) (xy 420.761562 -370.781222) (xy 420.738726 -370.731475)
			(xy 420.723234 -370.678975) (xy 420.715406 -370.624799) (xy 420.714932 -370.59743) (xy 420.71516 -370.578375)
			(xy 420.718982 -370.540457) (xy 420.722552 -370.521738) (xy 420.724834 -370.508255) (xy 420.723002 -370.480984)
			(xy 420.713998 -370.455177) (xy 420.698467 -370.432685) (xy 420.677525 -370.41512) (xy 420.652672 -370.403744)
			(xy 420.625691 -370.399371) (xy 420.598517 -370.402315) (xy 420.585646 -370.40693) (xy 420.563174 -370.415447)
			(xy 420.516636 -370.42744) (xy 420.468959 -370.433487) (xy 420.44493 -370.433854) (xy 420.416013 -370.433332)
			(xy 420.358841 -370.424606) (xy 420.303642 -370.40735) (xy 420.25168 -370.381959) (xy 420.204146 -370.349015)
			(xy 420.16213 -370.309274) (xy 420.14394 -370.286788) (xy 420.134043 -370.274983) (xy 420.108719 -370.257464)
			(xy 420.079326 -370.248288) (xy 420.048534 -370.248288) (xy 420.019141 -370.257464) (xy 419.993817 -370.274983)
			(xy 419.98392 -370.286788) (xy 419.965715 -370.309259) (xy 419.923698 -370.348996) (xy 419.876166 -370.381937)
			(xy 419.824208 -370.407327) (xy 419.769013 -370.424586) (xy 419.711845 -370.433318) (xy 419.68293 -370.433854)
			(xy 419.655682 -370.433294) (xy 419.601739 -370.425543) (xy 419.549448 -370.410194) (xy 419.499874 -370.387559)
			(xy 419.454026 -370.358101) (xy 419.412837 -370.322417) (xy 419.377145 -370.281235) (xy 419.347677 -370.235392)
			(xy 419.325033 -370.185823) (xy 419.309673 -370.133535) (xy 419.301911 -370.079594) (xy 419.301422 -370.052346)
			(xy 417.669658 -370.052346) (xy 417.673779 -370.058759) (xy 417.696421 -370.108336) (xy 417.711776 -370.160631)
			(xy 417.719532 -370.214579) (xy 417.720018 -370.24183) (xy 417.71959 -370.269202) (xy 417.711766 -370.323383)
			(xy 417.696269 -370.375888) (xy 417.673418 -370.425634) (xy 417.643684 -370.471598) (xy 417.626038 -370.492528)
			(xy 417.616769 -370.503832) (xy 417.604591 -370.530398) (xy 417.600422 -370.559323) (xy 417.604604 -370.588246)
			(xy 417.616794 -370.614806) (xy 417.626038 -370.626132) (xy 417.64371 -370.64704) (xy 417.673436 -370.693011)
			(xy 417.696282 -370.742762) (xy 417.711777 -370.795268) (xy 417.719604 -370.84945) (xy 417.7196 -370.904195)
			(xy 417.711767 -370.958377) (xy 417.696266 -371.010881) (xy 417.673414 -371.060628) (xy 417.643682 -371.106596)
			(xy 417.626038 -371.127528) (xy 417.616769 -371.138832) (xy 417.604591 -371.165398) (xy 417.600422 -371.194323)
			(xy 417.604604 -371.223246) (xy 417.616794 -371.249806) (xy 417.626038 -371.261132) (xy 417.643665 -371.282074)
			(xy 417.673377 -371.328044) (xy 417.696215 -371.37779) (xy 417.711709 -371.430288) (xy 417.719542 -371.484462)
			(xy 417.720018 -371.51183) (xy 417.71948 -371.540747) (xy 417.71076 -371.597918) (xy 417.693508 -371.653118)
			(xy 417.66812 -371.705081) (xy 417.635178 -371.752615) (xy 417.595437 -371.794631) (xy 417.572952 -371.81282)
			(xy 417.561113 -371.822683) (xy 417.543589 -371.848014) (xy 417.534413 -371.877417) (xy 417.534419 -371.908219)
			(xy 417.543606 -371.937619) (xy 417.561139 -371.962944) (xy 417.572952 -371.97284) (xy 417.593764 -371.989558)
			(xy 417.630894 -372.027916) (xy 417.662314 -372.071075) (xy 417.687412 -372.118193) (xy 417.705696 -372.168349)
			(xy 417.716811 -372.220564) (xy 417.720538 -372.273818) (xy 417.716805 -372.327073) (xy 417.705686 -372.379287)
			(xy 417.687397 -372.429441) (xy 417.662295 -372.476556) (xy 417.63087 -372.519712) (xy 417.593737 -372.558066)
			(xy 417.572952 -372.57482) (xy 417.561113 -372.584683) (xy 417.543589 -372.610014) (xy 417.534413 -372.639417)
			(xy 417.534419 -372.670219) (xy 417.543606 -372.699619) (xy 417.561139 -372.724944) (xy 417.572952 -372.73484)
			(xy 417.595465 -372.752995) (xy 417.635196 -372.795024) (xy 417.66813 -372.842567) (xy 417.693513 -372.894535)
			(xy 417.710763 -372.949738) (xy 417.719486 -373.006912) (xy 417.720018 -373.03583) (xy 417.719532 -373.063081)
			(xy 417.711776 -373.117029) (xy 417.696421 -373.169324) (xy 417.673779 -373.218901) (xy 417.644313 -373.264751)
			(xy 417.608622 -373.305942) (xy 417.567431 -373.341633) (xy 417.521581 -373.371099) (xy 417.472004 -373.393741)
			(xy 417.419709 -373.409096) (xy 417.365761 -373.416852) (xy 417.311259 -373.416852) (xy 417.257311 -373.409096)
			(xy 417.205016 -373.393741) (xy 417.155439 -373.371099) (xy 417.109589 -373.341633) (xy 417.068398 -373.305942)
			(xy 417.032707 -373.264751) (xy 417.003241 -373.218901) (xy 416.980599 -373.169324) (xy 416.965244 -373.117029)
			(xy 416.957488 -373.063081) (xy 416.957002 -373.03583) (xy 416.957541 -373.006914) (xy 416.966266 -372.949744)
			(xy 416.98352 -372.894545) (xy 417.008907 -372.842583) (xy 417.041847 -372.795049) (xy 417.081584 -372.753031)
			(xy 417.104068 -372.73484) (xy 417.115845 -372.724911) (xy 417.133366 -372.699597) (xy 417.142547 -372.670211)
			(xy 417.142553 -372.639425) (xy 417.133383 -372.610036) (xy 417.11587 -372.584716) (xy 417.104068 -372.57482)
			(xy 417.083314 -372.558031) (xy 417.046184 -372.519683) (xy 417.014761 -372.476532) (xy 416.989661 -372.429423)
			(xy 416.971373 -372.379275) (xy 416.960254 -372.327067) (xy 416.956522 -372.273818) (xy 415.75026 -372.273818)
			(xy 415.752038 -372.299218) (xy 415.748305 -372.352473) (xy 415.737186 -372.404687) (xy 415.718897 -372.454841)
			(xy 415.693795 -372.501956) (xy 415.66237 -372.545112) (xy 415.625237 -372.583466) (xy 415.604452 -372.60022)
			(xy 415.592613 -372.610083) (xy 415.575089 -372.635414) (xy 415.565913 -372.664817) (xy 415.565919 -372.695619)
			(xy 415.575106 -372.725019) (xy 415.592639 -372.750344) (xy 415.604452 -372.76024) (xy 415.626965 -372.778395)
			(xy 415.666696 -372.820424) (xy 415.69963 -372.867967) (xy 415.725013 -372.919935) (xy 415.742263 -372.975138)
			(xy 415.750986 -373.032312) (xy 415.751518 -373.06123) (xy 415.75105 -373.088482) (xy 415.74329 -373.142429)
			(xy 415.727931 -373.194724) (xy 415.705287 -373.244301) (xy 415.675819 -373.29015) (xy 415.640126 -373.33134)
			(xy 415.598934 -373.367031) (xy 415.553083 -373.396497) (xy 415.503505 -373.419138) (xy 415.45121 -373.434494)
			(xy 415.397262 -373.442252) (xy 415.37001 -373.442738) (xy 415.341092 -373.442236) (xy 415.283919 -373.433507)
			(xy 415.228719 -373.416247) (xy 415.176757 -373.390853) (xy 415.129224 -373.357905) (xy 415.087209 -373.31816)
			(xy 415.06902 -373.295672) (xy 415.059123 -373.283867) (xy 415.033799 -373.266348) (xy 415.004406 -373.257172)
			(xy 414.973614 -373.257172) (xy 414.944221 -373.266348) (xy 414.918897 -373.283867) (xy 414.909 -373.295672)
			(xy 414.890802 -373.31815) (xy 414.848784 -373.357886) (xy 414.801251 -373.390827) (xy 414.749291 -373.416217)
			(xy 414.694095 -373.433474) (xy 414.636926 -373.442203) (xy 414.60801 -373.442738) (xy 414.580639 -373.442281)
			(xy 414.526459 -373.434463) (xy 414.473955 -373.418973) (xy 414.424209 -373.396129) (xy 414.378243 -373.366401)
			(xy 414.357312 -373.348758) (xy 414.345984 -373.339522) (xy 414.319427 -373.327346) (xy 414.29051 -373.323173)
			(xy 414.261593 -373.327346) (xy 414.235036 -373.339522) (xy 414.223708 -373.348758) (xy 414.202778 -373.3664)
			(xy 414.156806 -373.396113) (xy 414.107058 -373.418949) (xy 414.054556 -373.434439) (xy 414.000379 -373.442265)
			(xy 413.97301 -373.442738) (xy 413.94576 -373.442213) (xy 413.891816 -373.434458) (xy 413.839524 -373.419106)
			(xy 413.789948 -373.396468) (xy 413.744099 -373.367006) (xy 413.70291 -373.331318) (xy 413.667218 -373.290133)
			(xy 413.637751 -373.244287) (xy 413.615108 -373.194714) (xy 413.59975 -373.142423) (xy 413.59199 -373.08848)
			(xy 413.591502 -373.06123) (xy 413.592041 -373.032314) (xy 413.600766 -372.975144) (xy 413.61802 -372.919945)
			(xy 413.643407 -372.867983) (xy 413.676347 -372.820449) (xy 413.716084 -372.778431) (xy 413.738568 -372.76024)
			(xy 413.750345 -372.750311) (xy 413.767866 -372.724997) (xy 413.777047 -372.695611) (xy 413.777053 -372.664825)
			(xy 413.767883 -372.635436) (xy 413.75037 -372.610116) (xy 413.738568 -372.60022) (xy 413.717814 -372.583431)
			(xy 413.680684 -372.545083) (xy 413.649261 -372.501932) (xy 413.624161 -372.454823) (xy 413.605873 -372.404675)
			(xy 413.594754 -372.352467) (xy 413.591022 -372.299218) (xy 412.382208 -372.299218) (xy 412.382208 -373.830088)
			(xy 412.885172 -374.333052) (xy 416.088785 -374.333052) (xy 416.088785 -374.278548) (xy 416.096542 -374.224599)
			(xy 416.111899 -374.172302) (xy 416.134542 -374.122724) (xy 416.16401 -374.076873) (xy 416.199704 -374.035683)
			(xy 416.240897 -373.999992) (xy 416.286751 -373.970527) (xy 416.336331 -373.947888) (xy 416.388628 -373.932536)
			(xy 416.442578 -373.924783) (xy 416.46983 -373.924322) (xy 416.498745 -373.924882) (xy 416.555915 -373.933601)
			(xy 416.611113 -373.95085) (xy 416.663076 -373.976234) (xy 416.710611 -374.009171) (xy 416.752629 -374.048905)
			(xy 416.77082 -374.071388) (xy 416.780717 -374.083193) (xy 416.806041 -374.100712) (xy 416.835434 -374.109888)
			(xy 416.866226 -374.109888) (xy 416.895619 -374.100712) (xy 416.920943 -374.083193) (xy 416.93084 -374.071388)
			(xy 416.949005 -374.048883) (xy 416.991031 -374.00915) (xy 417.038571 -373.976213) (xy 417.090537 -373.950829)
			(xy 417.145739 -373.933577) (xy 417.202913 -373.924854) (xy 417.23183 -373.924322) (xy 417.259082 -373.92475)
			(xy 417.313031 -373.93251) (xy 417.365326 -373.947869) (xy 417.414903 -373.970514) (xy 417.460754 -373.999983)
			(xy 417.501943 -374.035678) (xy 417.537635 -374.07687) (xy 417.5671 -374.122723) (xy 417.589741 -374.172302)
			(xy 417.605096 -374.224599) (xy 417.612852 -374.278548) (xy 417.612852 -374.333052) (xy 417.605096 -374.387001)
			(xy 417.589741 -374.439298) (xy 417.5671 -374.488877) (xy 417.537635 -374.53473) (xy 417.501943 -374.575922)
			(xy 417.460754 -374.611617) (xy 417.414903 -374.641086) (xy 417.365326 -374.663731) (xy 417.313031 -374.67909)
			(xy 417.259082 -374.68685) (xy 417.23183 -374.687338) (xy 417.202913 -374.686822) (xy 417.14574 -374.678096)
			(xy 417.09054 -374.660839) (xy 417.038578 -374.635447) (xy 416.991045 -374.602502) (xy 416.949029 -374.562759)
			(xy 416.93084 -374.540272) (xy 416.920943 -374.528467) (xy 416.895619 -374.510948) (xy 416.866226 -374.501772)
			(xy 416.835434 -374.501772) (xy 416.806041 -374.510948) (xy 416.780717 -374.528467) (xy 416.77082 -374.540272)
			(xy 416.752611 -374.56274) (xy 416.710596 -374.602478) (xy 416.663065 -374.635419) (xy 416.611107 -374.66081)
			(xy 416.555912 -374.67807) (xy 416.498745 -374.686802) (xy 416.46983 -374.687338) (xy 416.442578 -374.686817)
			(xy 416.388628 -374.679064) (xy 416.336331 -374.663712) (xy 416.286751 -374.641073) (xy 416.240897 -374.611608)
			(xy 416.199704 -374.575917) (xy 416.16401 -374.534727) (xy 416.134542 -374.488876) (xy 416.111899 -374.439298)
			(xy 416.096542 -374.387001) (xy 416.088785 -374.333052) (xy 412.885172 -374.333052) (xy 415.16554 -376.61342)
			(xy 424.691556 -376.61342) (xy 424.727216 -376.613905) (xy 424.798086 -376.621899) (xy 424.867615 -376.63778)
			(xy 424.934928 -376.661348) (xy 424.999179 -376.692306) (xy 425.059557 -376.730266) (xy 425.115305 -376.774748)
			(xy 425.140882 -376.799602) (xy 425.412662 -377.071382) (xy 429.91786 -377.071382)
		)
		(stroke
			(width 0)
			(type solid)
		)
		(fill yes)
		(layer "In2.Cu")
		(net "GND")
	)
	(gr_poly
		(pts
			(xy 161.674302 -197.83679) (xy 161.695679 -197.828504) (xy 161.740022 -197.816857) (xy 161.78549 -197.810979)
			(xy 161.808414 -197.810628) (xy 161.83134 -197.810962) (xy 161.876815 -197.816817) (xy 161.921158 -197.828477)
			(xy 161.942526 -197.83679) (xy 161.95167 -197.8406) (xy 163.874958 -197.8406) (xy 163.884102 -197.83679)
			(xy 163.905479 -197.828504) (xy 163.949822 -197.816857) (xy 163.99529 -197.810979) (xy 164.018214 -197.810628)
			(xy 164.04114 -197.810962) (xy 164.086615 -197.816817) (xy 164.130958 -197.828477) (xy 164.152326 -197.83679)
			(xy 164.16147 -197.8406) (xy 169.208958 -197.8406) (xy 169.218102 -197.83679) (xy 169.239479 -197.828504)
			(xy 169.283822 -197.816857) (xy 169.32929 -197.810979) (xy 169.352214 -197.810628) (xy 169.37514 -197.810962)
			(xy 169.420615 -197.816817) (xy 169.464958 -197.828477) (xy 169.486326 -197.83679) (xy 169.49547 -197.8406)
			(xy 171.418758 -197.8406) (xy 171.427902 -197.83679) (xy 171.449279 -197.828504) (xy 171.493622 -197.816857)
			(xy 171.53909 -197.810979) (xy 171.562014 -197.810628) (xy 171.58494 -197.810962) (xy 171.630415 -197.816817)
			(xy 171.674758 -197.828477) (xy 171.696126 -197.83679) (xy 171.70527 -197.8406) (xy 172.65269 -197.8406)
			(xy 172.661834 -197.83679) (xy 172.683211 -197.828506) (xy 172.727554 -197.816863) (xy 172.773023 -197.810989)
			(xy 172.795946 -197.810628) (xy 172.818871 -197.810964) (xy 172.864345 -197.816823) (xy 172.908686 -197.828487)
			(xy 172.930058 -197.83679) (xy 172.939202 -197.8406) (xy 176.752758 -197.8406) (xy 176.761902 -197.83679)
			(xy 176.783279 -197.828504) (xy 176.827622 -197.816857) (xy 176.87309 -197.810979) (xy 176.896014 -197.810628)
			(xy 176.91894 -197.810962) (xy 176.964415 -197.816817) (xy 177.008758 -197.828477) (xy 177.030126 -197.83679)
			(xy 177.03927 -197.8406) (xy 178.962558 -197.8406) (xy 178.971702 -197.83679) (xy 178.993079 -197.828504)
			(xy 179.037422 -197.816857) (xy 179.08289 -197.810979) (xy 179.105814 -197.810628) (xy 179.12874 -197.810962)
			(xy 179.174215 -197.816817) (xy 179.218558 -197.828477) (xy 179.239926 -197.83679) (xy 179.24907 -197.8406)
			(xy 184.296558 -197.8406) (xy 184.305702 -197.83679) (xy 184.327079 -197.828504) (xy 184.371422 -197.816857)
			(xy 184.41689 -197.810979) (xy 184.439814 -197.810628) (xy 184.46274 -197.810962) (xy 184.508215 -197.816817)
			(xy 184.552558 -197.828477) (xy 184.573926 -197.83679) (xy 184.58307 -197.8406) (xy 186.506358 -197.8406)
			(xy 186.515502 -197.83679) (xy 186.536879 -197.828504) (xy 186.581222 -197.816857) (xy 186.62669 -197.810979)
			(xy 186.649614 -197.810628) (xy 186.67254 -197.810962) (xy 186.718015 -197.816817) (xy 186.762358 -197.828477)
			(xy 186.783726 -197.83679) (xy 186.79287 -197.8406) (xy 187.74029 -197.8406) (xy 187.749434 -197.83679)
			(xy 187.770811 -197.828506) (xy 187.815154 -197.816863) (xy 187.860623 -197.810989) (xy 187.883546 -197.810628)
			(xy 187.906471 -197.810964) (xy 187.951945 -197.816823) (xy 187.996286 -197.828487) (xy 188.017658 -197.83679)
			(xy 188.026802 -197.8406) (xy 191.840358 -197.8406) (xy 191.849502 -197.83679) (xy 191.870879 -197.828504)
			(xy 191.915222 -197.816857) (xy 191.96069 -197.810979) (xy 191.983614 -197.810628) (xy 192.00654 -197.810962)
			(xy 192.052015 -197.816817) (xy 192.096358 -197.828477) (xy 192.117726 -197.83679) (xy 192.12687 -197.8406)
			(xy 194.050158 -197.8406) (xy 194.059302 -197.83679) (xy 194.080679 -197.828504) (xy 194.125022 -197.816857)
			(xy 194.17049 -197.810979) (xy 194.193414 -197.810628) (xy 194.21634 -197.810962) (xy 194.261815 -197.816817)
			(xy 194.306158 -197.828477) (xy 194.327526 -197.83679) (xy 194.33667 -197.8406) (xy 199.384158 -197.8406)
			(xy 199.393302 -197.83679) (xy 199.414679 -197.828504) (xy 199.459022 -197.816857) (xy 199.50449 -197.810979)
			(xy 199.527414 -197.810628) (xy 199.55034 -197.810962) (xy 199.595815 -197.816817) (xy 199.640158 -197.828477)
			(xy 199.661526 -197.83679) (xy 199.67067 -197.8406) (xy 201.593958 -197.8406) (xy 201.603102 -197.83679)
			(xy 201.624479 -197.828504) (xy 201.668822 -197.816857) (xy 201.71429 -197.810979) (xy 201.737214 -197.810628)
			(xy 201.76014 -197.810962) (xy 201.805615 -197.816817) (xy 201.849958 -197.828477) (xy 201.871326 -197.83679)
			(xy 201.88047 -197.8406) (xy 202.82789 -197.8406) (xy 202.837034 -197.83679) (xy 202.858411 -197.828506)
			(xy 202.902754 -197.816863) (xy 202.948223 -197.810989) (xy 202.971146 -197.810628) (xy 202.994071 -197.810964)
			(xy 203.039545 -197.816823) (xy 203.083886 -197.828487) (xy 203.105258 -197.83679) (xy 203.114402 -197.8406)
			(xy 206.927958 -197.8406) (xy 206.937102 -197.83679) (xy 206.958479 -197.828504) (xy 207.002822 -197.816857)
			(xy 207.04829 -197.810979) (xy 207.071214 -197.810628) (xy 207.09414 -197.810962) (xy 207.139615 -197.816817)
			(xy 207.183958 -197.828477) (xy 207.205326 -197.83679) (xy 207.21447 -197.8406) (xy 209.137758 -197.8406)
			(xy 209.146902 -197.83679) (xy 209.168279 -197.828504) (xy 209.212622 -197.816857) (xy 209.25809 -197.810979)
			(xy 209.281014 -197.810628) (xy 209.30394 -197.810962) (xy 209.349415 -197.816817) (xy 209.393758 -197.828477)
			(xy 209.415126 -197.83679) (xy 209.42427 -197.8406) (xy 213.7664 -197.8406) (xy 214.5284 -197.0786)
			(xy 214.5284 -196.813932) (xy 214.494872 -196.801994) (xy 214.469318 -196.79231) (xy 214.421292 -196.766237)
			(xy 214.377813 -196.733135) (xy 214.3399 -196.693779) (xy 214.308443 -196.649095) (xy 214.28418 -196.60013)
			(xy 214.267681 -196.548033) (xy 214.259334 -196.494028) (xy 214.259333 -196.439381) (xy 214.267679 -196.385376)
			(xy 214.284177 -196.333279) (xy 214.308438 -196.284313) (xy 214.339893 -196.239628) (xy 214.377806 -196.200272)
			(xy 214.421284 -196.167168) (xy 214.469309 -196.141094) (xy 214.494872 -196.131434) (xy 214.5284 -196.119496)
			(xy 214.5284 -195.11391) (xy 214.494872 -195.101972) (xy 214.468316 -195.091868) (xy 214.41855 -195.064456)
			(xy 214.373764 -195.029495) (xy 214.335092 -194.987871) (xy 214.31885 -194.964558) (xy 214.31035 -194.952802)
			(xy 214.288085 -194.934225) (xy 214.2615 -194.922649) (xy 214.232733 -194.919004) (xy 214.2041 -194.923585)
			(xy 214.177906 -194.936022) (xy 214.156259 -194.955315) (xy 214.148162 -194.967352) (xy 214.133126 -194.99058)
			(xy 214.097415 -195.032844) (xy 214.055978 -195.06951) (xy 214.009681 -195.099812) (xy 213.959496 -195.123113)
			(xy 213.906474 -195.138927) (xy 213.851723 -195.146922) (xy 213.824058 -195.147438) (xy 213.796524 -195.146952)
			(xy 213.742027 -195.139031) (xy 213.689235 -195.12336) (xy 213.639244 -195.100263) (xy 213.593091 -195.070221)
			(xy 213.551736 -195.033858) (xy 213.516036 -194.991928) (xy 213.50097 -194.968876) (xy 213.492669 -194.956597)
			(xy 213.470381 -194.937078) (xy 213.443426 -194.924783) (xy 213.414075 -194.920749) (xy 213.384803 -194.925315)
			(xy 213.358075 -194.938096) (xy 213.336144 -194.958015) (xy 213.327996 -194.9704) (xy 213.313087 -194.994164)
			(xy 213.277399 -195.037448) (xy 213.235762 -195.075045) (xy 213.189072 -195.106145) (xy 213.138335 -195.130079)
			(xy 213.084641 -195.146332) (xy 213.029148 -195.154554) (xy 213.001098 -195.155058) (xy 212.973843 -195.154572)
			(xy 212.919889 -195.146814) (xy 212.867587 -195.131457) (xy 212.818004 -195.108813) (xy 212.772148 -195.079342)
			(xy 212.730952 -195.043646) (xy 212.695256 -195.002451) (xy 212.665786 -194.956594) (xy 212.643142 -194.907011)
			(xy 212.627785 -194.854709) (xy 212.620028 -194.800755) (xy 212.620028 -194.746245) (xy 212.627785 -194.692291)
			(xy 212.643142 -194.639989) (xy 212.665786 -194.590406) (xy 212.695256 -194.544549) (xy 212.730952 -194.503354)
			(xy 212.772148 -194.467658) (xy 212.818004 -194.438187) (xy 212.867587 -194.415543) (xy 212.919889 -194.400186)
			(xy 212.973843 -194.392428) (xy 213.001098 -194.392042) (xy 213.028634 -194.392525) (xy 213.083135 -194.40044)
			(xy 213.135932 -194.416106) (xy 213.185929 -194.439199) (xy 213.232088 -194.469237) (xy 213.27345 -194.505599)
			(xy 213.309156 -194.547527) (xy 213.324186 -194.570604) (xy 213.332486 -194.582892) (xy 213.354777 -194.602427)
			(xy 213.38174 -194.614735) (xy 213.411102 -194.618778) (xy 213.440388 -194.614217) (xy 213.467129 -194.601434)
			(xy 213.489071 -194.581508) (xy 213.49716 -194.56908) (xy 213.512069 -194.545315) (xy 213.547757 -194.502028)
			(xy 213.589393 -194.464429) (xy 213.636083 -194.433325) (xy 213.68682 -194.409387) (xy 213.740513 -194.393129)
			(xy 213.796008 -194.384901) (xy 213.824058 -194.384422) (xy 213.851775 -194.384923) (xy 213.906624 -194.392957)
			(xy 213.959732 -194.408847) (xy 214.00998 -194.432259) (xy 214.056309 -194.462698) (xy 214.097744 -194.499524)
			(xy 214.13341 -194.541961) (xy 214.148416 -194.56527) (xy 214.1565 -194.577363) (xy 214.178133 -194.596787)
			(xy 214.204361 -194.609332) (xy 214.23306 -194.613985) (xy 214.261908 -194.610368) (xy 214.288571 -194.598775)
			(xy 214.31089 -194.580143) (xy 214.319358 -194.568318) (xy 214.335576 -194.545101) (xy 214.374152 -194.503642)
			(xy 214.418802 -194.468809) (xy 214.468403 -194.441482) (xy 214.494872 -194.431412) (xy 214.5284 -194.419474)
			(xy 214.5284 -194.190874) (xy 214.49411 -194.178936) (xy 214.468806 -194.169671) (xy 214.420887 -194.145029)
			(xy 214.376915 -194.113884) (xy 214.337765 -194.076859) (xy 214.304219 -194.034691) (xy 214.276944 -193.988219)
			(xy 214.256484 -193.93837) (xy 214.243246 -193.886137) (xy 214.239856 -193.859404) (xy 214.237824 -193.841624)
			(xy 213.179406 -192.783206) (xy 213.169204 -192.773613) (xy 213.14479 -192.759917) (xy 213.117574 -192.753364)
			(xy 213.089601 -192.754447) (xy 213.062973 -192.763084) (xy 213.03969 -192.778625) (xy 213.021501 -192.799905)
			(xy 213.009773 -192.825323) (xy 213.007194 -192.839086) (xy 213.002547 -192.865698) (xy 212.986735 -192.917353)
			(xy 212.963795 -192.966261) (xy 212.934184 -193.011444) (xy 212.898496 -193.051998) (xy 212.857444 -193.087112)
			(xy 212.811849 -193.116083) (xy 212.762623 -193.138333) (xy 212.71075 -193.153416) (xy 212.657269 -193.161031)
			(xy 212.630258 -193.161412) (xy 212.603009 -193.160923) (xy 212.549065 -193.153162) (xy 212.496775 -193.137803)
			(xy 212.447203 -193.11516) (xy 212.401358 -193.085692) (xy 212.360172 -193.050001) (xy 212.324485 -193.008812)
			(xy 212.295022 -192.962964) (xy 212.272383 -192.913389) (xy 212.25703 -192.861098) (xy 212.249274 -192.807153)
			(xy 212.24875 -192.779904) (xy 212.249218 -192.752896) (xy 212.256833 -192.69942) (xy 212.271913 -192.647551)
			(xy 212.294155 -192.598327) (xy 212.323116 -192.552731) (xy 212.358216 -192.511674) (xy 212.398755 -192.475976)
			(xy 212.443922 -192.446351) (xy 212.492815 -192.42339) (xy 212.544457 -192.407552) (xy 212.571076 -192.402968)
			(xy 212.584813 -192.400323) (xy 212.610193 -192.388579) (xy 212.631437 -192.370394) (xy 212.646956 -192.347129)
			(xy 212.655584 -192.320528) (xy 212.656678 -192.292585) (xy 212.650153 -192.265391) (xy 212.6365 -192.240985)
			(xy 212.626956 -192.230756) (xy 212.598 -192.2018) (xy 209.36585 -192.2018) (xy 209.350185 -192.20238)
			(xy 209.320327 -192.211874) (xy 209.294741 -192.229956) (xy 209.275825 -192.254932) (xy 209.265353 -192.284461)
			(xy 209.26425 -192.300098) (xy 209.262866 -192.328034) (xy 209.252934 -192.383077) (xy 209.235071 -192.436079)
			(xy 209.209659 -192.485904) (xy 209.177243 -192.531484) (xy 209.138519 -192.571843) (xy 209.094316 -192.606113)
			(xy 209.045582 -192.633561) (xy 208.993363 -192.653598) (xy 208.938778 -192.665795) (xy 208.882996 -192.66989)
			(xy 208.827214 -192.665795) (xy 208.772629 -192.653598) (xy 208.72041 -192.633561) (xy 208.671676 -192.606113)
			(xy 208.627473 -192.571843) (xy 208.588749 -192.531484) (xy 208.556333 -192.485904) (xy 208.530921 -192.436079)
			(xy 208.513058 -192.383077) (xy 208.503126 -192.328034) (xy 208.501742 -192.300098) (xy 208.500658 -192.284455)
			(xy 208.490199 -192.254913) (xy 208.471281 -192.229928) (xy 208.445684 -192.211847) (xy 208.415812 -192.20237)
			(xy 208.400142 -192.2018) (xy 204.9526 -192.2018) (xy 203.41717 -193.73723) (xy 203.434172 -193.761782)
			(xy 203.461142 -193.815062) (xy 203.479477 -193.871895) (xy 203.488731 -193.930891) (xy 203.489306 -193.96075)
			(xy 203.48882 -193.988001) (xy 203.483645 -194.023996) (xy 206.570072 -194.023996) (xy 206.570572 -193.995412)
			(xy 206.579108 -193.938886) (xy 206.595988 -193.884268) (xy 206.620835 -193.832782) (xy 206.65309 -193.785584)
			(xy 206.692031 -193.743731) (xy 206.71409 -193.725546) (xy 206.725587 -193.71577) (xy 206.742667 -193.690904)
			(xy 206.751744 -193.662135) (xy 206.752028 -193.631969) (xy 206.743494 -193.603034) (xy 206.726885 -193.577851)
			(xy 206.715614 -193.567812) (xy 206.694419 -193.549605) (xy 206.657081 -193.508039) (xy 206.626204 -193.461472)
			(xy 206.60245 -193.410899) (xy 206.586327 -193.357402) (xy 206.578179 -193.302125) (xy 206.577692 -193.274188)
			(xy 206.578178 -193.246937) (xy 206.585934 -193.192989) (xy 206.601289 -193.140694) (xy 206.623931 -193.091117)
			(xy 206.653397 -193.045267) (xy 206.689088 -193.004076) (xy 206.730279 -192.968385) (xy 206.776129 -192.938919)
			(xy 206.825706 -192.916277) (xy 206.878001 -192.900922) (xy 206.931949 -192.893166) (xy 206.986451 -192.893166)
			(xy 207.040399 -192.900922) (xy 207.092694 -192.916277) (xy 207.142271 -192.938919) (xy 207.188121 -192.968385)
			(xy 207.229312 -193.004076) (xy 207.265003 -193.045267) (xy 207.294469 -193.091117) (xy 207.317111 -193.140694)
			(xy 207.332466 -193.192989) (xy 207.340222 -193.246937) (xy 207.340708 -193.274188) (xy 207.340167 -193.30277)
			(xy 207.331635 -193.359293) (xy 207.314761 -193.413909) (xy 207.289922 -193.465394) (xy 207.257676 -193.512594)
			(xy 207.218744 -193.554451) (xy 207.19669 -193.572638) (xy 207.185211 -193.582432) (xy 207.168134 -193.607294)
			(xy 207.159056 -193.636058) (xy 207.159002 -193.641726) (xy 208.51825 -193.641726) (xy 208.522321 -193.586104)
			(xy 208.534447 -193.531667) (xy 208.55437 -193.479576) (xy 208.581666 -193.430941) (xy 208.615752 -193.386798)
			(xy 208.655901 -193.348089) (xy 208.701259 -193.315638) (xy 208.750859 -193.290137) (xy 208.803643 -193.27213)
			(xy 208.858486 -193.262) (xy 208.91422 -193.259963) (xy 208.969657 -193.266063) (xy 209.023614 -193.280169)
			(xy 209.074943 -193.301981) (xy 209.122549 -193.331035) (xy 209.165417 -193.36671) (xy 209.202634 -193.408247)
			(xy 209.233407 -193.45476) (xy 209.257079 -193.505257) (xy 209.273147 -193.558664) (xy 209.281267 -193.61384)
			(xy 209.281776 -193.641726) (xy 209.281267 -193.669612) (xy 209.280661 -193.67373) (xy 212.17712 -193.67373)
			(xy 212.181191 -193.618108) (xy 212.193317 -193.563671) (xy 212.21324 -193.51158) (xy 212.240536 -193.462945)
			(xy 212.274622 -193.418802) (xy 212.314771 -193.380093) (xy 212.360129 -193.347642) (xy 212.409729 -193.322141)
			(xy 212.462513 -193.304134) (xy 212.517356 -193.294004) (xy 212.57309 -193.291967) (xy 212.628527 -193.298067)
			(xy 212.682484 -193.312173) (xy 212.733813 -193.333985) (xy 212.781419 -193.363039) (xy 212.824287 -193.398714)
			(xy 212.861504 -193.440251) (xy 212.892277 -193.486764) (xy 212.915949 -193.537261) (xy 212.932017 -193.590668)
			(xy 212.940137 -193.645844) (xy 212.940646 -193.67373) (xy 212.940137 -193.701616) (xy 212.932017 -193.756792)
			(xy 212.915949 -193.810199) (xy 212.892277 -193.860696) (xy 212.861504 -193.907209) (xy 212.824287 -193.948746)
			(xy 212.781419 -193.984421) (xy 212.733813 -194.013475) (xy 212.682484 -194.035287) (xy 212.628527 -194.049393)
			(xy 212.57309 -194.055493) (xy 212.517356 -194.053456) (xy 212.462513 -194.043326) (xy 212.409729 -194.025319)
			(xy 212.360129 -193.999818) (xy 212.314771 -193.967367) (xy 212.274622 -193.928658) (xy 212.240536 -193.884515)
			(xy 212.21324 -193.83588) (xy 212.193317 -193.783789) (xy 212.181191 -193.729352) (xy 212.17712 -193.67373)
			(xy 209.280661 -193.67373) (xy 209.273147 -193.724788) (xy 209.257079 -193.778195) (xy 209.233407 -193.828692)
			(xy 209.202634 -193.875205) (xy 209.165417 -193.916742) (xy 209.122549 -193.952417) (xy 209.074943 -193.981471)
			(xy 209.023614 -194.003283) (xy 208.969657 -194.017389) (xy 208.91422 -194.023489) (xy 208.858486 -194.021452)
			(xy 208.803643 -194.011322) (xy 208.750859 -193.993315) (xy 208.701259 -193.967814) (xy 208.655901 -193.935363)
			(xy 208.615752 -193.896654) (xy 208.581666 -193.852511) (xy 208.55437 -193.803876) (xy 208.534447 -193.751785)
			(xy 208.522321 -193.697348) (xy 208.51825 -193.641726) (xy 207.159002 -193.641726) (xy 207.158769 -193.666219)
			(xy 207.167298 -193.69515) (xy 207.183899 -193.720332) (xy 207.195166 -193.730372) (xy 207.216349 -193.748592)
			(xy 207.253689 -193.790155) (xy 207.284568 -193.836719) (xy 207.308324 -193.88729) (xy 207.32445 -193.940785)
			(xy 207.3326 -193.99606) (xy 207.333088 -194.023996) (xy 207.332508 -194.054047) (xy 207.323073 -194.113404)
			(xy 207.304452 -194.170548) (xy 207.277106 -194.224069) (xy 207.241709 -194.272641) (xy 207.22082 -194.294252)
			(xy 207.211568 -194.304034) (xy 207.198172 -194.327383) (xy 207.19134 -194.35342) (xy 207.191547 -194.380338)
			(xy 207.198779 -194.406267) (xy 207.212532 -194.429407) (xy 207.231853 -194.44815) (xy 207.243426 -194.455034)
			(xy 207.266918 -194.468608) (xy 207.309881 -194.501739) (xy 207.34732 -194.541005) (xy 207.378368 -194.585497)
			(xy 207.402305 -194.634184) (xy 207.418579 -194.68594) (xy 207.426812 -194.739565) (xy 207.427322 -194.766692)
			(xy 207.426824 -194.793341) (xy 208.925404 -194.793341) (xy 208.925404 -194.740043) (xy 208.933347 -194.687339)
			(xy 208.949057 -194.636409) (xy 208.972183 -194.588388) (xy 209.002207 -194.544351) (xy 209.038459 -194.50528)
			(xy 209.08013 -194.472049) (xy 209.126288 -194.4454) (xy 209.175902 -194.425928) (xy 209.227864 -194.414068)
			(xy 209.281014 -194.410085) (xy 209.334164 -194.414068) (xy 209.386126 -194.425928) (xy 209.43574 -194.4454)
			(xy 209.481898 -194.472049) (xy 209.523569 -194.50528) (xy 209.559821 -194.544351) (xy 209.589845 -194.588388)
			(xy 209.612971 -194.636409) (xy 209.628681 -194.687339) (xy 209.636624 -194.740043) (xy 209.637122 -194.766692)
			(xy 209.636624 -194.793341) (xy 210.133936 -194.793341) (xy 210.133936 -194.740043) (xy 210.141879 -194.687339)
			(xy 210.157589 -194.636409) (xy 210.180715 -194.588388) (xy 210.210739 -194.544351) (xy 210.246991 -194.50528)
			(xy 210.288662 -194.472049) (xy 210.33482 -194.4454) (xy 210.384434 -194.425928) (xy 210.436396 -194.414068)
			(xy 210.489546 -194.410085) (xy 210.542696 -194.414068) (xy 210.594658 -194.425928) (xy 210.644272 -194.4454)
			(xy 210.69043 -194.472049) (xy 210.732101 -194.50528) (xy 210.768353 -194.544351) (xy 210.798377 -194.588388)
			(xy 210.821503 -194.636409) (xy 210.837213 -194.687339) (xy 210.845156 -194.740043) (xy 210.845654 -194.766692)
			(xy 210.845156 -194.793341) (xy 210.837213 -194.846045) (xy 210.821503 -194.896975) (xy 210.798377 -194.944996)
			(xy 210.768353 -194.989033) (xy 210.732101 -195.028104) (xy 210.69043 -195.061335) (xy 210.644272 -195.087984)
			(xy 210.594658 -195.107456) (xy 210.542696 -195.119316) (xy 210.489546 -195.1233) (xy 210.436396 -195.119316)
			(xy 210.384434 -195.107456) (xy 210.33482 -195.087984) (xy 210.288662 -195.061335) (xy 210.246991 -195.028104)
			(xy 210.210739 -194.989033) (xy 210.180715 -194.944996) (xy 210.157589 -194.896975) (xy 210.141879 -194.846045)
			(xy 210.133936 -194.793341) (xy 209.636624 -194.793341) (xy 209.628681 -194.846045) (xy 209.612971 -194.896975)
			(xy 209.589845 -194.944996) (xy 209.559821 -194.989033) (xy 209.523569 -195.028104) (xy 209.481898 -195.061335)
			(xy 209.43574 -195.087984) (xy 209.386126 -195.107456) (xy 209.334164 -195.119316) (xy 209.281014 -195.1233)
			(xy 209.227864 -195.119316) (xy 209.175902 -195.107456) (xy 209.126288 -195.087984) (xy 209.08013 -195.061335)
			(xy 209.038459 -195.028104) (xy 209.002207 -194.989033) (xy 208.972183 -194.944996) (xy 208.949057 -194.896975)
			(xy 208.933347 -194.846045) (xy 208.925404 -194.793341) (xy 207.426824 -194.793341) (xy 207.418881 -194.846045)
			(xy 207.403171 -194.896975) (xy 207.380045 -194.944996) (xy 207.350021 -194.989033) (xy 207.313769 -195.028104)
			(xy 207.272098 -195.061335) (xy 207.22594 -195.087984) (xy 207.176326 -195.107456) (xy 207.124364 -195.119316)
			(xy 207.071214 -195.1233) (xy 207.018064 -195.119316) (xy 206.966102 -195.107456) (xy 206.916488 -195.087984)
			(xy 206.87033 -195.061335) (xy 206.828659 -195.028104) (xy 206.792407 -194.989033) (xy 206.762383 -194.944996)
			(xy 206.739257 -194.896975) (xy 206.723547 -194.846045) (xy 206.715604 -194.793341) (xy 206.715106 -194.766692)
			(xy 206.715589 -194.740094) (xy 206.723498 -194.68749) (xy 206.739152 -194.63665) (xy 206.762203 -194.588708)
			(xy 206.792137 -194.544734) (xy 206.809848 -194.524884) (xy 206.818732 -194.514748) (xy 206.831201 -194.49086)
			(xy 206.836983 -194.46454) (xy 206.835673 -194.437625) (xy 206.827363 -194.411991) (xy 206.812632 -194.389427)
			(xy 206.792509 -194.371505) (xy 206.780638 -194.365118) (xy 206.757238 -194.352908) (xy 206.713767 -194.322971)
			(xy 206.674837 -194.28733) (xy 206.64119 -194.246664) (xy 206.613467 -194.201749) (xy 206.592199 -194.153442)
			(xy 206.577791 -194.102665) (xy 206.570518 -194.050387) (xy 206.570072 -194.023996) (xy 203.483645 -194.023996)
			(xy 203.481064 -194.041949) (xy 203.465709 -194.094244) (xy 203.443067 -194.143821) (xy 203.413601 -194.189671)
			(xy 203.37791 -194.230862) (xy 203.336719 -194.266553) (xy 203.290869 -194.296019) (xy 203.241292 -194.318661)
			(xy 203.188997 -194.334016) (xy 203.135049 -194.341772) (xy 203.080547 -194.341772) (xy 203.026599 -194.334016)
			(xy 202.974304 -194.318661) (xy 202.924727 -194.296019) (xy 202.878877 -194.266553) (xy 202.837686 -194.230862)
			(xy 202.801995 -194.189671) (xy 202.772529 -194.143821) (xy 202.749887 -194.094244) (xy 202.734532 -194.041949)
			(xy 202.726776 -193.988001) (xy 202.72629 -193.96075) (xy 202.726451 -193.944348) (xy 202.729253 -193.911664)
			(xy 202.731878 -193.895472) (xy 202.733896 -193.880826) (xy 202.730378 -193.851484) (xy 202.718613 -193.824375)
			(xy 202.699586 -193.801764) (xy 202.674886 -193.78554) (xy 202.646577 -193.777058) (xy 202.631802 -193.7766)
			(xy 201.5998 -193.7766) (xy 201.519028 -193.695828) (xy 201.513948 -193.692526) (xy 201.48968 -193.67675)
			(xy 201.445768 -193.63904) (xy 201.408057 -193.595129) (xy 201.392282 -193.57086) (xy 201.38898 -193.56578)
			(xy 200.7616 -192.9384) (xy 195.4022 -192.9384) (xy 194.82435 -193.51625) (xy 198.62876 -193.51625)
			(xy 198.632831 -193.460628) (xy 198.644957 -193.406191) (xy 198.66488 -193.3541) (xy 198.692176 -193.305465)
			(xy 198.726262 -193.261322) (xy 198.766411 -193.222613) (xy 198.811769 -193.190162) (xy 198.861369 -193.164661)
			(xy 198.914153 -193.146654) (xy 198.968996 -193.136524) (xy 199.02473 -193.134487) (xy 199.080167 -193.140587)
			(xy 199.134124 -193.154693) (xy 199.185453 -193.176505) (xy 199.233059 -193.205559) (xy 199.275927 -193.241234)
			(xy 199.313144 -193.282771) (xy 199.343917 -193.329284) (xy 199.367589 -193.379781) (xy 199.383657 -193.433188)
			(xy 199.391777 -193.488364) (xy 199.392286 -193.51625) (xy 199.391777 -193.544136) (xy 199.383657 -193.599312)
			(xy 199.367589 -193.652719) (xy 199.343917 -193.703216) (xy 199.313144 -193.749729) (xy 199.275927 -193.791266)
			(xy 199.233059 -193.826941) (xy 199.185453 -193.855995) (xy 199.134124 -193.877807) (xy 199.080167 -193.891913)
			(xy 199.02473 -193.898013) (xy 198.968996 -193.895976) (xy 198.914153 -193.885846) (xy 198.861369 -193.867839)
			(xy 198.811769 -193.842338) (xy 198.766411 -193.809887) (xy 198.726262 -193.771178) (xy 198.692176 -193.727035)
			(xy 198.66488 -193.6784) (xy 198.644957 -193.626309) (xy 198.632831 -193.571872) (xy 198.62876 -193.51625)
			(xy 194.82435 -193.51625) (xy 194.34556 -193.99504) (xy 194.354958 -194.024504) (xy 194.363477 -194.052895)
			(xy 194.364959 -194.06235) (xy 196.5485 -194.06235) (xy 196.552571 -194.006728) (xy 196.564697 -193.952291)
			(xy 196.58462 -193.9002) (xy 196.611916 -193.851565) (xy 196.646002 -193.807422) (xy 196.686151 -193.768713)
			(xy 196.731509 -193.736262) (xy 196.781109 -193.710761) (xy 196.833893 -193.692754) (xy 196.888736 -193.682624)
			(xy 196.94447 -193.680587) (xy 196.999907 -193.686687) (xy 197.053864 -193.700793) (xy 197.105193 -193.722605)
			(xy 197.152799 -193.751659) (xy 197.195667 -193.787334) (xy 197.232884 -193.828871) (xy 197.263657 -193.875384)
			(xy 197.287329 -193.925881) (xy 197.303397 -193.979288) (xy 197.311517 -194.034464) (xy 197.312026 -194.06235)
			(xy 197.311517 -194.090236) (xy 197.303397 -194.145412) (xy 197.287329 -194.198819) (xy 197.263657 -194.249316)
			(xy 197.232884 -194.295829) (xy 197.195667 -194.337366) (xy 197.152799 -194.373041) (xy 197.105193 -194.402095)
			(xy 197.053864 -194.423907) (xy 196.999907 -194.438013) (xy 196.94447 -194.444113) (xy 196.888736 -194.442076)
			(xy 196.833893 -194.431946) (xy 196.781109 -194.413939) (xy 196.731509 -194.388438) (xy 196.686151 -194.355987)
			(xy 196.646002 -194.317278) (xy 196.611916 -194.273135) (xy 196.58462 -194.2245) (xy 196.564697 -194.172409)
			(xy 196.552571 -194.117972) (xy 196.5485 -194.06235) (xy 194.364959 -194.06235) (xy 194.372657 -194.111454)
			(xy 194.373246 -194.14109) (xy 194.372628 -194.172219) (xy 194.362531 -194.233654) (xy 194.34262 -194.292643)
			(xy 194.328542 -194.320414) (xy 194.322732 -194.332175) (xy 194.316711 -194.357696) (xy 194.317413 -194.383909)
			(xy 194.324793 -194.409071) (xy 194.33836 -194.431511) (xy 194.357213 -194.449737) (xy 194.36842 -194.456558)
			(xy 194.391606 -194.470207) (xy 194.433951 -194.503397) (xy 194.470822 -194.542578) (xy 194.501379 -194.58686)
			(xy 194.524928 -194.635235) (xy 194.540931 -194.686602) (xy 194.549025 -194.739791) (xy 194.549522 -194.766692)
			(xy 194.549024 -194.793341) (xy 195.071736 -194.793341) (xy 195.071736 -194.740043) (xy 195.079679 -194.687339)
			(xy 195.095389 -194.636409) (xy 195.118515 -194.588388) (xy 195.148539 -194.544351) (xy 195.184791 -194.50528)
			(xy 195.226462 -194.472049) (xy 195.27262 -194.4454) (xy 195.322234 -194.425928) (xy 195.374196 -194.414068)
			(xy 195.427346 -194.410085) (xy 195.480496 -194.414068) (xy 195.532458 -194.425928) (xy 195.582072 -194.4454)
			(xy 195.62823 -194.472049) (xy 195.669901 -194.50528) (xy 195.706153 -194.544351) (xy 195.736177 -194.588388)
			(xy 195.759303 -194.636409) (xy 195.775013 -194.687339) (xy 195.782956 -194.740043) (xy 195.783454 -194.766692)
			(xy 195.783401 -194.769553) (xy 198.377763 -194.769553) (xy 198.377763 -194.715047) (xy 198.38552 -194.661097)
			(xy 198.400877 -194.608799) (xy 198.423519 -194.559219) (xy 198.452988 -194.513367) (xy 198.488682 -194.472175)
			(xy 198.529875 -194.436482) (xy 198.575728 -194.407015) (xy 198.625308 -194.384373) (xy 198.677606 -194.369018)
			(xy 198.731557 -194.361263) (xy 198.75881 -194.3608) (xy 198.78628 -194.361258) (xy 198.840652 -194.36914)
			(xy 198.893331 -194.38474) (xy 198.943228 -194.407734) (xy 198.98931 -194.437648) (xy 199.030625 -194.473862)
			(xy 199.066319 -194.515628) (xy 199.08139 -194.5386) (xy 199.089217 -194.550109) (xy 199.109877 -194.568741)
			(xy 199.134798 -194.581106) (xy 199.162133 -194.586286) (xy 199.18985 -194.583896) (xy 199.215894 -194.574113)
			(xy 199.238332 -194.557664) (xy 199.247252 -194.546982) (xy 199.264194 -194.526093) (xy 199.303367 -194.489238)
			(xy 199.347637 -194.458694) (xy 199.395998 -194.435157) (xy 199.447349 -194.419163) (xy 199.500522 -194.411075)
			(xy 199.527414 -194.410584) (xy 199.554062 -194.411099) (xy 199.606763 -194.419044) (xy 199.65769 -194.434755)
			(xy 199.705708 -194.45788) (xy 199.749742 -194.487904) (xy 199.78881 -194.524156) (xy 199.822039 -194.565825)
			(xy 199.848687 -194.611981) (xy 199.868158 -194.661593) (xy 199.880017 -194.713553) (xy 199.884 -194.7667)
			(xy 199.882003 -194.793341) (xy 201.381604 -194.793341) (xy 201.381604 -194.740043) (xy 201.389547 -194.687339)
			(xy 201.405257 -194.636409) (xy 201.428383 -194.588388) (xy 201.458407 -194.544351) (xy 201.494659 -194.50528)
			(xy 201.53633 -194.472049) (xy 201.582488 -194.4454) (xy 201.632102 -194.425928) (xy 201.684064 -194.414068)
			(xy 201.737214 -194.410085) (xy 201.790364 -194.414068) (xy 201.842326 -194.425928) (xy 201.89194 -194.4454)
			(xy 201.938098 -194.472049) (xy 201.979769 -194.50528) (xy 202.016021 -194.544351) (xy 202.046045 -194.588388)
			(xy 202.069171 -194.636409) (xy 202.084881 -194.687339) (xy 202.092824 -194.740043) (xy 202.093322 -194.766692)
			(xy 202.092824 -194.793341) (xy 202.084881 -194.846045) (xy 202.069171 -194.896975) (xy 202.052169 -194.932279)
			(xy 202.188308 -194.932279) (xy 202.188308 -194.878981) (xy 202.196251 -194.826277) (xy 202.211961 -194.775347)
			(xy 202.235087 -194.727326) (xy 202.265111 -194.683289) (xy 202.301363 -194.644218) (xy 202.343034 -194.610987)
			(xy 202.389192 -194.584338) (xy 202.438806 -194.564866) (xy 202.490768 -194.553006) (xy 202.543918 -194.549023)
			(xy 202.597068 -194.553006) (xy 202.64903 -194.564866) (xy 202.698644 -194.584338) (xy 202.744802 -194.610987)
			(xy 202.786473 -194.644218) (xy 202.822725 -194.683289) (xy 202.852749 -194.727326) (xy 202.875875 -194.775347)
			(xy 202.891585 -194.826277) (xy 202.899528 -194.878981) (xy 202.900026 -194.90563) (xy 202.899528 -194.932279)
			(xy 202.891585 -194.984983) (xy 202.875875 -195.035913) (xy 202.852749 -195.083934) (xy 202.822725 -195.127971)
			(xy 202.786473 -195.167042) (xy 202.744802 -195.200273) (xy 202.698644 -195.226922) (xy 202.64903 -195.246394)
			(xy 202.597068 -195.258254) (xy 202.543918 -195.262238) (xy 202.490768 -195.258254) (xy 202.438806 -195.246394)
			(xy 202.389192 -195.226922) (xy 202.343034 -195.200273) (xy 202.301363 -195.167042) (xy 202.265111 -195.127971)
			(xy 202.235087 -195.083934) (xy 202.211961 -195.035913) (xy 202.196251 -194.984983) (xy 202.188308 -194.932279)
			(xy 202.052169 -194.932279) (xy 202.046045 -194.944996) (xy 202.016021 -194.989033) (xy 201.979769 -195.028104)
			(xy 201.938098 -195.061335) (xy 201.89194 -195.087984) (xy 201.842326 -195.107456) (xy 201.790364 -195.119316)
			(xy 201.737214 -195.1233) (xy 201.684064 -195.119316) (xy 201.632102 -195.107456) (xy 201.582488 -195.087984)
			(xy 201.53633 -195.061335) (xy 201.494659 -195.028104) (xy 201.458407 -194.989033) (xy 201.428383 -194.944996)
			(xy 201.405257 -194.896975) (xy 201.389547 -194.846045) (xy 201.381604 -194.793341) (xy 199.882003 -194.793341)
			(xy 199.880017 -194.819847) (xy 199.868158 -194.871807) (xy 199.848687 -194.921419) (xy 199.822039 -194.967575)
			(xy 199.78881 -195.009244) (xy 199.749742 -195.045496) (xy 199.705708 -195.07552) (xy 199.65769 -195.098645)
			(xy 199.606763 -195.114356) (xy 199.554062 -195.122301) (xy 199.527414 -195.1228) (xy 199.498627 -195.122233)
			(xy 199.441805 -195.11296) (xy 199.387213 -195.094668) (xy 199.336275 -195.067834) (xy 199.290316 -195.033156)
			(xy 199.250532 -194.991539) (xy 199.23379 -194.968114) (xy 199.225493 -194.956949) (xy 199.204125 -194.93916)
			(xy 199.178755 -194.927785) (xy 199.151258 -194.923666) (xy 199.123668 -194.927107) (xy 199.098026 -194.937854)
			(xy 199.076227 -194.955112) (xy 199.067674 -194.966082) (xy 199.052256 -194.986683) (xy 199.016754 -195.023928)
			(xy 198.976564 -195.056061) (xy 198.932419 -195.082497) (xy 198.88512 -195.102757) (xy 198.835526 -195.116472)
			(xy 198.784538 -195.123393) (xy 198.75881 -195.123816) (xy 198.731557 -195.123337) (xy 198.677606 -195.115582)
			(xy 198.625308 -195.100227) (xy 198.575728 -195.077585) (xy 198.529875 -195.048118) (xy 198.488682 -195.012425)
			(xy 198.452988 -194.971233) (xy 198.423519 -194.925381) (xy 198.400877 -194.875801) (xy 198.38552 -194.823503)
			(xy 198.377763 -194.769553) (xy 195.783401 -194.769553) (xy 195.782956 -194.793341) (xy 195.775013 -194.846045)
			(xy 195.759303 -194.896975) (xy 195.736177 -194.944996) (xy 195.706153 -194.989033) (xy 195.669901 -195.028104)
			(xy 195.62823 -195.061335) (xy 195.582072 -195.087984) (xy 195.532458 -195.107456) (xy 195.480496 -195.119316)
			(xy 195.427346 -195.1233) (xy 195.374196 -195.119316) (xy 195.322234 -195.107456) (xy 195.27262 -195.087984)
			(xy 195.226462 -195.061335) (xy 195.184791 -195.028104) (xy 195.148539 -194.989033) (xy 195.118515 -194.944996)
			(xy 195.095389 -194.896975) (xy 195.079679 -194.846045) (xy 195.071736 -194.793341) (xy 194.549024 -194.793341)
			(xy 194.541081 -194.846045) (xy 194.525371 -194.896975) (xy 194.502245 -194.944996) (xy 194.472221 -194.989033)
			(xy 194.435969 -195.028104) (xy 194.394298 -195.061335) (xy 194.34814 -195.087984) (xy 194.298526 -195.107456)
			(xy 194.246564 -195.119316) (xy 194.193414 -195.1233) (xy 194.140264 -195.119316) (xy 194.088302 -195.107456)
			(xy 194.038688 -195.087984) (xy 193.99253 -195.061335) (xy 193.950859 -195.028104) (xy 193.914607 -194.989033)
			(xy 193.884583 -194.944996) (xy 193.861457 -194.896975) (xy 193.845747 -194.846045) (xy 193.837804 -194.793341)
			(xy 193.837306 -194.766692) (xy 193.837779 -194.740945) (xy 193.845222 -194.689991) (xy 193.859908 -194.640635)
			(xy 193.870326 -194.617086) (xy 193.87546 -194.605013) (xy 193.880043 -194.57919) (xy 193.8779 -194.553051)
			(xy 193.869172 -194.52832) (xy 193.854435 -194.506625) (xy 193.83466 -194.489398) (xy 193.823082 -194.483228)
			(xy 193.799479 -194.471079) (xy 193.755582 -194.44123) (xy 193.716245 -194.405585) (xy 193.682227 -194.364834)
			(xy 193.654184 -194.319762) (xy 193.632657 -194.271238) (xy 193.618061 -194.2202) (xy 193.610679 -194.167632)
			(xy 193.61023 -194.14109) (xy 193.610355 -194.129246) (xy 193.611877 -194.105607) (xy 193.613278 -194.093846)
			(xy 193.614548 -194.079526) (xy 193.609986 -194.051156) (xy 193.597705 -194.025178) (xy 193.578675 -194.003648)
			(xy 193.554402 -193.988268) (xy 193.526807 -193.980256) (xy 193.51244 -193.9798) (xy 177.165 -193.9798)
			(xy 176.901094 -194.243706) (xy 176.891536 -194.253851) (xy 176.877865 -194.278128) (xy 176.871269 -194.305198)
			(xy 176.872239 -194.333043) (xy 176.880703 -194.359588) (xy 176.896031 -194.382855) (xy 176.917079 -194.40111)
			(xy 176.942281 -194.412993) (xy 176.955958 -194.415664) (xy 176.983217 -194.420858) (xy 177.035804 -194.438571)
			(xy 177.085006 -194.464226) (xy 177.129634 -194.497203) (xy 177.168607 -194.536702) (xy 177.200982 -194.581768)
			(xy 177.225975 -194.63131) (xy 177.242981 -194.68413) (xy 177.251589 -194.738947) (xy 177.252122 -194.766692)
			(xy 177.251624 -194.793341) (xy 178.750204 -194.793341) (xy 178.750204 -194.740043) (xy 178.758147 -194.687339)
			(xy 178.773857 -194.636409) (xy 178.796983 -194.588388) (xy 178.827007 -194.544351) (xy 178.863259 -194.50528)
			(xy 178.90493 -194.472049) (xy 178.951088 -194.4454) (xy 179.000702 -194.425928) (xy 179.052664 -194.414068)
			(xy 179.105814 -194.410085) (xy 179.158964 -194.414068) (xy 179.210926 -194.425928) (xy 179.26054 -194.4454)
			(xy 179.306698 -194.472049) (xy 179.348369 -194.50528) (xy 179.384621 -194.544351) (xy 179.414645 -194.588388)
			(xy 179.437771 -194.636409) (xy 179.453481 -194.687339) (xy 179.461424 -194.740043) (xy 179.461922 -194.766692)
			(xy 179.461424 -194.793341) (xy 179.958736 -194.793341) (xy 179.958736 -194.740043) (xy 179.966679 -194.687339)
			(xy 179.982389 -194.636409) (xy 180.005515 -194.588388) (xy 180.035539 -194.544351) (xy 180.071791 -194.50528)
			(xy 180.113462 -194.472049) (xy 180.15962 -194.4454) (xy 180.209234 -194.425928) (xy 180.261196 -194.414068)
			(xy 180.314346 -194.410085) (xy 180.367496 -194.414068) (xy 180.419458 -194.425928) (xy 180.469072 -194.4454)
			(xy 180.51523 -194.472049) (xy 180.556901 -194.50528) (xy 180.578861 -194.528948) (xy 182.67502 -194.528948)
			(xy 182.679091 -194.473326) (xy 182.691217 -194.418889) (xy 182.71114 -194.366798) (xy 182.738436 -194.318163)
			(xy 182.772522 -194.27402) (xy 182.812671 -194.235311) (xy 182.858029 -194.20286) (xy 182.907629 -194.177359)
			(xy 182.960413 -194.159352) (xy 183.015256 -194.149222) (xy 183.07099 -194.147185) (xy 183.126427 -194.153285)
			(xy 183.180384 -194.167391) (xy 183.231713 -194.189203) (xy 183.279319 -194.218257) (xy 183.322187 -194.253932)
			(xy 183.359404 -194.295469) (xy 183.390177 -194.341982) (xy 183.413849 -194.392479) (xy 183.429917 -194.445886)
			(xy 183.438037 -194.501062) (xy 183.438546 -194.528948) (xy 183.438037 -194.556834) (xy 183.429917 -194.61201)
			(xy 183.413849 -194.665417) (xy 183.390177 -194.715914) (xy 183.359404 -194.762427) (xy 183.331705 -194.793341)
			(xy 184.084204 -194.793341) (xy 184.084204 -194.740043) (xy 184.092147 -194.687339) (xy 184.107857 -194.636409)
			(xy 184.130983 -194.588388) (xy 184.161007 -194.544351) (xy 184.197259 -194.50528) (xy 184.23893 -194.472049)
			(xy 184.285088 -194.4454) (xy 184.334702 -194.425928) (xy 184.386664 -194.414068) (xy 184.439814 -194.410085)
			(xy 184.492964 -194.414068) (xy 184.544926 -194.425928) (xy 184.59454 -194.4454) (xy 184.640698 -194.472049)
			(xy 184.682369 -194.50528) (xy 184.718621 -194.544351) (xy 184.748645 -194.588388) (xy 184.771771 -194.636409)
			(xy 184.787481 -194.687339) (xy 184.795424 -194.740043) (xy 184.795922 -194.766692) (xy 184.795922 -194.7667)
			(xy 186.29296 -194.7667) (xy 186.296944 -194.713544) (xy 186.308805 -194.661576) (xy 186.32828 -194.611956)
			(xy 186.354933 -194.565793) (xy 186.388169 -194.524118) (xy 186.427245 -194.487863) (xy 186.471288 -194.457836)
			(xy 186.519315 -194.434709) (xy 186.570252 -194.418999) (xy 186.622962 -194.411056) (xy 186.649614 -194.410584)
			(xy 186.675692 -194.411048) (xy 186.727291 -194.418646) (xy 186.77723 -194.433691) (xy 186.824439 -194.455861)
			(xy 186.867908 -194.484682) (xy 186.887612 -194.50177) (xy 186.898961 -194.511252) (xy 186.925685 -194.523881)
			(xy 186.954907 -194.528328) (xy 186.984178 -194.524221) (xy 187.011047 -194.511903) (xy 187.022486 -194.502532)
			(xy 187.04346 -194.484783) (xy 187.08954 -194.454858) (xy 187.139431 -194.431844) (xy 187.192105 -194.416214)
			(xy 187.246475 -194.408292) (xy 187.273946 -194.40779) (xy 187.300647 -194.408225) (xy 187.353527 -194.415683)
			(xy 187.404849 -194.430445) (xy 187.453609 -194.452224) (xy 187.498854 -194.480592) (xy 187.519564 -194.497452)
			(xy 187.53086 -194.506343) (xy 187.557138 -194.517971) (xy 187.585613 -194.521835) (xy 187.61404 -194.51763)
			(xy 187.640177 -194.505687) (xy 187.65139 -194.49669) (xy 187.670857 -194.480523) (xy 187.713504 -194.453289)
			(xy 187.759579 -194.432369) (xy 187.808153 -194.418186) (xy 187.858245 -194.411025) (xy 187.883546 -194.410584)
			(xy 187.910192 -194.411101) (xy 187.962889 -194.41905) (xy 188.013813 -194.434764) (xy 188.061826 -194.457891)
			(xy 188.105857 -194.487916) (xy 188.144921 -194.524167) (xy 188.178146 -194.565835) (xy 188.204791 -194.611989)
			(xy 188.224259 -194.661599) (xy 188.236117 -194.713556) (xy 188.238844 -194.749948) (xy 190.915828 -194.749948)
			(xy 190.915828 -194.695452) (xy 190.923584 -194.641512) (xy 190.938937 -194.589224) (xy 190.961575 -194.539654)
			(xy 190.991037 -194.49381) (xy 191.026723 -194.452625) (xy 191.067908 -194.416938) (xy 191.113752 -194.387476)
			(xy 191.163322 -194.364837) (xy 191.21561 -194.349484) (xy 191.26955 -194.341728) (xy 191.296798 -194.341242)
			(xy 191.325716 -194.341746) (xy 191.382888 -194.350476) (xy 191.438088 -194.367735) (xy 191.49005 -194.39313)
			(xy 191.537583 -194.426077) (xy 191.579599 -194.465821) (xy 191.597788 -194.488308) (xy 191.606696 -194.499018)
			(xy 191.629097 -194.515561) (xy 191.655133 -194.525437) (xy 191.682869 -194.527914) (xy 191.710243 -194.522807)
			(xy 191.73522 -194.510495) (xy 191.74587 -194.501516) (xy 191.765581 -194.48449) (xy 191.809013 -194.455743)
			(xy 191.856169 -194.433629) (xy 191.906044 -194.41862) (xy 191.957572 -194.411036) (xy 191.983614 -194.410584)
			(xy 192.010262 -194.411099) (xy 192.062963 -194.419044) (xy 192.11389 -194.434755) (xy 192.161908 -194.45788)
			(xy 192.205942 -194.487904) (xy 192.24501 -194.524156) (xy 192.278239 -194.565825) (xy 192.304887 -194.611981)
			(xy 192.324358 -194.661593) (xy 192.336217 -194.713553) (xy 192.3402 -194.7667) (xy 192.336217 -194.819847)
			(xy 192.324358 -194.871807) (xy 192.304887 -194.921419) (xy 192.278239 -194.967575) (xy 192.24501 -195.009244)
			(xy 192.205942 -195.045496) (xy 192.161908 -195.07552) (xy 192.11389 -195.098645) (xy 192.062963 -195.114356)
			(xy 192.010262 -195.122301) (xy 191.983614 -195.1228) (xy 191.958104 -195.12237) (xy 191.907604 -195.115107)
			(xy 191.858656 -195.100713) (xy 191.812263 -195.079483) (xy 191.769374 -195.05185) (xy 191.730866 -195.018381)
			(xy 191.713866 -194.999356) (xy 191.70446 -194.98912) (xy 191.681291 -194.973773) (xy 191.654843 -194.96524)
			(xy 191.627074 -194.964153) (xy 191.60004 -194.970592) (xy 191.575743 -194.98408) (xy 191.56553 -194.993514)
			(xy 191.543941 -195.014114) (xy 191.49557 -195.049051) (xy 191.442348 -195.076029) (xy 191.385573 -195.094388)
			(xy 191.326632 -195.103681) (xy 191.296798 -195.104258) (xy 191.26955 -195.103672) (xy 191.21561 -195.095916)
			(xy 191.163322 -195.080563) (xy 191.113752 -195.057924) (xy 191.067908 -195.028462) (xy 191.026723 -194.992775)
			(xy 190.991037 -194.95159) (xy 190.961575 -194.905746) (xy 190.938937 -194.856176) (xy 190.923584 -194.803888)
			(xy 190.915828 -194.749948) (xy 188.238844 -194.749948) (xy 188.2401 -194.7667) (xy 188.236117 -194.819844)
			(xy 188.224259 -194.871801) (xy 188.204791 -194.921411) (xy 188.178146 -194.967565) (xy 188.144921 -195.009233)
			(xy 188.105857 -195.045484) (xy 188.061826 -195.075509) (xy 188.013813 -195.098636) (xy 187.962889 -195.11435)
			(xy 187.910192 -195.122299) (xy 187.883546 -195.1228) (xy 187.855214 -195.122252) (xy 187.799262 -195.113291)
			(xy 187.745434 -195.095586) (xy 187.695087 -195.069585) (xy 187.671964 -195.053204) (xy 187.660126 -195.045088)
			(xy 187.633237 -195.035099) (xy 187.604629 -195.032989) (xy 187.576564 -195.038924) (xy 187.55126 -195.052436)
			(xy 187.540646 -195.062094) (xy 187.519154 -195.082381) (xy 187.471025 -195.116681) (xy 187.418183 -195.143148)
			(xy 187.361891 -195.16115) (xy 187.303496 -195.170256) (xy 187.273946 -195.170806) (xy 187.243688 -195.170268)
			(xy 187.183927 -195.160741) (xy 187.126418 -195.141902) (xy 187.072604 -195.114223) (xy 187.023831 -195.078398)
			(xy 187.002166 -195.057268) (xy 186.991441 -195.047129) (xy 186.965585 -195.032924) (xy 186.93675 -195.026694)
			(xy 186.907336 -195.028956) (xy 186.879792 -195.039522) (xy 186.8678 -195.048124) (xy 186.844216 -195.065642)
			(xy 186.792513 -195.09353) (xy 186.736934 -195.112554) (xy 186.678986 -195.122197) (xy 186.649614 -195.1228)
			(xy 186.622962 -195.122344) (xy 186.570252 -195.114401) (xy 186.519315 -195.098691) (xy 186.471288 -195.075564)
			(xy 186.427245 -195.045537) (xy 186.388169 -195.009282) (xy 186.354933 -194.967607) (xy 186.32828 -194.921444)
			(xy 186.308805 -194.871824) (xy 186.296944 -194.819856) (xy 186.29296 -194.7667) (xy 184.795922 -194.7667)
			(xy 184.795424 -194.793341) (xy 184.787481 -194.846045) (xy 184.771771 -194.896975) (xy 184.748645 -194.944996)
			(xy 184.718621 -194.989033) (xy 184.682369 -195.028104) (xy 184.640698 -195.061335) (xy 184.59454 -195.087984)
			(xy 184.544926 -195.107456) (xy 184.492964 -195.119316) (xy 184.439814 -195.1233) (xy 184.386664 -195.119316)
			(xy 184.334702 -195.107456) (xy 184.285088 -195.087984) (xy 184.23893 -195.061335) (xy 184.197259 -195.028104)
			(xy 184.161007 -194.989033) (xy 184.130983 -194.944996) (xy 184.107857 -194.896975) (xy 184.092147 -194.846045)
			(xy 184.084204 -194.793341) (xy 183.331705 -194.793341) (xy 183.322187 -194.803964) (xy 183.279319 -194.839639)
			(xy 183.231713 -194.868693) (xy 183.180384 -194.890505) (xy 183.126427 -194.904611) (xy 183.07099 -194.910711)
			(xy 183.015256 -194.908674) (xy 182.960413 -194.898544) (xy 182.907629 -194.880537) (xy 182.858029 -194.855036)
			(xy 182.812671 -194.822585) (xy 182.772522 -194.783876) (xy 182.738436 -194.739733) (xy 182.71114 -194.691098)
			(xy 182.691217 -194.639007) (xy 182.679091 -194.58457) (xy 182.67502 -194.528948) (xy 180.578861 -194.528948)
			(xy 180.593153 -194.544351) (xy 180.623177 -194.588388) (xy 180.646303 -194.636409) (xy 180.662013 -194.687339)
			(xy 180.669956 -194.740043) (xy 180.670454 -194.766692) (xy 180.669956 -194.793341) (xy 180.662013 -194.846045)
			(xy 180.646303 -194.896975) (xy 180.623177 -194.944996) (xy 180.593153 -194.989033) (xy 180.556901 -195.028104)
			(xy 180.51523 -195.061335) (xy 180.469072 -195.087984) (xy 180.419458 -195.107456) (xy 180.367496 -195.119316)
			(xy 180.314346 -195.1233) (xy 180.261196 -195.119316) (xy 180.209234 -195.107456) (xy 180.15962 -195.087984)
			(xy 180.113462 -195.061335) (xy 180.071791 -195.028104) (xy 180.035539 -194.989033) (xy 180.005515 -194.944996)
			(xy 179.982389 -194.896975) (xy 179.966679 -194.846045) (xy 179.958736 -194.793341) (xy 179.461424 -194.793341)
			(xy 179.453481 -194.846045) (xy 179.437771 -194.896975) (xy 179.414645 -194.944996) (xy 179.384621 -194.989033)
			(xy 179.348369 -195.028104) (xy 179.306698 -195.061335) (xy 179.26054 -195.087984) (xy 179.210926 -195.107456)
			(xy 179.158964 -195.119316) (xy 179.105814 -195.1233) (xy 179.052664 -195.119316) (xy 179.000702 -195.107456)
			(xy 178.951088 -195.087984) (xy 178.90493 -195.061335) (xy 178.863259 -195.028104) (xy 178.827007 -194.989033)
			(xy 178.796983 -194.944996) (xy 178.773857 -194.896975) (xy 178.758147 -194.846045) (xy 178.750204 -194.793341)
			(xy 177.251624 -194.793341) (xy 177.243681 -194.846045) (xy 177.227971 -194.896975) (xy 177.204845 -194.944996)
			(xy 177.174821 -194.989033) (xy 177.138569 -195.028104) (xy 177.096898 -195.061335) (xy 177.05074 -195.087984)
			(xy 177.001126 -195.107456) (xy 176.949164 -195.119316) (xy 176.896014 -195.1233) (xy 176.842864 -195.119316)
			(xy 176.790902 -195.107456) (xy 176.741288 -195.087984) (xy 176.69513 -195.061335) (xy 176.653459 -195.028104)
			(xy 176.617207 -194.989033) (xy 176.587183 -194.944996) (xy 176.564057 -194.896975) (xy 176.548347 -194.846045)
			(xy 176.540404 -194.793341) (xy 176.539906 -194.766692) (xy 176.540271 -194.743081) (xy 176.546474 -194.69627)
			(xy 176.558809 -194.650689) (xy 176.567592 -194.62877) (xy 176.572686 -194.615399) (xy 176.576022 -194.586992)
			(xy 176.571351 -194.558774) (xy 176.559041 -194.532958) (xy 176.540055 -194.511566) (xy 176.515883 -194.496276)
			(xy 176.48842 -194.488287) (xy 176.47412 -194.4878) (xy 173.21784 -194.4878) (xy 173.203541 -194.488319)
			(xy 173.176079 -194.496313) (xy 173.151907 -194.511602) (xy 173.132917 -194.532989) (xy 173.120596 -194.5588)
			(xy 173.115907 -194.587014) (xy 173.119218 -194.615423) (xy 173.124368 -194.62877) (xy 173.13314 -194.650693)
			(xy 173.145476 -194.696272) (xy 173.151679 -194.743082) (xy 173.152054 -194.766692) (xy 173.151556 -194.793341)
			(xy 173.143613 -194.846045) (xy 173.127903 -194.896975) (xy 173.104777 -194.944996) (xy 173.074753 -194.989033)
			(xy 173.038501 -195.028104) (xy 172.99683 -195.061335) (xy 172.950672 -195.087984) (xy 172.901058 -195.107456)
			(xy 172.849096 -195.119316) (xy 172.795946 -195.1233) (xy 172.742796 -195.119316) (xy 172.690834 -195.107456)
			(xy 172.64122 -195.087984) (xy 172.595062 -195.061335) (xy 172.553391 -195.028104) (xy 172.517139 -194.989033)
			(xy 172.487115 -194.944996) (xy 172.463989 -194.896975) (xy 172.448279 -194.846045) (xy 172.440336 -194.793341)
			(xy 172.439838 -194.766692) (xy 172.440203 -194.743081) (xy 172.446404 -194.696269) (xy 172.458737 -194.650688)
			(xy 172.467524 -194.62877) (xy 172.47262 -194.615402) (xy 172.475959 -194.587) (xy 172.471289 -194.558786)
			(xy 172.458976 -194.532975) (xy 172.439988 -194.511592) (xy 172.415813 -194.496314) (xy 172.38835 -194.488341)
			(xy 172.374052 -194.4878) (xy 171.983908 -194.4878) (xy 171.969612 -194.488323) (xy 171.942159 -194.496322)
			(xy 171.917995 -194.511612) (xy 171.899012 -194.532997) (xy 171.886695 -194.558803) (xy 171.882007 -194.587011)
			(xy 171.885316 -194.615414) (xy 171.890436 -194.62877) (xy 171.899209 -194.650693) (xy 171.911546 -194.696272)
			(xy 171.91775 -194.743082) (xy 171.918122 -194.766692) (xy 171.917624 -194.793341) (xy 171.909681 -194.846045)
			(xy 171.893971 -194.896975) (xy 171.870845 -194.944996) (xy 171.840821 -194.989033) (xy 171.804569 -195.028104)
			(xy 171.762898 -195.061335) (xy 171.71674 -195.087984) (xy 171.667126 -195.107456) (xy 171.615164 -195.119316)
			(xy 171.562014 -195.1233) (xy 171.508864 -195.119316) (xy 171.456902 -195.107456) (xy 171.407288 -195.087984)
			(xy 171.36113 -195.061335) (xy 171.319459 -195.028104) (xy 171.283207 -194.989033) (xy 171.253183 -194.944996)
			(xy 171.230057 -194.896975) (xy 171.214347 -194.846045) (xy 171.206404 -194.793341) (xy 171.205906 -194.766692)
			(xy 171.206271 -194.743081) (xy 171.212474 -194.69627) (xy 171.224809 -194.650689) (xy 171.233592 -194.62877)
			(xy 171.238686 -194.615399) (xy 171.242022 -194.586992) (xy 171.237351 -194.558774) (xy 171.225041 -194.532958)
			(xy 171.206055 -194.511566) (xy 171.181883 -194.496276) (xy 171.15442 -194.488287) (xy 171.14012 -194.4878)
			(xy 169.774108 -194.4878) (xy 169.759812 -194.488323) (xy 169.732359 -194.496322) (xy 169.708195 -194.511612)
			(xy 169.689212 -194.532997) (xy 169.676895 -194.558803) (xy 169.672207 -194.587011) (xy 169.675516 -194.615414)
			(xy 169.680636 -194.62877) (xy 169.689409 -194.650693) (xy 169.701746 -194.696272) (xy 169.70795 -194.743082)
			(xy 169.708322 -194.766692) (xy 169.707824 -194.793341) (xy 169.699881 -194.846045) (xy 169.684171 -194.896975)
			(xy 169.661045 -194.944996) (xy 169.631021 -194.989033) (xy 169.594769 -195.028104) (xy 169.553098 -195.061335)
			(xy 169.50694 -195.087984) (xy 169.457326 -195.107456) (xy 169.405364 -195.119316) (xy 169.352214 -195.1233)
			(xy 169.299064 -195.119316) (xy 169.247102 -195.107456) (xy 169.197488 -195.087984) (xy 169.15133 -195.061335)
			(xy 169.109659 -195.028104) (xy 169.073407 -194.989033) (xy 169.043383 -194.944996) (xy 169.020257 -194.896975)
			(xy 169.004547 -194.846045) (xy 168.996604 -194.793341) (xy 168.996106 -194.766692) (xy 168.996471 -194.743081)
			(xy 169.002674 -194.69627) (xy 169.015009 -194.650689) (xy 169.023792 -194.62877) (xy 169.028886 -194.615399)
			(xy 169.032222 -194.586992) (xy 169.027551 -194.558774) (xy 169.015241 -194.532958) (xy 168.996255 -194.511566)
			(xy 168.972083 -194.496276) (xy 168.94462 -194.488287) (xy 168.93032 -194.4878) (xy 165.67404 -194.4878)
			(xy 165.659741 -194.488319) (xy 165.632279 -194.496313) (xy 165.608107 -194.511602) (xy 165.589117 -194.532989)
			(xy 165.576796 -194.5588) (xy 165.572107 -194.587014) (xy 165.575418 -194.615423) (xy 165.580568 -194.62877)
			(xy 165.58934 -194.650693) (xy 165.601676 -194.696272) (xy 165.607879 -194.743082) (xy 165.608254 -194.766692)
			(xy 165.607756 -194.793341) (xy 165.599813 -194.846045) (xy 165.584103 -194.896975) (xy 165.560977 -194.944996)
			(xy 165.530953 -194.989033) (xy 165.494701 -195.028104) (xy 165.45303 -195.061335) (xy 165.406872 -195.087984)
			(xy 165.357258 -195.107456) (xy 165.305296 -195.119316) (xy 165.252146 -195.1233) (xy 165.198996 -195.119316)
			(xy 165.147034 -195.107456) (xy 165.09742 -195.087984) (xy 165.051262 -195.061335) (xy 165.009591 -195.028104)
			(xy 164.973339 -194.989033) (xy 164.943315 -194.944996) (xy 164.920189 -194.896975) (xy 164.904479 -194.846045)
			(xy 164.896536 -194.793341) (xy 164.896038 -194.766692) (xy 164.896403 -194.743081) (xy 164.902604 -194.696269)
			(xy 164.914937 -194.650688) (xy 164.923724 -194.62877) (xy 164.92882 -194.615402) (xy 164.932159 -194.587)
			(xy 164.927489 -194.558786) (xy 164.915176 -194.532975) (xy 164.896188 -194.511592) (xy 164.872013 -194.496314)
			(xy 164.84455 -194.488341) (xy 164.830252 -194.4878) (xy 164.440108 -194.4878) (xy 164.425812 -194.488323)
			(xy 164.398359 -194.496322) (xy 164.374195 -194.511612) (xy 164.355212 -194.532997) (xy 164.342895 -194.558803)
			(xy 164.338207 -194.587011) (xy 164.341516 -194.615414) (xy 164.346636 -194.62877) (xy 164.355409 -194.650693)
			(xy 164.367746 -194.696272) (xy 164.37395 -194.743082) (xy 164.374322 -194.766692) (xy 164.373824 -194.793341)
			(xy 164.365881 -194.846045) (xy 164.350171 -194.896975) (xy 164.327045 -194.944996) (xy 164.297021 -194.989033)
			(xy 164.260769 -195.028104) (xy 164.219098 -195.061335) (xy 164.17294 -195.087984) (xy 164.123326 -195.107456)
			(xy 164.071364 -195.119316) (xy 164.018214 -195.1233) (xy 163.965064 -195.119316) (xy 163.913102 -195.107456)
			(xy 163.863488 -195.087984) (xy 163.81733 -195.061335) (xy 163.775659 -195.028104) (xy 163.739407 -194.989033)
			(xy 163.709383 -194.944996) (xy 163.686257 -194.896975) (xy 163.670547 -194.846045) (xy 163.662604 -194.793341)
			(xy 163.662106 -194.766692) (xy 163.662471 -194.743081) (xy 163.668674 -194.69627) (xy 163.681009 -194.650689)
			(xy 163.689792 -194.62877) (xy 163.694886 -194.615399) (xy 163.698222 -194.586992) (xy 163.693551 -194.558774)
			(xy 163.681241 -194.532958) (xy 163.662255 -194.511566) (xy 163.638083 -194.496276) (xy 163.61062 -194.488287)
			(xy 163.59632 -194.4878) (xy 162.230308 -194.4878) (xy 162.216012 -194.488323) (xy 162.188559 -194.496322)
			(xy 162.164395 -194.511612) (xy 162.145412 -194.532997) (xy 162.133095 -194.558803) (xy 162.128407 -194.587011)
			(xy 162.131716 -194.615414) (xy 162.136836 -194.62877) (xy 162.145609 -194.650693) (xy 162.157946 -194.696272)
			(xy 162.16415 -194.743082) (xy 162.164522 -194.766692) (xy 162.164024 -194.793341) (xy 162.156081 -194.846045)
			(xy 162.140371 -194.896975) (xy 162.117245 -194.944996) (xy 162.087221 -194.989033) (xy 162.050969 -195.028104)
			(xy 162.009298 -195.061335) (xy 161.96314 -195.087984) (xy 161.913526 -195.107456) (xy 161.861564 -195.119316)
			(xy 161.808414 -195.1233) (xy 161.755264 -195.119316) (xy 161.703302 -195.107456) (xy 161.653688 -195.087984)
			(xy 161.60753 -195.061335) (xy 161.565859 -195.028104) (xy 161.529607 -194.989033) (xy 161.499583 -194.944996)
			(xy 161.476457 -194.896975) (xy 161.460747 -194.846045) (xy 161.452804 -194.793341) (xy 161.452306 -194.766692)
			(xy 161.452671 -194.743081) (xy 161.458874 -194.69627) (xy 161.471209 -194.650689) (xy 161.479992 -194.62877)
			(xy 161.485086 -194.615399) (xy 161.488422 -194.586992) (xy 161.483751 -194.558774) (xy 161.471441 -194.532958)
			(xy 161.452455 -194.511566) (xy 161.428283 -194.496276) (xy 161.40082 -194.488287) (xy 161.38652 -194.4878)
			(xy 160.38068 -194.4878) (xy 160.365561 -194.488354) (xy 160.33665 -194.497209) (xy 160.311597 -194.514139)
			(xy 160.292595 -194.53766) (xy 160.28131 -194.565712) (xy 160.278729 -194.595839) (xy 160.281366 -194.610736)
			(xy 160.285059 -194.629184) (xy 160.289005 -194.6666) (xy 160.28924 -194.685412) (xy 160.288742 -194.712061)
			(xy 160.280799 -194.764765) (xy 160.265089 -194.815695) (xy 160.241963 -194.863716) (xy 160.211939 -194.907753)
			(xy 160.175687 -194.946824) (xy 160.134016 -194.980055) (xy 160.087858 -195.006704) (xy 160.038244 -195.026176)
			(xy 159.986282 -195.038036) (xy 159.933132 -195.04202) (xy 159.879982 -195.038036) (xy 159.82802 -195.026176)
			(xy 159.778406 -195.006704) (xy 159.732248 -194.980055) (xy 159.690577 -194.946824) (xy 159.654325 -194.907753)
			(xy 159.624301 -194.863716) (xy 159.601175 -194.815695) (xy 159.585465 -194.764765) (xy 159.577522 -194.712061)
			(xy 159.577024 -194.685412) (xy 159.577254 -194.6666) (xy 159.581198 -194.629182) (xy 159.584898 -194.610736)
			(xy 159.587535 -194.595841) (xy 159.584954 -194.565717) (xy 159.573668 -194.537669) (xy 159.554666 -194.514153)
			(xy 159.529612 -194.497231) (xy 159.500701 -194.488385) (xy 159.485584 -194.4878) (xy 159.1056 -194.4878)
			(xy 157.902402 -193.284856) (xy 154.339798 -193.284856) (xy 154.3304 -193.294) (xy 153.397712 -193.294)
			(xy 153.384224 -193.294456) (xy 153.358207 -193.301598) (xy 153.33497 -193.315306) (xy 153.316136 -193.334623)
			(xy 153.30302 -193.3582) (xy 153.29654 -193.384389) (xy 153.296366 -193.397886) (xy 153.296366 -193.40703)
			(xy 153.29588 -193.434281) (xy 153.288124 -193.488229) (xy 153.272769 -193.540524) (xy 153.250127 -193.590101)
			(xy 153.220661 -193.635951) (xy 153.18497 -193.677142) (xy 153.143779 -193.712833) (xy 153.097929 -193.742299)
			(xy 153.048352 -193.764941) (xy 152.996057 -193.780296) (xy 152.942109 -193.788052) (xy 152.887607 -193.788052)
			(xy 152.833659 -193.780296) (xy 152.781364 -193.764941) (xy 152.731787 -193.742299) (xy 152.685937 -193.712833)
			(xy 152.644746 -193.677142) (xy 152.609055 -193.635951) (xy 152.579589 -193.590101) (xy 152.556947 -193.540524)
			(xy 152.541592 -193.488229) (xy 152.533836 -193.434281) (xy 152.53335 -193.40703) (xy 152.53335 -193.397886)
			(xy 152.533235 -193.384387) (xy 152.526749 -193.358191) (xy 152.513624 -193.334611) (xy 152.494777 -193.315296)
			(xy 152.471526 -193.301596) (xy 152.445497 -193.29447) (xy 152.432004 -193.294) (xy 147.6502 -193.294)
			(xy 113.3094 -158.9532) (xy 113.3094 -137.3632) (xy 112.9538 -137.0076) (xy 110.792006 -137.0076)
			(xy 110.7771 -137.008118) (xy 110.748555 -137.016723) (xy 110.72371 -137.0332) (xy 110.704679 -137.056148)
			(xy 110.693082 -137.083613) (xy 110.689907 -137.113256) (xy 110.692184 -137.127996) (xy 110.695279 -137.145549)
			(xy 110.698586 -137.18104) (xy 110.698788 -137.198862) (xy 110.698327 -137.226116) (xy 110.690575 -137.28007)
			(xy 110.675222 -137.332371) (xy 110.652581 -137.381955) (xy 110.623114 -137.427811) (xy 110.58742 -137.469007)
			(xy 110.546226 -137.504703) (xy 110.500371 -137.534172) (xy 110.450788 -137.556815) (xy 110.398488 -137.572171)
			(xy 110.344534 -137.579926) (xy 110.31728 -137.58037) (xy 110.290472 -137.579919) (xy 110.237384 -137.572415)
			(xy 110.185871 -137.557543) (xy 110.136952 -137.535598) (xy 110.091592 -137.507012) (xy 110.050687 -137.47235)
			(xy 110.032546 -137.452608) (xy 110.023143 -137.442691) (xy 110.000231 -137.427815) (xy 109.974194 -137.419548)
			(xy 109.946897 -137.418483) (xy 109.920295 -137.424695) (xy 109.896292 -137.43774) (xy 109.876609 -137.456683)
			(xy 109.862655 -137.480168) (xy 109.855429 -137.506513) (xy 109.855 -137.520172) (xy 109.855 -137.799826)
			(xy 112.102644 -137.799826) (xy 112.106715 -137.744204) (xy 112.118841 -137.689767) (xy 112.138764 -137.637676)
			(xy 112.16606 -137.589041) (xy 112.200146 -137.544898) (xy 112.240295 -137.506189) (xy 112.285653 -137.473738)
			(xy 112.335253 -137.448237) (xy 112.388037 -137.43023) (xy 112.44288 -137.4201) (xy 112.498614 -137.418063)
			(xy 112.554051 -137.424163) (xy 112.608008 -137.438269) (xy 112.659337 -137.460081) (xy 112.706943 -137.489135)
			(xy 112.749811 -137.52481) (xy 112.787028 -137.566347) (xy 112.817801 -137.61286) (xy 112.841473 -137.663357)
			(xy 112.857541 -137.716764) (xy 112.865661 -137.77194) (xy 112.86617 -137.799826) (xy 112.865661 -137.827712)
			(xy 112.857541 -137.882888) (xy 112.841473 -137.936295) (xy 112.817801 -137.986792) (xy 112.787028 -138.033305)
			(xy 112.749811 -138.074842) (xy 112.706943 -138.110517) (xy 112.659337 -138.139571) (xy 112.608008 -138.161383)
			(xy 112.554051 -138.175489) (xy 112.498614 -138.181589) (xy 112.44288 -138.179552) (xy 112.388037 -138.169422)
			(xy 112.335253 -138.151415) (xy 112.285653 -138.125914) (xy 112.240295 -138.093463) (xy 112.200146 -138.054754)
			(xy 112.16606 -138.010611) (xy 112.138764 -137.961976) (xy 112.118841 -137.909885) (xy 112.106715 -137.855448)
			(xy 112.102644 -137.799826) (xy 109.855 -137.799826) (xy 109.855 -139.069826) (xy 112.102644 -139.069826)
			(xy 112.106715 -139.014204) (xy 112.118841 -138.959767) (xy 112.138764 -138.907676) (xy 112.16606 -138.859041)
			(xy 112.200146 -138.814898) (xy 112.240295 -138.776189) (xy 112.285653 -138.743738) (xy 112.335253 -138.718237)
			(xy 112.388037 -138.70023) (xy 112.44288 -138.6901) (xy 112.498614 -138.688063) (xy 112.554051 -138.694163)
			(xy 112.608008 -138.708269) (xy 112.659337 -138.730081) (xy 112.706943 -138.759135) (xy 112.749811 -138.79481)
			(xy 112.787028 -138.836347) (xy 112.817801 -138.88286) (xy 112.841473 -138.933357) (xy 112.857541 -138.986764)
			(xy 112.865661 -139.04194) (xy 112.86617 -139.069826) (xy 112.865661 -139.097712) (xy 112.857541 -139.152888)
			(xy 112.841473 -139.206295) (xy 112.817801 -139.256792) (xy 112.787028 -139.303305) (xy 112.749811 -139.344842)
			(xy 112.706943 -139.380517) (xy 112.659337 -139.409571) (xy 112.608008 -139.431383) (xy 112.554051 -139.445489)
			(xy 112.498614 -139.451589) (xy 112.44288 -139.449552) (xy 112.388037 -139.439422) (xy 112.335253 -139.421415)
			(xy 112.285653 -139.395914) (xy 112.240295 -139.363463) (xy 112.200146 -139.324754) (xy 112.16606 -139.280611)
			(xy 112.138764 -139.231976) (xy 112.118841 -139.179885) (xy 112.106715 -139.125448) (xy 112.102644 -139.069826)
			(xy 109.855 -139.069826) (xy 109.855 -161.3662) (xy 142.431008 -193.942208) (xy 156.574742 -193.942208)
			(xy 156.578813 -193.886586) (xy 156.590939 -193.832149) (xy 156.610862 -193.780058) (xy 156.638158 -193.731423)
			(xy 156.672244 -193.68728) (xy 156.712393 -193.648571) (xy 156.757751 -193.61612) (xy 156.807351 -193.590619)
			(xy 156.860135 -193.572612) (xy 156.914978 -193.562482) (xy 156.970712 -193.560445) (xy 157.026149 -193.566545)
			(xy 157.080106 -193.580651) (xy 157.131435 -193.602463) (xy 157.179041 -193.631517) (xy 157.221909 -193.667192)
			(xy 157.259126 -193.708729) (xy 157.289899 -193.755242) (xy 157.313571 -193.805739) (xy 157.329639 -193.859146)
			(xy 157.337759 -193.914322) (xy 157.338268 -193.942208) (xy 157.337759 -193.970094) (xy 157.329639 -194.02527)
			(xy 157.313571 -194.078677) (xy 157.289899 -194.129174) (xy 157.259126 -194.175687) (xy 157.221909 -194.217224)
			(xy 157.179041 -194.252899) (xy 157.131435 -194.281953) (xy 157.080106 -194.303765) (xy 157.026149 -194.317871)
			(xy 156.970712 -194.323971) (xy 156.914978 -194.321934) (xy 156.860135 -194.311804) (xy 156.807351 -194.293797)
			(xy 156.757751 -194.268296) (xy 156.712393 -194.235845) (xy 156.672244 -194.197136) (xy 156.638158 -194.152993)
			(xy 156.610862 -194.104358) (xy 156.590939 -194.052267) (xy 156.578813 -193.99783) (xy 156.574742 -193.942208)
			(xy 142.431008 -193.942208) (xy 143.93799 -195.44919) (xy 155.16936 -195.44919) (xy 155.173431 -195.393568)
			(xy 155.185557 -195.339131) (xy 155.20548 -195.28704) (xy 155.232776 -195.238405) (xy 155.266862 -195.194262)
			(xy 155.307011 -195.155553) (xy 155.352369 -195.123102) (xy 155.401969 -195.097601) (xy 155.454753 -195.079594)
			(xy 155.509596 -195.069464) (xy 155.56533 -195.067427) (xy 155.620767 -195.073527) (xy 155.674724 -195.087633)
			(xy 155.726053 -195.109445) (xy 155.773659 -195.138499) (xy 155.816527 -195.174174) (xy 155.853744 -195.215711)
			(xy 155.884517 -195.262224) (xy 155.908189 -195.312721) (xy 155.924257 -195.366128) (xy 155.932377 -195.421304)
			(xy 155.932886 -195.44919) (xy 155.932377 -195.477076) (xy 155.924257 -195.532252) (xy 155.908189 -195.585659)
			(xy 155.884517 -195.636156) (xy 155.87984 -195.643225) (xy 157.352736 -195.643225) (xy 157.352736 -195.589927)
			(xy 157.360679 -195.537223) (xy 157.376389 -195.486293) (xy 157.399515 -195.438272) (xy 157.429539 -195.394235)
			(xy 157.465791 -195.355164) (xy 157.507462 -195.321933) (xy 157.55362 -195.295284) (xy 157.603234 -195.275812)
			(xy 157.655196 -195.263952) (xy 157.708346 -195.259969) (xy 157.761496 -195.263952) (xy 157.813458 -195.275812)
			(xy 157.863072 -195.295284) (xy 157.90923 -195.321933) (xy 157.950901 -195.355164) (xy 157.987153 -195.394235)
			(xy 158.017177 -195.438272) (xy 158.040303 -195.486293) (xy 158.056013 -195.537223) (xy 158.063956 -195.589927)
			(xy 158.064454 -195.616576) (xy 158.063956 -195.643225) (xy 159.562536 -195.643225) (xy 159.562536 -195.589927)
			(xy 159.570479 -195.537223) (xy 159.586189 -195.486293) (xy 159.609315 -195.438272) (xy 159.639339 -195.394235)
			(xy 159.675591 -195.355164) (xy 159.717262 -195.321933) (xy 159.76342 -195.295284) (xy 159.813034 -195.275812)
			(xy 159.864996 -195.263952) (xy 159.918146 -195.259969) (xy 159.971296 -195.263952) (xy 160.023258 -195.275812)
			(xy 160.072872 -195.295284) (xy 160.11903 -195.321933) (xy 160.160701 -195.355164) (xy 160.196953 -195.394235)
			(xy 160.226977 -195.438272) (xy 160.250103 -195.486293) (xy 160.265813 -195.537223) (xy 160.273756 -195.589927)
			(xy 160.274254 -195.616576) (xy 160.273756 -195.643225) (xy 160.265813 -195.695929) (xy 160.250103 -195.746859)
			(xy 160.226977 -195.79488) (xy 160.208791 -195.821554) (xy 162.162236 -195.821554) (xy 162.162236 -195.412614)
			(xy 162.162675 -195.402444) (xy 162.170455 -195.383649) (xy 162.184836 -195.369264) (xy 162.203628 -195.361478)
			(xy 162.213798 -195.361052) (xy 163.613338 -195.361052) (xy 163.6235 -195.361503) (xy 163.642273 -195.369292)
			(xy 163.656637 -195.383671) (xy 163.664408 -195.402452) (xy 163.6649 -195.412614) (xy 163.6649 -195.643225)
			(xy 164.896536 -195.643225) (xy 164.896536 -195.589927) (xy 164.904479 -195.537223) (xy 164.920189 -195.486293)
			(xy 164.943315 -195.438272) (xy 164.973339 -195.394235) (xy 165.009591 -195.355164) (xy 165.051262 -195.321933)
			(xy 165.09742 -195.295284) (xy 165.147034 -195.275812) (xy 165.198996 -195.263952) (xy 165.252146 -195.259969)
			(xy 165.305296 -195.263952) (xy 165.357258 -195.275812) (xy 165.406872 -195.295284) (xy 165.45303 -195.321933)
			(xy 165.494701 -195.355164) (xy 165.530953 -195.394235) (xy 165.560977 -195.438272) (xy 165.584103 -195.486293)
			(xy 165.599813 -195.537223) (xy 165.607756 -195.589927) (xy 165.608254 -195.616576) (xy 165.607756 -195.643225)
			(xy 167.106336 -195.643225) (xy 167.106336 -195.589927) (xy 167.114279 -195.537223) (xy 167.129989 -195.486293)
			(xy 167.153115 -195.438272) (xy 167.183139 -195.394235) (xy 167.219391 -195.355164) (xy 167.261062 -195.321933)
			(xy 167.30722 -195.295284) (xy 167.356834 -195.275812) (xy 167.408796 -195.263952) (xy 167.461946 -195.259969)
			(xy 167.515096 -195.263952) (xy 167.567058 -195.275812) (xy 167.616672 -195.295284) (xy 167.66283 -195.321933)
			(xy 167.704501 -195.355164) (xy 167.740753 -195.394235) (xy 167.770777 -195.438272) (xy 167.793903 -195.486293)
			(xy 167.809613 -195.537223) (xy 167.817556 -195.589927) (xy 167.818054 -195.616576) (xy 167.817556 -195.643225)
			(xy 167.809613 -195.695929) (xy 167.793903 -195.746859) (xy 167.770777 -195.79488) (xy 167.752591 -195.821554)
			(xy 169.706036 -195.821554) (xy 169.706036 -195.412614) (xy 169.706475 -195.402444) (xy 169.714255 -195.383649)
			(xy 169.728636 -195.369264) (xy 169.747428 -195.361478) (xy 169.757598 -195.361052) (xy 171.157138 -195.361052)
			(xy 171.1673 -195.361503) (xy 171.186073 -195.369292) (xy 171.200437 -195.383671) (xy 171.208208 -195.402452)
			(xy 171.2087 -195.412614) (xy 171.2087 -195.643225) (xy 172.440336 -195.643225) (xy 172.440336 -195.589927)
			(xy 172.448279 -195.537223) (xy 172.463989 -195.486293) (xy 172.487115 -195.438272) (xy 172.517139 -195.394235)
			(xy 172.553391 -195.355164) (xy 172.595062 -195.321933) (xy 172.64122 -195.295284) (xy 172.690834 -195.275812)
			(xy 172.742796 -195.263952) (xy 172.795946 -195.259969) (xy 172.849096 -195.263952) (xy 172.901058 -195.275812)
			(xy 172.950672 -195.295284) (xy 172.99683 -195.321933) (xy 173.038501 -195.355164) (xy 173.074753 -195.394235)
			(xy 173.104777 -195.438272) (xy 173.127903 -195.486293) (xy 173.143613 -195.537223) (xy 173.151556 -195.589927)
			(xy 173.152054 -195.616576) (xy 173.151556 -195.643225) (xy 174.650136 -195.643225) (xy 174.650136 -195.589927)
			(xy 174.658079 -195.537223) (xy 174.673789 -195.486293) (xy 174.696915 -195.438272) (xy 174.726939 -195.394235)
			(xy 174.763191 -195.355164) (xy 174.804862 -195.321933) (xy 174.85102 -195.295284) (xy 174.900634 -195.275812)
			(xy 174.952596 -195.263952) (xy 175.005746 -195.259969) (xy 175.058896 -195.263952) (xy 175.110858 -195.275812)
			(xy 175.160472 -195.295284) (xy 175.20663 -195.321933) (xy 175.248301 -195.355164) (xy 175.284553 -195.394235)
			(xy 175.314577 -195.438272) (xy 175.337703 -195.486293) (xy 175.353413 -195.537223) (xy 175.361356 -195.589927)
			(xy 175.361854 -195.616576) (xy 175.361854 -195.6166) (xy 176.539344 -195.6166) (xy 176.543328 -195.563442)
			(xy 176.55519 -195.511471) (xy 176.574666 -195.461849) (xy 176.60132 -195.415684) (xy 176.634557 -195.374007)
			(xy 176.673635 -195.33775) (xy 176.71768 -195.307722) (xy 176.765709 -195.284594) (xy 176.816648 -195.268883)
			(xy 176.86936 -195.26094) (xy 176.896014 -195.260468) (xy 176.92335 -195.260954) (xy 176.977378 -195.269318)
			(xy 177.029492 -195.285847) (xy 177.078464 -195.310153) (xy 177.123142 -195.341663) (xy 177.143156 -195.36029)
			(xy 177.153544 -195.369723) (xy 177.178278 -195.382954) (xy 177.205677 -195.388968) (xy 177.233679 -195.387313)
			(xy 177.260179 -195.378113) (xy 177.271934 -195.37045) (xy 177.278539 -195.366163) (xy 177.293531 -195.361373)
			(xy 177.301398 -195.361052) (xy 178.700938 -195.361052) (xy 178.7111 -195.361503) (xy 178.729873 -195.369292)
			(xy 178.744237 -195.383671) (xy 178.752008 -195.402452) (xy 178.7525 -195.412614) (xy 178.7525 -195.643225)
			(xy 179.984136 -195.643225) (xy 179.984136 -195.589927) (xy 179.992079 -195.537223) (xy 180.007789 -195.486293)
			(xy 180.030915 -195.438272) (xy 180.060939 -195.394235) (xy 180.097191 -195.355164) (xy 180.138862 -195.321933)
			(xy 180.18502 -195.295284) (xy 180.234634 -195.275812) (xy 180.286596 -195.263952) (xy 180.339746 -195.259969)
			(xy 180.392896 -195.263952) (xy 180.444858 -195.275812) (xy 180.494472 -195.295284) (xy 180.54063 -195.321933)
			(xy 180.582301 -195.355164) (xy 180.618553 -195.394235) (xy 180.648577 -195.438272) (xy 180.671703 -195.486293)
			(xy 180.687413 -195.537223) (xy 180.695356 -195.589927) (xy 180.695854 -195.616576) (xy 180.695356 -195.643225)
			(xy 182.193936 -195.643225) (xy 182.193936 -195.589927) (xy 182.201879 -195.537223) (xy 182.217589 -195.486293)
			(xy 182.240715 -195.438272) (xy 182.270739 -195.394235) (xy 182.306991 -195.355164) (xy 182.348662 -195.321933)
			(xy 182.39482 -195.295284) (xy 182.444434 -195.275812) (xy 182.496396 -195.263952) (xy 182.549546 -195.259969)
			(xy 182.602696 -195.263952) (xy 182.654658 -195.275812) (xy 182.704272 -195.295284) (xy 182.75043 -195.321933)
			(xy 182.792101 -195.355164) (xy 182.828353 -195.394235) (xy 182.858377 -195.438272) (xy 182.881503 -195.486293)
			(xy 182.897213 -195.537223) (xy 182.905156 -195.589927) (xy 182.905654 -195.616576) (xy 182.905156 -195.643225)
			(xy 182.897213 -195.695929) (xy 182.881503 -195.746859) (xy 182.858377 -195.79488) (xy 182.840191 -195.821554)
			(xy 184.793636 -195.821554) (xy 184.793636 -195.412614) (xy 184.794075 -195.402444) (xy 184.801855 -195.383649)
			(xy 184.816236 -195.369264) (xy 184.835028 -195.361478) (xy 184.845198 -195.361052) (xy 186.244738 -195.361052)
			(xy 186.2549 -195.361503) (xy 186.273673 -195.369292) (xy 186.288037 -195.383671) (xy 186.295808 -195.402452)
			(xy 186.2963 -195.412614) (xy 186.2963 -195.643225) (xy 187.527936 -195.643225) (xy 187.527936 -195.589927)
			(xy 187.535879 -195.537223) (xy 187.551589 -195.486293) (xy 187.574715 -195.438272) (xy 187.604739 -195.394235)
			(xy 187.640991 -195.355164) (xy 187.682662 -195.321933) (xy 187.72882 -195.295284) (xy 187.778434 -195.275812)
			(xy 187.830396 -195.263952) (xy 187.883546 -195.259969) (xy 187.936696 -195.263952) (xy 187.988658 -195.275812)
			(xy 188.038272 -195.295284) (xy 188.08443 -195.321933) (xy 188.126101 -195.355164) (xy 188.162353 -195.394235)
			(xy 188.192377 -195.438272) (xy 188.215503 -195.486293) (xy 188.231213 -195.537223) (xy 188.239156 -195.589927)
			(xy 188.239654 -195.616576) (xy 188.239156 -195.643225) (xy 189.737736 -195.643225) (xy 189.737736 -195.589927)
			(xy 189.745679 -195.537223) (xy 189.761389 -195.486293) (xy 189.784515 -195.438272) (xy 189.814539 -195.394235)
			(xy 189.850791 -195.355164) (xy 189.892462 -195.321933) (xy 189.93862 -195.295284) (xy 189.988234 -195.275812)
			(xy 190.040196 -195.263952) (xy 190.093346 -195.259969) (xy 190.146496 -195.263952) (xy 190.198458 -195.275812)
			(xy 190.248072 -195.295284) (xy 190.29423 -195.321933) (xy 190.335901 -195.355164) (xy 190.372153 -195.394235)
			(xy 190.402177 -195.438272) (xy 190.425303 -195.486293) (xy 190.441013 -195.537223) (xy 190.448956 -195.589927)
			(xy 190.449454 -195.616576) (xy 190.449454 -195.6166) (xy 191.626944 -195.6166) (xy 191.630928 -195.563442)
			(xy 191.64279 -195.511471) (xy 191.662266 -195.461849) (xy 191.68892 -195.415684) (xy 191.722157 -195.374007)
			(xy 191.761235 -195.33775) (xy 191.80528 -195.307722) (xy 191.853309 -195.284594) (xy 191.904248 -195.268883)
			(xy 191.95696 -195.26094) (xy 191.983614 -195.260468) (xy 192.01095 -195.260954) (xy 192.064978 -195.269318)
			(xy 192.117092 -195.285847) (xy 192.166064 -195.310153) (xy 192.210742 -195.341663) (xy 192.230756 -195.36029)
			(xy 192.241144 -195.369723) (xy 192.265878 -195.382954) (xy 192.293277 -195.388968) (xy 192.321279 -195.387313)
			(xy 192.347779 -195.378113) (xy 192.359534 -195.37045) (xy 192.366139 -195.366163) (xy 192.381131 -195.361373)
			(xy 192.388998 -195.361052) (xy 193.788538 -195.361052) (xy 193.7987 -195.361503) (xy 193.817473 -195.369292)
			(xy 193.831837 -195.383671) (xy 193.839608 -195.402452) (xy 193.8401 -195.412614) (xy 193.8401 -195.643225)
			(xy 195.071736 -195.643225) (xy 195.071736 -195.589927) (xy 195.079679 -195.537223) (xy 195.095389 -195.486293)
			(xy 195.118515 -195.438272) (xy 195.148539 -195.394235) (xy 195.184791 -195.355164) (xy 195.226462 -195.321933)
			(xy 195.27262 -195.295284) (xy 195.322234 -195.275812) (xy 195.374196 -195.263952) (xy 195.427346 -195.259969)
			(xy 195.480496 -195.263952) (xy 195.532458 -195.275812) (xy 195.582072 -195.295284) (xy 195.62823 -195.321933)
			(xy 195.669901 -195.355164) (xy 195.706153 -195.394235) (xy 195.736177 -195.438272) (xy 195.759303 -195.486293)
			(xy 195.775013 -195.537223) (xy 195.782956 -195.589927) (xy 195.783454 -195.616576) (xy 195.782956 -195.643225)
			(xy 197.281536 -195.643225) (xy 197.281536 -195.589927) (xy 197.289479 -195.537223) (xy 197.305189 -195.486293)
			(xy 197.328315 -195.438272) (xy 197.358339 -195.394235) (xy 197.394591 -195.355164) (xy 197.436262 -195.321933)
			(xy 197.48242 -195.295284) (xy 197.532034 -195.275812) (xy 197.583996 -195.263952) (xy 197.637146 -195.259969)
			(xy 197.690296 -195.263952) (xy 197.742258 -195.275812) (xy 197.791872 -195.295284) (xy 197.83803 -195.321933)
			(xy 197.879701 -195.355164) (xy 197.915953 -195.394235) (xy 197.945977 -195.438272) (xy 197.969103 -195.486293)
			(xy 197.984813 -195.537223) (xy 197.992756 -195.589927) (xy 197.993254 -195.616576) (xy 197.992756 -195.643225)
			(xy 197.984813 -195.695929) (xy 197.969103 -195.746859) (xy 197.945977 -195.79488) (xy 197.927791 -195.821554)
			(xy 199.881236 -195.821554) (xy 199.881236 -195.412614) (xy 199.881675 -195.402444) (xy 199.889455 -195.383649)
			(xy 199.903836 -195.369264) (xy 199.922628 -195.361478) (xy 199.932798 -195.361052) (xy 201.332338 -195.361052)
			(xy 201.3425 -195.361503) (xy 201.361273 -195.369292) (xy 201.375637 -195.383671) (xy 201.383408 -195.402452)
			(xy 201.3839 -195.412614) (xy 201.3839 -195.643225) (xy 202.615536 -195.643225) (xy 202.615536 -195.589927)
			(xy 202.623479 -195.537223) (xy 202.639189 -195.486293) (xy 202.662315 -195.438272) (xy 202.692339 -195.394235)
			(xy 202.728591 -195.355164) (xy 202.770262 -195.321933) (xy 202.81642 -195.295284) (xy 202.866034 -195.275812)
			(xy 202.917996 -195.263952) (xy 202.971146 -195.259969) (xy 203.024296 -195.263952) (xy 203.076258 -195.275812)
			(xy 203.125872 -195.295284) (xy 203.17203 -195.321933) (xy 203.213701 -195.355164) (xy 203.249953 -195.394235)
			(xy 203.279977 -195.438272) (xy 203.303103 -195.486293) (xy 203.318813 -195.537223) (xy 203.326756 -195.589927)
			(xy 203.327254 -195.616576) (xy 203.327254 -195.6166) (xy 204.824244 -195.6166) (xy 204.828228 -195.563439)
			(xy 204.840092 -195.511465) (xy 204.85957 -195.461841) (xy 204.886227 -195.415674) (xy 204.919468 -195.373996)
			(xy 204.958549 -195.337739) (xy 205.002599 -195.307711) (xy 205.050632 -195.284585) (xy 205.101575 -195.268877)
			(xy 205.154291 -195.260938) (xy 205.180946 -195.260468) (xy 205.206193 -195.260932) (xy 205.25618 -195.268065)
			(xy 205.30466 -195.282181) (xy 205.350662 -195.302999) (xy 205.393266 -195.330101) (xy 205.431618 -195.362944)
			(xy 205.464951 -195.400872) (xy 205.479142 -195.421758) (xy 205.487172 -195.433346) (xy 205.508422 -195.451863)
			(xy 205.533926 -195.463861) (xy 205.561739 -195.468425) (xy 205.58974 -195.465207) (xy 205.615793 -195.454453)
			(xy 205.637911 -195.436982) (xy 205.646528 -195.425822) (xy 205.661967 -195.405171) (xy 205.697498 -195.367806)
			(xy 205.737738 -195.335567) (xy 205.781952 -195.309041) (xy 205.829337 -195.288712) (xy 205.879028 -195.27495)
			(xy 205.930119 -195.268006) (xy 205.9559 -195.26758) (xy 205.98315 -195.26809) (xy 206.037096 -195.275847)
			(xy 206.089389 -195.291201) (xy 206.138965 -195.313842) (xy 206.184814 -195.343307) (xy 206.226003 -195.378997)
			(xy 206.261693 -195.420186) (xy 206.291158 -195.466035) (xy 206.313799 -195.515611) (xy 206.329153 -195.567904)
			(xy 206.336155 -195.6166) (xy 206.714544 -195.6166) (xy 206.718528 -195.563442) (xy 206.73039 -195.511471)
			(xy 206.749866 -195.461849) (xy 206.77652 -195.415684) (xy 206.809757 -195.374007) (xy 206.848835 -195.33775)
			(xy 206.89288 -195.307722) (xy 206.940909 -195.284594) (xy 206.991848 -195.268883) (xy 207.04456 -195.26094)
			(xy 207.071214 -195.260468) (xy 207.09855 -195.260954) (xy 207.152578 -195.269318) (xy 207.204692 -195.285847)
			(xy 207.253664 -195.310153) (xy 207.298342 -195.341663) (xy 207.318356 -195.36029) (xy 207.328744 -195.369723)
			(xy 207.353478 -195.382954) (xy 207.380877 -195.388968) (xy 207.408879 -195.387313) (xy 207.435379 -195.378113)
			(xy 207.447134 -195.37045) (xy 207.453739 -195.366163) (xy 207.468731 -195.361373) (xy 207.476598 -195.361052)
			(xy 208.876138 -195.361052) (xy 208.8863 -195.361503) (xy 208.905073 -195.369292) (xy 208.919437 -195.383671)
			(xy 208.927208 -195.402452) (xy 208.9277 -195.412614) (xy 208.9277 -195.643225) (xy 210.159336 -195.643225)
			(xy 210.159336 -195.589927) (xy 210.167279 -195.537223) (xy 210.182989 -195.486293) (xy 210.206115 -195.438272)
			(xy 210.236139 -195.394235) (xy 210.272391 -195.355164) (xy 210.314062 -195.321933) (xy 210.36022 -195.295284)
			(xy 210.409834 -195.275812) (xy 210.461796 -195.263952) (xy 210.514946 -195.259969) (xy 210.568096 -195.263952)
			(xy 210.620058 -195.275812) (xy 210.669672 -195.295284) (xy 210.71583 -195.321933) (xy 210.757501 -195.355164)
			(xy 210.793753 -195.394235) (xy 210.823777 -195.438272) (xy 210.846903 -195.486293) (xy 210.862613 -195.537223)
			(xy 210.870556 -195.589927) (xy 210.871054 -195.616576) (xy 210.870556 -195.643225) (xy 212.369136 -195.643225)
			(xy 212.369136 -195.589927) (xy 212.377079 -195.537223) (xy 212.392789 -195.486293) (xy 212.415915 -195.438272)
			(xy 212.445939 -195.394235) (xy 212.482191 -195.355164) (xy 212.523862 -195.321933) (xy 212.57002 -195.295284)
			(xy 212.619634 -195.275812) (xy 212.671596 -195.263952) (xy 212.724746 -195.259969) (xy 212.777896 -195.263952)
			(xy 212.829858 -195.275812) (xy 212.879472 -195.295284) (xy 212.92563 -195.321933) (xy 212.967301 -195.355164)
			(xy 213.003553 -195.394235) (xy 213.033577 -195.438272) (xy 213.056703 -195.486293) (xy 213.072413 -195.537223)
			(xy 213.080356 -195.589927) (xy 213.080854 -195.616576) (xy 213.080356 -195.643225) (xy 213.072413 -195.695929)
			(xy 213.056703 -195.746859) (xy 213.033577 -195.79488) (xy 213.003553 -195.838917) (xy 212.967301 -195.877988)
			(xy 212.92563 -195.911219) (xy 212.879472 -195.937868) (xy 212.829858 -195.95734) (xy 212.777896 -195.9692)
			(xy 212.724746 -195.973184) (xy 212.671596 -195.9692) (xy 212.619634 -195.95734) (xy 212.57002 -195.937868)
			(xy 212.523862 -195.911219) (xy 212.482191 -195.877988) (xy 212.445939 -195.838917) (xy 212.415915 -195.79488)
			(xy 212.392789 -195.746859) (xy 212.377079 -195.695929) (xy 212.369136 -195.643225) (xy 210.870556 -195.643225)
			(xy 210.862613 -195.695929) (xy 210.846903 -195.746859) (xy 210.823777 -195.79488) (xy 210.793753 -195.838917)
			(xy 210.757501 -195.877988) (xy 210.71583 -195.911219) (xy 210.669672 -195.937868) (xy 210.620058 -195.95734)
			(xy 210.568096 -195.9692) (xy 210.514946 -195.973184) (xy 210.461796 -195.9692) (xy 210.409834 -195.95734)
			(xy 210.36022 -195.937868) (xy 210.314062 -195.911219) (xy 210.272391 -195.877988) (xy 210.236139 -195.838917)
			(xy 210.206115 -195.79488) (xy 210.182989 -195.746859) (xy 210.167279 -195.695929) (xy 210.159336 -195.643225)
			(xy 208.9277 -195.643225) (xy 208.9277 -195.821554) (xy 208.927199 -195.831718) (xy 208.919437 -195.850504)
			(xy 208.905075 -195.864889) (xy 208.886301 -195.872683) (xy 208.876138 -195.873116) (xy 207.476598 -195.873116)
			(xy 207.468649 -195.87275) (xy 207.453521 -195.867846) (xy 207.44688 -195.863464) (xy 207.435109 -195.855762)
			(xy 207.408592 -195.846417) (xy 207.380531 -195.844673) (xy 207.353061 -195.850662) (xy 207.328273 -195.863929)
			(xy 207.317848 -195.87337) (xy 207.29784 -195.891895) (xy 207.253224 -195.923237) (xy 207.204351 -195.94741)
			(xy 207.152363 -195.963846) (xy 207.098476 -195.972163) (xy 207.071214 -195.972684) (xy 207.04456 -195.97226)
			(xy 206.991848 -195.964317) (xy 206.940909 -195.948606) (xy 206.89288 -195.925478) (xy 206.848835 -195.89545)
			(xy 206.809757 -195.859193) (xy 206.77652 -195.817516) (xy 206.749866 -195.771351) (xy 206.73039 -195.721729)
			(xy 206.718528 -195.669758) (xy 206.714544 -195.6166) (xy 206.336155 -195.6166) (xy 206.33691 -195.62185)
			(xy 206.33691 -195.67635) (xy 206.329153 -195.730296) (xy 206.313799 -195.782589) (xy 206.291158 -195.832165)
			(xy 206.261693 -195.878014) (xy 206.226003 -195.919203) (xy 206.184814 -195.954893) (xy 206.138965 -195.984358)
			(xy 206.089389 -196.006999) (xy 206.037096 -196.022353) (xy 205.98315 -196.03011) (xy 205.9559 -196.030596)
			(xy 205.927838 -196.030088) (xy 205.872323 -196.021852) (xy 205.818612 -196.005574) (xy 205.767864 -195.981605)
			(xy 205.721175 -195.95046) (xy 205.679552 -195.912813) (xy 205.643892 -195.869475) (xy 205.629002 -195.845684)
			(xy 205.621298 -195.83389) (xy 205.600745 -195.814648) (xy 205.575717 -195.80175) (xy 205.548119 -195.796177)
			(xy 205.520048 -195.798353) (xy 205.493638 -195.808112) (xy 205.470898 -195.824713) (xy 205.46187 -195.835524)
			(xy 205.444892 -195.856503) (xy 205.405664 -195.893568) (xy 205.361294 -195.92429) (xy 205.312796 -195.947967)
			(xy 205.261282 -195.964056) (xy 205.20793 -195.97219) (xy 205.180946 -195.972684) (xy 205.154291 -195.972262)
			(xy 205.101575 -195.964323) (xy 205.050632 -195.948615) (xy 205.002599 -195.925489) (xy 204.958549 -195.895461)
			(xy 204.919468 -195.859204) (xy 204.886227 -195.817526) (xy 204.85957 -195.771359) (xy 204.840092 -195.721735)
			(xy 204.828228 -195.669761) (xy 204.824244 -195.6166) (xy 203.327254 -195.6166) (xy 203.326756 -195.643225)
			(xy 203.318813 -195.695929) (xy 203.303103 -195.746859) (xy 203.279977 -195.79488) (xy 203.249953 -195.838917)
			(xy 203.213701 -195.877988) (xy 203.17203 -195.911219) (xy 203.125872 -195.937868) (xy 203.076258 -195.95734)
			(xy 203.024296 -195.9692) (xy 202.971146 -195.973184) (xy 202.917996 -195.9692) (xy 202.866034 -195.95734)
			(xy 202.81642 -195.937868) (xy 202.770262 -195.911219) (xy 202.728591 -195.877988) (xy 202.692339 -195.838917)
			(xy 202.662315 -195.79488) (xy 202.639189 -195.746859) (xy 202.623479 -195.695929) (xy 202.615536 -195.643225)
			(xy 201.3839 -195.643225) (xy 201.3839 -195.821554) (xy 201.383399 -195.831718) (xy 201.375637 -195.850504)
			(xy 201.361275 -195.864889) (xy 201.342501 -195.872683) (xy 201.332338 -195.873116) (xy 199.932798 -195.873116)
			(xy 199.922621 -195.872737) (xy 199.903817 -195.864942) (xy 199.889431 -195.850543) (xy 199.881654 -195.831732)
			(xy 199.881236 -195.821554) (xy 197.927791 -195.821554) (xy 197.915953 -195.838917) (xy 197.879701 -195.877988)
			(xy 197.83803 -195.911219) (xy 197.791872 -195.937868) (xy 197.742258 -195.95734) (xy 197.690296 -195.9692)
			(xy 197.637146 -195.973184) (xy 197.583996 -195.9692) (xy 197.532034 -195.95734) (xy 197.48242 -195.937868)
			(xy 197.436262 -195.911219) (xy 197.394591 -195.877988) (xy 197.358339 -195.838917) (xy 197.328315 -195.79488)
			(xy 197.305189 -195.746859) (xy 197.289479 -195.695929) (xy 197.281536 -195.643225) (xy 195.782956 -195.643225)
			(xy 195.775013 -195.695929) (xy 195.759303 -195.746859) (xy 195.736177 -195.79488) (xy 195.706153 -195.838917)
			(xy 195.669901 -195.877988) (xy 195.62823 -195.911219) (xy 195.582072 -195.937868) (xy 195.532458 -195.95734)
			(xy 195.480496 -195.9692) (xy 195.427346 -195.973184) (xy 195.374196 -195.9692) (xy 195.322234 -195.95734)
			(xy 195.27262 -195.937868) (xy 195.226462 -195.911219) (xy 195.184791 -195.877988) (xy 195.148539 -195.838917)
			(xy 195.118515 -195.79488) (xy 195.095389 -195.746859) (xy 195.079679 -195.695929) (xy 195.071736 -195.643225)
			(xy 193.8401 -195.643225) (xy 193.8401 -195.821554) (xy 193.839599 -195.831718) (xy 193.831837 -195.850504)
			(xy 193.817475 -195.864889) (xy 193.798701 -195.872683) (xy 193.788538 -195.873116) (xy 192.388998 -195.873116)
			(xy 192.381049 -195.87275) (xy 192.365921 -195.867846) (xy 192.35928 -195.863464) (xy 192.347509 -195.855762)
			(xy 192.320992 -195.846417) (xy 192.292931 -195.844673) (xy 192.265461 -195.850662) (xy 192.240673 -195.863929)
			(xy 192.230248 -195.87337) (xy 192.21024 -195.891895) (xy 192.165624 -195.923237) (xy 192.116751 -195.94741)
			(xy 192.064763 -195.963846) (xy 192.010876 -195.972163) (xy 191.983614 -195.972684) (xy 191.95696 -195.97226)
			(xy 191.904248 -195.964317) (xy 191.853309 -195.948606) (xy 191.80528 -195.925478) (xy 191.761235 -195.89545)
			(xy 191.722157 -195.859193) (xy 191.68892 -195.817516) (xy 191.662266 -195.771351) (xy 191.64279 -195.721729)
			(xy 191.630928 -195.669758) (xy 191.626944 -195.6166) (xy 190.449454 -195.6166) (xy 190.448956 -195.643225)
			(xy 190.441013 -195.695929) (xy 190.425303 -195.746859) (xy 190.402177 -195.79488) (xy 190.372153 -195.838917)
			(xy 190.335901 -195.877988) (xy 190.29423 -195.911219) (xy 190.248072 -195.937868) (xy 190.198458 -195.95734)
			(xy 190.146496 -195.9692) (xy 190.093346 -195.973184) (xy 190.040196 -195.9692) (xy 189.988234 -195.95734)
			(xy 189.93862 -195.937868) (xy 189.892462 -195.911219) (xy 189.850791 -195.877988) (xy 189.814539 -195.838917)
			(xy 189.784515 -195.79488) (xy 189.761389 -195.746859) (xy 189.745679 -195.695929) (xy 189.737736 -195.643225)
			(xy 188.239156 -195.643225) (xy 188.231213 -195.695929) (xy 188.215503 -195.746859) (xy 188.192377 -195.79488)
			(xy 188.162353 -195.838917) (xy 188.126101 -195.877988) (xy 188.08443 -195.911219) (xy 188.038272 -195.937868)
			(xy 187.988658 -195.95734) (xy 187.936696 -195.9692) (xy 187.883546 -195.973184) (xy 187.830396 -195.9692)
			(xy 187.778434 -195.95734) (xy 187.72882 -195.937868) (xy 187.682662 -195.911219) (xy 187.640991 -195.877988)
			(xy 187.604739 -195.838917) (xy 187.574715 -195.79488) (xy 187.551589 -195.746859) (xy 187.535879 -195.695929)
			(xy 187.527936 -195.643225) (xy 186.2963 -195.643225) (xy 186.2963 -195.821554) (xy 186.295799 -195.831718)
			(xy 186.288037 -195.850504) (xy 186.273675 -195.864889) (xy 186.254901 -195.872683) (xy 186.244738 -195.873116)
			(xy 184.845198 -195.873116) (xy 184.835021 -195.872737) (xy 184.816217 -195.864942) (xy 184.801831 -195.850543)
			(xy 184.794054 -195.831732) (xy 184.793636 -195.821554) (xy 182.840191 -195.821554) (xy 182.828353 -195.838917)
			(xy 182.792101 -195.877988) (xy 182.75043 -195.911219) (xy 182.704272 -195.937868) (xy 182.654658 -195.95734)
			(xy 182.602696 -195.9692) (xy 182.549546 -195.973184) (xy 182.496396 -195.9692) (xy 182.444434 -195.95734)
			(xy 182.39482 -195.937868) (xy 182.348662 -195.911219) (xy 182.306991 -195.877988) (xy 182.270739 -195.838917)
			(xy 182.240715 -195.79488) (xy 182.217589 -195.746859) (xy 182.201879 -195.695929) (xy 182.193936 -195.643225)
			(xy 180.695356 -195.643225) (xy 180.687413 -195.695929) (xy 180.671703 -195.746859) (xy 180.648577 -195.79488)
			(xy 180.618553 -195.838917) (xy 180.582301 -195.877988) (xy 180.54063 -195.911219) (xy 180.494472 -195.937868)
			(xy 180.444858 -195.95734) (xy 180.392896 -195.9692) (xy 180.339746 -195.973184) (xy 180.286596 -195.9692)
			(xy 180.234634 -195.95734) (xy 180.18502 -195.937868) (xy 180.138862 -195.911219) (xy 180.097191 -195.877988)
			(xy 180.060939 -195.838917) (xy 180.030915 -195.79488) (xy 180.007789 -195.746859) (xy 179.992079 -195.695929)
			(xy 179.984136 -195.643225) (xy 178.7525 -195.643225) (xy 178.7525 -195.821554) (xy 178.751999 -195.831718)
			(xy 178.744237 -195.850504) (xy 178.729875 -195.864889) (xy 178.711101 -195.872683) (xy 178.700938 -195.873116)
			(xy 177.301398 -195.873116) (xy 177.293449 -195.87275) (xy 177.278321 -195.867846) (xy 177.27168 -195.863464)
			(xy 177.259909 -195.855762) (xy 177.233392 -195.846417) (xy 177.205331 -195.844673) (xy 177.177861 -195.850662)
			(xy 177.153073 -195.863929) (xy 177.142648 -195.87337) (xy 177.12264 -195.891895) (xy 177.078024 -195.923237)
			(xy 177.029151 -195.94741) (xy 176.977163 -195.963846) (xy 176.923276 -195.972163) (xy 176.896014 -195.972684)
			(xy 176.86936 -195.97226) (xy 176.816648 -195.964317) (xy 176.765709 -195.948606) (xy 176.71768 -195.925478)
			(xy 176.673635 -195.89545) (xy 176.634557 -195.859193) (xy 176.60132 -195.817516) (xy 176.574666 -195.771351)
			(xy 176.55519 -195.721729) (xy 176.543328 -195.669758) (xy 176.539344 -195.6166) (xy 175.361854 -195.6166)
			(xy 175.361356 -195.643225) (xy 175.353413 -195.695929) (xy 175.337703 -195.746859) (xy 175.314577 -195.79488)
			(xy 175.284553 -195.838917) (xy 175.248301 -195.877988) (xy 175.20663 -195.911219) (xy 175.160472 -195.937868)
			(xy 175.110858 -195.95734) (xy 175.058896 -195.9692) (xy 175.005746 -195.973184) (xy 174.952596 -195.9692)
			(xy 174.900634 -195.95734) (xy 174.85102 -195.937868) (xy 174.804862 -195.911219) (xy 174.763191 -195.877988)
			(xy 174.726939 -195.838917) (xy 174.696915 -195.79488) (xy 174.673789 -195.746859) (xy 174.658079 -195.695929)
			(xy 174.650136 -195.643225) (xy 173.151556 -195.643225) (xy 173.143613 -195.695929) (xy 173.127903 -195.746859)
			(xy 173.104777 -195.79488) (xy 173.074753 -195.838917) (xy 173.038501 -195.877988) (xy 172.99683 -195.911219)
			(xy 172.950672 -195.937868) (xy 172.901058 -195.95734) (xy 172.849096 -195.9692) (xy 172.795946 -195.973184)
			(xy 172.742796 -195.9692) (xy 172.690834 -195.95734) (xy 172.64122 -195.937868) (xy 172.595062 -195.911219)
			(xy 172.553391 -195.877988) (xy 172.517139 -195.838917) (xy 172.487115 -195.79488) (xy 172.463989 -195.746859)
			(xy 172.448279 -195.695929) (xy 172.440336 -195.643225) (xy 171.2087 -195.643225) (xy 171.2087 -195.821554)
			(xy 171.208199 -195.831718) (xy 171.200437 -195.850504) (xy 171.186075 -195.864889) (xy 171.167301 -195.872683)
			(xy 171.157138 -195.873116) (xy 169.757598 -195.873116) (xy 169.747421 -195.872737) (xy 169.728617 -195.864942)
			(xy 169.714231 -195.850543) (xy 169.706454 -195.831732) (xy 169.706036 -195.821554) (xy 167.752591 -195.821554)
			(xy 167.740753 -195.838917) (xy 167.704501 -195.877988) (xy 167.66283 -195.911219) (xy 167.616672 -195.937868)
			(xy 167.567058 -195.95734) (xy 167.515096 -195.9692) (xy 167.461946 -195.973184) (xy 167.408796 -195.9692)
			(xy 167.356834 -195.95734) (xy 167.30722 -195.937868) (xy 167.261062 -195.911219) (xy 167.219391 -195.877988)
			(xy 167.183139 -195.838917) (xy 167.153115 -195.79488) (xy 167.129989 -195.746859) (xy 167.114279 -195.695929)
			(xy 167.106336 -195.643225) (xy 165.607756 -195.643225) (xy 165.599813 -195.695929) (xy 165.584103 -195.746859)
			(xy 165.560977 -195.79488) (xy 165.530953 -195.838917) (xy 165.494701 -195.877988) (xy 165.45303 -195.911219)
			(xy 165.406872 -195.937868) (xy 165.357258 -195.95734) (xy 165.305296 -195.9692) (xy 165.252146 -195.973184)
			(xy 165.198996 -195.9692) (xy 165.147034 -195.95734) (xy 165.09742 -195.937868) (xy 165.051262 -195.911219)
			(xy 165.009591 -195.877988) (xy 164.973339 -195.838917) (xy 164.943315 -195.79488) (xy 164.920189 -195.746859)
			(xy 164.904479 -195.695929) (xy 164.896536 -195.643225) (xy 163.6649 -195.643225) (xy 163.6649 -195.821554)
			(xy 163.664399 -195.831718) (xy 163.656637 -195.850504) (xy 163.642275 -195.864889) (xy 163.623501 -195.872683)
			(xy 163.613338 -195.873116) (xy 162.213798 -195.873116) (xy 162.203621 -195.872737) (xy 162.184817 -195.864942)
			(xy 162.170431 -195.850543) (xy 162.162654 -195.831732) (xy 162.162236 -195.821554) (xy 160.208791 -195.821554)
			(xy 160.196953 -195.838917) (xy 160.160701 -195.877988) (xy 160.11903 -195.911219) (xy 160.072872 -195.937868)
			(xy 160.023258 -195.95734) (xy 159.971296 -195.9692) (xy 159.918146 -195.973184) (xy 159.864996 -195.9692)
			(xy 159.813034 -195.95734) (xy 159.76342 -195.937868) (xy 159.717262 -195.911219) (xy 159.675591 -195.877988)
			(xy 159.639339 -195.838917) (xy 159.609315 -195.79488) (xy 159.586189 -195.746859) (xy 159.570479 -195.695929)
			(xy 159.562536 -195.643225) (xy 158.063956 -195.643225) (xy 158.056013 -195.695929) (xy 158.040303 -195.746859)
			(xy 158.017177 -195.79488) (xy 157.987153 -195.838917) (xy 157.950901 -195.877988) (xy 157.90923 -195.911219)
			(xy 157.863072 -195.937868) (xy 157.813458 -195.95734) (xy 157.761496 -195.9692) (xy 157.708346 -195.973184)
			(xy 157.655196 -195.9692) (xy 157.603234 -195.95734) (xy 157.55362 -195.937868) (xy 157.507462 -195.911219)
			(xy 157.465791 -195.877988) (xy 157.429539 -195.838917) (xy 157.399515 -195.79488) (xy 157.376389 -195.746859)
			(xy 157.360679 -195.695929) (xy 157.352736 -195.643225) (xy 155.87984 -195.643225) (xy 155.853744 -195.682669)
			(xy 155.816527 -195.724206) (xy 155.773659 -195.759881) (xy 155.726053 -195.788935) (xy 155.674724 -195.810747)
			(xy 155.620767 -195.824853) (xy 155.56533 -195.830953) (xy 155.509596 -195.828916) (xy 155.454753 -195.818786)
			(xy 155.401969 -195.800779) (xy 155.352369 -195.775278) (xy 155.307011 -195.742827) (xy 155.266862 -195.704118)
			(xy 155.232776 -195.659975) (xy 155.20548 -195.61134) (xy 155.185557 -195.559249) (xy 155.173431 -195.504812)
			(xy 155.16936 -195.44919) (xy 143.93799 -195.44919) (xy 145.160238 -196.671438) (xy 158.062168 -196.671438)
			(xy 158.062168 -196.262498) (xy 158.062563 -196.252323) (xy 158.070354 -196.233522) (xy 158.084749 -196.219136)
			(xy 158.103554 -196.211357) (xy 158.11373 -196.210936) (xy 159.51327 -196.210936) (xy 159.523439 -196.211389)
			(xy 159.542233 -196.219163) (xy 159.556619 -196.23354) (xy 159.564405 -196.252329) (xy 159.564832 -196.262498)
			(xy 159.564832 -196.493363) (xy 161.452804 -196.493363) (xy 161.452804 -196.440065) (xy 161.460747 -196.387361)
			(xy 161.476457 -196.336431) (xy 161.499583 -196.28841) (xy 161.529607 -196.244373) (xy 161.565859 -196.205302)
			(xy 161.60753 -196.172071) (xy 161.653688 -196.145422) (xy 161.703302 -196.12595) (xy 161.755264 -196.11409)
			(xy 161.808414 -196.110107) (xy 161.861564 -196.11409) (xy 161.913526 -196.12595) (xy 161.96314 -196.145422)
			(xy 162.009298 -196.172071) (xy 162.050969 -196.205302) (xy 162.087221 -196.244373) (xy 162.117245 -196.28841)
			(xy 162.140371 -196.336431) (xy 162.156081 -196.387361) (xy 162.164024 -196.440065) (xy 162.164522 -196.466714)
			(xy 162.164024 -196.493363) (xy 163.662604 -196.493363) (xy 163.662604 -196.440065) (xy 163.670547 -196.387361)
			(xy 163.686257 -196.336431) (xy 163.709383 -196.28841) (xy 163.739407 -196.244373) (xy 163.775659 -196.205302)
			(xy 163.81733 -196.172071) (xy 163.863488 -196.145422) (xy 163.913102 -196.12595) (xy 163.965064 -196.11409)
			(xy 164.018214 -196.110107) (xy 164.071364 -196.11409) (xy 164.123326 -196.12595) (xy 164.17294 -196.145422)
			(xy 164.219098 -196.172071) (xy 164.260769 -196.205302) (xy 164.297021 -196.244373) (xy 164.327045 -196.28841)
			(xy 164.350171 -196.336431) (xy 164.365881 -196.387361) (xy 164.373824 -196.440065) (xy 164.374322 -196.466714)
			(xy 164.373824 -196.493363) (xy 164.365881 -196.546067) (xy 164.350171 -196.596997) (xy 164.327045 -196.645018)
			(xy 164.309032 -196.671438) (xy 165.605968 -196.671438) (xy 165.605968 -196.262498) (xy 165.606363 -196.252323)
			(xy 165.614154 -196.233522) (xy 165.628549 -196.219136) (xy 165.647354 -196.211357) (xy 165.65753 -196.210936)
			(xy 167.05707 -196.210936) (xy 167.067239 -196.211389) (xy 167.086033 -196.219163) (xy 167.100419 -196.23354)
			(xy 167.108205 -196.252329) (xy 167.108632 -196.262498) (xy 167.108632 -196.493363) (xy 168.996604 -196.493363)
			(xy 168.996604 -196.440065) (xy 169.004547 -196.387361) (xy 169.020257 -196.336431) (xy 169.043383 -196.28841)
			(xy 169.073407 -196.244373) (xy 169.109659 -196.205302) (xy 169.15133 -196.172071) (xy 169.197488 -196.145422)
			(xy 169.247102 -196.12595) (xy 169.299064 -196.11409) (xy 169.352214 -196.110107) (xy 169.405364 -196.11409)
			(xy 169.457326 -196.12595) (xy 169.50694 -196.145422) (xy 169.553098 -196.172071) (xy 169.594769 -196.205302)
			(xy 169.631021 -196.244373) (xy 169.661045 -196.28841) (xy 169.684171 -196.336431) (xy 169.699881 -196.387361)
			(xy 169.707824 -196.440065) (xy 169.708322 -196.466714) (xy 169.707824 -196.493363) (xy 171.206404 -196.493363)
			(xy 171.206404 -196.440065) (xy 171.214347 -196.387361) (xy 171.230057 -196.336431) (xy 171.253183 -196.28841)
			(xy 171.283207 -196.244373) (xy 171.319459 -196.205302) (xy 171.36113 -196.172071) (xy 171.407288 -196.145422)
			(xy 171.456902 -196.12595) (xy 171.508864 -196.11409) (xy 171.562014 -196.110107) (xy 171.615164 -196.11409)
			(xy 171.667126 -196.12595) (xy 171.71674 -196.145422) (xy 171.762898 -196.172071) (xy 171.804569 -196.205302)
			(xy 171.840821 -196.244373) (xy 171.870845 -196.28841) (xy 171.893971 -196.336431) (xy 171.909681 -196.387361)
			(xy 171.917624 -196.440065) (xy 171.918122 -196.4667) (xy 172.439282 -196.4667) (xy 172.443266 -196.413545)
			(xy 172.455128 -196.361577) (xy 172.474604 -196.311957) (xy 172.501258 -196.265795) (xy 172.534495 -196.224122)
			(xy 172.573573 -196.187868) (xy 172.617618 -196.157844) (xy 172.665645 -196.134721) (xy 172.716584 -196.119014)
			(xy 172.769294 -196.111076) (xy 172.795946 -196.110606) (xy 172.823266 -196.111159) (xy 172.877266 -196.119489)
			(xy 172.929362 -196.135962) (xy 172.978334 -196.160193) (xy 173.023035 -196.191613) (xy 173.043088 -196.210174)
			(xy 173.053527 -196.219546) (xy 173.078243 -196.232785) (xy 173.105628 -196.238812) (xy 173.133619 -196.237172)
			(xy 173.160112 -196.227988) (xy 173.171866 -196.220334) (xy 173.178463 -196.216033) (xy 173.193461 -196.211253)
			(xy 173.20133 -196.210936) (xy 174.60087 -196.210936) (xy 174.611039 -196.211389) (xy 174.629833 -196.219163)
			(xy 174.644219 -196.23354) (xy 174.652005 -196.252329) (xy 174.652432 -196.262498) (xy 174.652432 -196.493363)
			(xy 176.540404 -196.493363) (xy 176.540404 -196.440065) (xy 176.548347 -196.387361) (xy 176.564057 -196.336431)
			(xy 176.587183 -196.28841) (xy 176.617207 -196.244373) (xy 176.653459 -196.205302) (xy 176.69513 -196.172071)
			(xy 176.741288 -196.145422) (xy 176.790902 -196.12595) (xy 176.842864 -196.11409) (xy 176.896014 -196.110107)
			(xy 176.949164 -196.11409) (xy 177.001126 -196.12595) (xy 177.05074 -196.145422) (xy 177.096898 -196.172071)
			(xy 177.138569 -196.205302) (xy 177.174821 -196.244373) (xy 177.204845 -196.28841) (xy 177.227971 -196.336431)
			(xy 177.243681 -196.387361) (xy 177.251624 -196.440065) (xy 177.252122 -196.466714) (xy 177.251624 -196.493363)
			(xy 178.750204 -196.493363) (xy 178.750204 -196.440065) (xy 178.758147 -196.387361) (xy 178.773857 -196.336431)
			(xy 178.796983 -196.28841) (xy 178.827007 -196.244373) (xy 178.863259 -196.205302) (xy 178.90493 -196.172071)
			(xy 178.951088 -196.145422) (xy 179.000702 -196.12595) (xy 179.052664 -196.11409) (xy 179.105814 -196.110107)
			(xy 179.158964 -196.11409) (xy 179.210926 -196.12595) (xy 179.26054 -196.145422) (xy 179.306698 -196.172071)
			(xy 179.348369 -196.205302) (xy 179.384621 -196.244373) (xy 179.414645 -196.28841) (xy 179.437771 -196.336431)
			(xy 179.453481 -196.387361) (xy 179.461424 -196.440065) (xy 179.461922 -196.466714) (xy 179.461424 -196.493363)
			(xy 179.453481 -196.546067) (xy 179.437771 -196.596997) (xy 179.414645 -196.645018) (xy 179.396632 -196.671438)
			(xy 180.693568 -196.671438) (xy 180.693568 -196.262498) (xy 180.693963 -196.252323) (xy 180.701754 -196.233522)
			(xy 180.716149 -196.219136) (xy 180.734954 -196.211357) (xy 180.74513 -196.210936) (xy 182.14467 -196.210936)
			(xy 182.154839 -196.211389) (xy 182.173633 -196.219163) (xy 182.188019 -196.23354) (xy 182.195805 -196.252329)
			(xy 182.196232 -196.262498) (xy 182.196232 -196.493363) (xy 184.084204 -196.493363) (xy 184.084204 -196.440065)
			(xy 184.092147 -196.387361) (xy 184.107857 -196.336431) (xy 184.130983 -196.28841) (xy 184.161007 -196.244373)
			(xy 184.197259 -196.205302) (xy 184.23893 -196.172071) (xy 184.285088 -196.145422) (xy 184.334702 -196.12595)
			(xy 184.386664 -196.11409) (xy 184.439814 -196.110107) (xy 184.492964 -196.11409) (xy 184.544926 -196.12595)
			(xy 184.59454 -196.145422) (xy 184.640698 -196.172071) (xy 184.682369 -196.205302) (xy 184.718621 -196.244373)
			(xy 184.748645 -196.28841) (xy 184.771771 -196.336431) (xy 184.787481 -196.387361) (xy 184.795424 -196.440065)
			(xy 184.795922 -196.466714) (xy 184.795424 -196.493363) (xy 186.294004 -196.493363) (xy 186.294004 -196.440065)
			(xy 186.301947 -196.387361) (xy 186.317657 -196.336431) (xy 186.340783 -196.28841) (xy 186.370807 -196.244373)
			(xy 186.407059 -196.205302) (xy 186.44873 -196.172071) (xy 186.494888 -196.145422) (xy 186.544502 -196.12595)
			(xy 186.596464 -196.11409) (xy 186.649614 -196.110107) (xy 186.702764 -196.11409) (xy 186.754726 -196.12595)
			(xy 186.80434 -196.145422) (xy 186.850498 -196.172071) (xy 186.892169 -196.205302) (xy 186.928421 -196.244373)
			(xy 186.958445 -196.28841) (xy 186.981571 -196.336431) (xy 186.997281 -196.387361) (xy 187.005224 -196.440065)
			(xy 187.005722 -196.4667) (xy 187.526882 -196.4667) (xy 187.530866 -196.413545) (xy 187.542728 -196.361577)
			(xy 187.562204 -196.311957) (xy 187.588858 -196.265795) (xy 187.622095 -196.224122) (xy 187.661173 -196.187868)
			(xy 187.705218 -196.157844) (xy 187.753245 -196.134721) (xy 187.804184 -196.119014) (xy 187.856894 -196.111076)
			(xy 187.883546 -196.110606) (xy 187.910866 -196.111159) (xy 187.964866 -196.119489) (xy 188.016962 -196.135962)
			(xy 188.065934 -196.160193) (xy 188.110635 -196.191613) (xy 188.130688 -196.210174) (xy 188.141127 -196.219546)
			(xy 188.165843 -196.232785) (xy 188.193228 -196.238812) (xy 188.221219 -196.237172) (xy 188.247712 -196.227988)
			(xy 188.259466 -196.220334) (xy 188.266063 -196.216033) (xy 188.281061 -196.211253) (xy 188.28893 -196.210936)
			(xy 189.68847 -196.210936) (xy 189.698639 -196.211389) (xy 189.717433 -196.219163) (xy 189.731819 -196.23354)
			(xy 189.739605 -196.252329) (xy 189.740032 -196.262498) (xy 189.740032 -196.493363) (xy 191.628004 -196.493363)
			(xy 191.628004 -196.440065) (xy 191.635947 -196.387361) (xy 191.651657 -196.336431) (xy 191.674783 -196.28841)
			(xy 191.704807 -196.244373) (xy 191.741059 -196.205302) (xy 191.78273 -196.172071) (xy 191.828888 -196.145422)
			(xy 191.878502 -196.12595) (xy 191.930464 -196.11409) (xy 191.983614 -196.110107) (xy 192.036764 -196.11409)
			(xy 192.088726 -196.12595) (xy 192.13834 -196.145422) (xy 192.184498 -196.172071) (xy 192.226169 -196.205302)
			(xy 192.262421 -196.244373) (xy 192.292445 -196.28841) (xy 192.315571 -196.336431) (xy 192.331281 -196.387361)
			(xy 192.339224 -196.440065) (xy 192.339722 -196.466714) (xy 192.339224 -196.493363) (xy 193.837804 -196.493363)
			(xy 193.837804 -196.440065) (xy 193.845747 -196.387361) (xy 193.861457 -196.336431) (xy 193.884583 -196.28841)
			(xy 193.914607 -196.244373) (xy 193.950859 -196.205302) (xy 193.99253 -196.172071) (xy 194.038688 -196.145422)
			(xy 194.088302 -196.12595) (xy 194.140264 -196.11409) (xy 194.193414 -196.110107) (xy 194.246564 -196.11409)
			(xy 194.298526 -196.12595) (xy 194.34814 -196.145422) (xy 194.394298 -196.172071) (xy 194.435969 -196.205302)
			(xy 194.472221 -196.244373) (xy 194.502245 -196.28841) (xy 194.525371 -196.336431) (xy 194.541081 -196.387361)
			(xy 194.549024 -196.440065) (xy 194.549522 -196.466714) (xy 194.549024 -196.493363) (xy 194.541081 -196.546067)
			(xy 194.525371 -196.596997) (xy 194.502245 -196.645018) (xy 194.484232 -196.671438) (xy 195.781168 -196.671438)
			(xy 195.781168 -196.262498) (xy 195.781563 -196.252323) (xy 195.789354 -196.233522) (xy 195.803749 -196.219136)
			(xy 195.822554 -196.211357) (xy 195.83273 -196.210936) (xy 197.23227 -196.210936) (xy 197.242439 -196.211389)
			(xy 197.261233 -196.219163) (xy 197.275619 -196.23354) (xy 197.283405 -196.252329) (xy 197.283832 -196.262498)
			(xy 197.283832 -196.493363) (xy 199.171804 -196.493363) (xy 199.171804 -196.440065) (xy 199.179747 -196.387361)
			(xy 199.195457 -196.336431) (xy 199.218583 -196.28841) (xy 199.248607 -196.244373) (xy 199.284859 -196.205302)
			(xy 199.32653 -196.172071) (xy 199.372688 -196.145422) (xy 199.422302 -196.12595) (xy 199.474264 -196.11409)
			(xy 199.527414 -196.110107) (xy 199.580564 -196.11409) (xy 199.632526 -196.12595) (xy 199.68214 -196.145422)
			(xy 199.728298 -196.172071) (xy 199.769969 -196.205302) (xy 199.806221 -196.244373) (xy 199.836245 -196.28841)
			(xy 199.859371 -196.336431) (xy 199.875081 -196.387361) (xy 199.883024 -196.440065) (xy 199.883522 -196.466714)
			(xy 199.883024 -196.493363) (xy 201.381604 -196.493363) (xy 201.381604 -196.440065) (xy 201.389547 -196.387361)
			(xy 201.405257 -196.336431) (xy 201.428383 -196.28841) (xy 201.458407 -196.244373) (xy 201.494659 -196.205302)
			(xy 201.53633 -196.172071) (xy 201.582488 -196.145422) (xy 201.632102 -196.12595) (xy 201.684064 -196.11409)
			(xy 201.737214 -196.110107) (xy 201.790364 -196.11409) (xy 201.842326 -196.12595) (xy 201.89194 -196.145422)
			(xy 201.938098 -196.172071) (xy 201.979769 -196.205302) (xy 202.016021 -196.244373) (xy 202.046045 -196.28841)
			(xy 202.069171 -196.336431) (xy 202.084881 -196.387361) (xy 202.092824 -196.440065) (xy 202.093322 -196.4667)
			(xy 202.614482 -196.4667) (xy 202.618466 -196.413545) (xy 202.630328 -196.361577) (xy 202.649804 -196.311957)
			(xy 202.676458 -196.265795) (xy 202.709695 -196.224122) (xy 202.748773 -196.187868) (xy 202.792818 -196.157844)
			(xy 202.840845 -196.134721) (xy 202.891784 -196.119014) (xy 202.944494 -196.111076) (xy 202.971146 -196.110606)
			(xy 202.998466 -196.111159) (xy 203.052466 -196.119489) (xy 203.104562 -196.135962) (xy 203.153534 -196.160193)
			(xy 203.198235 -196.191613) (xy 203.218288 -196.210174) (xy 203.228727 -196.219546) (xy 203.253443 -196.232785)
			(xy 203.280828 -196.238812) (xy 203.308819 -196.237172) (xy 203.335312 -196.227988) (xy 203.347066 -196.220334)
			(xy 203.353663 -196.216033) (xy 203.368661 -196.211253) (xy 203.37653 -196.210936) (xy 204.77607 -196.210936)
			(xy 204.786239 -196.211389) (xy 204.805033 -196.219163) (xy 204.819419 -196.23354) (xy 204.827205 -196.252329)
			(xy 204.827632 -196.262498) (xy 204.827632 -196.493363) (xy 206.715604 -196.493363) (xy 206.715604 -196.440065)
			(xy 206.723547 -196.387361) (xy 206.739257 -196.336431) (xy 206.762383 -196.28841) (xy 206.792407 -196.244373)
			(xy 206.828659 -196.205302) (xy 206.87033 -196.172071) (xy 206.916488 -196.145422) (xy 206.966102 -196.12595)
			(xy 207.018064 -196.11409) (xy 207.071214 -196.110107) (xy 207.124364 -196.11409) (xy 207.176326 -196.12595)
			(xy 207.22594 -196.145422) (xy 207.272098 -196.172071) (xy 207.313769 -196.205302) (xy 207.350021 -196.244373)
			(xy 207.380045 -196.28841) (xy 207.403171 -196.336431) (xy 207.418881 -196.387361) (xy 207.426824 -196.440065)
			(xy 207.427322 -196.466714) (xy 207.426824 -196.493363) (xy 208.925404 -196.493363) (xy 208.925404 -196.440065)
			(xy 208.933347 -196.387361) (xy 208.949057 -196.336431) (xy 208.972183 -196.28841) (xy 209.002207 -196.244373)
			(xy 209.038459 -196.205302) (xy 209.08013 -196.172071) (xy 209.126288 -196.145422) (xy 209.175902 -196.12595)
			(xy 209.227864 -196.11409) (xy 209.281014 -196.110107) (xy 209.334164 -196.11409) (xy 209.386126 -196.12595)
			(xy 209.43574 -196.145422) (xy 209.481898 -196.172071) (xy 209.523569 -196.205302) (xy 209.559821 -196.244373)
			(xy 209.589845 -196.28841) (xy 209.612971 -196.336431) (xy 209.628681 -196.387361) (xy 209.636624 -196.440065)
			(xy 209.637122 -196.466714) (xy 209.636624 -196.493363) (xy 209.628681 -196.546067) (xy 209.612971 -196.596997)
			(xy 209.589845 -196.645018) (xy 209.571832 -196.671438) (xy 210.868768 -196.671438) (xy 210.868768 -196.262498)
			(xy 210.869163 -196.252323) (xy 210.876954 -196.233522) (xy 210.891349 -196.219136) (xy 210.910154 -196.211357)
			(xy 210.92033 -196.210936) (xy 212.31987 -196.210936) (xy 212.330039 -196.211389) (xy 212.348833 -196.219163)
			(xy 212.363219 -196.23354) (xy 212.371005 -196.252329) (xy 212.371432 -196.262498) (xy 212.371432 -196.671438)
			(xy 212.370997 -196.681602) (xy 212.363204 -196.700378) (xy 212.348821 -196.714743) (xy 212.330035 -196.72251)
			(xy 212.31987 -196.723) (xy 210.92033 -196.723) (xy 210.910179 -196.722443) (xy 210.891417 -196.714686)
			(xy 210.877052 -196.70034) (xy 210.86927 -196.681589) (xy 210.868768 -196.671438) (xy 209.571832 -196.671438)
			(xy 209.559821 -196.689055) (xy 209.523569 -196.728126) (xy 209.481898 -196.761357) (xy 209.43574 -196.788006)
			(xy 209.386126 -196.807478) (xy 209.334164 -196.819338) (xy 209.281014 -196.823322) (xy 209.227864 -196.819338)
			(xy 209.175902 -196.807478) (xy 209.126288 -196.788006) (xy 209.08013 -196.761357) (xy 209.038459 -196.728126)
			(xy 209.002207 -196.689055) (xy 208.972183 -196.645018) (xy 208.949057 -196.596997) (xy 208.933347 -196.546067)
			(xy 208.925404 -196.493363) (xy 207.426824 -196.493363) (xy 207.418881 -196.546067) (xy 207.403171 -196.596997)
			(xy 207.380045 -196.645018) (xy 207.350021 -196.689055) (xy 207.313769 -196.728126) (xy 207.272098 -196.761357)
			(xy 207.22594 -196.788006) (xy 207.176326 -196.807478) (xy 207.124364 -196.819338) (xy 207.071214 -196.823322)
			(xy 207.018064 -196.819338) (xy 206.966102 -196.807478) (xy 206.916488 -196.788006) (xy 206.87033 -196.761357)
			(xy 206.828659 -196.728126) (xy 206.792407 -196.689055) (xy 206.762383 -196.645018) (xy 206.739257 -196.596997)
			(xy 206.723547 -196.546067) (xy 206.715604 -196.493363) (xy 204.827632 -196.493363) (xy 204.827632 -196.671438)
			(xy 204.827197 -196.681602) (xy 204.819404 -196.700378) (xy 204.805021 -196.714743) (xy 204.786235 -196.72251)
			(xy 204.77607 -196.723) (xy 203.37653 -196.723) (xy 203.368595 -196.722721) (xy 203.353463 -196.717939)
			(xy 203.346812 -196.713602) (xy 203.33512 -196.705837) (xy 203.308658 -196.696504) (xy 203.280655 -196.694738)
			(xy 203.25323 -196.700672) (xy 203.228462 -196.713858) (xy 203.218034 -196.723254) (xy 203.198016 -196.741822)
			(xy 203.153371 -196.77325) (xy 203.10445 -196.797491) (xy 203.052401 -196.813978) (xy 202.998445 -196.822322)
			(xy 202.971146 -196.822822) (xy 202.944494 -196.822324) (xy 202.891784 -196.814386) (xy 202.840845 -196.798679)
			(xy 202.792818 -196.775556) (xy 202.748773 -196.745532) (xy 202.709695 -196.709278) (xy 202.676458 -196.667605)
			(xy 202.649804 -196.621443) (xy 202.630328 -196.571823) (xy 202.618466 -196.519855) (xy 202.614482 -196.4667)
			(xy 202.093322 -196.4667) (xy 202.093322 -196.466714) (xy 202.092824 -196.493363) (xy 202.084881 -196.546067)
			(xy 202.069171 -196.596997) (xy 202.046045 -196.645018) (xy 202.016021 -196.689055) (xy 201.979769 -196.728126)
			(xy 201.938098 -196.761357) (xy 201.89194 -196.788006) (xy 201.842326 -196.807478) (xy 201.790364 -196.819338)
			(xy 201.737214 -196.823322) (xy 201.684064 -196.819338) (xy 201.632102 -196.807478) (xy 201.582488 -196.788006)
			(xy 201.53633 -196.761357) (xy 201.494659 -196.728126) (xy 201.458407 -196.689055) (xy 201.428383 -196.645018)
			(xy 201.405257 -196.596997) (xy 201.389547 -196.546067) (xy 201.381604 -196.493363) (xy 199.883024 -196.493363)
			(xy 199.875081 -196.546067) (xy 199.859371 -196.596997) (xy 199.836245 -196.645018) (xy 199.806221 -196.689055)
			(xy 199.769969 -196.728126) (xy 199.728298 -196.761357) (xy 199.68214 -196.788006) (xy 199.632526 -196.807478)
			(xy 199.580564 -196.819338) (xy 199.527414 -196.823322) (xy 199.474264 -196.819338) (xy 199.422302 -196.807478)
			(xy 199.372688 -196.788006) (xy 199.32653 -196.761357) (xy 199.284859 -196.728126) (xy 199.248607 -196.689055)
			(xy 199.218583 -196.645018) (xy 199.195457 -196.596997) (xy 199.179747 -196.546067) (xy 199.171804 -196.493363)
			(xy 197.283832 -196.493363) (xy 197.283832 -196.671438) (xy 197.283397 -196.681602) (xy 197.275604 -196.700378)
			(xy 197.261221 -196.714743) (xy 197.242435 -196.72251) (xy 197.23227 -196.723) (xy 195.83273 -196.723)
			(xy 195.822579 -196.722443) (xy 195.803817 -196.714686) (xy 195.789452 -196.70034) (xy 195.78167 -196.681589)
			(xy 195.781168 -196.671438) (xy 194.484232 -196.671438) (xy 194.472221 -196.689055) (xy 194.435969 -196.728126)
			(xy 194.394298 -196.761357) (xy 194.34814 -196.788006) (xy 194.298526 -196.807478) (xy 194.246564 -196.819338)
			(xy 194.193414 -196.823322) (xy 194.140264 -196.819338) (xy 194.088302 -196.807478) (xy 194.038688 -196.788006)
			(xy 193.99253 -196.761357) (xy 193.950859 -196.728126) (xy 193.914607 -196.689055) (xy 193.884583 -196.645018)
			(xy 193.861457 -196.596997) (xy 193.845747 -196.546067) (xy 193.837804 -196.493363) (xy 192.339224 -196.493363)
			(xy 192.331281 -196.546067) (xy 192.315571 -196.596997) (xy 192.292445 -196.645018) (xy 192.262421 -196.689055)
			(xy 192.226169 -196.728126) (xy 192.184498 -196.761357) (xy 192.13834 -196.788006) (xy 192.088726 -196.807478)
			(xy 192.036764 -196.819338) (xy 191.983614 -196.823322) (xy 191.930464 -196.819338) (xy 191.878502 -196.807478)
			(xy 191.828888 -196.788006) (xy 191.78273 -196.761357) (xy 191.741059 -196.728126) (xy 191.704807 -196.689055)
			(xy 191.674783 -196.645018) (xy 191.651657 -196.596997) (xy 191.635947 -196.546067) (xy 191.628004 -196.493363)
			(xy 189.740032 -196.493363) (xy 189.740032 -196.671438) (xy 189.739597 -196.681602) (xy 189.731804 -196.700378)
			(xy 189.717421 -196.714743) (xy 189.698635 -196.72251) (xy 189.68847 -196.723) (xy 188.28893 -196.723)
			(xy 188.280995 -196.722721) (xy 188.265863 -196.717939) (xy 188.259212 -196.713602) (xy 188.24752 -196.705837)
			(xy 188.221058 -196.696504) (xy 188.193055 -196.694738) (xy 188.16563 -196.700672) (xy 188.140862 -196.713858)
			(xy 188.130434 -196.723254) (xy 188.110416 -196.741822) (xy 188.065771 -196.77325) (xy 188.01685 -196.797491)
			(xy 187.964801 -196.813978) (xy 187.910845 -196.822322) (xy 187.883546 -196.822822) (xy 187.856894 -196.822324)
			(xy 187.804184 -196.814386) (xy 187.753245 -196.798679) (xy 187.705218 -196.775556) (xy 187.661173 -196.745532)
			(xy 187.622095 -196.709278) (xy 187.588858 -196.667605) (xy 187.562204 -196.621443) (xy 187.542728 -196.571823)
			(xy 187.530866 -196.519855) (xy 187.526882 -196.4667) (xy 187.005722 -196.4667) (xy 187.005722 -196.466714)
			(xy 187.005224 -196.493363) (xy 186.997281 -196.546067) (xy 186.981571 -196.596997) (xy 186.958445 -196.645018)
			(xy 186.928421 -196.689055) (xy 186.892169 -196.728126) (xy 186.850498 -196.761357) (xy 186.80434 -196.788006)
			(xy 186.754726 -196.807478) (xy 186.702764 -196.819338) (xy 186.649614 -196.823322) (xy 186.596464 -196.819338)
			(xy 186.544502 -196.807478) (xy 186.494888 -196.788006) (xy 186.44873 -196.761357) (xy 186.407059 -196.728126)
			(xy 186.370807 -196.689055) (xy 186.340783 -196.645018) (xy 186.317657 -196.596997) (xy 186.301947 -196.546067)
			(xy 186.294004 -196.493363) (xy 184.795424 -196.493363) (xy 184.787481 -196.546067) (xy 184.771771 -196.596997)
			(xy 184.748645 -196.645018) (xy 184.718621 -196.689055) (xy 184.682369 -196.728126) (xy 184.640698 -196.761357)
			(xy 184.59454 -196.788006) (xy 184.544926 -196.807478) (xy 184.492964 -196.819338) (xy 184.439814 -196.823322)
			(xy 184.386664 -196.819338) (xy 184.334702 -196.807478) (xy 184.285088 -196.788006) (xy 184.23893 -196.761357)
			(xy 184.197259 -196.728126) (xy 184.161007 -196.689055) (xy 184.130983 -196.645018) (xy 184.107857 -196.596997)
			(xy 184.092147 -196.546067) (xy 184.084204 -196.493363) (xy 182.196232 -196.493363) (xy 182.196232 -196.671438)
			(xy 182.195797 -196.681602) (xy 182.188004 -196.700378) (xy 182.173621 -196.714743) (xy 182.154835 -196.72251)
			(xy 182.14467 -196.723) (xy 180.74513 -196.723) (xy 180.734979 -196.722443) (xy 180.716217 -196.714686)
			(xy 180.701852 -196.70034) (xy 180.69407 -196.681589) (xy 180.693568 -196.671438) (xy 179.396632 -196.671438)
			(xy 179.384621 -196.689055) (xy 179.348369 -196.728126) (xy 179.306698 -196.761357) (xy 179.26054 -196.788006)
			(xy 179.210926 -196.807478) (xy 179.158964 -196.819338) (xy 179.105814 -196.823322) (xy 179.052664 -196.819338)
			(xy 179.000702 -196.807478) (xy 178.951088 -196.788006) (xy 178.90493 -196.761357) (xy 178.863259 -196.728126)
			(xy 178.827007 -196.689055) (xy 178.796983 -196.645018) (xy 178.773857 -196.596997) (xy 178.758147 -196.546067)
			(xy 178.750204 -196.493363) (xy 177.251624 -196.493363) (xy 177.243681 -196.546067) (xy 177.227971 -196.596997)
			(xy 177.204845 -196.645018) (xy 177.174821 -196.689055) (xy 177.138569 -196.728126) (xy 177.096898 -196.761357)
			(xy 177.05074 -196.788006) (xy 177.001126 -196.807478) (xy 176.949164 -196.819338) (xy 176.896014 -196.823322)
			(xy 176.842864 -196.819338) (xy 176.790902 -196.807478) (xy 176.741288 -196.788006) (xy 176.69513 -196.761357)
			(xy 176.653459 -196.728126) (xy 176.617207 -196.689055) (xy 176.587183 -196.645018) (xy 176.564057 -196.596997)
			(xy 176.548347 -196.546067) (xy 176.540404 -196.493363) (xy 174.652432 -196.493363) (xy 174.652432 -196.671438)
			(xy 174.651997 -196.681602) (xy 174.644204 -196.700378) (xy 174.629821 -196.714743) (xy 174.611035 -196.72251)
			(xy 174.60087 -196.723) (xy 173.20133 -196.723) (xy 173.193395 -196.722721) (xy 173.178263 -196.717939)
			(xy 173.171612 -196.713602) (xy 173.15992 -196.705837) (xy 173.133458 -196.696504) (xy 173.105455 -196.694738)
			(xy 173.07803 -196.700672) (xy 173.053262 -196.713858) (xy 173.042834 -196.723254) (xy 173.022816 -196.741822)
			(xy 172.978171 -196.77325) (xy 172.92925 -196.797491) (xy 172.877201 -196.813978) (xy 172.823245 -196.822322)
			(xy 172.795946 -196.822822) (xy 172.769294 -196.822324) (xy 172.716584 -196.814386) (xy 172.665645 -196.798679)
			(xy 172.617618 -196.775556) (xy 172.573573 -196.745532) (xy 172.534495 -196.709278) (xy 172.501258 -196.667605)
			(xy 172.474604 -196.621443) (xy 172.455128 -196.571823) (xy 172.443266 -196.519855) (xy 172.439282 -196.4667)
			(xy 171.918122 -196.4667) (xy 171.918122 -196.466714) (xy 171.917624 -196.493363) (xy 171.909681 -196.546067)
			(xy 171.893971 -196.596997) (xy 171.870845 -196.645018) (xy 171.840821 -196.689055) (xy 171.804569 -196.728126)
			(xy 171.762898 -196.761357) (xy 171.71674 -196.788006) (xy 171.667126 -196.807478) (xy 171.615164 -196.819338)
			(xy 171.562014 -196.823322) (xy 171.508864 -196.819338) (xy 171.456902 -196.807478) (xy 171.407288 -196.788006)
			(xy 171.36113 -196.761357) (xy 171.319459 -196.728126) (xy 171.283207 -196.689055) (xy 171.253183 -196.645018)
			(xy 171.230057 -196.596997) (xy 171.214347 -196.546067) (xy 171.206404 -196.493363) (xy 169.707824 -196.493363)
			(xy 169.699881 -196.546067) (xy 169.684171 -196.596997) (xy 169.661045 -196.645018) (xy 169.631021 -196.689055)
			(xy 169.594769 -196.728126) (xy 169.553098 -196.761357) (xy 169.50694 -196.788006) (xy 169.457326 -196.807478)
			(xy 169.405364 -196.819338) (xy 169.352214 -196.823322) (xy 169.299064 -196.819338) (xy 169.247102 -196.807478)
			(xy 169.197488 -196.788006) (xy 169.15133 -196.761357) (xy 169.109659 -196.728126) (xy 169.073407 -196.689055)
			(xy 169.043383 -196.645018) (xy 169.020257 -196.596997) (xy 169.004547 -196.546067) (xy 168.996604 -196.493363)
			(xy 167.108632 -196.493363) (xy 167.108632 -196.671438) (xy 167.108197 -196.681602) (xy 167.100404 -196.700378)
			(xy 167.086021 -196.714743) (xy 167.067235 -196.72251) (xy 167.05707 -196.723) (xy 165.65753 -196.723)
			(xy 165.647379 -196.722443) (xy 165.628617 -196.714686) (xy 165.614252 -196.70034) (xy 165.60647 -196.681589)
			(xy 165.605968 -196.671438) (xy 164.309032 -196.671438) (xy 164.297021 -196.689055) (xy 164.260769 -196.728126)
			(xy 164.219098 -196.761357) (xy 164.17294 -196.788006) (xy 164.123326 -196.807478) (xy 164.071364 -196.819338)
			(xy 164.018214 -196.823322) (xy 163.965064 -196.819338) (xy 163.913102 -196.807478) (xy 163.863488 -196.788006)
			(xy 163.81733 -196.761357) (xy 163.775659 -196.728126) (xy 163.739407 -196.689055) (xy 163.709383 -196.645018)
			(xy 163.686257 -196.596997) (xy 163.670547 -196.546067) (xy 163.662604 -196.493363) (xy 162.164024 -196.493363)
			(xy 162.156081 -196.546067) (xy 162.140371 -196.596997) (xy 162.117245 -196.645018) (xy 162.087221 -196.689055)
			(xy 162.050969 -196.728126) (xy 162.009298 -196.761357) (xy 161.96314 -196.788006) (xy 161.913526 -196.807478)
			(xy 161.861564 -196.819338) (xy 161.808414 -196.823322) (xy 161.755264 -196.819338) (xy 161.703302 -196.807478)
			(xy 161.653688 -196.788006) (xy 161.60753 -196.761357) (xy 161.565859 -196.728126) (xy 161.529607 -196.689055)
			(xy 161.499583 -196.645018) (xy 161.476457 -196.596997) (xy 161.460747 -196.546067) (xy 161.452804 -196.493363)
			(xy 159.564832 -196.493363) (xy 159.564832 -196.671438) (xy 159.564397 -196.681602) (xy 159.556604 -196.700378)
			(xy 159.542221 -196.714743) (xy 159.523435 -196.72251) (xy 159.51327 -196.723) (xy 158.11373 -196.723)
			(xy 158.103579 -196.722443) (xy 158.084817 -196.714686) (xy 158.070452 -196.70034) (xy 158.06267 -196.681589)
			(xy 158.062168 -196.671438) (xy 145.160238 -196.671438) (xy 145.832047 -197.343247) (xy 157.352736 -197.343247)
			(xy 157.352736 -197.289949) (xy 157.360679 -197.237245) (xy 157.376389 -197.186315) (xy 157.399515 -197.138294)
			(xy 157.429539 -197.094257) (xy 157.465791 -197.055186) (xy 157.507462 -197.021955) (xy 157.55362 -196.995306)
			(xy 157.603234 -196.975834) (xy 157.655196 -196.963974) (xy 157.708346 -196.959991) (xy 157.761496 -196.963974)
			(xy 157.813458 -196.975834) (xy 157.863072 -196.995306) (xy 157.90923 -197.021955) (xy 157.950901 -197.055186)
			(xy 157.987153 -197.094257) (xy 158.017177 -197.138294) (xy 158.040303 -197.186315) (xy 158.056013 -197.237245)
			(xy 158.063956 -197.289949) (xy 158.064454 -197.316598) (xy 158.063956 -197.343247) (xy 159.562536 -197.343247)
			(xy 159.562536 -197.289949) (xy 159.570479 -197.237245) (xy 159.586189 -197.186315) (xy 159.609315 -197.138294)
			(xy 159.639339 -197.094257) (xy 159.675591 -197.055186) (xy 159.717262 -197.021955) (xy 159.76342 -196.995306)
			(xy 159.813034 -196.975834) (xy 159.864996 -196.963974) (xy 159.918146 -196.959991) (xy 159.971296 -196.963974)
			(xy 160.023258 -196.975834) (xy 160.072872 -196.995306) (xy 160.11903 -197.021955) (xy 160.160701 -197.055186)
			(xy 160.196953 -197.094257) (xy 160.226977 -197.138294) (xy 160.250103 -197.186315) (xy 160.265813 -197.237245)
			(xy 160.273756 -197.289949) (xy 160.274254 -197.316598) (xy 160.273756 -197.343247) (xy 160.265813 -197.395951)
			(xy 160.250103 -197.446881) (xy 160.226977 -197.494902) (xy 160.208964 -197.521322) (xy 162.162236 -197.521322)
			(xy 162.162236 -197.112382) (xy 162.162718 -197.102223) (xy 162.170498 -197.083454) (xy 162.184867 -197.069089)
			(xy 162.203639 -197.061315) (xy 162.213798 -197.06082) (xy 163.613338 -197.06082) (xy 163.623496 -197.061302)
			(xy 163.642263 -197.069085) (xy 163.656626 -197.083454) (xy 163.664402 -197.102224) (xy 163.6649 -197.112382)
			(xy 163.6649 -197.343247) (xy 164.896536 -197.343247) (xy 164.896536 -197.289949) (xy 164.904479 -197.237245)
			(xy 164.920189 -197.186315) (xy 164.943315 -197.138294) (xy 164.973339 -197.094257) (xy 165.009591 -197.055186)
			(xy 165.051262 -197.021955) (xy 165.09742 -196.995306) (xy 165.147034 -196.975834) (xy 165.198996 -196.963974)
			(xy 165.252146 -196.959991) (xy 165.305296 -196.963974) (xy 165.357258 -196.975834) (xy 165.406872 -196.995306)
			(xy 165.45303 -197.021955) (xy 165.494701 -197.055186) (xy 165.530953 -197.094257) (xy 165.560977 -197.138294)
			(xy 165.584103 -197.186315) (xy 165.599813 -197.237245) (xy 165.607756 -197.289949) (xy 165.608254 -197.316598)
			(xy 165.607756 -197.343247) (xy 167.106336 -197.343247) (xy 167.106336 -197.289949) (xy 167.114279 -197.237245)
			(xy 167.129989 -197.186315) (xy 167.153115 -197.138294) (xy 167.183139 -197.094257) (xy 167.219391 -197.055186)
			(xy 167.261062 -197.021955) (xy 167.30722 -196.995306) (xy 167.356834 -196.975834) (xy 167.408796 -196.963974)
			(xy 167.461946 -196.959991) (xy 167.515096 -196.963974) (xy 167.567058 -196.975834) (xy 167.616672 -196.995306)
			(xy 167.66283 -197.021955) (xy 167.704501 -197.055186) (xy 167.740753 -197.094257) (xy 167.770777 -197.138294)
			(xy 167.793903 -197.186315) (xy 167.809613 -197.237245) (xy 167.817556 -197.289949) (xy 167.818054 -197.316598)
			(xy 167.817556 -197.343247) (xy 167.809613 -197.395951) (xy 167.793903 -197.446881) (xy 167.770777 -197.494902)
			(xy 167.752764 -197.521322) (xy 169.706036 -197.521322) (xy 169.706036 -197.112382) (xy 169.706518 -197.102223)
			(xy 169.714298 -197.083454) (xy 169.728667 -197.069089) (xy 169.747439 -197.061315) (xy 169.757598 -197.06082)
			(xy 171.157138 -197.06082) (xy 171.167296 -197.061302) (xy 171.186063 -197.069085) (xy 171.200426 -197.083454)
			(xy 171.208202 -197.102224) (xy 171.2087 -197.112382) (xy 171.2087 -197.343247) (xy 172.440336 -197.343247)
			(xy 172.440336 -197.289949) (xy 172.448279 -197.237245) (xy 172.463989 -197.186315) (xy 172.487115 -197.138294)
			(xy 172.517139 -197.094257) (xy 172.553391 -197.055186) (xy 172.595062 -197.021955) (xy 172.64122 -196.995306)
			(xy 172.690834 -196.975834) (xy 172.742796 -196.963974) (xy 172.795946 -196.959991) (xy 172.849096 -196.963974)
			(xy 172.901058 -196.975834) (xy 172.950672 -196.995306) (xy 172.99683 -197.021955) (xy 173.038501 -197.055186)
			(xy 173.074753 -197.094257) (xy 173.104777 -197.138294) (xy 173.127903 -197.186315) (xy 173.143613 -197.237245)
			(xy 173.151556 -197.289949) (xy 173.152054 -197.316598) (xy 173.151556 -197.343247) (xy 174.650136 -197.343247)
			(xy 174.650136 -197.289949) (xy 174.658079 -197.237245) (xy 174.673789 -197.186315) (xy 174.696915 -197.138294)
			(xy 174.726939 -197.094257) (xy 174.763191 -197.055186) (xy 174.804862 -197.021955) (xy 174.85102 -196.995306)
			(xy 174.900634 -196.975834) (xy 174.952596 -196.963974) (xy 175.005746 -196.959991) (xy 175.058896 -196.963974)
			(xy 175.110858 -196.975834) (xy 175.160472 -196.995306) (xy 175.20663 -197.021955) (xy 175.248301 -197.055186)
			(xy 175.284553 -197.094257) (xy 175.314577 -197.138294) (xy 175.337703 -197.186315) (xy 175.353413 -197.237245)
			(xy 175.361356 -197.289949) (xy 175.361854 -197.316598) (xy 175.361854 -197.3166) (xy 176.539366 -197.3166)
			(xy 176.54335 -197.263445) (xy 176.555211 -197.211478) (xy 176.574686 -197.161859) (xy 176.601338 -197.115697)
			(xy 176.634573 -197.074022) (xy 176.673649 -197.037767) (xy 176.717691 -197.007741) (xy 176.765717 -196.984615)
			(xy 176.816653 -196.968905) (xy 176.869362 -196.960962) (xy 176.896014 -196.96049) (xy 176.923335 -196.961005)
			(xy 176.977336 -196.969345) (xy 177.029433 -196.985828) (xy 177.078404 -197.010067) (xy 177.123104 -197.041494)
			(xy 177.143156 -197.060058) (xy 177.153544 -197.069491) (xy 177.178278 -197.082726) (xy 177.205677 -197.088742)
			(xy 177.23368 -197.087086) (xy 177.260179 -197.077883) (xy 177.271934 -197.070218) (xy 177.278537 -197.065928)
			(xy 177.29353 -197.061141) (xy 177.301398 -197.06082) (xy 178.700938 -197.06082) (xy 178.711096 -197.061302)
			(xy 178.729863 -197.069085) (xy 178.744226 -197.083454) (xy 178.752002 -197.102224) (xy 178.7525 -197.112382)
			(xy 178.7525 -197.343247) (xy 179.984136 -197.343247) (xy 179.984136 -197.289949) (xy 179.992079 -197.237245)
			(xy 180.007789 -197.186315) (xy 180.030915 -197.138294) (xy 180.060939 -197.094257) (xy 180.097191 -197.055186)
			(xy 180.138862 -197.021955) (xy 180.18502 -196.995306) (xy 180.234634 -196.975834) (xy 180.286596 -196.963974)
			(xy 180.339746 -196.959991) (xy 180.392896 -196.963974) (xy 180.444858 -196.975834) (xy 180.494472 -196.995306)
			(xy 180.54063 -197.021955) (xy 180.582301 -197.055186) (xy 180.618553 -197.094257) (xy 180.648577 -197.138294)
			(xy 180.671703 -197.186315) (xy 180.687413 -197.237245) (xy 180.695356 -197.289949) (xy 180.695854 -197.316598)
			(xy 180.695356 -197.343247) (xy 182.193936 -197.343247) (xy 182.193936 -197.289949) (xy 182.201879 -197.237245)
			(xy 182.217589 -197.186315) (xy 182.240715 -197.138294) (xy 182.270739 -197.094257) (xy 182.306991 -197.055186)
			(xy 182.348662 -197.021955) (xy 182.39482 -196.995306) (xy 182.444434 -196.975834) (xy 182.496396 -196.963974)
			(xy 182.549546 -196.959991) (xy 182.602696 -196.963974) (xy 182.654658 -196.975834) (xy 182.704272 -196.995306)
			(xy 182.75043 -197.021955) (xy 182.792101 -197.055186) (xy 182.828353 -197.094257) (xy 182.858377 -197.138294)
			(xy 182.881503 -197.186315) (xy 182.897213 -197.237245) (xy 182.905156 -197.289949) (xy 182.905654 -197.316598)
			(xy 182.905156 -197.343247) (xy 182.897213 -197.395951) (xy 182.881503 -197.446881) (xy 182.858377 -197.494902)
			(xy 182.840364 -197.521322) (xy 184.793636 -197.521322) (xy 184.793636 -197.112382) (xy 184.794118 -197.102223)
			(xy 184.801898 -197.083454) (xy 184.816267 -197.069089) (xy 184.835039 -197.061315) (xy 184.845198 -197.06082)
			(xy 186.244738 -197.06082) (xy 186.254896 -197.061302) (xy 186.273663 -197.069085) (xy 186.288026 -197.083454)
			(xy 186.295802 -197.102224) (xy 186.2963 -197.112382) (xy 186.2963 -197.343247) (xy 187.527936 -197.343247)
			(xy 187.527936 -197.289949) (xy 187.535879 -197.237245) (xy 187.551589 -197.186315) (xy 187.574715 -197.138294)
			(xy 187.604739 -197.094257) (xy 187.640991 -197.055186) (xy 187.682662 -197.021955) (xy 187.72882 -196.995306)
			(xy 187.778434 -196.975834) (xy 187.830396 -196.963974) (xy 187.883546 -196.959991) (xy 187.936696 -196.963974)
			(xy 187.988658 -196.975834) (xy 188.038272 -196.995306) (xy 188.08443 -197.021955) (xy 188.126101 -197.055186)
			(xy 188.162353 -197.094257) (xy 188.192377 -197.138294) (xy 188.215503 -197.186315) (xy 188.231213 -197.237245)
			(xy 188.239156 -197.289949) (xy 188.239654 -197.316598) (xy 188.239156 -197.343247) (xy 189.737736 -197.343247)
			(xy 189.737736 -197.289949) (xy 189.745679 -197.237245) (xy 189.761389 -197.186315) (xy 189.784515 -197.138294)
			(xy 189.814539 -197.094257) (xy 189.850791 -197.055186) (xy 189.892462 -197.021955) (xy 189.93862 -196.995306)
			(xy 189.988234 -196.975834) (xy 190.040196 -196.963974) (xy 190.093346 -196.959991) (xy 190.146496 -196.963974)
			(xy 190.198458 -196.975834) (xy 190.248072 -196.995306) (xy 190.29423 -197.021955) (xy 190.335901 -197.055186)
			(xy 190.372153 -197.094257) (xy 190.402177 -197.138294) (xy 190.425303 -197.186315) (xy 190.441013 -197.237245)
			(xy 190.448956 -197.289949) (xy 190.449454 -197.316598) (xy 190.449454 -197.3166) (xy 191.626966 -197.3166)
			(xy 191.63095 -197.263445) (xy 191.642811 -197.211478) (xy 191.662286 -197.161859) (xy 191.688938 -197.115697)
			(xy 191.722173 -197.074022) (xy 191.761249 -197.037767) (xy 191.805291 -197.007741) (xy 191.853317 -196.984615)
			(xy 191.904253 -196.968905) (xy 191.956962 -196.960962) (xy 191.983614 -196.96049) (xy 192.010935 -196.961005)
			(xy 192.064936 -196.969345) (xy 192.117033 -196.985828) (xy 192.166004 -197.010067) (xy 192.210704 -197.041494)
			(xy 192.230756 -197.060058) (xy 192.241144 -197.069491) (xy 192.265878 -197.082726) (xy 192.293277 -197.088742)
			(xy 192.32128 -197.087086) (xy 192.347779 -197.077883) (xy 192.359534 -197.070218) (xy 192.366137 -197.065928)
			(xy 192.38113 -197.061141) (xy 192.388998 -197.06082) (xy 193.788538 -197.06082) (xy 193.798696 -197.061302)
			(xy 193.817463 -197.069085) (xy 193.831826 -197.083454) (xy 193.839602 -197.102224) (xy 193.8401 -197.112382)
			(xy 193.8401 -197.343247) (xy 195.071736 -197.343247) (xy 195.071736 -197.289949) (xy 195.079679 -197.237245)
			(xy 195.095389 -197.186315) (xy 195.118515 -197.138294) (xy 195.148539 -197.094257) (xy 195.184791 -197.055186)
			(xy 195.226462 -197.021955) (xy 195.27262 -196.995306) (xy 195.322234 -196.975834) (xy 195.374196 -196.963974)
			(xy 195.427346 -196.959991) (xy 195.480496 -196.963974) (xy 195.532458 -196.975834) (xy 195.582072 -196.995306)
			(xy 195.62823 -197.021955) (xy 195.669901 -197.055186) (xy 195.706153 -197.094257) (xy 195.736177 -197.138294)
			(xy 195.759303 -197.186315) (xy 195.775013 -197.237245) (xy 195.782956 -197.289949) (xy 195.783454 -197.316598)
			(xy 195.782956 -197.343247) (xy 197.281536 -197.343247) (xy 197.281536 -197.289949) (xy 197.289479 -197.237245)
			(xy 197.305189 -197.186315) (xy 197.328315 -197.138294) (xy 197.358339 -197.094257) (xy 197.394591 -197.055186)
			(xy 197.436262 -197.021955) (xy 197.48242 -196.995306) (xy 197.532034 -196.975834) (xy 197.583996 -196.963974)
			(xy 197.637146 -196.959991) (xy 197.690296 -196.963974) (xy 197.742258 -196.975834) (xy 197.791872 -196.995306)
			(xy 197.83803 -197.021955) (xy 197.879701 -197.055186) (xy 197.915953 -197.094257) (xy 197.945977 -197.138294)
			(xy 197.969103 -197.186315) (xy 197.984813 -197.237245) (xy 197.992756 -197.289949) (xy 197.993254 -197.316598)
			(xy 197.992756 -197.343247) (xy 197.984813 -197.395951) (xy 197.969103 -197.446881) (xy 197.945977 -197.494902)
			(xy 197.927964 -197.521322) (xy 199.881236 -197.521322) (xy 199.881236 -197.112382) (xy 199.881718 -197.102223)
			(xy 199.889498 -197.083454) (xy 199.903867 -197.069089) (xy 199.922639 -197.061315) (xy 199.932798 -197.06082)
			(xy 201.332338 -197.06082) (xy 201.342496 -197.061302) (xy 201.361263 -197.069085) (xy 201.375626 -197.083454)
			(xy 201.383402 -197.102224) (xy 201.3839 -197.112382) (xy 201.3839 -197.343247) (xy 202.615536 -197.343247)
			(xy 202.615536 -197.289949) (xy 202.623479 -197.237245) (xy 202.639189 -197.186315) (xy 202.662315 -197.138294)
			(xy 202.692339 -197.094257) (xy 202.728591 -197.055186) (xy 202.770262 -197.021955) (xy 202.81642 -196.995306)
			(xy 202.866034 -196.975834) (xy 202.917996 -196.963974) (xy 202.971146 -196.959991) (xy 203.024296 -196.963974)
			(xy 203.076258 -196.975834) (xy 203.125872 -196.995306) (xy 203.17203 -197.021955) (xy 203.213701 -197.055186)
			(xy 203.249953 -197.094257) (xy 203.279977 -197.138294) (xy 203.303103 -197.186315) (xy 203.318813 -197.237245)
			(xy 203.326756 -197.289949) (xy 203.327254 -197.316598) (xy 203.326756 -197.343247) (xy 204.825336 -197.343247)
			(xy 204.825336 -197.289949) (xy 204.833279 -197.237245) (xy 204.848989 -197.186315) (xy 204.872115 -197.138294)
			(xy 204.902139 -197.094257) (xy 204.938391 -197.055186) (xy 204.980062 -197.021955) (xy 205.02622 -196.995306)
			(xy 205.075834 -196.975834) (xy 205.127796 -196.963974) (xy 205.180946 -196.959991) (xy 205.234096 -196.963974)
			(xy 205.286058 -196.975834) (xy 205.335672 -196.995306) (xy 205.38183 -197.021955) (xy 205.423501 -197.055186)
			(xy 205.459753 -197.094257) (xy 205.489777 -197.138294) (xy 205.512903 -197.186315) (xy 205.528613 -197.237245)
			(xy 205.536556 -197.289949) (xy 205.537054 -197.316598) (xy 205.537054 -197.3166) (xy 206.714566 -197.3166)
			(xy 206.71855 -197.263445) (xy 206.730411 -197.211478) (xy 206.749886 -197.161859) (xy 206.776538 -197.115697)
			(xy 206.809773 -197.074022) (xy 206.848849 -197.037767) (xy 206.892891 -197.007741) (xy 206.940917 -196.984615)
			(xy 206.991853 -196.968905) (xy 207.044562 -196.960962) (xy 207.071214 -196.96049) (xy 207.098535 -196.961005)
			(xy 207.152536 -196.969345) (xy 207.204633 -196.985828) (xy 207.253604 -197.010067) (xy 207.298304 -197.041494)
			(xy 207.318356 -197.060058) (xy 207.328744 -197.069491) (xy 207.353478 -197.082726) (xy 207.380877 -197.088742)
			(xy 207.40888 -197.087086) (xy 207.435379 -197.077883) (xy 207.447134 -197.070218) (xy 207.453737 -197.065928)
			(xy 207.46873 -197.061141) (xy 207.476598 -197.06082) (xy 208.876138 -197.06082) (xy 208.886296 -197.061302)
			(xy 208.905063 -197.069085) (xy 208.919426 -197.083454) (xy 208.927202 -197.102224) (xy 208.9277 -197.112382)
			(xy 208.9277 -197.343247) (xy 210.159336 -197.343247) (xy 210.159336 -197.289949) (xy 210.167279 -197.237245)
			(xy 210.182989 -197.186315) (xy 210.206115 -197.138294) (xy 210.236139 -197.094257) (xy 210.272391 -197.055186)
			(xy 210.314062 -197.021955) (xy 210.36022 -196.995306) (xy 210.409834 -196.975834) (xy 210.461796 -196.963974)
			(xy 210.514946 -196.959991) (xy 210.568096 -196.963974) (xy 210.620058 -196.975834) (xy 210.669672 -196.995306)
			(xy 210.71583 -197.021955) (xy 210.757501 -197.055186) (xy 210.793753 -197.094257) (xy 210.823777 -197.138294)
			(xy 210.846903 -197.186315) (xy 210.862613 -197.237245) (xy 210.870556 -197.289949) (xy 210.871054 -197.316598)
			(xy 210.870556 -197.343247) (xy 212.369136 -197.343247) (xy 212.369136 -197.289949) (xy 212.377079 -197.237245)
			(xy 212.392789 -197.186315) (xy 212.415915 -197.138294) (xy 212.445939 -197.094257) (xy 212.482191 -197.055186)
			(xy 212.523862 -197.021955) (xy 212.57002 -196.995306) (xy 212.619634 -196.975834) (xy 212.671596 -196.963974)
			(xy 212.724746 -196.959991) (xy 212.777896 -196.963974) (xy 212.829858 -196.975834) (xy 212.879472 -196.995306)
			(xy 212.92563 -197.021955) (xy 212.967301 -197.055186) (xy 213.003553 -197.094257) (xy 213.033577 -197.138294)
			(xy 213.056703 -197.186315) (xy 213.072413 -197.237245) (xy 213.080356 -197.289949) (xy 213.080854 -197.316598)
			(xy 213.080356 -197.343247) (xy 213.072413 -197.395951) (xy 213.056703 -197.446881) (xy 213.033577 -197.494902)
			(xy 213.003553 -197.538939) (xy 212.967301 -197.57801) (xy 212.92563 -197.611241) (xy 212.879472 -197.63789)
			(xy 212.829858 -197.657362) (xy 212.777896 -197.669222) (xy 212.724746 -197.673206) (xy 212.671596 -197.669222)
			(xy 212.619634 -197.657362) (xy 212.57002 -197.63789) (xy 212.523862 -197.611241) (xy 212.482191 -197.57801)
			(xy 212.445939 -197.538939) (xy 212.415915 -197.494902) (xy 212.392789 -197.446881) (xy 212.377079 -197.395951)
			(xy 212.369136 -197.343247) (xy 210.870556 -197.343247) (xy 210.862613 -197.395951) (xy 210.846903 -197.446881)
			(xy 210.823777 -197.494902) (xy 210.793753 -197.538939) (xy 210.757501 -197.57801) (xy 210.71583 -197.611241)
			(xy 210.669672 -197.63789) (xy 210.620058 -197.657362) (xy 210.568096 -197.669222) (xy 210.514946 -197.673206)
			(xy 210.461796 -197.669222) (xy 210.409834 -197.657362) (xy 210.36022 -197.63789) (xy 210.314062 -197.611241)
			(xy 210.272391 -197.57801) (xy 210.236139 -197.538939) (xy 210.206115 -197.494902) (xy 210.182989 -197.446881)
			(xy 210.167279 -197.395951) (xy 210.159336 -197.343247) (xy 208.9277 -197.343247) (xy 208.9277 -197.521322)
			(xy 208.927186 -197.531477) (xy 208.919411 -197.550239) (xy 208.905052 -197.564602) (xy 208.886292 -197.572383)
			(xy 208.876138 -197.572884) (xy 207.476598 -197.572884) (xy 207.468663 -197.572605) (xy 207.453532 -197.567821)
			(xy 207.44688 -197.563486) (xy 207.435146 -197.555791) (xy 207.408701 -197.546449) (xy 207.380711 -197.544669)
			(xy 207.353295 -197.550586) (xy 207.328531 -197.563752) (xy 207.318102 -197.573138) (xy 207.298095 -197.591718)
			(xy 207.253447 -197.623145) (xy 207.204523 -197.647384) (xy 207.152472 -197.663868) (xy 207.098514 -197.672209)
			(xy 207.071214 -197.672706) (xy 207.044562 -197.672238) (xy 206.991853 -197.664295) (xy 206.940917 -197.648585)
			(xy 206.892891 -197.625459) (xy 206.848849 -197.595433) (xy 206.809773 -197.559178) (xy 206.776538 -197.517503)
			(xy 206.749886 -197.471341) (xy 206.730411 -197.421722) (xy 206.71855 -197.369755) (xy 206.714566 -197.3166)
			(xy 205.537054 -197.3166) (xy 205.536556 -197.343247) (xy 205.528613 -197.395951) (xy 205.512903 -197.446881)
			(xy 205.489777 -197.494902) (xy 205.459753 -197.538939) (xy 205.423501 -197.57801) (xy 205.38183 -197.611241)
			(xy 205.335672 -197.63789) (xy 205.286058 -197.657362) (xy 205.234096 -197.669222) (xy 205.180946 -197.673206)
			(xy 205.127796 -197.669222) (xy 205.075834 -197.657362) (xy 205.02622 -197.63789) (xy 204.980062 -197.611241)
			(xy 204.938391 -197.57801) (xy 204.902139 -197.538939) (xy 204.872115 -197.494902) (xy 204.848989 -197.446881)
			(xy 204.833279 -197.395951) (xy 204.825336 -197.343247) (xy 203.326756 -197.343247) (xy 203.318813 -197.395951)
			(xy 203.303103 -197.446881) (xy 203.279977 -197.494902) (xy 203.249953 -197.538939) (xy 203.213701 -197.57801)
			(xy 203.17203 -197.611241) (xy 203.125872 -197.63789) (xy 203.076258 -197.657362) (xy 203.024296 -197.669222)
			(xy 202.971146 -197.673206) (xy 202.917996 -197.669222) (xy 202.866034 -197.657362) (xy 202.81642 -197.63789)
			(xy 202.770262 -197.611241) (xy 202.728591 -197.57801) (xy 202.692339 -197.538939) (xy 202.662315 -197.494902)
			(xy 202.639189 -197.446881) (xy 202.623479 -197.395951) (xy 202.615536 -197.343247) (xy 201.3839 -197.343247)
			(xy 201.3839 -197.521322) (xy 201.383386 -197.531477) (xy 201.375611 -197.550239) (xy 201.361252 -197.564602)
			(xy 201.342492 -197.572383) (xy 201.332338 -197.572884) (xy 199.932798 -197.572884) (xy 199.922643 -197.572369)
			(xy 199.903878 -197.564598) (xy 199.889513 -197.550239) (xy 199.881735 -197.531477) (xy 199.881236 -197.521322)
			(xy 197.927964 -197.521322) (xy 197.915953 -197.538939) (xy 197.879701 -197.57801) (xy 197.83803 -197.611241)
			(xy 197.791872 -197.63789) (xy 197.742258 -197.657362) (xy 197.690296 -197.669222) (xy 197.637146 -197.673206)
			(xy 197.583996 -197.669222) (xy 197.532034 -197.657362) (xy 197.48242 -197.63789) (xy 197.436262 -197.611241)
			(xy 197.394591 -197.57801) (xy 197.358339 -197.538939) (xy 197.328315 -197.494902) (xy 197.305189 -197.446881)
			(xy 197.289479 -197.395951) (xy 197.281536 -197.343247) (xy 195.782956 -197.343247) (xy 195.775013 -197.395951)
			(xy 195.759303 -197.446881) (xy 195.736177 -197.494902) (xy 195.706153 -197.538939) (xy 195.669901 -197.57801)
			(xy 195.62823 -197.611241) (xy 195.582072 -197.63789) (xy 195.532458 -197.657362) (xy 195.480496 -197.669222)
			(xy 195.427346 -197.673206) (xy 195.374196 -197.669222) (xy 195.322234 -197.657362) (xy 195.27262 -197.63789)
			(xy 195.226462 -197.611241) (xy 195.184791 -197.57801) (xy 195.148539 -197.538939) (xy 195.118515 -197.494902)
			(xy 195.095389 -197.446881) (xy 195.079679 -197.395951) (xy 195.071736 -197.343247) (xy 193.8401 -197.343247)
			(xy 193.8401 -197.521322) (xy 193.839586 -197.531477) (xy 193.831811 -197.550239) (xy 193.817452 -197.564602)
			(xy 193.798692 -197.572383) (xy 193.788538 -197.572884) (xy 192.388998 -197.572884) (xy 192.381063 -197.572605)
			(xy 192.365932 -197.567821) (xy 192.35928 -197.563486) (xy 192.347546 -197.555791) (xy 192.321101 -197.546449)
			(xy 192.293111 -197.544669) (xy 192.265695 -197.550586) (xy 192.240931 -197.563752) (xy 192.230502 -197.573138)
			(xy 192.210495 -197.591718) (xy 192.165847 -197.623145) (xy 192.116923 -197.647384) (xy 192.064872 -197.663868)
			(xy 192.010914 -197.672209) (xy 191.983614 -197.672706) (xy 191.956962 -197.672238) (xy 191.904253 -197.664295)
			(xy 191.853317 -197.648585) (xy 191.805291 -197.625459) (xy 191.761249 -197.595433) (xy 191.722173 -197.559178)
			(xy 191.688938 -197.517503) (xy 191.662286 -197.471341) (xy 191.642811 -197.421722) (xy 191.63095 -197.369755)
			(xy 191.626966 -197.3166) (xy 190.449454 -197.3166) (xy 190.448956 -197.343247) (xy 190.441013 -197.395951)
			(xy 190.425303 -197.446881) (xy 190.402177 -197.494902) (xy 190.372153 -197.538939) (xy 190.335901 -197.57801)
			(xy 190.29423 -197.611241) (xy 190.248072 -197.63789) (xy 190.198458 -197.657362) (xy 190.146496 -197.669222)
			(xy 190.093346 -197.673206) (xy 190.040196 -197.669222) (xy 189.988234 -197.657362) (xy 189.93862 -197.63789)
			(xy 189.892462 -197.611241) (xy 189.850791 -197.57801) (xy 189.814539 -197.538939) (xy 189.784515 -197.494902)
			(xy 189.761389 -197.446881) (xy 189.745679 -197.395951) (xy 189.737736 -197.343247) (xy 188.239156 -197.343247)
			(xy 188.231213 -197.395951) (xy 188.215503 -197.446881) (xy 188.192377 -197.494902) (xy 188.162353 -197.538939)
			(xy 188.126101 -197.57801) (xy 188.08443 -197.611241) (xy 188.038272 -197.63789) (xy 187.988658 -197.657362)
			(xy 187.936696 -197.669222) (xy 187.883546 -197.673206) (xy 187.830396 -197.669222) (xy 187.778434 -197.657362)
			(xy 187.72882 -197.63789) (xy 187.682662 -197.611241) (xy 187.640991 -197.57801) (xy 187.604739 -197.538939)
			(xy 187.574715 -197.494902) (xy 187.551589 -197.446881) (xy 187.535879 -197.395951) (xy 187.527936 -197.343247)
			(xy 186.2963 -197.343247) (xy 186.2963 -197.521322) (xy 186.295786 -197.531477) (xy 186.288011 -197.550239)
			(xy 186.273652 -197.564602) (xy 186.254892 -197.572383) (xy 186.244738 -197.572884) (xy 184.845198 -197.572884)
			(xy 184.835043 -197.572369) (xy 184.816278 -197.564598) (xy 184.801913 -197.550239) (xy 184.794135 -197.531477)
			(xy 184.793636 -197.521322) (xy 182.840364 -197.521322) (xy 182.828353 -197.538939) (xy 182.792101 -197.57801)
			(xy 182.75043 -197.611241) (xy 182.704272 -197.63789) (xy 182.654658 -197.657362) (xy 182.602696 -197.669222)
			(xy 182.549546 -197.673206) (xy 182.496396 -197.669222) (xy 182.444434 -197.657362) (xy 182.39482 -197.63789)
			(xy 182.348662 -197.611241) (xy 182.306991 -197.57801) (xy 182.270739 -197.538939) (xy 182.240715 -197.494902)
			(xy 182.217589 -197.446881) (xy 182.201879 -197.395951) (xy 182.193936 -197.343247) (xy 180.695356 -197.343247)
			(xy 180.687413 -197.395951) (xy 180.671703 -197.446881) (xy 180.648577 -197.494902) (xy 180.618553 -197.538939)
			(xy 180.582301 -197.57801) (xy 180.54063 -197.611241) (xy 180.494472 -197.63789) (xy 180.444858 -197.657362)
			(xy 180.392896 -197.669222) (xy 180.339746 -197.673206) (xy 180.286596 -197.669222) (xy 180.234634 -197.657362)
			(xy 180.18502 -197.63789) (xy 180.138862 -197.611241) (xy 180.097191 -197.57801) (xy 180.060939 -197.538939)
			(xy 180.030915 -197.494902) (xy 180.007789 -197.446881) (xy 179.992079 -197.395951) (xy 179.984136 -197.343247)
			(xy 178.7525 -197.343247) (xy 178.7525 -197.521322) (xy 178.751986 -197.531477) (xy 178.744211 -197.550239)
			(xy 178.729852 -197.564602) (xy 178.711092 -197.572383) (xy 178.700938 -197.572884) (xy 177.301398 -197.572884)
			(xy 177.293463 -197.572605) (xy 177.278332 -197.567821) (xy 177.27168 -197.563486) (xy 177.259946 -197.555791)
			(xy 177.233501 -197.546449) (xy 177.205511 -197.544669) (xy 177.178095 -197.550586) (xy 177.153331 -197.563752)
			(xy 177.142902 -197.573138) (xy 177.122895 -197.591718) (xy 177.078247 -197.623145) (xy 177.029323 -197.647384)
			(xy 176.977272 -197.663868) (xy 176.923314 -197.672209) (xy 176.896014 -197.672706) (xy 176.869362 -197.672238)
			(xy 176.816653 -197.664295) (xy 176.765717 -197.648585) (xy 176.717691 -197.625459) (xy 176.673649 -197.595433)
			(xy 176.634573 -197.559178) (xy 176.601338 -197.517503) (xy 176.574686 -197.471341) (xy 176.555211 -197.421722)
			(xy 176.54335 -197.369755) (xy 176.539366 -197.3166) (xy 175.361854 -197.3166) (xy 175.361356 -197.343247)
			(xy 175.353413 -197.395951) (xy 175.337703 -197.446881) (xy 175.314577 -197.494902) (xy 175.284553 -197.538939)
			(xy 175.248301 -197.57801) (xy 175.20663 -197.611241) (xy 175.160472 -197.63789) (xy 175.110858 -197.657362)
			(xy 175.058896 -197.669222) (xy 175.005746 -197.673206) (xy 174.952596 -197.669222) (xy 174.900634 -197.657362)
			(xy 174.85102 -197.63789) (xy 174.804862 -197.611241) (xy 174.763191 -197.57801) (xy 174.726939 -197.538939)
			(xy 174.696915 -197.494902) (xy 174.673789 -197.446881) (xy 174.658079 -197.395951) (xy 174.650136 -197.343247)
			(xy 173.151556 -197.343247) (xy 173.143613 -197.395951) (xy 173.127903 -197.446881) (xy 173.104777 -197.494902)
			(xy 173.074753 -197.538939) (xy 173.038501 -197.57801) (xy 172.99683 -197.611241) (xy 172.950672 -197.63789)
			(xy 172.901058 -197.657362) (xy 172.849096 -197.669222) (xy 172.795946 -197.673206) (xy 172.742796 -197.669222)
			(xy 172.690834 -197.657362) (xy 172.64122 -197.63789) (xy 172.595062 -197.611241) (xy 172.553391 -197.57801)
			(xy 172.517139 -197.538939) (xy 172.487115 -197.494902) (xy 172.463989 -197.446881) (xy 172.448279 -197.395951)
			(xy 172.440336 -197.343247) (xy 171.2087 -197.343247) (xy 171.2087 -197.521322) (xy 171.208186 -197.531477)
			(xy 171.200411 -197.550239) (xy 171.186052 -197.564602) (xy 171.167292 -197.572383) (xy 171.157138 -197.572884)
			(xy 169.757598 -197.572884) (xy 169.747443 -197.572369) (xy 169.728678 -197.564598) (xy 169.714313 -197.550239)
			(xy 169.706535 -197.531477) (xy 169.706036 -197.521322) (xy 167.752764 -197.521322) (xy 167.740753 -197.538939)
			(xy 167.704501 -197.57801) (xy 167.66283 -197.611241) (xy 167.616672 -197.63789) (xy 167.567058 -197.657362)
			(xy 167.515096 -197.669222) (xy 167.461946 -197.673206) (xy 167.408796 -197.669222) (xy 167.356834 -197.657362)
			(xy 167.30722 -197.63789) (xy 167.261062 -197.611241) (xy 167.219391 -197.57801) (xy 167.183139 -197.538939)
			(xy 167.153115 -197.494902) (xy 167.129989 -197.446881) (xy 167.114279 -197.395951) (xy 167.106336 -197.343247)
			(xy 165.607756 -197.343247) (xy 165.599813 -197.395951) (xy 165.584103 -197.446881) (xy 165.560977 -197.494902)
			(xy 165.530953 -197.538939) (xy 165.494701 -197.57801) (xy 165.45303 -197.611241) (xy 165.406872 -197.63789)
			(xy 165.357258 -197.657362) (xy 165.305296 -197.669222) (xy 165.252146 -197.673206) (xy 165.198996 -197.669222)
			(xy 165.147034 -197.657362) (xy 165.09742 -197.63789) (xy 165.051262 -197.611241) (xy 165.009591 -197.57801)
			(xy 164.973339 -197.538939) (xy 164.943315 -197.494902) (xy 164.920189 -197.446881) (xy 164.904479 -197.395951)
			(xy 164.896536 -197.343247) (xy 163.6649 -197.343247) (xy 163.6649 -197.521322) (xy 163.664386 -197.531477)
			(xy 163.656611 -197.550239) (xy 163.642252 -197.564602) (xy 163.623492 -197.572383) (xy 163.613338 -197.572884)
			(xy 162.213798 -197.572884) (xy 162.203643 -197.572369) (xy 162.184878 -197.564598) (xy 162.170513 -197.550239)
			(xy 162.162735 -197.531477) (xy 162.162236 -197.521322) (xy 160.208964 -197.521322) (xy 160.196953 -197.538939)
			(xy 160.160701 -197.57801) (xy 160.11903 -197.611241) (xy 160.072872 -197.63789) (xy 160.023258 -197.657362)
			(xy 159.971296 -197.669222) (xy 159.918146 -197.673206) (xy 159.864996 -197.669222) (xy 159.813034 -197.657362)
			(xy 159.76342 -197.63789) (xy 159.717262 -197.611241) (xy 159.675591 -197.57801) (xy 159.639339 -197.538939)
			(xy 159.609315 -197.494902) (xy 159.586189 -197.446881) (xy 159.570479 -197.395951) (xy 159.562536 -197.343247)
			(xy 158.063956 -197.343247) (xy 158.056013 -197.395951) (xy 158.040303 -197.446881) (xy 158.017177 -197.494902)
			(xy 157.987153 -197.538939) (xy 157.950901 -197.57801) (xy 157.90923 -197.611241) (xy 157.863072 -197.63789)
			(xy 157.813458 -197.657362) (xy 157.761496 -197.669222) (xy 157.708346 -197.673206) (xy 157.655196 -197.669222)
			(xy 157.603234 -197.657362) (xy 157.55362 -197.63789) (xy 157.507462 -197.611241) (xy 157.465791 -197.57801)
			(xy 157.429539 -197.538939) (xy 157.399515 -197.494902) (xy 157.376389 -197.446881) (xy 157.360679 -197.395951)
			(xy 157.352736 -197.343247) (xy 145.832047 -197.343247) (xy 146.3294 -197.8406) (xy 161.665158 -197.8406)
		)
		(stroke
			(width 0)
			(type solid)
		)
		(fill yes)
		(layer "In2.Cu")
		(net "P3V3_AUX")
	)
	(gr_poly
		(pts
			(xy 124.117862 -270.570706) (xy 124.06249 -270.515334) (xy 124.035566 -270.520922) (xy 124.018805 -270.524224)
			(xy 123.984829 -270.527791) (xy 123.967748 -270.528034) (xy 123.941778 -270.527555) (xy 123.890476 -270.519436)
			(xy 123.841076 -270.503392) (xy 123.794795 -270.479816) (xy 123.752771 -270.44929) (xy 123.716041 -270.412565)
			(xy 123.685509 -270.370546) (xy 123.661927 -270.324268) (xy 123.645875 -270.274871) (xy 123.637749 -270.22357)
			(xy 123.637749 -270.17163) (xy 123.645875 -270.120329) (xy 123.661927 -270.070932) (xy 123.685509 -270.024654)
			(xy 123.716041 -269.982635) (xy 123.752771 -269.94591) (xy 123.794795 -269.915384) (xy 123.841076 -269.891808)
			(xy 123.890476 -269.875764) (xy 123.941778 -269.867645) (xy 123.967748 -269.867126) (xy 123.996743 -269.867706)
			(xy 124.053847 -269.877801) (xy 124.081286 -269.887192) (xy 124.094553 -269.891596) (xy 124.122414 -269.893754)
			(xy 124.149817 -269.888281) (xy 124.174711 -269.875587) (xy 124.195233 -269.85662) (xy 124.209847 -269.832801)
			(xy 124.217458 -269.805913) (xy 124.217938 -269.791942) (xy 124.217938 -269.630652) (xy 124.199268 -269.613438)
			(xy 124.166915 -269.574296) (xy 124.140927 -269.530668) (xy 124.121914 -269.48358) (xy 124.110324 -269.434139)
			(xy 124.10643 -269.383507) (xy 124.110322 -269.332874) (xy 124.12191 -269.283433) (xy 124.140921 -269.236344)
			(xy 124.166907 -269.192715) (xy 124.199258 -269.153572) (xy 124.217938 -269.136368) (xy 124.217938 -268.975332)
			(xy 124.217501 -268.961354) (xy 124.209917 -268.934447) (xy 124.19531 -268.910611) (xy 124.174779 -268.891638)
			(xy 124.149867 -268.878955) (xy 124.122446 -268.873514) (xy 124.094578 -268.875725) (xy 124.081286 -268.880082)
			(xy 124.053842 -268.889451) (xy 123.996741 -268.899539) (xy 123.967748 -268.900148) (xy 123.941777 -268.899669)
			(xy 123.890473 -268.89155) (xy 123.841071 -268.875505) (xy 123.794787 -268.851928) (xy 123.752762 -268.821401)
			(xy 123.716031 -268.784674) (xy 123.685497 -268.742654) (xy 123.661914 -268.696374) (xy 123.645861 -268.646974)
			(xy 123.637735 -268.595671) (xy 123.637735 -268.543729) (xy 123.645861 -268.492426) (xy 123.661914 -268.443026)
			(xy 123.685497 -268.396746) (xy 123.716031 -268.354726) (xy 123.752762 -268.317999) (xy 123.794787 -268.287472)
			(xy 123.841071 -268.263895) (xy 123.890473 -268.24785) (xy 123.941777 -268.239731) (xy 123.967748 -268.23924)
			(xy 123.996743 -268.239821) (xy 124.053847 -268.249916) (xy 124.081286 -268.259306) (xy 124.094554 -268.263709)
			(xy 124.122416 -268.265867) (xy 124.14982 -268.260395) (xy 124.174715 -268.2477) (xy 124.195239 -268.228734)
			(xy 124.209855 -268.204916) (xy 124.217469 -268.178028) (xy 124.217938 -268.164056) (xy 124.217938 -268.00302)
			(xy 124.19927 -267.985806) (xy 124.166922 -267.946665) (xy 124.140938 -267.903039) (xy 124.12193 -267.855953)
			(xy 124.110345 -267.806514) (xy 124.106454 -267.755885) (xy 124.110349 -267.705257) (xy 124.121939 -267.655819)
			(xy 124.140951 -267.608735) (xy 124.166939 -267.565111) (xy 124.19929 -267.525973) (xy 124.217938 -267.508736)
			(xy 124.217938 -267.347446) (xy 124.217503 -267.333467) (xy 124.209921 -267.306556) (xy 124.195315 -267.282717)
			(xy 124.174783 -267.263741) (xy 124.149868 -267.251055) (xy 124.122445 -267.245614) (xy 124.094574 -267.247826)
			(xy 124.081286 -267.252196) (xy 124.053842 -267.261565) (xy 123.996741 -267.271652) (xy 123.967748 -267.272262)
			(xy 123.941776 -267.271783) (xy 123.890469 -267.263663) (xy 123.841065 -267.247617) (xy 123.79478 -267.22404)
			(xy 123.752753 -267.193511) (xy 123.71602 -267.156783) (xy 123.685485 -267.114761) (xy 123.661901 -267.068479)
			(xy 123.645848 -267.019077) (xy 123.637721 -266.967772) (xy 123.637721 -266.915828) (xy 123.645848 -266.864523)
			(xy 123.661901 -266.815121) (xy 123.685485 -266.768839) (xy 123.71602 -266.726817) (xy 123.752753 -266.690089)
			(xy 123.79478 -266.65956) (xy 123.841065 -266.635983) (xy 123.890469 -266.619937) (xy 123.941776 -266.611817)
			(xy 123.967748 -266.611354) (xy 123.996743 -266.611934) (xy 124.053848 -266.622027) (xy 124.081286 -266.63142)
			(xy 124.094555 -266.635823) (xy 124.122417 -266.637981) (xy 124.149822 -266.632508) (xy 124.174719 -266.619813)
			(xy 124.195244 -266.600848) (xy 124.209863 -266.57703) (xy 124.21748 -266.550142) (xy 124.217938 -266.53617)
			(xy 124.217938 -266.375388) (xy 124.199265 -266.358174) (xy 124.166906 -266.319032) (xy 124.140913 -266.275402)
			(xy 124.121895 -266.228311) (xy 124.110301 -266.178867) (xy 124.106402 -266.128231) (xy 124.110291 -266.077594)
			(xy 124.121877 -266.028147) (xy 124.140885 -265.981053) (xy 124.166871 -265.937418) (xy 124.199222 -265.89827)
			(xy 124.217938 -265.881104) (xy 124.217938 -265.719814) (xy 124.217499 -265.705838) (xy 124.209912 -265.678935)
			(xy 124.195305 -265.655104) (xy 124.174774 -265.636135) (xy 124.149864 -265.623454) (xy 124.122447 -265.618014)
			(xy 124.094582 -265.620224) (xy 124.081286 -265.624564) (xy 124.053842 -265.633931) (xy 123.99674 -265.644017)
			(xy 123.967748 -265.64463) (xy 123.941778 -265.644151) (xy 123.890477 -265.636032) (xy 123.841078 -265.619988)
			(xy 123.794797 -265.596413) (xy 123.752774 -265.565887) (xy 123.716044 -265.529163) (xy 123.685513 -265.487144)
			(xy 123.66193 -265.440867) (xy 123.645879 -265.39147) (xy 123.637753 -265.34017) (xy 123.637753 -265.28823)
			(xy 123.645879 -265.23693) (xy 123.66193 -265.187533) (xy 123.685513 -265.141256) (xy 123.716044 -265.099237)
			(xy 123.752774 -265.062513) (xy 123.794797 -265.031987) (xy 123.841078 -265.008412) (xy 123.890477 -264.992368)
			(xy 123.941778 -264.984249) (xy 123.967748 -264.983722) (xy 123.996743 -264.984302) (xy 124.053847 -264.994397)
			(xy 124.081286 -265.003788) (xy 124.094553 -265.008192) (xy 124.122414 -265.010351) (xy 124.149816 -265.004878)
			(xy 124.17471 -264.992183) (xy 124.195232 -264.973216) (xy 124.209844 -264.949397) (xy 124.217455 -264.922509)
			(xy 124.217938 -264.908538) (xy 124.217938 -264.747502) (xy 124.199271 -264.730288) (xy 124.166926 -264.691147)
			(xy 124.140945 -264.647522) (xy 124.12194 -264.600437) (xy 124.110356 -264.551) (xy 124.106467 -264.500373)
			(xy 124.110364 -264.449747) (xy 124.121956 -264.400312) (xy 124.140969 -264.35323) (xy 124.166957 -264.309609)
			(xy 124.199308 -264.270474) (xy 124.217938 -264.253218) (xy 124.217938 -264.092182) (xy 124.217507 -264.078199)
			(xy 124.209932 -264.05128) (xy 124.195327 -264.027431) (xy 124.174793 -264.008448) (xy 124.149873 -263.995757)
			(xy 124.122443 -263.990314) (xy 124.094565 -263.992528) (xy 124.081286 -263.996932) (xy 124.053842 -264.0063)
			(xy 123.996741 -264.016386) (xy 123.967748 -264.016998) (xy 123.941773 -264.016519) (xy 123.890461 -264.008399)
			(xy 123.841052 -263.992351) (xy 123.794761 -263.96877) (xy 123.75273 -263.938239) (xy 123.715993 -263.901507)
			(xy 123.685455 -263.85948) (xy 123.661868 -263.813193) (xy 123.645813 -263.763786) (xy 123.637685 -263.712475)
			(xy 123.637685 -263.660525) (xy 123.645813 -263.609214) (xy 123.661868 -263.559807) (xy 123.685455 -263.51352)
			(xy 123.715993 -263.471493) (xy 123.75273 -263.434761) (xy 123.794761 -263.40423) (xy 123.841052 -263.380649)
			(xy 123.890461 -263.364601) (xy 123.941773 -263.356481) (xy 123.967748 -263.35609) (xy 123.996743 -263.35667)
			(xy 124.053848 -263.366764) (xy 124.081286 -263.376156) (xy 124.094552 -263.380561) (xy 124.12241 -263.382721)
			(xy 124.149811 -263.377248) (xy 124.174702 -263.364552) (xy 124.195219 -263.345584) (xy 124.209826 -263.321764)
			(xy 124.217429 -263.294876) (xy 124.217938 -263.280906) (xy 124.217938 -263.119616) (xy 124.19927 -263.102402)
			(xy 124.166923 -263.063261) (xy 124.14094 -263.019635) (xy 124.121932 -262.972549) (xy 124.110347 -262.923111)
			(xy 124.106457 -262.872483) (xy 124.110352 -262.821855) (xy 124.121943 -262.772418) (xy 124.140955 -262.725334)
			(xy 124.166943 -262.681711) (xy 124.199294 -262.642573) (xy 124.217938 -262.625332) (xy 124.217938 -262.464296)
			(xy 124.217509 -262.450312) (xy 124.209936 -262.423389) (xy 124.195332 -262.399537) (xy 124.174796 -262.38055)
			(xy 124.149875 -262.367857) (xy 124.122442 -262.362414) (xy 124.094562 -262.364629) (xy 124.081286 -262.369046)
			(xy 124.053842 -262.378414) (xy 123.996741 -262.3885) (xy 123.967748 -262.389112) (xy 123.94178 -262.388633)
			(xy 123.890481 -262.380515) (xy 123.841084 -262.364471) (xy 123.794806 -262.340897) (xy 123.752786 -262.310373)
			(xy 123.716058 -262.273651) (xy 123.685528 -262.231635) (xy 123.661947 -262.18536) (xy 123.645896 -262.135966)
			(xy 123.637771 -262.084668) (xy 123.637771 -262.032732) (xy 123.645896 -261.981434) (xy 123.661947 -261.93204)
			(xy 123.685528 -261.885765) (xy 123.716058 -261.843749) (xy 123.752786 -261.807027) (xy 123.794806 -261.776503)
			(xy 123.841084 -261.752929) (xy 123.890481 -261.736885) (xy 123.94178 -261.728767) (xy 123.967748 -261.728204)
			(xy 123.996743 -261.728784) (xy 124.053848 -261.738878) (xy 124.081286 -261.74827) (xy 124.094552 -261.752674)
			(xy 124.122412 -261.754834) (xy 124.149813 -261.749361) (xy 124.174705 -261.736666) (xy 124.195225 -261.717698)
			(xy 124.209834 -261.693879) (xy 124.21744 -261.666991) (xy 124.217938 -261.65302) (xy 124.217938 -261.491984)
			(xy 124.197456 -261.472989) (xy 124.162547 -261.429384) (xy 124.135458 -261.380536) (xy 124.116956 -261.327833)
			(xy 124.107568 -261.27277) (xy 124.10694 -261.244842) (xy 124.107448 -261.218947) (xy 124.115533 -261.167793)
			(xy 124.131497 -261.118526) (xy 124.154949 -261.072351) (xy 124.185316 -261.030398) (xy 124.203206 -261.01167)
			(xy 124.217938 -260.996938) (xy 124.217938 -260.92277) (xy 124.047758 -260.75259) (xy 124.02185 -260.756654)
			(xy 124.008425 -260.75878) (xy 123.981339 -260.761072) (xy 123.967748 -260.761226) (xy 123.941178 -260.760692)
			(xy 123.888723 -260.752184) (xy 123.838305 -260.735396) (xy 123.79122 -260.710759) (xy 123.748683 -260.678909)
			(xy 123.711788 -260.640665) (xy 123.681484 -260.597012) (xy 123.669552 -260.573266) (xy 123.655836 -260.54431)
			(xy 123.33986 -260.54431) (xy 123.326144 -260.573266) (xy 123.314214 -260.597018) (xy 123.283929 -260.640695)
			(xy 123.247042 -260.67896) (xy 123.204505 -260.710827) (xy 123.157416 -260.735473) (xy 123.106988 -260.752263)
			(xy 123.054523 -260.760763) (xy 123.027948 -260.761226) (xy 123.003263 -260.760771) (xy 122.954441 -260.753432)
			(xy 122.907255 -260.738911) (xy 122.862755 -260.717531) (xy 122.82193 -260.689768) (xy 122.785692 -260.65624)
			(xy 122.754845 -260.617692) (xy 122.730077 -260.574985) (xy 122.720608 -260.552184) (xy 122.707908 -260.52018)
			(xy 122.408188 -260.52018) (xy 122.395488 -260.552184) (xy 122.385338 -260.576486) (xy 122.358465 -260.621777)
			(xy 122.324749 -260.662232) (xy 122.285044 -260.696828) (xy 122.240354 -260.724689) (xy 122.191811 -260.745109)
			(xy 122.140644 -260.757572) (xy 122.088148 -260.761761) (xy 122.035652 -260.757572) (xy 121.984485 -260.745109)
			(xy 121.935942 -260.724689) (xy 121.891252 -260.696828) (xy 121.851547 -260.662232) (xy 121.817831 -260.621777)
			(xy 121.790958 -260.576486) (xy 121.780808 -260.552184) (xy 121.768108 -260.52018) (xy 119.918226 -260.52018)
			(xy 119.167597 -261.270809) (xy 121.288049 -261.270809) (xy 121.288049 -261.218875) (xy 121.296174 -261.16758)
			(xy 121.312222 -261.118187) (xy 121.3358 -261.071913) (xy 121.366326 -261.029897) (xy 121.403049 -260.993174)
			(xy 121.445065 -260.962648) (xy 121.491339 -260.93907) (xy 121.540732 -260.923022) (xy 121.592027 -260.914897)
			(xy 121.643961 -260.914897) (xy 121.695256 -260.923022) (xy 121.744649 -260.93907) (xy 121.790923 -260.962648)
			(xy 121.832939 -260.993174) (xy 121.869662 -261.029897) (xy 121.900188 -261.071913) (xy 121.923766 -261.118187)
			(xy 121.939814 -261.16758) (xy 121.947939 -261.218875) (xy 121.948448 -261.244842) (xy 121.947939 -261.270809)
			(xy 122.227849 -261.270809) (xy 122.227849 -261.218875) (xy 122.235974 -261.16758) (xy 122.252022 -261.118187)
			(xy 122.2756 -261.071913) (xy 122.306126 -261.029897) (xy 122.342849 -260.993174) (xy 122.384865 -260.962648)
			(xy 122.431139 -260.93907) (xy 122.480532 -260.923022) (xy 122.531827 -260.914897) (xy 122.583761 -260.914897)
			(xy 122.635056 -260.923022) (xy 122.684449 -260.93907) (xy 122.730723 -260.962648) (xy 122.772739 -260.993174)
			(xy 122.809462 -261.029897) (xy 122.839988 -261.071913) (xy 122.863566 -261.118187) (xy 122.879614 -261.16758)
			(xy 122.887739 -261.218875) (xy 122.888248 -261.244842) (xy 122.887739 -261.270809) (xy 123.167649 -261.270809)
			(xy 123.167649 -261.218875) (xy 123.175774 -261.16758) (xy 123.191822 -261.118187) (xy 123.2154 -261.071913)
			(xy 123.245926 -261.029897) (xy 123.282649 -260.993174) (xy 123.324665 -260.962648) (xy 123.370939 -260.93907)
			(xy 123.420332 -260.923022) (xy 123.471627 -260.914897) (xy 123.523561 -260.914897) (xy 123.574856 -260.923022)
			(xy 123.624249 -260.93907) (xy 123.670523 -260.962648) (xy 123.712539 -260.993174) (xy 123.749262 -261.029897)
			(xy 123.779788 -261.071913) (xy 123.803366 -261.118187) (xy 123.819414 -261.16758) (xy 123.827539 -261.218875)
			(xy 123.828048 -261.244842) (xy 123.827539 -261.270809) (xy 123.819414 -261.322104) (xy 123.803366 -261.371497)
			(xy 123.779788 -261.417771) (xy 123.749262 -261.459787) (xy 123.712539 -261.49651) (xy 123.670523 -261.527036)
			(xy 123.624249 -261.550614) (xy 123.574856 -261.566662) (xy 123.523561 -261.574787) (xy 123.471627 -261.574787)
			(xy 123.420332 -261.566662) (xy 123.370939 -261.550614) (xy 123.324665 -261.527036) (xy 123.282649 -261.49651)
			(xy 123.245926 -261.459787) (xy 123.2154 -261.417771) (xy 123.191822 -261.371497) (xy 123.175774 -261.322104)
			(xy 123.167649 -261.270809) (xy 122.887739 -261.270809) (xy 122.879614 -261.322104) (xy 122.863566 -261.371497)
			(xy 122.839988 -261.417771) (xy 122.809462 -261.459787) (xy 122.772739 -261.49651) (xy 122.730723 -261.527036)
			(xy 122.684449 -261.550614) (xy 122.635056 -261.566662) (xy 122.583761 -261.574787) (xy 122.531827 -261.574787)
			(xy 122.480532 -261.566662) (xy 122.431139 -261.550614) (xy 122.384865 -261.527036) (xy 122.342849 -261.49651)
			(xy 122.306126 -261.459787) (xy 122.2756 -261.417771) (xy 122.252022 -261.371497) (xy 122.235974 -261.322104)
			(xy 122.227849 -261.270809) (xy 121.947939 -261.270809) (xy 121.939814 -261.322104) (xy 121.923766 -261.371497)
			(xy 121.900188 -261.417771) (xy 121.869662 -261.459787) (xy 121.832939 -261.49651) (xy 121.790923 -261.527036)
			(xy 121.744649 -261.550614) (xy 121.695256 -261.566662) (xy 121.643961 -261.574787) (xy 121.592027 -261.574787)
			(xy 121.540732 -261.566662) (xy 121.491339 -261.550614) (xy 121.445065 -261.527036) (xy 121.403049 -261.49651)
			(xy 121.366326 -261.459787) (xy 121.3358 -261.417771) (xy 121.312222 -261.371497) (xy 121.296174 -261.322104)
			(xy 121.288049 -261.270809) (xy 119.167597 -261.270809) (xy 118.419626 -262.01878) (xy 116.749068 -262.01878)
			(xy 116.733425 -262.019353) (xy 116.703604 -262.028813) (xy 116.678033 -262.04684) (xy 116.659102 -262.071748)
			(xy 116.654503 -262.084625) (xy 121.758203 -262.084625) (xy 121.758203 -262.032691) (xy 121.766328 -261.981396)
			(xy 121.782376 -261.932003) (xy 121.805954 -261.885729) (xy 121.83648 -261.843713) (xy 121.873203 -261.80699)
			(xy 121.915219 -261.776464) (xy 121.961493 -261.752886) (xy 122.010886 -261.736838) (xy 122.062181 -261.728713)
			(xy 122.114115 -261.728713) (xy 122.16541 -261.736838) (xy 122.214803 -261.752886) (xy 122.261077 -261.776464)
			(xy 122.303093 -261.80699) (xy 122.339816 -261.843713) (xy 122.370342 -261.885729) (xy 122.39392 -261.932003)
			(xy 122.409968 -261.981396) (xy 122.418093 -262.032691) (xy 122.418602 -262.058658) (xy 122.418093 -262.084625)
			(xy 122.697749 -262.084625) (xy 122.697749 -262.032691) (xy 122.705874 -261.981396) (xy 122.721922 -261.932003)
			(xy 122.7455 -261.885729) (xy 122.776026 -261.843713) (xy 122.812749 -261.80699) (xy 122.854765 -261.776464)
			(xy 122.901039 -261.752886) (xy 122.950432 -261.736838) (xy 123.001727 -261.728713) (xy 123.053661 -261.728713)
			(xy 123.104956 -261.736838) (xy 123.154349 -261.752886) (xy 123.200623 -261.776464) (xy 123.242639 -261.80699)
			(xy 123.279362 -261.843713) (xy 123.309888 -261.885729) (xy 123.333466 -261.932003) (xy 123.349514 -261.981396)
			(xy 123.357639 -262.032691) (xy 123.358148 -262.058658) (xy 123.357639 -262.084625) (xy 123.349514 -262.13592)
			(xy 123.333466 -262.185313) (xy 123.309888 -262.231587) (xy 123.279362 -262.273603) (xy 123.242639 -262.310326)
			(xy 123.200623 -262.340852) (xy 123.154349 -262.36443) (xy 123.104956 -262.380478) (xy 123.053661 -262.388603)
			(xy 123.001727 -262.388603) (xy 122.950432 -262.380478) (xy 122.901039 -262.36443) (xy 122.854765 -262.340852)
			(xy 122.812749 -262.310326) (xy 122.776026 -262.273603) (xy 122.7455 -262.231587) (xy 122.721922 -262.185313)
			(xy 122.705874 -262.13592) (xy 122.697749 -262.084625) (xy 122.418093 -262.084625) (xy 122.409968 -262.13592)
			(xy 122.39392 -262.185313) (xy 122.370342 -262.231587) (xy 122.339816 -262.273603) (xy 122.303093 -262.310326)
			(xy 122.261077 -262.340852) (xy 122.214803 -262.36443) (xy 122.16541 -262.380478) (xy 122.114115 -262.388603)
			(xy 122.062181 -262.388603) (xy 122.010886 -262.380478) (xy 121.961493 -262.36443) (xy 121.915219 -262.340852)
			(xy 121.873203 -262.310326) (xy 121.83648 -262.273603) (xy 121.805954 -262.231587) (xy 121.782376 -262.185313)
			(xy 121.766328 -262.13592) (xy 121.758203 -262.084625) (xy 116.654503 -262.084625) (xy 116.64858 -262.101211)
			(xy 116.647468 -262.116824) (xy 116.646031 -262.142889) (xy 116.635962 -262.194108) (xy 116.617958 -262.243105)
			(xy 116.59247 -262.288659) (xy 116.560132 -262.329635) (xy 116.541296 -262.34771) (xy 116.531316 -262.357544)
			(xy 116.516688 -262.381429) (xy 116.509087 -262.408386) (xy 116.509085 -262.436395) (xy 116.51668 -262.463354)
			(xy 116.531303 -262.487241) (xy 116.541296 -262.497062) (xy 116.560994 -262.515972) (xy 116.594518 -262.559067)
			(xy 116.620495 -262.60709) (xy 116.638218 -262.658732) (xy 116.647203 -262.712587) (xy 116.647722 -262.739886)
			(xy 116.647131 -262.767912) (xy 116.63767 -262.82316) (xy 116.619018 -262.876018) (xy 116.59171 -262.924968)
			(xy 116.57457 -262.94715) (xy 116.566343 -262.958151) (xy 116.555516 -262.983385) (xy 116.551798 -263.010591)
			(xy 116.555458 -263.037805) (xy 116.566231 -263.063063) (xy 116.58334 -263.08454) (xy 116.60555 -263.100688)
			(xy 116.618258 -263.1059) (xy 116.647791 -263.117729) (xy 116.702019 -263.150981) (xy 116.725954 -263.17194)
			(xy 116.737443 -263.181743) (xy 116.76468 -263.194757) (xy 116.794534 -263.199225) (xy 116.824388 -263.194757)
			(xy 116.851625 -263.181743) (xy 116.863114 -263.17194) (xy 116.881518 -263.155682) (xy 116.922228 -263.128225)
			(xy 116.966552 -263.107091) (xy 117.013514 -263.092745) (xy 117.062082 -263.085502) (xy 117.086634 -263.085072)
			(xy 117.111187 -263.085502) (xy 117.159756 -263.092734) (xy 117.206719 -263.107079) (xy 117.25104 -263.12822)
			(xy 117.291741 -263.155691) (xy 117.310154 -263.17194) (xy 117.321643 -263.181743) (xy 117.34888 -263.194757)
			(xy 117.378734 -263.199225) (xy 117.408588 -263.194757) (xy 117.435825 -263.181743) (xy 117.447314 -263.17194)
			(xy 117.465718 -263.155682) (xy 117.506428 -263.128225) (xy 117.550752 -263.107091) (xy 117.597714 -263.092745)
			(xy 117.646282 -263.085502) (xy 117.670834 -263.085072) (xy 117.696797 -263.085584) (xy 117.748084 -263.093712)
			(xy 117.797468 -263.109762) (xy 117.843734 -263.13334) (xy 117.885742 -263.163864) (xy 117.922458 -263.200584)
			(xy 117.952978 -263.242595) (xy 117.976551 -263.288863) (xy 117.992596 -263.338249) (xy 118.000719 -263.389537)
			(xy 118.000719 -263.391963) (xy 118.382543 -263.391963) (xy 118.382543 -263.340029) (xy 118.390668 -263.288734)
			(xy 118.406716 -263.239341) (xy 118.430294 -263.193067) (xy 118.46082 -263.151051) (xy 118.497543 -263.114328)
			(xy 118.539559 -263.083802) (xy 118.585833 -263.060224) (xy 118.635226 -263.044176) (xy 118.686521 -263.036051)
			(xy 118.738455 -263.036051) (xy 118.78975 -263.044176) (xy 118.839143 -263.060224) (xy 118.885417 -263.083802)
			(xy 118.927433 -263.114328) (xy 118.964156 -263.151051) (xy 118.994682 -263.193067) (xy 119.01826 -263.239341)
			(xy 119.034308 -263.288734) (xy 119.036658 -263.30357) (xy 119.375633 -263.30357) (xy 119.375633 -263.25163)
			(xy 119.383759 -263.200328) (xy 119.39981 -263.15093) (xy 119.423392 -263.104651) (xy 119.453923 -263.062631)
			(xy 119.490653 -263.025905) (xy 119.532675 -262.995377) (xy 119.578956 -262.971799) (xy 119.628356 -262.955752)
			(xy 119.679658 -262.947631) (xy 119.705628 -262.94715) (xy 119.732142 -262.947677) (xy 119.784486 -262.956165)
			(xy 119.834799 -262.972918) (xy 119.858536 -262.984742) (xy 119.872252 -262.991257) (xy 119.902084 -262.996822)
			(xy 119.932234 -262.993381) (xy 119.960044 -262.981237) (xy 119.983062 -262.961461) (xy 119.991632 -262.948928)
			(xy 120.0069 -262.925775) (xy 120.043972 -262.884529) (xy 120.087412 -262.850053) (xy 120.135998 -262.823315)
			(xy 120.188368 -262.805066) (xy 120.243049 -262.795818) (xy 120.270778 -262.795258) (xy 120.296749 -262.795715)
			(xy 120.348053 -262.803838) (xy 120.397454 -262.819886) (xy 120.443737 -262.843466) (xy 120.48576 -262.873995)
			(xy 120.510208 -262.898441) (xy 121.288049 -262.898441) (xy 121.288049 -262.846507) (xy 121.296174 -262.795212)
			(xy 121.312222 -262.745819) (xy 121.3358 -262.699545) (xy 121.366326 -262.657529) (xy 121.403049 -262.620806)
			(xy 121.445065 -262.59028) (xy 121.491339 -262.566702) (xy 121.540732 -262.550654) (xy 121.592027 -262.542529)
			(xy 121.643961 -262.542529) (xy 121.695256 -262.550654) (xy 121.744649 -262.566702) (xy 121.790923 -262.59028)
			(xy 121.832939 -262.620806) (xy 121.869662 -262.657529) (xy 121.900188 -262.699545) (xy 121.923766 -262.745819)
			(xy 121.939814 -262.795212) (xy 121.947939 -262.846507) (xy 121.948448 -262.872474) (xy 121.947939 -262.898441)
			(xy 122.228103 -262.898441) (xy 122.228103 -262.846507) (xy 122.236228 -262.795212) (xy 122.252276 -262.745819)
			(xy 122.275854 -262.699545) (xy 122.30638 -262.657529) (xy 122.343103 -262.620806) (xy 122.385119 -262.59028)
			(xy 122.431393 -262.566702) (xy 122.480786 -262.550654) (xy 122.532081 -262.542529) (xy 122.584015 -262.542529)
			(xy 122.63531 -262.550654) (xy 122.684703 -262.566702) (xy 122.730977 -262.59028) (xy 122.772993 -262.620806)
			(xy 122.809716 -262.657529) (xy 122.840242 -262.699545) (xy 122.86382 -262.745819) (xy 122.879868 -262.795212)
			(xy 122.887993 -262.846507) (xy 122.888502 -262.872474) (xy 122.887993 -262.898441) (xy 123.167649 -262.898441)
			(xy 123.167649 -262.846507) (xy 123.175774 -262.795212) (xy 123.191822 -262.745819) (xy 123.2154 -262.699545)
			(xy 123.245926 -262.657529) (xy 123.282649 -262.620806) (xy 123.324665 -262.59028) (xy 123.370939 -262.566702)
			(xy 123.420332 -262.550654) (xy 123.471627 -262.542529) (xy 123.523561 -262.542529) (xy 123.574856 -262.550654)
			(xy 123.624249 -262.566702) (xy 123.670523 -262.59028) (xy 123.712539 -262.620806) (xy 123.749262 -262.657529)
			(xy 123.779788 -262.699545) (xy 123.803366 -262.745819) (xy 123.819414 -262.795212) (xy 123.827539 -262.846507)
			(xy 123.828048 -262.872474) (xy 123.827539 -262.898441) (xy 123.819414 -262.949736) (xy 123.803366 -262.999129)
			(xy 123.779788 -263.045403) (xy 123.749262 -263.087419) (xy 123.712539 -263.124142) (xy 123.670523 -263.154668)
			(xy 123.624249 -263.178246) (xy 123.574856 -263.194294) (xy 123.523561 -263.202419) (xy 123.471627 -263.202419)
			(xy 123.420332 -263.194294) (xy 123.370939 -263.178246) (xy 123.324665 -263.154668) (xy 123.282649 -263.124142)
			(xy 123.245926 -263.087419) (xy 123.2154 -263.045403) (xy 123.191822 -262.999129) (xy 123.175774 -262.949736)
			(xy 123.167649 -262.898441) (xy 122.887993 -262.898441) (xy 122.879868 -262.949736) (xy 122.86382 -262.999129)
			(xy 122.840242 -263.045403) (xy 122.809716 -263.087419) (xy 122.772993 -263.124142) (xy 122.730977 -263.154668)
			(xy 122.684703 -263.178246) (xy 122.63531 -263.194294) (xy 122.584015 -263.202419) (xy 122.532081 -263.202419)
			(xy 122.480786 -263.194294) (xy 122.431393 -263.178246) (xy 122.385119 -263.154668) (xy 122.343103 -263.124142)
			(xy 122.30638 -263.087419) (xy 122.275854 -263.045403) (xy 122.252276 -262.999129) (xy 122.236228 -262.949736)
			(xy 122.228103 -262.898441) (xy 121.947939 -262.898441) (xy 121.939814 -262.949736) (xy 121.923766 -262.999129)
			(xy 121.900188 -263.045403) (xy 121.869662 -263.087419) (xy 121.832939 -263.124142) (xy 121.790923 -263.154668)
			(xy 121.744649 -263.178246) (xy 121.695256 -263.194294) (xy 121.643961 -263.202419) (xy 121.592027 -263.202419)
			(xy 121.540732 -263.194294) (xy 121.491339 -263.178246) (xy 121.445065 -263.154668) (xy 121.403049 -263.124142)
			(xy 121.366326 -263.087419) (xy 121.3358 -263.045403) (xy 121.312222 -262.999129) (xy 121.296174 -262.949736)
			(xy 121.288049 -262.898441) (xy 120.510208 -262.898441) (xy 120.522491 -262.910723) (xy 120.553023 -262.952745)
			(xy 120.576605 -262.999025) (xy 120.592657 -263.048426) (xy 120.600783 -263.099729) (xy 120.600783 -263.151671)
			(xy 120.592657 -263.202974) (xy 120.576605 -263.252375) (xy 120.553023 -263.298655) (xy 120.522491 -263.340677)
			(xy 120.48576 -263.377405) (xy 120.443737 -263.407934) (xy 120.397454 -263.431514) (xy 120.348053 -263.447562)
			(xy 120.296749 -263.455685) (xy 120.270778 -263.456166) (xy 120.244264 -263.455646) (xy 120.191919 -263.447157)
			(xy 120.141607 -263.430401) (xy 120.11787 -263.418574) (xy 120.104153 -263.41206) (xy 120.074322 -263.406492)
			(xy 120.044171 -263.409932) (xy 120.01636 -263.422076) (xy 119.993343 -263.441854) (xy 119.984774 -263.454388)
			(xy 119.969475 -263.47752) (xy 119.932412 -263.51877) (xy 119.88898 -263.553251) (xy 119.840399 -263.579994)
			(xy 119.788034 -263.598247) (xy 119.733356 -263.607497) (xy 119.705628 -263.608058) (xy 119.679658 -263.607569)
			(xy 119.628356 -263.599448) (xy 119.578956 -263.583401) (xy 119.532675 -263.559823) (xy 119.490653 -263.529295)
			(xy 119.453923 -263.492569) (xy 119.423392 -263.450549) (xy 119.39981 -263.40427) (xy 119.383759 -263.354872)
			(xy 119.375633 -263.30357) (xy 119.036658 -263.30357) (xy 119.042433 -263.340029) (xy 119.042942 -263.365996)
			(xy 119.042433 -263.391963) (xy 119.034308 -263.443258) (xy 119.01826 -263.492651) (xy 118.994682 -263.538925)
			(xy 118.964156 -263.580941) (xy 118.927433 -263.617664) (xy 118.885417 -263.64819) (xy 118.839143 -263.671768)
			(xy 118.78975 -263.687816) (xy 118.738455 -263.695941) (xy 118.686521 -263.695941) (xy 118.635226 -263.687816)
			(xy 118.585833 -263.671768) (xy 118.539559 -263.64819) (xy 118.497543 -263.617664) (xy 118.46082 -263.580941)
			(xy 118.430294 -263.538925) (xy 118.406716 -263.492651) (xy 118.390668 -263.443258) (xy 118.382543 -263.391963)
			(xy 118.000719 -263.391963) (xy 118.000719 -263.441463) (xy 117.992596 -263.492751) (xy 117.976551 -263.542137)
			(xy 117.952978 -263.588405) (xy 117.922458 -263.630416) (xy 117.885742 -263.667136) (xy 117.843734 -263.69766)
			(xy 117.814593 -263.712511) (xy 121.758203 -263.712511) (xy 121.758203 -263.660577) (xy 121.766328 -263.609282)
			(xy 121.782376 -263.559889) (xy 121.805954 -263.513615) (xy 121.83648 -263.471599) (xy 121.873203 -263.434876)
			(xy 121.915219 -263.40435) (xy 121.961493 -263.380772) (xy 122.010886 -263.364724) (xy 122.062181 -263.356599)
			(xy 122.114115 -263.356599) (xy 122.16541 -263.364724) (xy 122.214803 -263.380772) (xy 122.261077 -263.40435)
			(xy 122.303093 -263.434876) (xy 122.339816 -263.471599) (xy 122.370342 -263.513615) (xy 122.39392 -263.559889)
			(xy 122.409968 -263.609282) (xy 122.418093 -263.660577) (xy 122.418602 -263.686544) (xy 122.418093 -263.712511)
			(xy 122.697749 -263.712511) (xy 122.697749 -263.660577) (xy 122.705874 -263.609282) (xy 122.721922 -263.559889)
			(xy 122.7455 -263.513615) (xy 122.776026 -263.471599) (xy 122.812749 -263.434876) (xy 122.854765 -263.40435)
			(xy 122.901039 -263.380772) (xy 122.950432 -263.364724) (xy 123.001727 -263.356599) (xy 123.053661 -263.356599)
			(xy 123.104956 -263.364724) (xy 123.154349 -263.380772) (xy 123.200623 -263.40435) (xy 123.242639 -263.434876)
			(xy 123.279362 -263.471599) (xy 123.309888 -263.513615) (xy 123.333466 -263.559889) (xy 123.349514 -263.609282)
			(xy 123.357639 -263.660577) (xy 123.358148 -263.686544) (xy 123.357639 -263.712511) (xy 123.349514 -263.763806)
			(xy 123.333466 -263.813199) (xy 123.309888 -263.859473) (xy 123.279362 -263.901489) (xy 123.242639 -263.938212)
			(xy 123.200623 -263.968738) (xy 123.154349 -263.992316) (xy 123.104956 -264.008364) (xy 123.053661 -264.016489)
			(xy 123.001727 -264.016489) (xy 122.950432 -264.008364) (xy 122.901039 -263.992316) (xy 122.854765 -263.968738)
			(xy 122.812749 -263.938212) (xy 122.776026 -263.901489) (xy 122.7455 -263.859473) (xy 122.721922 -263.813199)
			(xy 122.705874 -263.763806) (xy 122.697749 -263.712511) (xy 122.418093 -263.712511) (xy 122.409968 -263.763806)
			(xy 122.39392 -263.813199) (xy 122.370342 -263.859473) (xy 122.339816 -263.901489) (xy 122.303093 -263.938212)
			(xy 122.261077 -263.968738) (xy 122.214803 -263.992316) (xy 122.16541 -264.008364) (xy 122.114115 -264.016489)
			(xy 122.062181 -264.016489) (xy 122.010886 -264.008364) (xy 121.961493 -263.992316) (xy 121.915219 -263.968738)
			(xy 121.873203 -263.938212) (xy 121.83648 -263.901489) (xy 121.805954 -263.859473) (xy 121.782376 -263.813199)
			(xy 121.766328 -263.763806) (xy 121.758203 -263.712511) (xy 117.814593 -263.712511) (xy 117.797468 -263.721238)
			(xy 117.748084 -263.737288) (xy 117.696797 -263.745416) (xy 117.670834 -263.74598) (xy 117.646279 -263.745555)
			(xy 117.597704 -263.738333) (xy 117.550734 -263.723997) (xy 117.506404 -263.702865) (xy 117.465692 -263.675401)
			(xy 117.447314 -263.659112) (xy 117.435825 -263.649309) (xy 117.408588 -263.636295) (xy 117.378734 -263.631827)
			(xy 117.34888 -263.636295) (xy 117.321643 -263.649309) (xy 117.310154 -263.659112) (xy 117.291751 -263.67537)
			(xy 117.25104 -263.702827) (xy 117.206716 -263.72396) (xy 117.159754 -263.738304) (xy 117.111186 -263.745543)
			(xy 117.086634 -263.74598) (xy 117.062079 -263.745555) (xy 117.013504 -263.738333) (xy 116.966534 -263.723997)
			(xy 116.922204 -263.702865) (xy 116.881492 -263.675401) (xy 116.863114 -263.659112) (xy 116.851625 -263.649309)
			(xy 116.824388 -263.636295) (xy 116.794534 -263.631827) (xy 116.76468 -263.636295) (xy 116.737443 -263.649309)
			(xy 116.725954 -263.659112) (xy 116.707551 -263.67537) (xy 116.66684 -263.702827) (xy 116.622516 -263.72396)
			(xy 116.575554 -263.738304) (xy 116.526986 -263.745543) (xy 116.502434 -263.74598) (xy 116.476462 -263.7455)
			(xy 116.425157 -263.737379) (xy 116.375755 -263.721333) (xy 116.32947 -263.697755) (xy 116.287444 -263.667227)
			(xy 116.250712 -263.630501) (xy 116.220176 -263.588481) (xy 116.19659 -263.542201) (xy 116.180535 -263.492801)
			(xy 116.172405 -263.441498) (xy 116.17198 -263.415526) (xy 116.17257 -263.387499) (xy 116.182029 -263.33225)
			(xy 116.20068 -263.279391) (xy 116.227987 -263.23044) (xy 116.245132 -263.208262) (xy 116.253361 -263.197261)
			(xy 116.264191 -263.172025) (xy 116.267911 -263.144816) (xy 116.264253 -263.117599) (xy 116.25348 -263.092338)
			(xy 116.236371 -263.070858) (xy 116.21416 -263.054707) (xy 116.201444 -263.049512) (xy 116.178139 -263.040277)
			(xy 116.134398 -263.015794) (xy 116.094851 -262.984991) (xy 116.060405 -262.948574) (xy 116.031848 -262.907376)
			(xy 116.009835 -262.862342) (xy 115.994869 -262.814501) (xy 115.987292 -262.764949) (xy 115.986814 -262.739886)
			(xy 115.987377 -262.712589) (xy 115.996357 -262.658738) (xy 116.014071 -262.607097) (xy 116.040036 -262.559072)
			(xy 116.073545 -262.515971) (xy 116.09324 -262.497062) (xy 116.103222 -262.487231) (xy 116.117852 -262.46335)
			(xy 116.125451 -262.436394) (xy 116.125448 -262.408387) (xy 116.117844 -262.381433) (xy 116.10321 -262.357554)
			(xy 116.09324 -262.34771) (xy 116.074399 -262.329646) (xy 116.042088 -262.288654) (xy 116.01662 -262.243094)
			(xy 115.998628 -262.194099) (xy 115.988557 -262.142884) (xy 115.987068 -262.116824) (xy 115.98596 -262.101204)
			(xy 115.975469 -262.071717) (xy 115.956543 -262.046789) (xy 115.930959 -262.028761) (xy 115.901118 -262.019325)
			(xy 115.885468 -262.01878) (xy 114.901472 -262.01878) (xy 114.899948 -262.068056) (xy 114.898787 -262.093547)
			(xy 114.889586 -262.143736) (xy 114.872777 -262.191913) (xy 114.84876 -262.236933) (xy 114.818105 -262.277724)
			(xy 114.781542 -262.313315) (xy 114.739941 -262.342861) (xy 114.694292 -262.365658) (xy 114.645679 -262.381164)
			(xy 114.595261 -262.389011) (xy 114.544235 -262.389011) (xy 114.493817 -262.381164) (xy 114.445204 -262.365658)
			(xy 114.399555 -262.342861) (xy 114.357954 -262.313315) (xy 114.321391 -262.277724) (xy 114.290736 -262.236933)
			(xy 114.266719 -262.191913) (xy 114.24991 -262.143736) (xy 114.240709 -262.093547) (xy 114.239548 -262.068056)
			(xy 114.238024 -262.01878) (xy 113.961672 -262.01878) (xy 113.960148 -262.068056) (xy 113.958987 -262.093547)
			(xy 113.949786 -262.143736) (xy 113.932977 -262.191913) (xy 113.90896 -262.236933) (xy 113.878305 -262.277724)
			(xy 113.841742 -262.313315) (xy 113.800141 -262.342861) (xy 113.754492 -262.365658) (xy 113.705879 -262.381164)
			(xy 113.655461 -262.389011) (xy 113.604435 -262.389011) (xy 113.554017 -262.381164) (xy 113.505404 -262.365658)
			(xy 113.459755 -262.342861) (xy 113.418154 -262.313315) (xy 113.381591 -262.277724) (xy 113.350936 -262.236933)
			(xy 113.326919 -262.191913) (xy 113.31011 -262.143736) (xy 113.300909 -262.093547) (xy 113.299748 -262.068056)
			(xy 113.298224 -262.01878) (xy 113.021872 -262.01878) (xy 113.020348 -262.068056) (xy 113.019187 -262.093547)
			(xy 113.009986 -262.143736) (xy 112.993177 -262.191913) (xy 112.96916 -262.236933) (xy 112.938505 -262.277724)
			(xy 112.901942 -262.313315) (xy 112.860341 -262.342861) (xy 112.814692 -262.365658) (xy 112.766079 -262.381164)
			(xy 112.715661 -262.389011) (xy 112.664635 -262.389011) (xy 112.614217 -262.381164) (xy 112.565604 -262.365658)
			(xy 112.519955 -262.342861) (xy 112.478354 -262.313315) (xy 112.441791 -262.277724) (xy 112.411136 -262.236933)
			(xy 112.387119 -262.191913) (xy 112.37031 -262.143736) (xy 112.361109 -262.093547) (xy 112.359948 -262.068056)
			(xy 112.358424 -262.01878) (xy 112.082072 -262.01878) (xy 112.080548 -262.068056) (xy 112.079387 -262.093547)
			(xy 112.070186 -262.143736) (xy 112.053377 -262.191913) (xy 112.02936 -262.236933) (xy 111.998705 -262.277724)
			(xy 111.962142 -262.313315) (xy 111.920541 -262.342861) (xy 111.874892 -262.365658) (xy 111.826279 -262.381164)
			(xy 111.775861 -262.389011) (xy 111.724835 -262.389011) (xy 111.674417 -262.381164) (xy 111.625804 -262.365658)
			(xy 111.580155 -262.342861) (xy 111.538554 -262.313315) (xy 111.501991 -262.277724) (xy 111.471336 -262.236933)
			(xy 111.447319 -262.191913) (xy 111.43051 -262.143736) (xy 111.421309 -262.093547) (xy 111.420148 -262.068056)
			(xy 111.418624 -262.01878) (xy 111.142526 -262.01878) (xy 111.141002 -262.068056) (xy 111.139841 -262.093547)
			(xy 111.13064 -262.143736) (xy 111.113831 -262.191913) (xy 111.089814 -262.236933) (xy 111.059159 -262.277724)
			(xy 111.022596 -262.313315) (xy 110.980995 -262.342861) (xy 110.935346 -262.365658) (xy 110.886733 -262.381164)
			(xy 110.836315 -262.389011) (xy 110.785289 -262.389011) (xy 110.734871 -262.381164) (xy 110.686258 -262.365658)
			(xy 110.640609 -262.342861) (xy 110.599008 -262.313315) (xy 110.562445 -262.277724) (xy 110.53179 -262.236933)
			(xy 110.507773 -262.191913) (xy 110.490964 -262.143736) (xy 110.481763 -262.093547) (xy 110.480602 -262.068056)
			(xy 110.479078 -262.01878) (xy 110.202472 -262.01878) (xy 110.200948 -262.068056) (xy 110.199787 -262.093547)
			(xy 110.190586 -262.143736) (xy 110.173777 -262.191913) (xy 110.14976 -262.236933) (xy 110.119105 -262.277724)
			(xy 110.082542 -262.313315) (xy 110.040941 -262.342861) (xy 109.995292 -262.365658) (xy 109.946679 -262.381164)
			(xy 109.896261 -262.389011) (xy 109.845235 -262.389011) (xy 109.794817 -262.381164) (xy 109.746204 -262.365658)
			(xy 109.700555 -262.342861) (xy 109.658954 -262.313315) (xy 109.622391 -262.277724) (xy 109.591736 -262.236933)
			(xy 109.567719 -262.191913) (xy 109.55091 -262.143736) (xy 109.541709 -262.093547) (xy 109.540548 -262.068056)
			(xy 109.539024 -262.01878) (xy 109.005878 -262.01878) (xy 108.994448 -262.053832) (xy 108.98677 -262.076072)
			(xy 108.965998 -262.118289) (xy 108.939441 -262.157127) (xy 108.923836 -262.174736) (xy 108.914034 -262.186225)
			(xy 108.901023 -262.21346) (xy 108.896558 -262.243312) (xy 108.90103 -262.273162) (xy 108.914047 -262.300395)
			(xy 108.923836 -262.311896) (xy 108.940096 -262.330299) (xy 108.967557 -262.371008) (xy 108.988695 -262.415332)
			(xy 109.003045 -262.462295) (xy 109.010291 -262.510863) (xy 109.010704 -262.535416) (xy 109.010195 -262.561383)
			(xy 109.00207 -262.612678) (xy 108.986022 -262.662071) (xy 108.962444 -262.708345) (xy 108.931918 -262.750361)
			(xy 108.895195 -262.787084) (xy 108.853179 -262.81761) (xy 108.806905 -262.841188) (xy 108.757512 -262.857236)
			(xy 108.706217 -262.865361) (xy 108.654283 -262.865361) (xy 108.602988 -262.857236) (xy 108.553595 -262.841188)
			(xy 108.507321 -262.81761) (xy 108.465305 -262.787084) (xy 108.428582 -262.750361) (xy 108.398056 -262.708345)
			(xy 108.374478 -262.662071) (xy 108.35843 -262.612678) (xy 108.350305 -262.561383) (xy 108.349796 -262.535416)
			(xy 108.350222 -262.510862) (xy 108.357449 -262.462289) (xy 108.371789 -262.415323) (xy 108.392926 -262.370998)
			(xy 108.420396 -262.330292) (xy 108.436664 -262.311896) (xy 108.446471 -262.300407) (xy 108.459491 -262.273169)
			(xy 108.463963 -262.243312) (xy 108.459497 -262.213454) (xy 108.446484 -262.186212) (xy 108.436664 -262.174736)
			(xy 108.421075 -262.157114) (xy 108.39452 -262.118277) (xy 108.373732 -262.07607) (xy 108.366052 -262.053832)
			(xy 108.354622 -262.01878) (xy 107.939078 -262.01878) (xy 107.92418 -262.019303) (xy 107.895654 -262.027912)
			(xy 107.870829 -262.044392) (xy 107.851819 -262.067337) (xy 107.840244 -262.094794) (xy 107.83709 -262.124423)
			(xy 107.839256 -262.139176) (xy 107.841883 -262.154279) (xy 107.844681 -262.184807) (xy 107.844844 -262.200136)
			(xy 107.844414 -262.224689) (xy 107.837182 -262.273258) (xy 107.822837 -262.320221) (xy 107.801697 -262.364542)
			(xy 107.774226 -262.405245) (xy 107.757976 -262.423656) (xy 107.748182 -262.435147) (xy 107.735185 -262.462381)
			(xy 107.730728 -262.492227) (xy 107.7352 -262.52207) (xy 107.748212 -262.549297) (xy 107.757976 -262.560816)
			(xy 107.774233 -262.57922) (xy 107.801688 -262.619931) (xy 107.822821 -262.664255) (xy 107.837166 -262.711217)
			(xy 107.844409 -262.759784) (xy 107.844844 -262.784336) (xy 107.844414 -262.808889) (xy 107.837182 -262.857458)
			(xy 107.824586 -262.898695) (xy 109.070903 -262.898695) (xy 109.070903 -262.846761) (xy 109.079028 -262.795466)
			(xy 109.095076 -262.746073) (xy 109.118654 -262.699799) (xy 109.14918 -262.657783) (xy 109.185903 -262.62106)
			(xy 109.227919 -262.590534) (xy 109.274193 -262.566956) (xy 109.323586 -262.550908) (xy 109.374881 -262.542783)
			(xy 109.426815 -262.542783) (xy 109.47811 -262.550908) (xy 109.527503 -262.566956) (xy 109.573777 -262.590534)
			(xy 109.615793 -262.62106) (xy 109.652516 -262.657783) (xy 109.683042 -262.699799) (xy 109.70662 -262.746073)
			(xy 109.722668 -262.795466) (xy 109.730793 -262.846761) (xy 109.731302 -262.872728) (xy 109.730793 -262.898695)
			(xy 110.010703 -262.898695) (xy 110.010703 -262.846761) (xy 110.018828 -262.795466) (xy 110.034876 -262.746073)
			(xy 110.058454 -262.699799) (xy 110.08898 -262.657783) (xy 110.125703 -262.62106) (xy 110.167719 -262.590534)
			(xy 110.213993 -262.566956) (xy 110.263386 -262.550908) (xy 110.314681 -262.542783) (xy 110.366615 -262.542783)
			(xy 110.41791 -262.550908) (xy 110.467303 -262.566956) (xy 110.513577 -262.590534) (xy 110.555593 -262.62106)
			(xy 110.592316 -262.657783) (xy 110.622842 -262.699799) (xy 110.64642 -262.746073) (xy 110.662468 -262.795466)
			(xy 110.670593 -262.846761) (xy 110.671102 -262.872728) (xy 110.670593 -262.898695) (xy 110.950757 -262.898695)
			(xy 110.950757 -262.846761) (xy 110.958882 -262.795466) (xy 110.97493 -262.746073) (xy 110.998508 -262.699799)
			(xy 111.029034 -262.657783) (xy 111.065757 -262.62106) (xy 111.107773 -262.590534) (xy 111.154047 -262.566956)
			(xy 111.20344 -262.550908) (xy 111.254735 -262.542783) (xy 111.306669 -262.542783) (xy 111.357964 -262.550908)
			(xy 111.407357 -262.566956) (xy 111.453631 -262.590534) (xy 111.495647 -262.62106) (xy 111.53237 -262.657783)
			(xy 111.562896 -262.699799) (xy 111.586474 -262.746073) (xy 111.602522 -262.795466) (xy 111.610647 -262.846761)
			(xy 111.611156 -262.872728) (xy 111.610647 -262.898695) (xy 111.890557 -262.898695) (xy 111.890557 -262.846761)
			(xy 111.898682 -262.795466) (xy 111.91473 -262.746073) (xy 111.938308 -262.699799) (xy 111.968834 -262.657783)
			(xy 112.005557 -262.62106) (xy 112.047573 -262.590534) (xy 112.093847 -262.566956) (xy 112.14324 -262.550908)
			(xy 112.194535 -262.542783) (xy 112.246469 -262.542783) (xy 112.297764 -262.550908) (xy 112.347157 -262.566956)
			(xy 112.393431 -262.590534) (xy 112.435447 -262.62106) (xy 112.47217 -262.657783) (xy 112.502696 -262.699799)
			(xy 112.526274 -262.746073) (xy 112.542322 -262.795466) (xy 112.550447 -262.846761) (xy 112.550956 -262.872728)
			(xy 112.550447 -262.898695) (xy 112.830103 -262.898695) (xy 112.830103 -262.846761) (xy 112.838228 -262.795466)
			(xy 112.854276 -262.746073) (xy 112.877854 -262.699799) (xy 112.90838 -262.657783) (xy 112.945103 -262.62106)
			(xy 112.987119 -262.590534) (xy 113.033393 -262.566956) (xy 113.082786 -262.550908) (xy 113.134081 -262.542783)
			(xy 113.186015 -262.542783) (xy 113.23731 -262.550908) (xy 113.286703 -262.566956) (xy 113.332977 -262.590534)
			(xy 113.374993 -262.62106) (xy 113.411716 -262.657783) (xy 113.442242 -262.699799) (xy 113.46582 -262.746073)
			(xy 113.481868 -262.795466) (xy 113.489993 -262.846761) (xy 113.490502 -262.872728) (xy 113.489993 -262.898695)
			(xy 113.770157 -262.898695) (xy 113.770157 -262.846761) (xy 113.778282 -262.795466) (xy 113.79433 -262.746073)
			(xy 113.817908 -262.699799) (xy 113.848434 -262.657783) (xy 113.885157 -262.62106) (xy 113.927173 -262.590534)
			(xy 113.973447 -262.566956) (xy 114.02284 -262.550908) (xy 114.074135 -262.542783) (xy 114.126069 -262.542783)
			(xy 114.177364 -262.550908) (xy 114.226757 -262.566956) (xy 114.273031 -262.590534) (xy 114.315047 -262.62106)
			(xy 114.35177 -262.657783) (xy 114.382296 -262.699799) (xy 114.405874 -262.746073) (xy 114.421922 -262.795466)
			(xy 114.430047 -262.846761) (xy 114.430556 -262.872728) (xy 114.430047 -262.898695) (xy 114.421922 -262.94999)
			(xy 114.405874 -262.999383) (xy 114.382296 -263.045657) (xy 114.35177 -263.087673) (xy 114.315047 -263.124396)
			(xy 114.273031 -263.154922) (xy 114.226757 -263.1785) (xy 114.177364 -263.194548) (xy 114.126069 -263.202673)
			(xy 114.074135 -263.202673) (xy 114.02284 -263.194548) (xy 113.973447 -263.1785) (xy 113.927173 -263.154922)
			(xy 113.885157 -263.124396) (xy 113.848434 -263.087673) (xy 113.817908 -263.045657) (xy 113.79433 -262.999383)
			(xy 113.778282 -262.94999) (xy 113.770157 -262.898695) (xy 113.489993 -262.898695) (xy 113.481868 -262.94999)
			(xy 113.46582 -262.999383) (xy 113.442242 -263.045657) (xy 113.411716 -263.087673) (xy 113.374993 -263.124396)
			(xy 113.332977 -263.154922) (xy 113.286703 -263.1785) (xy 113.23731 -263.194548) (xy 113.186015 -263.202673)
			(xy 113.134081 -263.202673) (xy 113.082786 -263.194548) (xy 113.033393 -263.1785) (xy 112.987119 -263.154922)
			(xy 112.945103 -263.124396) (xy 112.90838 -263.087673) (xy 112.877854 -263.045657) (xy 112.854276 -262.999383)
			(xy 112.838228 -262.94999) (xy 112.830103 -262.898695) (xy 112.550447 -262.898695) (xy 112.542322 -262.94999)
			(xy 112.526274 -262.999383) (xy 112.502696 -263.045657) (xy 112.47217 -263.087673) (xy 112.435447 -263.124396)
			(xy 112.393431 -263.154922) (xy 112.347157 -263.1785) (xy 112.297764 -263.194548) (xy 112.246469 -263.202673)
			(xy 112.194535 -263.202673) (xy 112.14324 -263.194548) (xy 112.093847 -263.1785) (xy 112.047573 -263.154922)
			(xy 112.005557 -263.124396) (xy 111.968834 -263.087673) (xy 111.938308 -263.045657) (xy 111.91473 -262.999383)
			(xy 111.898682 -262.94999) (xy 111.890557 -262.898695) (xy 111.610647 -262.898695) (xy 111.602522 -262.94999)
			(xy 111.586474 -262.999383) (xy 111.562896 -263.045657) (xy 111.53237 -263.087673) (xy 111.495647 -263.124396)
			(xy 111.453631 -263.154922) (xy 111.407357 -263.1785) (xy 111.357964 -263.194548) (xy 111.306669 -263.202673)
			(xy 111.254735 -263.202673) (xy 111.20344 -263.194548) (xy 111.154047 -263.1785) (xy 111.107773 -263.154922)
			(xy 111.065757 -263.124396) (xy 111.029034 -263.087673) (xy 110.998508 -263.045657) (xy 110.97493 -262.999383)
			(xy 110.958882 -262.94999) (xy 110.950757 -262.898695) (xy 110.670593 -262.898695) (xy 110.662468 -262.94999)
			(xy 110.64642 -262.999383) (xy 110.622842 -263.045657) (xy 110.592316 -263.087673) (xy 110.555593 -263.124396)
			(xy 110.513577 -263.154922) (xy 110.467303 -263.1785) (xy 110.41791 -263.194548) (xy 110.366615 -263.202673)
			(xy 110.314681 -263.202673) (xy 110.263386 -263.194548) (xy 110.213993 -263.1785) (xy 110.167719 -263.154922)
			(xy 110.125703 -263.124396) (xy 110.08898 -263.087673) (xy 110.058454 -263.045657) (xy 110.034876 -262.999383)
			(xy 110.018828 -262.94999) (xy 110.010703 -262.898695) (xy 109.730793 -262.898695) (xy 109.722668 -262.94999)
			(xy 109.70662 -262.999383) (xy 109.683042 -263.045657) (xy 109.652516 -263.087673) (xy 109.615793 -263.124396)
			(xy 109.573777 -263.154922) (xy 109.527503 -263.1785) (xy 109.47811 -263.194548) (xy 109.426815 -263.202673)
			(xy 109.374881 -263.202673) (xy 109.323586 -263.194548) (xy 109.274193 -263.1785) (xy 109.227919 -263.154922)
			(xy 109.185903 -263.124396) (xy 109.14918 -263.087673) (xy 109.118654 -263.045657) (xy 109.095076 -262.999383)
			(xy 109.079028 -262.94999) (xy 109.070903 -262.898695) (xy 107.824586 -262.898695) (xy 107.822837 -262.904421)
			(xy 107.801697 -262.948742) (xy 107.774226 -262.989445) (xy 107.757976 -263.007856) (xy 107.748182 -263.019347)
			(xy 107.735185 -263.046581) (xy 107.730728 -263.076427) (xy 107.7352 -263.10627) (xy 107.748212 -263.133497)
			(xy 107.757976 -263.145016) (xy 107.774233 -263.16342) (xy 107.801688 -263.204131) (xy 107.822821 -263.248455)
			(xy 107.837166 -263.295417) (xy 107.844409 -263.343984) (xy 107.844844 -263.368536) (xy 107.844335 -263.394503)
			(xy 107.83621 -263.445798) (xy 107.820162 -263.495191) (xy 107.796584 -263.541465) (xy 107.766058 -263.583481)
			(xy 107.729335 -263.620204) (xy 107.687319 -263.65073) (xy 107.641045 -263.674308) (xy 107.591652 -263.690356)
			(xy 107.540357 -263.698481) (xy 107.488423 -263.698481) (xy 107.437128 -263.690356) (xy 107.387735 -263.674308)
			(xy 107.341461 -263.65073) (xy 107.299445 -263.620204) (xy 107.262722 -263.583481) (xy 107.232196 -263.541465)
			(xy 107.208618 -263.495191) (xy 107.19257 -263.445798) (xy 107.184445 -263.394503) (xy 107.183936 -263.368536)
			(xy 107.184361 -263.343981) (xy 107.191583 -263.295406) (xy 107.205919 -263.248436) (xy 107.227052 -263.204107)
			(xy 107.254516 -263.163396) (xy 107.270804 -263.145016) (xy 107.280611 -263.133526) (xy 107.293631 -263.106285)
			(xy 107.298107 -263.076427) (xy 107.293647 -263.046566) (xy 107.280641 -263.019318) (xy 107.270804 -263.007856)
			(xy 107.25455 -262.989451) (xy 107.227099 -262.948739) (xy 107.205971 -262.904414) (xy 107.191631 -262.857453)
			(xy 107.184393 -262.808887) (xy 107.183936 -262.784336) (xy 107.184361 -262.759781) (xy 107.191583 -262.711206)
			(xy 107.205919 -262.664236) (xy 107.227052 -262.619907) (xy 107.254516 -262.579196) (xy 107.270804 -262.560816)
			(xy 107.280611 -262.549326) (xy 107.293631 -262.522085) (xy 107.298107 -262.492227) (xy 107.293647 -262.462366)
			(xy 107.280641 -262.435118) (xy 107.270804 -262.423656) (xy 107.25455 -262.405251) (xy 107.227099 -262.364539)
			(xy 107.205971 -262.320214) (xy 107.191631 -262.273253) (xy 107.184393 -262.224687) (xy 107.183936 -262.200136)
			(xy 107.184087 -262.184807) (xy 107.186888 -262.154278) (xy 107.189524 -262.139176) (xy 107.191768 -262.124437)
			(xy 107.18859 -262.094806) (xy 107.176995 -262.067354) (xy 107.15797 -262.044417) (xy 107.133134 -262.027946)
			(xy 107.104602 -262.019345) (xy 107.089702 -262.01878) (xy 106.380026 -262.01878) (xy 104.686041 -263.712765)
			(xy 109.540803 -263.712765) (xy 109.540803 -263.660831) (xy 109.548928 -263.609536) (xy 109.564976 -263.560143)
			(xy 109.588554 -263.513869) (xy 109.61908 -263.471853) (xy 109.655803 -263.43513) (xy 109.697819 -263.404604)
			(xy 109.744093 -263.381026) (xy 109.793486 -263.364978) (xy 109.844781 -263.356853) (xy 109.896715 -263.356853)
			(xy 109.94801 -263.364978) (xy 109.997403 -263.381026) (xy 110.043677 -263.404604) (xy 110.085693 -263.43513)
			(xy 110.122416 -263.471853) (xy 110.152942 -263.513869) (xy 110.17652 -263.560143) (xy 110.192568 -263.609536)
			(xy 110.200693 -263.660831) (xy 110.201202 -263.686798) (xy 110.200693 -263.712765) (xy 110.480603 -263.712765)
			(xy 110.480603 -263.660831) (xy 110.488728 -263.609536) (xy 110.504776 -263.560143) (xy 110.528354 -263.513869)
			(xy 110.55888 -263.471853) (xy 110.595603 -263.43513) (xy 110.637619 -263.404604) (xy 110.683893 -263.381026)
			(xy 110.733286 -263.364978) (xy 110.784581 -263.356853) (xy 110.836515 -263.356853) (xy 110.88781 -263.364978)
			(xy 110.937203 -263.381026) (xy 110.983477 -263.404604) (xy 111.025493 -263.43513) (xy 111.062216 -263.471853)
			(xy 111.092742 -263.513869) (xy 111.11632 -263.560143) (xy 111.132368 -263.609536) (xy 111.140493 -263.660831)
			(xy 111.141002 -263.686798) (xy 111.140493 -263.712765) (xy 111.420403 -263.712765) (xy 111.420403 -263.660831)
			(xy 111.428528 -263.609536) (xy 111.444576 -263.560143) (xy 111.468154 -263.513869) (xy 111.49868 -263.471853)
			(xy 111.535403 -263.43513) (xy 111.577419 -263.404604) (xy 111.623693 -263.381026) (xy 111.673086 -263.364978)
			(xy 111.724381 -263.356853) (xy 111.776315 -263.356853) (xy 111.82761 -263.364978) (xy 111.877003 -263.381026)
			(xy 111.923277 -263.404604) (xy 111.965293 -263.43513) (xy 112.002016 -263.471853) (xy 112.032542 -263.513869)
			(xy 112.05612 -263.560143) (xy 112.072168 -263.609536) (xy 112.080293 -263.660831) (xy 112.080802 -263.686798)
			(xy 112.080293 -263.712765) (xy 112.360203 -263.712765) (xy 112.360203 -263.660831) (xy 112.368328 -263.609536)
			(xy 112.384376 -263.560143) (xy 112.407954 -263.513869) (xy 112.43848 -263.471853) (xy 112.475203 -263.43513)
			(xy 112.517219 -263.404604) (xy 112.563493 -263.381026) (xy 112.612886 -263.364978) (xy 112.664181 -263.356853)
			(xy 112.716115 -263.356853) (xy 112.76741 -263.364978) (xy 112.816803 -263.381026) (xy 112.863077 -263.404604)
			(xy 112.905093 -263.43513) (xy 112.941816 -263.471853) (xy 112.972342 -263.513869) (xy 112.99592 -263.560143)
			(xy 113.011968 -263.609536) (xy 113.020093 -263.660831) (xy 113.020602 -263.686798) (xy 113.020098 -263.712511)
			(xy 113.299495 -263.712511) (xy 113.299495 -263.660577) (xy 113.30762 -263.609282) (xy 113.323668 -263.559889)
			(xy 113.347246 -263.513615) (xy 113.377772 -263.471599) (xy 113.414495 -263.434876) (xy 113.456511 -263.40435)
			(xy 113.502785 -263.380772) (xy 113.552178 -263.364724) (xy 113.603473 -263.356599) (xy 113.655407 -263.356599)
			(xy 113.706702 -263.364724) (xy 113.756095 -263.380772) (xy 113.802369 -263.40435) (xy 113.844385 -263.434876)
			(xy 113.881108 -263.471599) (xy 113.911634 -263.513615) (xy 113.935212 -263.559889) (xy 113.95126 -263.609282)
			(xy 113.959385 -263.660577) (xy 113.959894 -263.686544) (xy 113.959385 -263.712511) (xy 113.959345 -263.712765)
			(xy 114.239803 -263.712765) (xy 114.239803 -263.660831) (xy 114.247928 -263.609536) (xy 114.263976 -263.560143)
			(xy 114.287554 -263.513869) (xy 114.31808 -263.471853) (xy 114.354803 -263.43513) (xy 114.396819 -263.404604)
			(xy 114.443093 -263.381026) (xy 114.492486 -263.364978) (xy 114.543781 -263.356853) (xy 114.595715 -263.356853)
			(xy 114.64701 -263.364978) (xy 114.696403 -263.381026) (xy 114.742677 -263.404604) (xy 114.784693 -263.43513)
			(xy 114.821416 -263.471853) (xy 114.851942 -263.513869) (xy 114.87552 -263.560143) (xy 114.891568 -263.609536)
			(xy 114.899693 -263.660831) (xy 114.900202 -263.686798) (xy 114.899698 -263.712511) (xy 115.179603 -263.712511)
			(xy 115.179603 -263.660577) (xy 115.187728 -263.609282) (xy 115.203776 -263.559889) (xy 115.227354 -263.513615)
			(xy 115.25788 -263.471599) (xy 115.294603 -263.434876) (xy 115.336619 -263.40435) (xy 115.382893 -263.380772)
			(xy 115.432286 -263.364724) (xy 115.483581 -263.356599) (xy 115.535515 -263.356599) (xy 115.58681 -263.364724)
			(xy 115.636203 -263.380772) (xy 115.682477 -263.40435) (xy 115.724493 -263.434876) (xy 115.761216 -263.471599)
			(xy 115.791742 -263.513615) (xy 115.81532 -263.559889) (xy 115.831368 -263.609282) (xy 115.839493 -263.660577)
			(xy 115.840002 -263.686544) (xy 115.839493 -263.712511) (xy 115.831368 -263.763806) (xy 115.81532 -263.813199)
			(xy 115.791742 -263.859473) (xy 115.761216 -263.901489) (xy 115.724493 -263.938212) (xy 115.682477 -263.968738)
			(xy 115.636203 -263.992316) (xy 115.58681 -264.008364) (xy 115.535515 -264.016489) (xy 115.483581 -264.016489)
			(xy 115.432286 -264.008364) (xy 115.382893 -263.992316) (xy 115.336619 -263.968738) (xy 115.294603 -263.938212)
			(xy 115.25788 -263.901489) (xy 115.227354 -263.859473) (xy 115.203776 -263.813199) (xy 115.187728 -263.763806)
			(xy 115.179603 -263.712511) (xy 114.899698 -263.712511) (xy 114.899693 -263.712765) (xy 114.891568 -263.76406)
			(xy 114.87552 -263.813453) (xy 114.851942 -263.859727) (xy 114.821416 -263.901743) (xy 114.784693 -263.938466)
			(xy 114.742677 -263.968992) (xy 114.696403 -263.99257) (xy 114.64701 -264.008618) (xy 114.595715 -264.016743)
			(xy 114.543781 -264.016743) (xy 114.492486 -264.008618) (xy 114.443093 -263.99257) (xy 114.396819 -263.968992)
			(xy 114.354803 -263.938466) (xy 114.31808 -263.901743) (xy 114.287554 -263.859727) (xy 114.263976 -263.813453)
			(xy 114.247928 -263.76406) (xy 114.239803 -263.712765) (xy 113.959345 -263.712765) (xy 113.95126 -263.763806)
			(xy 113.935212 -263.813199) (xy 113.911634 -263.859473) (xy 113.881108 -263.901489) (xy 113.844385 -263.938212)
			(xy 113.802369 -263.968738) (xy 113.756095 -263.992316) (xy 113.706702 -264.008364) (xy 113.655407 -264.016489)
			(xy 113.603473 -264.016489) (xy 113.552178 -264.008364) (xy 113.502785 -263.992316) (xy 113.456511 -263.968738)
			(xy 113.414495 -263.938212) (xy 113.377772 -263.901489) (xy 113.347246 -263.859473) (xy 113.323668 -263.813199)
			(xy 113.30762 -263.763806) (xy 113.299495 -263.712511) (xy 113.020098 -263.712511) (xy 113.020093 -263.712765)
			(xy 113.011968 -263.76406) (xy 112.99592 -263.813453) (xy 112.972342 -263.859727) (xy 112.941816 -263.901743)
			(xy 112.905093 -263.938466) (xy 112.863077 -263.968992) (xy 112.816803 -263.99257) (xy 112.76741 -264.008618)
			(xy 112.716115 -264.016743) (xy 112.664181 -264.016743) (xy 112.612886 -264.008618) (xy 112.563493 -263.99257)
			(xy 112.517219 -263.968992) (xy 112.475203 -263.938466) (xy 112.43848 -263.901743) (xy 112.407954 -263.859727)
			(xy 112.384376 -263.813453) (xy 112.368328 -263.76406) (xy 112.360203 -263.712765) (xy 112.080293 -263.712765)
			(xy 112.072168 -263.76406) (xy 112.05612 -263.813453) (xy 112.032542 -263.859727) (xy 112.002016 -263.901743)
			(xy 111.965293 -263.938466) (xy 111.923277 -263.968992) (xy 111.877003 -263.99257) (xy 111.82761 -264.008618)
			(xy 111.776315 -264.016743) (xy 111.724381 -264.016743) (xy 111.673086 -264.008618) (xy 111.623693 -263.99257)
			(xy 111.577419 -263.968992) (xy 111.535403 -263.938466) (xy 111.49868 -263.901743) (xy 111.468154 -263.859727)
			(xy 111.444576 -263.813453) (xy 111.428528 -263.76406) (xy 111.420403 -263.712765) (xy 111.140493 -263.712765)
			(xy 111.132368 -263.76406) (xy 111.11632 -263.813453) (xy 111.092742 -263.859727) (xy 111.062216 -263.901743)
			(xy 111.025493 -263.938466) (xy 110.983477 -263.968992) (xy 110.937203 -263.99257) (xy 110.88781 -264.008618)
			(xy 110.836515 -264.016743) (xy 110.784581 -264.016743) (xy 110.733286 -264.008618) (xy 110.683893 -263.99257)
			(xy 110.637619 -263.968992) (xy 110.595603 -263.938466) (xy 110.55888 -263.901743) (xy 110.528354 -263.859727)
			(xy 110.504776 -263.813453) (xy 110.488728 -263.76406) (xy 110.480603 -263.712765) (xy 110.200693 -263.712765)
			(xy 110.192568 -263.76406) (xy 110.17652 -263.813453) (xy 110.152942 -263.859727) (xy 110.122416 -263.901743)
			(xy 110.085693 -263.938466) (xy 110.043677 -263.968992) (xy 109.997403 -263.99257) (xy 109.94801 -264.008618)
			(xy 109.896715 -264.016743) (xy 109.844781 -264.016743) (xy 109.793486 -264.008618) (xy 109.744093 -263.99257)
			(xy 109.697819 -263.968992) (xy 109.655803 -263.938466) (xy 109.61908 -263.901743) (xy 109.588554 -263.859727)
			(xy 109.564976 -263.813453) (xy 109.548928 -263.76406) (xy 109.540803 -263.712765) (xy 104.686041 -263.712765)
			(xy 104.05491 -264.343896) (xy 104.06761 -264.375138) (xy 104.079082 -264.405165) (xy 104.091488 -264.468225)
			(xy 104.092248 -264.50036) (xy 104.091712 -264.526327) (xy 108.131103 -264.526327) (xy 108.131103 -264.474393)
			(xy 108.139228 -264.423098) (xy 108.155276 -264.373705) (xy 108.178854 -264.327431) (xy 108.20938 -264.285415)
			(xy 108.246103 -264.248692) (xy 108.288119 -264.218166) (xy 108.334393 -264.194588) (xy 108.383786 -264.17854)
			(xy 108.435081 -264.170415) (xy 108.487015 -264.170415) (xy 108.53831 -264.17854) (xy 108.587703 -264.194588)
			(xy 108.633977 -264.218166) (xy 108.675993 -264.248692) (xy 108.712716 -264.285415) (xy 108.743242 -264.327431)
			(xy 108.76682 -264.373705) (xy 108.782868 -264.423098) (xy 108.790993 -264.474393) (xy 108.791502 -264.50036)
			(xy 108.790993 -264.526327) (xy 109.070649 -264.526327) (xy 109.070649 -264.474393) (xy 109.078774 -264.423098)
			(xy 109.094822 -264.373705) (xy 109.1184 -264.327431) (xy 109.148926 -264.285415) (xy 109.185649 -264.248692)
			(xy 109.227665 -264.218166) (xy 109.273939 -264.194588) (xy 109.323332 -264.17854) (xy 109.374627 -264.170415)
			(xy 109.426561 -264.170415) (xy 109.477856 -264.17854) (xy 109.527249 -264.194588) (xy 109.573523 -264.218166)
			(xy 109.615539 -264.248692) (xy 109.652262 -264.285415) (xy 109.682788 -264.327431) (xy 109.706366 -264.373705)
			(xy 109.722414 -264.423098) (xy 109.730539 -264.474393) (xy 109.731048 -264.50036) (xy 109.730539 -264.526327)
			(xy 110.010703 -264.526327) (xy 110.010703 -264.474393) (xy 110.018828 -264.423098) (xy 110.034876 -264.373705)
			(xy 110.058454 -264.327431) (xy 110.08898 -264.285415) (xy 110.125703 -264.248692) (xy 110.167719 -264.218166)
			(xy 110.213993 -264.194588) (xy 110.263386 -264.17854) (xy 110.314681 -264.170415) (xy 110.366615 -264.170415)
			(xy 110.41791 -264.17854) (xy 110.467303 -264.194588) (xy 110.513577 -264.218166) (xy 110.555593 -264.248692)
			(xy 110.592316 -264.285415) (xy 110.622842 -264.327431) (xy 110.64642 -264.373705) (xy 110.662468 -264.423098)
			(xy 110.670593 -264.474393) (xy 110.671102 -264.50036) (xy 110.670593 -264.526327) (xy 110.950503 -264.526327)
			(xy 110.950503 -264.474393) (xy 110.958628 -264.423098) (xy 110.974676 -264.373705) (xy 110.998254 -264.327431)
			(xy 111.02878 -264.285415) (xy 111.065503 -264.248692) (xy 111.107519 -264.218166) (xy 111.153793 -264.194588)
			(xy 111.203186 -264.17854) (xy 111.254481 -264.170415) (xy 111.306415 -264.170415) (xy 111.35771 -264.17854)
			(xy 111.407103 -264.194588) (xy 111.453377 -264.218166) (xy 111.495393 -264.248692) (xy 111.532116 -264.285415)
			(xy 111.562642 -264.327431) (xy 111.58622 -264.373705) (xy 111.602268 -264.423098) (xy 111.610393 -264.474393)
			(xy 111.610902 -264.50036) (xy 111.610393 -264.526327) (xy 111.890303 -264.526327) (xy 111.890303 -264.474393)
			(xy 111.898428 -264.423098) (xy 111.914476 -264.373705) (xy 111.938054 -264.327431) (xy 111.96858 -264.285415)
			(xy 112.005303 -264.248692) (xy 112.047319 -264.218166) (xy 112.093593 -264.194588) (xy 112.142986 -264.17854)
			(xy 112.194281 -264.170415) (xy 112.246215 -264.170415) (xy 112.29751 -264.17854) (xy 112.346903 -264.194588)
			(xy 112.393177 -264.218166) (xy 112.435193 -264.248692) (xy 112.471916 -264.285415) (xy 112.502442 -264.327431)
			(xy 112.52602 -264.373705) (xy 112.542068 -264.423098) (xy 112.550193 -264.474393) (xy 112.550702 -264.50036)
			(xy 112.550193 -264.526327) (xy 112.829849 -264.526327) (xy 112.829849 -264.474393) (xy 112.837974 -264.423098)
			(xy 112.854022 -264.373705) (xy 112.8776 -264.327431) (xy 112.908126 -264.285415) (xy 112.944849 -264.248692)
			(xy 112.986865 -264.218166) (xy 113.033139 -264.194588) (xy 113.082532 -264.17854) (xy 113.133827 -264.170415)
			(xy 113.185761 -264.170415) (xy 113.237056 -264.17854) (xy 113.286449 -264.194588) (xy 113.332723 -264.218166)
			(xy 113.374739 -264.248692) (xy 113.411462 -264.285415) (xy 113.441988 -264.327431) (xy 113.465566 -264.373705)
			(xy 113.481614 -264.423098) (xy 113.489739 -264.474393) (xy 113.490248 -264.50036) (xy 113.489739 -264.526327)
			(xy 113.769649 -264.526327) (xy 113.769649 -264.474393) (xy 113.777774 -264.423098) (xy 113.793822 -264.373705)
			(xy 113.8174 -264.327431) (xy 113.847926 -264.285415) (xy 113.884649 -264.248692) (xy 113.926665 -264.218166)
			(xy 113.972939 -264.194588) (xy 114.022332 -264.17854) (xy 114.073627 -264.170415) (xy 114.125561 -264.170415)
			(xy 114.176856 -264.17854) (xy 114.226249 -264.194588) (xy 114.272523 -264.218166) (xy 114.314539 -264.248692)
			(xy 114.351262 -264.285415) (xy 114.381788 -264.327431) (xy 114.405366 -264.373705) (xy 114.421414 -264.423098)
			(xy 114.429539 -264.474393) (xy 114.430048 -264.50036) (xy 114.429539 -264.526327) (xy 114.709449 -264.526327)
			(xy 114.709449 -264.474393) (xy 114.717574 -264.423098) (xy 114.733622 -264.373705) (xy 114.7572 -264.327431)
			(xy 114.787726 -264.285415) (xy 114.824449 -264.248692) (xy 114.866465 -264.218166) (xy 114.912739 -264.194588)
			(xy 114.962132 -264.17854) (xy 115.013427 -264.170415) (xy 115.065361 -264.170415) (xy 115.116656 -264.17854)
			(xy 115.166049 -264.194588) (xy 115.212323 -264.218166) (xy 115.254339 -264.248692) (xy 115.291062 -264.285415)
			(xy 115.321588 -264.327431) (xy 115.345166 -264.373705) (xy 115.361214 -264.423098) (xy 115.369339 -264.474393)
			(xy 115.369848 -264.50036) (xy 115.369339 -264.526327) (xy 115.649249 -264.526327) (xy 115.649249 -264.474393)
			(xy 115.657374 -264.423098) (xy 115.673422 -264.373705) (xy 115.697 -264.327431) (xy 115.727526 -264.285415)
			(xy 115.764249 -264.248692) (xy 115.806265 -264.218166) (xy 115.852539 -264.194588) (xy 115.901932 -264.17854)
			(xy 115.953227 -264.170415) (xy 116.005161 -264.170415) (xy 116.056456 -264.17854) (xy 116.105849 -264.194588)
			(xy 116.152123 -264.218166) (xy 116.194139 -264.248692) (xy 116.230862 -264.285415) (xy 116.261388 -264.327431)
			(xy 116.284966 -264.373705) (xy 116.301014 -264.423098) (xy 116.309139 -264.474393) (xy 116.309648 -264.50036)
			(xy 116.309139 -264.526327) (xy 116.589049 -264.526327) (xy 116.589049 -264.474393) (xy 116.597174 -264.423098)
			(xy 116.613222 -264.373705) (xy 116.6368 -264.327431) (xy 116.667326 -264.285415) (xy 116.704049 -264.248692)
			(xy 116.746065 -264.218166) (xy 116.792339 -264.194588) (xy 116.841732 -264.17854) (xy 116.893027 -264.170415)
			(xy 116.944961 -264.170415) (xy 116.996256 -264.17854) (xy 117.045649 -264.194588) (xy 117.091923 -264.218166)
			(xy 117.133939 -264.248692) (xy 117.170662 -264.285415) (xy 117.201188 -264.327431) (xy 117.224766 -264.373705)
			(xy 117.240814 -264.423098) (xy 117.248939 -264.474393) (xy 117.249448 -264.50036) (xy 117.248939 -264.526327)
			(xy 117.528849 -264.526327) (xy 117.528849 -264.474393) (xy 117.536974 -264.423098) (xy 117.553022 -264.373705)
			(xy 117.5766 -264.327431) (xy 117.607126 -264.285415) (xy 117.643849 -264.248692) (xy 117.685865 -264.218166)
			(xy 117.732139 -264.194588) (xy 117.781532 -264.17854) (xy 117.832827 -264.170415) (xy 117.884761 -264.170415)
			(xy 117.936056 -264.17854) (xy 117.985449 -264.194588) (xy 118.031723 -264.218166) (xy 118.073739 -264.248692)
			(xy 118.110462 -264.285415) (xy 118.140988 -264.327431) (xy 118.164566 -264.373705) (xy 118.180614 -264.423098)
			(xy 118.188739 -264.474393) (xy 118.189248 -264.50036) (xy 118.188739 -264.526327) (xy 118.468649 -264.526327)
			(xy 118.468649 -264.474393) (xy 118.476774 -264.423098) (xy 118.492822 -264.373705) (xy 118.5164 -264.327431)
			(xy 118.546926 -264.285415) (xy 118.583649 -264.248692) (xy 118.625665 -264.218166) (xy 118.671939 -264.194588)
			(xy 118.721332 -264.17854) (xy 118.772627 -264.170415) (xy 118.824561 -264.170415) (xy 118.875856 -264.17854)
			(xy 118.925249 -264.194588) (xy 118.971523 -264.218166) (xy 119.013539 -264.248692) (xy 119.050262 -264.285415)
			(xy 119.080788 -264.327431) (xy 119.104366 -264.373705) (xy 119.120414 -264.423098) (xy 119.128539 -264.474393)
			(xy 119.129048 -264.50036) (xy 119.128539 -264.526327) (xy 119.408449 -264.526327) (xy 119.408449 -264.474393)
			(xy 119.416574 -264.423098) (xy 119.432622 -264.373705) (xy 119.4562 -264.327431) (xy 119.486726 -264.285415)
			(xy 119.523449 -264.248692) (xy 119.565465 -264.218166) (xy 119.611739 -264.194588) (xy 119.661132 -264.17854)
			(xy 119.712427 -264.170415) (xy 119.764361 -264.170415) (xy 119.815656 -264.17854) (xy 119.865049 -264.194588)
			(xy 119.911323 -264.218166) (xy 119.953339 -264.248692) (xy 119.990062 -264.285415) (xy 120.020588 -264.327431)
			(xy 120.044166 -264.373705) (xy 120.060214 -264.423098) (xy 120.068339 -264.474393) (xy 120.068848 -264.50036)
			(xy 120.068339 -264.526327) (xy 120.348249 -264.526327) (xy 120.348249 -264.474393) (xy 120.356374 -264.423098)
			(xy 120.372422 -264.373705) (xy 120.396 -264.327431) (xy 120.426526 -264.285415) (xy 120.463249 -264.248692)
			(xy 120.505265 -264.218166) (xy 120.551539 -264.194588) (xy 120.600932 -264.17854) (xy 120.652227 -264.170415)
			(xy 120.704161 -264.170415) (xy 120.755456 -264.17854) (xy 120.804849 -264.194588) (xy 120.851123 -264.218166)
			(xy 120.893139 -264.248692) (xy 120.929862 -264.285415) (xy 120.960388 -264.327431) (xy 120.983966 -264.373705)
			(xy 121.000014 -264.423098) (xy 121.008139 -264.474393) (xy 121.008648 -264.50036) (xy 121.008139 -264.526327)
			(xy 121.288049 -264.526327) (xy 121.288049 -264.474393) (xy 121.296174 -264.423098) (xy 121.312222 -264.373705)
			(xy 121.3358 -264.327431) (xy 121.366326 -264.285415) (xy 121.403049 -264.248692) (xy 121.445065 -264.218166)
			(xy 121.491339 -264.194588) (xy 121.540732 -264.17854) (xy 121.592027 -264.170415) (xy 121.643961 -264.170415)
			(xy 121.695256 -264.17854) (xy 121.744649 -264.194588) (xy 121.790923 -264.218166) (xy 121.832939 -264.248692)
			(xy 121.869662 -264.285415) (xy 121.900188 -264.327431) (xy 121.923766 -264.373705) (xy 121.939814 -264.423098)
			(xy 121.947939 -264.474393) (xy 121.948448 -264.50036) (xy 121.947939 -264.526327) (xy 122.227849 -264.526327)
			(xy 122.227849 -264.474393) (xy 122.235974 -264.423098) (xy 122.252022 -264.373705) (xy 122.2756 -264.327431)
			(xy 122.306126 -264.285415) (xy 122.342849 -264.248692) (xy 122.384865 -264.218166) (xy 122.431139 -264.194588)
			(xy 122.480532 -264.17854) (xy 122.531827 -264.170415) (xy 122.583761 -264.170415) (xy 122.635056 -264.17854)
			(xy 122.684449 -264.194588) (xy 122.730723 -264.218166) (xy 122.772739 -264.248692) (xy 122.809462 -264.285415)
			(xy 122.839988 -264.327431) (xy 122.863566 -264.373705) (xy 122.879614 -264.423098) (xy 122.887739 -264.474393)
			(xy 122.888248 -264.50036) (xy 122.887739 -264.526327) (xy 123.167649 -264.526327) (xy 123.167649 -264.474393)
			(xy 123.175774 -264.423098) (xy 123.191822 -264.373705) (xy 123.2154 -264.327431) (xy 123.245926 -264.285415)
			(xy 123.282649 -264.248692) (xy 123.324665 -264.218166) (xy 123.370939 -264.194588) (xy 123.420332 -264.17854)
			(xy 123.471627 -264.170415) (xy 123.523561 -264.170415) (xy 123.574856 -264.17854) (xy 123.624249 -264.194588)
			(xy 123.670523 -264.218166) (xy 123.712539 -264.248692) (xy 123.749262 -264.285415) (xy 123.779788 -264.327431)
			(xy 123.803366 -264.373705) (xy 123.819414 -264.423098) (xy 123.827539 -264.474393) (xy 123.828048 -264.50036)
			(xy 123.827539 -264.526327) (xy 123.819414 -264.577622) (xy 123.803366 -264.627015) (xy 123.779788 -264.673289)
			(xy 123.749262 -264.715305) (xy 123.712539 -264.752028) (xy 123.670523 -264.782554) (xy 123.624249 -264.806132)
			(xy 123.574856 -264.82218) (xy 123.523561 -264.830305) (xy 123.471627 -264.830305) (xy 123.420332 -264.82218)
			(xy 123.370939 -264.806132) (xy 123.324665 -264.782554) (xy 123.282649 -264.752028) (xy 123.245926 -264.715305)
			(xy 123.2154 -264.673289) (xy 123.191822 -264.627015) (xy 123.175774 -264.577622) (xy 123.167649 -264.526327)
			(xy 122.887739 -264.526327) (xy 122.879614 -264.577622) (xy 122.863566 -264.627015) (xy 122.839988 -264.673289)
			(xy 122.809462 -264.715305) (xy 122.772739 -264.752028) (xy 122.730723 -264.782554) (xy 122.684449 -264.806132)
			(xy 122.635056 -264.82218) (xy 122.583761 -264.830305) (xy 122.531827 -264.830305) (xy 122.480532 -264.82218)
			(xy 122.431139 -264.806132) (xy 122.384865 -264.782554) (xy 122.342849 -264.752028) (xy 122.306126 -264.715305)
			(xy 122.2756 -264.673289) (xy 122.252022 -264.627015) (xy 122.235974 -264.577622) (xy 122.227849 -264.526327)
			(xy 121.947939 -264.526327) (xy 121.939814 -264.577622) (xy 121.923766 -264.627015) (xy 121.900188 -264.673289)
			(xy 121.869662 -264.715305) (xy 121.832939 -264.752028) (xy 121.790923 -264.782554) (xy 121.744649 -264.806132)
			(xy 121.695256 -264.82218) (xy 121.643961 -264.830305) (xy 121.592027 -264.830305) (xy 121.540732 -264.82218)
			(xy 121.491339 -264.806132) (xy 121.445065 -264.782554) (xy 121.403049 -264.752028) (xy 121.366326 -264.715305)
			(xy 121.3358 -264.673289) (xy 121.312222 -264.627015) (xy 121.296174 -264.577622) (xy 121.288049 -264.526327)
			(xy 121.008139 -264.526327) (xy 121.000014 -264.577622) (xy 120.983966 -264.627015) (xy 120.960388 -264.673289)
			(xy 120.929862 -264.715305) (xy 120.893139 -264.752028) (xy 120.851123 -264.782554) (xy 120.804849 -264.806132)
			(xy 120.755456 -264.82218) (xy 120.704161 -264.830305) (xy 120.652227 -264.830305) (xy 120.600932 -264.82218)
			(xy 120.551539 -264.806132) (xy 120.505265 -264.782554) (xy 120.463249 -264.752028) (xy 120.426526 -264.715305)
			(xy 120.396 -264.673289) (xy 120.372422 -264.627015) (xy 120.356374 -264.577622) (xy 120.348249 -264.526327)
			(xy 120.068339 -264.526327) (xy 120.060214 -264.577622) (xy 120.044166 -264.627015) (xy 120.020588 -264.673289)
			(xy 119.990062 -264.715305) (xy 119.953339 -264.752028) (xy 119.911323 -264.782554) (xy 119.865049 -264.806132)
			(xy 119.815656 -264.82218) (xy 119.764361 -264.830305) (xy 119.712427 -264.830305) (xy 119.661132 -264.82218)
			(xy 119.611739 -264.806132) (xy 119.565465 -264.782554) (xy 119.523449 -264.752028) (xy 119.486726 -264.715305)
			(xy 119.4562 -264.673289) (xy 119.432622 -264.627015) (xy 119.416574 -264.577622) (xy 119.408449 -264.526327)
			(xy 119.128539 -264.526327) (xy 119.120414 -264.577622) (xy 119.104366 -264.627015) (xy 119.080788 -264.673289)
			(xy 119.050262 -264.715305) (xy 119.013539 -264.752028) (xy 118.971523 -264.782554) (xy 118.925249 -264.806132)
			(xy 118.875856 -264.82218) (xy 118.824561 -264.830305) (xy 118.772627 -264.830305) (xy 118.721332 -264.82218)
			(xy 118.671939 -264.806132) (xy 118.625665 -264.782554) (xy 118.583649 -264.752028) (xy 118.546926 -264.715305)
			(xy 118.5164 -264.673289) (xy 118.492822 -264.627015) (xy 118.476774 -264.577622) (xy 118.468649 -264.526327)
			(xy 118.188739 -264.526327) (xy 118.180614 -264.577622) (xy 118.164566 -264.627015) (xy 118.140988 -264.673289)
			(xy 118.110462 -264.715305) (xy 118.073739 -264.752028) (xy 118.031723 -264.782554) (xy 117.985449 -264.806132)
			(xy 117.936056 -264.82218) (xy 117.884761 -264.830305) (xy 117.832827 -264.830305) (xy 117.781532 -264.82218)
			(xy 117.732139 -264.806132) (xy 117.685865 -264.782554) (xy 117.643849 -264.752028) (xy 117.607126 -264.715305)
			(xy 117.5766 -264.673289) (xy 117.553022 -264.627015) (xy 117.536974 -264.577622) (xy 117.528849 -264.526327)
			(xy 117.248939 -264.526327) (xy 117.240814 -264.577622) (xy 117.224766 -264.627015) (xy 117.201188 -264.673289)
			(xy 117.170662 -264.715305) (xy 117.133939 -264.752028) (xy 117.091923 -264.782554) (xy 117.045649 -264.806132)
			(xy 116.996256 -264.82218) (xy 116.944961 -264.830305) (xy 116.893027 -264.830305) (xy 116.841732 -264.82218)
			(xy 116.792339 -264.806132) (xy 116.746065 -264.782554) (xy 116.704049 -264.752028) (xy 116.667326 -264.715305)
			(xy 116.6368 -264.673289) (xy 116.613222 -264.627015) (xy 116.597174 -264.577622) (xy 116.589049 -264.526327)
			(xy 116.309139 -264.526327) (xy 116.301014 -264.577622) (xy 116.284966 -264.627015) (xy 116.261388 -264.673289)
			(xy 116.230862 -264.715305) (xy 116.194139 -264.752028) (xy 116.152123 -264.782554) (xy 116.105849 -264.806132)
			(xy 116.056456 -264.82218) (xy 116.005161 -264.830305) (xy 115.953227 -264.830305) (xy 115.901932 -264.82218)
			(xy 115.852539 -264.806132) (xy 115.806265 -264.782554) (xy 115.764249 -264.752028) (xy 115.727526 -264.715305)
			(xy 115.697 -264.673289) (xy 115.673422 -264.627015) (xy 115.657374 -264.577622) (xy 115.649249 -264.526327)
			(xy 115.369339 -264.526327) (xy 115.361214 -264.577622) (xy 115.345166 -264.627015) (xy 115.321588 -264.673289)
			(xy 115.291062 -264.715305) (xy 115.254339 -264.752028) (xy 115.212323 -264.782554) (xy 115.166049 -264.806132)
			(xy 115.116656 -264.82218) (xy 115.065361 -264.830305) (xy 115.013427 -264.830305) (xy 114.962132 -264.82218)
			(xy 114.912739 -264.806132) (xy 114.866465 -264.782554) (xy 114.824449 -264.752028) (xy 114.787726 -264.715305)
			(xy 114.7572 -264.673289) (xy 114.733622 -264.627015) (xy 114.717574 -264.577622) (xy 114.709449 -264.526327)
			(xy 114.429539 -264.526327) (xy 114.421414 -264.577622) (xy 114.405366 -264.627015) (xy 114.381788 -264.673289)
			(xy 114.351262 -264.715305) (xy 114.314539 -264.752028) (xy 114.272523 -264.782554) (xy 114.226249 -264.806132)
			(xy 114.176856 -264.82218) (xy 114.125561 -264.830305) (xy 114.073627 -264.830305) (xy 114.022332 -264.82218)
			(xy 113.972939 -264.806132) (xy 113.926665 -264.782554) (xy 113.884649 -264.752028) (xy 113.847926 -264.715305)
			(xy 113.8174 -264.673289) (xy 113.793822 -264.627015) (xy 113.777774 -264.577622) (xy 113.769649 -264.526327)
			(xy 113.489739 -264.526327) (xy 113.481614 -264.577622) (xy 113.465566 -264.627015) (xy 113.441988 -264.673289)
			(xy 113.411462 -264.715305) (xy 113.374739 -264.752028) (xy 113.332723 -264.782554) (xy 113.286449 -264.806132)
			(xy 113.237056 -264.82218) (xy 113.185761 -264.830305) (xy 113.133827 -264.830305) (xy 113.082532 -264.82218)
			(xy 113.033139 -264.806132) (xy 112.986865 -264.782554) (xy 112.944849 -264.752028) (xy 112.908126 -264.715305)
			(xy 112.8776 -264.673289) (xy 112.854022 -264.627015) (xy 112.837974 -264.577622) (xy 112.829849 -264.526327)
			(xy 112.550193 -264.526327) (xy 112.542068 -264.577622) (xy 112.52602 -264.627015) (xy 112.502442 -264.673289)
			(xy 112.471916 -264.715305) (xy 112.435193 -264.752028) (xy 112.393177 -264.782554) (xy 112.346903 -264.806132)
			(xy 112.29751 -264.82218) (xy 112.246215 -264.830305) (xy 112.194281 -264.830305) (xy 112.142986 -264.82218)
			(xy 112.093593 -264.806132) (xy 112.047319 -264.782554) (xy 112.005303 -264.752028) (xy 111.96858 -264.715305)
			(xy 111.938054 -264.673289) (xy 111.914476 -264.627015) (xy 111.898428 -264.577622) (xy 111.890303 -264.526327)
			(xy 111.610393 -264.526327) (xy 111.602268 -264.577622) (xy 111.58622 -264.627015) (xy 111.562642 -264.673289)
			(xy 111.532116 -264.715305) (xy 111.495393 -264.752028) (xy 111.453377 -264.782554) (xy 111.407103 -264.806132)
			(xy 111.35771 -264.82218) (xy 111.306415 -264.830305) (xy 111.254481 -264.830305) (xy 111.203186 -264.82218)
			(xy 111.153793 -264.806132) (xy 111.107519 -264.782554) (xy 111.065503 -264.752028) (xy 111.02878 -264.715305)
			(xy 110.998254 -264.673289) (xy 110.974676 -264.627015) (xy 110.958628 -264.577622) (xy 110.950503 -264.526327)
			(xy 110.670593 -264.526327) (xy 110.662468 -264.577622) (xy 110.64642 -264.627015) (xy 110.622842 -264.673289)
			(xy 110.592316 -264.715305) (xy 110.555593 -264.752028) (xy 110.513577 -264.782554) (xy 110.467303 -264.806132)
			(xy 110.41791 -264.82218) (xy 110.366615 -264.830305) (xy 110.314681 -264.830305) (xy 110.263386 -264.82218)
			(xy 110.213993 -264.806132) (xy 110.167719 -264.782554) (xy 110.125703 -264.752028) (xy 110.08898 -264.715305)
			(xy 110.058454 -264.673289) (xy 110.034876 -264.627015) (xy 110.018828 -264.577622) (xy 110.010703 -264.526327)
			(xy 109.730539 -264.526327) (xy 109.722414 -264.577622) (xy 109.706366 -264.627015) (xy 109.682788 -264.673289)
			(xy 109.652262 -264.715305) (xy 109.615539 -264.752028) (xy 109.573523 -264.782554) (xy 109.527249 -264.806132)
			(xy 109.477856 -264.82218) (xy 109.426561 -264.830305) (xy 109.374627 -264.830305) (xy 109.323332 -264.82218)
			(xy 109.273939 -264.806132) (xy 109.227665 -264.782554) (xy 109.185649 -264.752028) (xy 109.148926 -264.715305)
			(xy 109.1184 -264.673289) (xy 109.094822 -264.627015) (xy 109.078774 -264.577622) (xy 109.070649 -264.526327)
			(xy 108.790993 -264.526327) (xy 108.782868 -264.577622) (xy 108.76682 -264.627015) (xy 108.743242 -264.673289)
			(xy 108.712716 -264.715305) (xy 108.675993 -264.752028) (xy 108.633977 -264.782554) (xy 108.587703 -264.806132)
			(xy 108.53831 -264.82218) (xy 108.487015 -264.830305) (xy 108.435081 -264.830305) (xy 108.383786 -264.82218)
			(xy 108.334393 -264.806132) (xy 108.288119 -264.782554) (xy 108.246103 -264.752028) (xy 108.20938 -264.715305)
			(xy 108.178854 -264.673289) (xy 108.155276 -264.627015) (xy 108.139228 -264.577622) (xy 108.131103 -264.526327)
			(xy 104.091712 -264.526327) (xy 104.091664 -264.528663) (xy 104.082023 -264.584442) (xy 104.063031 -264.637768)
			(xy 104.035244 -264.687085) (xy 104.017826 -264.709402) (xy 104.017826 -264.897108) (xy 104.018224 -264.910439)
			(xy 104.025133 -264.936192) (xy 104.038476 -264.959276) (xy 104.057343 -264.978115) (xy 104.080447 -264.991425)
			(xy 104.106209 -264.998295) (xy 104.132872 -264.998258) (xy 104.145842 -264.995152) (xy 104.166967 -264.989812)
			(xy 104.210161 -264.984078) (xy 104.231948 -264.983722) (xy 104.257915 -264.984235) (xy 104.309208 -264.992366)
			(xy 104.358597 -265.00842) (xy 104.404868 -265.032002) (xy 104.44688 -265.062531) (xy 104.4836 -265.099256)
			(xy 104.514123 -265.141273) (xy 104.537699 -265.187547) (xy 104.553745 -265.236939) (xy 104.561869 -265.288233)
			(xy 104.561869 -265.340143) (xy 104.841803 -265.340143) (xy 104.841803 -265.288209) (xy 104.849928 -265.236914)
			(xy 104.865976 -265.187521) (xy 104.889554 -265.141247) (xy 104.92008 -265.099231) (xy 104.956803 -265.062508)
			(xy 104.998819 -265.031982) (xy 105.045093 -265.008404) (xy 105.094486 -264.992356) (xy 105.145781 -264.984231)
			(xy 105.197715 -264.984231) (xy 105.24901 -264.992356) (xy 105.298403 -265.008404) (xy 105.344677 -265.031982)
			(xy 105.386693 -265.062508) (xy 105.423416 -265.099231) (xy 105.453942 -265.141247) (xy 105.47752 -265.187521)
			(xy 105.493568 -265.236914) (xy 105.501693 -265.288209) (xy 105.502202 -265.314176) (xy 105.501693 -265.340143)
			(xy 105.781603 -265.340143) (xy 105.781603 -265.288209) (xy 105.789728 -265.236914) (xy 105.805776 -265.187521)
			(xy 105.829354 -265.141247) (xy 105.85988 -265.099231) (xy 105.896603 -265.062508) (xy 105.938619 -265.031982)
			(xy 105.984893 -265.008404) (xy 106.034286 -264.992356) (xy 106.085581 -264.984231) (xy 106.137515 -264.984231)
			(xy 106.18881 -264.992356) (xy 106.238203 -265.008404) (xy 106.284477 -265.031982) (xy 106.326493 -265.062508)
			(xy 106.363216 -265.099231) (xy 106.393742 -265.141247) (xy 106.41732 -265.187521) (xy 106.433368 -265.236914)
			(xy 106.441493 -265.288209) (xy 106.442002 -265.314176) (xy 106.441493 -265.340143) (xy 106.721403 -265.340143)
			(xy 106.721403 -265.288209) (xy 106.729528 -265.236914) (xy 106.745576 -265.187521) (xy 106.769154 -265.141247)
			(xy 106.79968 -265.099231) (xy 106.836403 -265.062508) (xy 106.878419 -265.031982) (xy 106.924693 -265.008404)
			(xy 106.974086 -264.992356) (xy 107.025381 -264.984231) (xy 107.077315 -264.984231) (xy 107.12861 -264.992356)
			(xy 107.178003 -265.008404) (xy 107.224277 -265.031982) (xy 107.266293 -265.062508) (xy 107.303016 -265.099231)
			(xy 107.333542 -265.141247) (xy 107.35712 -265.187521) (xy 107.373168 -265.236914) (xy 107.381293 -265.288209)
			(xy 107.381802 -265.314176) (xy 107.381293 -265.340143) (xy 108.601003 -265.340143) (xy 108.601003 -265.288209)
			(xy 108.609128 -265.236914) (xy 108.625176 -265.187521) (xy 108.648754 -265.141247) (xy 108.67928 -265.099231)
			(xy 108.716003 -265.062508) (xy 108.758019 -265.031982) (xy 108.804293 -265.008404) (xy 108.853686 -264.992356)
			(xy 108.904981 -264.984231) (xy 108.956915 -264.984231) (xy 109.00821 -264.992356) (xy 109.057603 -265.008404)
			(xy 109.103877 -265.031982) (xy 109.145893 -265.062508) (xy 109.182616 -265.099231) (xy 109.213142 -265.141247)
			(xy 109.23672 -265.187521) (xy 109.252768 -265.236914) (xy 109.260893 -265.288209) (xy 109.261402 -265.314176)
			(xy 109.260893 -265.340143) (xy 109.540549 -265.340143) (xy 109.540549 -265.288209) (xy 109.548674 -265.236914)
			(xy 109.564722 -265.187521) (xy 109.5883 -265.141247) (xy 109.618826 -265.099231) (xy 109.655549 -265.062508)
			(xy 109.697565 -265.031982) (xy 109.743839 -265.008404) (xy 109.793232 -264.992356) (xy 109.844527 -264.984231)
			(xy 109.896461 -264.984231) (xy 109.947756 -264.992356) (xy 109.997149 -265.008404) (xy 110.043423 -265.031982)
			(xy 110.085439 -265.062508) (xy 110.122162 -265.099231) (xy 110.152688 -265.141247) (xy 110.176266 -265.187521)
			(xy 110.192314 -265.236914) (xy 110.200439 -265.288209) (xy 110.200948 -265.314176) (xy 110.200439 -265.340143)
			(xy 110.480349 -265.340143) (xy 110.480349 -265.288209) (xy 110.488474 -265.236914) (xy 110.504522 -265.187521)
			(xy 110.5281 -265.141247) (xy 110.558626 -265.099231) (xy 110.595349 -265.062508) (xy 110.637365 -265.031982)
			(xy 110.683639 -265.008404) (xy 110.733032 -264.992356) (xy 110.784327 -264.984231) (xy 110.836261 -264.984231)
			(xy 110.887556 -264.992356) (xy 110.936949 -265.008404) (xy 110.983223 -265.031982) (xy 111.025239 -265.062508)
			(xy 111.061962 -265.099231) (xy 111.092488 -265.141247) (xy 111.116066 -265.187521) (xy 111.132114 -265.236914)
			(xy 111.140239 -265.288209) (xy 111.140748 -265.314176) (xy 111.140239 -265.340143) (xy 111.420149 -265.340143)
			(xy 111.420149 -265.288209) (xy 111.428274 -265.236914) (xy 111.444322 -265.187521) (xy 111.4679 -265.141247)
			(xy 111.498426 -265.099231) (xy 111.535149 -265.062508) (xy 111.577165 -265.031982) (xy 111.623439 -265.008404)
			(xy 111.672832 -264.992356) (xy 111.724127 -264.984231) (xy 111.776061 -264.984231) (xy 111.827356 -264.992356)
			(xy 111.876749 -265.008404) (xy 111.923023 -265.031982) (xy 111.965039 -265.062508) (xy 112.001762 -265.099231)
			(xy 112.032288 -265.141247) (xy 112.055866 -265.187521) (xy 112.071914 -265.236914) (xy 112.080039 -265.288209)
			(xy 112.080548 -265.314176) (xy 112.080039 -265.340143) (xy 112.359949 -265.340143) (xy 112.359949 -265.288209)
			(xy 112.368074 -265.236914) (xy 112.384122 -265.187521) (xy 112.4077 -265.141247) (xy 112.438226 -265.099231)
			(xy 112.474949 -265.062508) (xy 112.516965 -265.031982) (xy 112.563239 -265.008404) (xy 112.612632 -264.992356)
			(xy 112.663927 -264.984231) (xy 112.715861 -264.984231) (xy 112.767156 -264.992356) (xy 112.816549 -265.008404)
			(xy 112.862823 -265.031982) (xy 112.904839 -265.062508) (xy 112.941562 -265.099231) (xy 112.972088 -265.141247)
			(xy 112.995666 -265.187521) (xy 113.011714 -265.236914) (xy 113.019839 -265.288209) (xy 113.020348 -265.314176)
			(xy 113.019839 -265.340143) (xy 113.299749 -265.340143) (xy 113.299749 -265.288209) (xy 113.307874 -265.236914)
			(xy 113.323922 -265.187521) (xy 113.3475 -265.141247) (xy 113.378026 -265.099231) (xy 113.414749 -265.062508)
			(xy 113.456765 -265.031982) (xy 113.503039 -265.008404) (xy 113.552432 -264.992356) (xy 113.603727 -264.984231)
			(xy 113.655661 -264.984231) (xy 113.706956 -264.992356) (xy 113.756349 -265.008404) (xy 113.802623 -265.031982)
			(xy 113.844639 -265.062508) (xy 113.881362 -265.099231) (xy 113.911888 -265.141247) (xy 113.935466 -265.187521)
			(xy 113.951514 -265.236914) (xy 113.959639 -265.288209) (xy 113.960148 -265.314176) (xy 113.959639 -265.340143)
			(xy 114.239549 -265.340143) (xy 114.239549 -265.288209) (xy 114.247674 -265.236914) (xy 114.263722 -265.187521)
			(xy 114.2873 -265.141247) (xy 114.317826 -265.099231) (xy 114.354549 -265.062508) (xy 114.396565 -265.031982)
			(xy 114.442839 -265.008404) (xy 114.492232 -264.992356) (xy 114.543527 -264.984231) (xy 114.595461 -264.984231)
			(xy 114.646756 -264.992356) (xy 114.696149 -265.008404) (xy 114.742423 -265.031982) (xy 114.784439 -265.062508)
			(xy 114.821162 -265.099231) (xy 114.851688 -265.141247) (xy 114.875266 -265.187521) (xy 114.891314 -265.236914)
			(xy 114.899439 -265.288209) (xy 114.899948 -265.314176) (xy 114.899439 -265.340143) (xy 115.179603 -265.340143)
			(xy 115.179603 -265.288209) (xy 115.187728 -265.236914) (xy 115.203776 -265.187521) (xy 115.227354 -265.141247)
			(xy 115.25788 -265.099231) (xy 115.294603 -265.062508) (xy 115.336619 -265.031982) (xy 115.382893 -265.008404)
			(xy 115.432286 -264.992356) (xy 115.483581 -264.984231) (xy 115.535515 -264.984231) (xy 115.58681 -264.992356)
			(xy 115.636203 -265.008404) (xy 115.682477 -265.031982) (xy 115.724493 -265.062508) (xy 115.761216 -265.099231)
			(xy 115.791742 -265.141247) (xy 115.81532 -265.187521) (xy 115.831368 -265.236914) (xy 115.839493 -265.288209)
			(xy 115.840002 -265.314176) (xy 115.839493 -265.340143) (xy 116.119403 -265.340143) (xy 116.119403 -265.288209)
			(xy 116.127528 -265.236914) (xy 116.143576 -265.187521) (xy 116.167154 -265.141247) (xy 116.19768 -265.099231)
			(xy 116.234403 -265.062508) (xy 116.276419 -265.031982) (xy 116.322693 -265.008404) (xy 116.372086 -264.992356)
			(xy 116.423381 -264.984231) (xy 116.475315 -264.984231) (xy 116.52661 -264.992356) (xy 116.576003 -265.008404)
			(xy 116.622277 -265.031982) (xy 116.664293 -265.062508) (xy 116.701016 -265.099231) (xy 116.731542 -265.141247)
			(xy 116.75512 -265.187521) (xy 116.771168 -265.236914) (xy 116.779293 -265.288209) (xy 116.779802 -265.314176)
			(xy 116.779293 -265.340143) (xy 117.059203 -265.340143) (xy 117.059203 -265.288209) (xy 117.067328 -265.236914)
			(xy 117.083376 -265.187521) (xy 117.106954 -265.141247) (xy 117.13748 -265.099231) (xy 117.174203 -265.062508)
			(xy 117.216219 -265.031982) (xy 117.262493 -265.008404) (xy 117.311886 -264.992356) (xy 117.363181 -264.984231)
			(xy 117.415115 -264.984231) (xy 117.46641 -264.992356) (xy 117.515803 -265.008404) (xy 117.562077 -265.031982)
			(xy 117.604093 -265.062508) (xy 117.640816 -265.099231) (xy 117.671342 -265.141247) (xy 117.69492 -265.187521)
			(xy 117.710968 -265.236914) (xy 117.719093 -265.288209) (xy 117.719602 -265.314176) (xy 117.719093 -265.340143)
			(xy 117.998749 -265.340143) (xy 117.998749 -265.288209) (xy 118.006874 -265.236914) (xy 118.022922 -265.187521)
			(xy 118.0465 -265.141247) (xy 118.077026 -265.099231) (xy 118.113749 -265.062508) (xy 118.155765 -265.031982)
			(xy 118.202039 -265.008404) (xy 118.251432 -264.992356) (xy 118.302727 -264.984231) (xy 118.354661 -264.984231)
			(xy 118.405956 -264.992356) (xy 118.455349 -265.008404) (xy 118.501623 -265.031982) (xy 118.543639 -265.062508)
			(xy 118.580362 -265.099231) (xy 118.610888 -265.141247) (xy 118.634466 -265.187521) (xy 118.650514 -265.236914)
			(xy 118.658639 -265.288209) (xy 118.659148 -265.314176) (xy 118.658639 -265.340143) (xy 118.938803 -265.340143)
			(xy 118.938803 -265.288209) (xy 118.946928 -265.236914) (xy 118.962976 -265.187521) (xy 118.986554 -265.141247)
			(xy 119.01708 -265.099231) (xy 119.053803 -265.062508) (xy 119.095819 -265.031982) (xy 119.142093 -265.008404)
			(xy 119.191486 -264.992356) (xy 119.242781 -264.984231) (xy 119.294715 -264.984231) (xy 119.34601 -264.992356)
			(xy 119.395403 -265.008404) (xy 119.441677 -265.031982) (xy 119.483693 -265.062508) (xy 119.520416 -265.099231)
			(xy 119.550942 -265.141247) (xy 119.57452 -265.187521) (xy 119.590568 -265.236914) (xy 119.598693 -265.288209)
			(xy 119.599202 -265.314176) (xy 119.598693 -265.340143) (xy 119.878603 -265.340143) (xy 119.878603 -265.288209)
			(xy 119.886728 -265.236914) (xy 119.902776 -265.187521) (xy 119.926354 -265.141247) (xy 119.95688 -265.099231)
			(xy 119.993603 -265.062508) (xy 120.035619 -265.031982) (xy 120.081893 -265.008404) (xy 120.131286 -264.992356)
			(xy 120.182581 -264.984231) (xy 120.234515 -264.984231) (xy 120.28581 -264.992356) (xy 120.335203 -265.008404)
			(xy 120.381477 -265.031982) (xy 120.423493 -265.062508) (xy 120.460216 -265.099231) (xy 120.490742 -265.141247)
			(xy 120.51432 -265.187521) (xy 120.530368 -265.236914) (xy 120.538493 -265.288209) (xy 120.539002 -265.314176)
			(xy 120.538493 -265.340143) (xy 121.758203 -265.340143) (xy 121.758203 -265.288209) (xy 121.766328 -265.236914)
			(xy 121.782376 -265.187521) (xy 121.805954 -265.141247) (xy 121.83648 -265.099231) (xy 121.873203 -265.062508)
			(xy 121.915219 -265.031982) (xy 121.961493 -265.008404) (xy 122.010886 -264.992356) (xy 122.062181 -264.984231)
			(xy 122.114115 -264.984231) (xy 122.16541 -264.992356) (xy 122.214803 -265.008404) (xy 122.261077 -265.031982)
			(xy 122.303093 -265.062508) (xy 122.339816 -265.099231) (xy 122.370342 -265.141247) (xy 122.39392 -265.187521)
			(xy 122.409968 -265.236914) (xy 122.418093 -265.288209) (xy 122.418602 -265.314176) (xy 122.418093 -265.340143)
			(xy 122.698003 -265.340143) (xy 122.698003 -265.288209) (xy 122.706128 -265.236914) (xy 122.722176 -265.187521)
			(xy 122.745754 -265.141247) (xy 122.77628 -265.099231) (xy 122.813003 -265.062508) (xy 122.855019 -265.031982)
			(xy 122.901293 -265.008404) (xy 122.950686 -264.992356) (xy 123.001981 -264.984231) (xy 123.053915 -264.984231)
			(xy 123.10521 -264.992356) (xy 123.154603 -265.008404) (xy 123.200877 -265.031982) (xy 123.242893 -265.062508)
			(xy 123.279616 -265.099231) (xy 123.310142 -265.141247) (xy 123.33372 -265.187521) (xy 123.349768 -265.236914)
			(xy 123.357893 -265.288209) (xy 123.358402 -265.314176) (xy 123.357893 -265.340143) (xy 123.349768 -265.391438)
			(xy 123.33372 -265.440831) (xy 123.310142 -265.487105) (xy 123.279616 -265.529121) (xy 123.242893 -265.565844)
			(xy 123.200877 -265.59637) (xy 123.154603 -265.619948) (xy 123.10521 -265.635996) (xy 123.053915 -265.644121)
			(xy 123.001981 -265.644121) (xy 122.950686 -265.635996) (xy 122.901293 -265.619948) (xy 122.855019 -265.59637)
			(xy 122.813003 -265.565844) (xy 122.77628 -265.529121) (xy 122.745754 -265.487105) (xy 122.722176 -265.440831)
			(xy 122.706128 -265.391438) (xy 122.698003 -265.340143) (xy 122.418093 -265.340143) (xy 122.409968 -265.391438)
			(xy 122.39392 -265.440831) (xy 122.370342 -265.487105) (xy 122.339816 -265.529121) (xy 122.303093 -265.565844)
			(xy 122.261077 -265.59637) (xy 122.214803 -265.619948) (xy 122.16541 -265.635996) (xy 122.114115 -265.644121)
			(xy 122.062181 -265.644121) (xy 122.010886 -265.635996) (xy 121.961493 -265.619948) (xy 121.915219 -265.59637)
			(xy 121.873203 -265.565844) (xy 121.83648 -265.529121) (xy 121.805954 -265.487105) (xy 121.782376 -265.440831)
			(xy 121.766328 -265.391438) (xy 121.758203 -265.340143) (xy 120.538493 -265.340143) (xy 120.530368 -265.391438)
			(xy 120.51432 -265.440831) (xy 120.490742 -265.487105) (xy 120.460216 -265.529121) (xy 120.423493 -265.565844)
			(xy 120.381477 -265.59637) (xy 120.335203 -265.619948) (xy 120.28581 -265.635996) (xy 120.234515 -265.644121)
			(xy 120.182581 -265.644121) (xy 120.131286 -265.635996) (xy 120.081893 -265.619948) (xy 120.035619 -265.59637)
			(xy 119.993603 -265.565844) (xy 119.95688 -265.529121) (xy 119.926354 -265.487105) (xy 119.902776 -265.440831)
			(xy 119.886728 -265.391438) (xy 119.878603 -265.340143) (xy 119.598693 -265.340143) (xy 119.590568 -265.391438)
			(xy 119.57452 -265.440831) (xy 119.550942 -265.487105) (xy 119.520416 -265.529121) (xy 119.483693 -265.565844)
			(xy 119.441677 -265.59637) (xy 119.395403 -265.619948) (xy 119.34601 -265.635996) (xy 119.294715 -265.644121)
			(xy 119.242781 -265.644121) (xy 119.191486 -265.635996) (xy 119.142093 -265.619948) (xy 119.095819 -265.59637)
			(xy 119.053803 -265.565844) (xy 119.01708 -265.529121) (xy 118.986554 -265.487105) (xy 118.962976 -265.440831)
			(xy 118.946928 -265.391438) (xy 118.938803 -265.340143) (xy 118.658639 -265.340143) (xy 118.650514 -265.391438)
			(xy 118.634466 -265.440831) (xy 118.610888 -265.487105) (xy 118.580362 -265.529121) (xy 118.543639 -265.565844)
			(xy 118.501623 -265.59637) (xy 118.455349 -265.619948) (xy 118.405956 -265.635996) (xy 118.354661 -265.644121)
			(xy 118.302727 -265.644121) (xy 118.251432 -265.635996) (xy 118.202039 -265.619948) (xy 118.155765 -265.59637)
			(xy 118.113749 -265.565844) (xy 118.077026 -265.529121) (xy 118.0465 -265.487105) (xy 118.022922 -265.440831)
			(xy 118.006874 -265.391438) (xy 117.998749 -265.340143) (xy 117.719093 -265.340143) (xy 117.710968 -265.391438)
			(xy 117.69492 -265.440831) (xy 117.671342 -265.487105) (xy 117.640816 -265.529121) (xy 117.604093 -265.565844)
			(xy 117.562077 -265.59637) (xy 117.515803 -265.619948) (xy 117.46641 -265.635996) (xy 117.415115 -265.644121)
			(xy 117.363181 -265.644121) (xy 117.311886 -265.635996) (xy 117.262493 -265.619948) (xy 117.216219 -265.59637)
			(xy 117.174203 -265.565844) (xy 117.13748 -265.529121) (xy 117.106954 -265.487105) (xy 117.083376 -265.440831)
			(xy 117.067328 -265.391438) (xy 117.059203 -265.340143) (xy 116.779293 -265.340143) (xy 116.771168 -265.391438)
			(xy 116.75512 -265.440831) (xy 116.731542 -265.487105) (xy 116.701016 -265.529121) (xy 116.664293 -265.565844)
			(xy 116.622277 -265.59637) (xy 116.576003 -265.619948) (xy 116.52661 -265.635996) (xy 116.475315 -265.644121)
			(xy 116.423381 -265.644121) (xy 116.372086 -265.635996) (xy 116.322693 -265.619948) (xy 116.276419 -265.59637)
			(xy 116.234403 -265.565844) (xy 116.19768 -265.529121) (xy 116.167154 -265.487105) (xy 116.143576 -265.440831)
			(xy 116.127528 -265.391438) (xy 116.119403 -265.340143) (xy 115.839493 -265.340143) (xy 115.831368 -265.391438)
			(xy 115.81532 -265.440831) (xy 115.791742 -265.487105) (xy 115.761216 -265.529121) (xy 115.724493 -265.565844)
			(xy 115.682477 -265.59637) (xy 115.636203 -265.619948) (xy 115.58681 -265.635996) (xy 115.535515 -265.644121)
			(xy 115.483581 -265.644121) (xy 115.432286 -265.635996) (xy 115.382893 -265.619948) (xy 115.336619 -265.59637)
			(xy 115.294603 -265.565844) (xy 115.25788 -265.529121) (xy 115.227354 -265.487105) (xy 115.203776 -265.440831)
			(xy 115.187728 -265.391438) (xy 115.179603 -265.340143) (xy 114.899439 -265.340143) (xy 114.891314 -265.391438)
			(xy 114.875266 -265.440831) (xy 114.851688 -265.487105) (xy 114.821162 -265.529121) (xy 114.784439 -265.565844)
			(xy 114.742423 -265.59637) (xy 114.696149 -265.619948) (xy 114.646756 -265.635996) (xy 114.595461 -265.644121)
			(xy 114.543527 -265.644121) (xy 114.492232 -265.635996) (xy 114.442839 -265.619948) (xy 114.396565 -265.59637)
			(xy 114.354549 -265.565844) (xy 114.317826 -265.529121) (xy 114.2873 -265.487105) (xy 114.263722 -265.440831)
			(xy 114.247674 -265.391438) (xy 114.239549 -265.340143) (xy 113.959639 -265.340143) (xy 113.951514 -265.391438)
			(xy 113.935466 -265.440831) (xy 113.911888 -265.487105) (xy 113.881362 -265.529121) (xy 113.844639 -265.565844)
			(xy 113.802623 -265.59637) (xy 113.756349 -265.619948) (xy 113.706956 -265.635996) (xy 113.655661 -265.644121)
			(xy 113.603727 -265.644121) (xy 113.552432 -265.635996) (xy 113.503039 -265.619948) (xy 113.456765 -265.59637)
			(xy 113.414749 -265.565844) (xy 113.378026 -265.529121) (xy 113.3475 -265.487105) (xy 113.323922 -265.440831)
			(xy 113.307874 -265.391438) (xy 113.299749 -265.340143) (xy 113.019839 -265.340143) (xy 113.011714 -265.391438)
			(xy 112.995666 -265.440831) (xy 112.972088 -265.487105) (xy 112.941562 -265.529121) (xy 112.904839 -265.565844)
			(xy 112.862823 -265.59637) (xy 112.816549 -265.619948) (xy 112.767156 -265.635996) (xy 112.715861 -265.644121)
			(xy 112.663927 -265.644121) (xy 112.612632 -265.635996) (xy 112.563239 -265.619948) (xy 112.516965 -265.59637)
			(xy 112.474949 -265.565844) (xy 112.438226 -265.529121) (xy 112.4077 -265.487105) (xy 112.384122 -265.440831)
			(xy 112.368074 -265.391438) (xy 112.359949 -265.340143) (xy 112.080039 -265.340143) (xy 112.071914 -265.391438)
			(xy 112.055866 -265.440831) (xy 112.032288 -265.487105) (xy 112.001762 -265.529121) (xy 111.965039 -265.565844)
			(xy 111.923023 -265.59637) (xy 111.876749 -265.619948) (xy 111.827356 -265.635996) (xy 111.776061 -265.644121)
			(xy 111.724127 -265.644121) (xy 111.672832 -265.635996) (xy 111.623439 -265.619948) (xy 111.577165 -265.59637)
			(xy 111.535149 -265.565844) (xy 111.498426 -265.529121) (xy 111.4679 -265.487105) (xy 111.444322 -265.440831)
			(xy 111.428274 -265.391438) (xy 111.420149 -265.340143) (xy 111.140239 -265.340143) (xy 111.132114 -265.391438)
			(xy 111.116066 -265.440831) (xy 111.092488 -265.487105) (xy 111.061962 -265.529121) (xy 111.025239 -265.565844)
			(xy 110.983223 -265.59637) (xy 110.936949 -265.619948) (xy 110.887556 -265.635996) (xy 110.836261 -265.644121)
			(xy 110.784327 -265.644121) (xy 110.733032 -265.635996) (xy 110.683639 -265.619948) (xy 110.637365 -265.59637)
			(xy 110.595349 -265.565844) (xy 110.558626 -265.529121) (xy 110.5281 -265.487105) (xy 110.504522 -265.440831)
			(xy 110.488474 -265.391438) (xy 110.480349 -265.340143) (xy 110.200439 -265.340143) (xy 110.192314 -265.391438)
			(xy 110.176266 -265.440831) (xy 110.152688 -265.487105) (xy 110.122162 -265.529121) (xy 110.085439 -265.565844)
			(xy 110.043423 -265.59637) (xy 109.997149 -265.619948) (xy 109.947756 -265.635996) (xy 109.896461 -265.644121)
			(xy 109.844527 -265.644121) (xy 109.793232 -265.635996) (xy 109.743839 -265.619948) (xy 109.697565 -265.59637)
			(xy 109.655549 -265.565844) (xy 109.618826 -265.529121) (xy 109.5883 -265.487105) (xy 109.564722 -265.440831)
			(xy 109.548674 -265.391438) (xy 109.540549 -265.340143) (xy 109.260893 -265.340143) (xy 109.252768 -265.391438)
			(xy 109.23672 -265.440831) (xy 109.213142 -265.487105) (xy 109.182616 -265.529121) (xy 109.145893 -265.565844)
			(xy 109.103877 -265.59637) (xy 109.057603 -265.619948) (xy 109.00821 -265.635996) (xy 108.956915 -265.644121)
			(xy 108.904981 -265.644121) (xy 108.853686 -265.635996) (xy 108.804293 -265.619948) (xy 108.758019 -265.59637)
			(xy 108.716003 -265.565844) (xy 108.67928 -265.529121) (xy 108.648754 -265.487105) (xy 108.625176 -265.440831)
			(xy 108.609128 -265.391438) (xy 108.601003 -265.340143) (xy 107.381293 -265.340143) (xy 107.373168 -265.391438)
			(xy 107.35712 -265.440831) (xy 107.333542 -265.487105) (xy 107.303016 -265.529121) (xy 107.266293 -265.565844)
			(xy 107.224277 -265.59637) (xy 107.178003 -265.619948) (xy 107.12861 -265.635996) (xy 107.077315 -265.644121)
			(xy 107.025381 -265.644121) (xy 106.974086 -265.635996) (xy 106.924693 -265.619948) (xy 106.878419 -265.59637)
			(xy 106.836403 -265.565844) (xy 106.79968 -265.529121) (xy 106.769154 -265.487105) (xy 106.745576 -265.440831)
			(xy 106.729528 -265.391438) (xy 106.721403 -265.340143) (xy 106.441493 -265.340143) (xy 106.433368 -265.391438)
			(xy 106.41732 -265.440831) (xy 106.393742 -265.487105) (xy 106.363216 -265.529121) (xy 106.326493 -265.565844)
			(xy 106.284477 -265.59637) (xy 106.238203 -265.619948) (xy 106.18881 -265.635996) (xy 106.137515 -265.644121)
			(xy 106.085581 -265.644121) (xy 106.034286 -265.635996) (xy 105.984893 -265.619948) (xy 105.938619 -265.59637)
			(xy 105.896603 -265.565844) (xy 105.85988 -265.529121) (xy 105.829354 -265.487105) (xy 105.805776 -265.440831)
			(xy 105.789728 -265.391438) (xy 105.781603 -265.340143) (xy 105.501693 -265.340143) (xy 105.493568 -265.391438)
			(xy 105.47752 -265.440831) (xy 105.453942 -265.487105) (xy 105.423416 -265.529121) (xy 105.386693 -265.565844)
			(xy 105.344677 -265.59637) (xy 105.298403 -265.619948) (xy 105.24901 -265.635996) (xy 105.197715 -265.644121)
			(xy 105.145781 -265.644121) (xy 105.094486 -265.635996) (xy 105.045093 -265.619948) (xy 104.998819 -265.59637)
			(xy 104.956803 -265.565844) (xy 104.92008 -265.529121) (xy 104.889554 -265.487105) (xy 104.865976 -265.440831)
			(xy 104.849928 -265.391438) (xy 104.841803 -265.340143) (xy 104.561869 -265.340143) (xy 104.561869 -265.340167)
			(xy 104.553745 -265.391461) (xy 104.537699 -265.440853) (xy 104.514123 -265.487127) (xy 104.4836 -265.529144)
			(xy 104.44688 -265.565869) (xy 104.404868 -265.596398) (xy 104.358597 -265.61998) (xy 104.309208 -265.636034)
			(xy 104.257915 -265.644165) (xy 104.231948 -265.64463) (xy 104.210161 -265.644282) (xy 104.166965 -265.638549)
			(xy 104.145842 -265.6332) (xy 104.132867 -265.630114) (xy 104.106206 -265.630078) (xy 104.080445 -265.636947)
			(xy 104.057341 -265.650252) (xy 104.038471 -265.669087) (xy 104.025121 -265.692165) (xy 104.018203 -265.717914)
			(xy 104.017826 -265.731244) (xy 104.017826 -265.919204) (xy 104.033357 -265.938996) (xy 104.058875 -265.98235)
			(xy 104.077534 -266.029068) (xy 104.088902 -266.078074) (xy 104.092717 -266.128236) (xy 104.090736 -266.154213)
			(xy 104.371649 -266.154213) (xy 104.371649 -266.102279) (xy 104.379774 -266.050984) (xy 104.395822 -266.001591)
			(xy 104.4194 -265.955317) (xy 104.449926 -265.913301) (xy 104.486649 -265.876578) (xy 104.528665 -265.846052)
			(xy 104.574939 -265.822474) (xy 104.624332 -265.806426) (xy 104.675627 -265.798301) (xy 104.727561 -265.798301)
			(xy 104.778856 -265.806426) (xy 104.828249 -265.822474) (xy 104.874523 -265.846052) (xy 104.916539 -265.876578)
			(xy 104.953262 -265.913301) (xy 104.983788 -265.955317) (xy 105.007366 -266.001591) (xy 105.023414 -266.050984)
			(xy 105.031539 -266.102279) (xy 105.032048 -266.128246) (xy 105.031539 -266.154213) (xy 105.311449 -266.154213)
			(xy 105.311449 -266.102279) (xy 105.319574 -266.050984) (xy 105.335622 -266.001591) (xy 105.3592 -265.955317)
			(xy 105.389726 -265.913301) (xy 105.426449 -265.876578) (xy 105.468465 -265.846052) (xy 105.514739 -265.822474)
			(xy 105.564132 -265.806426) (xy 105.615427 -265.798301) (xy 105.667361 -265.798301) (xy 105.718656 -265.806426)
			(xy 105.768049 -265.822474) (xy 105.814323 -265.846052) (xy 105.856339 -265.876578) (xy 105.893062 -265.913301)
			(xy 105.923588 -265.955317) (xy 105.947166 -266.001591) (xy 105.963214 -266.050984) (xy 105.971339 -266.102279)
			(xy 105.971848 -266.128246) (xy 105.971339 -266.154213) (xy 106.251249 -266.154213) (xy 106.251249 -266.102279)
			(xy 106.259374 -266.050984) (xy 106.275422 -266.001591) (xy 106.299 -265.955317) (xy 106.329526 -265.913301)
			(xy 106.366249 -265.876578) (xy 106.408265 -265.846052) (xy 106.454539 -265.822474) (xy 106.503932 -265.806426)
			(xy 106.555227 -265.798301) (xy 106.607161 -265.798301) (xy 106.658456 -265.806426) (xy 106.707849 -265.822474)
			(xy 106.754123 -265.846052) (xy 106.796139 -265.876578) (xy 106.832862 -265.913301) (xy 106.863388 -265.955317)
			(xy 106.886966 -266.001591) (xy 106.903014 -266.050984) (xy 106.911139 -266.102279) (xy 106.911648 -266.128246)
			(xy 106.911139 -266.154213) (xy 107.191049 -266.154213) (xy 107.191049 -266.102279) (xy 107.199174 -266.050984)
			(xy 107.215222 -266.001591) (xy 107.2388 -265.955317) (xy 107.269326 -265.913301) (xy 107.306049 -265.876578)
			(xy 107.348065 -265.846052) (xy 107.394339 -265.822474) (xy 107.443732 -265.806426) (xy 107.495027 -265.798301)
			(xy 107.546961 -265.798301) (xy 107.598256 -265.806426) (xy 107.647649 -265.822474) (xy 107.693923 -265.846052)
			(xy 107.735939 -265.876578) (xy 107.772662 -265.913301) (xy 107.803188 -265.955317) (xy 107.826766 -266.001591)
			(xy 107.842814 -266.050984) (xy 107.850939 -266.102279) (xy 107.851448 -266.128246) (xy 107.850939 -266.154213)
			(xy 108.130849 -266.154213) (xy 108.130849 -266.102279) (xy 108.138974 -266.050984) (xy 108.155022 -266.001591)
			(xy 108.1786 -265.955317) (xy 108.209126 -265.913301) (xy 108.245849 -265.876578) (xy 108.287865 -265.846052)
			(xy 108.334139 -265.822474) (xy 108.383532 -265.806426) (xy 108.434827 -265.798301) (xy 108.486761 -265.798301)
			(xy 108.538056 -265.806426) (xy 108.587449 -265.822474) (xy 108.633723 -265.846052) (xy 108.675739 -265.876578)
			(xy 108.712462 -265.913301) (xy 108.742988 -265.955317) (xy 108.766566 -266.001591) (xy 108.782614 -266.050984)
			(xy 108.790739 -266.102279) (xy 108.791248 -266.128246) (xy 108.790739 -266.154213) (xy 109.070903 -266.154213)
			(xy 109.070903 -266.102279) (xy 109.079028 -266.050984) (xy 109.095076 -266.001591) (xy 109.118654 -265.955317)
			(xy 109.14918 -265.913301) (xy 109.185903 -265.876578) (xy 109.227919 -265.846052) (xy 109.274193 -265.822474)
			(xy 109.323586 -265.806426) (xy 109.374881 -265.798301) (xy 109.426815 -265.798301) (xy 109.47811 -265.806426)
			(xy 109.527503 -265.822474) (xy 109.573777 -265.846052) (xy 109.615793 -265.876578) (xy 109.652516 -265.913301)
			(xy 109.683042 -265.955317) (xy 109.70662 -266.001591) (xy 109.722668 -266.050984) (xy 109.730793 -266.102279)
			(xy 109.731302 -266.128246) (xy 109.730793 -266.154213) (xy 110.010703 -266.154213) (xy 110.010703 -266.102279)
			(xy 110.018828 -266.050984) (xy 110.034876 -266.001591) (xy 110.058454 -265.955317) (xy 110.08898 -265.913301)
			(xy 110.125703 -265.876578) (xy 110.167719 -265.846052) (xy 110.213993 -265.822474) (xy 110.263386 -265.806426)
			(xy 110.314681 -265.798301) (xy 110.366615 -265.798301) (xy 110.41791 -265.806426) (xy 110.467303 -265.822474)
			(xy 110.513577 -265.846052) (xy 110.555593 -265.876578) (xy 110.592316 -265.913301) (xy 110.622842 -265.955317)
			(xy 110.64642 -266.001591) (xy 110.662468 -266.050984) (xy 110.670593 -266.102279) (xy 110.671102 -266.128246)
			(xy 110.670593 -266.154213) (xy 110.950503 -266.154213) (xy 110.950503 -266.102279) (xy 110.958628 -266.050984)
			(xy 110.974676 -266.001591) (xy 110.998254 -265.955317) (xy 111.02878 -265.913301) (xy 111.065503 -265.876578)
			(xy 111.107519 -265.846052) (xy 111.153793 -265.822474) (xy 111.203186 -265.806426) (xy 111.254481 -265.798301)
			(xy 111.306415 -265.798301) (xy 111.35771 -265.806426) (xy 111.407103 -265.822474) (xy 111.453377 -265.846052)
			(xy 111.495393 -265.876578) (xy 111.532116 -265.913301) (xy 111.562642 -265.955317) (xy 111.58622 -266.001591)
			(xy 111.602268 -266.050984) (xy 111.610393 -266.102279) (xy 111.610902 -266.128246) (xy 111.610393 -266.154213)
			(xy 111.890303 -266.154213) (xy 111.890303 -266.102279) (xy 111.898428 -266.050984) (xy 111.914476 -266.001591)
			(xy 111.938054 -265.955317) (xy 111.96858 -265.913301) (xy 112.005303 -265.876578) (xy 112.047319 -265.846052)
			(xy 112.093593 -265.822474) (xy 112.142986 -265.806426) (xy 112.194281 -265.798301) (xy 112.246215 -265.798301)
			(xy 112.29751 -265.806426) (xy 112.346903 -265.822474) (xy 112.393177 -265.846052) (xy 112.435193 -265.876578)
			(xy 112.471916 -265.913301) (xy 112.502442 -265.955317) (xy 112.52602 -266.001591) (xy 112.542068 -266.050984)
			(xy 112.550193 -266.102279) (xy 112.550702 -266.128246) (xy 112.550193 -266.154213) (xy 112.829595 -266.154213)
			(xy 112.829595 -266.102279) (xy 112.83772 -266.050984) (xy 112.853768 -266.001591) (xy 112.877346 -265.955317)
			(xy 112.907872 -265.913301) (xy 112.944595 -265.876578) (xy 112.986611 -265.846052) (xy 113.032885 -265.822474)
			(xy 113.082278 -265.806426) (xy 113.133573 -265.798301) (xy 113.185507 -265.798301) (xy 113.236802 -265.806426)
			(xy 113.286195 -265.822474) (xy 113.332469 -265.846052) (xy 113.374485 -265.876578) (xy 113.411208 -265.913301)
			(xy 113.441734 -265.955317) (xy 113.465312 -266.001591) (xy 113.48136 -266.050984) (xy 113.489485 -266.102279)
			(xy 113.489994 -266.128246) (xy 113.489485 -266.154213) (xy 113.769649 -266.154213) (xy 113.769649 -266.102279)
			(xy 113.777774 -266.050984) (xy 113.793822 -266.001591) (xy 113.8174 -265.955317) (xy 113.847926 -265.913301)
			(xy 113.884649 -265.876578) (xy 113.926665 -265.846052) (xy 113.972939 -265.822474) (xy 114.022332 -265.806426)
			(xy 114.073627 -265.798301) (xy 114.125561 -265.798301) (xy 114.176856 -265.806426) (xy 114.226249 -265.822474)
			(xy 114.272523 -265.846052) (xy 114.314539 -265.876578) (xy 114.351262 -265.913301) (xy 114.381788 -265.955317)
			(xy 114.405366 -266.001591) (xy 114.421414 -266.050984) (xy 114.429539 -266.102279) (xy 114.430048 -266.128246)
			(xy 114.429539 -266.154213) (xy 114.709449 -266.154213) (xy 114.709449 -266.102279) (xy 114.717574 -266.050984)
			(xy 114.733622 -266.001591) (xy 114.7572 -265.955317) (xy 114.787726 -265.913301) (xy 114.824449 -265.876578)
			(xy 114.866465 -265.846052) (xy 114.912739 -265.822474) (xy 114.962132 -265.806426) (xy 115.013427 -265.798301)
			(xy 115.065361 -265.798301) (xy 115.116656 -265.806426) (xy 115.166049 -265.822474) (xy 115.212323 -265.846052)
			(xy 115.254339 -265.876578) (xy 115.291062 -265.913301) (xy 115.321588 -265.955317) (xy 115.345166 -266.001591)
			(xy 115.361214 -266.050984) (xy 115.369339 -266.102279) (xy 115.369848 -266.128246) (xy 115.369339 -266.154213)
			(xy 115.649249 -266.154213) (xy 115.649249 -266.102279) (xy 115.657374 -266.050984) (xy 115.673422 -266.001591)
			(xy 115.697 -265.955317) (xy 115.727526 -265.913301) (xy 115.764249 -265.876578) (xy 115.806265 -265.846052)
			(xy 115.852539 -265.822474) (xy 115.901932 -265.806426) (xy 115.953227 -265.798301) (xy 116.005161 -265.798301)
			(xy 116.056456 -265.806426) (xy 116.105849 -265.822474) (xy 116.152123 -265.846052) (xy 116.194139 -265.876578)
			(xy 116.230862 -265.913301) (xy 116.261388 -265.955317) (xy 116.284966 -266.001591) (xy 116.301014 -266.050984)
			(xy 116.309139 -266.102279) (xy 116.309648 -266.128246) (xy 116.309139 -266.154213) (xy 116.309099 -266.154467)
			(xy 116.589049 -266.154467) (xy 116.589049 -266.102533) (xy 116.597174 -266.051238) (xy 116.613222 -266.001845)
			(xy 116.6368 -265.955571) (xy 116.667326 -265.913555) (xy 116.704049 -265.876832) (xy 116.746065 -265.846306)
			(xy 116.792339 -265.822728) (xy 116.841732 -265.80668) (xy 116.893027 -265.798555) (xy 116.944961 -265.798555)
			(xy 116.996256 -265.80668) (xy 117.045649 -265.822728) (xy 117.091923 -265.846306) (xy 117.133939 -265.876832)
			(xy 117.170662 -265.913555) (xy 117.201188 -265.955571) (xy 117.224766 -266.001845) (xy 117.240814 -266.051238)
			(xy 117.248939 -266.102533) (xy 117.249448 -266.1285) (xy 117.248944 -266.154213) (xy 117.528849 -266.154213)
			(xy 117.528849 -266.102279) (xy 117.536974 -266.050984) (xy 117.553022 -266.001591) (xy 117.5766 -265.955317)
			(xy 117.607126 -265.913301) (xy 117.643849 -265.876578) (xy 117.685865 -265.846052) (xy 117.732139 -265.822474)
			(xy 117.781532 -265.806426) (xy 117.832827 -265.798301) (xy 117.884761 -265.798301) (xy 117.936056 -265.806426)
			(xy 117.985449 -265.822474) (xy 118.031723 -265.846052) (xy 118.073739 -265.876578) (xy 118.110462 -265.913301)
			(xy 118.140988 -265.955317) (xy 118.164566 -266.001591) (xy 118.180614 -266.050984) (xy 118.188739 -266.102279)
			(xy 118.189248 -266.128246) (xy 118.188739 -266.154213) (xy 118.188699 -266.154467) (xy 118.468649 -266.154467)
			(xy 118.468649 -266.102533) (xy 118.476774 -266.051238) (xy 118.492822 -266.001845) (xy 118.5164 -265.955571)
			(xy 118.546926 -265.913555) (xy 118.583649 -265.876832) (xy 118.625665 -265.846306) (xy 118.671939 -265.822728)
			(xy 118.721332 -265.80668) (xy 118.772627 -265.798555) (xy 118.824561 -265.798555) (xy 118.875856 -265.80668)
			(xy 118.925249 -265.822728) (xy 118.971523 -265.846306) (xy 119.013539 -265.876832) (xy 119.050262 -265.913555)
			(xy 119.080788 -265.955571) (xy 119.104366 -266.001845) (xy 119.120414 -266.051238) (xy 119.128539 -266.102533)
			(xy 119.129048 -266.1285) (xy 119.128544 -266.154213) (xy 119.408449 -266.154213) (xy 119.408449 -266.102279)
			(xy 119.416574 -266.050984) (xy 119.432622 -266.001591) (xy 119.4562 -265.955317) (xy 119.486726 -265.913301)
			(xy 119.523449 -265.876578) (xy 119.565465 -265.846052) (xy 119.611739 -265.822474) (xy 119.661132 -265.806426)
			(xy 119.712427 -265.798301) (xy 119.764361 -265.798301) (xy 119.815656 -265.806426) (xy 119.865049 -265.822474)
			(xy 119.911323 -265.846052) (xy 119.953339 -265.876578) (xy 119.990062 -265.913301) (xy 120.020588 -265.955317)
			(xy 120.044166 -266.001591) (xy 120.060214 -266.050984) (xy 120.068339 -266.102279) (xy 120.068848 -266.128246)
			(xy 120.068339 -266.154213) (xy 120.348249 -266.154213) (xy 120.348249 -266.102279) (xy 120.356374 -266.050984)
			(xy 120.372422 -266.001591) (xy 120.396 -265.955317) (xy 120.426526 -265.913301) (xy 120.463249 -265.876578)
			(xy 120.505265 -265.846052) (xy 120.551539 -265.822474) (xy 120.600932 -265.806426) (xy 120.652227 -265.798301)
			(xy 120.704161 -265.798301) (xy 120.755456 -265.806426) (xy 120.804849 -265.822474) (xy 120.851123 -265.846052)
			(xy 120.893139 -265.876578) (xy 120.929862 -265.913301) (xy 120.960388 -265.955317) (xy 120.983966 -266.001591)
			(xy 121.000014 -266.050984) (xy 121.008139 -266.102279) (xy 121.008648 -266.128246) (xy 121.008139 -266.154213)
			(xy 122.227849 -266.154213) (xy 122.227849 -266.102279) (xy 122.235974 -266.050984) (xy 122.252022 -266.001591)
			(xy 122.2756 -265.955317) (xy 122.306126 -265.913301) (xy 122.342849 -265.876578) (xy 122.384865 -265.846052)
			(xy 122.431139 -265.822474) (xy 122.480532 -265.806426) (xy 122.531827 -265.798301) (xy 122.583761 -265.798301)
			(xy 122.635056 -265.806426) (xy 122.684449 -265.822474) (xy 122.730723 -265.846052) (xy 122.772739 -265.876578)
			(xy 122.809462 -265.913301) (xy 122.839988 -265.955317) (xy 122.863566 -266.001591) (xy 122.879614 -266.050984)
			(xy 122.887739 -266.102279) (xy 122.888248 -266.128246) (xy 122.887739 -266.154213) (xy 123.167649 -266.154213)
			(xy 123.167649 -266.102279) (xy 123.175774 -266.050984) (xy 123.191822 -266.001591) (xy 123.2154 -265.955317)
			(xy 123.245926 -265.913301) (xy 123.282649 -265.876578) (xy 123.324665 -265.846052) (xy 123.370939 -265.822474)
			(xy 123.420332 -265.806426) (xy 123.471627 -265.798301) (xy 123.523561 -265.798301) (xy 123.574856 -265.806426)
			(xy 123.624249 -265.822474) (xy 123.670523 -265.846052) (xy 123.712539 -265.876578) (xy 123.749262 -265.913301)
			(xy 123.779788 -265.955317) (xy 123.803366 -266.001591) (xy 123.819414 -266.050984) (xy 123.827539 -266.102279)
			(xy 123.828048 -266.128246) (xy 123.827539 -266.154213) (xy 123.819414 -266.205508) (xy 123.803366 -266.254901)
			(xy 123.779788 -266.301175) (xy 123.749262 -266.343191) (xy 123.712539 -266.379914) (xy 123.670523 -266.41044)
			(xy 123.624249 -266.434018) (xy 123.574856 -266.450066) (xy 123.523561 -266.458191) (xy 123.471627 -266.458191)
			(xy 123.420332 -266.450066) (xy 123.370939 -266.434018) (xy 123.324665 -266.41044) (xy 123.282649 -266.379914)
			(xy 123.245926 -266.343191) (xy 123.2154 -266.301175) (xy 123.191822 -266.254901) (xy 123.175774 -266.205508)
			(xy 123.167649 -266.154213) (xy 122.887739 -266.154213) (xy 122.879614 -266.205508) (xy 122.863566 -266.254901)
			(xy 122.839988 -266.301175) (xy 122.809462 -266.343191) (xy 122.772739 -266.379914) (xy 122.730723 -266.41044)
			(xy 122.684449 -266.434018) (xy 122.635056 -266.450066) (xy 122.583761 -266.458191) (xy 122.531827 -266.458191)
			(xy 122.480532 -266.450066) (xy 122.431139 -266.434018) (xy 122.384865 -266.41044) (xy 122.342849 -266.379914)
			(xy 122.306126 -266.343191) (xy 122.2756 -266.301175) (xy 122.252022 -266.254901) (xy 122.235974 -266.205508)
			(xy 122.227849 -266.154213) (xy 121.008139 -266.154213) (xy 121.000014 -266.205508) (xy 120.983966 -266.254901)
			(xy 120.960388 -266.301175) (xy 120.929862 -266.343191) (xy 120.893139 -266.379914) (xy 120.851123 -266.41044)
			(xy 120.804849 -266.434018) (xy 120.755456 -266.450066) (xy 120.704161 -266.458191) (xy 120.652227 -266.458191)
			(xy 120.600932 -266.450066) (xy 120.551539 -266.434018) (xy 120.505265 -266.41044) (xy 120.463249 -266.379914)
			(xy 120.426526 -266.343191) (xy 120.396 -266.301175) (xy 120.372422 -266.254901) (xy 120.356374 -266.205508)
			(xy 120.348249 -266.154213) (xy 120.068339 -266.154213) (xy 120.060214 -266.205508) (xy 120.044166 -266.254901)
			(xy 120.020588 -266.301175) (xy 119.990062 -266.343191) (xy 119.953339 -266.379914) (xy 119.911323 -266.41044)
			(xy 119.865049 -266.434018) (xy 119.815656 -266.450066) (xy 119.764361 -266.458191) (xy 119.712427 -266.458191)
			(xy 119.661132 -266.450066) (xy 119.611739 -266.434018) (xy 119.565465 -266.41044) (xy 119.523449 -266.379914)
			(xy 119.486726 -266.343191) (xy 119.4562 -266.301175) (xy 119.432622 -266.254901) (xy 119.416574 -266.205508)
			(xy 119.408449 -266.154213) (xy 119.128544 -266.154213) (xy 119.128539 -266.154467) (xy 119.120414 -266.205762)
			(xy 119.104366 -266.255155) (xy 119.080788 -266.301429) (xy 119.050262 -266.343445) (xy 119.013539 -266.380168)
			(xy 118.971523 -266.410694) (xy 118.925249 -266.434272) (xy 118.875856 -266.45032) (xy 118.824561 -266.458445)
			(xy 118.772627 -266.458445) (xy 118.721332 -266.45032) (xy 118.671939 -266.434272) (xy 118.625665 -266.410694)
			(xy 118.583649 -266.380168) (xy 118.546926 -266.343445) (xy 118.5164 -266.301429) (xy 118.492822 -266.255155)
			(xy 118.476774 -266.205762) (xy 118.468649 -266.154467) (xy 118.188699 -266.154467) (xy 118.180614 -266.205508)
			(xy 118.164566 -266.254901) (xy 118.140988 -266.301175) (xy 118.110462 -266.343191) (xy 118.073739 -266.379914)
			(xy 118.031723 -266.41044) (xy 117.985449 -266.434018) (xy 117.936056 -266.450066) (xy 117.884761 -266.458191)
			(xy 117.832827 -266.458191) (xy 117.781532 -266.450066) (xy 117.732139 -266.434018) (xy 117.685865 -266.41044)
			(xy 117.643849 -266.379914) (xy 117.607126 -266.343191) (xy 117.5766 -266.301175) (xy 117.553022 -266.254901)
			(xy 117.536974 -266.205508) (xy 117.528849 -266.154213) (xy 117.248944 -266.154213) (xy 117.248939 -266.154467)
			(xy 117.240814 -266.205762) (xy 117.224766 -266.255155) (xy 117.201188 -266.301429) (xy 117.170662 -266.343445)
			(xy 117.133939 -266.380168) (xy 117.091923 -266.410694) (xy 117.045649 -266.434272) (xy 116.996256 -266.45032)
			(xy 116.944961 -266.458445) (xy 116.893027 -266.458445) (xy 116.841732 -266.45032) (xy 116.792339 -266.434272)
			(xy 116.746065 -266.410694) (xy 116.704049 -266.380168) (xy 116.667326 -266.343445) (xy 116.6368 -266.301429)
			(xy 116.613222 -266.255155) (xy 116.597174 -266.205762) (xy 116.589049 -266.154467) (xy 116.309099 -266.154467)
			(xy 116.301014 -266.205508) (xy 116.284966 -266.254901) (xy 116.261388 -266.301175) (xy 116.230862 -266.343191)
			(xy 116.194139 -266.379914) (xy 116.152123 -266.41044) (xy 116.105849 -266.434018) (xy 116.056456 -266.450066)
			(xy 116.005161 -266.458191) (xy 115.953227 -266.458191) (xy 115.901932 -266.450066) (xy 115.852539 -266.434018)
			(xy 115.806265 -266.41044) (xy 115.764249 -266.379914) (xy 115.727526 -266.343191) (xy 115.697 -266.301175)
			(xy 115.673422 -266.254901) (xy 115.657374 -266.205508) (xy 115.649249 -266.154213) (xy 115.369339 -266.154213)
			(xy 115.361214 -266.205508) (xy 115.345166 -266.254901) (xy 115.321588 -266.301175) (xy 115.291062 -266.343191)
			(xy 115.254339 -266.379914) (xy 115.212323 -266.41044) (xy 115.166049 -266.434018) (xy 115.116656 -266.450066)
			(xy 115.065361 -266.458191) (xy 115.013427 -266.458191) (xy 114.962132 -266.450066) (xy 114.912739 -266.434018)
			(xy 114.866465 -266.41044) (xy 114.824449 -266.379914) (xy 114.787726 -266.343191) (xy 114.7572 -266.301175)
			(xy 114.733622 -266.254901) (xy 114.717574 -266.205508) (xy 114.709449 -266.154213) (xy 114.429539 -266.154213)
			(xy 114.421414 -266.205508) (xy 114.405366 -266.254901) (xy 114.381788 -266.301175) (xy 114.351262 -266.343191)
			(xy 114.314539 -266.379914) (xy 114.272523 -266.41044) (xy 114.226249 -266.434018) (xy 114.176856 -266.450066)
			(xy 114.125561 -266.458191) (xy 114.073627 -266.458191) (xy 114.022332 -266.450066) (xy 113.972939 -266.434018)
			(xy 113.926665 -266.41044) (xy 113.884649 -266.379914) (xy 113.847926 -266.343191) (xy 113.8174 -266.301175)
			(xy 113.793822 -266.254901) (xy 113.777774 -266.205508) (xy 113.769649 -266.154213) (xy 113.489485 -266.154213)
			(xy 113.48136 -266.205508) (xy 113.465312 -266.254901) (xy 113.441734 -266.301175) (xy 113.411208 -266.343191)
			(xy 113.374485 -266.379914) (xy 113.332469 -266.41044) (xy 113.286195 -266.434018) (xy 113.236802 -266.450066)
			(xy 113.185507 -266.458191) (xy 113.133573 -266.458191) (xy 113.082278 -266.450066) (xy 113.032885 -266.434018)
			(xy 112.986611 -266.41044) (xy 112.944595 -266.379914) (xy 112.907872 -266.343191) (xy 112.877346 -266.301175)
			(xy 112.853768 -266.254901) (xy 112.83772 -266.205508) (xy 112.829595 -266.154213) (xy 112.550193 -266.154213)
			(xy 112.542068 -266.205508) (xy 112.52602 -266.254901) (xy 112.502442 -266.301175) (xy 112.471916 -266.343191)
			(xy 112.435193 -266.379914) (xy 112.393177 -266.41044) (xy 112.346903 -266.434018) (xy 112.29751 -266.450066)
			(xy 112.246215 -266.458191) (xy 112.194281 -266.458191) (xy 112.142986 -266.450066) (xy 112.093593 -266.434018)
			(xy 112.047319 -266.41044) (xy 112.005303 -266.379914) (xy 111.96858 -266.343191) (xy 111.938054 -266.301175)
			(xy 111.914476 -266.254901) (xy 111.898428 -266.205508) (xy 111.890303 -266.154213) (xy 111.610393 -266.154213)
			(xy 111.602268 -266.205508) (xy 111.58622 -266.254901) (xy 111.562642 -266.301175) (xy 111.532116 -266.343191)
			(xy 111.495393 -266.379914) (xy 111.453377 -266.41044) (xy 111.407103 -266.434018) (xy 111.35771 -266.450066)
			(xy 111.306415 -266.458191) (xy 111.254481 -266.458191) (xy 111.203186 -266.450066) (xy 111.153793 -266.434018)
			(xy 111.107519 -266.41044) (xy 111.065503 -266.379914) (xy 111.02878 -266.343191) (xy 110.998254 -266.301175)
			(xy 110.974676 -266.254901) (xy 110.958628 -266.205508) (xy 110.950503 -266.154213) (xy 110.670593 -266.154213)
			(xy 110.662468 -266.205508) (xy 110.64642 -266.254901) (xy 110.622842 -266.301175) (xy 110.592316 -266.343191)
			(xy 110.555593 -266.379914) (xy 110.513577 -266.41044) (xy 110.467303 -266.434018) (xy 110.41791 -266.450066)
			(xy 110.366615 -266.458191) (xy 110.314681 -266.458191) (xy 110.263386 -266.450066) (xy 110.213993 -266.434018)
			(xy 110.167719 -266.41044) (xy 110.125703 -266.379914) (xy 110.08898 -266.343191) (xy 110.058454 -266.301175)
			(xy 110.034876 -266.254901) (xy 110.018828 -266.205508) (xy 110.010703 -266.154213) (xy 109.730793 -266.154213)
			(xy 109.722668 -266.205508) (xy 109.70662 -266.254901) (xy 109.683042 -266.301175) (xy 109.652516 -266.343191)
			(xy 109.615793 -266.379914) (xy 109.573777 -266.41044) (xy 109.527503 -266.434018) (xy 109.47811 -266.450066)
			(xy 109.426815 -266.458191) (xy 109.374881 -266.458191) (xy 109.323586 -266.450066) (xy 109.274193 -266.434018)
			(xy 109.227919 -266.41044) (xy 109.185903 -266.379914) (xy 109.14918 -266.343191) (xy 109.118654 -266.301175)
			(xy 109.095076 -266.254901) (xy 109.079028 -266.205508) (xy 109.070903 -266.154213) (xy 108.790739 -266.154213)
			(xy 108.782614 -266.205508) (xy 108.766566 -266.254901) (xy 108.742988 -266.301175) (xy 108.712462 -266.343191)
			(xy 108.675739 -266.379914) (xy 108.633723 -266.41044) (xy 108.587449 -266.434018) (xy 108.538056 -266.450066)
			(xy 108.486761 -266.458191) (xy 108.434827 -266.458191) (xy 108.383532 -266.450066) (xy 108.334139 -266.434018)
			(xy 108.287865 -266.41044) (xy 108.245849 -266.379914) (xy 108.209126 -266.343191) (xy 108.1786 -266.301175)
			(xy 108.155022 -266.254901) (xy 108.138974 -266.205508) (xy 108.130849 -266.154213) (xy 107.850939 -266.154213)
			(xy 107.842814 -266.205508) (xy 107.826766 -266.254901) (xy 107.803188 -266.301175) (xy 107.772662 -266.343191)
			(xy 107.735939 -266.379914) (xy 107.693923 -266.41044) (xy 107.647649 -266.434018) (xy 107.598256 -266.450066)
			(xy 107.546961 -266.458191) (xy 107.495027 -266.458191) (xy 107.443732 -266.450066) (xy 107.394339 -266.434018)
			(xy 107.348065 -266.41044) (xy 107.306049 -266.379914) (xy 107.269326 -266.343191) (xy 107.2388 -266.301175)
			(xy 107.215222 -266.254901) (xy 107.199174 -266.205508) (xy 107.191049 -266.154213) (xy 106.911139 -266.154213)
			(xy 106.903014 -266.205508) (xy 106.886966 -266.254901) (xy 106.863388 -266.301175) (xy 106.832862 -266.343191)
			(xy 106.796139 -266.379914) (xy 106.754123 -266.41044) (xy 106.707849 -266.434018) (xy 106.658456 -266.450066)
			(xy 106.607161 -266.458191) (xy 106.555227 -266.458191) (xy 106.503932 -266.450066) (xy 106.454539 -266.434018)
			(xy 106.408265 -266.41044) (xy 106.366249 -266.379914) (xy 106.329526 -266.343191) (xy 106.299 -266.301175)
			(xy 106.275422 -266.254901) (xy 106.259374 -266.205508) (xy 106.251249 -266.154213) (xy 105.971339 -266.154213)
			(xy 105.963214 -266.205508) (xy 105.947166 -266.254901) (xy 105.923588 -266.301175) (xy 105.893062 -266.343191)
			(xy 105.856339 -266.379914) (xy 105.814323 -266.41044) (xy 105.768049 -266.434018) (xy 105.718656 -266.450066)
			(xy 105.667361 -266.458191) (xy 105.615427 -266.458191) (xy 105.564132 -266.450066) (xy 105.514739 -266.434018)
			(xy 105.468465 -266.41044) (xy 105.426449 -266.379914) (xy 105.389726 -266.343191) (xy 105.3592 -266.301175)
			(xy 105.335622 -266.254901) (xy 105.319574 -266.205508) (xy 105.311449 -266.154213) (xy 105.031539 -266.154213)
			(xy 105.023414 -266.205508) (xy 105.007366 -266.254901) (xy 104.983788 -266.301175) (xy 104.953262 -266.343191)
			(xy 104.916539 -266.379914) (xy 104.874523 -266.41044) (xy 104.828249 -266.434018) (xy 104.778856 -266.450066)
			(xy 104.727561 -266.458191) (xy 104.675627 -266.458191) (xy 104.624332 -266.450066) (xy 104.574939 -266.434018)
			(xy 104.528665 -266.41044) (xy 104.486649 -266.379914) (xy 104.449926 -266.343191) (xy 104.4194 -266.301175)
			(xy 104.395822 -266.254901) (xy 104.379774 -266.205508) (xy 104.371649 -266.154213) (xy 104.090736 -266.154213)
			(xy 104.088891 -266.178397) (xy 104.077512 -266.2274) (xy 104.058844 -266.274114) (xy 104.033316 -266.317463)
			(xy 104.017826 -266.337288) (xy 104.017826 -266.48918) (xy 104.149398 -266.620752) (xy 104.175306 -266.61618)
			(xy 104.189291 -266.613904) (xy 104.217525 -266.611483) (xy 104.231694 -266.611354) (xy 104.257663 -266.611836)
			(xy 104.308963 -266.619961) (xy 104.35836 -266.63601) (xy 104.404637 -266.65959) (xy 104.446657 -266.690118)
			(xy 104.483383 -266.726845) (xy 104.513911 -266.768864) (xy 104.537491 -266.815142) (xy 104.55354 -266.864539)
			(xy 104.561664 -266.915839) (xy 104.562148 -266.941808) (xy 104.561997 -266.955976) (xy 104.559582 -266.984209)
			(xy 104.557322 -266.998196) (xy 104.55275 -267.024104) (xy 104.820466 -267.29182) (xy 104.98582 -267.29182)
			(xy 104.98582 -267.216382) (xy 104.966516 -267.201142) (xy 104.947267 -267.185393) (xy 104.913274 -267.149093)
			(xy 104.885112 -267.108102) (xy 104.863421 -267.063349) (xy 104.848692 -267.015848) (xy 104.841257 -266.966674)
			(xy 104.840786 -266.941808) (xy 104.841295 -266.915841) (xy 104.84942 -266.864546) (xy 104.865468 -266.815153)
			(xy 104.889046 -266.768879) (xy 104.919572 -266.726863) (xy 104.956295 -266.69014) (xy 104.998311 -266.659614)
			(xy 105.044585 -266.636036) (xy 105.093978 -266.619988) (xy 105.145273 -266.611863) (xy 105.197207 -266.611863)
			(xy 105.248502 -266.619988) (xy 105.297895 -266.636036) (xy 105.344169 -266.659614) (xy 105.386185 -266.69014)
			(xy 105.422908 -266.726863) (xy 105.453434 -266.768879) (xy 105.477012 -266.815153) (xy 105.49306 -266.864546)
			(xy 105.501185 -266.915841) (xy 105.501694 -266.941808) (xy 105.501189 -266.967126) (xy 105.49343 -267.017165)
			(xy 105.47814 -267.065438) (xy 105.455675 -267.110819) (xy 105.441496 -267.1318) (xy 105.433894 -267.143441)
			(xy 105.424642 -267.169646) (xy 105.422803 -267.197376) (xy 105.428514 -267.224574) (xy 105.441351 -267.249222)
			(xy 105.460361 -267.269494) (xy 105.484136 -267.283884) (xy 105.510912 -267.291327) (xy 105.524808 -267.29182)
			(xy 105.757726 -267.29182) (xy 105.771633 -267.291428) (xy 105.798432 -267.28399) (xy 105.822228 -267.269593)
			(xy 105.841252 -267.249306) (xy 105.854092 -267.224635) (xy 105.859794 -267.197414) (xy 105.857934 -267.169664)
			(xy 105.84865 -267.143447) (xy 105.841038 -267.1318) (xy 105.826834 -267.110832) (xy 105.804341 -267.065457)
			(xy 105.789045 -267.017179) (xy 105.781305 -266.96713) (xy 105.78084 -266.941808) (xy 105.781349 -266.915841)
			(xy 105.789474 -266.864546) (xy 105.805522 -266.815153) (xy 105.8291 -266.768879) (xy 105.859626 -266.726863)
			(xy 105.896349 -266.69014) (xy 105.938365 -266.659614) (xy 105.984639 -266.636036) (xy 106.034032 -266.619988)
			(xy 106.085327 -266.611863) (xy 106.137261 -266.611863) (xy 106.188556 -266.619988) (xy 106.237949 -266.636036)
			(xy 106.284223 -266.659614) (xy 106.326239 -266.69014) (xy 106.362962 -266.726863) (xy 106.393488 -266.768879)
			(xy 106.417066 -266.815153) (xy 106.433114 -266.864546) (xy 106.441239 -266.915841) (xy 106.441748 -266.941808)
			(xy 106.441243 -266.967126) (xy 106.433483 -267.017164) (xy 106.418191 -267.065436) (xy 106.395724 -267.110816)
			(xy 106.38155 -267.1318) (xy 106.37395 -267.143443) (xy 106.364702 -267.169651) (xy 106.362866 -267.197383)
			(xy 106.368577 -267.224582) (xy 106.381412 -267.249232) (xy 106.400419 -267.269508) (xy 106.424191 -267.283906)
			(xy 106.450965 -267.291359) (xy 106.464862 -267.29182) (xy 106.69778 -267.29182) (xy 106.711692 -267.291433)
			(xy 106.738502 -267.284003) (xy 106.76231 -267.269608) (xy 106.781344 -267.249318) (xy 106.794191 -267.22464)
			(xy 106.799894 -267.19741) (xy 106.798032 -267.169652) (xy 106.78874 -267.143428) (xy 106.781092 -267.1318)
			(xy 106.76689 -267.110831) (xy 106.7444 -267.065456) (xy 106.729106 -267.017178) (xy 106.721368 -266.967129)
			(xy 106.720894 -266.941808) (xy 106.721403 -266.915841) (xy 106.729528 -266.864546) (xy 106.745576 -266.815153)
			(xy 106.769154 -266.768879) (xy 106.79968 -266.726863) (xy 106.836403 -266.69014) (xy 106.878419 -266.659614)
			(xy 106.924693 -266.636036) (xy 106.974086 -266.619988) (xy 107.025381 -266.611863) (xy 107.077315 -266.611863)
			(xy 107.12861 -266.619988) (xy 107.178003 -266.636036) (xy 107.224277 -266.659614) (xy 107.266293 -266.69014)
			(xy 107.303016 -266.726863) (xy 107.333542 -266.768879) (xy 107.35712 -266.815153) (xy 107.373168 -266.864546)
			(xy 107.381293 -266.915841) (xy 107.381802 -266.941808) (xy 107.381297 -266.967126) (xy 107.373538 -267.017165)
			(xy 107.358248 -267.065438) (xy 107.335784 -267.11082) (xy 107.321604 -267.1318) (xy 107.313962 -267.14342)
			(xy 107.304705 -267.169637) (xy 107.302865 -267.197378) (xy 107.308579 -267.224588) (xy 107.321421 -267.249246)
			(xy 107.340441 -267.269526) (xy 107.364226 -267.283921) (xy 107.391014 -267.291366) (xy 107.404916 -267.29182)
			(xy 107.63758 -267.29182) (xy 107.651492 -267.291433) (xy 107.678302 -267.284003) (xy 107.70211 -267.269608)
			(xy 107.721144 -267.249318) (xy 107.733991 -267.22464) (xy 107.739694 -267.19741) (xy 107.737832 -267.169652)
			(xy 107.72854 -267.143428) (xy 107.720892 -267.1318) (xy 107.70669 -267.110831) (xy 107.6842 -267.065456)
			(xy 107.668906 -267.017178) (xy 107.661168 -266.967129) (xy 107.660694 -266.941808) (xy 107.661203 -266.915841)
			(xy 107.669328 -266.864546) (xy 107.685376 -266.815153) (xy 107.708954 -266.768879) (xy 107.73948 -266.726863)
			(xy 107.776203 -266.69014) (xy 107.818219 -266.659614) (xy 107.864493 -266.636036) (xy 107.913886 -266.619988)
			(xy 107.965181 -266.611863) (xy 108.017115 -266.611863) (xy 108.06841 -266.619988) (xy 108.117803 -266.636036)
			(xy 108.164077 -266.659614) (xy 108.206093 -266.69014) (xy 108.242816 -266.726863) (xy 108.273342 -266.768879)
			(xy 108.29692 -266.815153) (xy 108.312968 -266.864546) (xy 108.321093 -266.915841) (xy 108.321602 -266.941808)
			(xy 108.321097 -266.967126) (xy 108.313338 -267.017165) (xy 108.298048 -267.065438) (xy 108.275584 -267.11082)
			(xy 108.261404 -267.1318) (xy 108.253762 -267.14342) (xy 108.244505 -267.169637) (xy 108.242665 -267.197378)
			(xy 108.248379 -267.224588) (xy 108.261221 -267.249246) (xy 108.280241 -267.269526) (xy 108.304026 -267.283921)
			(xy 108.330814 -267.291366) (xy 108.344716 -267.29182) (xy 108.57738 -267.29182) (xy 108.591292 -267.291433)
			(xy 108.618102 -267.284003) (xy 108.64191 -267.269608) (xy 108.660944 -267.249318) (xy 108.673791 -267.22464)
			(xy 108.679494 -267.19741) (xy 108.677632 -267.169652) (xy 108.66834 -267.143428) (xy 108.660692 -267.1318)
			(xy 108.64649 -267.110831) (xy 108.624 -267.065456) (xy 108.608706 -267.017178) (xy 108.600968 -266.967129)
			(xy 108.600494 -266.941808) (xy 108.601003 -266.915841) (xy 108.609128 -266.864546) (xy 108.625176 -266.815153)
			(xy 108.648754 -266.768879) (xy 108.67928 -266.726863) (xy 108.716003 -266.69014) (xy 108.758019 -266.659614)
			(xy 108.804293 -266.636036) (xy 108.853686 -266.619988) (xy 108.904981 -266.611863) (xy 108.956915 -266.611863)
			(xy 109.00821 -266.619988) (xy 109.057603 -266.636036) (xy 109.103877 -266.659614) (xy 109.145893 -266.69014)
			(xy 109.182616 -266.726863) (xy 109.213142 -266.768879) (xy 109.23672 -266.815153) (xy 109.252768 -266.864546)
			(xy 109.260893 -266.915841) (xy 109.261402 -266.941808) (xy 109.260897 -266.967126) (xy 109.253138 -267.017165)
			(xy 109.237848 -267.065438) (xy 109.215384 -267.11082) (xy 109.201204 -267.1318) (xy 109.193562 -267.14342)
			(xy 109.184305 -267.169637) (xy 109.182465 -267.197378) (xy 109.188179 -267.224588) (xy 109.201021 -267.249246)
			(xy 109.220041 -267.269526) (xy 109.243826 -267.283921) (xy 109.270614 -267.291366) (xy 109.284516 -267.29182)
			(xy 109.516926 -267.29182) (xy 109.530833 -267.291428) (xy 109.557632 -267.28399) (xy 109.581428 -267.269593)
			(xy 109.600452 -267.249306) (xy 109.613292 -267.224635) (xy 109.618994 -267.197414) (xy 109.617134 -267.169664)
			(xy 109.60785 -267.143447) (xy 109.600238 -267.1318) (xy 109.586034 -267.110832) (xy 109.563541 -267.065457)
			(xy 109.548245 -267.017179) (xy 109.540505 -266.96713) (xy 109.54004 -266.941808) (xy 109.540549 -266.915841)
			(xy 109.548674 -266.864546) (xy 109.564722 -266.815153) (xy 109.5883 -266.768879) (xy 109.618826 -266.726863)
			(xy 109.655549 -266.69014) (xy 109.697565 -266.659614) (xy 109.743839 -266.636036) (xy 109.793232 -266.619988)
			(xy 109.844527 -266.611863) (xy 109.896461 -266.611863) (xy 109.947756 -266.619988) (xy 109.997149 -266.636036)
			(xy 110.043423 -266.659614) (xy 110.085439 -266.69014) (xy 110.122162 -266.726863) (xy 110.152688 -266.768879)
			(xy 110.176266 -266.815153) (xy 110.192314 -266.864546) (xy 110.200439 -266.915841) (xy 110.200948 -266.941808)
			(xy 110.200443 -266.967126) (xy 110.192683 -267.017164) (xy 110.177391 -267.065436) (xy 110.154924 -267.110816)
			(xy 110.14075 -267.1318) (xy 110.13315 -267.143443) (xy 110.123902 -267.169651) (xy 110.122066 -267.197383)
			(xy 110.127777 -267.224582) (xy 110.140612 -267.249232) (xy 110.159619 -267.269508) (xy 110.183391 -267.283906)
			(xy 110.210165 -267.291359) (xy 110.224062 -267.29182) (xy 110.45698 -267.29182) (xy 110.470892 -267.291433)
			(xy 110.497702 -267.284003) (xy 110.52151 -267.269608) (xy 110.540544 -267.249318) (xy 110.553391 -267.22464)
			(xy 110.559094 -267.19741) (xy 110.557232 -267.169652) (xy 110.54794 -267.143428) (xy 110.540292 -267.1318)
			(xy 110.52609 -267.110831) (xy 110.5036 -267.065456) (xy 110.488306 -267.017178) (xy 110.480568 -266.967129)
			(xy 110.480094 -266.941808) (xy 110.480603 -266.915841) (xy 110.488728 -266.864546) (xy 110.504776 -266.815153)
			(xy 110.528354 -266.768879) (xy 110.55888 -266.726863) (xy 110.595603 -266.69014) (xy 110.637619 -266.659614)
			(xy 110.683893 -266.636036) (xy 110.733286 -266.619988) (xy 110.784581 -266.611863) (xy 110.836515 -266.611863)
			(xy 110.88781 -266.619988) (xy 110.937203 -266.636036) (xy 110.983477 -266.659614) (xy 111.025493 -266.69014)
			(xy 111.062216 -266.726863) (xy 111.092742 -266.768879) (xy 111.11632 -266.815153) (xy 111.132368 -266.864546)
			(xy 111.140493 -266.915841) (xy 111.141002 -266.941808) (xy 111.140497 -266.967126) (xy 111.132738 -267.017165)
			(xy 111.117448 -267.065438) (xy 111.094984 -267.11082) (xy 111.080804 -267.1318) (xy 111.073162 -267.14342)
			(xy 111.063905 -267.169637) (xy 111.062065 -267.197378) (xy 111.067779 -267.224588) (xy 111.080621 -267.249246)
			(xy 111.099641 -267.269526) (xy 111.123426 -267.283921) (xy 111.150214 -267.291366) (xy 111.164116 -267.29182)
			(xy 111.396526 -267.29182) (xy 111.410433 -267.291428) (xy 111.437232 -267.28399) (xy 111.461028 -267.269593)
			(xy 111.480052 -267.249306) (xy 111.492892 -267.224635) (xy 111.498594 -267.197414) (xy 111.496734 -267.169664)
			(xy 111.48745 -267.143447) (xy 111.479838 -267.1318) (xy 111.465634 -267.110832) (xy 111.443141 -267.065457)
			(xy 111.427845 -267.017179) (xy 111.420105 -266.96713) (xy 111.41964 -266.941808) (xy 111.420149 -266.915841)
			(xy 111.428274 -266.864546) (xy 111.444322 -266.815153) (xy 111.4679 -266.768879) (xy 111.498426 -266.726863)
			(xy 111.535149 -266.69014) (xy 111.577165 -266.659614) (xy 111.623439 -266.636036) (xy 111.672832 -266.619988)
			(xy 111.724127 -266.611863) (xy 111.776061 -266.611863) (xy 111.827356 -266.619988) (xy 111.876749 -266.636036)
			(xy 111.923023 -266.659614) (xy 111.965039 -266.69014) (xy 112.001762 -266.726863) (xy 112.032288 -266.768879)
			(xy 112.055866 -266.815153) (xy 112.071914 -266.864546) (xy 112.080039 -266.915841) (xy 112.080548 -266.941808)
			(xy 112.080043 -266.967126) (xy 112.072283 -267.017164) (xy 112.056991 -267.065436) (xy 112.034524 -267.110816)
			(xy 112.02035 -267.1318) (xy 112.01275 -267.143443) (xy 112.003502 -267.169651) (xy 112.001666 -267.197383)
			(xy 112.007377 -267.224582) (xy 112.020212 -267.249232) (xy 112.039219 -267.269508) (xy 112.062991 -267.283906)
			(xy 112.089765 -267.291359) (xy 112.103662 -267.29182) (xy 112.336326 -267.29182) (xy 112.350233 -267.291428)
			(xy 112.377032 -267.28399) (xy 112.400828 -267.269593) (xy 112.419852 -267.249306) (xy 112.432692 -267.224635)
			(xy 112.438394 -267.197414) (xy 112.436534 -267.169664) (xy 112.42725 -267.143447) (xy 112.419638 -267.1318)
			(xy 112.405434 -267.110832) (xy 112.382941 -267.065457) (xy 112.367645 -267.017179) (xy 112.359905 -266.96713)
			(xy 112.35944 -266.941808) (xy 112.359949 -266.915841) (xy 112.368074 -266.864546) (xy 112.384122 -266.815153)
			(xy 112.4077 -266.768879) (xy 112.438226 -266.726863) (xy 112.474949 -266.69014) (xy 112.516965 -266.659614)
			(xy 112.563239 -266.636036) (xy 112.612632 -266.619988) (xy 112.663927 -266.611863) (xy 112.715861 -266.611863)
			(xy 112.767156 -266.619988) (xy 112.816549 -266.636036) (xy 112.862823 -266.659614) (xy 112.904839 -266.69014)
			(xy 112.941562 -266.726863) (xy 112.972088 -266.768879) (xy 112.995666 -266.815153) (xy 113.011714 -266.864546)
			(xy 113.019839 -266.915841) (xy 113.020348 -266.941808) (xy 113.019843 -266.967126) (xy 113.012083 -267.017164)
			(xy 112.996791 -267.065436) (xy 112.974324 -267.110816) (xy 112.96015 -267.1318) (xy 112.95255 -267.143443)
			(xy 112.943302 -267.169651) (xy 112.941466 -267.197383) (xy 112.947177 -267.224582) (xy 112.960012 -267.249232)
			(xy 112.979019 -267.269508) (xy 113.002791 -267.283906) (xy 113.029565 -267.291359) (xy 113.043462 -267.29182)
			(xy 113.276126 -267.29182) (xy 113.290033 -267.291428) (xy 113.316832 -267.28399) (xy 113.340628 -267.269593)
			(xy 113.359652 -267.249306) (xy 113.372492 -267.224635) (xy 113.378194 -267.197414) (xy 113.376334 -267.169664)
			(xy 113.36705 -267.143447) (xy 113.359438 -267.1318) (xy 113.345234 -267.110832) (xy 113.322741 -267.065457)
			(xy 113.307445 -267.017179) (xy 113.299705 -266.96713) (xy 113.29924 -266.941808) (xy 113.299722 -266.915838)
			(xy 113.307846 -266.864537) (xy 113.323896 -266.815139) (xy 113.347475 -266.76886) (xy 113.378004 -266.726839)
			(xy 113.41473 -266.690111) (xy 113.45675 -266.659581) (xy 113.503029 -266.636) (xy 113.552426 -266.619949)
			(xy 113.603727 -266.611823) (xy 113.655667 -266.611823) (xy 113.706967 -266.619947) (xy 113.756365 -266.635997)
			(xy 113.802644 -266.659577) (xy 113.844665 -266.690107) (xy 113.881392 -266.726834) (xy 113.911922 -266.768854)
			(xy 113.935502 -266.815133) (xy 113.951552 -266.864531) (xy 113.959677 -266.915831) (xy 113.959677 -266.967771)
			(xy 113.959676 -266.967775) (xy 114.239803 -266.967775) (xy 114.239803 -266.915841) (xy 114.247928 -266.864546)
			(xy 114.263976 -266.815153) (xy 114.287554 -266.768879) (xy 114.31808 -266.726863) (xy 114.354803 -266.69014)
			(xy 114.396819 -266.659614) (xy 114.443093 -266.636036) (xy 114.492486 -266.619988) (xy 114.543781 -266.611863)
			(xy 114.595715 -266.611863) (xy 114.64701 -266.619988) (xy 114.696403 -266.636036) (xy 114.742677 -266.659614)
			(xy 114.784693 -266.69014) (xy 114.821416 -266.726863) (xy 114.851942 -266.768879) (xy 114.87552 -266.815153)
			(xy 114.891568 -266.864546) (xy 114.899693 -266.915841) (xy 114.900202 -266.941808) (xy 114.899693 -266.967775)
			(xy 115.179603 -266.967775) (xy 115.179603 -266.915841) (xy 115.187728 -266.864546) (xy 115.203776 -266.815153)
			(xy 115.227354 -266.768879) (xy 115.25788 -266.726863) (xy 115.294603 -266.69014) (xy 115.336619 -266.659614)
			(xy 115.382893 -266.636036) (xy 115.432286 -266.619988) (xy 115.483581 -266.611863) (xy 115.535515 -266.611863)
			(xy 115.58681 -266.619988) (xy 115.636203 -266.636036) (xy 115.682477 -266.659614) (xy 115.724493 -266.69014)
			(xy 115.761216 -266.726863) (xy 115.791742 -266.768879) (xy 115.81532 -266.815153) (xy 115.831368 -266.864546)
			(xy 115.839493 -266.915841) (xy 115.840002 -266.941808) (xy 115.839493 -266.967775) (xy 116.118895 -266.967775)
			(xy 116.118895 -266.915841) (xy 116.12702 -266.864546) (xy 116.143068 -266.815153) (xy 116.166646 -266.768879)
			(xy 116.197172 -266.726863) (xy 116.233895 -266.69014) (xy 116.275911 -266.659614) (xy 116.322185 -266.636036)
			(xy 116.371578 -266.619988) (xy 116.422873 -266.611863) (xy 116.474807 -266.611863) (xy 116.526102 -266.619988)
			(xy 116.575495 -266.636036) (xy 116.621769 -266.659614) (xy 116.663785 -266.69014) (xy 116.700508 -266.726863)
			(xy 116.731034 -266.768879) (xy 116.754612 -266.815153) (xy 116.77066 -266.864546) (xy 116.778785 -266.915841)
			(xy 116.779294 -266.941808) (xy 116.778785 -266.967775) (xy 117.059203 -266.967775) (xy 117.059203 -266.915841)
			(xy 117.067328 -266.864546) (xy 117.083376 -266.815153) (xy 117.106954 -266.768879) (xy 117.13748 -266.726863)
			(xy 117.174203 -266.69014) (xy 117.216219 -266.659614) (xy 117.262493 -266.636036) (xy 117.311886 -266.619988)
			(xy 117.363181 -266.611863) (xy 117.415115 -266.611863) (xy 117.46641 -266.619988) (xy 117.515803 -266.636036)
			(xy 117.562077 -266.659614) (xy 117.604093 -266.69014) (xy 117.640816 -266.726863) (xy 117.671342 -266.768879)
			(xy 117.69492 -266.815153) (xy 117.710968 -266.864546) (xy 117.719093 -266.915841) (xy 117.719602 -266.941808)
			(xy 117.719093 -266.967775) (xy 117.998495 -266.967775) (xy 117.998495 -266.915841) (xy 118.00662 -266.864546)
			(xy 118.022668 -266.815153) (xy 118.046246 -266.768879) (xy 118.076772 -266.726863) (xy 118.113495 -266.69014)
			(xy 118.155511 -266.659614) (xy 118.201785 -266.636036) (xy 118.251178 -266.619988) (xy 118.302473 -266.611863)
			(xy 118.354407 -266.611863) (xy 118.405702 -266.619988) (xy 118.455095 -266.636036) (xy 118.501369 -266.659614)
			(xy 118.543385 -266.69014) (xy 118.580108 -266.726863) (xy 118.610634 -266.768879) (xy 118.634212 -266.815153)
			(xy 118.65026 -266.864546) (xy 118.658385 -266.915841) (xy 118.658894 -266.941808) (xy 118.658385 -266.967775)
			(xy 121.758203 -266.967775) (xy 121.758203 -266.915841) (xy 121.766328 -266.864546) (xy 121.782376 -266.815153)
			(xy 121.805954 -266.768879) (xy 121.83648 -266.726863) (xy 121.873203 -266.69014) (xy 121.915219 -266.659614)
			(xy 121.961493 -266.636036) (xy 122.010886 -266.619988) (xy 122.062181 -266.611863) (xy 122.114115 -266.611863)
			(xy 122.16541 -266.619988) (xy 122.214803 -266.636036) (xy 122.261077 -266.659614) (xy 122.303093 -266.69014)
			(xy 122.339816 -266.726863) (xy 122.370342 -266.768879) (xy 122.39392 -266.815153) (xy 122.409968 -266.864546)
			(xy 122.418093 -266.915841) (xy 122.418602 -266.941808) (xy 122.418093 -266.967775) (xy 122.698003 -266.967775)
			(xy 122.698003 -266.915841) (xy 122.706128 -266.864546) (xy 122.722176 -266.815153) (xy 122.745754 -266.768879)
			(xy 122.77628 -266.726863) (xy 122.813003 -266.69014) (xy 122.855019 -266.659614) (xy 122.901293 -266.636036)
			(xy 122.950686 -266.619988) (xy 123.001981 -266.611863) (xy 123.053915 -266.611863) (xy 123.10521 -266.619988)
			(xy 123.154603 -266.636036) (xy 123.200877 -266.659614) (xy 123.242893 -266.69014) (xy 123.279616 -266.726863)
			(xy 123.310142 -266.768879) (xy 123.33372 -266.815153) (xy 123.349768 -266.864546) (xy 123.357893 -266.915841)
			(xy 123.358402 -266.941808) (xy 123.357893 -266.967775) (xy 123.349768 -267.01907) (xy 123.33372 -267.068463)
			(xy 123.310142 -267.114737) (xy 123.279616 -267.156753) (xy 123.242893 -267.193476) (xy 123.200877 -267.224002)
			(xy 123.154603 -267.24758) (xy 123.10521 -267.263628) (xy 123.053915 -267.271753) (xy 123.001981 -267.271753)
			(xy 122.950686 -267.263628) (xy 122.901293 -267.24758) (xy 122.855019 -267.224002) (xy 122.813003 -267.193476)
			(xy 122.77628 -267.156753) (xy 122.745754 -267.114737) (xy 122.722176 -267.068463) (xy 122.706128 -267.01907)
			(xy 122.698003 -266.967775) (xy 122.418093 -266.967775) (xy 122.409968 -267.01907) (xy 122.39392 -267.068463)
			(xy 122.370342 -267.114737) (xy 122.339816 -267.156753) (xy 122.303093 -267.193476) (xy 122.261077 -267.224002)
			(xy 122.214803 -267.24758) (xy 122.16541 -267.263628) (xy 122.114115 -267.271753) (xy 122.062181 -267.271753)
			(xy 122.010886 -267.263628) (xy 121.961493 -267.24758) (xy 121.915219 -267.224002) (xy 121.873203 -267.193476)
			(xy 121.83648 -267.156753) (xy 121.805954 -267.114737) (xy 121.782376 -267.068463) (xy 121.766328 -267.01907)
			(xy 121.758203 -266.967775) (xy 118.658385 -266.967775) (xy 118.65026 -267.01907) (xy 118.634212 -267.068463)
			(xy 118.610634 -267.114737) (xy 118.580108 -267.156753) (xy 118.543385 -267.193476) (xy 118.501369 -267.224002)
			(xy 118.455095 -267.24758) (xy 118.405702 -267.263628) (xy 118.354407 -267.271753) (xy 118.302473 -267.271753)
			(xy 118.251178 -267.263628) (xy 118.201785 -267.24758) (xy 118.155511 -267.224002) (xy 118.113495 -267.193476)
			(xy 118.076772 -267.156753) (xy 118.046246 -267.114737) (xy 118.022668 -267.068463) (xy 118.00662 -267.01907)
			(xy 117.998495 -266.967775) (xy 117.719093 -266.967775) (xy 117.710968 -267.01907) (xy 117.69492 -267.068463)
			(xy 117.671342 -267.114737) (xy 117.640816 -267.156753) (xy 117.604093 -267.193476) (xy 117.562077 -267.224002)
			(xy 117.515803 -267.24758) (xy 117.46641 -267.263628) (xy 117.415115 -267.271753) (xy 117.363181 -267.271753)
			(xy 117.311886 -267.263628) (xy 117.262493 -267.24758) (xy 117.216219 -267.224002) (xy 117.174203 -267.193476)
			(xy 117.13748 -267.156753) (xy 117.106954 -267.114737) (xy 117.083376 -267.068463) (xy 117.067328 -267.01907)
			(xy 117.059203 -266.967775) (xy 116.778785 -266.967775) (xy 116.77066 -267.01907) (xy 116.754612 -267.068463)
			(xy 116.731034 -267.114737) (xy 116.700508 -267.156753) (xy 116.663785 -267.193476) (xy 116.621769 -267.224002)
			(xy 116.575495 -267.24758) (xy 116.526102 -267.263628) (xy 116.474807 -267.271753) (xy 116.422873 -267.271753)
			(xy 116.371578 -267.263628) (xy 116.322185 -267.24758) (xy 116.275911 -267.224002) (xy 116.233895 -267.193476)
			(xy 116.197172 -267.156753) (xy 116.166646 -267.114737) (xy 116.143068 -267.068463) (xy 116.12702 -267.01907)
			(xy 116.118895 -266.967775) (xy 115.839493 -266.967775) (xy 115.831368 -267.01907) (xy 115.81532 -267.068463)
			(xy 115.791742 -267.114737) (xy 115.761216 -267.156753) (xy 115.724493 -267.193476) (xy 115.682477 -267.224002)
			(xy 115.636203 -267.24758) (xy 115.58681 -267.263628) (xy 115.535515 -267.271753) (xy 115.483581 -267.271753)
			(xy 115.432286 -267.263628) (xy 115.382893 -267.24758) (xy 115.336619 -267.224002) (xy 115.294603 -267.193476)
			(xy 115.25788 -267.156753) (xy 115.227354 -267.114737) (xy 115.203776 -267.068463) (xy 115.187728 -267.01907)
			(xy 115.179603 -266.967775) (xy 114.899693 -266.967775) (xy 114.891568 -267.01907) (xy 114.87552 -267.068463)
			(xy 114.851942 -267.114737) (xy 114.821416 -267.156753) (xy 114.784693 -267.193476) (xy 114.742677 -267.224002)
			(xy 114.696403 -267.24758) (xy 114.64701 -267.263628) (xy 114.595715 -267.271753) (xy 114.543781 -267.271753)
			(xy 114.492486 -267.263628) (xy 114.443093 -267.24758) (xy 114.396819 -267.224002) (xy 114.354803 -267.193476)
			(xy 114.31808 -267.156753) (xy 114.287554 -267.114737) (xy 114.263976 -267.068463) (xy 114.247928 -267.01907)
			(xy 114.239803 -266.967775) (xy 113.959676 -266.967775) (xy 113.951552 -267.019072) (xy 113.935501 -267.06847)
			(xy 113.91192 -267.114748) (xy 113.88139 -267.156768) (xy 113.844663 -267.193495) (xy 113.802642 -267.224024)
			(xy 113.756363 -267.247604) (xy 113.706965 -267.263653) (xy 113.655664 -267.271778) (xy 113.629694 -267.272262)
			(xy 113.621058 -267.272262) (xy 113.605909 -267.272422) (xy 113.57674 -267.280545) (xy 113.551239 -267.296871)
			(xy 113.531651 -267.319961) (xy 113.5197 -267.347782) (xy 113.51644 -267.377885) (xy 113.522157 -267.40762)
			(xy 113.536347 -267.434368) (xy 113.546636 -267.44549) (xy 113.676938 -267.575792) (xy 113.687688 -267.585805)
			(xy 113.713534 -267.599745) (xy 113.742279 -267.605757) (xy 113.771545 -267.603342) (xy 113.798915 -267.592702)
			(xy 113.822128 -267.574714) (xy 113.831116 -267.563092) (xy 113.846771 -267.542175) (xy 113.883565 -267.505085)
			(xy 113.925732 -267.47424) (xy 113.972222 -267.450404) (xy 114.02188 -267.434171) (xy 114.073472 -267.425944)
			(xy 114.099594 -267.425424) (xy 114.125562 -267.425933) (xy 114.176859 -267.434056) (xy 114.226254 -267.450104)
			(xy 114.27253 -267.473681) (xy 114.314549 -267.504207) (xy 114.351275 -267.54093) (xy 114.381804 -267.582946)
			(xy 114.405385 -267.62922) (xy 114.421437 -267.678614) (xy 114.429565 -267.72991) (xy 114.430048 -267.755878)
			(xy 114.429537 -267.781845) (xy 114.709449 -267.781845) (xy 114.709449 -267.729911) (xy 114.717574 -267.678616)
			(xy 114.733622 -267.629223) (xy 114.7572 -267.582949) (xy 114.787726 -267.540933) (xy 114.824449 -267.50421)
			(xy 114.866465 -267.473684) (xy 114.912739 -267.450106) (xy 114.962132 -267.434058) (xy 115.013427 -267.425933)
			(xy 115.065361 -267.425933) (xy 115.116656 -267.434058) (xy 115.166049 -267.450106) (xy 115.212323 -267.473684)
			(xy 115.254339 -267.50421) (xy 115.291062 -267.540933) (xy 115.321588 -267.582949) (xy 115.345166 -267.629223)
			(xy 115.361214 -267.678616) (xy 115.369339 -267.729911) (xy 115.369848 -267.755878) (xy 115.369339 -267.781845)
			(xy 115.649249 -267.781845) (xy 115.649249 -267.729911) (xy 115.657374 -267.678616) (xy 115.673422 -267.629223)
			(xy 115.697 -267.582949) (xy 115.727526 -267.540933) (xy 115.764249 -267.50421) (xy 115.806265 -267.473684)
			(xy 115.852539 -267.450106) (xy 115.901932 -267.434058) (xy 115.953227 -267.425933) (xy 116.005161 -267.425933)
			(xy 116.056456 -267.434058) (xy 116.105849 -267.450106) (xy 116.152123 -267.473684) (xy 116.194139 -267.50421)
			(xy 116.230862 -267.540933) (xy 116.261388 -267.582949) (xy 116.284966 -267.629223) (xy 116.301014 -267.678616)
			(xy 116.309139 -267.729911) (xy 116.309648 -267.755878) (xy 116.309139 -267.781845) (xy 116.589303 -267.781845)
			(xy 116.589303 -267.729911) (xy 116.597428 -267.678616) (xy 116.613476 -267.629223) (xy 116.637054 -267.582949)
			(xy 116.66758 -267.540933) (xy 116.704303 -267.50421) (xy 116.746319 -267.473684) (xy 116.792593 -267.450106)
			(xy 116.841986 -267.434058) (xy 116.893281 -267.425933) (xy 116.945215 -267.425933) (xy 116.99651 -267.434058)
			(xy 117.045903 -267.450106) (xy 117.092177 -267.473684) (xy 117.134193 -267.50421) (xy 117.170916 -267.540933)
			(xy 117.201442 -267.582949) (xy 117.22502 -267.629223) (xy 117.241068 -267.678616) (xy 117.249193 -267.729911)
			(xy 117.249702 -267.755878) (xy 117.249193 -267.781845) (xy 117.528849 -267.781845) (xy 117.528849 -267.729911)
			(xy 117.536974 -267.678616) (xy 117.553022 -267.629223) (xy 117.5766 -267.582949) (xy 117.607126 -267.540933)
			(xy 117.643849 -267.50421) (xy 117.685865 -267.473684) (xy 117.732139 -267.450106) (xy 117.781532 -267.434058)
			(xy 117.832827 -267.425933) (xy 117.884761 -267.425933) (xy 117.936056 -267.434058) (xy 117.985449 -267.450106)
			(xy 118.031723 -267.473684) (xy 118.073739 -267.50421) (xy 118.110462 -267.540933) (xy 118.140988 -267.582949)
			(xy 118.164566 -267.629223) (xy 118.180614 -267.678616) (xy 118.188739 -267.729911) (xy 118.189248 -267.755878)
			(xy 118.188739 -267.781845) (xy 119.408449 -267.781845) (xy 119.408449 -267.729911) (xy 119.416574 -267.678616)
			(xy 119.432622 -267.629223) (xy 119.4562 -267.582949) (xy 119.486726 -267.540933) (xy 119.523449 -267.50421)
			(xy 119.565465 -267.473684) (xy 119.611739 -267.450106) (xy 119.661132 -267.434058) (xy 119.712427 -267.425933)
			(xy 119.764361 -267.425933) (xy 119.815656 -267.434058) (xy 119.865049 -267.450106) (xy 119.911323 -267.473684)
			(xy 119.953339 -267.50421) (xy 119.990062 -267.540933) (xy 120.020588 -267.582949) (xy 120.044166 -267.629223)
			(xy 120.060214 -267.678616) (xy 120.068339 -267.729911) (xy 120.068848 -267.755878) (xy 120.068339 -267.781845)
			(xy 123.167649 -267.781845) (xy 123.167649 -267.729911) (xy 123.175774 -267.678616) (xy 123.191822 -267.629223)
			(xy 123.2154 -267.582949) (xy 123.245926 -267.540933) (xy 123.282649 -267.50421) (xy 123.324665 -267.473684)
			(xy 123.370939 -267.450106) (xy 123.420332 -267.434058) (xy 123.471627 -267.425933) (xy 123.523561 -267.425933)
			(xy 123.574856 -267.434058) (xy 123.624249 -267.450106) (xy 123.670523 -267.473684) (xy 123.712539 -267.50421)
			(xy 123.749262 -267.540933) (xy 123.779788 -267.582949) (xy 123.803366 -267.629223) (xy 123.819414 -267.678616)
			(xy 123.827539 -267.729911) (xy 123.828048 -267.755878) (xy 123.827539 -267.781845) (xy 123.819414 -267.83314)
			(xy 123.803366 -267.882533) (xy 123.779788 -267.928807) (xy 123.749262 -267.970823) (xy 123.712539 -268.007546)
			(xy 123.670523 -268.038072) (xy 123.624249 -268.06165) (xy 123.574856 -268.077698) (xy 123.523561 -268.085823)
			(xy 123.471627 -268.085823) (xy 123.420332 -268.077698) (xy 123.370939 -268.06165) (xy 123.324665 -268.038072)
			(xy 123.282649 -268.007546) (xy 123.245926 -267.970823) (xy 123.2154 -267.928807) (xy 123.191822 -267.882533)
			(xy 123.175774 -267.83314) (xy 123.167649 -267.781845) (xy 120.068339 -267.781845) (xy 120.060214 -267.83314)
			(xy 120.044166 -267.882533) (xy 120.020588 -267.928807) (xy 119.990062 -267.970823) (xy 119.953339 -268.007546)
			(xy 119.911323 -268.038072) (xy 119.865049 -268.06165) (xy 119.815656 -268.077698) (xy 119.764361 -268.085823)
			(xy 119.712427 -268.085823) (xy 119.661132 -268.077698) (xy 119.611739 -268.06165) (xy 119.565465 -268.038072)
			(xy 119.523449 -268.007546) (xy 119.486726 -267.970823) (xy 119.4562 -267.928807) (xy 119.432622 -267.882533)
			(xy 119.416574 -267.83314) (xy 119.408449 -267.781845) (xy 118.188739 -267.781845) (xy 118.180614 -267.83314)
			(xy 118.164566 -267.882533) (xy 118.140988 -267.928807) (xy 118.110462 -267.970823) (xy 118.073739 -268.007546)
			(xy 118.031723 -268.038072) (xy 117.985449 -268.06165) (xy 117.936056 -268.077698) (xy 117.884761 -268.085823)
			(xy 117.832827 -268.085823) (xy 117.781532 -268.077698) (xy 117.732139 -268.06165) (xy 117.685865 -268.038072)
			(xy 117.643849 -268.007546) (xy 117.607126 -267.970823) (xy 117.5766 -267.928807) (xy 117.553022 -267.882533)
			(xy 117.536974 -267.83314) (xy 117.528849 -267.781845) (xy 117.249193 -267.781845) (xy 117.241068 -267.83314)
			(xy 117.22502 -267.882533) (xy 117.201442 -267.928807) (xy 117.170916 -267.970823) (xy 117.134193 -268.007546)
			(xy 117.092177 -268.038072) (xy 117.045903 -268.06165) (xy 116.99651 -268.077698) (xy 116.945215 -268.085823)
			(xy 116.893281 -268.085823) (xy 116.841986 -268.077698) (xy 116.792593 -268.06165) (xy 116.746319 -268.038072)
			(xy 116.704303 -268.007546) (xy 116.66758 -267.970823) (xy 116.637054 -267.928807) (xy 116.613476 -267.882533)
			(xy 116.597428 -267.83314) (xy 116.589303 -267.781845) (xy 116.309139 -267.781845) (xy 116.301014 -267.83314)
			(xy 116.284966 -267.882533) (xy 116.261388 -267.928807) (xy 116.230862 -267.970823) (xy 116.194139 -268.007546)
			(xy 116.152123 -268.038072) (xy 116.105849 -268.06165) (xy 116.056456 -268.077698) (xy 116.005161 -268.085823)
			(xy 115.953227 -268.085823) (xy 115.901932 -268.077698) (xy 115.852539 -268.06165) (xy 115.806265 -268.038072)
			(xy 115.764249 -268.007546) (xy 115.727526 -267.970823) (xy 115.697 -267.928807) (xy 115.673422 -267.882533)
			(xy 115.657374 -267.83314) (xy 115.649249 -267.781845) (xy 115.369339 -267.781845) (xy 115.361214 -267.83314)
			(xy 115.345166 -267.882533) (xy 115.321588 -267.928807) (xy 115.291062 -267.970823) (xy 115.254339 -268.007546)
			(xy 115.212323 -268.038072) (xy 115.166049 -268.06165) (xy 115.116656 -268.077698) (xy 115.065361 -268.085823)
			(xy 115.013427 -268.085823) (xy 114.962132 -268.077698) (xy 114.912739 -268.06165) (xy 114.866465 -268.038072)
			(xy 114.824449 -268.007546) (xy 114.787726 -267.970823) (xy 114.7572 -267.928807) (xy 114.733622 -267.882533)
			(xy 114.717574 -267.83314) (xy 114.709449 -267.781845) (xy 114.429537 -267.781845) (xy 114.429518 -267.782825)
			(xy 114.420778 -267.836007) (xy 114.403527 -267.887066) (xy 114.378221 -267.934649) (xy 114.345531 -267.977498)
			(xy 114.306323 -268.014475) (xy 114.284252 -268.029944) (xy 114.272185 -268.038755) (xy 114.253362 -268.061941)
			(xy 114.242041 -268.089576) (xy 114.239189 -268.119304) (xy 114.245049 -268.148588) (xy 114.25912 -268.17493)
			(xy 114.269266 -268.1859) (xy 114.38001 -268.296644) (xy 114.413284 -268.27861) (xy 114.437491 -268.26624)
			(xy 114.488943 -268.248704) (xy 114.542569 -268.239812) (xy 114.569748 -268.23924) (xy 114.595713 -268.239753)
			(xy 114.647003 -268.247883) (xy 114.696389 -268.263936) (xy 114.742657 -268.287516) (xy 114.784667 -268.318043)
			(xy 114.821384 -268.354765) (xy 114.851906 -268.396779) (xy 114.87548 -268.44305) (xy 114.891527 -268.492438)
			(xy 114.89965 -268.543729) (xy 114.900202 -268.569694) (xy 114.899676 -268.595661) (xy 115.179603 -268.595661)
			(xy 115.179603 -268.543727) (xy 115.187728 -268.492432) (xy 115.203776 -268.443039) (xy 115.227354 -268.396765)
			(xy 115.25788 -268.354749) (xy 115.294603 -268.318026) (xy 115.336619 -268.2875) (xy 115.382893 -268.263922)
			(xy 115.432286 -268.247874) (xy 115.483581 -268.239749) (xy 115.535515 -268.239749) (xy 115.58681 -268.247874)
			(xy 115.636203 -268.263922) (xy 115.682477 -268.2875) (xy 115.724493 -268.318026) (xy 115.761216 -268.354749)
			(xy 115.791742 -268.396765) (xy 115.81532 -268.443039) (xy 115.831368 -268.492432) (xy 115.839493 -268.543727)
			(xy 115.840002 -268.569694) (xy 115.839493 -268.595661) (xy 116.119403 -268.595661) (xy 116.119403 -268.543727)
			(xy 116.127528 -268.492432) (xy 116.143576 -268.443039) (xy 116.167154 -268.396765) (xy 116.19768 -268.354749)
			(xy 116.234403 -268.318026) (xy 116.276419 -268.2875) (xy 116.322693 -268.263922) (xy 116.372086 -268.247874)
			(xy 116.423381 -268.239749) (xy 116.475315 -268.239749) (xy 116.52661 -268.247874) (xy 116.576003 -268.263922)
			(xy 116.622277 -268.2875) (xy 116.664293 -268.318026) (xy 116.701016 -268.354749) (xy 116.731542 -268.396765)
			(xy 116.75512 -268.443039) (xy 116.771168 -268.492432) (xy 116.779293 -268.543727) (xy 116.779802 -268.569694)
			(xy 116.779293 -268.595661) (xy 117.058949 -268.595661) (xy 117.058949 -268.543727) (xy 117.067074 -268.492432)
			(xy 117.083122 -268.443039) (xy 117.1067 -268.396765) (xy 117.137226 -268.354749) (xy 117.173949 -268.318026)
			(xy 117.215965 -268.2875) (xy 117.262239 -268.263922) (xy 117.311632 -268.247874) (xy 117.362927 -268.239749)
			(xy 117.414861 -268.239749) (xy 117.466156 -268.247874) (xy 117.515549 -268.263922) (xy 117.561823 -268.2875)
			(xy 117.603839 -268.318026) (xy 117.640562 -268.354749) (xy 117.671088 -268.396765) (xy 117.694666 -268.443039)
			(xy 117.710714 -268.492432) (xy 117.718839 -268.543727) (xy 117.719348 -268.569694) (xy 117.718839 -268.595661)
			(xy 117.999003 -268.595661) (xy 117.999003 -268.543727) (xy 118.007128 -268.492432) (xy 118.023176 -268.443039)
			(xy 118.046754 -268.396765) (xy 118.07728 -268.354749) (xy 118.114003 -268.318026) (xy 118.156019 -268.2875)
			(xy 118.202293 -268.263922) (xy 118.251686 -268.247874) (xy 118.302981 -268.239749) (xy 118.354915 -268.239749)
			(xy 118.40621 -268.247874) (xy 118.455603 -268.263922) (xy 118.501877 -268.2875) (xy 118.543893 -268.318026)
			(xy 118.580616 -268.354749) (xy 118.611142 -268.396765) (xy 118.63472 -268.443039) (xy 118.650768 -268.492432)
			(xy 118.658893 -268.543727) (xy 118.659402 -268.569694) (xy 118.658893 -268.595661) (xy 122.697749 -268.595661)
			(xy 122.697749 -268.543727) (xy 122.705874 -268.492432) (xy 122.721922 -268.443039) (xy 122.7455 -268.396765)
			(xy 122.776026 -268.354749) (xy 122.812749 -268.318026) (xy 122.854765 -268.2875) (xy 122.901039 -268.263922)
			(xy 122.950432 -268.247874) (xy 123.001727 -268.239749) (xy 123.053661 -268.239749) (xy 123.104956 -268.247874)
			(xy 123.154349 -268.263922) (xy 123.200623 -268.2875) (xy 123.242639 -268.318026) (xy 123.279362 -268.354749)
			(xy 123.309888 -268.396765) (xy 123.333466 -268.443039) (xy 123.349514 -268.492432) (xy 123.357639 -268.543727)
			(xy 123.358148 -268.569694) (xy 123.357639 -268.595661) (xy 123.349514 -268.646956) (xy 123.333466 -268.696349)
			(xy 123.309888 -268.742623) (xy 123.279362 -268.784639) (xy 123.242639 -268.821362) (xy 123.200623 -268.851888)
			(xy 123.154349 -268.875466) (xy 123.104956 -268.891514) (xy 123.053661 -268.899639) (xy 123.001727 -268.899639)
			(xy 122.950432 -268.891514) (xy 122.901039 -268.875466) (xy 122.854765 -268.851888) (xy 122.812749 -268.821362)
			(xy 122.776026 -268.784639) (xy 122.7455 -268.742623) (xy 122.721922 -268.696349) (xy 122.705874 -268.646956)
			(xy 122.697749 -268.595661) (xy 118.658893 -268.595661) (xy 118.650768 -268.646956) (xy 118.63472 -268.696349)
			(xy 118.611142 -268.742623) (xy 118.580616 -268.784639) (xy 118.543893 -268.821362) (xy 118.501877 -268.851888)
			(xy 118.455603 -268.875466) (xy 118.40621 -268.891514) (xy 118.354915 -268.899639) (xy 118.302981 -268.899639)
			(xy 118.251686 -268.891514) (xy 118.202293 -268.875466) (xy 118.156019 -268.851888) (xy 118.114003 -268.821362)
			(xy 118.07728 -268.784639) (xy 118.046754 -268.742623) (xy 118.023176 -268.696349) (xy 118.007128 -268.646956)
			(xy 117.999003 -268.595661) (xy 117.718839 -268.595661) (xy 117.710714 -268.646956) (xy 117.694666 -268.696349)
			(xy 117.671088 -268.742623) (xy 117.640562 -268.784639) (xy 117.603839 -268.821362) (xy 117.561823 -268.851888)
			(xy 117.515549 -268.875466) (xy 117.466156 -268.891514) (xy 117.414861 -268.899639) (xy 117.362927 -268.899639)
			(xy 117.311632 -268.891514) (xy 117.262239 -268.875466) (xy 117.215965 -268.851888) (xy 117.173949 -268.821362)
			(xy 117.137226 -268.784639) (xy 117.1067 -268.742623) (xy 117.083122 -268.696349) (xy 117.067074 -268.646956)
			(xy 117.058949 -268.595661) (xy 116.779293 -268.595661) (xy 116.771168 -268.646956) (xy 116.75512 -268.696349)
			(xy 116.731542 -268.742623) (xy 116.701016 -268.784639) (xy 116.664293 -268.821362) (xy 116.622277 -268.851888)
			(xy 116.576003 -268.875466) (xy 116.52661 -268.891514) (xy 116.475315 -268.899639) (xy 116.423381 -268.899639)
			(xy 116.372086 -268.891514) (xy 116.322693 -268.875466) (xy 116.276419 -268.851888) (xy 116.234403 -268.821362)
			(xy 116.19768 -268.784639) (xy 116.167154 -268.742623) (xy 116.143576 -268.696349) (xy 116.127528 -268.646956)
			(xy 116.119403 -268.595661) (xy 115.839493 -268.595661) (xy 115.831368 -268.646956) (xy 115.81532 -268.696349)
			(xy 115.791742 -268.742623) (xy 115.761216 -268.784639) (xy 115.724493 -268.821362) (xy 115.682477 -268.851888)
			(xy 115.636203 -268.875466) (xy 115.58681 -268.891514) (xy 115.535515 -268.899639) (xy 115.483581 -268.899639)
			(xy 115.432286 -268.891514) (xy 115.382893 -268.875466) (xy 115.336619 -268.851888) (xy 115.294603 -268.821362)
			(xy 115.25788 -268.784639) (xy 115.227354 -268.742623) (xy 115.203776 -268.696349) (xy 115.187728 -268.646956)
			(xy 115.179603 -268.595661) (xy 114.899676 -268.595661) (xy 114.899651 -268.596874) (xy 114.890757 -268.650502)
			(xy 114.873206 -268.701951) (xy 114.860832 -268.726158) (xy 114.842798 -268.759432) (xy 115.15852 -269.075154)
			(xy 115.167664 -269.078964) (xy 115.191049 -269.089333) (xy 115.234567 -269.116214) (xy 115.273423 -269.149481)
			(xy 115.306689 -269.188337) (xy 115.33357 -269.231856) (xy 115.34394 -269.25524) (xy 115.34775 -269.264384)
			(xy 115.479322 -269.395956) (xy 115.489624 -269.405625) (xy 115.514289 -269.41938) (xy 115.541779 -269.425851)
			(xy 115.569991 -269.424542) (xy 115.596764 -269.415554) (xy 115.62005 -269.399575) (xy 115.638067 -269.377827)
			(xy 115.649436 -269.351974) (xy 115.651788 -269.338044) (xy 115.655909 -269.312038) (xy 115.671319 -269.261692)
			(xy 115.69452 -269.214428) (xy 115.724924 -269.171443) (xy 115.761762 -269.133825) (xy 115.8041 -269.102526)
			(xy 115.850867 -269.078339) (xy 115.900879 -269.061877) (xy 115.952868 -269.053556) (xy 115.979194 -269.053056)
			(xy 116.005163 -269.053538) (xy 116.056463 -269.061663) (xy 116.105859 -269.077712) (xy 116.152137 -269.101292)
			(xy 116.194156 -269.13182) (xy 116.230882 -269.168547) (xy 116.26141 -269.210566) (xy 116.284989 -269.256844)
			(xy 116.301038 -269.306241) (xy 116.309162 -269.357541) (xy 116.309648 -269.38351) (xy 116.309137 -269.409477)
			(xy 116.589049 -269.409477) (xy 116.589049 -269.357543) (xy 116.597174 -269.306248) (xy 116.613222 -269.256855)
			(xy 116.6368 -269.210581) (xy 116.667326 -269.168565) (xy 116.704049 -269.131842) (xy 116.746065 -269.101316)
			(xy 116.792339 -269.077738) (xy 116.841732 -269.06169) (xy 116.893027 -269.053565) (xy 116.944961 -269.053565)
			(xy 116.996256 -269.06169) (xy 117.045649 -269.077738) (xy 117.091923 -269.101316) (xy 117.133939 -269.131842)
			(xy 117.170662 -269.168565) (xy 117.201188 -269.210581) (xy 117.224766 -269.256855) (xy 117.240814 -269.306248)
			(xy 117.248939 -269.357543) (xy 117.249448 -269.38351) (xy 117.248939 -269.409477) (xy 117.529103 -269.409477)
			(xy 117.529103 -269.357543) (xy 117.537228 -269.306248) (xy 117.553276 -269.256855) (xy 117.576854 -269.210581)
			(xy 117.60738 -269.168565) (xy 117.644103 -269.131842) (xy 117.686119 -269.101316) (xy 117.732393 -269.077738)
			(xy 117.781786 -269.06169) (xy 117.833081 -269.053565) (xy 117.885015 -269.053565) (xy 117.93631 -269.06169)
			(xy 117.985703 -269.077738) (xy 118.031977 -269.101316) (xy 118.073993 -269.131842) (xy 118.110716 -269.168565)
			(xy 118.141242 -269.210581) (xy 118.16482 -269.256855) (xy 118.180868 -269.306248) (xy 118.188993 -269.357543)
			(xy 118.189502 -269.38351) (xy 118.188993 -269.409477) (xy 120.348249 -269.409477) (xy 120.348249 -269.357543)
			(xy 120.356374 -269.306248) (xy 120.372422 -269.256855) (xy 120.396 -269.210581) (xy 120.426526 -269.168565)
			(xy 120.463249 -269.131842) (xy 120.505265 -269.101316) (xy 120.551539 -269.077738) (xy 120.600932 -269.06169)
			(xy 120.652227 -269.053565) (xy 120.704161 -269.053565) (xy 120.755456 -269.06169) (xy 120.804849 -269.077738)
			(xy 120.851123 -269.101316) (xy 120.893139 -269.131842) (xy 120.929862 -269.168565) (xy 120.960388 -269.210581)
			(xy 120.983966 -269.256855) (xy 121.000014 -269.306248) (xy 121.008139 -269.357543) (xy 121.008648 -269.38351)
			(xy 121.008139 -269.409477) (xy 122.227849 -269.409477) (xy 122.227849 -269.357543) (xy 122.235974 -269.306248)
			(xy 122.252022 -269.256855) (xy 122.2756 -269.210581) (xy 122.306126 -269.168565) (xy 122.342849 -269.131842)
			(xy 122.384865 -269.101316) (xy 122.431139 -269.077738) (xy 122.480532 -269.06169) (xy 122.531827 -269.053565)
			(xy 122.583761 -269.053565) (xy 122.635056 -269.06169) (xy 122.684449 -269.077738) (xy 122.730723 -269.101316)
			(xy 122.772739 -269.131842) (xy 122.809462 -269.168565) (xy 122.839988 -269.210581) (xy 122.863566 -269.256855)
			(xy 122.879614 -269.306248) (xy 122.887739 -269.357543) (xy 122.888248 -269.38351) (xy 122.887739 -269.409477)
			(xy 123.167649 -269.409477) (xy 123.167649 -269.357543) (xy 123.175774 -269.306248) (xy 123.191822 -269.256855)
			(xy 123.2154 -269.210581) (xy 123.245926 -269.168565) (xy 123.282649 -269.131842) (xy 123.324665 -269.101316)
			(xy 123.370939 -269.077738) (xy 123.420332 -269.06169) (xy 123.471627 -269.053565) (xy 123.523561 -269.053565)
			(xy 123.574856 -269.06169) (xy 123.624249 -269.077738) (xy 123.670523 -269.101316) (xy 123.712539 -269.131842)
			(xy 123.749262 -269.168565) (xy 123.779788 -269.210581) (xy 123.803366 -269.256855) (xy 123.819414 -269.306248)
			(xy 123.827539 -269.357543) (xy 123.828048 -269.38351) (xy 123.827539 -269.409477) (xy 123.819414 -269.460772)
			(xy 123.803366 -269.510165) (xy 123.779788 -269.556439) (xy 123.749262 -269.598455) (xy 123.712539 -269.635178)
			(xy 123.670523 -269.665704) (xy 123.624249 -269.689282) (xy 123.574856 -269.70533) (xy 123.523561 -269.713455)
			(xy 123.471627 -269.713455) (xy 123.420332 -269.70533) (xy 123.370939 -269.689282) (xy 123.324665 -269.665704)
			(xy 123.282649 -269.635178) (xy 123.245926 -269.598455) (xy 123.2154 -269.556439) (xy 123.191822 -269.510165)
			(xy 123.175774 -269.460772) (xy 123.167649 -269.409477) (xy 122.887739 -269.409477) (xy 122.879614 -269.460772)
			(xy 122.863566 -269.510165) (xy 122.839988 -269.556439) (xy 122.809462 -269.598455) (xy 122.772739 -269.635178)
			(xy 122.730723 -269.665704) (xy 122.684449 -269.689282) (xy 122.635056 -269.70533) (xy 122.583761 -269.713455)
			(xy 122.531827 -269.713455) (xy 122.480532 -269.70533) (xy 122.431139 -269.689282) (xy 122.384865 -269.665704)
			(xy 122.342849 -269.635178) (xy 122.306126 -269.598455) (xy 122.2756 -269.556439) (xy 122.252022 -269.510165)
			(xy 122.235974 -269.460772) (xy 122.227849 -269.409477) (xy 121.008139 -269.409477) (xy 121.000014 -269.460772)
			(xy 120.983966 -269.510165) (xy 120.960388 -269.556439) (xy 120.929862 -269.598455) (xy 120.893139 -269.635178)
			(xy 120.851123 -269.665704) (xy 120.804849 -269.689282) (xy 120.755456 -269.70533) (xy 120.704161 -269.713455)
			(xy 120.652227 -269.713455) (xy 120.600932 -269.70533) (xy 120.551539 -269.689282) (xy 120.505265 -269.665704)
			(xy 120.463249 -269.635178) (xy 120.426526 -269.598455) (xy 120.396 -269.556439) (xy 120.372422 -269.510165)
			(xy 120.356374 -269.460772) (xy 120.348249 -269.409477) (xy 118.188993 -269.409477) (xy 118.180868 -269.460772)
			(xy 118.16482 -269.510165) (xy 118.141242 -269.556439) (xy 118.110716 -269.598455) (xy 118.073993 -269.635178)
			(xy 118.031977 -269.665704) (xy 117.985703 -269.689282) (xy 117.93631 -269.70533) (xy 117.885015 -269.713455)
			(xy 117.833081 -269.713455) (xy 117.781786 -269.70533) (xy 117.732393 -269.689282) (xy 117.686119 -269.665704)
			(xy 117.644103 -269.635178) (xy 117.60738 -269.598455) (xy 117.576854 -269.556439) (xy 117.553276 -269.510165)
			(xy 117.537228 -269.460772) (xy 117.529103 -269.409477) (xy 117.248939 -269.409477) (xy 117.240814 -269.460772)
			(xy 117.224766 -269.510165) (xy 117.201188 -269.556439) (xy 117.170662 -269.598455) (xy 117.133939 -269.635178)
			(xy 117.091923 -269.665704) (xy 117.045649 -269.689282) (xy 116.996256 -269.70533) (xy 116.944961 -269.713455)
			(xy 116.893027 -269.713455) (xy 116.841732 -269.70533) (xy 116.792339 -269.689282) (xy 116.746065 -269.665704)
			(xy 116.704049 -269.635178) (xy 116.667326 -269.598455) (xy 116.6368 -269.556439) (xy 116.613222 -269.510165)
			(xy 116.597174 -269.460772) (xy 116.589049 -269.409477) (xy 116.309137 -269.409477) (xy 116.30913 -269.409829)
			(xy 116.300773 -269.461799) (xy 116.284288 -269.511788) (xy 116.260091 -269.558535) (xy 116.228793 -269.600857)
			(xy 116.191185 -269.637687) (xy 116.148217 -269.668092) (xy 116.100975 -269.691306) (xy 116.050652 -269.706742)
			(xy 116.02466 -269.710916) (xy 116.010749 -269.713317) (xy 115.984931 -269.72471) (xy 115.963215 -269.742731)
			(xy 115.947256 -269.766004) (xy 115.938272 -269.792755) (xy 115.936947 -269.820944) (xy 115.943384 -269.84842)
			(xy 115.95709 -269.873087) (xy 115.966748 -269.883382) (xy 116.059966 -269.9766) (xy 116.06994 -269.985964)
			(xy 116.09371 -269.99949) (xy 116.12022 -270.006211) (xy 116.147562 -270.005645) (xy 116.173771 -269.997833)
			(xy 116.196961 -269.983335) (xy 116.206524 -269.973552) (xy 116.225437 -269.953861) (xy 116.268535 -269.92035)
			(xy 116.316559 -269.894385) (xy 116.3682 -269.876675) (xy 116.422051 -269.867702) (xy 116.449348 -269.867126)
			(xy 116.475313 -269.867639) (xy 116.526604 -269.875769) (xy 116.575991 -269.891822) (xy 116.62226 -269.915402)
			(xy 116.664271 -269.945928) (xy 116.70099 -269.982651) (xy 116.731513 -270.024664) (xy 116.755089 -270.070935)
			(xy 116.771138 -270.120324) (xy 116.779263 -270.171615) (xy 116.779802 -270.19758) (xy 116.779269 -270.223547)
			(xy 117.058949 -270.223547) (xy 117.058949 -270.171613) (xy 117.067074 -270.120318) (xy 117.083122 -270.070925)
			(xy 117.1067 -270.024651) (xy 117.137226 -269.982635) (xy 117.173949 -269.945912) (xy 117.215965 -269.915386)
			(xy 117.262239 -269.891808) (xy 117.311632 -269.87576) (xy 117.362927 -269.867635) (xy 117.414861 -269.867635)
			(xy 117.466156 -269.87576) (xy 117.515549 -269.891808) (xy 117.561823 -269.915386) (xy 117.603839 -269.945912)
			(xy 117.640562 -269.982635) (xy 117.671088 -270.024651) (xy 117.694666 -270.070925) (xy 117.710714 -270.120318)
			(xy 117.718839 -270.171613) (xy 117.719348 -270.19758) (xy 117.718839 -270.223547) (xy 117.999003 -270.223547)
			(xy 117.999003 -270.171613) (xy 118.007128 -270.120318) (xy 118.023176 -270.070925) (xy 118.046754 -270.024651)
			(xy 118.07728 -269.982635) (xy 118.114003 -269.945912) (xy 118.156019 -269.915386) (xy 118.202293 -269.891808)
			(xy 118.251686 -269.87576) (xy 118.302981 -269.867635) (xy 118.354915 -269.867635) (xy 118.40621 -269.87576)
			(xy 118.455603 -269.891808) (xy 118.501877 -269.915386) (xy 118.543893 -269.945912) (xy 118.580616 -269.982635)
			(xy 118.611142 -270.024651) (xy 118.63472 -270.070925) (xy 118.650768 -270.120318) (xy 118.658893 -270.171613)
			(xy 118.659402 -270.19758) (xy 118.658893 -270.223547) (xy 122.698003 -270.223547) (xy 122.698003 -270.171613)
			(xy 122.706128 -270.120318) (xy 122.722176 -270.070925) (xy 122.745754 -270.024651) (xy 122.77628 -269.982635)
			(xy 122.813003 -269.945912) (xy 122.855019 -269.915386) (xy 122.901293 -269.891808) (xy 122.950686 -269.87576)
			(xy 123.001981 -269.867635) (xy 123.053915 -269.867635) (xy 123.10521 -269.87576) (xy 123.154603 -269.891808)
			(xy 123.200877 -269.915386) (xy 123.242893 -269.945912) (xy 123.279616 -269.982635) (xy 123.310142 -270.024651)
			(xy 123.33372 -270.070925) (xy 123.349768 -270.120318) (xy 123.357893 -270.171613) (xy 123.358402 -270.19758)
			(xy 123.357893 -270.223547) (xy 123.349768 -270.274842) (xy 123.33372 -270.324235) (xy 123.310142 -270.370509)
			(xy 123.279616 -270.412525) (xy 123.242893 -270.449248) (xy 123.200877 -270.479774) (xy 123.154603 -270.503352)
			(xy 123.10521 -270.5194) (xy 123.053915 -270.527525) (xy 123.001981 -270.527525) (xy 122.950686 -270.5194)
			(xy 122.901293 -270.503352) (xy 122.855019 -270.479774) (xy 122.813003 -270.449248) (xy 122.77628 -270.412525)
			(xy 122.745754 -270.370509) (xy 122.722176 -270.324235) (xy 122.706128 -270.274842) (xy 122.698003 -270.223547)
			(xy 118.658893 -270.223547) (xy 118.650768 -270.274842) (xy 118.63472 -270.324235) (xy 118.611142 -270.370509)
			(xy 118.580616 -270.412525) (xy 118.543893 -270.449248) (xy 118.501877 -270.479774) (xy 118.455603 -270.503352)
			(xy 118.40621 -270.5194) (xy 118.354915 -270.527525) (xy 118.302981 -270.527525) (xy 118.251686 -270.5194)
			(xy 118.202293 -270.503352) (xy 118.156019 -270.479774) (xy 118.114003 -270.449248) (xy 118.07728 -270.412525)
			(xy 118.046754 -270.370509) (xy 118.023176 -270.324235) (xy 118.007128 -270.274842) (xy 117.999003 -270.223547)
			(xy 117.718839 -270.223547) (xy 117.710714 -270.274842) (xy 117.694666 -270.324235) (xy 117.671088 -270.370509)
			(xy 117.640562 -270.412525) (xy 117.603839 -270.449248) (xy 117.561823 -270.479774) (xy 117.515549 -270.503352)
			(xy 117.466156 -270.5194) (xy 117.414861 -270.527525) (xy 117.362927 -270.527525) (xy 117.311632 -270.5194)
			(xy 117.262239 -270.503352) (xy 117.215965 -270.479774) (xy 117.173949 -270.449248) (xy 117.137226 -270.412525)
			(xy 117.1067 -270.370509) (xy 117.083122 -270.324235) (xy 117.067074 -270.274842) (xy 117.058949 -270.223547)
			(xy 116.779269 -270.223547) (xy 116.779242 -270.224879) (xy 116.770266 -270.278733) (xy 116.752557 -270.330378)
			(xy 116.726596 -270.378407) (xy 116.69309 -270.421514) (xy 116.673376 -270.440404) (xy 116.663643 -270.449996)
			(xy 116.649209 -270.473187) (xy 116.641435 -270.499374) (xy 116.640876 -270.526684) (xy 116.647573 -270.553167)
			(xy 116.661046 -270.576929) (xy 116.670328 -270.586962) (xy 116.755926 -270.67256) (xy 124.016008 -270.67256)
		)
		(stroke
			(width 0)
			(type solid)
		)
		(fill yes)
		(layer "In2.Cu")
		(net "PVCCINFAON_CPU1")
	)
	(gr_poly
		(pts
			(xy 361.95762 -270.691356) (xy 361.977783 -270.686503) (xy 362.018926 -270.681275) (xy 362.039662 -270.680942)
			(xy 362.060398 -270.681283) (xy 362.10154 -270.686508) (xy 362.121704 -270.691356) (xy 362.1278 -270.69288)
			(xy 362.891324 -270.69288) (xy 362.89742 -270.691356) (xy 362.917583 -270.686503) (xy 362.958726 -270.681275)
			(xy 362.979462 -270.680942) (xy 363.000198 -270.681283) (xy 363.04134 -270.686508) (xy 363.061504 -270.691356)
			(xy 363.0676 -270.69288) (xy 363.831124 -270.69288) (xy 363.83722 -270.691356) (xy 363.857383 -270.686503)
			(xy 363.898526 -270.681275) (xy 363.919262 -270.680942) (xy 363.939998 -270.681283) (xy 363.98114 -270.686508)
			(xy 364.001304 -270.691356) (xy 364.0074 -270.69288) (xy 364.770924 -270.69288) (xy 364.77702 -270.691356)
			(xy 364.797183 -270.686503) (xy 364.838326 -270.681275) (xy 364.859062 -270.680942) (xy 364.879798 -270.681283)
			(xy 364.92094 -270.686508) (xy 364.941104 -270.691356) (xy 364.9472 -270.69288) (xy 365.710724 -270.69288)
			(xy 365.71682 -270.691356) (xy 365.736983 -270.686503) (xy 365.778126 -270.681275) (xy 365.798862 -270.680942)
			(xy 365.819598 -270.681283) (xy 365.86074 -270.686508) (xy 365.880904 -270.691356) (xy 365.887 -270.69288)
			(xy 366.650524 -270.69288) (xy 366.65662 -270.691356) (xy 366.676783 -270.686503) (xy 366.717926 -270.681275)
			(xy 366.738662 -270.680942) (xy 366.759398 -270.681283) (xy 366.80054 -270.686508) (xy 366.820704 -270.691356)
			(xy 366.8268 -270.69288) (xy 367.590324 -270.69288) (xy 367.59642 -270.691356) (xy 367.616583 -270.686503)
			(xy 367.657726 -270.681275) (xy 367.678462 -270.680942) (xy 367.699198 -270.681283) (xy 367.74034 -270.686508)
			(xy 367.760504 -270.691356) (xy 367.7666 -270.69288) (xy 368.530124 -270.69288) (xy 368.53622 -270.691356)
			(xy 368.556383 -270.686503) (xy 368.597526 -270.681275) (xy 368.618262 -270.680942) (xy 368.638998 -270.681283)
			(xy 368.68014 -270.686508) (xy 368.700304 -270.691356) (xy 368.7064 -270.69288) (xy 369.469924 -270.69288)
			(xy 369.47602 -270.691356) (xy 369.496183 -270.686503) (xy 369.537326 -270.681275) (xy 369.558062 -270.680942)
			(xy 369.578798 -270.681283) (xy 369.61994 -270.686508) (xy 369.640104 -270.691356) (xy 369.6462 -270.69288)
			(xy 370.409978 -270.69288) (xy 370.416074 -270.691356) (xy 370.436238 -270.686506) (xy 370.47738 -270.681285)
			(xy 370.498116 -270.680942) (xy 370.518852 -270.68128) (xy 370.559996 -270.6865) (xy 370.580158 -270.691356)
			(xy 370.586254 -270.69288) (xy 371.33657 -270.69288) (xy 371.619526 -270.409924) (xy 371.619526 -270.359632)
			(xy 371.613938 -270.34871) (xy 371.602412 -270.325203) (xy 371.586112 -270.275455) (xy 371.57786 -270.223758)
			(xy 371.577863 -270.171407) (xy 371.58612 -270.119711) (xy 371.602426 -270.069964) (xy 371.613938 -270.04645)
			(xy 371.619526 -270.035528) (xy 371.619526 -269.807944) (xy 371.619012 -269.793038) (xy 371.610414 -269.764495)
			(xy 371.593937 -269.739651) (xy 371.570987 -269.720626) (xy 371.543519 -269.709041) (xy 371.513876 -269.705884)
			(xy 371.49913 -269.708122) (xy 371.48391 -269.710851) (xy 371.453124 -269.713775) (xy 371.437662 -269.713964)
			(xy 371.411696 -269.713452) (xy 371.360404 -269.705323) (xy 371.311015 -269.68927) (xy 371.264745 -269.66569)
			(xy 371.222733 -269.635162) (xy 371.186014 -269.598438) (xy 371.15549 -269.556423) (xy 371.131915 -269.51015)
			(xy 371.115869 -269.460759) (xy 371.107745 -269.409466) (xy 371.107745 -269.357534) (xy 371.115869 -269.306241)
			(xy 371.131915 -269.25685) (xy 371.15549 -269.210577) (xy 371.186014 -269.168562) (xy 371.222733 -269.131838)
			(xy 371.264745 -269.10131) (xy 371.311015 -269.07773) (xy 371.360404 -269.061677) (xy 371.411696 -269.053548)
			(xy 371.437662 -269.053056) (xy 371.453123 -269.053263) (xy 371.483906 -269.056191) (xy 371.49913 -269.058898)
			(xy 371.513872 -269.061141) (xy 371.543508 -269.05796) (xy 371.570967 -269.046366) (xy 371.593913 -269.027344)
			(xy 371.610397 -269.002511) (xy 371.619017 -268.973979) (xy 371.619526 -268.959076) (xy 371.619526 -268.731746)
			(xy 371.613938 -268.720824) (xy 371.602411 -268.697317) (xy 371.586109 -268.647568) (xy 371.577855 -268.595871)
			(xy 371.577855 -268.543519) (xy 371.586111 -268.491821) (xy 371.602415 -268.442073) (xy 371.613938 -268.418564)
			(xy 371.619526 -268.407642) (xy 371.619526 -268.180312) (xy 371.619008 -268.16541) (xy 371.610404 -268.136874)
			(xy 371.593926 -268.112039) (xy 371.570978 -268.093021) (xy 371.543516 -268.08144) (xy 371.513879 -268.078284)
			(xy 371.49913 -268.08049) (xy 371.48391 -268.083219) (xy 371.453124 -268.086144) (xy 371.437662 -268.086332)
			(xy 371.411698 -268.08582) (xy 371.360411 -268.077691) (xy 371.311027 -268.061641) (xy 371.264762 -268.038062)
			(xy 371.222754 -268.007537) (xy 371.186038 -267.970817) (xy 371.155518 -267.928806) (xy 371.131945 -267.882538)
			(xy 371.1159 -267.833152) (xy 371.107777 -267.781864) (xy 371.107777 -267.729936) (xy 371.1159 -267.678648)
			(xy 371.131945 -267.629262) (xy 371.155518 -267.582994) (xy 371.186038 -267.540983) (xy 371.222754 -267.504263)
			(xy 371.264762 -267.473738) (xy 371.311027 -267.450159) (xy 371.360411 -267.434109) (xy 371.411698 -267.42598)
			(xy 371.437662 -267.425424) (xy 371.453123 -267.425631) (xy 371.483906 -267.428559) (xy 371.49913 -267.431266)
			(xy 371.513871 -267.433509) (xy 371.543504 -267.430329) (xy 371.570959 -267.418734) (xy 371.593901 -267.399711)
			(xy 371.610378 -267.374877) (xy 371.61899 -267.346345) (xy 371.619526 -267.331444) (xy 371.619526 -267.10386)
			(xy 371.613938 -267.092938) (xy 371.60241 -267.069431) (xy 371.586105 -267.019682) (xy 371.577849 -266.967984)
			(xy 371.577848 -266.915631) (xy 371.586102 -266.863932) (xy 371.602404 -266.814182) (xy 371.613938 -266.790678)
			(xy 371.619526 -266.779756) (xy 371.619526 -266.55268) (xy 371.619004 -266.537781) (xy 371.610394 -266.509254)
			(xy 371.593915 -266.484427) (xy 371.57097 -266.465416) (xy 371.543512 -266.453839) (xy 371.513882 -266.450684)
			(xy 371.49913 -266.452858) (xy 371.48391 -266.455586) (xy 371.453124 -266.458511) (xy 371.437662 -266.4587)
			(xy 371.411693 -266.458188) (xy 371.360396 -266.450058) (xy 371.311001 -266.434003) (xy 371.264726 -266.41042)
			(xy 371.22271 -266.379889) (xy 371.185986 -266.343161) (xy 371.15546 -266.301141) (xy 371.131882 -266.254864)
			(xy 371.115834 -266.205467) (xy 371.107709 -266.154169) (xy 371.107709 -266.102231) (xy 371.115834 -266.050933)
			(xy 371.131882 -266.001536) (xy 371.15546 -265.955259) (xy 371.185986 -265.913239) (xy 371.22271 -265.876511)
			(xy 371.264726 -265.84598) (xy 371.311001 -265.822397) (xy 371.360396 -265.806342) (xy 371.411693 -265.798212)
			(xy 371.437662 -265.797792) (xy 371.453123 -265.797999) (xy 371.483906 -265.800928) (xy 371.49913 -265.803634)
			(xy 371.513869 -265.805877) (xy 371.543499 -265.802697) (xy 371.570951 -265.791102) (xy 371.593888 -265.772077)
			(xy 371.610359 -265.747243) (xy 371.618962 -265.718712) (xy 371.619526 -265.703812) (xy 371.619526 -265.476228)
			(xy 371.613938 -265.465306) (xy 371.602412 -265.441799) (xy 371.586113 -265.392051) (xy 371.577862 -265.340354)
			(xy 371.577865 -265.288003) (xy 371.586123 -265.236308) (xy 371.602429 -265.186561) (xy 371.613938 -265.163046)
			(xy 371.619526 -265.152124) (xy 371.619526 -264.924794) (xy 371.619005 -264.909894) (xy 371.610399 -264.881363)
			(xy 371.59392 -264.856532) (xy 371.570973 -264.837518) (xy 371.543514 -264.82594) (xy 371.513881 -264.822784)
			(xy 371.49913 -264.824972) (xy 371.48391 -264.827701) (xy 371.453124 -264.830626) (xy 371.437662 -264.830814)
			(xy 371.4117 -264.830302) (xy 371.360416 -264.822174) (xy 371.311034 -264.806124) (xy 371.264771 -264.782547)
			(xy 371.222765 -264.752024) (xy 371.186052 -264.715306) (xy 371.155533 -264.673296) (xy 371.131962 -264.627031)
			(xy 371.115917 -264.577647) (xy 371.107795 -264.526362) (xy 371.107795 -264.474438) (xy 371.115917 -264.423153)
			(xy 371.131962 -264.373769) (xy 371.155533 -264.327504) (xy 371.186052 -264.285494) (xy 371.222765 -264.248776)
			(xy 371.264771 -264.218253) (xy 371.311034 -264.194676) (xy 371.360416 -264.178626) (xy 371.4117 -264.170498)
			(xy 371.437662 -264.169906) (xy 371.453123 -264.170113) (xy 371.483907 -264.173041) (xy 371.49913 -264.175748)
			(xy 371.51387 -264.177991) (xy 371.543501 -264.174811) (xy 371.570954 -264.163216) (xy 371.593894 -264.144192)
			(xy 371.610368 -264.119358) (xy 371.618975 -264.090827) (xy 371.619526 -264.075926) (xy 371.619526 -263.848596)
			(xy 371.613938 -263.837674) (xy 371.602407 -263.814167) (xy 371.586097 -263.764417) (xy 371.577835 -263.712717)
			(xy 371.577829 -263.660361) (xy 371.586078 -263.608659) (xy 371.602377 -263.558905) (xy 371.613938 -263.535414)
			(xy 371.619526 -263.524492) (xy 371.619526 -263.296908) (xy 371.619007 -263.282006) (xy 371.610403 -263.253472)
			(xy 371.593925 -263.228638) (xy 371.570977 -263.20962) (xy 371.543515 -263.19804) (xy 371.513879 -263.194884)
			(xy 371.49913 -263.197086) (xy 371.48391 -263.199815) (xy 371.453124 -263.20274) (xy 371.437662 -263.202928)
			(xy 371.411699 -263.202416) (xy 371.360412 -263.194288) (xy 371.311029 -263.178237) (xy 371.264764 -263.154659)
			(xy 371.222756 -263.124134) (xy 371.186041 -263.087415) (xy 371.155521 -263.045404) (xy 371.131949 -262.999136)
			(xy 371.115904 -262.949751) (xy 371.107781 -262.898463) (xy 371.107781 -262.846537) (xy 371.115904 -262.795249)
			(xy 371.131949 -262.745864) (xy 371.155521 -262.699596) (xy 371.186041 -262.657585) (xy 371.222756 -262.620866)
			(xy 371.264764 -262.590341) (xy 371.311029 -262.566763) (xy 371.360412 -262.550712) (xy 371.411699 -262.542584)
			(xy 371.437662 -262.54202) (xy 371.453123 -262.542227) (xy 371.483906 -262.545155) (xy 371.49913 -262.547862)
			(xy 371.513871 -262.550105) (xy 371.543503 -262.546925) (xy 371.570958 -262.53533) (xy 371.593899 -262.516307)
			(xy 371.610376 -262.491473) (xy 371.618986 -262.462941) (xy 371.619526 -262.44804) (xy 371.619526 -262.22071)
			(xy 371.613938 -262.209788) (xy 371.602414 -262.186282) (xy 371.586117 -262.136533) (xy 371.577869 -262.084837)
			(xy 371.577874 -262.032488) (xy 371.586135 -261.980794) (xy 371.602442 -261.931049) (xy 371.613938 -261.907528)
			(xy 371.619526 -261.896606) (xy 371.619526 -261.669276) (xy 371.619003 -261.654377) (xy 371.610393 -261.625851)
			(xy 371.593914 -261.601026) (xy 371.570969 -261.582015) (xy 371.543512 -261.570439) (xy 371.513882 -261.567284)
			(xy 371.49913 -261.569454) (xy 371.48391 -261.572183) (xy 371.453124 -261.575107) (xy 371.437662 -261.575296)
			(xy 371.411696 -261.574784) (xy 371.360403 -261.566655) (xy 371.311012 -261.550604) (xy 371.264741 -261.527025)
			(xy 371.222727 -261.496498) (xy 371.186004 -261.459776) (xy 371.155477 -261.417763) (xy 371.131898 -261.371491)
			(xy 371.115846 -261.322101) (xy 371.107716 -261.270808) (xy 371.107208 -261.244842) (xy 371.107665 -261.220223)
			(xy 371.114977 -261.171531) (xy 371.129429 -261.124462) (xy 371.150703 -261.080057) (xy 371.178328 -261.039299)
			(xy 371.211692 -261.003088) (xy 371.250058 -260.972227) (xy 371.292577 -260.947397) (xy 371.338308 -260.929148)
			(xy 371.38624 -260.917884) (xy 371.410738 -260.915404) (xy 371.425124 -260.91375) (xy 371.452173 -260.90345)
			(xy 371.475242 -260.885969) (xy 371.492475 -260.862715) (xy 371.502485 -260.835557) (xy 371.504467 -260.806681)
			(xy 371.498263 -260.77841) (xy 371.48437 -260.753019) (xy 371.474492 -260.74243) (xy 371.369844 -260.637782)
			(xy 371.359612 -260.628169) (xy 371.335119 -260.614469) (xy 371.307817 -260.607971) (xy 371.279779 -260.609167)
			(xy 371.25313 -260.617967) (xy 371.229893 -260.633703) (xy 371.220492 -260.644132) (xy 371.204699 -260.66214)
			(xy 371.16881 -260.693859) (xy 371.12872 -260.720067) (xy 371.085267 -260.740216) (xy 371.039362 -260.753883)
			(xy 370.991965 -260.760783) (xy 370.968016 -260.761226) (xy 370.942047 -260.760744) (xy 370.890747 -260.752621)
			(xy 370.84135 -260.736572) (xy 370.795073 -260.712993) (xy 370.753054 -260.682464) (xy 370.716328 -260.645737)
			(xy 370.685801 -260.603717) (xy 370.662223 -260.557439) (xy 370.646176 -260.508041) (xy 370.638055 -260.456741)
			(xy 370.637562 -260.430772) (xy 370.637934 -260.408163) (xy 370.644104 -260.363367) (xy 370.656324 -260.319831)
			(xy 370.664994 -260.298946) (xy 370.670305 -260.285531) (xy 370.673994 -260.256931) (xy 370.669539 -260.22844)
			(xy 370.657295 -260.20233) (xy 370.63824 -260.180685) (xy 370.613893 -260.165232) (xy 370.586195 -260.157203)
			(xy 370.571776 -260.156706) (xy 370.424456 -260.156706) (xy 370.410045 -260.15721) (xy 370.382371 -260.165269)
			(xy 370.358047 -260.180732) (xy 370.339007 -260.202371) (xy 370.326764 -260.228466) (xy 370.322293 -260.25694)
			(xy 370.325949 -260.285531) (xy 370.331238 -260.298946) (xy 370.33992 -260.319826) (xy 370.352139 -260.363364)
			(xy 370.358309 -260.408162) (xy 370.35867 -260.430772) (xy 370.358161 -260.456739) (xy 370.350036 -260.508034)
			(xy 370.333988 -260.557427) (xy 370.31041 -260.603701) (xy 370.279884 -260.645717) (xy 370.243161 -260.68244)
			(xy 370.201145 -260.712966) (xy 370.154871 -260.736544) (xy 370.105478 -260.752592) (xy 370.054183 -260.760717)
			(xy 370.002249 -260.760717) (xy 369.950954 -260.752592) (xy 369.901561 -260.736544) (xy 369.855287 -260.712966)
			(xy 369.813271 -260.68244) (xy 369.776548 -260.645717) (xy 369.746022 -260.603701) (xy 369.722444 -260.557427)
			(xy 369.706396 -260.508034) (xy 369.698271 -260.456739) (xy 369.697762 -260.430772) (xy 369.698134 -260.408163)
			(xy 369.704304 -260.363367) (xy 369.716524 -260.319831) (xy 369.725194 -260.298946) (xy 369.730505 -260.285531)
			(xy 369.734194 -260.256931) (xy 369.729739 -260.22844) (xy 369.717495 -260.20233) (xy 369.69844 -260.180685)
			(xy 369.674093 -260.165232) (xy 369.646395 -260.157203) (xy 369.631976 -260.156706) (xy 368.437414 -260.156706)
			(xy 367.323311 -261.270809) (xy 369.228117 -261.270809) (xy 369.228117 -261.218875) (xy 369.236242 -261.16758)
			(xy 369.25229 -261.118187) (xy 369.275868 -261.071913) (xy 369.306394 -261.029897) (xy 369.343117 -260.993174)
			(xy 369.385133 -260.962648) (xy 369.431407 -260.93907) (xy 369.4808 -260.923022) (xy 369.532095 -260.914897)
			(xy 369.584029 -260.914897) (xy 369.635324 -260.923022) (xy 369.684717 -260.93907) (xy 369.730991 -260.962648)
			(xy 369.773007 -260.993174) (xy 369.80973 -261.029897) (xy 369.840256 -261.071913) (xy 369.863834 -261.118187)
			(xy 369.879882 -261.16758) (xy 369.888007 -261.218875) (xy 369.888516 -261.244842) (xy 369.888007 -261.270809)
			(xy 370.167917 -261.270809) (xy 370.167917 -261.218875) (xy 370.176042 -261.16758) (xy 370.19209 -261.118187)
			(xy 370.215668 -261.071913) (xy 370.246194 -261.029897) (xy 370.282917 -260.993174) (xy 370.324933 -260.962648)
			(xy 370.371207 -260.93907) (xy 370.4206 -260.923022) (xy 370.471895 -260.914897) (xy 370.523829 -260.914897)
			(xy 370.575124 -260.923022) (xy 370.624517 -260.93907) (xy 370.670791 -260.962648) (xy 370.712807 -260.993174)
			(xy 370.74953 -261.029897) (xy 370.780056 -261.071913) (xy 370.803634 -261.118187) (xy 370.819682 -261.16758)
			(xy 370.827807 -261.218875) (xy 370.828316 -261.244842) (xy 370.827807 -261.270809) (xy 370.819682 -261.322104)
			(xy 370.803634 -261.371497) (xy 370.780056 -261.417771) (xy 370.74953 -261.459787) (xy 370.712807 -261.49651)
			(xy 370.670791 -261.527036) (xy 370.624517 -261.550614) (xy 370.575124 -261.566662) (xy 370.523829 -261.574787)
			(xy 370.471895 -261.574787) (xy 370.4206 -261.566662) (xy 370.371207 -261.550614) (xy 370.324933 -261.527036)
			(xy 370.282917 -261.49651) (xy 370.246194 -261.459787) (xy 370.215668 -261.417771) (xy 370.19209 -261.371497)
			(xy 370.176042 -261.322104) (xy 370.167917 -261.270809) (xy 369.888007 -261.270809) (xy 369.879882 -261.322104)
			(xy 369.863834 -261.371497) (xy 369.840256 -261.417771) (xy 369.80973 -261.459787) (xy 369.773007 -261.49651)
			(xy 369.730991 -261.527036) (xy 369.684717 -261.550614) (xy 369.635324 -261.566662) (xy 369.584029 -261.574787)
			(xy 369.532095 -261.574787) (xy 369.4808 -261.566662) (xy 369.431407 -261.550614) (xy 369.385133 -261.527036)
			(xy 369.343117 -261.49651) (xy 369.306394 -261.459787) (xy 369.275868 -261.417771) (xy 369.25229 -261.371497)
			(xy 369.236242 -261.322104) (xy 369.228117 -261.270809) (xy 367.323311 -261.270809) (xy 366.858296 -261.735824)
			(xy 364.59668 -261.735824) (xy 364.582451 -261.736299) (xy 364.555099 -261.744151) (xy 364.530971 -261.759242)
			(xy 364.511941 -261.780399) (xy 364.499482 -261.805985) (xy 364.49456 -261.834013) (xy 364.497559 -261.862313)
			(xy 364.508244 -261.888688) (xy 364.51667 -261.900162) (xy 364.5333 -261.922167) (xy 364.559763 -261.970558)
			(xy 364.577828 -262.022669) (xy 364.586993 -262.077055) (xy 364.587142 -262.084625) (xy 369.698271 -262.084625)
			(xy 369.698271 -262.032691) (xy 369.706396 -261.981396) (xy 369.722444 -261.932003) (xy 369.746022 -261.885729)
			(xy 369.776548 -261.843713) (xy 369.813271 -261.80699) (xy 369.855287 -261.776464) (xy 369.901561 -261.752886)
			(xy 369.950954 -261.736838) (xy 370.002249 -261.728713) (xy 370.054183 -261.728713) (xy 370.105478 -261.736838)
			(xy 370.154871 -261.752886) (xy 370.201145 -261.776464) (xy 370.243161 -261.80699) (xy 370.279884 -261.843713)
			(xy 370.31041 -261.885729) (xy 370.333988 -261.932003) (xy 370.350036 -261.981396) (xy 370.358161 -262.032691)
			(xy 370.35867 -262.058658) (xy 370.358161 -262.084625) (xy 370.637817 -262.084625) (xy 370.637817 -262.032691)
			(xy 370.645942 -261.981396) (xy 370.66199 -261.932003) (xy 370.685568 -261.885729) (xy 370.716094 -261.843713)
			(xy 370.752817 -261.80699) (xy 370.794833 -261.776464) (xy 370.841107 -261.752886) (xy 370.8905 -261.736838)
			(xy 370.941795 -261.728713) (xy 370.993729 -261.728713) (xy 371.045024 -261.736838) (xy 371.094417 -261.752886)
			(xy 371.140691 -261.776464) (xy 371.182707 -261.80699) (xy 371.21943 -261.843713) (xy 371.249956 -261.885729)
			(xy 371.273534 -261.932003) (xy 371.289582 -261.981396) (xy 371.297707 -262.032691) (xy 371.298216 -262.058658)
			(xy 371.297707 -262.084625) (xy 371.289582 -262.13592) (xy 371.273534 -262.185313) (xy 371.249956 -262.231587)
			(xy 371.21943 -262.273603) (xy 371.182707 -262.310326) (xy 371.140691 -262.340852) (xy 371.094417 -262.36443)
			(xy 371.045024 -262.380478) (xy 370.993729 -262.388603) (xy 370.941795 -262.388603) (xy 370.8905 -262.380478)
			(xy 370.841107 -262.36443) (xy 370.794833 -262.340852) (xy 370.752817 -262.310326) (xy 370.716094 -262.273603)
			(xy 370.685568 -262.231587) (xy 370.66199 -262.185313) (xy 370.645942 -262.13592) (xy 370.637817 -262.084625)
			(xy 370.358161 -262.084625) (xy 370.350036 -262.13592) (xy 370.333988 -262.185313) (xy 370.31041 -262.231587)
			(xy 370.279884 -262.273603) (xy 370.243161 -262.310326) (xy 370.201145 -262.340852) (xy 370.154871 -262.36443)
			(xy 370.105478 -262.380478) (xy 370.054183 -262.388603) (xy 370.002249 -262.388603) (xy 369.950954 -262.380478)
			(xy 369.901561 -262.36443) (xy 369.855287 -262.340852) (xy 369.813271 -262.310326) (xy 369.776548 -262.273603)
			(xy 369.746022 -262.231587) (xy 369.722444 -262.185313) (xy 369.706396 -262.13592) (xy 369.698271 -262.084625)
			(xy 364.587142 -262.084625) (xy 364.587536 -262.104632) (xy 364.586971 -262.131928) (xy 364.577987 -262.185776)
			(xy 364.56027 -262.237414) (xy 364.5343 -262.285434) (xy 364.500787 -262.328529) (xy 364.48111 -262.347456)
			(xy 364.471135 -262.357289) (xy 364.456517 -262.38117) (xy 364.448926 -262.408122) (xy 364.448932 -262.436122)
			(xy 364.456534 -262.46307) (xy 364.471162 -262.486945) (xy 364.48111 -262.496808) (xy 364.500804 -262.51572)
			(xy 364.534321 -262.558816) (xy 364.56029 -262.60684) (xy 364.578005 -262.658481) (xy 364.586982 -262.712334)
			(xy 364.587536 -262.739632) (xy 364.586941 -262.767657) (xy 364.577474 -262.822901) (xy 364.558817 -262.875755)
			(xy 364.531505 -262.9247) (xy 364.514384 -262.946896) (xy 364.506095 -262.957898) (xy 364.495165 -262.983169)
			(xy 364.491384 -263.010442) (xy 364.495027 -263.037734) (xy 364.50583 -263.06306) (xy 364.523006 -263.08458)
			(xy 364.545307 -263.100729) (xy 364.558072 -263.1059) (xy 364.587673 -263.11771) (xy 364.642032 -263.150961)
			(xy 364.666022 -263.17194) (xy 364.677511 -263.181743) (xy 364.704748 -263.194757) (xy 364.734602 -263.199225)
			(xy 364.764456 -263.194757) (xy 364.791693 -263.181743) (xy 364.803182 -263.17194) (xy 364.821585 -263.15568)
			(xy 364.862295 -263.128219) (xy 364.906618 -263.107081) (xy 364.953581 -263.09273) (xy 365.002149 -263.085483)
			(xy 365.026702 -263.085072) (xy 365.051256 -263.0855) (xy 365.099827 -263.092728) (xy 365.146793 -263.107069)
			(xy 365.191117 -263.128207) (xy 365.231822 -263.155676) (xy 365.250222 -263.17194) (xy 365.261711 -263.181743)
			(xy 365.288948 -263.194757) (xy 365.318802 -263.199225) (xy 365.348656 -263.194757) (xy 365.375893 -263.181743)
			(xy 365.387382 -263.17194) (xy 365.405785 -263.15568) (xy 365.446495 -263.128219) (xy 365.490818 -263.107081)
			(xy 365.537781 -263.09273) (xy 365.586349 -263.085483) (xy 365.610902 -263.085072) (xy 365.636867 -263.085581)
			(xy 365.688158 -263.093705) (xy 365.737546 -263.109753) (xy 365.783816 -263.133329) (xy 365.825829 -263.163853)
			(xy 365.862549 -263.200573) (xy 365.893072 -263.242585) (xy 365.916648 -263.288856) (xy 365.932695 -263.338244)
			(xy 365.940819 -263.389535) (xy 365.940819 -263.402123) (xy 366.329469 -263.402123) (xy 366.329469 -263.350189)
			(xy 366.337594 -263.298894) (xy 366.353642 -263.249501) (xy 366.37722 -263.203227) (xy 366.407746 -263.161211)
			(xy 366.444469 -263.124488) (xy 366.486485 -263.093962) (xy 366.532759 -263.070384) (xy 366.582152 -263.054336)
			(xy 366.633447 -263.046211) (xy 366.685381 -263.046211) (xy 366.736676 -263.054336) (xy 366.786069 -263.070384)
			(xy 366.832343 -263.093962) (xy 366.874359 -263.124488) (xy 366.911082 -263.161211) (xy 366.941608 -263.203227)
			(xy 366.965186 -263.249501) (xy 366.981234 -263.298894) (xy 366.981974 -263.303567) (xy 367.315759 -263.303567)
			(xy 367.315759 -263.251633) (xy 367.323883 -263.200339) (xy 367.339932 -263.150948) (xy 367.363509 -263.104675)
			(xy 367.394034 -263.062659) (xy 367.430756 -263.025937) (xy 367.472771 -262.995411) (xy 367.519044 -262.971833)
			(xy 367.568435 -262.955784) (xy 367.619729 -262.94766) (xy 367.645696 -262.94715) (xy 367.672209 -262.947689)
			(xy 367.724554 -262.956172) (xy 367.774866 -262.97292) (xy 367.798604 -262.984742) (xy 367.812288 -262.99133)
			(xy 367.842135 -262.996881) (xy 367.872296 -262.993424) (xy 367.900112 -262.981263) (xy 367.923131 -262.96147)
			(xy 367.9317 -262.948928) (xy 367.946989 -262.92579) (xy 367.984057 -262.884544) (xy 368.027492 -262.850066)
			(xy 368.076075 -262.823326) (xy 368.12844 -262.805073) (xy 368.183118 -262.795821) (xy 368.210846 -262.795258)
			(xy 368.236812 -262.795747) (xy 368.288103 -262.803877) (xy 368.337491 -262.81993) (xy 368.383761 -262.843511)
			(xy 368.425772 -262.87404) (xy 368.45017 -262.898441) (xy 369.228117 -262.898441) (xy 369.228117 -262.846507)
			(xy 369.236242 -262.795212) (xy 369.25229 -262.745819) (xy 369.275868 -262.699545) (xy 369.306394 -262.657529)
			(xy 369.343117 -262.620806) (xy 369.385133 -262.59028) (xy 369.431407 -262.566702) (xy 369.4808 -262.550654)
			(xy 369.532095 -262.542529) (xy 369.584029 -262.542529) (xy 369.635324 -262.550654) (xy 369.684717 -262.566702)
			(xy 369.730991 -262.59028) (xy 369.773007 -262.620806) (xy 369.80973 -262.657529) (xy 369.840256 -262.699545)
			(xy 369.863834 -262.745819) (xy 369.879882 -262.795212) (xy 369.888007 -262.846507) (xy 369.888516 -262.872474)
			(xy 369.888007 -262.898441) (xy 370.168171 -262.898441) (xy 370.168171 -262.846507) (xy 370.176296 -262.795212)
			(xy 370.192344 -262.745819) (xy 370.215922 -262.699545) (xy 370.246448 -262.657529) (xy 370.283171 -262.620806)
			(xy 370.325187 -262.59028) (xy 370.371461 -262.566702) (xy 370.420854 -262.550654) (xy 370.472149 -262.542529)
			(xy 370.524083 -262.542529) (xy 370.575378 -262.550654) (xy 370.624771 -262.566702) (xy 370.671045 -262.59028)
			(xy 370.713061 -262.620806) (xy 370.749784 -262.657529) (xy 370.78031 -262.699545) (xy 370.803888 -262.745819)
			(xy 370.819936 -262.795212) (xy 370.828061 -262.846507) (xy 370.82857 -262.872474) (xy 370.828061 -262.898441)
			(xy 370.819936 -262.949736) (xy 370.803888 -262.999129) (xy 370.78031 -263.045403) (xy 370.749784 -263.087419)
			(xy 370.713061 -263.124142) (xy 370.671045 -263.154668) (xy 370.624771 -263.178246) (xy 370.575378 -263.194294)
			(xy 370.524083 -263.202419) (xy 370.472149 -263.202419) (xy 370.420854 -263.194294) (xy 370.371461 -263.178246)
			(xy 370.325187 -263.154668) (xy 370.283171 -263.124142) (xy 370.246448 -263.087419) (xy 370.215922 -263.045403)
			(xy 370.192344 -262.999129) (xy 370.176296 -262.949736) (xy 370.168171 -262.898441) (xy 369.888007 -262.898441)
			(xy 369.879882 -262.949736) (xy 369.863834 -262.999129) (xy 369.840256 -263.045403) (xy 369.80973 -263.087419)
			(xy 369.773007 -263.124142) (xy 369.730991 -263.154668) (xy 369.684717 -263.178246) (xy 369.635324 -263.194294)
			(xy 369.584029 -263.202419) (xy 369.532095 -263.202419) (xy 369.4808 -263.194294) (xy 369.431407 -263.178246)
			(xy 369.385133 -263.154668) (xy 369.343117 -263.124142) (xy 369.306394 -263.087419) (xy 369.275868 -263.045403)
			(xy 369.25229 -262.999129) (xy 369.236242 -262.949736) (xy 369.228117 -262.898441) (xy 368.45017 -262.898441)
			(xy 368.46249 -262.910763) (xy 368.493013 -262.952779) (xy 368.516587 -262.999051) (xy 368.532634 -263.048442)
			(xy 368.540757 -263.099734) (xy 368.540757 -263.151666) (xy 368.532634 -263.202958) (xy 368.516587 -263.252349)
			(xy 368.493013 -263.298621) (xy 368.46249 -263.340637) (xy 368.425772 -263.37736) (xy 368.383761 -263.407889)
			(xy 368.337491 -263.43147) (xy 368.288103 -263.447523) (xy 368.236812 -263.455653) (xy 368.210846 -263.456166)
			(xy 368.184331 -263.455659) (xy 368.131986 -263.447164) (xy 368.081674 -263.430403) (xy 368.057938 -263.418574)
			(xy 368.044236 -263.412025) (xy 368.014398 -263.406464) (xy 367.984242 -263.409912) (xy 367.956428 -263.422064)
			(xy 367.933411 -263.44185) (xy 367.924842 -263.454388) (xy 367.909498 -263.477488) (xy 367.872444 -263.51874)
			(xy 367.829021 -263.553224) (xy 367.780449 -263.579972) (xy 367.728092 -263.598232) (xy 367.673421 -263.607492)
			(xy 367.645696 -263.608058) (xy 367.619729 -263.60754) (xy 367.568435 -263.599416) (xy 367.519044 -263.583367)
			(xy 367.472771 -263.559789) (xy 367.430756 -263.529263) (xy 367.394034 -263.492541) (xy 367.363509 -263.450525)
			(xy 367.339932 -263.404252) (xy 367.323883 -263.354861) (xy 367.315759 -263.303567) (xy 366.981974 -263.303567)
			(xy 366.989359 -263.350189) (xy 366.989868 -263.376156) (xy 366.989359 -263.402123) (xy 366.981234 -263.453418)
			(xy 366.965186 -263.502811) (xy 366.941608 -263.549085) (xy 366.911082 -263.591101) (xy 366.874359 -263.627824)
			(xy 366.832343 -263.65835) (xy 366.786069 -263.681928) (xy 366.736676 -263.697976) (xy 366.685381 -263.706101)
			(xy 366.633447 -263.706101) (xy 366.582152 -263.697976) (xy 366.532759 -263.681928) (xy 366.486485 -263.65835)
			(xy 366.444469 -263.627824) (xy 366.407746 -263.591101) (xy 366.37722 -263.549085) (xy 366.353642 -263.502811)
			(xy 366.337594 -263.453418) (xy 366.329469 -263.402123) (xy 365.940819 -263.402123) (xy 365.940819 -263.441465)
			(xy 365.932695 -263.492756) (xy 365.916648 -263.542144) (xy 365.893072 -263.588415) (xy 365.862549 -263.630427)
			(xy 365.825829 -263.667147) (xy 365.783816 -263.697671) (xy 365.754691 -263.712511) (xy 369.698271 -263.712511)
			(xy 369.698271 -263.660577) (xy 369.706396 -263.609282) (xy 369.722444 -263.559889) (xy 369.746022 -263.513615)
			(xy 369.776548 -263.471599) (xy 369.813271 -263.434876) (xy 369.855287 -263.40435) (xy 369.901561 -263.380772)
			(xy 369.950954 -263.364724) (xy 370.002249 -263.356599) (xy 370.054183 -263.356599) (xy 370.105478 -263.364724)
			(xy 370.154871 -263.380772) (xy 370.201145 -263.40435) (xy 370.243161 -263.434876) (xy 370.279884 -263.471599)
			(xy 370.31041 -263.513615) (xy 370.333988 -263.559889) (xy 370.350036 -263.609282) (xy 370.358161 -263.660577)
			(xy 370.35867 -263.686544) (xy 370.358161 -263.712511) (xy 370.637817 -263.712511) (xy 370.637817 -263.660577)
			(xy 370.645942 -263.609282) (xy 370.66199 -263.559889) (xy 370.685568 -263.513615) (xy 370.716094 -263.471599)
			(xy 370.752817 -263.434876) (xy 370.794833 -263.40435) (xy 370.841107 -263.380772) (xy 370.8905 -263.364724)
			(xy 370.941795 -263.356599) (xy 370.993729 -263.356599) (xy 371.045024 -263.364724) (xy 371.094417 -263.380772)
			(xy 371.140691 -263.40435) (xy 371.182707 -263.434876) (xy 371.21943 -263.471599) (xy 371.249956 -263.513615)
			(xy 371.273534 -263.559889) (xy 371.289582 -263.609282) (xy 371.297707 -263.660577) (xy 371.298216 -263.686544)
			(xy 371.297707 -263.712511) (xy 371.289582 -263.763806) (xy 371.273534 -263.813199) (xy 371.249956 -263.859473)
			(xy 371.21943 -263.901489) (xy 371.182707 -263.938212) (xy 371.140691 -263.968738) (xy 371.094417 -263.992316)
			(xy 371.045024 -264.008364) (xy 370.993729 -264.016489) (xy 370.941795 -264.016489) (xy 370.8905 -264.008364)
			(xy 370.841107 -263.992316) (xy 370.794833 -263.968738) (xy 370.752817 -263.938212) (xy 370.716094 -263.901489)
			(xy 370.685568 -263.859473) (xy 370.66199 -263.813199) (xy 370.645942 -263.763806) (xy 370.637817 -263.712511)
			(xy 370.358161 -263.712511) (xy 370.350036 -263.763806) (xy 370.333988 -263.813199) (xy 370.31041 -263.859473)
			(xy 370.279884 -263.901489) (xy 370.243161 -263.938212) (xy 370.201145 -263.968738) (xy 370.154871 -263.992316)
			(xy 370.105478 -264.008364) (xy 370.054183 -264.016489) (xy 370.002249 -264.016489) (xy 369.950954 -264.008364)
			(xy 369.901561 -263.992316) (xy 369.855287 -263.968738) (xy 369.813271 -263.938212) (xy 369.776548 -263.901489)
			(xy 369.746022 -263.859473) (xy 369.722444 -263.813199) (xy 369.706396 -263.763806) (xy 369.698271 -263.712511)
			(xy 365.754691 -263.712511) (xy 365.737546 -263.721247) (xy 365.688158 -263.737295) (xy 365.636867 -263.745419)
			(xy 365.610902 -263.74598) (xy 365.586348 -263.745553) (xy 365.537775 -263.738326) (xy 365.490808 -263.723987)
			(xy 365.446481 -263.702852) (xy 365.405773 -263.675386) (xy 365.387382 -263.659112) (xy 365.375893 -263.649309)
			(xy 365.348656 -263.636295) (xy 365.318802 -263.631827) (xy 365.288948 -263.636295) (xy 365.261711 -263.649309)
			(xy 365.250222 -263.659112) (xy 365.23182 -263.675374) (xy 365.191111 -263.702839) (xy 365.146788 -263.723981)
			(xy 365.099825 -263.738335) (xy 365.051256 -263.745584) (xy 365.026702 -263.74598) (xy 365.002148 -263.745553)
			(xy 364.953575 -263.738326) (xy 364.906608 -263.723987) (xy 364.862281 -263.702852) (xy 364.821573 -263.675386)
			(xy 364.803182 -263.659112) (xy 364.791693 -263.649309) (xy 364.764456 -263.636295) (xy 364.734602 -263.631827)
			(xy 364.704748 -263.636295) (xy 364.677511 -263.649309) (xy 364.666022 -263.659112) (xy 364.64762 -263.675374)
			(xy 364.606911 -263.702839) (xy 364.562588 -263.723981) (xy 364.515625 -263.738335) (xy 364.467056 -263.745584)
			(xy 364.442502 -263.74598) (xy 364.416534 -263.745471) (xy 364.365237 -263.737347) (xy 364.315843 -263.721299)
			(xy 364.269567 -263.697722) (xy 364.227548 -263.667196) (xy 364.190822 -263.630473) (xy 364.160293 -263.588457)
			(xy 364.136712 -263.542183) (xy 364.12066 -263.49279) (xy 364.112531 -263.441494) (xy 364.112048 -263.415526)
			(xy 364.112638 -263.387499) (xy 364.122096 -263.33225) (xy 364.140746 -263.27939) (xy 364.168051 -263.230437)
			(xy 364.1852 -263.208262) (xy 364.193483 -263.197262) (xy 364.204403 -263.171997) (xy 364.208176 -263.144732)
			(xy 364.204528 -263.117451) (xy 364.193723 -263.092136) (xy 364.176546 -263.070629) (xy 364.154248 -263.054492)
			(xy 364.141512 -263.049258) (xy 364.118177 -263.040055) (xy 364.074371 -263.015619) (xy 364.034762 -262.984843)
			(xy 364.00026 -262.948433) (xy 363.971658 -262.907226) (xy 363.949614 -262.862169) (xy 363.934633 -262.814298)
			(xy 363.927062 -262.764712) (xy 363.926628 -262.739632) (xy 363.927188 -262.712333) (xy 363.936162 -262.658479)
			(xy 363.953871 -262.606833) (xy 363.979832 -262.558804) (xy 364.01334 -262.515698) (xy 364.033054 -262.496808)
			(xy 364.043041 -262.486976) (xy 364.057681 -262.463091) (xy 364.06529 -262.436129) (xy 364.065296 -262.408114)
			(xy 364.057699 -262.381149) (xy 364.043069 -262.357257) (xy 364.033054 -262.347456) (xy 364.013364 -262.328543)
			(xy 363.979856 -262.285444) (xy 363.953894 -262.23742) (xy 363.936187 -262.185779) (xy 363.927217 -262.131928)
			(xy 363.926628 -262.104632) (xy 363.927179 -262.077055) (xy 363.936333 -262.022666) (xy 363.954392 -261.970552)
			(xy 363.980855 -261.92216) (xy 363.997494 -261.900162) (xy 364.005915 -261.888674) (xy 364.016639 -261.862297)
			(xy 364.019663 -261.833986) (xy 364.014753 -261.805939) (xy 364.002291 -261.780339) (xy 363.983245 -261.759174)
			(xy 363.959096 -261.744091) (xy 363.931721 -261.736261) (xy 363.917484 -261.735824) (xy 362.880656 -261.735824)
			(xy 362.867243 -261.736236) (xy 362.841345 -261.743231) (xy 362.818161 -261.756727) (xy 362.799289 -261.775793)
			(xy 362.786032 -261.799114) (xy 362.779303 -261.825083) (xy 362.779567 -261.851908) (xy 362.786805 -261.877739)
			(xy 362.79328 -261.889494) (xy 362.807898 -261.915269) (xy 362.828717 -261.970741) (xy 362.839317 -262.029034)
			(xy 362.840016 -262.058658) (xy 362.839507 -262.084625) (xy 362.831382 -262.13592) (xy 362.815334 -262.185313)
			(xy 362.791756 -262.231587) (xy 362.76123 -262.273603) (xy 362.724507 -262.310326) (xy 362.682491 -262.340852)
			(xy 362.636217 -262.36443) (xy 362.586824 -262.380478) (xy 362.535529 -262.388603) (xy 362.483595 -262.388603)
			(xy 362.4323 -262.380478) (xy 362.382907 -262.36443) (xy 362.336633 -262.340852) (xy 362.294617 -262.310326)
			(xy 362.257894 -262.273603) (xy 362.227368 -262.231587) (xy 362.20379 -262.185313) (xy 362.187742 -262.13592)
			(xy 362.179617 -262.084625) (xy 362.179108 -262.058658) (xy 362.17979 -262.029033) (xy 362.190395 -261.970738)
			(xy 362.211221 -261.915268) (xy 362.225844 -261.889494) (xy 362.232376 -261.877756) (xy 362.239655 -261.851908)
			(xy 362.239942 -261.825056) (xy 362.233218 -261.799058) (xy 362.219947 -261.775713) (xy 362.201048 -261.756636)
			(xy 362.177829 -261.743147) (xy 362.151895 -261.736178) (xy 362.138468 -261.735824) (xy 361.940856 -261.735824)
			(xy 361.927443 -261.736236) (xy 361.901545 -261.743231) (xy 361.878361 -261.756727) (xy 361.859489 -261.775793)
			(xy 361.846232 -261.799114) (xy 361.839503 -261.825083) (xy 361.839767 -261.851908) (xy 361.847005 -261.877739)
			(xy 361.85348 -261.889494) (xy 361.868098 -261.915269) (xy 361.888917 -261.970741) (xy 361.899517 -262.029034)
			(xy 361.900216 -262.058658) (xy 361.899707 -262.084625) (xy 361.891582 -262.13592) (xy 361.875534 -262.185313)
			(xy 361.851956 -262.231587) (xy 361.82143 -262.273603) (xy 361.784707 -262.310326) (xy 361.742691 -262.340852)
			(xy 361.696417 -262.36443) (xy 361.647024 -262.380478) (xy 361.595729 -262.388603) (xy 361.543795 -262.388603)
			(xy 361.4925 -262.380478) (xy 361.443107 -262.36443) (xy 361.396833 -262.340852) (xy 361.354817 -262.310326)
			(xy 361.318094 -262.273603) (xy 361.287568 -262.231587) (xy 361.26399 -262.185313) (xy 361.247942 -262.13592)
			(xy 361.239817 -262.084625) (xy 361.239308 -262.058658) (xy 361.23999 -262.029033) (xy 361.250595 -261.970738)
			(xy 361.271421 -261.915268) (xy 361.286044 -261.889494) (xy 361.292576 -261.877756) (xy 361.299855 -261.851908)
			(xy 361.300142 -261.825056) (xy 361.293418 -261.799058) (xy 361.280147 -261.775713) (xy 361.261248 -261.756636)
			(xy 361.238029 -261.743147) (xy 361.212095 -261.736178) (xy 361.198668 -261.735824) (xy 361.001056 -261.735824)
			(xy 360.987643 -261.736236) (xy 360.961745 -261.743231) (xy 360.938561 -261.756727) (xy 360.919689 -261.775793)
			(xy 360.906432 -261.799114) (xy 360.899703 -261.825083) (xy 360.899967 -261.851908) (xy 360.907205 -261.877739)
			(xy 360.91368 -261.889494) (xy 360.928298 -261.915269) (xy 360.949117 -261.970741) (xy 360.959717 -262.029034)
			(xy 360.960416 -262.058658) (xy 360.959907 -262.084625) (xy 360.951782 -262.13592) (xy 360.935734 -262.185313)
			(xy 360.912156 -262.231587) (xy 360.88163 -262.273603) (xy 360.844907 -262.310326) (xy 360.802891 -262.340852)
			(xy 360.756617 -262.36443) (xy 360.707224 -262.380478) (xy 360.655929 -262.388603) (xy 360.603995 -262.388603)
			(xy 360.5527 -262.380478) (xy 360.503307 -262.36443) (xy 360.457033 -262.340852) (xy 360.415017 -262.310326)
			(xy 360.378294 -262.273603) (xy 360.347768 -262.231587) (xy 360.32419 -262.185313) (xy 360.308142 -262.13592)
			(xy 360.300017 -262.084625) (xy 360.299508 -262.058658) (xy 360.30019 -262.029033) (xy 360.310795 -261.970738)
			(xy 360.331621 -261.915268) (xy 360.346244 -261.889494) (xy 360.352776 -261.877756) (xy 360.360055 -261.851908)
			(xy 360.360342 -261.825056) (xy 360.353618 -261.799058) (xy 360.340347 -261.775713) (xy 360.321448 -261.756636)
			(xy 360.298229 -261.743147) (xy 360.272295 -261.736178) (xy 360.258868 -261.735824) (xy 360.061256 -261.735824)
			(xy 360.047843 -261.736236) (xy 360.021945 -261.743231) (xy 359.998761 -261.756727) (xy 359.979889 -261.775793)
			(xy 359.966632 -261.799114) (xy 359.959903 -261.825083) (xy 359.960167 -261.851908) (xy 359.967405 -261.877739)
			(xy 359.97388 -261.889494) (xy 359.988498 -261.915269) (xy 360.009317 -261.970741) (xy 360.019917 -262.029034)
			(xy 360.020616 -262.058658) (xy 360.020107 -262.084625) (xy 360.011982 -262.13592) (xy 359.995934 -262.185313)
			(xy 359.972356 -262.231587) (xy 359.94183 -262.273603) (xy 359.905107 -262.310326) (xy 359.863091 -262.340852)
			(xy 359.816817 -262.36443) (xy 359.767424 -262.380478) (xy 359.716129 -262.388603) (xy 359.664195 -262.388603)
			(xy 359.6129 -262.380478) (xy 359.563507 -262.36443) (xy 359.517233 -262.340852) (xy 359.475217 -262.310326)
			(xy 359.438494 -262.273603) (xy 359.407968 -262.231587) (xy 359.38439 -262.185313) (xy 359.368342 -262.13592)
			(xy 359.360217 -262.084625) (xy 359.359708 -262.058658) (xy 359.36039 -262.029033) (xy 359.370995 -261.970738)
			(xy 359.391821 -261.915268) (xy 359.406444 -261.889494) (xy 359.412976 -261.877756) (xy 359.420255 -261.851908)
			(xy 359.420542 -261.825056) (xy 359.413818 -261.799058) (xy 359.400547 -261.775713) (xy 359.381648 -261.756636)
			(xy 359.358429 -261.743147) (xy 359.332495 -261.736178) (xy 359.319068 -261.735824) (xy 359.238804 -261.735824)
			(xy 359.237026 -261.737602) (xy 359.122726 -261.737602) (xy 359.107415 -261.738105) (xy 359.07816 -261.747145)
			(xy 359.052899 -261.764451) (xy 359.033904 -261.788468) (xy 359.022881 -261.817036) (xy 359.020823 -261.847587)
			(xy 359.027913 -261.877375) (xy 359.03535 -261.890764) (xy 359.049696 -261.916396) (xy 359.070083 -261.971477)
			(xy 359.080434 -262.029291) (xy 359.08107 -262.058658) (xy 359.080561 -262.084625) (xy 359.072436 -262.13592)
			(xy 359.056388 -262.185313) (xy 359.03281 -262.231587) (xy 359.002284 -262.273603) (xy 358.965561 -262.310326)
			(xy 358.923545 -262.340852) (xy 358.877271 -262.36443) (xy 358.827878 -262.380478) (xy 358.776583 -262.388603)
			(xy 358.724649 -262.388603) (xy 358.673354 -262.380478) (xy 358.623961 -262.36443) (xy 358.577687 -262.340852)
			(xy 358.535671 -262.310326) (xy 358.498948 -262.273603) (xy 358.468422 -262.231587) (xy 358.444844 -262.185313)
			(xy 358.428796 -262.13592) (xy 358.420671 -262.084625) (xy 358.420162 -262.058658) (xy 358.42077 -262.029288)
			(xy 358.431103 -261.971464) (xy 358.451505 -261.916382) (xy 358.465882 -261.890764) (xy 358.473194 -261.877327)
			(xy 358.480224 -261.847568) (xy 358.478142 -261.817061) (xy 358.467134 -261.788534) (xy 358.448184 -261.764535)
			(xy 358.422987 -261.747212) (xy 358.393794 -261.738113) (xy 358.378506 -261.737602) (xy 358.182672 -261.737602)
			(xy 358.167367 -261.738112) (xy 358.138127 -261.747161) (xy 358.112881 -261.764468) (xy 358.093897 -261.788479)
			(xy 358.082881 -261.817037) (xy 358.080822 -261.847577) (xy 358.087905 -261.877355) (xy 358.095296 -261.890764)
			(xy 358.109644 -261.916395) (xy 358.130035 -261.971476) (xy 358.140388 -262.029291) (xy 358.141016 -262.058658)
			(xy 358.140536 -262.084628) (xy 358.132416 -262.13593) (xy 358.11637 -262.18533) (xy 358.092792 -262.231611)
			(xy 358.062263 -262.273633) (xy 358.025536 -262.31036) (xy 357.983514 -262.340889) (xy 357.937234 -262.364468)
			(xy 357.887834 -262.380515) (xy 357.836532 -262.388636) (xy 357.810562 -262.389112) (xy 357.784002 -262.388579)
			(xy 357.731567 -262.380077) (xy 357.681166 -262.363298) (xy 357.634099 -262.338673) (xy 357.591575 -262.306838)
			(xy 357.554691 -262.268611) (xy 357.524396 -262.224976) (xy 357.50147 -262.177058) (xy 357.486503 -262.12609)
			(xy 357.482648 -262.099806) (xy 357.480443 -262.085754) (xy 357.469319 -262.059589) (xy 357.451408 -262.037509)
			(xy 357.428099 -262.021229) (xy 357.401203 -262.012013) (xy 357.372807 -262.010576) (xy 357.345118 -262.017031)
			(xy 357.320285 -262.030876) (xy 357.309928 -262.040624) (xy 356.93096 -262.419592) (xy 356.938834 -262.44804)
			(xy 356.944293 -262.469406) (xy 356.950158 -262.513113) (xy 356.950518 -262.535162) (xy 356.950038 -262.561132)
			(xy 356.941917 -262.612434) (xy 356.92587 -262.661833) (xy 356.902292 -262.708113) (xy 356.871764 -262.750135)
			(xy 356.835036 -262.786862) (xy 356.793015 -262.817391) (xy 356.746735 -262.84097) (xy 356.697336 -262.857017)
			(xy 356.646034 -262.865138) (xy 356.620064 -262.865616) (xy 356.598015 -262.865248) (xy 356.55431 -262.859382)
			(xy 356.532942 -262.853932) (xy 356.504494 -262.846058) (xy 356.452111 -262.898441) (xy 357.010717 -262.898441)
			(xy 357.010717 -262.846507) (xy 357.018842 -262.795212) (xy 357.03489 -262.745819) (xy 357.058468 -262.699545)
			(xy 357.088994 -262.657529) (xy 357.125717 -262.620806) (xy 357.167733 -262.59028) (xy 357.214007 -262.566702)
			(xy 357.2634 -262.550654) (xy 357.314695 -262.542529) (xy 357.366629 -262.542529) (xy 357.417924 -262.550654)
			(xy 357.467317 -262.566702) (xy 357.513591 -262.59028) (xy 357.555607 -262.620806) (xy 357.59233 -262.657529)
			(xy 357.622856 -262.699545) (xy 357.646434 -262.745819) (xy 357.662482 -262.795212) (xy 357.670607 -262.846507)
			(xy 357.671116 -262.872474) (xy 357.670607 -262.898441) (xy 357.950517 -262.898441) (xy 357.950517 -262.846507)
			(xy 357.958642 -262.795212) (xy 357.97469 -262.745819) (xy 357.998268 -262.699545) (xy 358.028794 -262.657529)
			(xy 358.065517 -262.620806) (xy 358.107533 -262.59028) (xy 358.153807 -262.566702) (xy 358.2032 -262.550654)
			(xy 358.254495 -262.542529) (xy 358.306429 -262.542529) (xy 358.357724 -262.550654) (xy 358.407117 -262.566702)
			(xy 358.453391 -262.59028) (xy 358.495407 -262.620806) (xy 358.53213 -262.657529) (xy 358.562656 -262.699545)
			(xy 358.586234 -262.745819) (xy 358.602282 -262.795212) (xy 358.610407 -262.846507) (xy 358.610916 -262.872474)
			(xy 358.610407 -262.898441) (xy 358.890571 -262.898441) (xy 358.890571 -262.846507) (xy 358.898696 -262.795212)
			(xy 358.914744 -262.745819) (xy 358.938322 -262.699545) (xy 358.968848 -262.657529) (xy 359.005571 -262.620806)
			(xy 359.047587 -262.59028) (xy 359.093861 -262.566702) (xy 359.143254 -262.550654) (xy 359.194549 -262.542529)
			(xy 359.246483 -262.542529) (xy 359.297778 -262.550654) (xy 359.347171 -262.566702) (xy 359.393445 -262.59028)
			(xy 359.435461 -262.620806) (xy 359.472184 -262.657529) (xy 359.50271 -262.699545) (xy 359.526288 -262.745819)
			(xy 359.542336 -262.795212) (xy 359.550461 -262.846507) (xy 359.55097 -262.872474) (xy 359.550461 -262.898441)
			(xy 359.830371 -262.898441) (xy 359.830371 -262.846507) (xy 359.838496 -262.795212) (xy 359.854544 -262.745819)
			(xy 359.878122 -262.699545) (xy 359.908648 -262.657529) (xy 359.945371 -262.620806) (xy 359.987387 -262.59028)
			(xy 360.033661 -262.566702) (xy 360.083054 -262.550654) (xy 360.134349 -262.542529) (xy 360.186283 -262.542529)
			(xy 360.237578 -262.550654) (xy 360.286971 -262.566702) (xy 360.333245 -262.59028) (xy 360.375261 -262.620806)
			(xy 360.411984 -262.657529) (xy 360.44251 -262.699545) (xy 360.466088 -262.745819) (xy 360.482136 -262.795212)
			(xy 360.490261 -262.846507) (xy 360.49077 -262.872474) (xy 360.490261 -262.898441) (xy 360.769917 -262.898441)
			(xy 360.769917 -262.846507) (xy 360.778042 -262.795212) (xy 360.79409 -262.745819) (xy 360.817668 -262.699545)
			(xy 360.848194 -262.657529) (xy 360.884917 -262.620806) (xy 360.926933 -262.59028) (xy 360.973207 -262.566702)
			(xy 361.0226 -262.550654) (xy 361.073895 -262.542529) (xy 361.125829 -262.542529) (xy 361.177124 -262.550654)
			(xy 361.226517 -262.566702) (xy 361.272791 -262.59028) (xy 361.314807 -262.620806) (xy 361.35153 -262.657529)
			(xy 361.382056 -262.699545) (xy 361.405634 -262.745819) (xy 361.421682 -262.795212) (xy 361.429807 -262.846507)
			(xy 361.430316 -262.872474) (xy 361.429807 -262.898441) (xy 361.709971 -262.898441) (xy 361.709971 -262.846507)
			(xy 361.718096 -262.795212) (xy 361.734144 -262.745819) (xy 361.757722 -262.699545) (xy 361.788248 -262.657529)
			(xy 361.824971 -262.620806) (xy 361.866987 -262.59028) (xy 361.913261 -262.566702) (xy 361.962654 -262.550654)
			(xy 362.013949 -262.542529) (xy 362.065883 -262.542529) (xy 362.117178 -262.550654) (xy 362.166571 -262.566702)
			(xy 362.212845 -262.59028) (xy 362.254861 -262.620806) (xy 362.291584 -262.657529) (xy 362.32211 -262.699545)
			(xy 362.345688 -262.745819) (xy 362.361736 -262.795212) (xy 362.369861 -262.846507) (xy 362.37037 -262.872474)
			(xy 362.369861 -262.898441) (xy 362.361736 -262.949736) (xy 362.345688 -262.999129) (xy 362.32211 -263.045403)
			(xy 362.291584 -263.087419) (xy 362.254861 -263.124142) (xy 362.212845 -263.154668) (xy 362.166571 -263.178246)
			(xy 362.117178 -263.194294) (xy 362.065883 -263.202419) (xy 362.013949 -263.202419) (xy 361.962654 -263.194294)
			(xy 361.913261 -263.178246) (xy 361.866987 -263.154668) (xy 361.824971 -263.124142) (xy 361.788248 -263.087419)
			(xy 361.757722 -263.045403) (xy 361.734144 -262.999129) (xy 361.718096 -262.949736) (xy 361.709971 -262.898441)
			(xy 361.429807 -262.898441) (xy 361.421682 -262.949736) (xy 361.405634 -262.999129) (xy 361.382056 -263.045403)
			(xy 361.35153 -263.087419) (xy 361.314807 -263.124142) (xy 361.272791 -263.154668) (xy 361.226517 -263.178246)
			(xy 361.177124 -263.194294) (xy 361.125829 -263.202419) (xy 361.073895 -263.202419) (xy 361.0226 -263.194294)
			(xy 360.973207 -263.178246) (xy 360.926933 -263.154668) (xy 360.884917 -263.124142) (xy 360.848194 -263.087419)
			(xy 360.817668 -263.045403) (xy 360.79409 -262.999129) (xy 360.778042 -262.949736) (xy 360.769917 -262.898441)
			(xy 360.490261 -262.898441) (xy 360.482136 -262.949736) (xy 360.466088 -262.999129) (xy 360.44251 -263.045403)
			(xy 360.411984 -263.087419) (xy 360.375261 -263.124142) (xy 360.333245 -263.154668) (xy 360.286971 -263.178246)
			(xy 360.237578 -263.194294) (xy 360.186283 -263.202419) (xy 360.134349 -263.202419) (xy 360.083054 -263.194294)
			(xy 360.033661 -263.178246) (xy 359.987387 -263.154668) (xy 359.945371 -263.124142) (xy 359.908648 -263.087419)
			(xy 359.878122 -263.045403) (xy 359.854544 -262.999129) (xy 359.838496 -262.949736) (xy 359.830371 -262.898441)
			(xy 359.550461 -262.898441) (xy 359.542336 -262.949736) (xy 359.526288 -262.999129) (xy 359.50271 -263.045403)
			(xy 359.472184 -263.087419) (xy 359.435461 -263.124142) (xy 359.393445 -263.154668) (xy 359.347171 -263.178246)
			(xy 359.297778 -263.194294) (xy 359.246483 -263.202419) (xy 359.194549 -263.202419) (xy 359.143254 -263.194294)
			(xy 359.093861 -263.178246) (xy 359.047587 -263.154668) (xy 359.005571 -263.124142) (xy 358.968848 -263.087419)
			(xy 358.938322 -263.045403) (xy 358.914744 -262.999129) (xy 358.898696 -262.949736) (xy 358.890571 -262.898441)
			(xy 358.610407 -262.898441) (xy 358.602282 -262.949736) (xy 358.586234 -262.999129) (xy 358.562656 -263.045403)
			(xy 358.53213 -263.087419) (xy 358.495407 -263.124142) (xy 358.453391 -263.154668) (xy 358.407117 -263.178246)
			(xy 358.357724 -263.194294) (xy 358.306429 -263.202419) (xy 358.254495 -263.202419) (xy 358.2032 -263.194294)
			(xy 358.153807 -263.178246) (xy 358.107533 -263.154668) (xy 358.065517 -263.124142) (xy 358.028794 -263.087419)
			(xy 357.998268 -263.045403) (xy 357.97469 -262.999129) (xy 357.958642 -262.949736) (xy 357.950517 -262.898441)
			(xy 357.670607 -262.898441) (xy 357.662482 -262.949736) (xy 357.646434 -262.999129) (xy 357.622856 -263.045403)
			(xy 357.59233 -263.087419) (xy 357.555607 -263.124142) (xy 357.513591 -263.154668) (xy 357.467317 -263.178246)
			(xy 357.417924 -263.194294) (xy 357.366629 -263.202419) (xy 357.314695 -263.202419) (xy 357.2634 -263.194294)
			(xy 357.214007 -263.178246) (xy 357.167733 -263.154668) (xy 357.125717 -263.124142) (xy 357.088994 -263.087419)
			(xy 357.058468 -263.045403) (xy 357.03489 -262.999129) (xy 357.018842 -262.949736) (xy 357.010717 -262.898441)
			(xy 356.452111 -262.898441) (xy 355.638041 -263.712511) (xy 357.480617 -263.712511) (xy 357.480617 -263.660577)
			(xy 357.488742 -263.609282) (xy 357.50479 -263.559889) (xy 357.528368 -263.513615) (xy 357.558894 -263.471599)
			(xy 357.595617 -263.434876) (xy 357.637633 -263.40435) (xy 357.683907 -263.380772) (xy 357.7333 -263.364724)
			(xy 357.784595 -263.356599) (xy 357.836529 -263.356599) (xy 357.887824 -263.364724) (xy 357.937217 -263.380772)
			(xy 357.983491 -263.40435) (xy 358.025507 -263.434876) (xy 358.06223 -263.471599) (xy 358.092756 -263.513615)
			(xy 358.116334 -263.559889) (xy 358.132382 -263.609282) (xy 358.140507 -263.660577) (xy 358.141016 -263.686544)
			(xy 358.140507 -263.712511) (xy 358.420417 -263.712511) (xy 358.420417 -263.660577) (xy 358.428542 -263.609282)
			(xy 358.44459 -263.559889) (xy 358.468168 -263.513615) (xy 358.498694 -263.471599) (xy 358.535417 -263.434876)
			(xy 358.577433 -263.40435) (xy 358.623707 -263.380772) (xy 358.6731 -263.364724) (xy 358.724395 -263.356599)
			(xy 358.776329 -263.356599) (xy 358.827624 -263.364724) (xy 358.877017 -263.380772) (xy 358.923291 -263.40435)
			(xy 358.965307 -263.434876) (xy 359.00203 -263.471599) (xy 359.032556 -263.513615) (xy 359.056134 -263.559889)
			(xy 359.072182 -263.609282) (xy 359.080307 -263.660577) (xy 359.080816 -263.686544) (xy 359.080307 -263.712511)
			(xy 359.360217 -263.712511) (xy 359.360217 -263.660577) (xy 359.368342 -263.609282) (xy 359.38439 -263.559889)
			(xy 359.407968 -263.513615) (xy 359.438494 -263.471599) (xy 359.475217 -263.434876) (xy 359.517233 -263.40435)
			(xy 359.563507 -263.380772) (xy 359.6129 -263.364724) (xy 359.664195 -263.356599) (xy 359.716129 -263.356599)
			(xy 359.767424 -263.364724) (xy 359.816817 -263.380772) (xy 359.863091 -263.40435) (xy 359.905107 -263.434876)
			(xy 359.94183 -263.471599) (xy 359.972356 -263.513615) (xy 359.995934 -263.559889) (xy 360.011982 -263.609282)
			(xy 360.020107 -263.660577) (xy 360.020616 -263.686544) (xy 360.020107 -263.712511) (xy 360.300017 -263.712511)
			(xy 360.300017 -263.660577) (xy 360.308142 -263.609282) (xy 360.32419 -263.559889) (xy 360.347768 -263.513615)
			(xy 360.378294 -263.471599) (xy 360.415017 -263.434876) (xy 360.457033 -263.40435) (xy 360.503307 -263.380772)
			(xy 360.5527 -263.364724) (xy 360.603995 -263.356599) (xy 360.655929 -263.356599) (xy 360.707224 -263.364724)
			(xy 360.756617 -263.380772) (xy 360.802891 -263.40435) (xy 360.844907 -263.434876) (xy 360.88163 -263.471599)
			(xy 360.912156 -263.513615) (xy 360.935734 -263.559889) (xy 360.951782 -263.609282) (xy 360.959907 -263.660577)
			(xy 360.960416 -263.686544) (xy 360.959907 -263.712511) (xy 361.239817 -263.712511) (xy 361.239817 -263.660577)
			(xy 361.247942 -263.609282) (xy 361.26399 -263.559889) (xy 361.287568 -263.513615) (xy 361.318094 -263.471599)
			(xy 361.354817 -263.434876) (xy 361.396833 -263.40435) (xy 361.443107 -263.380772) (xy 361.4925 -263.364724)
			(xy 361.543795 -263.356599) (xy 361.595729 -263.356599) (xy 361.647024 -263.364724) (xy 361.696417 -263.380772)
			(xy 361.742691 -263.40435) (xy 361.784707 -263.434876) (xy 361.82143 -263.471599) (xy 361.851956 -263.513615)
			(xy 361.875534 -263.559889) (xy 361.891582 -263.609282) (xy 361.899707 -263.660577) (xy 361.900216 -263.686544)
			(xy 361.899707 -263.712511) (xy 362.179617 -263.712511) (xy 362.179617 -263.660577) (xy 362.187742 -263.609282)
			(xy 362.20379 -263.559889) (xy 362.227368 -263.513615) (xy 362.257894 -263.471599) (xy 362.294617 -263.434876)
			(xy 362.336633 -263.40435) (xy 362.382907 -263.380772) (xy 362.4323 -263.364724) (xy 362.483595 -263.356599)
			(xy 362.535529 -263.356599) (xy 362.586824 -263.364724) (xy 362.636217 -263.380772) (xy 362.682491 -263.40435)
			(xy 362.724507 -263.434876) (xy 362.76123 -263.471599) (xy 362.791756 -263.513615) (xy 362.815334 -263.559889)
			(xy 362.831382 -263.609282) (xy 362.839507 -263.660577) (xy 362.840016 -263.686544) (xy 362.839507 -263.712511)
			(xy 363.119671 -263.712511) (xy 363.119671 -263.660577) (xy 363.127796 -263.609282) (xy 363.143844 -263.559889)
			(xy 363.167422 -263.513615) (xy 363.197948 -263.471599) (xy 363.234671 -263.434876) (xy 363.276687 -263.40435)
			(xy 363.322961 -263.380772) (xy 363.372354 -263.364724) (xy 363.423649 -263.356599) (xy 363.475583 -263.356599)
			(xy 363.526878 -263.364724) (xy 363.576271 -263.380772) (xy 363.622545 -263.40435) (xy 363.664561 -263.434876)
			(xy 363.701284 -263.471599) (xy 363.73181 -263.513615) (xy 363.755388 -263.559889) (xy 363.771436 -263.609282)
			(xy 363.779561 -263.660577) (xy 363.78007 -263.686544) (xy 363.779561 -263.712511) (xy 363.771436 -263.763806)
			(xy 363.755388 -263.813199) (xy 363.73181 -263.859473) (xy 363.701284 -263.901489) (xy 363.664561 -263.938212)
			(xy 363.622545 -263.968738) (xy 363.576271 -263.992316) (xy 363.526878 -264.008364) (xy 363.475583 -264.016489)
			(xy 363.423649 -264.016489) (xy 363.372354 -264.008364) (xy 363.322961 -263.992316) (xy 363.276687 -263.968738)
			(xy 363.234671 -263.938212) (xy 363.197948 -263.901489) (xy 363.167422 -263.859473) (xy 363.143844 -263.813199)
			(xy 363.127796 -263.763806) (xy 363.119671 -263.712511) (xy 362.839507 -263.712511) (xy 362.831382 -263.763806)
			(xy 362.815334 -263.813199) (xy 362.791756 -263.859473) (xy 362.76123 -263.901489) (xy 362.724507 -263.938212)
			(xy 362.682491 -263.968738) (xy 362.636217 -263.992316) (xy 362.586824 -264.008364) (xy 362.535529 -264.016489)
			(xy 362.483595 -264.016489) (xy 362.4323 -264.008364) (xy 362.382907 -263.992316) (xy 362.336633 -263.968738)
			(xy 362.294617 -263.938212) (xy 362.257894 -263.901489) (xy 362.227368 -263.859473) (xy 362.20379 -263.813199)
			(xy 362.187742 -263.763806) (xy 362.179617 -263.712511) (xy 361.899707 -263.712511) (xy 361.891582 -263.763806)
			(xy 361.875534 -263.813199) (xy 361.851956 -263.859473) (xy 361.82143 -263.901489) (xy 361.784707 -263.938212)
			(xy 361.742691 -263.968738) (xy 361.696417 -263.992316) (xy 361.647024 -264.008364) (xy 361.595729 -264.016489)
			(xy 361.543795 -264.016489) (xy 361.4925 -264.008364) (xy 361.443107 -263.992316) (xy 361.396833 -263.968738)
			(xy 361.354817 -263.938212) (xy 361.318094 -263.901489) (xy 361.287568 -263.859473) (xy 361.26399 -263.813199)
			(xy 361.247942 -263.763806) (xy 361.239817 -263.712511) (xy 360.959907 -263.712511) (xy 360.951782 -263.763806)
			(xy 360.935734 -263.813199) (xy 360.912156 -263.859473) (xy 360.88163 -263.901489) (xy 360.844907 -263.938212)
			(xy 360.802891 -263.968738) (xy 360.756617 -263.992316) (xy 360.707224 -264.008364) (xy 360.655929 -264.016489)
			(xy 360.603995 -264.016489) (xy 360.5527 -264.008364) (xy 360.503307 -263.992316) (xy 360.457033 -263.968738)
			(xy 360.415017 -263.938212) (xy 360.378294 -263.901489) (xy 360.347768 -263.859473) (xy 360.32419 -263.813199)
			(xy 360.308142 -263.763806) (xy 360.300017 -263.712511) (xy 360.020107 -263.712511) (xy 360.011982 -263.763806)
			(xy 359.995934 -263.813199) (xy 359.972356 -263.859473) (xy 359.94183 -263.901489) (xy 359.905107 -263.938212)
			(xy 359.863091 -263.968738) (xy 359.816817 -263.992316) (xy 359.767424 -264.008364) (xy 359.716129 -264.016489)
			(xy 359.664195 -264.016489) (xy 359.6129 -264.008364) (xy 359.563507 -263.992316) (xy 359.517233 -263.968738)
			(xy 359.475217 -263.938212) (xy 359.438494 -263.901489) (xy 359.407968 -263.859473) (xy 359.38439 -263.813199)
			(xy 359.368342 -263.763806) (xy 359.360217 -263.712511) (xy 359.080307 -263.712511) (xy 359.072182 -263.763806)
			(xy 359.056134 -263.813199) (xy 359.032556 -263.859473) (xy 359.00203 -263.901489) (xy 358.965307 -263.938212)
			(xy 358.923291 -263.968738) (xy 358.877017 -263.992316) (xy 358.827624 -264.008364) (xy 358.776329 -264.016489)
			(xy 358.724395 -264.016489) (xy 358.6731 -264.008364) (xy 358.623707 -263.992316) (xy 358.577433 -263.968738)
			(xy 358.535417 -263.938212) (xy 358.498694 -263.901489) (xy 358.468168 -263.859473) (xy 358.44459 -263.813199)
			(xy 358.428542 -263.763806) (xy 358.420417 -263.712511) (xy 358.140507 -263.712511) (xy 358.132382 -263.763806)
			(xy 358.116334 -263.813199) (xy 358.092756 -263.859473) (xy 358.06223 -263.901489) (xy 358.025507 -263.938212)
			(xy 357.983491 -263.968738) (xy 357.937217 -263.992316) (xy 357.887824 -264.008364) (xy 357.836529 -264.016489)
			(xy 357.784595 -264.016489) (xy 357.7333 -264.008364) (xy 357.683907 -263.992316) (xy 357.637633 -263.968738)
			(xy 357.595617 -263.938212) (xy 357.558894 -263.901489) (xy 357.528368 -263.859473) (xy 357.50479 -263.813199)
			(xy 357.488742 -263.763806) (xy 357.480617 -263.712511) (xy 355.638041 -263.712511) (xy 355.337364 -264.013188)
			(xy 352.22053 -264.013188) (xy 352.032062 -264.201656) (xy 352.032062 -264.488422) (xy 352.032316 -264.50036)
			(xy 352.032062 -264.512298) (xy 352.032062 -264.526327) (xy 356.071171 -264.526327) (xy 356.071171 -264.474393)
			(xy 356.079296 -264.423098) (xy 356.095344 -264.373705) (xy 356.118922 -264.327431) (xy 356.149448 -264.285415)
			(xy 356.186171 -264.248692) (xy 356.228187 -264.218166) (xy 356.274461 -264.194588) (xy 356.323854 -264.17854)
			(xy 356.375149 -264.170415) (xy 356.427083 -264.170415) (xy 356.478378 -264.17854) (xy 356.527771 -264.194588)
			(xy 356.574045 -264.218166) (xy 356.616061 -264.248692) (xy 356.652784 -264.285415) (xy 356.68331 -264.327431)
			(xy 356.706888 -264.373705) (xy 356.722936 -264.423098) (xy 356.731061 -264.474393) (xy 356.73157 -264.50036)
			(xy 356.731061 -264.526327) (xy 357.010717 -264.526327) (xy 357.010717 -264.474393) (xy 357.018842 -264.423098)
			(xy 357.03489 -264.373705) (xy 357.058468 -264.327431) (xy 357.088994 -264.285415) (xy 357.125717 -264.248692)
			(xy 357.167733 -264.218166) (xy 357.214007 -264.194588) (xy 357.2634 -264.17854) (xy 357.314695 -264.170415)
			(xy 357.366629 -264.170415) (xy 357.417924 -264.17854) (xy 357.467317 -264.194588) (xy 357.513591 -264.218166)
			(xy 357.555607 -264.248692) (xy 357.59233 -264.285415) (xy 357.622856 -264.327431) (xy 357.646434 -264.373705)
			(xy 357.662482 -264.423098) (xy 357.670607 -264.474393) (xy 357.671116 -264.50036) (xy 357.670607 -264.526327)
			(xy 357.950771 -264.526327) (xy 357.950771 -264.474393) (xy 357.958896 -264.423098) (xy 357.974944 -264.373705)
			(xy 357.998522 -264.327431) (xy 358.029048 -264.285415) (xy 358.065771 -264.248692) (xy 358.107787 -264.218166)
			(xy 358.154061 -264.194588) (xy 358.203454 -264.17854) (xy 358.254749 -264.170415) (xy 358.306683 -264.170415)
			(xy 358.357978 -264.17854) (xy 358.407371 -264.194588) (xy 358.453645 -264.218166) (xy 358.495661 -264.248692)
			(xy 358.532384 -264.285415) (xy 358.56291 -264.327431) (xy 358.586488 -264.373705) (xy 358.602536 -264.423098)
			(xy 358.610661 -264.474393) (xy 358.61117 -264.50036) (xy 358.610661 -264.526327) (xy 358.890571 -264.526327)
			(xy 358.890571 -264.474393) (xy 358.898696 -264.423098) (xy 358.914744 -264.373705) (xy 358.938322 -264.327431)
			(xy 358.968848 -264.285415) (xy 359.005571 -264.248692) (xy 359.047587 -264.218166) (xy 359.093861 -264.194588)
			(xy 359.143254 -264.17854) (xy 359.194549 -264.170415) (xy 359.246483 -264.170415) (xy 359.297778 -264.17854)
			(xy 359.347171 -264.194588) (xy 359.393445 -264.218166) (xy 359.435461 -264.248692) (xy 359.472184 -264.285415)
			(xy 359.50271 -264.327431) (xy 359.526288 -264.373705) (xy 359.542336 -264.423098) (xy 359.550461 -264.474393)
			(xy 359.55097 -264.50036) (xy 359.550461 -264.526327) (xy 359.830371 -264.526327) (xy 359.830371 -264.474393)
			(xy 359.838496 -264.423098) (xy 359.854544 -264.373705) (xy 359.878122 -264.327431) (xy 359.908648 -264.285415)
			(xy 359.945371 -264.248692) (xy 359.987387 -264.218166) (xy 360.033661 -264.194588) (xy 360.083054 -264.17854)
			(xy 360.134349 -264.170415) (xy 360.186283 -264.170415) (xy 360.237578 -264.17854) (xy 360.286971 -264.194588)
			(xy 360.333245 -264.218166) (xy 360.375261 -264.248692) (xy 360.411984 -264.285415) (xy 360.44251 -264.327431)
			(xy 360.466088 -264.373705) (xy 360.482136 -264.423098) (xy 360.490261 -264.474393) (xy 360.49077 -264.50036)
			(xy 360.490261 -264.526327) (xy 360.769917 -264.526327) (xy 360.769917 -264.474393) (xy 360.778042 -264.423098)
			(xy 360.79409 -264.373705) (xy 360.817668 -264.327431) (xy 360.848194 -264.285415) (xy 360.884917 -264.248692)
			(xy 360.926933 -264.218166) (xy 360.973207 -264.194588) (xy 361.0226 -264.17854) (xy 361.073895 -264.170415)
			(xy 361.125829 -264.170415) (xy 361.177124 -264.17854) (xy 361.226517 -264.194588) (xy 361.272791 -264.218166)
			(xy 361.314807 -264.248692) (xy 361.35153 -264.285415) (xy 361.382056 -264.327431) (xy 361.405634 -264.373705)
			(xy 361.421682 -264.423098) (xy 361.429807 -264.474393) (xy 361.430316 -264.50036) (xy 361.429807 -264.526327)
			(xy 361.709717 -264.526327) (xy 361.709717 -264.474393) (xy 361.717842 -264.423098) (xy 361.73389 -264.373705)
			(xy 361.757468 -264.327431) (xy 361.787994 -264.285415) (xy 361.824717 -264.248692) (xy 361.866733 -264.218166)
			(xy 361.913007 -264.194588) (xy 361.9624 -264.17854) (xy 362.013695 -264.170415) (xy 362.065629 -264.170415)
			(xy 362.116924 -264.17854) (xy 362.166317 -264.194588) (xy 362.212591 -264.218166) (xy 362.254607 -264.248692)
			(xy 362.29133 -264.285415) (xy 362.321856 -264.327431) (xy 362.345434 -264.373705) (xy 362.361482 -264.423098)
			(xy 362.369607 -264.474393) (xy 362.370116 -264.50036) (xy 362.369607 -264.526327) (xy 362.649517 -264.526327)
			(xy 362.649517 -264.474393) (xy 362.657642 -264.423098) (xy 362.67369 -264.373705) (xy 362.697268 -264.327431)
			(xy 362.727794 -264.285415) (xy 362.764517 -264.248692) (xy 362.806533 -264.218166) (xy 362.852807 -264.194588)
			(xy 362.9022 -264.17854) (xy 362.953495 -264.170415) (xy 363.005429 -264.170415) (xy 363.056724 -264.17854)
			(xy 363.106117 -264.194588) (xy 363.152391 -264.218166) (xy 363.194407 -264.248692) (xy 363.23113 -264.285415)
			(xy 363.261656 -264.327431) (xy 363.285234 -264.373705) (xy 363.301282 -264.423098) (xy 363.309407 -264.474393)
			(xy 363.309916 -264.50036) (xy 363.309407 -264.526327) (xy 363.589317 -264.526327) (xy 363.589317 -264.474393)
			(xy 363.597442 -264.423098) (xy 363.61349 -264.373705) (xy 363.637068 -264.327431) (xy 363.667594 -264.285415)
			(xy 363.704317 -264.248692) (xy 363.746333 -264.218166) (xy 363.792607 -264.194588) (xy 363.842 -264.17854)
			(xy 363.893295 -264.170415) (xy 363.945229 -264.170415) (xy 363.996524 -264.17854) (xy 364.045917 -264.194588)
			(xy 364.092191 -264.218166) (xy 364.134207 -264.248692) (xy 364.17093 -264.285415) (xy 364.201456 -264.327431)
			(xy 364.225034 -264.373705) (xy 364.241082 -264.423098) (xy 364.249207 -264.474393) (xy 364.249716 -264.50036)
			(xy 364.249207 -264.526327) (xy 364.529117 -264.526327) (xy 364.529117 -264.474393) (xy 364.537242 -264.423098)
			(xy 364.55329 -264.373705) (xy 364.576868 -264.327431) (xy 364.607394 -264.285415) (xy 364.644117 -264.248692)
			(xy 364.686133 -264.218166) (xy 364.732407 -264.194588) (xy 364.7818 -264.17854) (xy 364.833095 -264.170415)
			(xy 364.885029 -264.170415) (xy 364.936324 -264.17854) (xy 364.985717 -264.194588) (xy 365.031991 -264.218166)
			(xy 365.074007 -264.248692) (xy 365.11073 -264.285415) (xy 365.141256 -264.327431) (xy 365.164834 -264.373705)
			(xy 365.180882 -264.423098) (xy 365.189007 -264.474393) (xy 365.189516 -264.50036) (xy 365.189007 -264.526327)
			(xy 365.468917 -264.526327) (xy 365.468917 -264.474393) (xy 365.477042 -264.423098) (xy 365.49309 -264.373705)
			(xy 365.516668 -264.327431) (xy 365.547194 -264.285415) (xy 365.583917 -264.248692) (xy 365.625933 -264.218166)
			(xy 365.672207 -264.194588) (xy 365.7216 -264.17854) (xy 365.772895 -264.170415) (xy 365.824829 -264.170415)
			(xy 365.876124 -264.17854) (xy 365.925517 -264.194588) (xy 365.971791 -264.218166) (xy 366.013807 -264.248692)
			(xy 366.05053 -264.285415) (xy 366.081056 -264.327431) (xy 366.104634 -264.373705) (xy 366.120682 -264.423098)
			(xy 366.128807 -264.474393) (xy 366.129316 -264.50036) (xy 366.128807 -264.526327) (xy 366.408717 -264.526327)
			(xy 366.408717 -264.474393) (xy 366.416842 -264.423098) (xy 366.43289 -264.373705) (xy 366.456468 -264.327431)
			(xy 366.486994 -264.285415) (xy 366.523717 -264.248692) (xy 366.565733 -264.218166) (xy 366.612007 -264.194588)
			(xy 366.6614 -264.17854) (xy 366.712695 -264.170415) (xy 366.764629 -264.170415) (xy 366.815924 -264.17854)
			(xy 366.865317 -264.194588) (xy 366.911591 -264.218166) (xy 366.953607 -264.248692) (xy 366.99033 -264.285415)
			(xy 367.020856 -264.327431) (xy 367.044434 -264.373705) (xy 367.060482 -264.423098) (xy 367.068607 -264.474393)
			(xy 367.069116 -264.50036) (xy 367.068607 -264.526327) (xy 367.348517 -264.526327) (xy 367.348517 -264.474393)
			(xy 367.356642 -264.423098) (xy 367.37269 -264.373705) (xy 367.396268 -264.327431) (xy 367.426794 -264.285415)
			(xy 367.463517 -264.248692) (xy 367.505533 -264.218166) (xy 367.551807 -264.194588) (xy 367.6012 -264.17854)
			(xy 367.652495 -264.170415) (xy 367.704429 -264.170415) (xy 367.755724 -264.17854) (xy 367.805117 -264.194588)
			(xy 367.851391 -264.218166) (xy 367.893407 -264.248692) (xy 367.93013 -264.285415) (xy 367.960656 -264.327431)
			(xy 367.984234 -264.373705) (xy 368.000282 -264.423098) (xy 368.008407 -264.474393) (xy 368.008916 -264.50036)
			(xy 368.008407 -264.526327) (xy 368.288317 -264.526327) (xy 368.288317 -264.474393) (xy 368.296442 -264.423098)
			(xy 368.31249 -264.373705) (xy 368.336068 -264.327431) (xy 368.366594 -264.285415) (xy 368.403317 -264.248692)
			(xy 368.445333 -264.218166) (xy 368.491607 -264.194588) (xy 368.541 -264.17854) (xy 368.592295 -264.170415)
			(xy 368.644229 -264.170415) (xy 368.695524 -264.17854) (xy 368.744917 -264.194588) (xy 368.791191 -264.218166)
			(xy 368.833207 -264.248692) (xy 368.86993 -264.285415) (xy 368.900456 -264.327431) (xy 368.924034 -264.373705)
			(xy 368.940082 -264.423098) (xy 368.948207 -264.474393) (xy 368.948716 -264.50036) (xy 368.948207 -264.526327)
			(xy 369.228117 -264.526327) (xy 369.228117 -264.474393) (xy 369.236242 -264.423098) (xy 369.25229 -264.373705)
			(xy 369.275868 -264.327431) (xy 369.306394 -264.285415) (xy 369.343117 -264.248692) (xy 369.385133 -264.218166)
			(xy 369.431407 -264.194588) (xy 369.4808 -264.17854) (xy 369.532095 -264.170415) (xy 369.584029 -264.170415)
			(xy 369.635324 -264.17854) (xy 369.684717 -264.194588) (xy 369.730991 -264.218166) (xy 369.773007 -264.248692)
			(xy 369.80973 -264.285415) (xy 369.840256 -264.327431) (xy 369.863834 -264.373705) (xy 369.879882 -264.423098)
			(xy 369.888007 -264.474393) (xy 369.888516 -264.50036) (xy 369.888007 -264.526327) (xy 370.167917 -264.526327)
			(xy 370.167917 -264.474393) (xy 370.176042 -264.423098) (xy 370.19209 -264.373705) (xy 370.215668 -264.327431)
			(xy 370.246194 -264.285415) (xy 370.282917 -264.248692) (xy 370.324933 -264.218166) (xy 370.371207 -264.194588)
			(xy 370.4206 -264.17854) (xy 370.471895 -264.170415) (xy 370.523829 -264.170415) (xy 370.575124 -264.17854)
			(xy 370.624517 -264.194588) (xy 370.670791 -264.218166) (xy 370.712807 -264.248692) (xy 370.74953 -264.285415)
			(xy 370.780056 -264.327431) (xy 370.803634 -264.373705) (xy 370.819682 -264.423098) (xy 370.827807 -264.474393)
			(xy 370.828316 -264.50036) (xy 370.827807 -264.526327) (xy 370.819682 -264.577622) (xy 370.803634 -264.627015)
			(xy 370.780056 -264.673289) (xy 370.74953 -264.715305) (xy 370.712807 -264.752028) (xy 370.670791 -264.782554)
			(xy 370.624517 -264.806132) (xy 370.575124 -264.82218) (xy 370.523829 -264.830305) (xy 370.471895 -264.830305)
			(xy 370.4206 -264.82218) (xy 370.371207 -264.806132) (xy 370.324933 -264.782554) (xy 370.282917 -264.752028)
			(xy 370.246194 -264.715305) (xy 370.215668 -264.673289) (xy 370.19209 -264.627015) (xy 370.176042 -264.577622)
			(xy 370.167917 -264.526327) (xy 369.888007 -264.526327) (xy 369.879882 -264.577622) (xy 369.863834 -264.627015)
			(xy 369.840256 -264.673289) (xy 369.80973 -264.715305) (xy 369.773007 -264.752028) (xy 369.730991 -264.782554)
			(xy 369.684717 -264.806132) (xy 369.635324 -264.82218) (xy 369.584029 -264.830305) (xy 369.532095 -264.830305)
			(xy 369.4808 -264.82218) (xy 369.431407 -264.806132) (xy 369.385133 -264.782554) (xy 369.343117 -264.752028)
			(xy 369.306394 -264.715305) (xy 369.275868 -264.673289) (xy 369.25229 -264.627015) (xy 369.236242 -264.577622)
			(xy 369.228117 -264.526327) (xy 368.948207 -264.526327) (xy 368.940082 -264.577622) (xy 368.924034 -264.627015)
			(xy 368.900456 -264.673289) (xy 368.86993 -264.715305) (xy 368.833207 -264.752028) (xy 368.791191 -264.782554)
			(xy 368.744917 -264.806132) (xy 368.695524 -264.82218) (xy 368.644229 -264.830305) (xy 368.592295 -264.830305)
			(xy 368.541 -264.82218) (xy 368.491607 -264.806132) (xy 368.445333 -264.782554) (xy 368.403317 -264.752028)
			(xy 368.366594 -264.715305) (xy 368.336068 -264.673289) (xy 368.31249 -264.627015) (xy 368.296442 -264.577622)
			(xy 368.288317 -264.526327) (xy 368.008407 -264.526327) (xy 368.000282 -264.577622) (xy 367.984234 -264.627015)
			(xy 367.960656 -264.673289) (xy 367.93013 -264.715305) (xy 367.893407 -264.752028) (xy 367.851391 -264.782554)
			(xy 367.805117 -264.806132) (xy 367.755724 -264.82218) (xy 367.704429 -264.830305) (xy 367.652495 -264.830305)
			(xy 367.6012 -264.82218) (xy 367.551807 -264.806132) (xy 367.505533 -264.782554) (xy 367.463517 -264.752028)
			(xy 367.426794 -264.715305) (xy 367.396268 -264.673289) (xy 367.37269 -264.627015) (xy 367.356642 -264.577622)
			(xy 367.348517 -264.526327) (xy 367.068607 -264.526327) (xy 367.060482 -264.577622) (xy 367.044434 -264.627015)
			(xy 367.020856 -264.673289) (xy 366.99033 -264.715305) (xy 366.953607 -264.752028) (xy 366.911591 -264.782554)
			(xy 366.865317 -264.806132) (xy 366.815924 -264.82218) (xy 366.764629 -264.830305) (xy 366.712695 -264.830305)
			(xy 366.6614 -264.82218) (xy 366.612007 -264.806132) (xy 366.565733 -264.782554) (xy 366.523717 -264.752028)
			(xy 366.486994 -264.715305) (xy 366.456468 -264.673289) (xy 366.43289 -264.627015) (xy 366.416842 -264.577622)
			(xy 366.408717 -264.526327) (xy 366.128807 -264.526327) (xy 366.120682 -264.577622) (xy 366.104634 -264.627015)
			(xy 366.081056 -264.673289) (xy 366.05053 -264.715305) (xy 366.013807 -264.752028) (xy 365.971791 -264.782554)
			(xy 365.925517 -264.806132) (xy 365.876124 -264.82218) (xy 365.824829 -264.830305) (xy 365.772895 -264.830305)
			(xy 365.7216 -264.82218) (xy 365.672207 -264.806132) (xy 365.625933 -264.782554) (xy 365.583917 -264.752028)
			(xy 365.547194 -264.715305) (xy 365.516668 -264.673289) (xy 365.49309 -264.627015) (xy 365.477042 -264.577622)
			(xy 365.468917 -264.526327) (xy 365.189007 -264.526327) (xy 365.180882 -264.577622) (xy 365.164834 -264.627015)
			(xy 365.141256 -264.673289) (xy 365.11073 -264.715305) (xy 365.074007 -264.752028) (xy 365.031991 -264.782554)
			(xy 364.985717 -264.806132) (xy 364.936324 -264.82218) (xy 364.885029 -264.830305) (xy 364.833095 -264.830305)
			(xy 364.7818 -264.82218) (xy 364.732407 -264.806132) (xy 364.686133 -264.782554) (xy 364.644117 -264.752028)
			(xy 364.607394 -264.715305) (xy 364.576868 -264.673289) (xy 364.55329 -264.627015) (xy 364.537242 -264.577622)
			(xy 364.529117 -264.526327) (xy 364.249207 -264.526327) (xy 364.241082 -264.577622) (xy 364.225034 -264.627015)
			(xy 364.201456 -264.673289) (xy 364.17093 -264.715305) (xy 364.134207 -264.752028) (xy 364.092191 -264.782554)
			(xy 364.045917 -264.806132) (xy 363.996524 -264.82218) (xy 363.945229 -264.830305) (xy 363.893295 -264.830305)
			(xy 363.842 -264.82218) (xy 363.792607 -264.806132) (xy 363.746333 -264.782554) (xy 363.704317 -264.752028)
			(xy 363.667594 -264.715305) (xy 363.637068 -264.673289) (xy 363.61349 -264.627015) (xy 363.597442 -264.577622)
			(xy 363.589317 -264.526327) (xy 363.309407 -264.526327) (xy 363.301282 -264.577622) (xy 363.285234 -264.627015)
			(xy 363.261656 -264.673289) (xy 363.23113 -264.715305) (xy 363.194407 -264.752028) (xy 363.152391 -264.782554)
			(xy 363.106117 -264.806132) (xy 363.056724 -264.82218) (xy 363.005429 -264.830305) (xy 362.953495 -264.830305)
			(xy 362.9022 -264.82218) (xy 362.852807 -264.806132) (xy 362.806533 -264.782554) (xy 362.764517 -264.752028)
			(xy 362.727794 -264.715305) (xy 362.697268 -264.673289) (xy 362.67369 -264.627015) (xy 362.657642 -264.577622)
			(xy 362.649517 -264.526327) (xy 362.369607 -264.526327) (xy 362.361482 -264.577622) (xy 362.345434 -264.627015)
			(xy 362.321856 -264.673289) (xy 362.29133 -264.715305) (xy 362.254607 -264.752028) (xy 362.212591 -264.782554)
			(xy 362.166317 -264.806132) (xy 362.116924 -264.82218) (xy 362.065629 -264.830305) (xy 362.013695 -264.830305)
			(xy 361.9624 -264.82218) (xy 361.913007 -264.806132) (xy 361.866733 -264.782554) (xy 361.824717 -264.752028)
			(xy 361.787994 -264.715305) (xy 361.757468 -264.673289) (xy 361.73389 -264.627015) (xy 361.717842 -264.577622)
			(xy 361.709717 -264.526327) (xy 361.429807 -264.526327) (xy 361.421682 -264.577622) (xy 361.405634 -264.627015)
			(xy 361.382056 -264.673289) (xy 361.35153 -264.715305) (xy 361.314807 -264.752028) (xy 361.272791 -264.782554)
			(xy 361.226517 -264.806132) (xy 361.177124 -264.82218) (xy 361.125829 -264.830305) (xy 361.073895 -264.830305)
			(xy 361.0226 -264.82218) (xy 360.973207 -264.806132) (xy 360.926933 -264.782554) (xy 360.884917 -264.752028)
			(xy 360.848194 -264.715305) (xy 360.817668 -264.673289) (xy 360.79409 -264.627015) (xy 360.778042 -264.577622)
			(xy 360.769917 -264.526327) (xy 360.490261 -264.526327) (xy 360.482136 -264.577622) (xy 360.466088 -264.627015)
			(xy 360.44251 -264.673289) (xy 360.411984 -264.715305) (xy 360.375261 -264.752028) (xy 360.333245 -264.782554)
			(xy 360.286971 -264.806132) (xy 360.237578 -264.82218) (xy 360.186283 -264.830305) (xy 360.134349 -264.830305)
			(xy 360.083054 -264.82218) (xy 360.033661 -264.806132) (xy 359.987387 -264.782554) (xy 359.945371 -264.752028)
			(xy 359.908648 -264.715305) (xy 359.878122 -264.673289) (xy 359.854544 -264.627015) (xy 359.838496 -264.577622)
			(xy 359.830371 -264.526327) (xy 359.550461 -264.526327) (xy 359.542336 -264.577622) (xy 359.526288 -264.627015)
			(xy 359.50271 -264.673289) (xy 359.472184 -264.715305) (xy 359.435461 -264.752028) (xy 359.393445 -264.782554)
			(xy 359.347171 -264.806132) (xy 359.297778 -264.82218) (xy 359.246483 -264.830305) (xy 359.194549 -264.830305)
			(xy 359.143254 -264.82218) (xy 359.093861 -264.806132) (xy 359.047587 -264.782554) (xy 359.005571 -264.752028)
			(xy 358.968848 -264.715305) (xy 358.938322 -264.673289) (xy 358.914744 -264.627015) (xy 358.898696 -264.577622)
			(xy 358.890571 -264.526327) (xy 358.610661 -264.526327) (xy 358.602536 -264.577622) (xy 358.586488 -264.627015)
			(xy 358.56291 -264.673289) (xy 358.532384 -264.715305) (xy 358.495661 -264.752028) (xy 358.453645 -264.782554)
			(xy 358.407371 -264.806132) (xy 358.357978 -264.82218) (xy 358.306683 -264.830305) (xy 358.254749 -264.830305)
			(xy 358.203454 -264.82218) (xy 358.154061 -264.806132) (xy 358.107787 -264.782554) (xy 358.065771 -264.752028)
			(xy 358.029048 -264.715305) (xy 357.998522 -264.673289) (xy 357.974944 -264.627015) (xy 357.958896 -264.577622)
			(xy 357.950771 -264.526327) (xy 357.670607 -264.526327) (xy 357.662482 -264.577622) (xy 357.646434 -264.627015)
			(xy 357.622856 -264.673289) (xy 357.59233 -264.715305) (xy 357.555607 -264.752028) (xy 357.513591 -264.782554)
			(xy 357.467317 -264.806132) (xy 357.417924 -264.82218) (xy 357.366629 -264.830305) (xy 357.314695 -264.830305)
			(xy 357.2634 -264.82218) (xy 357.214007 -264.806132) (xy 357.167733 -264.782554) (xy 357.125717 -264.752028)
			(xy 357.088994 -264.715305) (xy 357.058468 -264.673289) (xy 357.03489 -264.627015) (xy 357.018842 -264.577622)
			(xy 357.010717 -264.526327) (xy 356.731061 -264.526327) (xy 356.722936 -264.577622) (xy 356.706888 -264.627015)
			(xy 356.68331 -264.673289) (xy 356.652784 -264.715305) (xy 356.616061 -264.752028) (xy 356.574045 -264.782554)
			(xy 356.527771 -264.806132) (xy 356.478378 -264.82218) (xy 356.427083 -264.830305) (xy 356.375149 -264.830305)
			(xy 356.323854 -264.82218) (xy 356.274461 -264.806132) (xy 356.228187 -264.782554) (xy 356.186171 -264.752028)
			(xy 356.149448 -264.715305) (xy 356.118922 -264.673289) (xy 356.095344 -264.627015) (xy 356.079296 -264.577622)
			(xy 356.071171 -264.526327) (xy 352.032062 -264.526327) (xy 352.032062 -264.8839) (xy 352.032502 -264.89797)
			(xy 352.040167 -264.925044) (xy 352.05494 -264.948993) (xy 352.075697 -264.967991) (xy 352.100856 -264.980593)
			(xy 352.128502 -264.985837) (xy 352.142552 -264.984992) (xy 352.172016 -264.983722) (xy 352.197984 -264.984233)
			(xy 352.249281 -264.992359) (xy 352.298675 -265.008411) (xy 352.34495 -265.031991) (xy 352.386967 -265.06252)
			(xy 352.423691 -265.099245) (xy 352.454217 -265.141264) (xy 352.477795 -265.18754) (xy 352.493844 -265.236934)
			(xy 352.501969 -265.288232) (xy 352.501969 -265.340143) (xy 352.781871 -265.340143) (xy 352.781871 -265.288209)
			(xy 352.789996 -265.236914) (xy 352.806044 -265.187521) (xy 352.829622 -265.141247) (xy 352.860148 -265.099231)
			(xy 352.896871 -265.062508) (xy 352.938887 -265.031982) (xy 352.985161 -265.008404) (xy 353.034554 -264.992356)
			(xy 353.085849 -264.984231) (xy 353.137783 -264.984231) (xy 353.189078 -264.992356) (xy 353.238471 -265.008404)
			(xy 353.284745 -265.031982) (xy 353.326761 -265.062508) (xy 353.363484 -265.099231) (xy 353.39401 -265.141247)
			(xy 353.417588 -265.187521) (xy 353.433636 -265.236914) (xy 353.441761 -265.288209) (xy 353.44227 -265.314176)
			(xy 353.441761 -265.340143) (xy 353.721671 -265.340143) (xy 353.721671 -265.288209) (xy 353.729796 -265.236914)
			(xy 353.745844 -265.187521) (xy 353.769422 -265.141247) (xy 353.799948 -265.099231) (xy 353.836671 -265.062508)
			(xy 353.878687 -265.031982) (xy 353.924961 -265.008404) (xy 353.974354 -264.992356) (xy 354.025649 -264.984231)
			(xy 354.077583 -264.984231) (xy 354.128878 -264.992356) (xy 354.178271 -265.008404) (xy 354.224545 -265.031982)
			(xy 354.266561 -265.062508) (xy 354.303284 -265.099231) (xy 354.33381 -265.141247) (xy 354.357388 -265.187521)
			(xy 354.373436 -265.236914) (xy 354.381561 -265.288209) (xy 354.38207 -265.314176) (xy 354.381561 -265.340143)
			(xy 354.661471 -265.340143) (xy 354.661471 -265.288209) (xy 354.669596 -265.236914) (xy 354.685644 -265.187521)
			(xy 354.709222 -265.141247) (xy 354.739748 -265.099231) (xy 354.776471 -265.062508) (xy 354.818487 -265.031982)
			(xy 354.864761 -265.008404) (xy 354.914154 -264.992356) (xy 354.965449 -264.984231) (xy 355.017383 -264.984231)
			(xy 355.068678 -264.992356) (xy 355.118071 -265.008404) (xy 355.164345 -265.031982) (xy 355.206361 -265.062508)
			(xy 355.243084 -265.099231) (xy 355.27361 -265.141247) (xy 355.297188 -265.187521) (xy 355.313236 -265.236914)
			(xy 355.321361 -265.288209) (xy 355.32187 -265.314176) (xy 355.321361 -265.340143) (xy 356.541071 -265.340143)
			(xy 356.541071 -265.288209) (xy 356.549196 -265.236914) (xy 356.565244 -265.187521) (xy 356.588822 -265.141247)
			(xy 356.619348 -265.099231) (xy 356.656071 -265.062508) (xy 356.698087 -265.031982) (xy 356.744361 -265.008404)
			(xy 356.793754 -264.992356) (xy 356.845049 -264.984231) (xy 356.896983 -264.984231) (xy 356.948278 -264.992356)
			(xy 356.997671 -265.008404) (xy 357.043945 -265.031982) (xy 357.085961 -265.062508) (xy 357.122684 -265.099231)
			(xy 357.15321 -265.141247) (xy 357.176788 -265.187521) (xy 357.192836 -265.236914) (xy 357.200961 -265.288209)
			(xy 357.20147 -265.314176) (xy 357.200961 -265.340143) (xy 357.480617 -265.340143) (xy 357.480617 -265.288209)
			(xy 357.488742 -265.236914) (xy 357.50479 -265.187521) (xy 357.528368 -265.141247) (xy 357.558894 -265.099231)
			(xy 357.595617 -265.062508) (xy 357.637633 -265.031982) (xy 357.683907 -265.008404) (xy 357.7333 -264.992356)
			(xy 357.784595 -264.984231) (xy 357.836529 -264.984231) (xy 357.887824 -264.992356) (xy 357.937217 -265.008404)
			(xy 357.983491 -265.031982) (xy 358.025507 -265.062508) (xy 358.06223 -265.099231) (xy 358.092756 -265.141247)
			(xy 358.116334 -265.187521) (xy 358.132382 -265.236914) (xy 358.140507 -265.288209) (xy 358.141016 -265.314176)
			(xy 358.140507 -265.340143) (xy 358.420417 -265.340143) (xy 358.420417 -265.288209) (xy 358.428542 -265.236914)
			(xy 358.44459 -265.187521) (xy 358.468168 -265.141247) (xy 358.498694 -265.099231) (xy 358.535417 -265.062508)
			(xy 358.577433 -265.031982) (xy 358.623707 -265.008404) (xy 358.6731 -264.992356) (xy 358.724395 -264.984231)
			(xy 358.776329 -264.984231) (xy 358.827624 -264.992356) (xy 358.877017 -265.008404) (xy 358.923291 -265.031982)
			(xy 358.965307 -265.062508) (xy 359.00203 -265.099231) (xy 359.032556 -265.141247) (xy 359.056134 -265.187521)
			(xy 359.072182 -265.236914) (xy 359.080307 -265.288209) (xy 359.080816 -265.314176) (xy 359.080307 -265.340143)
			(xy 359.360217 -265.340143) (xy 359.360217 -265.288209) (xy 359.368342 -265.236914) (xy 359.38439 -265.187521)
			(xy 359.407968 -265.141247) (xy 359.438494 -265.099231) (xy 359.475217 -265.062508) (xy 359.517233 -265.031982)
			(xy 359.563507 -265.008404) (xy 359.6129 -264.992356) (xy 359.664195 -264.984231) (xy 359.716129 -264.984231)
			(xy 359.767424 -264.992356) (xy 359.816817 -265.008404) (xy 359.863091 -265.031982) (xy 359.905107 -265.062508)
			(xy 359.94183 -265.099231) (xy 359.972356 -265.141247) (xy 359.995934 -265.187521) (xy 360.011982 -265.236914)
			(xy 360.020107 -265.288209) (xy 360.020616 -265.314176) (xy 360.020107 -265.340143) (xy 360.300017 -265.340143)
			(xy 360.300017 -265.288209) (xy 360.308142 -265.236914) (xy 360.32419 -265.187521) (xy 360.347768 -265.141247)
			(xy 360.378294 -265.099231) (xy 360.415017 -265.062508) (xy 360.457033 -265.031982) (xy 360.503307 -265.008404)
			(xy 360.5527 -264.992356) (xy 360.603995 -264.984231) (xy 360.655929 -264.984231) (xy 360.707224 -264.992356)
			(xy 360.756617 -265.008404) (xy 360.802891 -265.031982) (xy 360.844907 -265.062508) (xy 360.88163 -265.099231)
			(xy 360.912156 -265.141247) (xy 360.935734 -265.187521) (xy 360.951782 -265.236914) (xy 360.959907 -265.288209)
			(xy 360.960416 -265.314176) (xy 360.959907 -265.340143) (xy 361.239817 -265.340143) (xy 361.239817 -265.288209)
			(xy 361.247942 -265.236914) (xy 361.26399 -265.187521) (xy 361.287568 -265.141247) (xy 361.318094 -265.099231)
			(xy 361.354817 -265.062508) (xy 361.396833 -265.031982) (xy 361.443107 -265.008404) (xy 361.4925 -264.992356)
			(xy 361.543795 -264.984231) (xy 361.595729 -264.984231) (xy 361.647024 -264.992356) (xy 361.696417 -265.008404)
			(xy 361.742691 -265.031982) (xy 361.784707 -265.062508) (xy 361.82143 -265.099231) (xy 361.851956 -265.141247)
			(xy 361.875534 -265.187521) (xy 361.891582 -265.236914) (xy 361.899707 -265.288209) (xy 361.900216 -265.314176)
			(xy 361.899707 -265.340143) (xy 362.179617 -265.340143) (xy 362.179617 -265.288209) (xy 362.187742 -265.236914)
			(xy 362.20379 -265.187521) (xy 362.227368 -265.141247) (xy 362.257894 -265.099231) (xy 362.294617 -265.062508)
			(xy 362.336633 -265.031982) (xy 362.382907 -265.008404) (xy 362.4323 -264.992356) (xy 362.483595 -264.984231)
			(xy 362.535529 -264.984231) (xy 362.586824 -264.992356) (xy 362.636217 -265.008404) (xy 362.682491 -265.031982)
			(xy 362.724507 -265.062508) (xy 362.76123 -265.099231) (xy 362.791756 -265.141247) (xy 362.815334 -265.187521)
			(xy 362.831382 -265.236914) (xy 362.839507 -265.288209) (xy 362.840016 -265.314176) (xy 362.839507 -265.340143)
			(xy 363.119671 -265.340143) (xy 363.119671 -265.288209) (xy 363.127796 -265.236914) (xy 363.143844 -265.187521)
			(xy 363.167422 -265.141247) (xy 363.197948 -265.099231) (xy 363.234671 -265.062508) (xy 363.276687 -265.031982)
			(xy 363.322961 -265.008404) (xy 363.372354 -264.992356) (xy 363.423649 -264.984231) (xy 363.475583 -264.984231)
			(xy 363.526878 -264.992356) (xy 363.576271 -265.008404) (xy 363.622545 -265.031982) (xy 363.664561 -265.062508)
			(xy 363.701284 -265.099231) (xy 363.73181 -265.141247) (xy 363.755388 -265.187521) (xy 363.771436 -265.236914)
			(xy 363.779561 -265.288209) (xy 363.78007 -265.314176) (xy 363.779561 -265.340143) (xy 364.059471 -265.340143)
			(xy 364.059471 -265.288209) (xy 364.067596 -265.236914) (xy 364.083644 -265.187521) (xy 364.107222 -265.141247)
			(xy 364.137748 -265.099231) (xy 364.174471 -265.062508) (xy 364.216487 -265.031982) (xy 364.262761 -265.008404)
			(xy 364.312154 -264.992356) (xy 364.363449 -264.984231) (xy 364.415383 -264.984231) (xy 364.466678 -264.992356)
			(xy 364.516071 -265.008404) (xy 364.562345 -265.031982) (xy 364.604361 -265.062508) (xy 364.641084 -265.099231)
			(xy 364.67161 -265.141247) (xy 364.695188 -265.187521) (xy 364.711236 -265.236914) (xy 364.719361 -265.288209)
			(xy 364.71987 -265.314176) (xy 364.719361 -265.340143) (xy 364.999271 -265.340143) (xy 364.999271 -265.288209)
			(xy 365.007396 -265.236914) (xy 365.023444 -265.187521) (xy 365.047022 -265.141247) (xy 365.077548 -265.099231)
			(xy 365.114271 -265.062508) (xy 365.156287 -265.031982) (xy 365.202561 -265.008404) (xy 365.251954 -264.992356)
			(xy 365.303249 -264.984231) (xy 365.355183 -264.984231) (xy 365.406478 -264.992356) (xy 365.455871 -265.008404)
			(xy 365.502145 -265.031982) (xy 365.544161 -265.062508) (xy 365.580884 -265.099231) (xy 365.61141 -265.141247)
			(xy 365.634988 -265.187521) (xy 365.651036 -265.236914) (xy 365.659161 -265.288209) (xy 365.65967 -265.314176)
			(xy 365.659161 -265.340143) (xy 365.938817 -265.340143) (xy 365.938817 -265.288209) (xy 365.946942 -265.236914)
			(xy 365.96299 -265.187521) (xy 365.986568 -265.141247) (xy 366.017094 -265.099231) (xy 366.053817 -265.062508)
			(xy 366.095833 -265.031982) (xy 366.142107 -265.008404) (xy 366.1915 -264.992356) (xy 366.242795 -264.984231)
			(xy 366.294729 -264.984231) (xy 366.346024 -264.992356) (xy 366.395417 -265.008404) (xy 366.441691 -265.031982)
			(xy 366.483707 -265.062508) (xy 366.52043 -265.099231) (xy 366.550956 -265.141247) (xy 366.574534 -265.187521)
			(xy 366.590582 -265.236914) (xy 366.598707 -265.288209) (xy 366.599216 -265.314176) (xy 366.598707 -265.340143)
			(xy 366.878871 -265.340143) (xy 366.878871 -265.288209) (xy 366.886996 -265.236914) (xy 366.903044 -265.187521)
			(xy 366.926622 -265.141247) (xy 366.957148 -265.099231) (xy 366.993871 -265.062508) (xy 367.035887 -265.031982)
			(xy 367.082161 -265.008404) (xy 367.131554 -264.992356) (xy 367.182849 -264.984231) (xy 367.234783 -264.984231)
			(xy 367.286078 -264.992356) (xy 367.335471 -265.008404) (xy 367.381745 -265.031982) (xy 367.423761 -265.062508)
			(xy 367.460484 -265.099231) (xy 367.49101 -265.141247) (xy 367.514588 -265.187521) (xy 367.530636 -265.236914)
			(xy 367.538761 -265.288209) (xy 367.53927 -265.314176) (xy 367.538761 -265.340143) (xy 367.818671 -265.340143)
			(xy 367.818671 -265.288209) (xy 367.826796 -265.236914) (xy 367.842844 -265.187521) (xy 367.866422 -265.141247)
			(xy 367.896948 -265.099231) (xy 367.933671 -265.062508) (xy 367.975687 -265.031982) (xy 368.021961 -265.008404)
			(xy 368.071354 -264.992356) (xy 368.122649 -264.984231) (xy 368.174583 -264.984231) (xy 368.225878 -264.992356)
			(xy 368.275271 -265.008404) (xy 368.321545 -265.031982) (xy 368.363561 -265.062508) (xy 368.400284 -265.099231)
			(xy 368.43081 -265.141247) (xy 368.454388 -265.187521) (xy 368.470436 -265.236914) (xy 368.478561 -265.288209)
			(xy 368.47907 -265.314176) (xy 368.478561 -265.340143) (xy 369.698271 -265.340143) (xy 369.698271 -265.288209)
			(xy 369.706396 -265.236914) (xy 369.722444 -265.187521) (xy 369.746022 -265.141247) (xy 369.776548 -265.099231)
			(xy 369.813271 -265.062508) (xy 369.855287 -265.031982) (xy 369.901561 -265.008404) (xy 369.950954 -264.992356)
			(xy 370.002249 -264.984231) (xy 370.054183 -264.984231) (xy 370.105478 -264.992356) (xy 370.154871 -265.008404)
			(xy 370.201145 -265.031982) (xy 370.243161 -265.062508) (xy 370.279884 -265.099231) (xy 370.31041 -265.141247)
			(xy 370.333988 -265.187521) (xy 370.350036 -265.236914) (xy 370.358161 -265.288209) (xy 370.35867 -265.314176)
			(xy 370.358161 -265.340143) (xy 370.638071 -265.340143) (xy 370.638071 -265.288209) (xy 370.646196 -265.236914)
			(xy 370.662244 -265.187521) (xy 370.685822 -265.141247) (xy 370.716348 -265.099231) (xy 370.753071 -265.062508)
			(xy 370.795087 -265.031982) (xy 370.841361 -265.008404) (xy 370.890754 -264.992356) (xy 370.942049 -264.984231)
			(xy 370.993983 -264.984231) (xy 371.045278 -264.992356) (xy 371.094671 -265.008404) (xy 371.140945 -265.031982)
			(xy 371.182961 -265.062508) (xy 371.219684 -265.099231) (xy 371.25021 -265.141247) (xy 371.273788 -265.187521)
			(xy 371.289836 -265.236914) (xy 371.297961 -265.288209) (xy 371.29847 -265.314176) (xy 371.297961 -265.340143)
			(xy 371.289836 -265.391438) (xy 371.273788 -265.440831) (xy 371.25021 -265.487105) (xy 371.219684 -265.529121)
			(xy 371.182961 -265.565844) (xy 371.140945 -265.59637) (xy 371.094671 -265.619948) (xy 371.045278 -265.635996)
			(xy 370.993983 -265.644121) (xy 370.942049 -265.644121) (xy 370.890754 -265.635996) (xy 370.841361 -265.619948)
			(xy 370.795087 -265.59637) (xy 370.753071 -265.565844) (xy 370.716348 -265.529121) (xy 370.685822 -265.487105)
			(xy 370.662244 -265.440831) (xy 370.646196 -265.391438) (xy 370.638071 -265.340143) (xy 370.358161 -265.340143)
			(xy 370.350036 -265.391438) (xy 370.333988 -265.440831) (xy 370.31041 -265.487105) (xy 370.279884 -265.529121)
			(xy 370.243161 -265.565844) (xy 370.201145 -265.59637) (xy 370.154871 -265.619948) (xy 370.105478 -265.635996)
			(xy 370.054183 -265.644121) (xy 370.002249 -265.644121) (xy 369.950954 -265.635996) (xy 369.901561 -265.619948)
			(xy 369.855287 -265.59637) (xy 369.813271 -265.565844) (xy 369.776548 -265.529121) (xy 369.746022 -265.487105)
			(xy 369.722444 -265.440831) (xy 369.706396 -265.391438) (xy 369.698271 -265.340143) (xy 368.478561 -265.340143)
			(xy 368.470436 -265.391438) (xy 368.454388 -265.440831) (xy 368.43081 -265.487105) (xy 368.400284 -265.529121)
			(xy 368.363561 -265.565844) (xy 368.321545 -265.59637) (xy 368.275271 -265.619948) (xy 368.225878 -265.635996)
			(xy 368.174583 -265.644121) (xy 368.122649 -265.644121) (xy 368.071354 -265.635996) (xy 368.021961 -265.619948)
			(xy 367.975687 -265.59637) (xy 367.933671 -265.565844) (xy 367.896948 -265.529121) (xy 367.866422 -265.487105)
			(xy 367.842844 -265.440831) (xy 367.826796 -265.391438) (xy 367.818671 -265.340143) (xy 367.538761 -265.340143)
			(xy 367.530636 -265.391438) (xy 367.514588 -265.440831) (xy 367.49101 -265.487105) (xy 367.460484 -265.529121)
			(xy 367.423761 -265.565844) (xy 367.381745 -265.59637) (xy 367.335471 -265.619948) (xy 367.286078 -265.635996)
			(xy 367.234783 -265.644121) (xy 367.182849 -265.644121) (xy 367.131554 -265.635996) (xy 367.082161 -265.619948)
			(xy 367.035887 -265.59637) (xy 366.993871 -265.565844) (xy 366.957148 -265.529121) (xy 366.926622 -265.487105)
			(xy 366.903044 -265.440831) (xy 366.886996 -265.391438) (xy 366.878871 -265.340143) (xy 366.598707 -265.340143)
			(xy 366.590582 -265.391438) (xy 366.574534 -265.440831) (xy 366.550956 -265.487105) (xy 366.52043 -265.529121)
			(xy 366.483707 -265.565844) (xy 366.441691 -265.59637) (xy 366.395417 -265.619948) (xy 366.346024 -265.635996)
			(xy 366.294729 -265.644121) (xy 366.242795 -265.644121) (xy 366.1915 -265.635996) (xy 366.142107 -265.619948)
			(xy 366.095833 -265.59637) (xy 366.053817 -265.565844) (xy 366.017094 -265.529121) (xy 365.986568 -265.487105)
			(xy 365.96299 -265.440831) (xy 365.946942 -265.391438) (xy 365.938817 -265.340143) (xy 365.659161 -265.340143)
			(xy 365.651036 -265.391438) (xy 365.634988 -265.440831) (xy 365.61141 -265.487105) (xy 365.580884 -265.529121)
			(xy 365.544161 -265.565844) (xy 365.502145 -265.59637) (xy 365.455871 -265.619948) (xy 365.406478 -265.635996)
			(xy 365.355183 -265.644121) (xy 365.303249 -265.644121) (xy 365.251954 -265.635996) (xy 365.202561 -265.619948)
			(xy 365.156287 -265.59637) (xy 365.114271 -265.565844) (xy 365.077548 -265.529121) (xy 365.047022 -265.487105)
			(xy 365.023444 -265.440831) (xy 365.007396 -265.391438) (xy 364.999271 -265.340143) (xy 364.719361 -265.340143)
			(xy 364.711236 -265.391438) (xy 364.695188 -265.440831) (xy 364.67161 -265.487105) (xy 364.641084 -265.529121)
			(xy 364.604361 -265.565844) (xy 364.562345 -265.59637) (xy 364.516071 -265.619948) (xy 364.466678 -265.635996)
			(xy 364.415383 -265.644121) (xy 364.363449 -265.644121) (xy 364.312154 -265.635996) (xy 364.262761 -265.619948)
			(xy 364.216487 -265.59637) (xy 364.174471 -265.565844) (xy 364.137748 -265.529121) (xy 364.107222 -265.487105)
			(xy 364.083644 -265.440831) (xy 364.067596 -265.391438) (xy 364.059471 -265.340143) (xy 363.779561 -265.340143)
			(xy 363.771436 -265.391438) (xy 363.755388 -265.440831) (xy 363.73181 -265.487105) (xy 363.701284 -265.529121)
			(xy 363.664561 -265.565844) (xy 363.622545 -265.59637) (xy 363.576271 -265.619948) (xy 363.526878 -265.635996)
			(xy 363.475583 -265.644121) (xy 363.423649 -265.644121) (xy 363.372354 -265.635996) (xy 363.322961 -265.619948)
			(xy 363.276687 -265.59637) (xy 363.234671 -265.565844) (xy 363.197948 -265.529121) (xy 363.167422 -265.487105)
			(xy 363.143844 -265.440831) (xy 363.127796 -265.391438) (xy 363.119671 -265.340143) (xy 362.839507 -265.340143)
			(xy 362.831382 -265.391438) (xy 362.815334 -265.440831) (xy 362.791756 -265.487105) (xy 362.76123 -265.529121)
			(xy 362.724507 -265.565844) (xy 362.682491 -265.59637) (xy 362.636217 -265.619948) (xy 362.586824 -265.635996)
			(xy 362.535529 -265.644121) (xy 362.483595 -265.644121) (xy 362.4323 -265.635996) (xy 362.382907 -265.619948)
			(xy 362.336633 -265.59637) (xy 362.294617 -265.565844) (xy 362.257894 -265.529121) (xy 362.227368 -265.487105)
			(xy 362.20379 -265.440831) (xy 362.187742 -265.391438) (xy 362.179617 -265.340143) (xy 361.899707 -265.340143)
			(xy 361.891582 -265.391438) (xy 361.875534 -265.440831) (xy 361.851956 -265.487105) (xy 361.82143 -265.529121)
			(xy 361.784707 -265.565844) (xy 361.742691 -265.59637) (xy 361.696417 -265.619948) (xy 361.647024 -265.635996)
			(xy 361.595729 -265.644121) (xy 361.543795 -265.644121) (xy 361.4925 -265.635996) (xy 361.443107 -265.619948)
			(xy 361.396833 -265.59637) (xy 361.354817 -265.565844) (xy 361.318094 -265.529121) (xy 361.287568 -265.487105)
			(xy 361.26399 -265.440831) (xy 361.247942 -265.391438) (xy 361.239817 -265.340143) (xy 360.959907 -265.340143)
			(xy 360.951782 -265.391438) (xy 360.935734 -265.440831) (xy 360.912156 -265.487105) (xy 360.88163 -265.529121)
			(xy 360.844907 -265.565844) (xy 360.802891 -265.59637) (xy 360.756617 -265.619948) (xy 360.707224 -265.635996)
			(xy 360.655929 -265.644121) (xy 360.603995 -265.644121) (xy 360.5527 -265.635996) (xy 360.503307 -265.619948)
			(xy 360.457033 -265.59637) (xy 360.415017 -265.565844) (xy 360.378294 -265.529121) (xy 360.347768 -265.487105)
			(xy 360.32419 -265.440831) (xy 360.308142 -265.391438) (xy 360.300017 -265.340143) (xy 360.020107 -265.340143)
			(xy 360.011982 -265.391438) (xy 359.995934 -265.440831) (xy 359.972356 -265.487105) (xy 359.94183 -265.529121)
			(xy 359.905107 -265.565844) (xy 359.863091 -265.59637) (xy 359.816817 -265.619948) (xy 359.767424 -265.635996)
			(xy 359.716129 -265.644121) (xy 359.664195 -265.644121) (xy 359.6129 -265.635996) (xy 359.563507 -265.619948)
			(xy 359.517233 -265.59637) (xy 359.475217 -265.565844) (xy 359.438494 -265.529121) (xy 359.407968 -265.487105)
			(xy 359.38439 -265.440831) (xy 359.368342 -265.391438) (xy 359.360217 -265.340143) (xy 359.080307 -265.340143)
			(xy 359.072182 -265.391438) (xy 359.056134 -265.440831) (xy 359.032556 -265.487105) (xy 359.00203 -265.529121)
			(xy 358.965307 -265.565844) (xy 358.923291 -265.59637) (xy 358.877017 -265.619948) (xy 358.827624 -265.635996)
			(xy 358.776329 -265.644121) (xy 358.724395 -265.644121) (xy 358.6731 -265.635996) (xy 358.623707 -265.619948)
			(xy 358.577433 -265.59637) (xy 358.535417 -265.565844) (xy 358.498694 -265.529121) (xy 358.468168 -265.487105)
			(xy 358.44459 -265.440831) (xy 358.428542 -265.391438) (xy 358.420417 -265.340143) (xy 358.140507 -265.340143)
			(xy 358.132382 -265.391438) (xy 358.116334 -265.440831) (xy 358.092756 -265.487105) (xy 358.06223 -265.529121)
			(xy 358.025507 -265.565844) (xy 357.983491 -265.59637) (xy 357.937217 -265.619948) (xy 357.887824 -265.635996)
			(xy 357.836529 -265.644121) (xy 357.784595 -265.644121) (xy 357.7333 -265.635996) (xy 357.683907 -265.619948)
			(xy 357.637633 -265.59637) (xy 357.595617 -265.565844) (xy 357.558894 -265.529121) (xy 357.528368 -265.487105)
			(xy 357.50479 -265.440831) (xy 357.488742 -265.391438) (xy 357.480617 -265.340143) (xy 357.200961 -265.340143)
			(xy 357.192836 -265.391438) (xy 357.176788 -265.440831) (xy 357.15321 -265.487105) (xy 357.122684 -265.529121)
			(xy 357.085961 -265.565844) (xy 357.043945 -265.59637) (xy 356.997671 -265.619948) (xy 356.948278 -265.635996)
			(xy 356.896983 -265.644121) (xy 356.845049 -265.644121) (xy 356.793754 -265.635996) (xy 356.744361 -265.619948)
			(xy 356.698087 -265.59637) (xy 356.656071 -265.565844) (xy 356.619348 -265.529121) (xy 356.588822 -265.487105)
			(xy 356.565244 -265.440831) (xy 356.549196 -265.391438) (xy 356.541071 -265.340143) (xy 355.321361 -265.340143)
			(xy 355.313236 -265.391438) (xy 355.297188 -265.440831) (xy 355.27361 -265.487105) (xy 355.243084 -265.529121)
			(xy 355.206361 -265.565844) (xy 355.164345 -265.59637) (xy 355.118071 -265.619948) (xy 355.068678 -265.635996)
			(xy 355.017383 -265.644121) (xy 354.965449 -265.644121) (xy 354.914154 -265.635996) (xy 354.864761 -265.619948)
			(xy 354.818487 -265.59637) (xy 354.776471 -265.565844) (xy 354.739748 -265.529121) (xy 354.709222 -265.487105)
			(xy 354.685644 -265.440831) (xy 354.669596 -265.391438) (xy 354.661471 -265.340143) (xy 354.381561 -265.340143)
			(xy 354.373436 -265.391438) (xy 354.357388 -265.440831) (xy 354.33381 -265.487105) (xy 354.303284 -265.529121)
			(xy 354.266561 -265.565844) (xy 354.224545 -265.59637) (xy 354.178271 -265.619948) (xy 354.128878 -265.635996)
			(xy 354.077583 -265.644121) (xy 354.025649 -265.644121) (xy 353.974354 -265.635996) (xy 353.924961 -265.619948)
			(xy 353.878687 -265.59637) (xy 353.836671 -265.565844) (xy 353.799948 -265.529121) (xy 353.769422 -265.487105)
			(xy 353.745844 -265.440831) (xy 353.729796 -265.391438) (xy 353.721671 -265.340143) (xy 353.441761 -265.340143)
			(xy 353.433636 -265.391438) (xy 353.417588 -265.440831) (xy 353.39401 -265.487105) (xy 353.363484 -265.529121)
			(xy 353.326761 -265.565844) (xy 353.284745 -265.59637) (xy 353.238471 -265.619948) (xy 353.189078 -265.635996)
			(xy 353.137783 -265.644121) (xy 353.085849 -265.644121) (xy 353.034554 -265.635996) (xy 352.985161 -265.619948)
			(xy 352.938887 -265.59637) (xy 352.896871 -265.565844) (xy 352.860148 -265.529121) (xy 352.829622 -265.487105)
			(xy 352.806044 -265.440831) (xy 352.789996 -265.391438) (xy 352.781871 -265.340143) (xy 352.501969 -265.340143)
			(xy 352.501969 -265.340168) (xy 352.493844 -265.391466) (xy 352.477795 -265.44086) (xy 352.454217 -265.487136)
			(xy 352.423691 -265.529155) (xy 352.386967 -265.56588) (xy 352.34495 -265.596409) (xy 352.298675 -265.619989)
			(xy 352.249281 -265.636041) (xy 352.197984 -265.644167) (xy 352.172016 -265.64463) (xy 352.142552 -265.64336)
			(xy 352.12851 -265.642583) (xy 352.100897 -265.647862) (xy 352.075768 -265.660467) (xy 352.055028 -265.679446)
			(xy 352.040247 -265.703359) (xy 352.032544 -265.730396) (xy 352.032062 -265.744452) (xy 352.032062 -266.116308)
			(xy 352.032316 -266.128246) (xy 352.032062 -266.140184) (xy 352.032062 -266.154213) (xy 352.311717 -266.154213)
			(xy 352.311717 -266.102279) (xy 352.319842 -266.050984) (xy 352.33589 -266.001591) (xy 352.359468 -265.955317)
			(xy 352.389994 -265.913301) (xy 352.426717 -265.876578) (xy 352.468733 -265.846052) (xy 352.515007 -265.822474)
			(xy 352.5644 -265.806426) (xy 352.615695 -265.798301) (xy 352.667629 -265.798301) (xy 352.718924 -265.806426)
			(xy 352.768317 -265.822474) (xy 352.814591 -265.846052) (xy 352.856607 -265.876578) (xy 352.89333 -265.913301)
			(xy 352.923856 -265.955317) (xy 352.947434 -266.001591) (xy 352.963482 -266.050984) (xy 352.971607 -266.102279)
			(xy 352.972116 -266.128246) (xy 352.971607 -266.154213) (xy 353.251517 -266.154213) (xy 353.251517 -266.102279)
			(xy 353.259642 -266.050984) (xy 353.27569 -266.001591) (xy 353.299268 -265.955317) (xy 353.329794 -265.913301)
			(xy 353.366517 -265.876578) (xy 353.408533 -265.846052) (xy 353.454807 -265.822474) (xy 353.5042 -265.806426)
			(xy 353.555495 -265.798301) (xy 353.607429 -265.798301) (xy 353.658724 -265.806426) (xy 353.708117 -265.822474)
			(xy 353.754391 -265.846052) (xy 353.796407 -265.876578) (xy 353.83313 -265.913301) (xy 353.863656 -265.955317)
			(xy 353.887234 -266.001591) (xy 353.903282 -266.050984) (xy 353.911407 -266.102279) (xy 353.911916 -266.128246)
			(xy 353.911407 -266.154213) (xy 354.191317 -266.154213) (xy 354.191317 -266.102279) (xy 354.199442 -266.050984)
			(xy 354.21549 -266.001591) (xy 354.239068 -265.955317) (xy 354.269594 -265.913301) (xy 354.306317 -265.876578)
			(xy 354.348333 -265.846052) (xy 354.394607 -265.822474) (xy 354.444 -265.806426) (xy 354.495295 -265.798301)
			(xy 354.547229 -265.798301) (xy 354.598524 -265.806426) (xy 354.647917 -265.822474) (xy 354.694191 -265.846052)
			(xy 354.736207 -265.876578) (xy 354.77293 -265.913301) (xy 354.803456 -265.955317) (xy 354.827034 -266.001591)
			(xy 354.843082 -266.050984) (xy 354.851207 -266.102279) (xy 354.851716 -266.128246) (xy 354.851207 -266.154213)
			(xy 355.131117 -266.154213) (xy 355.131117 -266.102279) (xy 355.139242 -266.050984) (xy 355.15529 -266.001591)
			(xy 355.178868 -265.955317) (xy 355.209394 -265.913301) (xy 355.246117 -265.876578) (xy 355.288133 -265.846052)
			(xy 355.334407 -265.822474) (xy 355.3838 -265.806426) (xy 355.435095 -265.798301) (xy 355.487029 -265.798301)
			(xy 355.538324 -265.806426) (xy 355.587717 -265.822474) (xy 355.633991 -265.846052) (xy 355.676007 -265.876578)
			(xy 355.71273 -265.913301) (xy 355.743256 -265.955317) (xy 355.766834 -266.001591) (xy 355.782882 -266.050984)
			(xy 355.791007 -266.102279) (xy 355.791516 -266.128246) (xy 355.791007 -266.154213) (xy 356.070917 -266.154213)
			(xy 356.070917 -266.102279) (xy 356.079042 -266.050984) (xy 356.09509 -266.001591) (xy 356.118668 -265.955317)
			(xy 356.149194 -265.913301) (xy 356.185917 -265.876578) (xy 356.227933 -265.846052) (xy 356.274207 -265.822474)
			(xy 356.3236 -265.806426) (xy 356.374895 -265.798301) (xy 356.426829 -265.798301) (xy 356.478124 -265.806426)
			(xy 356.527517 -265.822474) (xy 356.573791 -265.846052) (xy 356.615807 -265.876578) (xy 356.65253 -265.913301)
			(xy 356.683056 -265.955317) (xy 356.706634 -266.001591) (xy 356.722682 -266.050984) (xy 356.730807 -266.102279)
			(xy 356.731316 -266.128246) (xy 356.730807 -266.154213) (xy 357.010971 -266.154213) (xy 357.010971 -266.102279)
			(xy 357.019096 -266.050984) (xy 357.035144 -266.001591) (xy 357.058722 -265.955317) (xy 357.089248 -265.913301)
			(xy 357.125971 -265.876578) (xy 357.167987 -265.846052) (xy 357.214261 -265.822474) (xy 357.263654 -265.806426)
			(xy 357.314949 -265.798301) (xy 357.366883 -265.798301) (xy 357.418178 -265.806426) (xy 357.467571 -265.822474)
			(xy 357.513845 -265.846052) (xy 357.555861 -265.876578) (xy 357.592584 -265.913301) (xy 357.62311 -265.955317)
			(xy 357.646688 -266.001591) (xy 357.662736 -266.050984) (xy 357.670861 -266.102279) (xy 357.67137 -266.128246)
			(xy 357.670861 -266.154213) (xy 357.950771 -266.154213) (xy 357.950771 -266.102279) (xy 357.958896 -266.050984)
			(xy 357.974944 -266.001591) (xy 357.998522 -265.955317) (xy 358.029048 -265.913301) (xy 358.065771 -265.876578)
			(xy 358.107787 -265.846052) (xy 358.154061 -265.822474) (xy 358.203454 -265.806426) (xy 358.254749 -265.798301)
			(xy 358.306683 -265.798301) (xy 358.357978 -265.806426) (xy 358.407371 -265.822474) (xy 358.453645 -265.846052)
			(xy 358.495661 -265.876578) (xy 358.532384 -265.913301) (xy 358.56291 -265.955317) (xy 358.586488 -266.001591)
			(xy 358.602536 -266.050984) (xy 358.610661 -266.102279) (xy 358.61117 -266.128246) (xy 358.610661 -266.154213)
			(xy 358.890571 -266.154213) (xy 358.890571 -266.102279) (xy 358.898696 -266.050984) (xy 358.914744 -266.001591)
			(xy 358.938322 -265.955317) (xy 358.968848 -265.913301) (xy 359.005571 -265.876578) (xy 359.047587 -265.846052)
			(xy 359.093861 -265.822474) (xy 359.143254 -265.806426) (xy 359.194549 -265.798301) (xy 359.246483 -265.798301)
			(xy 359.297778 -265.806426) (xy 359.347171 -265.822474) (xy 359.393445 -265.846052) (xy 359.435461 -265.876578)
			(xy 359.472184 -265.913301) (xy 359.50271 -265.955317) (xy 359.526288 -266.001591) (xy 359.542336 -266.050984)
			(xy 359.550461 -266.102279) (xy 359.55097 -266.128246) (xy 359.550461 -266.154213) (xy 359.830371 -266.154213)
			(xy 359.830371 -266.102279) (xy 359.838496 -266.050984) (xy 359.854544 -266.001591) (xy 359.878122 -265.955317)
			(xy 359.908648 -265.913301) (xy 359.945371 -265.876578) (xy 359.987387 -265.846052) (xy 360.033661 -265.822474)
			(xy 360.083054 -265.806426) (xy 360.134349 -265.798301) (xy 360.186283 -265.798301) (xy 360.237578 -265.806426)
			(xy 360.286971 -265.822474) (xy 360.333245 -265.846052) (xy 360.375261 -265.876578) (xy 360.411984 -265.913301)
			(xy 360.44251 -265.955317) (xy 360.466088 -266.001591) (xy 360.482136 -266.050984) (xy 360.490261 -266.102279)
			(xy 360.49077 -266.128246) (xy 360.490261 -266.154213) (xy 360.769917 -266.154213) (xy 360.769917 -266.102279)
			(xy 360.778042 -266.050984) (xy 360.79409 -266.001591) (xy 360.817668 -265.955317) (xy 360.848194 -265.913301)
			(xy 360.884917 -265.876578) (xy 360.926933 -265.846052) (xy 360.973207 -265.822474) (xy 361.0226 -265.806426)
			(xy 361.073895 -265.798301) (xy 361.125829 -265.798301) (xy 361.177124 -265.806426) (xy 361.226517 -265.822474)
			(xy 361.272791 -265.846052) (xy 361.314807 -265.876578) (xy 361.35153 -265.913301) (xy 361.382056 -265.955317)
			(xy 361.405634 -266.001591) (xy 361.421682 -266.050984) (xy 361.429807 -266.102279) (xy 361.430316 -266.128246)
			(xy 361.429807 -266.154213) (xy 361.709717 -266.154213) (xy 361.709717 -266.102279) (xy 361.717842 -266.050984)
			(xy 361.73389 -266.001591) (xy 361.757468 -265.955317) (xy 361.787994 -265.913301) (xy 361.824717 -265.876578)
			(xy 361.866733 -265.846052) (xy 361.913007 -265.822474) (xy 361.9624 -265.806426) (xy 362.013695 -265.798301)
			(xy 362.065629 -265.798301) (xy 362.116924 -265.806426) (xy 362.166317 -265.822474) (xy 362.212591 -265.846052)
			(xy 362.254607 -265.876578) (xy 362.29133 -265.913301) (xy 362.321856 -265.955317) (xy 362.345434 -266.001591)
			(xy 362.361482 -266.050984) (xy 362.369607 -266.102279) (xy 362.370116 -266.128246) (xy 362.369607 -266.154213)
			(xy 362.649517 -266.154213) (xy 362.649517 -266.102279) (xy 362.657642 -266.050984) (xy 362.67369 -266.001591)
			(xy 362.697268 -265.955317) (xy 362.727794 -265.913301) (xy 362.764517 -265.876578) (xy 362.806533 -265.846052)
			(xy 362.852807 -265.822474) (xy 362.9022 -265.806426) (xy 362.953495 -265.798301) (xy 363.005429 -265.798301)
			(xy 363.056724 -265.806426) (xy 363.106117 -265.822474) (xy 363.152391 -265.846052) (xy 363.194407 -265.876578)
			(xy 363.23113 -265.913301) (xy 363.261656 -265.955317) (xy 363.285234 -266.001591) (xy 363.301282 -266.050984)
			(xy 363.309407 -266.102279) (xy 363.309916 -266.128246) (xy 363.309407 -266.154213) (xy 363.589317 -266.154213)
			(xy 363.589317 -266.102279) (xy 363.597442 -266.050984) (xy 363.61349 -266.001591) (xy 363.637068 -265.955317)
			(xy 363.667594 -265.913301) (xy 363.704317 -265.876578) (xy 363.746333 -265.846052) (xy 363.792607 -265.822474)
			(xy 363.842 -265.806426) (xy 363.893295 -265.798301) (xy 363.945229 -265.798301) (xy 363.996524 -265.806426)
			(xy 364.045917 -265.822474) (xy 364.092191 -265.846052) (xy 364.134207 -265.876578) (xy 364.17093 -265.913301)
			(xy 364.201456 -265.955317) (xy 364.225034 -266.001591) (xy 364.241082 -266.050984) (xy 364.249207 -266.102279)
			(xy 364.249716 -266.128246) (xy 364.249207 -266.154213) (xy 364.249167 -266.154467) (xy 364.529117 -266.154467)
			(xy 364.529117 -266.102533) (xy 364.537242 -266.051238) (xy 364.55329 -266.001845) (xy 364.576868 -265.955571)
			(xy 364.607394 -265.913555) (xy 364.644117 -265.876832) (xy 364.686133 -265.846306) (xy 364.732407 -265.822728)
			(xy 364.7818 -265.80668) (xy 364.833095 -265.798555) (xy 364.885029 -265.798555) (xy 364.936324 -265.80668)
			(xy 364.985717 -265.822728) (xy 365.031991 -265.846306) (xy 365.074007 -265.876832) (xy 365.11073 -265.913555)
			(xy 365.141256 -265.955571) (xy 365.164834 -266.001845) (xy 365.180882 -266.051238) (xy 365.189007 -266.102533)
			(xy 365.189516 -266.1285) (xy 365.189012 -266.154213) (xy 365.468917 -266.154213) (xy 365.468917 -266.102279)
			(xy 365.477042 -266.050984) (xy 365.49309 -266.001591) (xy 365.516668 -265.955317) (xy 365.547194 -265.913301)
			(xy 365.583917 -265.876578) (xy 365.625933 -265.846052) (xy 365.672207 -265.822474) (xy 365.7216 -265.806426)
			(xy 365.772895 -265.798301) (xy 365.824829 -265.798301) (xy 365.876124 -265.806426) (xy 365.925517 -265.822474)
			(xy 365.971791 -265.846052) (xy 366.013807 -265.876578) (xy 366.05053 -265.913301) (xy 366.081056 -265.955317)
			(xy 366.104634 -266.001591) (xy 366.120682 -266.050984) (xy 366.128807 -266.102279) (xy 366.129316 -266.128246)
			(xy 366.128807 -266.154213) (xy 366.128767 -266.154467) (xy 366.408717 -266.154467) (xy 366.408717 -266.102533)
			(xy 366.416842 -266.051238) (xy 366.43289 -266.001845) (xy 366.456468 -265.955571) (xy 366.486994 -265.913555)
			(xy 366.523717 -265.876832) (xy 366.565733 -265.846306) (xy 366.612007 -265.822728) (xy 366.6614 -265.80668)
			(xy 366.712695 -265.798555) (xy 366.764629 -265.798555) (xy 366.815924 -265.80668) (xy 366.865317 -265.822728)
			(xy 366.911591 -265.846306) (xy 366.953607 -265.876832) (xy 366.99033 -265.913555) (xy 367.020856 -265.955571)
			(xy 367.044434 -266.001845) (xy 367.060482 -266.051238) (xy 367.068607 -266.102533) (xy 367.069116 -266.1285)
			(xy 367.068612 -266.154213) (xy 367.348517 -266.154213) (xy 367.348517 -266.102279) (xy 367.356642 -266.050984)
			(xy 367.37269 -266.001591) (xy 367.396268 -265.955317) (xy 367.426794 -265.913301) (xy 367.463517 -265.876578)
			(xy 367.505533 -265.846052) (xy 367.551807 -265.822474) (xy 367.6012 -265.806426) (xy 367.652495 -265.798301)
			(xy 367.704429 -265.798301) (xy 367.755724 -265.806426) (xy 367.805117 -265.822474) (xy 367.851391 -265.846052)
			(xy 367.893407 -265.876578) (xy 367.93013 -265.913301) (xy 367.960656 -265.955317) (xy 367.984234 -266.001591)
			(xy 368.000282 -266.050984) (xy 368.008407 -266.102279) (xy 368.008916 -266.128246) (xy 368.008407 -266.154213)
			(xy 368.288317 -266.154213) (xy 368.288317 -266.102279) (xy 368.296442 -266.050984) (xy 368.31249 -266.001591)
			(xy 368.336068 -265.955317) (xy 368.366594 -265.913301) (xy 368.403317 -265.876578) (xy 368.445333 -265.846052)
			(xy 368.491607 -265.822474) (xy 368.541 -265.806426) (xy 368.592295 -265.798301) (xy 368.644229 -265.798301)
			(xy 368.695524 -265.806426) (xy 368.744917 -265.822474) (xy 368.791191 -265.846052) (xy 368.833207 -265.876578)
			(xy 368.86993 -265.913301) (xy 368.900456 -265.955317) (xy 368.924034 -266.001591) (xy 368.940082 -266.050984)
			(xy 368.948207 -266.102279) (xy 368.948716 -266.128246) (xy 368.948207 -266.154213) (xy 370.167917 -266.154213)
			(xy 370.167917 -266.102279) (xy 370.176042 -266.050984) (xy 370.19209 -266.001591) (xy 370.215668 -265.955317)
			(xy 370.246194 -265.913301) (xy 370.282917 -265.876578) (xy 370.324933 -265.846052) (xy 370.371207 -265.822474)
			(xy 370.4206 -265.806426) (xy 370.471895 -265.798301) (xy 370.523829 -265.798301) (xy 370.575124 -265.806426)
			(xy 370.624517 -265.822474) (xy 370.670791 -265.846052) (xy 370.712807 -265.876578) (xy 370.74953 -265.913301)
			(xy 370.780056 -265.955317) (xy 370.803634 -266.001591) (xy 370.819682 -266.050984) (xy 370.827807 -266.102279)
			(xy 370.828316 -266.128246) (xy 370.827807 -266.154213) (xy 370.819682 -266.205508) (xy 370.803634 -266.254901)
			(xy 370.780056 -266.301175) (xy 370.74953 -266.343191) (xy 370.712807 -266.379914) (xy 370.670791 -266.41044)
			(xy 370.624517 -266.434018) (xy 370.575124 -266.450066) (xy 370.523829 -266.458191) (xy 370.471895 -266.458191)
			(xy 370.4206 -266.450066) (xy 370.371207 -266.434018) (xy 370.324933 -266.41044) (xy 370.282917 -266.379914)
			(xy 370.246194 -266.343191) (xy 370.215668 -266.301175) (xy 370.19209 -266.254901) (xy 370.176042 -266.205508)
			(xy 370.167917 -266.154213) (xy 368.948207 -266.154213) (xy 368.940082 -266.205508) (xy 368.924034 -266.254901)
			(xy 368.900456 -266.301175) (xy 368.86993 -266.343191) (xy 368.833207 -266.379914) (xy 368.791191 -266.41044)
			(xy 368.744917 -266.434018) (xy 368.695524 -266.450066) (xy 368.644229 -266.458191) (xy 368.592295 -266.458191)
			(xy 368.541 -266.450066) (xy 368.491607 -266.434018) (xy 368.445333 -266.41044) (xy 368.403317 -266.379914)
			(xy 368.366594 -266.343191) (xy 368.336068 -266.301175) (xy 368.31249 -266.254901) (xy 368.296442 -266.205508)
			(xy 368.288317 -266.154213) (xy 368.008407 -266.154213) (xy 368.000282 -266.205508) (xy 367.984234 -266.254901)
			(xy 367.960656 -266.301175) (xy 367.93013 -266.343191) (xy 367.893407 -266.379914) (xy 367.851391 -266.41044)
			(xy 367.805117 -266.434018) (xy 367.755724 -266.450066) (xy 367.704429 -266.458191) (xy 367.652495 -266.458191)
			(xy 367.6012 -266.450066) (xy 367.551807 -266.434018) (xy 367.505533 -266.41044) (xy 367.463517 -266.379914)
			(xy 367.426794 -266.343191) (xy 367.396268 -266.301175) (xy 367.37269 -266.254901) (xy 367.356642 -266.205508)
			(xy 367.348517 -266.154213) (xy 367.068612 -266.154213) (xy 367.068607 -266.154467) (xy 367.060482 -266.205762)
			(xy 367.044434 -266.255155) (xy 367.020856 -266.301429) (xy 366.99033 -266.343445) (xy 366.953607 -266.380168)
			(xy 366.911591 -266.410694) (xy 366.865317 -266.434272) (xy 366.815924 -266.45032) (xy 366.764629 -266.458445)
			(xy 366.712695 -266.458445) (xy 366.6614 -266.45032) (xy 366.612007 -266.434272) (xy 366.565733 -266.410694)
			(xy 366.523717 -266.380168) (xy 366.486994 -266.343445) (xy 366.456468 -266.301429) (xy 366.43289 -266.255155)
			(xy 366.416842 -266.205762) (xy 366.408717 -266.154467) (xy 366.128767 -266.154467) (xy 366.120682 -266.205508)
			(xy 366.104634 -266.254901) (xy 366.081056 -266.301175) (xy 366.05053 -266.343191) (xy 366.013807 -266.379914)
			(xy 365.971791 -266.41044) (xy 365.925517 -266.434018) (xy 365.876124 -266.450066) (xy 365.824829 -266.458191)
			(xy 365.772895 -266.458191) (xy 365.7216 -266.450066) (xy 365.672207 -266.434018) (xy 365.625933 -266.41044)
			(xy 365.583917 -266.379914) (xy 365.547194 -266.343191) (xy 365.516668 -266.301175) (xy 365.49309 -266.254901)
			(xy 365.477042 -266.205508) (xy 365.468917 -266.154213) (xy 365.189012 -266.154213) (xy 365.189007 -266.154467)
			(xy 365.180882 -266.205762) (xy 365.164834 -266.255155) (xy 365.141256 -266.301429) (xy 365.11073 -266.343445)
			(xy 365.074007 -266.380168) (xy 365.031991 -266.410694) (xy 364.985717 -266.434272) (xy 364.936324 -266.45032)
			(xy 364.885029 -266.458445) (xy 364.833095 -266.458445) (xy 364.7818 -266.45032) (xy 364.732407 -266.434272)
			(xy 364.686133 -266.410694) (xy 364.644117 -266.380168) (xy 364.607394 -266.343445) (xy 364.576868 -266.301429)
			(xy 364.55329 -266.255155) (xy 364.537242 -266.205762) (xy 364.529117 -266.154467) (xy 364.249167 -266.154467)
			(xy 364.241082 -266.205508) (xy 364.225034 -266.254901) (xy 364.201456 -266.301175) (xy 364.17093 -266.343191)
			(xy 364.134207 -266.379914) (xy 364.092191 -266.41044) (xy 364.045917 -266.434018) (xy 363.996524 -266.450066)
			(xy 363.945229 -266.458191) (xy 363.893295 -266.458191) (xy 363.842 -266.450066) (xy 363.792607 -266.434018)
			(xy 363.746333 -266.41044) (xy 363.704317 -266.379914) (xy 363.667594 -266.343191) (xy 363.637068 -266.301175)
			(xy 363.61349 -266.254901) (xy 363.597442 -266.205508) (xy 363.589317 -266.154213) (xy 363.309407 -266.154213)
			(xy 363.301282 -266.205508) (xy 363.285234 -266.254901) (xy 363.261656 -266.301175) (xy 363.23113 -266.343191)
			(xy 363.194407 -266.379914) (xy 363.152391 -266.41044) (xy 363.106117 -266.434018) (xy 363.056724 -266.450066)
			(xy 363.005429 -266.458191) (xy 362.953495 -266.458191) (xy 362.9022 -266.450066) (xy 362.852807 -266.434018)
			(xy 362.806533 -266.41044) (xy 362.764517 -266.379914) (xy 362.727794 -266.343191) (xy 362.697268 -266.301175)
			(xy 362.67369 -266.254901) (xy 362.657642 -266.205508) (xy 362.649517 -266.154213) (xy 362.369607 -266.154213)
			(xy 362.361482 -266.205508) (xy 362.345434 -266.254901) (xy 362.321856 -266.301175) (xy 362.29133 -266.343191)
			(xy 362.254607 -266.379914) (xy 362.212591 -266.41044) (xy 362.166317 -266.434018) (xy 362.116924 -266.450066)
			(xy 362.065629 -266.458191) (xy 362.013695 -266.458191) (xy 361.9624 -266.450066) (xy 361.913007 -266.434018)
			(xy 361.866733 -266.41044) (xy 361.824717 -266.379914) (xy 361.787994 -266.343191) (xy 361.757468 -266.301175)
			(xy 361.73389 -266.254901) (xy 361.717842 -266.205508) (xy 361.709717 -266.154213) (xy 361.429807 -266.154213)
			(xy 361.421682 -266.205508) (xy 361.405634 -266.254901) (xy 361.382056 -266.301175) (xy 361.35153 -266.343191)
			(xy 361.314807 -266.379914) (xy 361.272791 -266.41044) (xy 361.226517 -266.434018) (xy 361.177124 -266.450066)
			(xy 361.125829 -266.458191) (xy 361.073895 -266.458191) (xy 361.0226 -266.450066) (xy 360.973207 -266.434018)
			(xy 360.926933 -266.41044) (xy 360.884917 -266.379914) (xy 360.848194 -266.343191) (xy 360.817668 -266.301175)
			(xy 360.79409 -266.254901) (xy 360.778042 -266.205508) (xy 360.769917 -266.154213) (xy 360.490261 -266.154213)
			(xy 360.482136 -266.205508) (xy 360.466088 -266.254901) (xy 360.44251 -266.301175) (xy 360.411984 -266.343191)
			(xy 360.375261 -266.379914) (xy 360.333245 -266.41044) (xy 360.286971 -266.434018) (xy 360.237578 -266.450066)
			(xy 360.186283 -266.458191) (xy 360.134349 -266.458191) (xy 360.083054 -266.450066) (xy 360.033661 -266.434018)
			(xy 359.987387 -266.41044) (xy 359.945371 -266.379914) (xy 359.908648 -266.343191) (xy 359.878122 -266.301175)
			(xy 359.854544 -266.254901) (xy 359.838496 -266.205508) (xy 359.830371 -266.154213) (xy 359.550461 -266.154213)
			(xy 359.542336 -266.205508) (xy 359.526288 -266.254901) (xy 359.50271 -266.301175) (xy 359.472184 -266.343191)
			(xy 359.435461 -266.379914) (xy 359.393445 -266.41044) (xy 359.347171 -266.434018) (xy 359.297778 -266.450066)
			(xy 359.246483 -266.458191) (xy 359.194549 -266.458191) (xy 359.143254 -266.450066) (xy 359.093861 -266.434018)
			(xy 359.047587 -266.41044) (xy 359.005571 -266.379914) (xy 358.968848 -266.343191) (xy 358.938322 -266.301175)
			(xy 358.914744 -266.254901) (xy 358.898696 -266.205508) (xy 358.890571 -266.154213) (xy 358.610661 -266.154213)
			(xy 358.602536 -266.205508) (xy 358.586488 -266.254901) (xy 358.56291 -266.301175) (xy 358.532384 -266.343191)
			(xy 358.495661 -266.379914) (xy 358.453645 -266.41044) (xy 358.407371 -266.434018) (xy 358.357978 -266.450066)
			(xy 358.306683 -266.458191) (xy 358.254749 -266.458191) (xy 358.203454 -266.450066) (xy 358.154061 -266.434018)
			(xy 358.107787 -266.41044) (xy 358.065771 -266.379914) (xy 358.029048 -266.343191) (xy 357.998522 -266.301175)
			(xy 357.974944 -266.254901) (xy 357.958896 -266.205508) (xy 357.950771 -266.154213) (xy 357.670861 -266.154213)
			(xy 357.662736 -266.205508) (xy 357.646688 -266.254901) (xy 357.62311 -266.301175) (xy 357.592584 -266.343191)
			(xy 357.555861 -266.379914) (xy 357.513845 -266.41044) (xy 357.467571 -266.434018) (xy 357.418178 -266.450066)
			(xy 357.366883 -266.458191) (xy 357.314949 -266.458191) (xy 357.263654 -266.450066) (xy 357.214261 -266.434018)
			(xy 357.167987 -266.41044) (xy 357.125971 -266.379914) (xy 357.089248 -266.343191) (xy 357.058722 -266.301175)
			(xy 357.035144 -266.254901) (xy 357.019096 -266.205508) (xy 357.010971 -266.154213) (xy 356.730807 -266.154213)
			(xy 356.722682 -266.205508) (xy 356.706634 -266.254901) (xy 356.683056 -266.301175) (xy 356.65253 -266.343191)
			(xy 356.615807 -266.379914) (xy 356.573791 -266.41044) (xy 356.527517 -266.434018) (xy 356.478124 -266.450066)
			(xy 356.426829 -266.458191) (xy 356.374895 -266.458191) (xy 356.3236 -266.450066) (xy 356.274207 -266.434018)
			(xy 356.227933 -266.41044) (xy 356.185917 -266.379914) (xy 356.149194 -266.343191) (xy 356.118668 -266.301175)
			(xy 356.09509 -266.254901) (xy 356.079042 -266.205508) (xy 356.070917 -266.154213) (xy 355.791007 -266.154213)
			(xy 355.782882 -266.205508) (xy 355.766834 -266.254901) (xy 355.743256 -266.301175) (xy 355.71273 -266.343191)
			(xy 355.676007 -266.379914) (xy 355.633991 -266.41044) (xy 355.587717 -266.434018) (xy 355.538324 -266.450066)
			(xy 355.487029 -266.458191) (xy 355.435095 -266.458191) (xy 355.3838 -266.450066) (xy 355.334407 -266.434018)
			(xy 355.288133 -266.41044) (xy 355.246117 -266.379914) (xy 355.209394 -266.343191) (xy 355.178868 -266.301175)
			(xy 355.15529 -266.254901) (xy 355.139242 -266.205508) (xy 355.131117 -266.154213) (xy 354.851207 -266.154213)
			(xy 354.843082 -266.205508) (xy 354.827034 -266.254901) (xy 354.803456 -266.301175) (xy 354.77293 -266.343191)
			(xy 354.736207 -266.379914) (xy 354.694191 -266.41044) (xy 354.647917 -266.434018) (xy 354.598524 -266.450066)
			(xy 354.547229 -266.458191) (xy 354.495295 -266.458191) (xy 354.444 -266.450066) (xy 354.394607 -266.434018)
			(xy 354.348333 -266.41044) (xy 354.306317 -266.379914) (xy 354.269594 -266.343191) (xy 354.239068 -266.301175)
			(xy 354.21549 -266.254901) (xy 354.199442 -266.205508) (xy 354.191317 -266.154213) (xy 353.911407 -266.154213)
			(xy 353.903282 -266.205508) (xy 353.887234 -266.254901) (xy 353.863656 -266.301175) (xy 353.83313 -266.343191)
			(xy 353.796407 -266.379914) (xy 353.754391 -266.41044) (xy 353.708117 -266.434018) (xy 353.658724 -266.450066)
			(xy 353.607429 -266.458191) (xy 353.555495 -266.458191) (xy 353.5042 -266.450066) (xy 353.454807 -266.434018)
			(xy 353.408533 -266.41044) (xy 353.366517 -266.379914) (xy 353.329794 -266.343191) (xy 353.299268 -266.301175)
			(xy 353.27569 -266.254901) (xy 353.259642 -266.205508) (xy 353.251517 -266.154213) (xy 352.971607 -266.154213)
			(xy 352.963482 -266.205508) (xy 352.947434 -266.254901) (xy 352.923856 -266.301175) (xy 352.89333 -266.343191)
			(xy 352.856607 -266.379914) (xy 352.814591 -266.41044) (xy 352.768317 -266.434018) (xy 352.718924 -266.450066)
			(xy 352.667629 -266.458191) (xy 352.615695 -266.458191) (xy 352.5644 -266.450066) (xy 352.515007 -266.434018)
			(xy 352.468733 -266.41044) (xy 352.426717 -266.379914) (xy 352.389994 -266.343191) (xy 352.359468 -266.301175)
			(xy 352.33589 -266.254901) (xy 352.319842 -266.205508) (xy 352.311717 -266.154213) (xy 352.032062 -266.154213)
			(xy 352.032062 -266.576302) (xy 352.079306 -266.623546) (xy 352.105976 -266.617958) (xy 352.122308 -266.614851)
			(xy 352.155392 -266.611544) (xy 352.172016 -266.611354) (xy 352.197982 -266.611864) (xy 352.249275 -266.619991)
			(xy 352.298665 -266.636041) (xy 352.344936 -266.65962) (xy 352.386949 -266.690146) (xy 352.423669 -266.726869)
			(xy 352.454193 -266.768885) (xy 352.477768 -266.815157) (xy 352.493815 -266.864549) (xy 352.501937 -266.915842)
			(xy 352.50247 -266.941808) (xy 352.502276 -266.958432) (xy 352.501341 -266.967775) (xy 352.781871 -266.967775)
			(xy 352.781871 -266.915841) (xy 352.789996 -266.864546) (xy 352.806044 -266.815153) (xy 352.829622 -266.768879)
			(xy 352.860148 -266.726863) (xy 352.896871 -266.69014) (xy 352.938887 -266.659614) (xy 352.985161 -266.636036)
			(xy 353.034554 -266.619988) (xy 353.085849 -266.611863) (xy 353.137783 -266.611863) (xy 353.189078 -266.619988)
			(xy 353.238471 -266.636036) (xy 353.284745 -266.659614) (xy 353.326761 -266.69014) (xy 353.363484 -266.726863)
			(xy 353.39401 -266.768879) (xy 353.417588 -266.815153) (xy 353.433636 -266.864546) (xy 353.441761 -266.915841)
			(xy 353.44227 -266.941808) (xy 353.441761 -266.967775) (xy 353.721671 -266.967775) (xy 353.721671 -266.915841)
			(xy 353.729796 -266.864546) (xy 353.745844 -266.815153) (xy 353.769422 -266.768879) (xy 353.799948 -266.726863)
			(xy 353.836671 -266.69014) (xy 353.878687 -266.659614) (xy 353.924961 -266.636036) (xy 353.974354 -266.619988)
			(xy 354.025649 -266.611863) (xy 354.077583 -266.611863) (xy 354.128878 -266.619988) (xy 354.178271 -266.636036)
			(xy 354.224545 -266.659614) (xy 354.266561 -266.69014) (xy 354.303284 -266.726863) (xy 354.33381 -266.768879)
			(xy 354.357388 -266.815153) (xy 354.373436 -266.864546) (xy 354.381561 -266.915841) (xy 354.38207 -266.941808)
			(xy 354.381561 -266.967775) (xy 354.661471 -266.967775) (xy 354.661471 -266.915841) (xy 354.669596 -266.864546)
			(xy 354.685644 -266.815153) (xy 354.709222 -266.768879) (xy 354.739748 -266.726863) (xy 354.776471 -266.69014)
			(xy 354.818487 -266.659614) (xy 354.864761 -266.636036) (xy 354.914154 -266.619988) (xy 354.965449 -266.611863)
			(xy 355.017383 -266.611863) (xy 355.068678 -266.619988) (xy 355.118071 -266.636036) (xy 355.164345 -266.659614)
			(xy 355.206361 -266.69014) (xy 355.243084 -266.726863) (xy 355.27361 -266.768879) (xy 355.297188 -266.815153)
			(xy 355.313236 -266.864546) (xy 355.321361 -266.915841) (xy 355.32187 -266.941808) (xy 355.321361 -266.967775)
			(xy 355.601271 -266.967775) (xy 355.601271 -266.915841) (xy 355.609396 -266.864546) (xy 355.625444 -266.815153)
			(xy 355.649022 -266.768879) (xy 355.679548 -266.726863) (xy 355.716271 -266.69014) (xy 355.758287 -266.659614)
			(xy 355.804561 -266.636036) (xy 355.853954 -266.619988) (xy 355.905249 -266.611863) (xy 355.957183 -266.611863)
			(xy 356.008478 -266.619988) (xy 356.057871 -266.636036) (xy 356.104145 -266.659614) (xy 356.146161 -266.69014)
			(xy 356.182884 -266.726863) (xy 356.21341 -266.768879) (xy 356.236988 -266.815153) (xy 356.253036 -266.864546)
			(xy 356.261161 -266.915841) (xy 356.26167 -266.941808) (xy 356.261161 -266.967775) (xy 356.541071 -266.967775)
			(xy 356.541071 -266.915841) (xy 356.549196 -266.864546) (xy 356.565244 -266.815153) (xy 356.588822 -266.768879)
			(xy 356.619348 -266.726863) (xy 356.656071 -266.69014) (xy 356.698087 -266.659614) (xy 356.744361 -266.636036)
			(xy 356.793754 -266.619988) (xy 356.845049 -266.611863) (xy 356.896983 -266.611863) (xy 356.948278 -266.619988)
			(xy 356.997671 -266.636036) (xy 357.043945 -266.659614) (xy 357.085961 -266.69014) (xy 357.122684 -266.726863)
			(xy 357.15321 -266.768879) (xy 357.176788 -266.815153) (xy 357.192836 -266.864546) (xy 357.200961 -266.915841)
			(xy 357.20147 -266.941808) (xy 357.200961 -266.967775) (xy 357.480617 -266.967775) (xy 357.480617 -266.915841)
			(xy 357.488742 -266.864546) (xy 357.50479 -266.815153) (xy 357.528368 -266.768879) (xy 357.558894 -266.726863)
			(xy 357.595617 -266.69014) (xy 357.637633 -266.659614) (xy 357.683907 -266.636036) (xy 357.7333 -266.619988)
			(xy 357.784595 -266.611863) (xy 357.836529 -266.611863) (xy 357.887824 -266.619988) (xy 357.937217 -266.636036)
			(xy 357.983491 -266.659614) (xy 358.025507 -266.69014) (xy 358.06223 -266.726863) (xy 358.092756 -266.768879)
			(xy 358.116334 -266.815153) (xy 358.132382 -266.864546) (xy 358.140507 -266.915841) (xy 358.141016 -266.941808)
			(xy 358.140507 -266.967775) (xy 358.420671 -266.967775) (xy 358.420671 -266.915841) (xy 358.428796 -266.864546)
			(xy 358.444844 -266.815153) (xy 358.468422 -266.768879) (xy 358.498948 -266.726863) (xy 358.535671 -266.69014)
			(xy 358.577687 -266.659614) (xy 358.623961 -266.636036) (xy 358.673354 -266.619988) (xy 358.724649 -266.611863)
			(xy 358.776583 -266.611863) (xy 358.827878 -266.619988) (xy 358.877271 -266.636036) (xy 358.923545 -266.659614)
			(xy 358.965561 -266.69014) (xy 359.002284 -266.726863) (xy 359.03281 -266.768879) (xy 359.056388 -266.815153)
			(xy 359.072436 -266.864546) (xy 359.080561 -266.915841) (xy 359.08107 -266.941808) (xy 359.080561 -266.967775)
			(xy 359.360217 -266.967775) (xy 359.360217 -266.915841) (xy 359.368342 -266.864546) (xy 359.38439 -266.815153)
			(xy 359.407968 -266.768879) (xy 359.438494 -266.726863) (xy 359.475217 -266.69014) (xy 359.517233 -266.659614)
			(xy 359.563507 -266.636036) (xy 359.6129 -266.619988) (xy 359.664195 -266.611863) (xy 359.716129 -266.611863)
			(xy 359.767424 -266.619988) (xy 359.816817 -266.636036) (xy 359.863091 -266.659614) (xy 359.905107 -266.69014)
			(xy 359.94183 -266.726863) (xy 359.972356 -266.768879) (xy 359.995934 -266.815153) (xy 360.011982 -266.864546)
			(xy 360.020107 -266.915841) (xy 360.020616 -266.941808) (xy 360.020107 -266.967775) (xy 360.300017 -266.967775)
			(xy 360.300017 -266.915841) (xy 360.308142 -266.864546) (xy 360.32419 -266.815153) (xy 360.347768 -266.768879)
			(xy 360.378294 -266.726863) (xy 360.415017 -266.69014) (xy 360.457033 -266.659614) (xy 360.503307 -266.636036)
			(xy 360.5527 -266.619988) (xy 360.603995 -266.611863) (xy 360.655929 -266.611863) (xy 360.707224 -266.619988)
			(xy 360.756617 -266.636036) (xy 360.802891 -266.659614) (xy 360.844907 -266.69014) (xy 360.88163 -266.726863)
			(xy 360.912156 -266.768879) (xy 360.935734 -266.815153) (xy 360.951782 -266.864546) (xy 360.959907 -266.915841)
			(xy 360.960416 -266.941808) (xy 360.959907 -266.967775) (xy 361.239817 -266.967775) (xy 361.239817 -266.915841)
			(xy 361.247942 -266.864546) (xy 361.26399 -266.815153) (xy 361.287568 -266.768879) (xy 361.318094 -266.726863)
			(xy 361.354817 -266.69014) (xy 361.396833 -266.659614) (xy 361.443107 -266.636036) (xy 361.4925 -266.619988)
			(xy 361.543795 -266.611863) (xy 361.595729 -266.611863) (xy 361.647024 -266.619988) (xy 361.696417 -266.636036)
			(xy 361.742691 -266.659614) (xy 361.784707 -266.69014) (xy 361.82143 -266.726863) (xy 361.851956 -266.768879)
			(xy 361.875534 -266.815153) (xy 361.891582 -266.864546) (xy 361.899707 -266.915841) (xy 361.900216 -266.941808)
			(xy 361.899707 -266.967775) (xy 362.179617 -266.967775) (xy 362.179617 -266.915841) (xy 362.187742 -266.864546)
			(xy 362.20379 -266.815153) (xy 362.227368 -266.768879) (xy 362.257894 -266.726863) (xy 362.294617 -266.69014)
			(xy 362.336633 -266.659614) (xy 362.382907 -266.636036) (xy 362.4323 -266.619988) (xy 362.483595 -266.611863)
			(xy 362.535529 -266.611863) (xy 362.586824 -266.619988) (xy 362.636217 -266.636036) (xy 362.682491 -266.659614)
			(xy 362.724507 -266.69014) (xy 362.76123 -266.726863) (xy 362.791756 -266.768879) (xy 362.815334 -266.815153)
			(xy 362.831382 -266.864546) (xy 362.839507 -266.915841) (xy 362.840016 -266.941808) (xy 362.839507 -266.967775)
			(xy 363.119417 -266.967775) (xy 363.119417 -266.915841) (xy 363.127542 -266.864546) (xy 363.14359 -266.815153)
			(xy 363.167168 -266.768879) (xy 363.197694 -266.726863) (xy 363.234417 -266.69014) (xy 363.276433 -266.659614)
			(xy 363.322707 -266.636036) (xy 363.3721 -266.619988) (xy 363.423395 -266.611863) (xy 363.475329 -266.611863)
			(xy 363.526624 -266.619988) (xy 363.576017 -266.636036) (xy 363.622291 -266.659614) (xy 363.664307 -266.69014)
			(xy 363.70103 -266.726863) (xy 363.731556 -266.768879) (xy 363.755134 -266.815153) (xy 363.771182 -266.864546)
			(xy 363.779307 -266.915841) (xy 363.779816 -266.941808) (xy 363.779307 -266.967775) (xy 364.059217 -266.967775)
			(xy 364.059217 -266.915841) (xy 364.067342 -266.864546) (xy 364.08339 -266.815153) (xy 364.106968 -266.768879)
			(xy 364.137494 -266.726863) (xy 364.174217 -266.69014) (xy 364.216233 -266.659614) (xy 364.262507 -266.636036)
			(xy 364.3119 -266.619988) (xy 364.363195 -266.611863) (xy 364.415129 -266.611863) (xy 364.466424 -266.619988)
			(xy 364.515817 -266.636036) (xy 364.562091 -266.659614) (xy 364.604107 -266.69014) (xy 364.64083 -266.726863)
			(xy 364.671356 -266.768879) (xy 364.694934 -266.815153) (xy 364.710982 -266.864546) (xy 364.719107 -266.915841)
			(xy 364.719616 -266.941808) (xy 364.719107 -266.967775) (xy 364.999271 -266.967775) (xy 364.999271 -266.915841)
			(xy 365.007396 -266.864546) (xy 365.023444 -266.815153) (xy 365.047022 -266.768879) (xy 365.077548 -266.726863)
			(xy 365.114271 -266.69014) (xy 365.156287 -266.659614) (xy 365.202561 -266.636036) (xy 365.251954 -266.619988)
			(xy 365.303249 -266.611863) (xy 365.355183 -266.611863) (xy 365.406478 -266.619988) (xy 365.455871 -266.636036)
			(xy 365.502145 -266.659614) (xy 365.544161 -266.69014) (xy 365.580884 -266.726863) (xy 365.61141 -266.768879)
			(xy 365.634988 -266.815153) (xy 365.651036 -266.864546) (xy 365.659161 -266.915841) (xy 365.65967 -266.941808)
			(xy 365.659161 -266.967775) (xy 365.938563 -266.967775) (xy 365.938563 -266.915841) (xy 365.946688 -266.864546)
			(xy 365.962736 -266.815153) (xy 365.986314 -266.768879) (xy 366.01684 -266.726863) (xy 366.053563 -266.69014)
			(xy 366.095579 -266.659614) (xy 366.141853 -266.636036) (xy 366.191246 -266.619988) (xy 366.242541 -266.611863)
			(xy 366.294475 -266.611863) (xy 366.34577 -266.619988) (xy 366.395163 -266.636036) (xy 366.441437 -266.659614)
			(xy 366.483453 -266.69014) (xy 366.520176 -266.726863) (xy 366.550702 -266.768879) (xy 366.57428 -266.815153)
			(xy 366.590328 -266.864546) (xy 366.598453 -266.915841) (xy 366.598962 -266.941808) (xy 366.598453 -266.967775)
			(xy 369.698271 -266.967775) (xy 369.698271 -266.915841) (xy 369.706396 -266.864546) (xy 369.722444 -266.815153)
			(xy 369.746022 -266.768879) (xy 369.776548 -266.726863) (xy 369.813271 -266.69014) (xy 369.855287 -266.659614)
			(xy 369.901561 -266.636036) (xy 369.950954 -266.619988) (xy 370.002249 -266.611863) (xy 370.054183 -266.611863)
			(xy 370.105478 -266.619988) (xy 370.154871 -266.636036) (xy 370.201145 -266.659614) (xy 370.243161 -266.69014)
			(xy 370.279884 -266.726863) (xy 370.31041 -266.768879) (xy 370.333988 -266.815153) (xy 370.350036 -266.864546)
			(xy 370.358161 -266.915841) (xy 370.35867 -266.941808) (xy 370.358161 -266.967775) (xy 370.638071 -266.967775)
			(xy 370.638071 -266.915841) (xy 370.646196 -266.864546) (xy 370.662244 -266.815153) (xy 370.685822 -266.768879)
			(xy 370.716348 -266.726863) (xy 370.753071 -266.69014) (xy 370.795087 -266.659614) (xy 370.841361 -266.636036)
			(xy 370.890754 -266.619988) (xy 370.942049 -266.611863) (xy 370.993983 -266.611863) (xy 371.045278 -266.619988)
			(xy 371.094671 -266.636036) (xy 371.140945 -266.659614) (xy 371.182961 -266.69014) (xy 371.219684 -266.726863)
			(xy 371.25021 -266.768879) (xy 371.273788 -266.815153) (xy 371.289836 -266.864546) (xy 371.297961 -266.915841)
			(xy 371.29847 -266.941808) (xy 371.297961 -266.967775) (xy 371.289836 -267.01907) (xy 371.273788 -267.068463)
			(xy 371.25021 -267.114737) (xy 371.219684 -267.156753) (xy 371.182961 -267.193476) (xy 371.140945 -267.224002)
			(xy 371.094671 -267.24758) (xy 371.045278 -267.263628) (xy 370.993983 -267.271753) (xy 370.942049 -267.271753)
			(xy 370.890754 -267.263628) (xy 370.841361 -267.24758) (xy 370.795087 -267.224002) (xy 370.753071 -267.193476)
			(xy 370.716348 -267.156753) (xy 370.685822 -267.114737) (xy 370.662244 -267.068463) (xy 370.646196 -267.01907)
			(xy 370.638071 -266.967775) (xy 370.358161 -266.967775) (xy 370.350036 -267.01907) (xy 370.333988 -267.068463)
			(xy 370.31041 -267.114737) (xy 370.279884 -267.156753) (xy 370.243161 -267.193476) (xy 370.201145 -267.224002)
			(xy 370.154871 -267.24758) (xy 370.105478 -267.263628) (xy 370.054183 -267.271753) (xy 370.002249 -267.271753)
			(xy 369.950954 -267.263628) (xy 369.901561 -267.24758) (xy 369.855287 -267.224002) (xy 369.813271 -267.193476)
			(xy 369.776548 -267.156753) (xy 369.746022 -267.114737) (xy 369.722444 -267.068463) (xy 369.706396 -267.01907)
			(xy 369.698271 -266.967775) (xy 366.598453 -266.967775) (xy 366.590328 -267.01907) (xy 366.57428 -267.068463)
			(xy 366.550702 -267.114737) (xy 366.520176 -267.156753) (xy 366.483453 -267.193476) (xy 366.441437 -267.224002)
			(xy 366.395163 -267.24758) (xy 366.34577 -267.263628) (xy 366.294475 -267.271753) (xy 366.242541 -267.271753)
			(xy 366.191246 -267.263628) (xy 366.141853 -267.24758) (xy 366.095579 -267.224002) (xy 366.053563 -267.193476)
			(xy 366.01684 -267.156753) (xy 365.986314 -267.114737) (xy 365.962736 -267.068463) (xy 365.946688 -267.01907)
			(xy 365.938563 -266.967775) (xy 365.659161 -266.967775) (xy 365.651036 -267.01907) (xy 365.634988 -267.068463)
			(xy 365.61141 -267.114737) (xy 365.580884 -267.156753) (xy 365.544161 -267.193476) (xy 365.502145 -267.224002)
			(xy 365.455871 -267.24758) (xy 365.406478 -267.263628) (xy 365.355183 -267.271753) (xy 365.303249 -267.271753)
			(xy 365.251954 -267.263628) (xy 365.202561 -267.24758) (xy 365.156287 -267.224002) (xy 365.114271 -267.193476)
			(xy 365.077548 -267.156753) (xy 365.047022 -267.114737) (xy 365.023444 -267.068463) (xy 365.007396 -267.01907)
			(xy 364.999271 -266.967775) (xy 364.719107 -266.967775) (xy 364.710982 -267.01907) (xy 364.694934 -267.068463)
			(xy 364.671356 -267.114737) (xy 364.64083 -267.156753) (xy 364.604107 -267.193476) (xy 364.562091 -267.224002)
			(xy 364.515817 -267.24758) (xy 364.466424 -267.263628) (xy 364.415129 -267.271753) (xy 364.363195 -267.271753)
			(xy 364.3119 -267.263628) (xy 364.262507 -267.24758) (xy 364.216233 -267.224002) (xy 364.174217 -267.193476)
			(xy 364.137494 -267.156753) (xy 364.106968 -267.114737) (xy 364.08339 -267.068463) (xy 364.067342 -267.01907)
			(xy 364.059217 -266.967775) (xy 363.779307 -266.967775) (xy 363.771182 -267.01907) (xy 363.755134 -267.068463)
			(xy 363.731556 -267.114737) (xy 363.70103 -267.156753) (xy 363.664307 -267.193476) (xy 363.622291 -267.224002)
			(xy 363.576017 -267.24758) (xy 363.526624 -267.263628) (xy 363.475329 -267.271753) (xy 363.423395 -267.271753)
			(xy 363.3721 -267.263628) (xy 363.322707 -267.24758) (xy 363.276433 -267.224002) (xy 363.234417 -267.193476)
			(xy 363.197694 -267.156753) (xy 363.167168 -267.114737) (xy 363.14359 -267.068463) (xy 363.127542 -267.01907)
			(xy 363.119417 -266.967775) (xy 362.839507 -266.967775) (xy 362.831382 -267.01907) (xy 362.815334 -267.068463)
			(xy 362.791756 -267.114737) (xy 362.76123 -267.156753) (xy 362.724507 -267.193476) (xy 362.682491 -267.224002)
			(xy 362.636217 -267.24758) (xy 362.586824 -267.263628) (xy 362.535529 -267.271753) (xy 362.483595 -267.271753)
			(xy 362.4323 -267.263628) (xy 362.382907 -267.24758) (xy 362.336633 -267.224002) (xy 362.294617 -267.193476)
			(xy 362.257894 -267.156753) (xy 362.227368 -267.114737) (xy 362.20379 -267.068463) (xy 362.187742 -267.01907)
			(xy 362.179617 -266.967775) (xy 361.899707 -266.967775) (xy 361.891582 -267.01907) (xy 361.875534 -267.068463)
			(xy 361.851956 -267.114737) (xy 361.82143 -267.156753) (xy 361.784707 -267.193476) (xy 361.742691 -267.224002)
			(xy 361.696417 -267.24758) (xy 361.647024 -267.263628) (xy 361.595729 -267.271753) (xy 361.543795 -267.271753)
			(xy 361.4925 -267.263628) (xy 361.443107 -267.24758) (xy 361.396833 -267.224002) (xy 361.354817 -267.193476)
			(xy 361.318094 -267.156753) (xy 361.287568 -267.114737) (xy 361.26399 -267.068463) (xy 361.247942 -267.01907)
			(xy 361.239817 -266.967775) (xy 360.959907 -266.967775) (xy 360.951782 -267.01907) (xy 360.935734 -267.068463)
			(xy 360.912156 -267.114737) (xy 360.88163 -267.156753) (xy 360.844907 -267.193476) (xy 360.802891 -267.224002)
			(xy 360.756617 -267.24758) (xy 360.707224 -267.263628) (xy 360.655929 -267.271753) (xy 360.603995 -267.271753)
			(xy 360.5527 -267.263628) (xy 360.503307 -267.24758) (xy 360.457033 -267.224002) (xy 360.415017 -267.193476)
			(xy 360.378294 -267.156753) (xy 360.347768 -267.114737) (xy 360.32419 -267.068463) (xy 360.308142 -267.01907)
			(xy 360.300017 -266.967775) (xy 360.020107 -266.967775) (xy 360.011982 -267.01907) (xy 359.995934 -267.068463)
			(xy 359.972356 -267.114737) (xy 359.94183 -267.156753) (xy 359.905107 -267.193476) (xy 359.863091 -267.224002)
			(xy 359.816817 -267.24758) (xy 359.767424 -267.263628) (xy 359.716129 -267.271753) (xy 359.664195 -267.271753)
			(xy 359.6129 -267.263628) (xy 359.563507 -267.24758) (xy 359.517233 -267.224002) (xy 359.475217 -267.193476)
			(xy 359.438494 -267.156753) (xy 359.407968 -267.114737) (xy 359.38439 -267.068463) (xy 359.368342 -267.01907)
			(xy 359.360217 -266.967775) (xy 359.080561 -266.967775) (xy 359.072436 -267.01907) (xy 359.056388 -267.068463)
			(xy 359.03281 -267.114737) (xy 359.002284 -267.156753) (xy 358.965561 -267.193476) (xy 358.923545 -267.224002)
			(xy 358.877271 -267.24758) (xy 358.827878 -267.263628) (xy 358.776583 -267.271753) (xy 358.724649 -267.271753)
			(xy 358.673354 -267.263628) (xy 358.623961 -267.24758) (xy 358.577687 -267.224002) (xy 358.535671 -267.193476)
			(xy 358.498948 -267.156753) (xy 358.468422 -267.114737) (xy 358.444844 -267.068463) (xy 358.428796 -267.01907)
			(xy 358.420671 -266.967775) (xy 358.140507 -266.967775) (xy 358.132382 -267.01907) (xy 358.116334 -267.068463)
			(xy 358.092756 -267.114737) (xy 358.06223 -267.156753) (xy 358.025507 -267.193476) (xy 357.983491 -267.224002)
			(xy 357.937217 -267.24758) (xy 357.887824 -267.263628) (xy 357.836529 -267.271753) (xy 357.784595 -267.271753)
			(xy 357.7333 -267.263628) (xy 357.683907 -267.24758) (xy 357.637633 -267.224002) (xy 357.595617 -267.193476)
			(xy 357.558894 -267.156753) (xy 357.528368 -267.114737) (xy 357.50479 -267.068463) (xy 357.488742 -267.01907)
			(xy 357.480617 -266.967775) (xy 357.200961 -266.967775) (xy 357.192836 -267.01907) (xy 357.176788 -267.068463)
			(xy 357.15321 -267.114737) (xy 357.122684 -267.156753) (xy 357.085961 -267.193476) (xy 357.043945 -267.224002)
			(xy 356.997671 -267.24758) (xy 356.948278 -267.263628) (xy 356.896983 -267.271753) (xy 356.845049 -267.271753)
			(xy 356.793754 -267.263628) (xy 356.744361 -267.24758) (xy 356.698087 -267.224002) (xy 356.656071 -267.193476)
			(xy 356.619348 -267.156753) (xy 356.588822 -267.114737) (xy 356.565244 -267.068463) (xy 356.549196 -267.01907)
			(xy 356.541071 -266.967775) (xy 356.261161 -266.967775) (xy 356.253036 -267.01907) (xy 356.236988 -267.068463)
			(xy 356.21341 -267.114737) (xy 356.182884 -267.156753) (xy 356.146161 -267.193476) (xy 356.104145 -267.224002)
			(xy 356.057871 -267.24758) (xy 356.008478 -267.263628) (xy 355.957183 -267.271753) (xy 355.905249 -267.271753)
			(xy 355.853954 -267.263628) (xy 355.804561 -267.24758) (xy 355.758287 -267.224002) (xy 355.716271 -267.193476)
			(xy 355.679548 -267.156753) (xy 355.649022 -267.114737) (xy 355.625444 -267.068463) (xy 355.609396 -267.01907)
			(xy 355.601271 -266.967775) (xy 355.321361 -266.967775) (xy 355.313236 -267.01907) (xy 355.297188 -267.068463)
			(xy 355.27361 -267.114737) (xy 355.243084 -267.156753) (xy 355.206361 -267.193476) (xy 355.164345 -267.224002)
			(xy 355.118071 -267.24758) (xy 355.068678 -267.263628) (xy 355.017383 -267.271753) (xy 354.965449 -267.271753)
			(xy 354.914154 -267.263628) (xy 354.864761 -267.24758) (xy 354.818487 -267.224002) (xy 354.776471 -267.193476)
			(xy 354.739748 -267.156753) (xy 354.709222 -267.114737) (xy 354.685644 -267.068463) (xy 354.669596 -267.01907)
			(xy 354.661471 -266.967775) (xy 354.381561 -266.967775) (xy 354.373436 -267.01907) (xy 354.357388 -267.068463)
			(xy 354.33381 -267.114737) (xy 354.303284 -267.156753) (xy 354.266561 -267.193476) (xy 354.224545 -267.224002)
			(xy 354.178271 -267.24758) (xy 354.128878 -267.263628) (xy 354.077583 -267.271753) (xy 354.025649 -267.271753)
			(xy 353.974354 -267.263628) (xy 353.924961 -267.24758) (xy 353.878687 -267.224002) (xy 353.836671 -267.193476)
			(xy 353.799948 -267.156753) (xy 353.769422 -267.114737) (xy 353.745844 -267.068463) (xy 353.729796 -267.01907)
			(xy 353.721671 -266.967775) (xy 353.441761 -266.967775) (xy 353.433636 -267.01907) (xy 353.417588 -267.068463)
			(xy 353.39401 -267.114737) (xy 353.363484 -267.156753) (xy 353.326761 -267.193476) (xy 353.284745 -267.224002)
			(xy 353.238471 -267.24758) (xy 353.189078 -267.263628) (xy 353.137783 -267.271753) (xy 353.085849 -267.271753)
			(xy 353.034554 -267.263628) (xy 352.985161 -267.24758) (xy 352.938887 -267.224002) (xy 352.896871 -267.193476)
			(xy 352.860148 -267.156753) (xy 352.829622 -267.114737) (xy 352.806044 -267.068463) (xy 352.789996 -267.01907)
			(xy 352.781871 -266.967775) (xy 352.501341 -266.967775) (xy 352.498966 -266.991515) (xy 352.495866 -267.007848)
			(xy 352.490278 -267.034518) (xy 352.980752 -267.524992) (xy 353.344988 -267.524992) (xy 353.363783 -267.506497)
			(xy 353.406155 -267.475117) (xy 353.452969 -267.450859) (xy 353.50304 -267.434337) (xy 353.555099 -267.42597)
			(xy 353.607825 -267.42597) (xy 353.659884 -267.434337) (xy 353.709955 -267.450859) (xy 353.756769 -267.475117)
			(xy 353.799141 -267.506497) (xy 353.817936 -267.524992) (xy 354.284788 -267.524992) (xy 354.303583 -267.506497)
			(xy 354.345955 -267.475117) (xy 354.392769 -267.450859) (xy 354.44284 -267.434337) (xy 354.494899 -267.42597)
			(xy 354.547625 -267.42597) (xy 354.599684 -267.434337) (xy 354.649755 -267.450859) (xy 354.696569 -267.475117)
			(xy 354.738941 -267.506497) (xy 354.757736 -267.524992) (xy 355.224588 -267.524992) (xy 355.243383 -267.506497)
			(xy 355.285755 -267.475117) (xy 355.332569 -267.450859) (xy 355.38264 -267.434337) (xy 355.434699 -267.42597)
			(xy 355.487425 -267.42597) (xy 355.539484 -267.434337) (xy 355.589555 -267.450859) (xy 355.636369 -267.475117)
			(xy 355.678741 -267.506497) (xy 355.697536 -267.524992) (xy 356.164388 -267.524992) (xy 356.183183 -267.506497)
			(xy 356.225555 -267.475117) (xy 356.272369 -267.450859) (xy 356.32244 -267.434337) (xy 356.374499 -267.42597)
			(xy 356.427225 -267.42597) (xy 356.479284 -267.434337) (xy 356.529355 -267.450859) (xy 356.576169 -267.475117)
			(xy 356.618541 -267.506497) (xy 356.637336 -267.524992) (xy 357.104188 -267.524992) (xy 357.122983 -267.506497)
			(xy 357.165355 -267.475117) (xy 357.212169 -267.450859) (xy 357.26224 -267.434337) (xy 357.314299 -267.42597)
			(xy 357.367025 -267.42597) (xy 357.419084 -267.434337) (xy 357.469155 -267.450859) (xy 357.515969 -267.475117)
			(xy 357.558341 -267.506497) (xy 357.577136 -267.524992) (xy 358.043988 -267.524992) (xy 358.062784 -267.506498)
			(xy 358.105157 -267.475115) (xy 358.151971 -267.45085) (xy 358.20204 -267.434317) (xy 358.254098 -267.425933)
			(xy 358.280462 -267.425424) (xy 358.306434 -267.425904) (xy 358.357739 -267.434024) (xy 358.407142 -267.45007)
			(xy 358.453426 -267.473648) (xy 358.495453 -267.504175) (xy 358.532186 -267.540902) (xy 358.562721 -267.582922)
			(xy 358.586307 -267.629203) (xy 358.602362 -267.678603) (xy 358.610491 -267.729906) (xy 358.610916 -267.755878)
			(xy 358.610462 -267.780821) (xy 358.610306 -267.781845) (xy 358.890571 -267.781845) (xy 358.890571 -267.729911)
			(xy 358.898696 -267.678616) (xy 358.914744 -267.629223) (xy 358.938322 -267.582949) (xy 358.968848 -267.540933)
			(xy 359.005571 -267.50421) (xy 359.047587 -267.473684) (xy 359.093861 -267.450106) (xy 359.143254 -267.434058)
			(xy 359.194549 -267.425933) (xy 359.246483 -267.425933) (xy 359.297778 -267.434058) (xy 359.347171 -267.450106)
			(xy 359.393445 -267.473684) (xy 359.435461 -267.50421) (xy 359.472184 -267.540933) (xy 359.50271 -267.582949)
			(xy 359.526288 -267.629223) (xy 359.542336 -267.678616) (xy 359.550461 -267.729911) (xy 359.55097 -267.755878)
			(xy 359.550461 -267.781845) (xy 359.830371 -267.781845) (xy 359.830371 -267.729911) (xy 359.838496 -267.678616)
			(xy 359.854544 -267.629223) (xy 359.878122 -267.582949) (xy 359.908648 -267.540933) (xy 359.945371 -267.50421)
			(xy 359.987387 -267.473684) (xy 360.033661 -267.450106) (xy 360.083054 -267.434058) (xy 360.134349 -267.425933)
			(xy 360.186283 -267.425933) (xy 360.237578 -267.434058) (xy 360.286971 -267.450106) (xy 360.333245 -267.473684)
			(xy 360.375261 -267.50421) (xy 360.411984 -267.540933) (xy 360.44251 -267.582949) (xy 360.466088 -267.629223)
			(xy 360.482136 -267.678616) (xy 360.490261 -267.729911) (xy 360.49077 -267.755878) (xy 360.490261 -267.781845)
			(xy 360.769917 -267.781845) (xy 360.769917 -267.729911) (xy 360.778042 -267.678616) (xy 360.79409 -267.629223)
			(xy 360.817668 -267.582949) (xy 360.848194 -267.540933) (xy 360.884917 -267.50421) (xy 360.926933 -267.473684)
			(xy 360.973207 -267.450106) (xy 361.0226 -267.434058) (xy 361.073895 -267.425933) (xy 361.125829 -267.425933)
			(xy 361.177124 -267.434058) (xy 361.226517 -267.450106) (xy 361.272791 -267.473684) (xy 361.314807 -267.50421)
			(xy 361.35153 -267.540933) (xy 361.382056 -267.582949) (xy 361.405634 -267.629223) (xy 361.421682 -267.678616)
			(xy 361.429807 -267.729911) (xy 361.430316 -267.755878) (xy 361.429807 -267.781845) (xy 361.709717 -267.781845)
			(xy 361.709717 -267.729911) (xy 361.717842 -267.678616) (xy 361.73389 -267.629223) (xy 361.757468 -267.582949)
			(xy 361.787994 -267.540933) (xy 361.824717 -267.50421) (xy 361.866733 -267.473684) (xy 361.913007 -267.450106)
			(xy 361.9624 -267.434058) (xy 362.013695 -267.425933) (xy 362.065629 -267.425933) (xy 362.116924 -267.434058)
			(xy 362.166317 -267.450106) (xy 362.212591 -267.473684) (xy 362.254607 -267.50421) (xy 362.29133 -267.540933)
			(xy 362.321856 -267.582949) (xy 362.345434 -267.629223) (xy 362.361482 -267.678616) (xy 362.369607 -267.729911)
			(xy 362.370116 -267.755878) (xy 362.369607 -267.781845) (xy 362.649517 -267.781845) (xy 362.649517 -267.729911)
			(xy 362.657642 -267.678616) (xy 362.67369 -267.629223) (xy 362.697268 -267.582949) (xy 362.727794 -267.540933)
			(xy 362.764517 -267.50421) (xy 362.806533 -267.473684) (xy 362.852807 -267.450106) (xy 362.9022 -267.434058)
			(xy 362.953495 -267.425933) (xy 363.005429 -267.425933) (xy 363.056724 -267.434058) (xy 363.106117 -267.450106)
			(xy 363.152391 -267.473684) (xy 363.194407 -267.50421) (xy 363.23113 -267.540933) (xy 363.261656 -267.582949)
			(xy 363.285234 -267.629223) (xy 363.301282 -267.678616) (xy 363.309407 -267.729911) (xy 363.309916 -267.755878)
			(xy 363.309407 -267.781845) (xy 363.589317 -267.781845) (xy 363.589317 -267.729911) (xy 363.597442 -267.678616)
			(xy 363.61349 -267.629223) (xy 363.637068 -267.582949) (xy 363.667594 -267.540933) (xy 363.704317 -267.50421)
			(xy 363.746333 -267.473684) (xy 363.792607 -267.450106) (xy 363.842 -267.434058) (xy 363.893295 -267.425933)
			(xy 363.945229 -267.425933) (xy 363.996524 -267.434058) (xy 364.045917 -267.450106) (xy 364.092191 -267.473684)
			(xy 364.134207 -267.50421) (xy 364.17093 -267.540933) (xy 364.201456 -267.582949) (xy 364.225034 -267.629223)
			(xy 364.241082 -267.678616) (xy 364.249207 -267.729911) (xy 364.249716 -267.755878) (xy 364.249207 -267.781845)
			(xy 364.529371 -267.781845) (xy 364.529371 -267.729911) (xy 364.537496 -267.678616) (xy 364.553544 -267.629223)
			(xy 364.577122 -267.582949) (xy 364.607648 -267.540933) (xy 364.644371 -267.50421) (xy 364.686387 -267.473684)
			(xy 364.732661 -267.450106) (xy 364.782054 -267.434058) (xy 364.833349 -267.425933) (xy 364.885283 -267.425933)
			(xy 364.936578 -267.434058) (xy 364.985971 -267.450106) (xy 365.032245 -267.473684) (xy 365.074261 -267.50421)
			(xy 365.110984 -267.540933) (xy 365.14151 -267.582949) (xy 365.165088 -267.629223) (xy 365.181136 -267.678616)
			(xy 365.189261 -267.729911) (xy 365.18977 -267.755878) (xy 365.189261 -267.781845) (xy 365.468917 -267.781845)
			(xy 365.468917 -267.729911) (xy 365.477042 -267.678616) (xy 365.49309 -267.629223) (xy 365.516668 -267.582949)
			(xy 365.547194 -267.540933) (xy 365.583917 -267.50421) (xy 365.625933 -267.473684) (xy 365.672207 -267.450106)
			(xy 365.7216 -267.434058) (xy 365.772895 -267.425933) (xy 365.824829 -267.425933) (xy 365.876124 -267.434058)
			(xy 365.925517 -267.450106) (xy 365.971791 -267.473684) (xy 366.013807 -267.50421) (xy 366.05053 -267.540933)
			(xy 366.081056 -267.582949) (xy 366.104634 -267.629223) (xy 366.120682 -267.678616) (xy 366.128807 -267.729911)
			(xy 366.129316 -267.755878) (xy 366.128807 -267.781845) (xy 367.348517 -267.781845) (xy 367.348517 -267.729911)
			(xy 367.356642 -267.678616) (xy 367.37269 -267.629223) (xy 367.396268 -267.582949) (xy 367.426794 -267.540933)
			(xy 367.463517 -267.50421) (xy 367.505533 -267.473684) (xy 367.551807 -267.450106) (xy 367.6012 -267.434058)
			(xy 367.652495 -267.425933) (xy 367.704429 -267.425933) (xy 367.755724 -267.434058) (xy 367.805117 -267.450106)
			(xy 367.851391 -267.473684) (xy 367.893407 -267.50421) (xy 367.93013 -267.540933) (xy 367.960656 -267.582949)
			(xy 367.984234 -267.629223) (xy 368.000282 -267.678616) (xy 368.008407 -267.729911) (xy 368.008916 -267.755878)
			(xy 368.008407 -267.781845) (xy 368.000282 -267.83314) (xy 367.984234 -267.882533) (xy 367.960656 -267.928807)
			(xy 367.93013 -267.970823) (xy 367.893407 -268.007546) (xy 367.851391 -268.038072) (xy 367.805117 -268.06165)
			(xy 367.755724 -268.077698) (xy 367.704429 -268.085823) (xy 367.652495 -268.085823) (xy 367.6012 -268.077698)
			(xy 367.551807 -268.06165) (xy 367.505533 -268.038072) (xy 367.463517 -268.007546) (xy 367.426794 -267.970823)
			(xy 367.396268 -267.928807) (xy 367.37269 -267.882533) (xy 367.356642 -267.83314) (xy 367.348517 -267.781845)
			(xy 366.128807 -267.781845) (xy 366.120682 -267.83314) (xy 366.104634 -267.882533) (xy 366.081056 -267.928807)
			(xy 366.05053 -267.970823) (xy 366.013807 -268.007546) (xy 365.971791 -268.038072) (xy 365.925517 -268.06165)
			(xy 365.876124 -268.077698) (xy 365.824829 -268.085823) (xy 365.772895 -268.085823) (xy 365.7216 -268.077698)
			(xy 365.672207 -268.06165) (xy 365.625933 -268.038072) (xy 365.583917 -268.007546) (xy 365.547194 -267.970823)
			(xy 365.516668 -267.928807) (xy 365.49309 -267.882533) (xy 365.477042 -267.83314) (xy 365.468917 -267.781845)
			(xy 365.189261 -267.781845) (xy 365.181136 -267.83314) (xy 365.165088 -267.882533) (xy 365.14151 -267.928807)
			(xy 365.110984 -267.970823) (xy 365.074261 -268.007546) (xy 365.032245 -268.038072) (xy 364.985971 -268.06165)
			(xy 364.936578 -268.077698) (xy 364.885283 -268.085823) (xy 364.833349 -268.085823) (xy 364.782054 -268.077698)
			(xy 364.732661 -268.06165) (xy 364.686387 -268.038072) (xy 364.644371 -268.007546) (xy 364.607648 -267.970823)
			(xy 364.577122 -267.928807) (xy 364.553544 -267.882533) (xy 364.537496 -267.83314) (xy 364.529371 -267.781845)
			(xy 364.249207 -267.781845) (xy 364.241082 -267.83314) (xy 364.225034 -267.882533) (xy 364.201456 -267.928807)
			(xy 364.17093 -267.970823) (xy 364.134207 -268.007546) (xy 364.092191 -268.038072) (xy 364.045917 -268.06165)
			(xy 363.996524 -268.077698) (xy 363.945229 -268.085823) (xy 363.893295 -268.085823) (xy 363.842 -268.077698)
			(xy 363.792607 -268.06165) (xy 363.746333 -268.038072) (xy 363.704317 -268.007546) (xy 363.667594 -267.970823)
			(xy 363.637068 -267.928807) (xy 363.61349 -267.882533) (xy 363.597442 -267.83314) (xy 363.589317 -267.781845)
			(xy 363.309407 -267.781845) (xy 363.301282 -267.83314) (xy 363.285234 -267.882533) (xy 363.261656 -267.928807)
			(xy 363.23113 -267.970823) (xy 363.194407 -268.007546) (xy 363.152391 -268.038072) (xy 363.106117 -268.06165)
			(xy 363.056724 -268.077698) (xy 363.005429 -268.085823) (xy 362.953495 -268.085823) (xy 362.9022 -268.077698)
			(xy 362.852807 -268.06165) (xy 362.806533 -268.038072) (xy 362.764517 -268.007546) (xy 362.727794 -267.970823)
			(xy 362.697268 -267.928807) (xy 362.67369 -267.882533) (xy 362.657642 -267.83314) (xy 362.649517 -267.781845)
			(xy 362.369607 -267.781845) (xy 362.361482 -267.83314) (xy 362.345434 -267.882533) (xy 362.321856 -267.928807)
			(xy 362.29133 -267.970823) (xy 362.254607 -268.007546) (xy 362.212591 -268.038072) (xy 362.166317 -268.06165)
			(xy 362.116924 -268.077698) (xy 362.065629 -268.085823) (xy 362.013695 -268.085823) (xy 361.9624 -268.077698)
			(xy 361.913007 -268.06165) (xy 361.866733 -268.038072) (xy 361.824717 -268.007546) (xy 361.787994 -267.970823)
			(xy 361.757468 -267.928807) (xy 361.73389 -267.882533) (xy 361.717842 -267.83314) (xy 361.709717 -267.781845)
			(xy 361.429807 -267.781845) (xy 361.421682 -267.83314) (xy 361.405634 -267.882533) (xy 361.382056 -267.928807)
			(xy 361.35153 -267.970823) (xy 361.314807 -268.007546) (xy 361.272791 -268.038072) (xy 361.226517 -268.06165)
			(xy 361.177124 -268.077698) (xy 361.125829 -268.085823) (xy 361.073895 -268.085823) (xy 361.0226 -268.077698)
			(xy 360.973207 -268.06165) (xy 360.926933 -268.038072) (xy 360.884917 -268.007546) (xy 360.848194 -267.970823)
			(xy 360.817668 -267.928807) (xy 360.79409 -267.882533) (xy 360.778042 -267.83314) (xy 360.769917 -267.781845)
			(xy 360.490261 -267.781845) (xy 360.482136 -267.83314) (xy 360.466088 -267.882533) (xy 360.44251 -267.928807)
			(xy 360.411984 -267.970823) (xy 360.375261 -268.007546) (xy 360.333245 -268.038072) (xy 360.286971 -268.06165)
			(xy 360.237578 -268.077698) (xy 360.186283 -268.085823) (xy 360.134349 -268.085823) (xy 360.083054 -268.077698)
			(xy 360.033661 -268.06165) (xy 359.987387 -268.038072) (xy 359.945371 -268.007546) (xy 359.908648 -267.970823)
			(xy 359.878122 -267.928807) (xy 359.854544 -267.882533) (xy 359.838496 -267.83314) (xy 359.830371 -267.781845)
			(xy 359.550461 -267.781845) (xy 359.542336 -267.83314) (xy 359.526288 -267.882533) (xy 359.50271 -267.928807)
			(xy 359.472184 -267.970823) (xy 359.435461 -268.007546) (xy 359.393445 -268.038072) (xy 359.347171 -268.06165)
			(xy 359.297778 -268.077698) (xy 359.246483 -268.085823) (xy 359.194549 -268.085823) (xy 359.143254 -268.077698)
			(xy 359.093861 -268.06165) (xy 359.047587 -268.038072) (xy 359.005571 -268.007546) (xy 358.968848 -267.970823)
			(xy 358.938322 -267.928807) (xy 358.914744 -267.882533) (xy 358.898696 -267.83314) (xy 358.890571 -267.781845)
			(xy 358.610306 -267.781845) (xy 358.602966 -267.830141) (xy 358.588141 -267.877774) (xy 358.566324 -267.922636)
			(xy 358.53801 -267.963709) (xy 358.521254 -267.982192) (xy 358.487472 -268.01826) (xy 358.71023 -268.241018)
			(xy 358.732836 -268.239748) (xy 358.750616 -268.23924) (xy 358.776583 -268.23975) (xy 358.827876 -268.247877)
			(xy 358.877267 -268.263927) (xy 358.923539 -268.287505) (xy 358.965553 -268.318032) (xy 359.002275 -268.354755)
			(xy 359.0328 -268.39677) (xy 359.056377 -268.443042) (xy 359.072426 -268.492434) (xy 359.08055 -268.543727)
			(xy 359.08107 -268.569694) (xy 359.080562 -268.587474) (xy 359.080102 -268.595661) (xy 359.360217 -268.595661)
			(xy 359.360217 -268.543727) (xy 359.368342 -268.492432) (xy 359.38439 -268.443039) (xy 359.407968 -268.396765)
			(xy 359.438494 -268.354749) (xy 359.475217 -268.318026) (xy 359.517233 -268.2875) (xy 359.563507 -268.263922)
			(xy 359.6129 -268.247874) (xy 359.664195 -268.239749) (xy 359.716129 -268.239749) (xy 359.767424 -268.247874)
			(xy 359.816817 -268.263922) (xy 359.863091 -268.2875) (xy 359.905107 -268.318026) (xy 359.94183 -268.354749)
			(xy 359.972356 -268.396765) (xy 359.995934 -268.443039) (xy 360.011982 -268.492432) (xy 360.020107 -268.543727)
			(xy 360.020616 -268.569694) (xy 360.020107 -268.595661) (xy 360.300017 -268.595661) (xy 360.300017 -268.543727)
			(xy 360.308142 -268.492432) (xy 360.32419 -268.443039) (xy 360.347768 -268.396765) (xy 360.378294 -268.354749)
			(xy 360.415017 -268.318026) (xy 360.457033 -268.2875) (xy 360.503307 -268.263922) (xy 360.5527 -268.247874)
			(xy 360.603995 -268.239749) (xy 360.655929 -268.239749) (xy 360.707224 -268.247874) (xy 360.756617 -268.263922)
			(xy 360.802891 -268.2875) (xy 360.844907 -268.318026) (xy 360.88163 -268.354749) (xy 360.912156 -268.396765)
			(xy 360.935734 -268.443039) (xy 360.951782 -268.492432) (xy 360.959907 -268.543727) (xy 360.960416 -268.569694)
			(xy 360.959907 -268.595661) (xy 361.239817 -268.595661) (xy 361.239817 -268.543727) (xy 361.247942 -268.492432)
			(xy 361.26399 -268.443039) (xy 361.287568 -268.396765) (xy 361.318094 -268.354749) (xy 361.354817 -268.318026)
			(xy 361.396833 -268.2875) (xy 361.443107 -268.263922) (xy 361.4925 -268.247874) (xy 361.543795 -268.239749)
			(xy 361.595729 -268.239749) (xy 361.647024 -268.247874) (xy 361.696417 -268.263922) (xy 361.742691 -268.2875)
			(xy 361.784707 -268.318026) (xy 361.82143 -268.354749) (xy 361.851956 -268.396765) (xy 361.875534 -268.443039)
			(xy 361.891582 -268.492432) (xy 361.899707 -268.543727) (xy 361.900216 -268.569694) (xy 361.899707 -268.595661)
			(xy 362.179871 -268.595661) (xy 362.179871 -268.543727) (xy 362.187996 -268.492432) (xy 362.204044 -268.443039)
			(xy 362.227622 -268.396765) (xy 362.258148 -268.354749) (xy 362.294871 -268.318026) (xy 362.336887 -268.2875)
			(xy 362.383161 -268.263922) (xy 362.432554 -268.247874) (xy 362.483849 -268.239749) (xy 362.535783 -268.239749)
			(xy 362.587078 -268.247874) (xy 362.636471 -268.263922) (xy 362.682745 -268.2875) (xy 362.724761 -268.318026)
			(xy 362.761484 -268.354749) (xy 362.79201 -268.396765) (xy 362.815588 -268.443039) (xy 362.831636 -268.492432)
			(xy 362.839761 -268.543727) (xy 362.84027 -268.569694) (xy 362.839761 -268.595661) (xy 363.119671 -268.595661)
			(xy 363.119671 -268.543727) (xy 363.127796 -268.492432) (xy 363.143844 -268.443039) (xy 363.167422 -268.396765)
			(xy 363.197948 -268.354749) (xy 363.234671 -268.318026) (xy 363.276687 -268.2875) (xy 363.322961 -268.263922)
			(xy 363.372354 -268.247874) (xy 363.423649 -268.239749) (xy 363.475583 -268.239749) (xy 363.526878 -268.247874)
			(xy 363.576271 -268.263922) (xy 363.622545 -268.2875) (xy 363.664561 -268.318026) (xy 363.701284 -268.354749)
			(xy 363.73181 -268.396765) (xy 363.755388 -268.443039) (xy 363.771436 -268.492432) (xy 363.779561 -268.543727)
			(xy 363.78007 -268.569694) (xy 363.779561 -268.595661) (xy 364.059471 -268.595661) (xy 364.059471 -268.543727)
			(xy 364.067596 -268.492432) (xy 364.083644 -268.443039) (xy 364.107222 -268.396765) (xy 364.137748 -268.354749)
			(xy 364.174471 -268.318026) (xy 364.216487 -268.2875) (xy 364.262761 -268.263922) (xy 364.312154 -268.247874)
			(xy 364.363449 -268.239749) (xy 364.415383 -268.239749) (xy 364.466678 -268.247874) (xy 364.516071 -268.263922)
			(xy 364.562345 -268.2875) (xy 364.604361 -268.318026) (xy 364.641084 -268.354749) (xy 364.67161 -268.396765)
			(xy 364.695188 -268.443039) (xy 364.711236 -268.492432) (xy 364.719361 -268.543727) (xy 364.71987 -268.569694)
			(xy 364.719361 -268.595661) (xy 364.999017 -268.595661) (xy 364.999017 -268.543727) (xy 365.007142 -268.492432)
			(xy 365.02319 -268.443039) (xy 365.046768 -268.396765) (xy 365.077294 -268.354749) (xy 365.114017 -268.318026)
			(xy 365.156033 -268.2875) (xy 365.202307 -268.263922) (xy 365.2517 -268.247874) (xy 365.302995 -268.239749)
			(xy 365.354929 -268.239749) (xy 365.406224 -268.247874) (xy 365.455617 -268.263922) (xy 365.501891 -268.2875)
			(xy 365.543907 -268.318026) (xy 365.58063 -268.354749) (xy 365.611156 -268.396765) (xy 365.634734 -268.443039)
			(xy 365.650782 -268.492432) (xy 365.658907 -268.543727) (xy 365.659416 -268.569694) (xy 365.658907 -268.595661)
			(xy 365.939071 -268.595661) (xy 365.939071 -268.543727) (xy 365.947196 -268.492432) (xy 365.963244 -268.443039)
			(xy 365.986822 -268.396765) (xy 366.017348 -268.354749) (xy 366.054071 -268.318026) (xy 366.096087 -268.2875)
			(xy 366.142361 -268.263922) (xy 366.191754 -268.247874) (xy 366.243049 -268.239749) (xy 366.294983 -268.239749)
			(xy 366.346278 -268.247874) (xy 366.395671 -268.263922) (xy 366.441945 -268.2875) (xy 366.483961 -268.318026)
			(xy 366.520684 -268.354749) (xy 366.55121 -268.396765) (xy 366.574788 -268.443039) (xy 366.590836 -268.492432)
			(xy 366.598961 -268.543727) (xy 366.59947 -268.569694) (xy 366.598961 -268.595661) (xy 370.637817 -268.595661)
			(xy 370.637817 -268.543727) (xy 370.645942 -268.492432) (xy 370.66199 -268.443039) (xy 370.685568 -268.396765)
			(xy 370.716094 -268.354749) (xy 370.752817 -268.318026) (xy 370.794833 -268.2875) (xy 370.841107 -268.263922)
			(xy 370.8905 -268.247874) (xy 370.941795 -268.239749) (xy 370.993729 -268.239749) (xy 371.045024 -268.247874)
			(xy 371.094417 -268.263922) (xy 371.140691 -268.2875) (xy 371.182707 -268.318026) (xy 371.21943 -268.354749)
			(xy 371.249956 -268.396765) (xy 371.273534 -268.443039) (xy 371.289582 -268.492432) (xy 371.297707 -268.543727)
			(xy 371.298216 -268.569694) (xy 371.297707 -268.595661) (xy 371.289582 -268.646956) (xy 371.273534 -268.696349)
			(xy 371.249956 -268.742623) (xy 371.21943 -268.784639) (xy 371.182707 -268.821362) (xy 371.140691 -268.851888)
			(xy 371.094417 -268.875466) (xy 371.045024 -268.891514) (xy 370.993729 -268.899639) (xy 370.941795 -268.899639)
			(xy 370.8905 -268.891514) (xy 370.841107 -268.875466) (xy 370.794833 -268.851888) (xy 370.752817 -268.821362)
			(xy 370.716094 -268.784639) (xy 370.685568 -268.742623) (xy 370.66199 -268.696349) (xy 370.645942 -268.646956)
			(xy 370.637817 -268.595661) (xy 366.598961 -268.595661) (xy 366.590836 -268.646956) (xy 366.574788 -268.696349)
			(xy 366.55121 -268.742623) (xy 366.520684 -268.784639) (xy 366.483961 -268.821362) (xy 366.441945 -268.851888)
			(xy 366.395671 -268.875466) (xy 366.346278 -268.891514) (xy 366.294983 -268.899639) (xy 366.243049 -268.899639)
			(xy 366.191754 -268.891514) (xy 366.142361 -268.875466) (xy 366.096087 -268.851888) (xy 366.054071 -268.821362)
			(xy 366.017348 -268.784639) (xy 365.986822 -268.742623) (xy 365.963244 -268.696349) (xy 365.947196 -268.646956)
			(xy 365.939071 -268.595661) (xy 365.658907 -268.595661) (xy 365.650782 -268.646956) (xy 365.634734 -268.696349)
			(xy 365.611156 -268.742623) (xy 365.58063 -268.784639) (xy 365.543907 -268.821362) (xy 365.501891 -268.851888)
			(xy 365.455617 -268.875466) (xy 365.406224 -268.891514) (xy 365.354929 -268.899639) (xy 365.302995 -268.899639)
			(xy 365.2517 -268.891514) (xy 365.202307 -268.875466) (xy 365.156033 -268.851888) (xy 365.114017 -268.821362)
			(xy 365.077294 -268.784639) (xy 365.046768 -268.742623) (xy 365.02319 -268.696349) (xy 365.007142 -268.646956)
			(xy 364.999017 -268.595661) (xy 364.719361 -268.595661) (xy 364.711236 -268.646956) (xy 364.695188 -268.696349)
			(xy 364.67161 -268.742623) (xy 364.641084 -268.784639) (xy 364.604361 -268.821362) (xy 364.562345 -268.851888)
			(xy 364.516071 -268.875466) (xy 364.466678 -268.891514) (xy 364.415383 -268.899639) (xy 364.363449 -268.899639)
			(xy 364.312154 -268.891514) (xy 364.262761 -268.875466) (xy 364.216487 -268.851888) (xy 364.174471 -268.821362)
			(xy 364.137748 -268.784639) (xy 364.107222 -268.742623) (xy 364.083644 -268.696349) (xy 364.067596 -268.646956)
			(xy 364.059471 -268.595661) (xy 363.779561 -268.595661) (xy 363.771436 -268.646956) (xy 363.755388 -268.696349)
			(xy 363.73181 -268.742623) (xy 363.701284 -268.784639) (xy 363.664561 -268.821362) (xy 363.622545 -268.851888)
			(xy 363.576271 -268.875466) (xy 363.526878 -268.891514) (xy 363.475583 -268.899639) (xy 363.423649 -268.899639)
			(xy 363.372354 -268.891514) (xy 363.322961 -268.875466) (xy 363.276687 -268.851888) (xy 363.234671 -268.821362)
			(xy 363.197948 -268.784639) (xy 363.167422 -268.742623) (xy 363.143844 -268.696349) (xy 363.127796 -268.646956)
			(xy 363.119671 -268.595661) (xy 362.839761 -268.595661) (xy 362.831636 -268.646956) (xy 362.815588 -268.696349)
			(xy 362.79201 -268.742623) (xy 362.761484 -268.784639) (xy 362.724761 -268.821362) (xy 362.682745 -268.851888)
			(xy 362.636471 -268.875466) (xy 362.587078 -268.891514) (xy 362.535783 -268.899639) (xy 362.483849 -268.899639)
			(xy 362.432554 -268.891514) (xy 362.383161 -268.875466) (xy 362.336887 -268.851888) (xy 362.294871 -268.821362)
			(xy 362.258148 -268.784639) (xy 362.227622 -268.742623) (xy 362.204044 -268.696349) (xy 362.187996 -268.646956)
			(xy 362.179871 -268.595661) (xy 361.899707 -268.595661) (xy 361.891582 -268.646956) (xy 361.875534 -268.696349)
			(xy 361.851956 -268.742623) (xy 361.82143 -268.784639) (xy 361.784707 -268.821362) (xy 361.742691 -268.851888)
			(xy 361.696417 -268.875466) (xy 361.647024 -268.891514) (xy 361.595729 -268.899639) (xy 361.543795 -268.899639)
			(xy 361.4925 -268.891514) (xy 361.443107 -268.875466) (xy 361.396833 -268.851888) (xy 361.354817 -268.821362)
			(xy 361.318094 -268.784639) (xy 361.287568 -268.742623) (xy 361.26399 -268.696349) (xy 361.247942 -268.646956)
			(xy 361.239817 -268.595661) (xy 360.959907 -268.595661) (xy 360.951782 -268.646956) (xy 360.935734 -268.696349)
			(xy 360.912156 -268.742623) (xy 360.88163 -268.784639) (xy 360.844907 -268.821362) (xy 360.802891 -268.851888)
			(xy 360.756617 -268.875466) (xy 360.707224 -268.891514) (xy 360.655929 -268.899639) (xy 360.603995 -268.899639)
			(xy 360.5527 -268.891514) (xy 360.503307 -268.875466) (xy 360.457033 -268.851888) (xy 360.415017 -268.821362)
			(xy 360.378294 -268.784639) (xy 360.347768 -268.742623) (xy 360.32419 -268.696349) (xy 360.308142 -268.646956)
			(xy 360.300017 -268.595661) (xy 360.020107 -268.595661) (xy 360.011982 -268.646956) (xy 359.995934 -268.696349)
			(xy 359.972356 -268.742623) (xy 359.94183 -268.784639) (xy 359.905107 -268.821362) (xy 359.863091 -268.851888)
			(xy 359.816817 -268.875466) (xy 359.767424 -268.891514) (xy 359.716129 -268.899639) (xy 359.664195 -268.899639)
			(xy 359.6129 -268.891514) (xy 359.563507 -268.875466) (xy 359.517233 -268.851888) (xy 359.475217 -268.821362)
			(xy 359.438494 -268.784639) (xy 359.407968 -268.742623) (xy 359.38439 -268.696349) (xy 359.368342 -268.646956)
			(xy 359.360217 -268.595661) (xy 359.080102 -268.595661) (xy 359.079292 -268.61008) (xy 359.71226 -269.243048)
			(xy 359.722009 -269.252236) (xy 359.745214 -269.265607) (xy 359.771099 -269.272478) (xy 359.79788 -269.272375)
			(xy 359.823711 -269.265305) (xy 359.846812 -269.251756) (xy 359.865591 -269.232661) (xy 359.872534 -269.221204)
			(xy 359.8852 -269.199686) (xy 359.915997 -269.160385) (xy 359.952353 -269.126161) (xy 359.993442 -269.097793)
			(xy 360.038328 -269.075925) (xy 360.085993 -269.061055) (xy 360.135351 -269.05352) (xy 360.160316 -269.053056)
			(xy 360.186282 -269.053566) (xy 360.237575 -269.061693) (xy 360.286964 -269.077743) (xy 360.333235 -269.101322)
			(xy 360.375248 -269.131848) (xy 360.411968 -269.168572) (xy 360.442492 -269.210587) (xy 360.466067 -269.25686)
			(xy 360.482113 -269.306251) (xy 360.490236 -269.357544) (xy 360.49077 -269.38351) (xy 360.490319 -269.40848)
			(xy 360.490167 -269.409477) (xy 360.769917 -269.409477) (xy 360.769917 -269.357543) (xy 360.778042 -269.306248)
			(xy 360.79409 -269.256855) (xy 360.817668 -269.210581) (xy 360.848194 -269.168565) (xy 360.884917 -269.131842)
			(xy 360.926933 -269.101316) (xy 360.973207 -269.077738) (xy 361.0226 -269.06169) (xy 361.073895 -269.053565)
			(xy 361.125829 -269.053565) (xy 361.177124 -269.06169) (xy 361.226517 -269.077738) (xy 361.272791 -269.101316)
			(xy 361.314807 -269.131842) (xy 361.35153 -269.168565) (xy 361.382056 -269.210581) (xy 361.405634 -269.256855)
			(xy 361.421682 -269.306248) (xy 361.429807 -269.357543) (xy 361.430316 -269.38351) (xy 361.429807 -269.409477)
			(xy 361.710225 -269.409477) (xy 361.710225 -269.357543) (xy 361.71835 -269.306248) (xy 361.734398 -269.256855)
			(xy 361.757976 -269.210581) (xy 361.788502 -269.168565) (xy 361.825225 -269.131842) (xy 361.867241 -269.101316)
			(xy 361.913515 -269.077738) (xy 361.962908 -269.06169) (xy 362.014203 -269.053565) (xy 362.066137 -269.053565)
			(xy 362.117432 -269.06169) (xy 362.166825 -269.077738) (xy 362.213099 -269.101316) (xy 362.255115 -269.131842)
			(xy 362.291838 -269.168565) (xy 362.322364 -269.210581) (xy 362.345942 -269.256855) (xy 362.36199 -269.306248)
			(xy 362.370115 -269.357543) (xy 362.370624 -269.38351) (xy 362.370115 -269.409477) (xy 362.649517 -269.409477)
			(xy 362.649517 -269.357543) (xy 362.657642 -269.306248) (xy 362.67369 -269.256855) (xy 362.697268 -269.210581)
			(xy 362.727794 -269.168565) (xy 362.764517 -269.131842) (xy 362.806533 -269.101316) (xy 362.852807 -269.077738)
			(xy 362.9022 -269.06169) (xy 362.953495 -269.053565) (xy 363.005429 -269.053565) (xy 363.056724 -269.06169)
			(xy 363.106117 -269.077738) (xy 363.152391 -269.101316) (xy 363.194407 -269.131842) (xy 363.23113 -269.168565)
			(xy 363.261656 -269.210581) (xy 363.285234 -269.256855) (xy 363.301282 -269.306248) (xy 363.309407 -269.357543)
			(xy 363.309916 -269.38351) (xy 363.309407 -269.409477) (xy 363.589317 -269.409477) (xy 363.589317 -269.357543)
			(xy 363.597442 -269.306248) (xy 363.61349 -269.256855) (xy 363.637068 -269.210581) (xy 363.667594 -269.168565)
			(xy 363.704317 -269.131842) (xy 363.746333 -269.101316) (xy 363.792607 -269.077738) (xy 363.842 -269.06169)
			(xy 363.893295 -269.053565) (xy 363.945229 -269.053565) (xy 363.996524 -269.06169) (xy 364.045917 -269.077738)
			(xy 364.092191 -269.101316) (xy 364.134207 -269.131842) (xy 364.17093 -269.168565) (xy 364.201456 -269.210581)
			(xy 364.225034 -269.256855) (xy 364.241082 -269.306248) (xy 364.249207 -269.357543) (xy 364.249716 -269.38351)
			(xy 364.249207 -269.409477) (xy 364.529117 -269.409477) (xy 364.529117 -269.357543) (xy 364.537242 -269.306248)
			(xy 364.55329 -269.256855) (xy 364.576868 -269.210581) (xy 364.607394 -269.168565) (xy 364.644117 -269.131842)
			(xy 364.686133 -269.101316) (xy 364.732407 -269.077738) (xy 364.7818 -269.06169) (xy 364.833095 -269.053565)
			(xy 364.885029 -269.053565) (xy 364.936324 -269.06169) (xy 364.985717 -269.077738) (xy 365.031991 -269.101316)
			(xy 365.074007 -269.131842) (xy 365.11073 -269.168565) (xy 365.141256 -269.210581) (xy 365.164834 -269.256855)
			(xy 365.180882 -269.306248) (xy 365.189007 -269.357543) (xy 365.189516 -269.38351) (xy 365.189007 -269.409477)
			(xy 365.469171 -269.409477) (xy 365.469171 -269.357543) (xy 365.477296 -269.306248) (xy 365.493344 -269.256855)
			(xy 365.516922 -269.210581) (xy 365.547448 -269.168565) (xy 365.584171 -269.131842) (xy 365.626187 -269.101316)
			(xy 365.672461 -269.077738) (xy 365.721854 -269.06169) (xy 365.773149 -269.053565) (xy 365.825083 -269.053565)
			(xy 365.876378 -269.06169) (xy 365.925771 -269.077738) (xy 365.972045 -269.101316) (xy 366.014061 -269.131842)
			(xy 366.050784 -269.168565) (xy 366.08131 -269.210581) (xy 366.104888 -269.256855) (xy 366.120936 -269.306248)
			(xy 366.129061 -269.357543) (xy 366.12957 -269.38351) (xy 366.129061 -269.409477) (xy 368.288317 -269.409477)
			(xy 368.288317 -269.357543) (xy 368.296442 -269.306248) (xy 368.31249 -269.256855) (xy 368.336068 -269.210581)
			(xy 368.366594 -269.168565) (xy 368.403317 -269.131842) (xy 368.445333 -269.101316) (xy 368.491607 -269.077738)
			(xy 368.541 -269.06169) (xy 368.592295 -269.053565) (xy 368.644229 -269.053565) (xy 368.695524 -269.06169)
			(xy 368.744917 -269.077738) (xy 368.791191 -269.101316) (xy 368.833207 -269.131842) (xy 368.86993 -269.168565)
			(xy 368.900456 -269.210581) (xy 368.924034 -269.256855) (xy 368.940082 -269.306248) (xy 368.948207 -269.357543)
			(xy 368.948716 -269.38351) (xy 368.948207 -269.409477) (xy 370.167917 -269.409477) (xy 370.167917 -269.357543)
			(xy 370.176042 -269.306248) (xy 370.19209 -269.256855) (xy 370.215668 -269.210581) (xy 370.246194 -269.168565)
			(xy 370.282917 -269.131842) (xy 370.324933 -269.101316) (xy 370.371207 -269.077738) (xy 370.4206 -269.06169)
			(xy 370.471895 -269.053565) (xy 370.523829 -269.053565) (xy 370.575124 -269.06169) (xy 370.624517 -269.077738)
			(xy 370.670791 -269.101316) (xy 370.712807 -269.131842) (xy 370.74953 -269.168565) (xy 370.780056 -269.210581)
			(xy 370.803634 -269.256855) (xy 370.819682 -269.306248) (xy 370.827807 -269.357543) (xy 370.828316 -269.38351)
			(xy 370.827807 -269.409477) (xy 370.819682 -269.460772) (xy 370.803634 -269.510165) (xy 370.780056 -269.556439)
			(xy 370.74953 -269.598455) (xy 370.712807 -269.635178) (xy 370.670791 -269.665704) (xy 370.624517 -269.689282)
			(xy 370.575124 -269.70533) (xy 370.523829 -269.713455) (xy 370.471895 -269.713455) (xy 370.4206 -269.70533)
			(xy 370.371207 -269.689282) (xy 370.324933 -269.665704) (xy 370.282917 -269.635178) (xy 370.246194 -269.598455)
			(xy 370.215668 -269.556439) (xy 370.19209 -269.510165) (xy 370.176042 -269.460772) (xy 370.167917 -269.409477)
			(xy 368.948207 -269.409477) (xy 368.940082 -269.460772) (xy 368.924034 -269.510165) (xy 368.900456 -269.556439)
			(xy 368.86993 -269.598455) (xy 368.833207 -269.635178) (xy 368.791191 -269.665704) (xy 368.744917 -269.689282)
			(xy 368.695524 -269.70533) (xy 368.644229 -269.713455) (xy 368.592295 -269.713455) (xy 368.541 -269.70533)
			(xy 368.491607 -269.689282) (xy 368.445333 -269.665704) (xy 368.403317 -269.635178) (xy 368.366594 -269.598455)
			(xy 368.336068 -269.556439) (xy 368.31249 -269.510165) (xy 368.296442 -269.460772) (xy 368.288317 -269.409477)
			(xy 366.129061 -269.409477) (xy 366.120936 -269.460772) (xy 366.104888 -269.510165) (xy 366.08131 -269.556439)
			(xy 366.050784 -269.598455) (xy 366.014061 -269.635178) (xy 365.972045 -269.665704) (xy 365.925771 -269.689282)
			(xy 365.876378 -269.70533) (xy 365.825083 -269.713455) (xy 365.773149 -269.713455) (xy 365.721854 -269.70533)
			(xy 365.672461 -269.689282) (xy 365.626187 -269.665704) (xy 365.584171 -269.635178) (xy 365.547448 -269.598455)
			(xy 365.516922 -269.556439) (xy 365.493344 -269.510165) (xy 365.477296 -269.460772) (xy 365.469171 -269.409477)
			(xy 365.189007 -269.409477) (xy 365.180882 -269.460772) (xy 365.164834 -269.510165) (xy 365.141256 -269.556439)
			(xy 365.11073 -269.598455) (xy 365.074007 -269.635178) (xy 365.031991 -269.665704) (xy 364.985717 -269.689282)
			(xy 364.936324 -269.70533) (xy 364.885029 -269.713455) (xy 364.833095 -269.713455) (xy 364.7818 -269.70533)
			(xy 364.732407 -269.689282) (xy 364.686133 -269.665704) (xy 364.644117 -269.635178) (xy 364.607394 -269.598455)
			(xy 364.576868 -269.556439) (xy 364.55329 -269.510165) (xy 364.537242 -269.460772) (xy 364.529117 -269.409477)
			(xy 364.249207 -269.409477) (xy 364.241082 -269.460772) (xy 364.225034 -269.510165) (xy 364.201456 -269.556439)
			(xy 364.17093 -269.598455) (xy 364.134207 -269.635178) (xy 364.092191 -269.665704) (xy 364.045917 -269.689282)
			(xy 363.996524 -269.70533) (xy 363.945229 -269.713455) (xy 363.893295 -269.713455) (xy 363.842 -269.70533)
			(xy 363.792607 -269.689282) (xy 363.746333 -269.665704) (xy 363.704317 -269.635178) (xy 363.667594 -269.598455)
			(xy 363.637068 -269.556439) (xy 363.61349 -269.510165) (xy 363.597442 -269.460772) (xy 363.589317 -269.409477)
			(xy 363.309407 -269.409477) (xy 363.301282 -269.460772) (xy 363.285234 -269.510165) (xy 363.261656 -269.556439)
			(xy 363.23113 -269.598455) (xy 363.194407 -269.635178) (xy 363.152391 -269.665704) (xy 363.106117 -269.689282)
			(xy 363.056724 -269.70533) (xy 363.005429 -269.713455) (xy 362.953495 -269.713455) (xy 362.9022 -269.70533)
			(xy 362.852807 -269.689282) (xy 362.806533 -269.665704) (xy 362.764517 -269.635178) (xy 362.727794 -269.598455)
			(xy 362.697268 -269.556439) (xy 362.67369 -269.510165) (xy 362.657642 -269.460772) (xy 362.649517 -269.409477)
			(xy 362.370115 -269.409477) (xy 362.36199 -269.460772) (xy 362.345942 -269.510165) (xy 362.322364 -269.556439)
			(xy 362.291838 -269.598455) (xy 362.255115 -269.635178) (xy 362.213099 -269.665704) (xy 362.166825 -269.689282)
			(xy 362.117432 -269.70533) (xy 362.066137 -269.713455) (xy 362.014203 -269.713455) (xy 361.962908 -269.70533)
			(xy 361.913515 -269.689282) (xy 361.867241 -269.665704) (xy 361.825225 -269.635178) (xy 361.788502 -269.598455)
			(xy 361.757976 -269.556439) (xy 361.734398 -269.510165) (xy 361.71835 -269.460772) (xy 361.710225 -269.409477)
			(xy 361.429807 -269.409477) (xy 361.421682 -269.460772) (xy 361.405634 -269.510165) (xy 361.382056 -269.556439)
			(xy 361.35153 -269.598455) (xy 361.314807 -269.635178) (xy 361.272791 -269.665704) (xy 361.226517 -269.689282)
			(xy 361.177124 -269.70533) (xy 361.125829 -269.713455) (xy 361.073895 -269.713455) (xy 361.0226 -269.70533)
			(xy 360.973207 -269.689282) (xy 360.926933 -269.665704) (xy 360.884917 -269.635178) (xy 360.848194 -269.598455)
			(xy 360.817668 -269.556439) (xy 360.79409 -269.510165) (xy 360.778042 -269.460772) (xy 360.769917 -269.409477)
			(xy 360.490167 -269.409477) (xy 360.482814 -269.457852) (xy 360.467961 -269.505531) (xy 360.4461 -269.550431)
			(xy 360.417727 -269.591527) (xy 360.383491 -269.627884) (xy 360.344171 -269.658672) (xy 360.322622 -269.671292)
			(xy 360.311175 -269.678244) (xy 360.292112 -269.697042) (xy 360.278584 -269.720146) (xy 360.271519 -269.74597)
			(xy 360.271402 -269.772742) (xy 360.27824 -269.798627) (xy 360.291565 -269.821848) (xy 360.300778 -269.831566)
			(xy 360.413554 -269.944342) (xy 360.448098 -269.921736) (xy 360.468443 -269.908838) (xy 360.51208 -269.888435)
			(xy 360.558217 -269.874586) (xy 360.605877 -269.867584) (xy 360.629962 -269.867126) (xy 360.655934 -269.867606)
			(xy 360.707239 -269.875726) (xy 360.756642 -269.891772) (xy 360.802926 -269.91535) (xy 360.844952 -269.945877)
			(xy 360.881685 -269.982604) (xy 360.91222 -270.024625) (xy 360.935805 -270.070905) (xy 360.95186 -270.120305)
			(xy 360.959989 -270.171608) (xy 360.960416 -270.19758) (xy 360.95998 -270.221667) (xy 360.959704 -270.223547)
			(xy 361.239817 -270.223547) (xy 361.239817 -270.171613) (xy 361.247942 -270.120318) (xy 361.26399 -270.070925)
			(xy 361.287568 -270.024651) (xy 361.318094 -269.982635) (xy 361.354817 -269.945912) (xy 361.396833 -269.915386)
			(xy 361.443107 -269.891808) (xy 361.4925 -269.87576) (xy 361.543795 -269.867635) (xy 361.595729 -269.867635)
			(xy 361.647024 -269.87576) (xy 361.696417 -269.891808) (xy 361.742691 -269.915386) (xy 361.784707 -269.945912)
			(xy 361.82143 -269.982635) (xy 361.851956 -270.024651) (xy 361.875534 -270.070925) (xy 361.891582 -270.120318)
			(xy 361.899707 -270.171613) (xy 361.900216 -270.19758) (xy 361.899707 -270.223547) (xy 362.179617 -270.223547)
			(xy 362.179617 -270.171613) (xy 362.187742 -270.120318) (xy 362.20379 -270.070925) (xy 362.227368 -270.024651)
			(xy 362.257894 -269.982635) (xy 362.294617 -269.945912) (xy 362.336633 -269.915386) (xy 362.382907 -269.891808)
			(xy 362.4323 -269.87576) (xy 362.483595 -269.867635) (xy 362.535529 -269.867635) (xy 362.586824 -269.87576)
			(xy 362.636217 -269.891808) (xy 362.682491 -269.915386) (xy 362.724507 -269.945912) (xy 362.76123 -269.982635)
			(xy 362.791756 -270.024651) (xy 362.815334 -270.070925) (xy 362.831382 -270.120318) (xy 362.839507 -270.171613)
			(xy 362.840016 -270.19758) (xy 362.839507 -270.223547) (xy 363.119417 -270.223547) (xy 363.119417 -270.171613)
			(xy 363.127542 -270.120318) (xy 363.14359 -270.070925) (xy 363.167168 -270.024651) (xy 363.197694 -269.982635)
			(xy 363.234417 -269.945912) (xy 363.276433 -269.915386) (xy 363.322707 -269.891808) (xy 363.3721 -269.87576)
			(xy 363.423395 -269.867635) (xy 363.475329 -269.867635) (xy 363.526624 -269.87576) (xy 363.576017 -269.891808)
			(xy 363.622291 -269.915386) (xy 363.664307 -269.945912) (xy 363.70103 -269.982635) (xy 363.731556 -270.024651)
			(xy 363.755134 -270.070925) (xy 363.771182 -270.120318) (xy 363.779307 -270.171613) (xy 363.779816 -270.19758)
			(xy 363.779307 -270.223547) (xy 364.059471 -270.223547) (xy 364.059471 -270.171613) (xy 364.067596 -270.120318)
			(xy 364.083644 -270.070925) (xy 364.107222 -270.024651) (xy 364.137748 -269.982635) (xy 364.174471 -269.945912)
			(xy 364.216487 -269.915386) (xy 364.262761 -269.891808) (xy 364.312154 -269.87576) (xy 364.363449 -269.867635)
			(xy 364.415383 -269.867635) (xy 364.466678 -269.87576) (xy 364.516071 -269.891808) (xy 364.562345 -269.915386)
			(xy 364.604361 -269.945912) (xy 364.641084 -269.982635) (xy 364.67161 -270.024651) (xy 364.695188 -270.070925)
			(xy 364.711236 -270.120318) (xy 364.719361 -270.171613) (xy 364.71987 -270.19758) (xy 364.719361 -270.223547)
			(xy 364.999017 -270.223547) (xy 364.999017 -270.171613) (xy 365.007142 -270.120318) (xy 365.02319 -270.070925)
			(xy 365.046768 -270.024651) (xy 365.077294 -269.982635) (xy 365.114017 -269.945912) (xy 365.156033 -269.915386)
			(xy 365.202307 -269.891808) (xy 365.2517 -269.87576) (xy 365.302995 -269.867635) (xy 365.354929 -269.867635)
			(xy 365.406224 -269.87576) (xy 365.455617 -269.891808) (xy 365.501891 -269.915386) (xy 365.543907 -269.945912)
			(xy 365.58063 -269.982635) (xy 365.611156 -270.024651) (xy 365.634734 -270.070925) (xy 365.650782 -270.120318)
			(xy 365.658907 -270.171613) (xy 365.659416 -270.19758) (xy 365.658907 -270.223547) (xy 365.939071 -270.223547)
			(xy 365.939071 -270.171613) (xy 365.947196 -270.120318) (xy 365.963244 -270.070925) (xy 365.986822 -270.024651)
			(xy 366.017348 -269.982635) (xy 366.054071 -269.945912) (xy 366.096087 -269.915386) (xy 366.142361 -269.891808)
			(xy 366.191754 -269.87576) (xy 366.243049 -269.867635) (xy 366.294983 -269.867635) (xy 366.346278 -269.87576)
			(xy 366.395671 -269.891808) (xy 366.441945 -269.915386) (xy 366.483961 -269.945912) (xy 366.520684 -269.982635)
			(xy 366.55121 -270.024651) (xy 366.574788 -270.070925) (xy 366.590836 -270.120318) (xy 366.598961 -270.171613)
			(xy 366.59947 -270.19758) (xy 366.598961 -270.223547) (xy 370.638071 -270.223547) (xy 370.638071 -270.171613)
			(xy 370.646196 -270.120318) (xy 370.662244 -270.070925) (xy 370.685822 -270.024651) (xy 370.716348 -269.982635)
			(xy 370.753071 -269.945912) (xy 370.795087 -269.915386) (xy 370.841361 -269.891808) (xy 370.890754 -269.87576)
			(xy 370.942049 -269.867635) (xy 370.993983 -269.867635) (xy 371.045278 -269.87576) (xy 371.094671 -269.891808)
			(xy 371.140945 -269.915386) (xy 371.182961 -269.945912) (xy 371.219684 -269.982635) (xy 371.25021 -270.024651)
			(xy 371.273788 -270.070925) (xy 371.289836 -270.120318) (xy 371.297961 -270.171613) (xy 371.29847 -270.19758)
			(xy 371.297961 -270.223547) (xy 371.289836 -270.274842) (xy 371.273788 -270.324235) (xy 371.25021 -270.370509)
			(xy 371.219684 -270.412525) (xy 371.182961 -270.449248) (xy 371.140945 -270.479774) (xy 371.094671 -270.503352)
			(xy 371.045278 -270.5194) (xy 370.993983 -270.527525) (xy 370.942049 -270.527525) (xy 370.890754 -270.5194)
			(xy 370.841361 -270.503352) (xy 370.795087 -270.479774) (xy 370.753071 -270.449248) (xy 370.716348 -270.412525)
			(xy 370.685822 -270.370509) (xy 370.662244 -270.324235) (xy 370.646196 -270.274842) (xy 370.638071 -270.223547)
			(xy 366.598961 -270.223547) (xy 366.590836 -270.274842) (xy 366.574788 -270.324235) (xy 366.55121 -270.370509)
			(xy 366.520684 -270.412525) (xy 366.483961 -270.449248) (xy 366.441945 -270.479774) (xy 366.395671 -270.503352)
			(xy 366.346278 -270.5194) (xy 366.294983 -270.527525) (xy 366.243049 -270.527525) (xy 366.191754 -270.5194)
			(xy 366.142361 -270.503352) (xy 366.096087 -270.479774) (xy 366.054071 -270.449248) (xy 366.017348 -270.412525)
			(xy 365.986822 -270.370509) (xy 365.963244 -270.324235) (xy 365.947196 -270.274842) (xy 365.939071 -270.223547)
			(xy 365.658907 -270.223547) (xy 365.650782 -270.274842) (xy 365.634734 -270.324235) (xy 365.611156 -270.370509)
			(xy 365.58063 -270.412525) (xy 365.543907 -270.449248) (xy 365.501891 -270.479774) (xy 365.455617 -270.503352)
			(xy 365.406224 -270.5194) (xy 365.354929 -270.527525) (xy 365.302995 -270.527525) (xy 365.2517 -270.5194)
			(xy 365.202307 -270.503352) (xy 365.156033 -270.479774) (xy 365.114017 -270.449248) (xy 365.077294 -270.412525)
			(xy 365.046768 -270.370509) (xy 365.02319 -270.324235) (xy 365.007142 -270.274842) (xy 364.999017 -270.223547)
			(xy 364.719361 -270.223547) (xy 364.711236 -270.274842) (xy 364.695188 -270.324235) (xy 364.67161 -270.370509)
			(xy 364.641084 -270.412525) (xy 364.604361 -270.449248) (xy 364.562345 -270.479774) (xy 364.516071 -270.503352)
			(xy 364.466678 -270.5194) (xy 364.415383 -270.527525) (xy 364.363449 -270.527525) (xy 364.312154 -270.5194)
			(xy 364.262761 -270.503352) (xy 364.216487 -270.479774) (xy 364.174471 -270.449248) (xy 364.137748 -270.412525)
			(xy 364.107222 -270.370509) (xy 364.083644 -270.324235) (xy 364.067596 -270.274842) (xy 364.059471 -270.223547)
			(xy 363.779307 -270.223547) (xy 363.771182 -270.274842) (xy 363.755134 -270.324235) (xy 363.731556 -270.370509)
			(xy 363.70103 -270.412525) (xy 363.664307 -270.449248) (xy 363.622291 -270.479774) (xy 363.576017 -270.503352)
			(xy 363.526624 -270.5194) (xy 363.475329 -270.527525) (xy 363.423395 -270.527525) (xy 363.3721 -270.5194)
			(xy 363.322707 -270.503352) (xy 363.276433 -270.479774) (xy 363.234417 -270.449248) (xy 363.197694 -270.412525)
			(xy 363.167168 -270.370509) (xy 363.14359 -270.324235) (xy 363.127542 -270.274842) (xy 363.119417 -270.223547)
			(xy 362.839507 -270.223547) (xy 362.831382 -270.274842) (xy 362.815334 -270.324235) (xy 362.791756 -270.370509)
			(xy 362.76123 -270.412525) (xy 362.724507 -270.449248) (xy 362.682491 -270.479774) (xy 362.636217 -270.503352)
			(xy 362.586824 -270.5194) (xy 362.535529 -270.527525) (xy 362.483595 -270.527525) (xy 362.4323 -270.5194)
			(xy 362.382907 -270.503352) (xy 362.336633 -270.479774) (xy 362.294617 -270.449248) (xy 362.257894 -270.412525)
			(xy 362.227368 -270.370509) (xy 362.20379 -270.324235) (xy 362.187742 -270.274842) (xy 362.179617 -270.223547)
			(xy 361.899707 -270.223547) (xy 361.891582 -270.274842) (xy 361.875534 -270.324235) (xy 361.851956 -270.370509)
			(xy 361.82143 -270.412525) (xy 361.784707 -270.449248) (xy 361.742691 -270.479774) (xy 361.696417 -270.503352)
			(xy 361.647024 -270.5194) (xy 361.595729 -270.527525) (xy 361.543795 -270.527525) (xy 361.4925 -270.5194)
			(xy 361.443107 -270.503352) (xy 361.396833 -270.479774) (xy 361.354817 -270.449248) (xy 361.318094 -270.412525)
			(xy 361.287568 -270.370509) (xy 361.26399 -270.324235) (xy 361.247942 -270.274842) (xy 361.239817 -270.223547)
			(xy 360.959704 -270.223547) (xy 360.952981 -270.26933) (xy 360.939129 -270.315469) (xy 360.918717 -270.359105)
			(xy 360.905806 -270.379444) (xy 360.8832 -270.413988) (xy 361.154218 -270.685006) (xy 361.16895 -270.688308)
			(xy 361.181904 -270.691356) (xy 361.188 -270.69288) (xy 361.951524 -270.69288)
		)
		(stroke
			(width 0)
			(type solid)
		)
		(fill yes)
		(layer "In2.Cu")
		(net "PVCCINFAON_CPU0")
	)
	(gr_poly
		(pts
			(xy 21.29917 -183.897524) (xy 21.312698 -183.897104) (xy 21.338805 -183.889998) (xy 21.362125 -183.876278)
			(xy 21.381018 -183.85691) (xy 21.394153 -183.833257) (xy 21.400608 -183.806981) (xy 21.399928 -183.779933)
			(xy 21.39216 -183.754016) (xy 21.377851 -183.731053) (xy 21.368258 -183.721502) (xy 21.347402 -183.70327)
			(xy 21.310659 -183.661814) (xy 21.280294 -183.615483) (xy 21.256947 -183.565249) (xy 21.241105 -183.512167)
			(xy 21.233104 -183.457353) (xy 21.232622 -183.429656) (xy 21.233108 -183.402405) (xy 21.240864 -183.348457)
			(xy 21.256219 -183.296162) (xy 21.278861 -183.246585) (xy 21.308327 -183.200735) (xy 21.344018 -183.159544)
			(xy 21.385209 -183.123853) (xy 21.431059 -183.094387) (xy 21.480636 -183.071745) (xy 21.532931 -183.05639)
			(xy 21.586879 -183.048634) (xy 21.641381 -183.048634) (xy 21.695329 -183.05639) (xy 21.747624 -183.071745)
			(xy 21.797201 -183.094387) (xy 21.843051 -183.123853) (xy 21.884242 -183.159544) (xy 21.919933 -183.200735)
			(xy 21.944625 -183.239156) (xy 22.886922 -183.239156) (xy 22.890993 -183.183534) (xy 22.903119 -183.129097)
			(xy 22.923042 -183.077006) (xy 22.950338 -183.028371) (xy 22.984424 -182.984228) (xy 23.024573 -182.945519)
			(xy 23.069931 -182.913068) (xy 23.119531 -182.887567) (xy 23.172315 -182.86956) (xy 23.227158 -182.85943)
			(xy 23.282892 -182.857393) (xy 23.338329 -182.863493) (xy 23.392286 -182.877599) (xy 23.443615 -182.899411)
			(xy 23.491221 -182.928465) (xy 23.534089 -182.96414) (xy 23.571306 -183.005677) (xy 23.602079 -183.05219)
			(xy 23.625751 -183.102687) (xy 23.641819 -183.156094) (xy 23.649939 -183.21127) (xy 23.650448 -183.239156)
			(xy 23.649939 -183.267042) (xy 23.641819 -183.322218) (xy 23.639824 -183.32885) (xy 35.261795 -183.32885)
			(xy 35.261795 -183.27435) (xy 35.269552 -183.220404) (xy 35.284906 -183.168112) (xy 35.307547 -183.118536)
			(xy 35.337012 -183.072688) (xy 35.372702 -183.031499) (xy 35.413891 -182.995809) (xy 35.45974 -182.966345)
			(xy 35.509315 -182.943705) (xy 35.561608 -182.928351) (xy 35.615554 -182.920595) (xy 35.642804 -182.920132)
			(xy 35.670175 -182.920588) (xy 35.724355 -182.928407) (xy 35.776858 -182.943898) (xy 35.826605 -182.966742)
			(xy 35.872571 -182.996469) (xy 35.893502 -183.014112) (xy 35.90483 -183.023348) (xy 35.931387 -183.035524)
			(xy 35.960304 -183.039697) (xy 35.989221 -183.035524) (xy 36.015778 -183.023348) (xy 36.027106 -183.014112)
			(xy 36.048027 -182.996459) (xy 36.094002 -182.966748) (xy 36.143753 -182.943915) (xy 36.196256 -182.928427)
			(xy 36.250434 -182.920604) (xy 36.277804 -182.920132) (xy 36.305058 -182.920538) (xy 36.359011 -182.928296)
			(xy 36.411311 -182.943653) (xy 36.460893 -182.966297) (xy 36.506747 -182.995766) (xy 36.547941 -183.031462)
			(xy 36.583636 -183.072656) (xy 36.613105 -183.118511) (xy 36.635748 -183.168093) (xy 36.651105 -183.220393)
			(xy 36.658862 -183.274346) (xy 36.658862 -183.32885) (xy 40.544995 -183.32885) (xy 40.544995 -183.27435)
			(xy 40.552752 -183.220404) (xy 40.568106 -183.168112) (xy 40.590747 -183.118536) (xy 40.620212 -183.072688)
			(xy 40.655902 -183.031499) (xy 40.697091 -182.995809) (xy 40.74294 -182.966345) (xy 40.792515 -182.943705)
			(xy 40.844808 -182.928351) (xy 40.898754 -182.920595) (xy 40.926004 -182.920132) (xy 40.953375 -182.920588)
			(xy 41.007555 -182.928407) (xy 41.060058 -182.943898) (xy 41.109805 -182.966742) (xy 41.155771 -182.996469)
			(xy 41.176702 -183.014112) (xy 41.18803 -183.023348) (xy 41.214587 -183.035524) (xy 41.243504 -183.039697)
			(xy 41.272421 -183.035524) (xy 41.298978 -183.023348) (xy 41.310306 -183.014112) (xy 41.331227 -182.996459)
			(xy 41.377202 -182.966748) (xy 41.426953 -182.943915) (xy 41.479456 -182.928427) (xy 41.533634 -182.920604)
			(xy 41.561004 -182.920132) (xy 41.588258 -182.920538) (xy 41.642211 -182.928296) (xy 41.694511 -182.943653)
			(xy 41.744093 -182.966297) (xy 41.789947 -182.995766) (xy 41.831141 -183.031462) (xy 41.866836 -183.072656)
			(xy 41.896305 -183.118511) (xy 41.918948 -183.168093) (xy 41.934305 -183.220393) (xy 41.942062 -183.274346)
			(xy 41.942062 -183.328854) (xy 41.934305 -183.382807) (xy 41.918948 -183.435107) (xy 41.896305 -183.484689)
			(xy 41.866836 -183.530544) (xy 41.831141 -183.571738) (xy 41.789947 -183.607434) (xy 41.744093 -183.636903)
			(xy 41.694511 -183.659547) (xy 41.642211 -183.674904) (xy 41.588258 -183.682662) (xy 41.561004 -183.683148)
			(xy 41.533633 -183.682692) (xy 41.479453 -183.674874) (xy 41.42695 -183.659383) (xy 41.377203 -183.636539)
			(xy 41.331237 -183.606811) (xy 41.310306 -183.589168) (xy 41.298978 -183.579932) (xy 41.272421 -183.567756)
			(xy 41.243504 -183.563583) (xy 41.214587 -183.567756) (xy 41.18803 -183.579932) (xy 41.176702 -183.589168)
			(xy 41.155776 -183.606815) (xy 41.109802 -183.636526) (xy 41.060053 -183.659361) (xy 41.007551 -183.674851)
			(xy 40.953374 -183.682676) (xy 40.926004 -183.683148) (xy 40.898754 -183.682605) (xy 40.844808 -183.674849)
			(xy 40.792515 -183.659495) (xy 40.74294 -183.636855) (xy 40.697091 -183.607391) (xy 40.655902 -183.571701)
			(xy 40.620212 -183.530512) (xy 40.590747 -183.484664) (xy 40.568106 -183.435088) (xy 40.552752 -183.382796)
			(xy 40.544995 -183.32885) (xy 36.658862 -183.32885) (xy 36.658862 -183.328854) (xy 36.651105 -183.382807)
			(xy 36.635748 -183.435107) (xy 36.613105 -183.484689) (xy 36.583636 -183.530544) (xy 36.547941 -183.571738)
			(xy 36.506747 -183.607434) (xy 36.460893 -183.636903) (xy 36.411311 -183.659547) (xy 36.359011 -183.674904)
			(xy 36.305058 -183.682662) (xy 36.277804 -183.683148) (xy 36.250433 -183.682692) (xy 36.196253 -183.674874)
			(xy 36.14375 -183.659383) (xy 36.094003 -183.636539) (xy 36.048037 -183.606811) (xy 36.027106 -183.589168)
			(xy 36.015778 -183.579932) (xy 35.989221 -183.567756) (xy 35.960304 -183.563583) (xy 35.931387 -183.567756)
			(xy 35.90483 -183.579932) (xy 35.893502 -183.589168) (xy 35.872576 -183.606815) (xy 35.826602 -183.636526)
			(xy 35.776853 -183.659361) (xy 35.724351 -183.674851) (xy 35.670174 -183.682676) (xy 35.642804 -183.683148)
			(xy 35.615554 -183.682605) (xy 35.561608 -183.674849) (xy 35.509315 -183.659495) (xy 35.45974 -183.636855)
			(xy 35.413891 -183.607391) (xy 35.372702 -183.571701) (xy 35.337012 -183.530512) (xy 35.307547 -183.484664)
			(xy 35.284906 -183.435088) (xy 35.269552 -183.382796) (xy 35.261795 -183.32885) (xy 23.639824 -183.32885)
			(xy 23.625751 -183.375625) (xy 23.602079 -183.426122) (xy 23.571306 -183.472635) (xy 23.534089 -183.514172)
			(xy 23.491221 -183.549847) (xy 23.443615 -183.578901) (xy 23.392286 -183.600713) (xy 23.338329 -183.614819)
			(xy 23.282892 -183.620919) (xy 23.227158 -183.618882) (xy 23.172315 -183.608752) (xy 23.119531 -183.590745)
			(xy 23.069931 -183.565244) (xy 23.024573 -183.532793) (xy 22.984424 -183.494084) (xy 22.950338 -183.449941)
			(xy 22.923042 -183.401306) (xy 22.903119 -183.349215) (xy 22.890993 -183.294778) (xy 22.886922 -183.239156)
			(xy 21.944625 -183.239156) (xy 21.949399 -183.246585) (xy 21.972041 -183.296162) (xy 21.987396 -183.348457)
			(xy 21.995152 -183.402405) (xy 21.995638 -183.429656) (xy 21.99514 -183.457351) (xy 21.987129 -183.512159)
			(xy 21.971282 -183.565235) (xy 21.947933 -183.615463) (xy 21.917572 -183.661791) (xy 21.880836 -183.703247)
			(xy 21.860002 -183.721502) (xy 21.850382 -183.731014) (xy 21.836098 -183.753979) (xy 21.82835 -183.77989)
			(xy 21.827684 -183.806927) (xy 21.834145 -183.833188) (xy 21.84728 -183.856829) (xy 21.866166 -183.876187)
			(xy 21.889474 -183.889903) (xy 21.915568 -183.897012) (xy 21.92909 -183.897524) (xy 57.685686 -183.897524)
			(xy 59.264042 -182.319168) (xy 59.264042 -169.200322) (xy 59.247024 -169.192194) (xy 59.223207 -169.181613)
			(xy 59.178694 -169.154511) (xy 59.138607 -169.12121) (xy 59.103802 -169.082422) (xy 59.075022 -169.038975)
			(xy 59.052882 -168.991797) (xy 59.037855 -168.941896) (xy 59.030262 -168.890337) (xy 59.029854 -168.86428)
			(xy 59.030294 -168.839069) (xy 59.037412 -168.789153) (xy 59.051503 -168.74074) (xy 59.072285 -168.694801)
			(xy 59.099342 -168.652254) (xy 59.132133 -168.613952) (xy 59.170001 -168.580659) (xy 59.212187 -168.553044)
			(xy 59.234832 -168.541954) (xy 59.264042 -168.528238) (xy 59.264042 -162.80257) (xy 58.999628 -162.538156)
			(xy 53.034946 -162.538156) (xy 53.009964 -162.537641) (xy 52.960621 -162.529783) (xy 52.913111 -162.514315)
			(xy 52.868599 -162.491617) (xy 52.828178 -162.462246) (xy 52.810156 -162.444938) (xy 52.416964 -162.051492)
			(xy 52.340002 -162.051492) (xy 52.330542 -162.051874) (xy 52.312908 -162.058731) (xy 52.298958 -162.071513)
			(xy 52.29059 -162.088482) (xy 52.288942 -162.10733) (xy 52.291234 -162.116516) (xy 52.29479 -162.128708)
			(xy 52.299108 -162.136074) (xy 52.315652 -162.165368) (xy 52.339292 -162.228349) (xy 52.346098 -162.261296)
			(xy 52.349072 -162.278477) (xy 52.352248 -162.313203) (xy 52.352448 -162.330638) (xy 52.35196 -162.357889)
			(xy 52.344199 -162.411834) (xy 52.328841 -162.464127) (xy 52.306198 -162.513702) (xy 52.276732 -162.55955)
			(xy 52.241041 -162.600739) (xy 52.199852 -162.63643) (xy 52.154003 -162.665897) (xy 52.104429 -162.68854)
			(xy 52.052136 -162.703899) (xy 51.998191 -162.71166) (xy 51.97094 -162.712146) (xy 51.943732 -162.711666)
			(xy 51.889867 -162.703941) (xy 51.837647 -162.688641) (xy 51.78813 -162.666077) (xy 51.742321 -162.636706)
			(xy 51.701149 -162.601126) (xy 51.66545 -162.560056) (xy 51.635949 -162.514332) (xy 51.613243 -162.464879)
			(xy 51.597793 -162.412703) (xy 51.589913 -162.358861) (xy 51.589432 -162.331654) (xy 51.589432 -162.331146)
			(xy 51.589803 -162.304772) (xy 51.596935 -162.252511) (xy 51.603656 -162.227006) (xy 51.606562 -162.212663)
			(xy 51.604957 -162.183453) (xy 51.595132 -162.155899) (xy 51.577895 -162.132263) (xy 51.554662 -162.114488)
			(xy 51.527341 -162.104033) (xy 51.498176 -162.101757) (xy 51.483768 -162.104324) (xy 51.461692 -162.109333)
			(xy 51.416741 -162.114686) (xy 51.394106 -162.114992) (xy 51.388518 -162.114992) (xy 51.361055 -162.114126)
			(xy 51.306794 -162.10548) (xy 51.254334 -162.089142) (xy 51.20476 -162.06545) (xy 51.159095 -162.034893)
			(xy 51.118285 -161.998103) (xy 51.083173 -161.955841) (xy 51.054484 -161.90898) (xy 51.032813 -161.858489)
			(xy 51.018606 -161.805412) (xy 51.014884 -161.778188) (xy 51.013868 -161.769298) (xy 51.012852 -161.757106)
			(xy 51.012344 -161.733484) (xy 51.012809 -161.706638) (xy 51.02035 -161.653478) (xy 51.035268 -161.601899)
			(xy 51.057268 -161.55292) (xy 51.085915 -161.507509) (xy 51.120644 -161.46656) (xy 51.16077 -161.430883)
			(xy 51.2055 -161.401183) (xy 51.253951 -161.378044) (xy 51.305166 -161.361925) (xy 51.358136 -161.353143)
			(xy 51.384962 -161.351976) (xy 51.39309 -161.351976) (xy 51.421119 -161.352417) (xy 51.476587 -161.360507)
			(xy 51.530277 -161.376619) (xy 51.581036 -161.400406) (xy 51.604672 -161.415476) (xy 52.54879 -161.415476)
			(xy 52.573771 -161.415994) (xy 52.623113 -161.423855) (xy 52.670622 -161.439325) (xy 52.715132 -161.462022)
			(xy 52.755553 -161.491391) (xy 52.77358 -161.508694) (xy 52.884578 -161.619946) (xy 52.895664 -161.630195)
			(xy 52.922345 -161.64429) (xy 52.95198 -161.649975) (xy 52.981984 -161.646755) (xy 53.009738 -161.634911)
			(xy 53.032821 -161.615475) (xy 53.049219 -161.590144) (xy 53.057503 -161.561128) (xy 53.057806 -161.546032)
			(xy 53.057806 -161.539174) (xy 53.058294 -161.511924) (xy 53.066054 -161.45798) (xy 53.081411 -161.405689)
			(xy 53.104054 -161.356116) (xy 53.133521 -161.31027) (xy 53.169213 -161.269084) (xy 53.210402 -161.233397)
			(xy 53.256252 -161.203935) (xy 53.305827 -161.181297) (xy 53.358119 -161.165945) (xy 53.412064 -161.158191)
			(xy 53.439314 -161.157666) (xy 53.467023 -161.158165) (xy 53.521856 -161.166193) (xy 53.574948 -161.182077)
			(xy 53.62518 -161.205483) (xy 53.671493 -161.235917) (xy 53.692552 -161.253932) (xy 53.703658 -161.262355)
			(xy 53.729212 -161.273455) (xy 53.756814 -161.277248) (xy 53.784416 -161.273455) (xy 53.80997 -161.262355)
			(xy 53.821076 -161.253932) (xy 53.842119 -161.235896) (xy 53.888438 -161.205467) (xy 53.938674 -161.182062)
			(xy 53.991769 -161.166175) (xy 54.046604 -161.158141) (xy 54.074314 -161.157666) (xy 54.101565 -161.158153)
			(xy 54.155513 -161.165911) (xy 54.207807 -161.181267) (xy 54.257385 -161.203908) (xy 54.303235 -161.233375)
			(xy 54.344426 -161.269066) (xy 54.380118 -161.310255) (xy 54.409586 -161.356105) (xy 54.432229 -161.405681)
			(xy 54.447587 -161.457975) (xy 54.455346 -161.511923) (xy 54.455822 -161.539174) (xy 54.455359 -161.566463)
			(xy 54.447587 -161.620485) (xy 54.432199 -161.672849) (xy 54.409508 -161.722486) (xy 54.395116 -161.745676)
			(xy 54.388137 -161.757361) (xy 54.380023 -161.783332) (xy 54.379062 -161.810523) (xy 54.385321 -161.837001)
			(xy 54.398355 -161.860884) (xy 54.417238 -161.880473) (xy 54.440626 -161.894375) (xy 54.466857 -161.901602)
			(xy 54.48046 -161.90214) (xy 59.1312 -161.90214) (xy 59.153044 -161.902902) (xy 59.156092 -161.903156)
			(xy 59.169939 -161.903551) (xy 59.197022 -161.897782) (xy 59.22156 -161.88495) (xy 59.241749 -161.865998)
			(xy 59.256105 -161.842319) (xy 59.263572 -161.815655) (xy 59.264042 -161.80181) (xy 59.264042 -160.564322)
			(xy 59.247024 -160.556194) (xy 59.223207 -160.545613) (xy 59.178694 -160.518511) (xy 59.138607 -160.48521)
			(xy 59.103802 -160.446422) (xy 59.075022 -160.402975) (xy 59.052882 -160.355797) (xy 59.037855 -160.305896)
			(xy 59.030262 -160.254337) (xy 59.029854 -160.22828) (xy 59.030428 -160.199251) (xy 59.039845 -160.141963)
			(xy 59.058427 -160.08696) (xy 59.085682 -160.035698) (xy 59.120889 -159.989533) (xy 59.141614 -159.9692)
			(xy 59.150518 -159.959518) (xy 59.163503 -159.936655) (xy 59.170217 -159.911233) (xy 59.170213 -159.884939)
			(xy 59.163492 -159.859519) (xy 59.1505 -159.836659) (xy 59.141614 -159.82696) (xy 59.122526 -159.808298)
			(xy 59.089595 -159.766284) (xy 59.063302 -159.719827) (xy 59.044233 -159.669967) (xy 59.032817 -159.617821)
			(xy 59.029308 -159.564555) (xy 59.033785 -159.511361) (xy 59.046148 -159.459431) (xy 59.066121 -159.409926)
			(xy 59.093255 -159.363955) (xy 59.126944 -159.322547) (xy 59.166434 -159.286628) (xy 59.21084 -159.257003)
			(xy 59.234832 -159.2453) (xy 59.264042 -159.231584) (xy 59.264042 -154.26817) (xy 58.999628 -154.003756)
			(xy 53.269134 -154.003756) (xy 53.244152 -154.00324) (xy 53.19481 -153.99538) (xy 53.147301 -153.979911)
			(xy 53.102791 -153.957212) (xy 53.062371 -153.927841) (xy 53.044344 -153.910538) (xy 52.223416 -153.089356)
			(xy 51.947572 -153.089356) (xy 51.89728 -153.139648) (xy 51.88705 -153.150626) (xy 51.872909 -153.177075)
			(xy 51.867057 -153.206491) (xy 51.87 -153.236338) (xy 51.881483 -153.264045) (xy 51.900516 -153.287224)
			(xy 51.925461 -153.303876) (xy 51.954166 -153.312568) (xy 51.969162 -153.31313) (xy 51.97094 -153.31313)
			(xy 51.998187 -153.313619) (xy 52.052125 -153.321379) (xy 52.104409 -153.336736) (xy 52.153976 -153.359377)
			(xy 52.199817 -153.388842) (xy 52.240999 -153.42453) (xy 52.276682 -153.465715) (xy 52.306142 -153.511559)
			(xy 52.328778 -153.561128) (xy 52.344129 -153.613415) (xy 52.351884 -153.667353) (xy 52.351884 -153.721847)
			(xy 52.344129 -153.775785) (xy 52.328778 -153.828072) (xy 52.306142 -153.877641) (xy 52.276682 -153.923485)
			(xy 52.240999 -153.96467) (xy 52.199817 -154.000358) (xy 52.153976 -154.029823) (xy 52.104409 -154.052464)
			(xy 52.052125 -154.067821) (xy 51.998187 -154.075581) (xy 51.97094 -154.076146) (xy 51.943732 -154.075666)
			(xy 51.889867 -154.067941) (xy 51.837647 -154.052641) (xy 51.78813 -154.030077) (xy 51.742321 -154.000706)
			(xy 51.701149 -153.965126) (xy 51.66545 -153.924056) (xy 51.635949 -153.878332) (xy 51.613243 -153.828879)
			(xy 51.597793 -153.776703) (xy 51.589913 -153.722861) (xy 51.589432 -153.695654) (xy 51.589432 -153.695146)
			(xy 51.589803 -153.668772) (xy 51.596935 -153.616511) (xy 51.603656 -153.591006) (xy 51.606562 -153.576663)
			(xy 51.604957 -153.547453) (xy 51.595132 -153.519899) (xy 51.577895 -153.496263) (xy 51.554662 -153.478488)
			(xy 51.527341 -153.468033) (xy 51.498176 -153.465757) (xy 51.483768 -153.468324) (xy 51.461692 -153.473333)
			(xy 51.416741 -153.478686) (xy 51.394106 -153.478992) (xy 51.388518 -153.478992) (xy 51.361513 -153.478149)
			(xy 51.308137 -153.469788) (xy 51.256474 -153.45398) (xy 51.207558 -153.431042) (xy 51.162367 -153.401433)
			(xy 51.121805 -153.365744) (xy 51.086683 -153.32469) (xy 51.057704 -153.279092) (xy 51.035448 -153.229862)
			(xy 51.020359 -153.177985) (xy 51.012739 -153.124498) (xy 51.012344 -153.097484) (xy 51.012831 -153.070232)
			(xy 51.020589 -153.016284) (xy 51.035945 -152.963988) (xy 51.058586 -152.91441) (xy 51.088052 -152.868558)
			(xy 51.123743 -152.827366) (xy 51.164932 -152.791672) (xy 51.210782 -152.762202) (xy 51.260358 -152.739556)
			(xy 51.312652 -152.724196) (xy 51.3666 -152.716433) (xy 51.393852 -152.715976) (xy 51.399948 -152.715976)
			(xy 51.421284 -152.716484) (xy 51.537616 -152.600152) (xy 51.590956 -152.546558) (xy 51.60894 -152.529202)
			(xy 51.649352 -152.499799) (xy 51.69387 -152.477089) (xy 51.741397 -152.461632) (xy 51.790758 -152.453811)
			(xy 51.815746 -152.45334) (xy 52.355242 -152.45334) (xy 52.380224 -152.453854) (xy 52.429568 -152.461711)
			(xy 52.47708 -152.477177) (xy 52.521593 -152.499873) (xy 52.562016 -152.529243) (xy 52.580032 -152.546558)
			(xy 52.897278 -152.864058) (xy 52.907126 -152.873319) (xy 52.930577 -152.88675) (xy 52.956732 -152.893551)
			(xy 52.983754 -152.893246) (xy 53.009748 -152.885855) (xy 53.032889 -152.871897) (xy 53.051553 -152.852353)
			(xy 53.064429 -152.828593) (xy 53.067966 -152.815544) (xy 53.074993 -152.788025) (xy 53.096083 -152.735292)
			(xy 53.124759 -152.686269) (xy 53.160387 -152.64204) (xy 53.20218 -152.603583) (xy 53.249213 -152.571748)
			(xy 53.300446 -152.54724) (xy 53.354748 -152.530599) (xy 53.410917 -152.522194) (xy 53.439314 -152.521666)
			(xy 53.467023 -152.522165) (xy 53.521856 -152.530193) (xy 53.574948 -152.546077) (xy 53.62518 -152.569483)
			(xy 53.671493 -152.599917) (xy 53.692552 -152.617932) (xy 53.703658 -152.626355) (xy 53.729212 -152.637455)
			(xy 53.756814 -152.641248) (xy 53.784416 -152.637455) (xy 53.80997 -152.626355) (xy 53.821076 -152.617932)
			(xy 53.842119 -152.599896) (xy 53.888438 -152.569467) (xy 53.938674 -152.546062) (xy 53.991769 -152.530175)
			(xy 54.046604 -152.522141) (xy 54.074314 -152.521666) (xy 54.101565 -152.522153) (xy 54.155513 -152.529911)
			(xy 54.207807 -152.545267) (xy 54.257385 -152.567908) (xy 54.303235 -152.597375) (xy 54.344426 -152.633066)
			(xy 54.380118 -152.674255) (xy 54.409586 -152.720105) (xy 54.432229 -152.769681) (xy 54.447587 -152.821975)
			(xy 54.455346 -152.875923) (xy 54.455822 -152.903174) (xy 54.455342 -152.930357) (xy 54.447626 -152.984174)
			(xy 54.432347 -153.036349) (xy 54.409813 -153.085826) (xy 54.380483 -153.131602) (xy 54.34495 -153.17275)
			(xy 54.324758 -153.190956) (xy 54.322726 -153.192734) (xy 54.318916 -153.196798) (xy 54.309185 -153.207933)
			(xy 54.296017 -153.234394) (xy 54.290975 -153.263519) (xy 54.294482 -153.292867) (xy 54.306244 -153.319984)
			(xy 54.325276 -153.342598) (xy 54.349986 -153.358817) (xy 54.378305 -153.367283) (xy 54.393084 -153.36774)
			(xy 59.1312 -153.36774) (xy 59.153044 -153.368502) (xy 59.156092 -153.368756) (xy 59.169939 -153.369151)
			(xy 59.197022 -153.363382) (xy 59.22156 -153.35055) (xy 59.241749 -153.331598) (xy 59.256105 -153.307919)
			(xy 59.263572 -153.281255) (xy 59.264042 -153.26741) (xy 59.264042 -151.928322) (xy 59.247024 -151.920194)
			(xy 59.223207 -151.909613) (xy 59.178694 -151.882511) (xy 59.138607 -151.84921) (xy 59.103802 -151.810422)
			(xy 59.075022 -151.766975) (xy 59.052882 -151.719797) (xy 59.037855 -151.669896) (xy 59.030262 -151.618337)
			(xy 59.029854 -151.59228) (xy 59.030428 -151.563251) (xy 59.039845 -151.505963) (xy 59.058427 -151.45096)
			(xy 59.085682 -151.399698) (xy 59.120889 -151.353533) (xy 59.141614 -151.3332) (xy 59.150518 -151.323518)
			(xy 59.163503 -151.300655) (xy 59.170217 -151.275233) (xy 59.170213 -151.248939) (xy 59.163492 -151.223519)
			(xy 59.1505 -151.200659) (xy 59.141614 -151.19096) (xy 59.122526 -151.172298) (xy 59.089595 -151.130284)
			(xy 59.063302 -151.083827) (xy 59.044233 -151.033967) (xy 59.032817 -150.981821) (xy 59.029308 -150.928555)
			(xy 59.033785 -150.875361) (xy 59.046148 -150.823431) (xy 59.066121 -150.773926) (xy 59.093255 -150.727955)
			(xy 59.126944 -150.686547) (xy 59.166434 -150.650628) (xy 59.21084 -150.621003) (xy 59.234832 -150.6093)
			(xy 59.264042 -150.595584) (xy 59.264042 -145.75917) (xy 58.974228 -145.469356) (xy 53.25745 -145.469356)
			(xy 53.232468 -145.468841) (xy 53.183125 -145.460984) (xy 53.135614 -145.445516) (xy 53.091102 -145.422819)
			(xy 53.05068 -145.393448) (xy 53.03266 -145.376138) (xy 52.75961 -145.102834) (xy 52.273962 -144.617186)
			(xy 52.232814 -144.658334) (xy 52.224625 -144.670215) (xy 52.214609 -144.697262) (xy 52.212565 -144.726032)
			(xy 52.218658 -144.754223) (xy 52.232399 -144.779582) (xy 52.242212 -144.79016) (xy 52.243228 -144.791176)
			(xy 52.248562 -144.797018) (xy 52.248816 -144.797018) (xy 52.268055 -144.818228) (xy 52.300607 -144.865337)
			(xy 52.325757 -144.91678) (xy 52.342942 -144.971402) (xy 52.351776 -145.027978) (xy 52.352448 -145.056606)
			(xy 52.352448 -145.064226) (xy 52.351588 -145.091218) (xy 52.343199 -145.144566) (xy 52.32737 -145.196197)
			(xy 52.304418 -145.24508) (xy 52.274801 -145.290238) (xy 52.239112 -145.330767) (xy 52.198064 -145.365859)
			(xy 52.152478 -145.394811) (xy 52.103264 -145.417045) (xy 52.051406 -145.432116) (xy 51.997942 -145.439724)
			(xy 51.97094 -145.440146) (xy 51.943732 -145.439666) (xy 51.889867 -145.431941) (xy 51.837647 -145.416641)
			(xy 51.78813 -145.394077) (xy 51.742321 -145.364706) (xy 51.701149 -145.329126) (xy 51.66545 -145.288056)
			(xy 51.635949 -145.242332) (xy 51.613243 -145.192879) (xy 51.597793 -145.140703) (xy 51.589913 -145.086861)
			(xy 51.589432 -145.059654) (xy 51.589432 -145.059146) (xy 51.589803 -145.032772) (xy 51.596935 -144.980511)
			(xy 51.603656 -144.955006) (xy 51.606562 -144.940663) (xy 51.604957 -144.911453) (xy 51.595132 -144.883899)
			(xy 51.577895 -144.860263) (xy 51.554662 -144.842488) (xy 51.527341 -144.832033) (xy 51.498176 -144.829757)
			(xy 51.483768 -144.832324) (xy 51.461692 -144.837333) (xy 51.416741 -144.842686) (xy 51.394106 -144.842992)
			(xy 51.388518 -144.842992) (xy 51.361513 -144.842149) (xy 51.308137 -144.833788) (xy 51.256474 -144.81798)
			(xy 51.207558 -144.795042) (xy 51.162367 -144.765433) (xy 51.121805 -144.729744) (xy 51.086683 -144.68869)
			(xy 51.057704 -144.643092) (xy 51.035448 -144.593862) (xy 51.020359 -144.541985) (xy 51.012739 -144.488498)
			(xy 51.012344 -144.461484) (xy 51.012831 -144.434232) (xy 51.020589 -144.380284) (xy 51.035945 -144.327988)
			(xy 51.058586 -144.27841) (xy 51.088052 -144.232558) (xy 51.123743 -144.191366) (xy 51.164932 -144.155672)
			(xy 51.210782 -144.126202) (xy 51.260358 -144.103556) (xy 51.312652 -144.088196) (xy 51.3666 -144.080433)
			(xy 51.393852 -144.079976) (xy 51.399948 -144.079976) (xy 51.421284 -144.080484) (xy 51.534568 -143.9672)
			(xy 51.552568 -143.949918) (xy 51.592952 -143.920614) (xy 51.637418 -143.897978) (xy 51.684875 -143.882566)
			(xy 51.734156 -143.874757) (xy 51.759104 -143.874236) (xy 52.2986 -143.874236) (xy 52.32355 -143.874725)
			(xy 52.372835 -143.88253) (xy 52.420293 -143.897947) (xy 52.464756 -143.920597) (xy 52.505129 -143.949923)
			(xy 52.523136 -143.9672) (xy 52.884578 -144.328642) (xy 52.895419 -144.338712) (xy 52.921488 -144.352682)
			(xy 52.950466 -144.358599) (xy 52.979924 -144.355967) (xy 53.007394 -144.345007) (xy 53.030573 -144.326637)
			(xy 53.047519 -144.302397) (xy 53.056811 -144.274319) (xy 53.057806 -144.259554) (xy 53.058792 -144.23275)
			(xy 53.067355 -144.1798) (xy 53.08325 -144.128572) (xy 53.106165 -144.080076) (xy 53.135648 -144.035268)
			(xy 53.171116 -143.995031) (xy 53.211872 -143.96016) (xy 53.25711 -143.931342) (xy 53.305939 -143.909145)
			(xy 53.357396 -143.894007) (xy 53.410466 -143.886227) (xy 53.437282 -143.885666) (xy 53.443378 -143.885666)
			(xy 53.47568 -143.886644) (xy 53.539269 -143.898136) (xy 53.56987 -143.908526) (xy 53.57114 -143.909034)
			(xy 53.573426 -143.909796) (xy 53.58647 -143.913528) (xy 53.613566 -143.914704) (xy 53.640013 -143.908693)
			(xy 53.663938 -143.895919) (xy 53.683647 -143.877287) (xy 53.697743 -143.854117) (xy 53.70195 -143.841216)
			(xy 53.7087 -143.813369) (xy 53.729419 -143.759948) (xy 53.757896 -143.710228) (xy 53.793489 -143.665326)
			(xy 53.835398 -143.626253) (xy 53.882679 -143.593889) (xy 53.93427 -143.56896) (xy 53.989009 -143.552029)
			(xy 54.045665 -143.543475) (xy 54.074314 -143.54302) (xy 54.101565 -143.543484) (xy 54.155513 -143.551243)
			(xy 54.207808 -143.566601) (xy 54.257385 -143.589244) (xy 54.303234 -143.618713) (xy 54.344423 -143.654407)
			(xy 54.380112 -143.6956) (xy 54.409576 -143.741452) (xy 54.432214 -143.791031) (xy 54.447566 -143.843328)
			(xy 54.455319 -143.897276) (xy 54.455822 -143.924528) (xy 54.455344 -143.95164) (xy 54.447663 -144.005317)
			(xy 54.432459 -144.057366) (xy 54.410039 -144.106738) (xy 54.380854 -144.152438) (xy 54.345493 -144.193545)
			(xy 54.304668 -144.229232) (xy 54.259202 -144.258779) (xy 54.21001 -144.281591) (xy 54.158083 -144.297208)
			(xy 54.104469 -144.305316) (xy 54.077362 -144.306036) (xy 54.074314 -144.306036) (xy 54.041719 -144.305352)
			(xy 53.977482 -144.294244) (xy 53.946552 -144.283938) (xy 53.945028 -144.28343) (xy 53.944012 -144.283176)
			(xy 53.930801 -144.27881) (xy 53.903068 -144.276681) (xy 53.87579 -144.282123) (xy 53.850997 -144.294731)
			(xy 53.830532 -144.313568) (xy 53.815916 -144.337234) (xy 53.811678 -144.350486) (xy 53.804928 -144.378334)
			(xy 53.78421 -144.431756) (xy 53.755734 -144.481479) (xy 53.720141 -144.526383) (xy 53.678232 -144.565459)
			(xy 53.630951 -144.597826) (xy 53.57936 -144.622758) (xy 53.524621 -144.639694) (xy 53.467964 -144.648251)
			(xy 53.439314 -144.648682) (xy 53.409478 -144.648081) (xy 53.350535 -144.638764) (xy 53.321966 -144.63014)
			(xy 53.292248 -144.620488) (xy 53.234336 -144.6784) (xy 53.389276 -144.83334) (xy 59.1058 -144.83334)
			(xy 59.115861 -144.833419) (xy 59.135942 -144.834689) (xy 59.145932 -144.83588) (xy 59.14771 -144.836134)
			(xy 59.150758 -144.836642) (xy 59.151012 -144.836642) (xy 59.152536 -144.836896) (xy 59.16666 -144.83781)
			(xy 59.194492 -144.832724) (xy 59.219859 -144.820195) (xy 59.240814 -144.801186) (xy 59.255748 -144.777156)
			(xy 59.263513 -144.74995) (xy 59.264042 -144.735804) (xy 59.264042 -133.446012) (xy 45.183298 -119.365268)
			(xy 24.4094 -119.365268) (xy 21.820378 -121.95429) (xy 21.820378 -123.902978) (xy 26.902408 -123.902978)
			(xy 26.906479 -123.847356) (xy 26.918605 -123.792919) (xy 26.938528 -123.740828) (xy 26.965824 -123.692193)
			(xy 26.99991 -123.64805) (xy 27.040059 -123.609341) (xy 27.085417 -123.57689) (xy 27.135017 -123.551389)
			(xy 27.187801 -123.533382) (xy 27.242644 -123.523252) (xy 27.298378 -123.521215) (xy 27.353815 -123.527315)
			(xy 27.407772 -123.541421) (xy 27.459101 -123.563233) (xy 27.506707 -123.592287) (xy 27.549575 -123.627962)
			(xy 27.586792 -123.669499) (xy 27.617565 -123.716012) (xy 27.641237 -123.766509) (xy 27.657305 -123.819916)
			(xy 27.665425 -123.875092) (xy 27.665934 -123.902978) (xy 27.665425 -123.930864) (xy 27.657305 -123.98604)
			(xy 27.641237 -124.039447) (xy 27.617565 -124.089944) (xy 27.586792 -124.136457) (xy 27.549575 -124.177994)
			(xy 27.506707 -124.213669) (xy 27.459101 -124.242723) (xy 27.407772 -124.264535) (xy 27.353815 -124.278641)
			(xy 27.298378 -124.284741) (xy 27.242644 -124.282704) (xy 27.187801 -124.272574) (xy 27.135017 -124.254567)
			(xy 27.085417 -124.229066) (xy 27.040059 -124.196615) (xy 26.99991 -124.157906) (xy 26.965824 -124.113763)
			(xy 26.938528 -124.065128) (xy 26.918605 -124.013037) (xy 26.906479 -123.9586) (xy 26.902408 -123.902978)
			(xy 21.820378 -123.902978) (xy 21.820378 -124.313442) (xy 28.05176 -124.313442) (xy 28.05176 -122.951748)
			(xy 28.052415 -122.926753) (xy 28.062211 -122.87773) (xy 28.081379 -122.831559) (xy 28.109183 -122.790012)
			(xy 28.126436 -122.771916) (xy 30.748732 -120.14962) (xy 30.766823 -120.132359) (xy 30.808369 -120.104549)
			(xy 30.854542 -120.085377) (xy 30.903567 -120.07558) (xy 30.928564 -120.074944) (xy 39.882572 -120.074944)
			(xy 39.907568 -120.075591) (xy 39.95659 -120.085391) (xy 40.002761 -120.104561) (xy 40.044308 -120.132366)
			(xy 40.062404 -120.14962) (xy 44.63161 -124.718826) (xy 44.648852 -124.736918) (xy 44.676591 -124.778483)
			(xy 44.695694 -124.824658) (xy 44.705426 -124.873672) (xy 44.706032 -124.898658) (xy 44.706032 -127.619506)
			(xy 46.656496 -127.619506) (xy 46.660567 -127.563884) (xy 46.672693 -127.509447) (xy 46.692616 -127.457356)
			(xy 46.719912 -127.408721) (xy 46.753998 -127.364578) (xy 46.794147 -127.325869) (xy 46.839505 -127.293418)
			(xy 46.889105 -127.267917) (xy 46.941889 -127.24991) (xy 46.996732 -127.23978) (xy 47.052466 -127.237743)
			(xy 47.107903 -127.243843) (xy 47.16186 -127.257949) (xy 47.213189 -127.279761) (xy 47.260795 -127.308815)
			(xy 47.303663 -127.34449) (xy 47.34088 -127.386027) (xy 47.371653 -127.43254) (xy 47.395325 -127.483037)
			(xy 47.411393 -127.536444) (xy 47.419513 -127.59162) (xy 47.420022 -127.619506) (xy 47.419513 -127.647392)
			(xy 47.411393 -127.702568) (xy 47.395325 -127.755975) (xy 47.371653 -127.806472) (xy 47.34088 -127.852985)
			(xy 47.303663 -127.894522) (xy 47.260795 -127.930197) (xy 47.213189 -127.959251) (xy 47.16186 -127.981063)
			(xy 47.107903 -127.995169) (xy 47.052466 -128.001269) (xy 46.996732 -127.999232) (xy 46.941889 -127.989102)
			(xy 46.889105 -127.971095) (xy 46.839505 -127.945594) (xy 46.794147 -127.913143) (xy 46.753998 -127.874434)
			(xy 46.719912 -127.830291) (xy 46.692616 -127.781656) (xy 46.672693 -127.729565) (xy 46.660567 -127.675128)
			(xy 46.656496 -127.619506) (xy 44.706032 -127.619506) (xy 44.706032 -138.30681) (xy 44.705413 -138.331793)
			(xy 44.695673 -138.380801) (xy 44.676568 -138.426971) (xy 44.648831 -138.468532) (xy 44.63161 -138.486642)
			(xy 38.870128 -144.248378) (xy 38.870128 -146.75866) (xy 43.126914 -146.75866) (xy 43.127436 -146.729921)
			(xy 43.136063 -146.673095) (xy 43.153114 -146.618205) (xy 43.178206 -146.566493) (xy 43.210769 -146.51913)
			(xy 43.230038 -146.497802) (xy 43.240134 -146.486238) (xy 43.253567 -146.458655) (xy 43.258189 -146.428324)
			(xy 43.253582 -146.397991) (xy 43.240162 -146.370401) (xy 43.230038 -146.358864) (xy 43.21077 -146.337534)
			(xy 43.178203 -146.290173) (xy 43.15311 -146.238462) (xy 43.136059 -146.183572) (xy 43.127435 -146.126745)
			(xy 43.126914 -146.098006) (xy 43.12738 -146.070636) (xy 43.135197 -146.016457) (xy 43.150686 -145.963953)
			(xy 43.173528 -145.914206) (xy 43.203253 -145.86824) (xy 43.220894 -145.847308) (xy 43.230126 -145.835977)
			(xy 43.242304 -145.80942) (xy 43.246478 -145.780505) (xy 43.242307 -145.751588) (xy 43.23013 -145.725031)
			(xy 43.220894 -145.713704) (xy 43.203242 -145.692782) (xy 43.173533 -145.646806) (xy 43.150699 -145.597056)
			(xy 43.135211 -145.544553) (xy 43.127386 -145.490376) (xy 43.126914 -145.463006) (xy 43.127361 -145.435752)
			(xy 43.135118 -145.3818) (xy 43.150474 -145.3295) (xy 43.173117 -145.279919) (xy 43.202587 -145.234064)
			(xy 43.238282 -145.192871) (xy 43.279477 -145.157177) (xy 43.325333 -145.12771) (xy 43.374915 -145.105068)
			(xy 43.427215 -145.089714) (xy 43.481168 -145.08196) (xy 43.508422 -145.081498) (xy 43.535793 -145.081952)
			(xy 43.589972 -145.089773) (xy 43.642476 -145.105265) (xy 43.692222 -145.128109) (xy 43.738189 -145.157836)
			(xy 43.75912 -145.175478) (xy 43.770448 -145.184714) (xy 43.797005 -145.19689) (xy 43.825922 -145.201063)
			(xy 43.854839 -145.19689) (xy 43.881396 -145.184714) (xy 43.892724 -145.175478) (xy 43.913671 -145.157858)
			(xy 43.95964 -145.128144) (xy 44.009384 -145.105305) (xy 44.061881 -145.089809) (xy 44.116054 -145.081975)
			(xy 44.143422 -145.081498) (xy 44.172161 -145.082009) (xy 44.228989 -145.090635) (xy 44.28388 -145.107688)
			(xy 44.335592 -145.132782) (xy 44.382954 -145.16535) (xy 44.40428 -145.184622) (xy 44.415814 -145.194694)
			(xy 44.44336 -145.208036) (xy 44.473622 -145.212621) (xy 44.503884 -145.208036) (xy 44.53143 -145.194694)
			(xy 44.542964 -145.184622) (xy 44.564291 -145.165352) (xy 44.611654 -145.132787) (xy 44.663365 -145.107696)
			(xy 44.718256 -145.090646) (xy 44.775083 -145.082024) (xy 44.832561 -145.082024) (xy 44.889388 -145.090646)
			(xy 44.944279 -145.107696) (xy 44.99599 -145.132787) (xy 45.043353 -145.165352) (xy 45.06468 -145.184622)
			(xy 45.076214 -145.194694) (xy 45.10376 -145.208036) (xy 45.134022 -145.212621) (xy 45.164284 -145.208036)
			(xy 45.19183 -145.194694) (xy 45.203364 -145.184622) (xy 45.224691 -145.165352) (xy 45.272054 -145.132787)
			(xy 45.323765 -145.107696) (xy 45.378656 -145.090646) (xy 45.435483 -145.082024) (xy 45.492961 -145.082024)
			(xy 45.549788 -145.090646) (xy 45.604679 -145.107696) (xy 45.65639 -145.132787) (xy 45.703753 -145.165352)
			(xy 45.72508 -145.184622) (xy 45.736614 -145.194694) (xy 45.76416 -145.208036) (xy 45.794422 -145.212621)
			(xy 45.824684 -145.208036) (xy 45.85223 -145.194694) (xy 45.863764 -145.184622) (xy 45.885091 -145.165352)
			(xy 45.932454 -145.132787) (xy 45.984165 -145.107696) (xy 46.039056 -145.090646) (xy 46.095883 -145.082024)
			(xy 46.153361 -145.082024) (xy 46.210188 -145.090646) (xy 46.265079 -145.107696) (xy 46.31679 -145.132787)
			(xy 46.364153 -145.165352) (xy 46.38548 -145.184622) (xy 46.397014 -145.194694) (xy 46.42456 -145.208036)
			(xy 46.454822 -145.212621) (xy 46.485084 -145.208036) (xy 46.51263 -145.194694) (xy 46.524164 -145.184622)
			(xy 46.545491 -145.165352) (xy 46.592854 -145.132787) (xy 46.644565 -145.107696) (xy 46.699456 -145.090646)
			(xy 46.756283 -145.082024) (xy 46.813761 -145.082024) (xy 46.870588 -145.090646) (xy 46.925479 -145.107696)
			(xy 46.97719 -145.132787) (xy 47.024553 -145.165352) (xy 47.04588 -145.184622) (xy 47.057414 -145.194694)
			(xy 47.08496 -145.208036) (xy 47.115222 -145.212621) (xy 47.145484 -145.208036) (xy 47.17303 -145.194694)
			(xy 47.184564 -145.184622) (xy 47.20588 -145.165338) (xy 47.253245 -145.132774) (xy 47.30496 -145.107685)
			(xy 47.359853 -145.090637) (xy 47.416682 -145.082017) (xy 47.445422 -145.081498) (xy 47.472674 -145.081957)
			(xy 47.526623 -145.089717) (xy 47.578919 -145.105075) (xy 47.628496 -145.127719) (xy 47.674347 -145.157189)
			(xy 47.715537 -145.192883) (xy 47.751228 -145.234076) (xy 47.780694 -145.279928) (xy 47.803335 -145.329508)
			(xy 47.818689 -145.381804) (xy 47.826445 -145.435754) (xy 47.82693 -145.463006) (xy 47.826467 -145.489242)
			(xy 47.819271 -145.541217) (xy 47.805017 -145.591715) (xy 47.783973 -145.639781) (xy 47.756538 -145.684508)
			(xy 47.723228 -145.725051) (xy 47.704248 -145.743168) (xy 47.696871 -145.750692) (xy 47.688442 -145.769979)
			(xy 47.688444 -145.791029) (xy 47.696876 -145.810315) (xy 47.704248 -145.817844) (xy 47.725584 -145.83918)
			(xy 47.733113 -145.846552) (xy 47.752398 -145.854983) (xy 47.773446 -145.854983) (xy 47.792731 -145.846552)
			(xy 47.80026 -145.83918) (xy 47.818371 -145.820192) (xy 47.858911 -145.786874) (xy 47.903638 -145.759432)
			(xy 47.951706 -145.738384) (xy 48.002206 -145.724128) (xy 48.054185 -145.716934) (xy 48.080422 -145.716498)
			(xy 48.107674 -145.716957) (xy 48.161623 -145.724717) (xy 48.213919 -145.740075) (xy 48.263496 -145.762719)
			(xy 48.309347 -145.792189) (xy 48.350537 -145.827883) (xy 48.386228 -145.869076) (xy 48.400993 -145.892052)
			(xy 49.996289 -145.892052) (xy 49.996289 -145.837548) (xy 50.004047 -145.783598) (xy 50.019404 -145.731301)
			(xy 50.042047 -145.681722) (xy 50.071517 -145.635871) (xy 50.107212 -145.594681) (xy 50.148406 -145.55899)
			(xy 50.194261 -145.529526) (xy 50.243842 -145.506888) (xy 50.296141 -145.491537) (xy 50.350092 -145.483786)
			(xy 50.377344 -145.483326) (xy 50.407031 -145.483911) (xy 50.465689 -145.493102) (xy 50.522215 -145.511271)
			(xy 50.575243 -145.537978) (xy 50.623492 -145.57258) (xy 50.665798 -145.614239) (xy 50.683922 -145.637758)
			(xy 50.692348 -145.648365) (xy 50.713661 -145.665072) (xy 50.738615 -145.675591) (xy 50.765456 -145.679181)
			(xy 50.792297 -145.675591) (xy 50.817251 -145.665072) (xy 50.838564 -145.648365) (xy 50.84699 -145.637758)
			(xy 50.86512 -145.614243) (xy 50.907427 -145.572585) (xy 50.955675 -145.537982) (xy 51.008701 -145.511271)
			(xy 51.065225 -145.493095) (xy 51.123881 -145.483893) (xy 51.153568 -145.483326) (xy 51.180825 -145.483719)
			(xy 51.234784 -145.491473) (xy 51.28709 -145.506827) (xy 51.336679 -145.52947) (xy 51.38254 -145.55894)
			(xy 51.423741 -145.594637) (xy 51.459441 -145.635834) (xy 51.488915 -145.681693) (xy 51.511561 -145.73128)
			(xy 51.52692 -145.783585) (xy 51.534679 -145.837543) (xy 51.534679 -145.892057) (xy 51.52692 -145.946015)
			(xy 51.511561 -145.99832) (xy 51.488915 -146.047907) (xy 51.459441 -146.093766) (xy 51.423741 -146.134963)
			(xy 51.38254 -146.17066) (xy 51.336679 -146.20013) (xy 51.28709 -146.222773) (xy 51.234784 -146.238127)
			(xy 51.180825 -146.245881) (xy 51.153568 -146.246342) (xy 51.123881 -146.24576) (xy 51.065222 -146.23657)
			(xy 51.008695 -146.218402) (xy 50.955667 -146.191694) (xy 50.907418 -146.157091) (xy 50.865114 -146.11543)
			(xy 50.84699 -146.09191) (xy 50.838564 -146.081303) (xy 50.817251 -146.064596) (xy 50.792297 -146.054077)
			(xy 50.765456 -146.050487) (xy 50.738615 -146.054077) (xy 50.713661 -146.064596) (xy 50.692348 -146.081303)
			(xy 50.683922 -146.09191) (xy 50.665776 -146.115412) (xy 50.623474 -146.157073) (xy 50.575229 -146.191678)
			(xy 50.522206 -146.218392) (xy 50.465685 -146.23657) (xy 50.40703 -146.245774) (xy 50.377344 -146.246342)
			(xy 50.350092 -146.245814) (xy 50.296141 -146.238063) (xy 50.243842 -146.222712) (xy 50.194261 -146.200074)
			(xy 50.148406 -146.17061) (xy 50.107212 -146.134919) (xy 50.071517 -146.093729) (xy 50.042047 -146.047878)
			(xy 50.019404 -145.998299) (xy 50.004047 -145.946002) (xy 49.996289 -145.892052) (xy 48.400993 -145.892052)
			(xy 48.415694 -145.914928) (xy 48.438335 -145.964508) (xy 48.453689 -146.016804) (xy 48.461445 -146.070754)
			(xy 48.46193 -146.098006) (xy 48.461402 -146.126745) (xy 48.452779 -146.183571) (xy 48.43573 -146.238462)
			(xy 48.410639 -146.290174) (xy 48.378076 -146.337537) (xy 48.358806 -146.358864) (xy 48.348699 -146.3704)
			(xy 48.335361 -146.398008) (xy 48.330783 -146.428324) (xy 48.335375 -146.458639) (xy 48.348727 -146.48624)
			(xy 48.358806 -146.497802) (xy 48.378048 -146.519154) (xy 48.41062 -146.566508) (xy 48.435719 -146.618213)
			(xy 48.452776 -146.673099) (xy 48.461405 -146.729923) (xy 48.46193 -146.75866) (xy 48.461408 -146.785911)
			(xy 48.453657 -146.839859) (xy 48.438307 -146.892154) (xy 48.415671 -146.941732) (xy 48.386209 -146.987585)
			(xy 48.350521 -147.028777) (xy 48.309334 -147.064472) (xy 48.263487 -147.093941) (xy 48.213912 -147.116585)
			(xy 48.161619 -147.131943) (xy 48.107673 -147.139703) (xy 48.080422 -147.140168) (xy 48.053052 -147.139697)
			(xy 47.998873 -147.131881) (xy 47.946369 -147.116394) (xy 47.896622 -147.093553) (xy 47.850656 -147.063829)
			(xy 47.829724 -147.046188) (xy 47.818396 -147.036952) (xy 47.791839 -147.024776) (xy 47.762922 -147.020603)
			(xy 47.734005 -147.024776) (xy 47.707448 -147.036952) (xy 47.69612 -147.046188) (xy 47.67519 -147.063829)
			(xy 47.629217 -147.093541) (xy 47.579469 -147.116377) (xy 47.526968 -147.131867) (xy 47.472791 -147.139695)
			(xy 47.445422 -147.140168) (xy 47.416685 -147.139613) (xy 47.359859 -147.130995) (xy 47.30497 -147.113951)
			(xy 47.253257 -147.088867) (xy 47.205893 -147.05631) (xy 47.184564 -147.037044) (xy 47.17303 -147.026972)
			(xy 47.145484 -147.01363) (xy 47.115222 -147.009045) (xy 47.08496 -147.01363) (xy 47.057414 -147.026972)
			(xy 47.04588 -147.037044) (xy 47.024553 -147.056314) (xy 46.97719 -147.088879) (xy 46.925479 -147.11397)
			(xy 46.870588 -147.13102) (xy 46.813761 -147.139642) (xy 46.756283 -147.139642) (xy 46.699456 -147.13102)
			(xy 46.644565 -147.11397) (xy 46.592854 -147.088879) (xy 46.545491 -147.056314) (xy 46.524164 -147.037044)
			(xy 46.51263 -147.026972) (xy 46.485084 -147.01363) (xy 46.454822 -147.009045) (xy 46.42456 -147.01363)
			(xy 46.397014 -147.026972) (xy 46.38548 -147.037044) (xy 46.364153 -147.056314) (xy 46.31679 -147.088879)
			(xy 46.265079 -147.11397) (xy 46.210188 -147.13102) (xy 46.153361 -147.139642) (xy 46.095883 -147.139642)
			(xy 46.039056 -147.13102) (xy 45.984165 -147.11397) (xy 45.932454 -147.088879) (xy 45.885091 -147.056314)
			(xy 45.863764 -147.037044) (xy 45.85223 -147.026972) (xy 45.824684 -147.01363) (xy 45.794422 -147.009045)
			(xy 45.76416 -147.01363) (xy 45.736614 -147.026972) (xy 45.72508 -147.037044) (xy 45.703753 -147.056314)
			(xy 45.65639 -147.088879) (xy 45.604679 -147.11397) (xy 45.549788 -147.13102) (xy 45.492961 -147.139642)
			(xy 45.435483 -147.139642) (xy 45.378656 -147.13102) (xy 45.323765 -147.11397) (xy 45.272054 -147.088879)
			(xy 45.224691 -147.056314) (xy 45.203364 -147.037044) (xy 45.19183 -147.026972) (xy 45.164284 -147.01363)
			(xy 45.134022 -147.009045) (xy 45.10376 -147.01363) (xy 45.076214 -147.026972) (xy 45.06468 -147.037044)
			(xy 45.043353 -147.056314) (xy 44.99599 -147.088879) (xy 44.944279 -147.11397) (xy 44.889388 -147.13102)
			(xy 44.832561 -147.139642) (xy 44.775083 -147.139642) (xy 44.718256 -147.13102) (xy 44.663365 -147.11397)
			(xy 44.611654 -147.088879) (xy 44.564291 -147.056314) (xy 44.542964 -147.037044) (xy 44.53143 -147.026972)
			(xy 44.503884 -147.01363) (xy 44.473622 -147.009045) (xy 44.44336 -147.01363) (xy 44.415814 -147.026972)
			(xy 44.40428 -147.037044) (xy 44.382941 -147.056301) (xy 44.335583 -147.08887) (xy 44.283874 -147.113965)
			(xy 44.228986 -147.131019) (xy 44.17216 -147.139645) (xy 44.143422 -147.140168) (xy 44.116052 -147.139697)
			(xy 44.061873 -147.131881) (xy 44.009369 -147.116394) (xy 43.959622 -147.093553) (xy 43.913656 -147.063829)
			(xy 43.892724 -147.046188) (xy 43.881396 -147.036952) (xy 43.854839 -147.024776) (xy 43.825922 -147.020603)
			(xy 43.797005 -147.024776) (xy 43.770448 -147.036952) (xy 43.75912 -147.046188) (xy 43.73819 -147.063829)
			(xy 43.692217 -147.093541) (xy 43.642469 -147.116377) (xy 43.589968 -147.131867) (xy 43.535791 -147.139695)
			(xy 43.508422 -147.140168) (xy 43.481168 -147.139724) (xy 43.427214 -147.131969) (xy 43.374914 -147.116614)
			(xy 43.325331 -147.093971) (xy 43.279476 -147.064502) (xy 43.238282 -147.028806) (xy 43.202588 -146.98761)
			(xy 43.17312 -146.941753) (xy 43.15048 -146.89217) (xy 43.135127 -146.839868) (xy 43.127375 -146.785914)
			(xy 43.126914 -146.75866) (xy 38.870128 -146.75866) (xy 38.870128 -146.915124) (xy 40.669464 -148.71446)
			(xy 49.797716 -148.71446) (xy 50.305462 -148.206968) (xy 50.286877 -148.185776) (xy 50.255494 -148.138958)
			(xy 50.23134 -148.088032) (xy 50.21494 -148.034107) (xy 50.206652 -147.978356) (xy 50.206148 -147.950174)
			(xy 50.206653 -147.922924) (xy 50.214412 -147.868979) (xy 50.229769 -147.816688) (xy 50.25241 -147.767113)
			(xy 50.281874 -147.721265) (xy 50.317564 -147.680076) (xy 50.358751 -147.644385) (xy 50.404597 -147.614918)
			(xy 50.454171 -147.592275) (xy 50.506462 -147.576916) (xy 50.560406 -147.569155) (xy 50.587656 -147.568666)
			(xy 50.58791 -147.568666) (xy 50.617749 -147.569247) (xy 50.676695 -147.578559) (xy 50.705258 -147.587208)
			(xy 50.719167 -147.591239) (xy 50.748099 -147.592148) (xy 50.776118 -147.584883) (xy 50.800963 -147.570032)
			(xy 50.820629 -147.548792) (xy 50.833527 -147.522879) (xy 50.836576 -147.508722) (xy 50.843165 -147.475884)
			(xy 50.866284 -147.413031) (xy 50.88255 -147.383754) (xy 50.889618 -147.370804) (xy 50.896647 -147.342161)
			(xy 50.895197 -147.312704) (xy 50.885389 -147.28489) (xy 50.868042 -147.261039) (xy 50.844601 -147.243141)
			(xy 50.830988 -147.23745) (xy 50.80422 -147.226735) (xy 50.753979 -147.19845) (xy 50.70857 -147.162922)
			(xy 50.669027 -147.120963) (xy 50.636253 -147.073528) (xy 50.610993 -147.0217) (xy 50.593825 -146.96666)
			(xy 50.585139 -146.909662) (xy 50.584608 -146.880834) (xy 50.585094 -146.853583) (xy 50.59285 -146.799635)
			(xy 50.608205 -146.74734) (xy 50.630847 -146.697763) (xy 50.660313 -146.651913) (xy 50.696004 -146.610722)
			(xy 50.737195 -146.575031) (xy 50.783045 -146.545565) (xy 50.832622 -146.522923) (xy 50.884917 -146.507568)
			(xy 50.938865 -146.499812) (xy 50.993367 -146.499812) (xy 51.047315 -146.507568) (xy 51.09961 -146.522923)
			(xy 51.149187 -146.545565) (xy 51.195037 -146.575031) (xy 51.236228 -146.610722) (xy 51.271919 -146.651913)
			(xy 51.301385 -146.697763) (xy 51.324027 -146.74734) (xy 51.339382 -146.799635) (xy 51.347138 -146.853583)
			(xy 51.347624 -146.880834) (xy 51.347624 -146.881088) (xy 51.347224 -146.906292) (xy 51.340585 -146.95626)
			(xy 51.327409 -147.004914) (xy 51.307926 -147.051404) (xy 51.295554 -147.073366) (xy 51.28846 -147.086303)
			(xy 51.281434 -147.114951) (xy 51.282888 -147.144412) (xy 51.292701 -147.172229) (xy 51.310054 -147.196081)
			(xy 51.3335 -147.21398) (xy 51.347116 -147.21967) (xy 51.373892 -147.230366) (xy 51.424134 -147.258654)
			(xy 51.469543 -147.294184) (xy 51.509085 -147.336146) (xy 51.541859 -147.383583) (xy 51.567117 -147.435414)
			(xy 51.584283 -147.490457) (xy 51.592966 -147.547457) (xy 51.593496 -147.576286) (xy 51.593032 -147.603539)
			(xy 51.585276 -147.657491) (xy 51.569921 -147.709789) (xy 51.54728 -147.75937) (xy 51.517812 -147.805224)
			(xy 51.482118 -147.846417) (xy 51.440925 -147.882111) (xy 51.395072 -147.911579) (xy 51.345491 -147.934221)
			(xy 51.293193 -147.949576) (xy 51.239241 -147.957331) (xy 51.211988 -147.957794) (xy 51.211734 -147.957794)
			(xy 51.181895 -147.957227) (xy 51.122949 -147.947906) (xy 51.094386 -147.939252) (xy 51.080457 -147.935302)
			(xy 51.051539 -147.934385) (xy 51.02353 -147.941636) (xy 50.998691 -147.956471) (xy 50.979026 -147.977693)
			(xy 50.966122 -148.003589) (xy 50.963068 -148.017738) (xy 50.957407 -148.046251) (xy 50.938564 -148.101243)
			(xy 50.911588 -148.152735) (xy 50.877105 -148.199533) (xy 50.856896 -148.22043) (xy 50.842164 -148.235162)
			(xy 50.842164 -148.284438) (xy 50.841494 -148.309432) (xy 50.831701 -148.358454) (xy 50.812537 -148.404624)
			(xy 50.784739 -148.446172) (xy 50.767488 -148.46427) (xy 50.082958 -149.1488) (xy 50.064874 -149.166069)
			(xy 50.023325 -149.193877) (xy 49.97715 -149.213046) (xy 49.928123 -149.222841) (xy 49.903126 -149.223476)
			(xy 40.564054 -149.223476) (xy 40.53906 -149.222807) (xy 40.490039 -149.213013) (xy 40.443868 -149.193849)
			(xy 40.40232 -149.166051) (xy 40.384222 -149.1488) (xy 38.435788 -147.200366) (xy 38.418521 -147.18228)
			(xy 38.390713 -147.140732) (xy 38.371543 -147.094558) (xy 38.361747 -147.045531) (xy 38.361112 -147.020534)
			(xy 38.361112 -144.142968) (xy 38.361732 -144.117971) (xy 38.371542 -144.068948) (xy 38.39072 -144.022778)
			(xy 38.418532 -143.981232) (xy 38.435788 -143.963136) (xy 44.197524 -138.2014) (xy 44.197524 -125.004068)
			(xy 39.777162 -120.58396) (xy 31.033974 -120.58396) (xy 28.560776 -123.057158) (xy 28.560776 -123.200414)
			(xy 29.125416 -123.200414) (xy 29.129487 -123.144792) (xy 29.141613 -123.090355) (xy 29.161536 -123.038264)
			(xy 29.188832 -122.989629) (xy 29.222918 -122.945486) (xy 29.263067 -122.906777) (xy 29.308425 -122.874326)
			(xy 29.358025 -122.848825) (xy 29.410809 -122.830818) (xy 29.465652 -122.820688) (xy 29.521386 -122.818651)
			(xy 29.576823 -122.824751) (xy 29.63078 -122.838857) (xy 29.682109 -122.860669) (xy 29.729715 -122.889723)
			(xy 29.772583 -122.925398) (xy 29.8098 -122.966935) (xy 29.840573 -123.013448) (xy 29.864245 -123.063945)
			(xy 29.880313 -123.117352) (xy 29.888433 -123.172528) (xy 29.888942 -123.200414) (xy 29.888433 -123.2283)
			(xy 29.880313 -123.283476) (xy 29.864245 -123.336883) (xy 29.840573 -123.38738) (xy 29.8098 -123.433893)
			(xy 29.772583 -123.47543) (xy 29.729715 -123.511105) (xy 29.682109 -123.540159) (xy 29.63078 -123.561971)
			(xy 29.576823 -123.576077) (xy 29.521386 -123.582177) (xy 29.465652 -123.58014) (xy 29.410809 -123.57001)
			(xy 29.358025 -123.552003) (xy 29.308425 -123.526502) (xy 29.263067 -123.494051) (xy 29.222918 -123.455342)
			(xy 29.188832 -123.411199) (xy 29.161536 -123.362564) (xy 29.141613 -123.310473) (xy 29.129487 -123.256036)
			(xy 29.125416 -123.200414) (xy 28.560776 -123.200414) (xy 28.560776 -124.015246) (xy 30.589728 -124.015246)
			(xy 30.589728 -122.22353) (xy 30.590322 -122.198546) (xy 30.600072 -122.149537) (xy 30.619184 -122.103368)
			(xy 30.646927 -122.061808) (xy 30.66415 -122.043698) (xy 31.796228 -120.91162) (xy 31.814321 -120.894361)
			(xy 31.855866 -120.866551) (xy 31.902038 -120.847378) (xy 31.951063 -120.83758) (xy 31.97606 -120.836944)
			(xy 39.56685 -120.836944) (xy 39.591845 -120.837604) (xy 39.640867 -120.8474) (xy 39.687038 -120.866566)
			(xy 39.728585 -120.894368) (xy 39.746682 -120.91162) (xy 43.86961 -125.034548) (xy 43.886815 -125.052673)
			(xy 43.914561 -125.094227) (xy 43.933674 -125.140392) (xy 43.943419 -125.189397) (xy 43.944032 -125.21438)
			(xy 43.944032 -137.92581) (xy 43.943413 -137.950793) (xy 43.933673 -137.999801) (xy 43.914568 -138.045971)
			(xy 43.886831 -138.087532) (xy 43.86961 -138.105642) (xy 37.986208 -143.989298) (xy 37.986208 -150.44547)
			(xy 50.99304 -150.44547) (xy 50.993427 -150.418214) (xy 51.001189 -150.364258) (xy 51.016552 -150.311956)
			(xy 51.039201 -150.262372) (xy 51.068677 -150.216517) (xy 51.104379 -150.175323) (xy 51.145579 -150.13963)
			(xy 51.191441 -150.110164) (xy 51.241029 -150.087524) (xy 51.293334 -150.072173) (xy 51.347292 -150.064422)
			(xy 51.374548 -150.063962) (xy 51.402122 -150.064442) (xy 51.456695 -150.072388) (xy 51.509556 -150.088109)
			(xy 51.559603 -150.111276) (xy 51.605792 -150.141408) (xy 51.647163 -150.177875) (xy 51.665378 -150.198582)
			(xy 51.675276 -150.20948) (xy 51.699926 -150.225555) (xy 51.728134 -150.233939) (xy 51.757562 -150.233939)
			(xy 51.78577 -150.225555) (xy 51.81042 -150.20948) (xy 51.820318 -150.198582) (xy 51.838512 -150.177855)
			(xy 51.879885 -150.141387) (xy 51.926079 -150.111257) (xy 51.97613 -150.088094) (xy 52.028995 -150.072381)
			(xy 52.083572 -150.064445) (xy 52.111148 -150.063962) (xy 52.137649 -150.064415) (xy 52.19014 -150.071762)
			(xy 52.241107 -150.086307) (xy 52.289569 -150.10777) (xy 52.334592 -150.135737) (xy 52.355242 -150.152354)
			(xy 52.367396 -150.161784) (xy 52.395794 -150.173573) (xy 52.426411 -150.176397) (xy 52.456486 -150.170003)
			(xy 52.483306 -150.154967) (xy 52.504451 -150.132645) (xy 52.511706 -150.11908) (xy 52.523817 -150.095395)
			(xy 52.553737 -150.051413) (xy 52.589605 -150.01213) (xy 52.630693 -149.978345) (xy 52.653184 -149.96414)
			(xy 52.665431 -149.956248) (xy 52.685104 -149.934769) (xy 52.697907 -149.908607) (xy 52.702796 -149.879894)
			(xy 52.699373 -149.850969) (xy 52.694078 -149.837394) (xy 52.684593 -149.814182) (xy 52.671241 -149.76585)
			(xy 52.664511 -149.716161) (xy 52.664106 -149.69109) (xy 52.66454 -149.666021) (xy 52.671286 -149.616338)
			(xy 52.684614 -149.568004) (xy 52.694078 -149.544786) (xy 52.699333 -149.531207) (xy 52.702713 -149.502299)
			(xy 52.697811 -149.47361) (xy 52.685024 -149.447464) (xy 52.665389 -149.42598) (xy 52.653184 -149.41804)
			(xy 52.630024 -149.403514) (xy 52.587899 -149.368668) (xy 52.551317 -149.328041) (xy 52.521063 -149.282506)
			(xy 52.497786 -149.233039) (xy 52.481986 -149.180703) (xy 52.474001 -149.126619) (xy 52.474003 -149.07195)
			(xy 52.481993 -149.017867) (xy 52.497797 -148.965532) (xy 52.521079 -148.916067) (xy 52.551336 -148.870534)
			(xy 52.587922 -148.829911) (xy 52.630049 -148.795068) (xy 52.653184 -148.7805) (xy 52.66539 -148.772551)
			(xy 52.685063 -148.751088) (xy 52.697871 -148.724941) (xy 52.702771 -148.696241) (xy 52.699363 -148.667326)
			(xy 52.694078 -148.653754) (xy 52.684581 -148.630547) (xy 52.671233 -148.582213) (xy 52.664508 -148.532522)
			(xy 52.664106 -148.50745) (xy 52.664627 -148.479565) (xy 52.672939 -148.424418) (xy 52.689377 -148.371126)
			(xy 52.713575 -148.32088) (xy 52.744991 -148.274801) (xy 52.782924 -148.233919) (xy 52.826526 -148.199147)
			(xy 52.874824 -148.171262) (xy 52.926739 -148.150887) (xy 52.98111 -148.138477) (xy 53.036724 -148.13431)
			(xy 53.092338 -148.138477) (xy 53.146709 -148.150887) (xy 53.198624 -148.171262) (xy 53.246922 -148.199147)
			(xy 53.290524 -148.233919) (xy 53.328457 -148.274801) (xy 53.359873 -148.32088) (xy 53.384071 -148.371126)
			(xy 53.400509 -148.424418) (xy 53.408821 -148.479565) (xy 53.409342 -148.50745) (xy 53.408875 -148.534782)
			(xy 53.400906 -148.588863) (xy 53.385118 -148.641198) (xy 53.36185 -148.690662) (xy 53.331601 -148.736195)
			(xy 53.295022 -148.776817) (xy 53.252897 -148.811655) (xy 53.229764 -148.82622) (xy 53.217537 -148.834138)
			(xy 53.19787 -148.855612) (xy 53.185068 -148.881767) (xy 53.180173 -148.910472) (xy 53.183584 -148.939392)
			(xy 53.18887 -148.952966) (xy 53.198345 -148.976181) (xy 53.211701 -149.024512) (xy 53.218435 -149.074199)
			(xy 53.218842 -149.09927) (xy 53.218431 -149.12434) (xy 53.211677 -149.174023) (xy 53.198339 -149.222357)
			(xy 53.18887 -149.245574) (xy 53.183624 -149.259151) (xy 53.180262 -149.288051) (xy 53.185173 -149.316729)
			(xy 53.197961 -149.342863) (xy 53.217591 -149.364338) (xy 53.229764 -149.37232) (xy 53.252885 -149.386903)
			(xy 53.295003 -149.421747) (xy 53.331579 -149.462369) (xy 53.361829 -149.507898) (xy 53.385103 -149.557358)
			(xy 53.400902 -149.609688) (xy 53.408888 -149.663764) (xy 53.408889 -149.718426) (xy 53.400905 -149.772502)
			(xy 53.385107 -149.824832) (xy 53.361834 -149.874292) (xy 53.331585 -149.919823) (xy 53.29501 -149.960446)
			(xy 53.252893 -149.995291) (xy 53.229764 -150.00986) (xy 53.217509 -150.017739) (xy 53.197842 -150.039225)
			(xy 53.185043 -150.06539) (xy 53.180156 -150.094104) (xy 53.183577 -150.12303) (xy 53.18887 -150.136606)
			(xy 53.198357 -150.159817) (xy 53.211708 -150.208149) (xy 53.218438 -150.257838) (xy 53.218842 -150.28291)
			(xy 53.21837 -150.309752) (xy 53.210665 -150.362881) (xy 53.195416 -150.414354) (xy 53.172938 -150.463106)
			(xy 53.143697 -150.508127) (xy 53.108298 -150.548487) (xy 53.067473 -150.583349) (xy 53.022069 -150.611993)
			(xy 52.973024 -150.633824) (xy 52.947316 -150.641558) (xy 52.932841 -150.646276) (xy 52.907286 -150.662788)
			(xy 52.887726 -150.686092) (xy 52.875894 -150.714122) (xy 52.87284 -150.744393) (xy 52.878835 -150.774222)
			(xy 52.885594 -150.787862) (xy 52.900228 -150.816008) (xy 52.920955 -150.875959) (xy 52.931453 -150.938517)
			(xy 52.932076 -150.970234) (xy 52.931855 -150.988253) (xy 52.928421 -151.024128) (xy 52.925218 -151.041862)
			(xy 52.922936 -151.057077) (xy 52.926453 -151.087622) (xy 52.938901 -151.115736) (xy 52.959153 -151.138871)
			(xy 52.985373 -151.154931) (xy 53.000148 -151.15921) (xy 53.027191 -151.166611) (xy 53.078917 -151.188241)
			(xy 53.126922 -151.217205) (xy 53.170174 -151.25288) (xy 53.207741 -151.294499) (xy 53.238815 -151.341165)
			(xy 53.262728 -151.391876) (xy 53.278965 -151.44554) (xy 53.287177 -151.501001) (xy 53.287676 -151.529034)
			(xy 53.287254 -151.556288) (xy 53.279492 -151.610239) (xy 53.264131 -151.662537) (xy 53.241483 -151.712117)
			(xy 53.21201 -151.757968) (xy 53.176312 -151.799159) (xy 53.135115 -151.83485) (xy 53.089259 -151.864315)
			(xy 53.039675 -151.886954) (xy 52.987375 -151.902306) (xy 52.933422 -151.910058) (xy 52.906168 -151.910542)
			(xy 52.878594 -151.91005) (xy 52.824022 -151.902105) (xy 52.771161 -151.886387) (xy 52.721115 -151.863222)
			(xy 52.674925 -151.833093) (xy 52.633554 -151.796628) (xy 52.615338 -151.775922) (xy 52.60544 -151.765024)
			(xy 52.58079 -151.748949) (xy 52.552582 -151.740565) (xy 52.523154 -151.740565) (xy 52.494946 -151.748949)
			(xy 52.470296 -151.765024) (xy 52.460398 -151.775922) (xy 52.442183 -151.796628) (xy 52.400812 -151.833093)
			(xy 52.354622 -151.86322) (xy 52.304575 -151.886383) (xy 52.251714 -151.902099) (xy 52.197142 -151.910039)
			(xy 52.141994 -151.910039) (xy 52.087422 -151.902099) (xy 52.034561 -151.886383) (xy 51.984514 -151.86322)
			(xy 51.938324 -151.833093) (xy 51.896953 -151.796628) (xy 51.878738 -151.775922) (xy 51.86884 -151.765024)
			(xy 51.84419 -151.748949) (xy 51.815982 -151.740565) (xy 51.786554 -151.740565) (xy 51.758346 -151.748949)
			(xy 51.733696 -151.765024) (xy 51.723798 -151.775922) (xy 51.705596 -151.796642) (xy 51.664225 -151.83311)
			(xy 51.618033 -151.863241) (xy 51.567983 -151.886405) (xy 51.515119 -151.90212) (xy 51.460543 -151.910058)
			(xy 51.432968 -151.910542) (xy 51.405718 -151.910052) (xy 51.351772 -151.902292) (xy 51.299479 -151.886935)
			(xy 51.249904 -151.864292) (xy 51.204055 -151.834826) (xy 51.162866 -151.799135) (xy 51.127175 -151.757946)
			(xy 51.097709 -151.712098) (xy 51.075066 -151.662523) (xy 51.059708 -151.61023) (xy 51.051948 -151.556284)
			(xy 51.05146 -151.529034) (xy 51.052043 -151.501181) (xy 51.060161 -151.44607) (xy 51.0762 -151.392722)
			(xy 51.09982 -151.342272) (xy 51.130519 -151.295788) (xy 51.167647 -151.254258) (xy 51.210414 -151.218563)
			(xy 51.257914 -151.189461) (xy 51.309138 -151.167569) (xy 51.33594 -151.159972) (xy 51.350063 -151.155719)
			(xy 51.375204 -151.14032) (xy 51.394916 -151.118396) (xy 51.407566 -151.091764) (xy 51.412104 -151.062632)
			(xy 51.410616 -151.047958) (xy 51.408945 -151.034942) (xy 51.407166 -151.008757) (xy 51.40706 -150.995634)
			(xy 51.407158 -150.981485) (xy 51.409189 -150.953262) (xy 51.411124 -150.939246) (xy 51.412683 -150.925896)
			(xy 51.409585 -150.899209) (xy 51.39962 -150.874259) (xy 51.38348 -150.852781) (xy 51.362288 -150.836267)
			(xy 51.337516 -150.825867) (xy 51.324256 -150.823676) (xy 51.297113 -150.81953) (xy 51.244287 -150.804561)
			(xy 51.194152 -150.782174) (xy 51.147744 -150.752832) (xy 51.106021 -150.717141) (xy 51.069844 -150.675838)
			(xy 51.039961 -150.629777) (xy 51.016989 -150.579907) (xy 51.001402 -150.52726) (xy 50.993522 -150.472923)
			(xy 50.99304 -150.44547) (xy 37.986208 -150.44547) (xy 37.986208 -151.644871) (xy 43.782962 -151.644871)
			(xy 43.786968 -151.589723) (xy 43.798892 -151.535731) (xy 43.818485 -151.484026) (xy 43.845337 -151.435691)
			(xy 43.878885 -151.391738) (xy 43.898312 -151.372062) (xy 43.907656 -151.362295) (xy 43.921334 -151.338994)
			(xy 43.928423 -151.312922) (xy 43.928426 -151.285903) (xy 43.921344 -151.259829) (xy 43.907671 -151.236525)
			(xy 43.898312 -151.226774) (xy 43.880473 -151.208774) (xy 43.849246 -151.16886) (xy 43.823579 -151.125162)
			(xy 43.803922 -151.078452) (xy 43.790624 -151.029549) (xy 43.783917 -150.979317) (xy 43.783504 -150.953978)
			(xy 43.783957 -150.926726) (xy 43.791717 -150.872776) (xy 43.807076 -150.82048) (xy 43.82972 -150.770902)
			(xy 43.85919 -150.725051) (xy 43.894885 -150.683861) (xy 43.936078 -150.64817) (xy 43.981932 -150.618704)
			(xy 44.031512 -150.596064) (xy 44.083809 -150.58071) (xy 44.13776 -150.572955) (xy 44.165012 -150.57247)
			(xy 44.194271 -150.573037) (xy 44.252103 -150.581981) (xy 44.307894 -150.599642) (xy 44.360337 -150.625607)
			(xy 44.408206 -150.659268) (xy 44.42968 -150.67915) (xy 44.439987 -150.688465) (xy 44.464413 -150.701673)
			(xy 44.491499 -150.707794) (xy 44.519231 -150.706373) (xy 44.545549 -150.697515) (xy 44.568497 -150.681879)
			(xy 44.577762 -150.67153) (xy 44.596006 -150.650711) (xy 44.637408 -150.613972) (xy 44.683688 -150.583606)
			(xy 44.733873 -150.560253) (xy 44.786908 -150.544404) (xy 44.841678 -150.536392) (xy 44.869354 -150.535894)
			(xy 44.896723 -150.536388) (xy 44.950901 -150.5442) (xy 45.003404 -150.559682) (xy 45.053151 -150.582518)
			(xy 45.099119 -150.612236) (xy 45.120052 -150.629874) (xy 45.13138 -150.63911) (xy 45.157937 -150.651286)
			(xy 45.186854 -150.655459) (xy 45.215771 -150.651286) (xy 45.242328 -150.63911) (xy 45.253656 -150.629874)
			(xy 45.274589 -150.612233) (xy 45.320557 -150.582509) (xy 45.370303 -150.559663) (xy 45.422805 -150.544167)
			(xy 45.476983 -150.536338) (xy 45.531725 -150.536338) (xy 45.585903 -150.544167) (xy 45.638405 -150.559663)
			(xy 45.688151 -150.582509) (xy 45.734119 -150.612233) (xy 45.755052 -150.629874) (xy 45.76638 -150.63911)
			(xy 45.792937 -150.651286) (xy 45.821854 -150.655459) (xy 45.850771 -150.651286) (xy 45.877328 -150.63911)
			(xy 45.888656 -150.629874) (xy 45.909589 -150.612233) (xy 45.955557 -150.582509) (xy 46.005303 -150.559663)
			(xy 46.057805 -150.544167) (xy 46.111983 -150.536338) (xy 46.166725 -150.536338) (xy 46.220903 -150.544167)
			(xy 46.273405 -150.559663) (xy 46.323151 -150.582509) (xy 46.369119 -150.612233) (xy 46.390052 -150.629874)
			(xy 46.40138 -150.63911) (xy 46.427937 -150.651286) (xy 46.456854 -150.655459) (xy 46.485771 -150.651286)
			(xy 46.512328 -150.63911) (xy 46.523656 -150.629874) (xy 46.54459 -150.612238) (xy 46.590563 -150.582527)
			(xy 46.64031 -150.55969) (xy 46.69281 -150.544199) (xy 46.746985 -150.536369) (xy 46.774354 -150.535894)
			(xy 46.804152 -150.536484) (xy 46.863022 -150.545758) (xy 46.919734 -150.56407) (xy 46.972911 -150.590976)
			(xy 47.021258 -150.625822) (xy 47.042832 -150.646384) (xy 47.054372 -150.657021) (xy 47.082273 -150.671355)
			(xy 47.113206 -150.676557) (xy 47.144261 -150.672139) (xy 47.172516 -150.658516) (xy 47.18431 -150.648162)
			(xy 47.205669 -150.628715) (xy 47.25316 -150.595835) (xy 47.305067 -150.570493) (xy 47.360201 -150.553269)
			(xy 47.417303 -150.544556) (xy 47.446184 -150.544022) (xy 47.473438 -150.54447) (xy 47.527391 -150.552226)
			(xy 47.579691 -150.567581) (xy 47.629273 -150.590224) (xy 47.675128 -150.619693) (xy 47.716321 -150.655389)
			(xy 47.752015 -150.696584) (xy 47.781483 -150.742439) (xy 47.804124 -150.792022) (xy 47.819477 -150.844323)
			(xy 47.827231 -150.898276) (xy 47.827692 -150.92553) (xy 47.827299 -150.950869) (xy 47.820586 -151.001101)
			(xy 47.807281 -151.050002) (xy 47.787619 -151.096711) (xy 47.761946 -151.140406) (xy 47.730715 -151.180317)
			(xy 47.712884 -151.198326) (xy 47.703553 -151.208104) (xy 47.689874 -151.231402) (xy 47.682784 -151.257471)
			(xy 47.682779 -151.284487) (xy 47.689858 -151.310559) (xy 47.703527 -151.333863) (xy 47.712884 -151.343614)
			(xy 47.732318 -151.363281) (xy 47.76586 -151.407234) (xy 47.792706 -151.455569) (xy 47.812293 -151.507273)
			(xy 47.824211 -151.561262) (xy 47.828212 -151.616407) (xy 47.824209 -151.671552) (xy 47.812289 -151.725541)
			(xy 47.7927 -151.777244) (xy 47.765852 -151.825578) (xy 47.732309 -151.86953) (xy 47.712884 -151.889206)
			(xy 47.703473 -151.898913) (xy 47.6898 -151.922231) (xy 47.68272 -151.948319) (xy 47.682729 -151.975351)
			(xy 47.689827 -152.001433) (xy 47.703516 -152.024742) (xy 47.712884 -152.034494) (xy 47.730707 -152.05251)
			(xy 47.761935 -152.09242) (xy 47.787605 -152.136114) (xy 47.807264 -152.182822) (xy 47.820566 -152.231722)
			(xy 47.827277 -152.281952) (xy 47.827692 -152.30729) (xy 47.827235 -152.334543) (xy 47.819479 -152.388495)
			(xy 47.804124 -152.440794) (xy 47.781481 -152.490375) (xy 47.752013 -152.536229) (xy 47.716318 -152.577423)
			(xy 47.675125 -152.613116) (xy 47.62927 -152.642584) (xy 47.579689 -152.665226) (xy 47.527389 -152.680581)
			(xy 47.473437 -152.688336) (xy 47.446184 -152.688798) (xy 47.416385 -152.688249) (xy 47.357513 -152.678966)
			(xy 47.300799 -152.660644) (xy 47.247624 -152.633728) (xy 47.199279 -152.598874) (xy 47.177706 -152.578308)
			(xy 47.166217 -152.567611) (xy 47.138297 -152.553284) (xy 47.107349 -152.548094) (xy 47.076284 -152.552527)
			(xy 47.048023 -152.566167) (xy 47.036228 -152.57653) (xy 47.014852 -152.595958) (xy 46.967366 -152.628841)
			(xy 46.915463 -152.654186) (xy 46.860333 -152.671415) (xy 46.803234 -152.680133) (xy 46.774354 -152.68067)
			(xy 46.746985 -152.68018) (xy 46.692806 -152.672369) (xy 46.640303 -152.656886) (xy 46.590556 -152.634049)
			(xy 46.544588 -152.604329) (xy 46.523656 -152.58669) (xy 46.512328 -152.577454) (xy 46.485771 -152.565278)
			(xy 46.456854 -152.561105) (xy 46.427937 -152.565278) (xy 46.40138 -152.577454) (xy 46.390052 -152.58669)
			(xy 46.369119 -152.604331) (xy 46.323151 -152.634055) (xy 46.273405 -152.656901) (xy 46.220903 -152.672397)
			(xy 46.166725 -152.680226) (xy 46.111983 -152.680226) (xy 46.057805 -152.672397) (xy 46.005303 -152.656901)
			(xy 45.955557 -152.634055) (xy 45.909589 -152.604331) (xy 45.888656 -152.58669) (xy 45.877328 -152.577454)
			(xy 45.850771 -152.565278) (xy 45.821854 -152.561105) (xy 45.792937 -152.565278) (xy 45.76638 -152.577454)
			(xy 45.755052 -152.58669) (xy 45.734119 -152.604331) (xy 45.688151 -152.634055) (xy 45.638405 -152.656901)
			(xy 45.585903 -152.672397) (xy 45.531725 -152.680226) (xy 45.476983 -152.680226) (xy 45.422805 -152.672397)
			(xy 45.370303 -152.656901) (xy 45.320557 -152.634055) (xy 45.274589 -152.604331) (xy 45.253656 -152.58669)
			(xy 45.242328 -152.577454) (xy 45.215771 -152.565278) (xy 45.186854 -152.561105) (xy 45.157937 -152.565278)
			(xy 45.13138 -152.577454) (xy 45.120052 -152.58669) (xy 45.09911 -152.604317) (xy 45.05314 -152.634031)
			(xy 45.003395 -152.656869) (xy 44.950897 -152.672363) (xy 44.896723 -152.680194) (xy 44.869354 -152.68067)
			(xy 44.840094 -152.680113) (xy 44.782263 -152.671165) (xy 44.726473 -152.653501) (xy 44.674029 -152.627534)
			(xy 44.62616 -152.593872) (xy 44.604686 -152.57399) (xy 44.594404 -152.564648) (xy 44.569969 -152.551451)
			(xy 44.542878 -152.545339) (xy 44.515144 -152.546766) (xy 44.488824 -152.555626) (xy 44.465872 -152.571261)
			(xy 44.456604 -152.58161) (xy 44.438387 -152.602453) (xy 44.396978 -152.639189) (xy 44.350692 -152.669551)
			(xy 44.300502 -152.692899) (xy 44.247463 -152.708743) (xy 44.19269 -152.71675) (xy 44.165012 -152.717246)
			(xy 44.137763 -152.716711) (xy 44.083819 -152.708957) (xy 44.031527 -152.693605) (xy 43.981953 -152.670968)
			(xy 43.936104 -152.641507) (xy 43.894915 -152.60582) (xy 43.859223 -152.564636) (xy 43.829756 -152.518791)
			(xy 43.807112 -152.469219) (xy 43.791754 -152.41693) (xy 43.783993 -152.362987) (xy 43.783504 -152.335738)
			(xy 43.783942 -152.3104) (xy 43.790646 -152.26017) (xy 43.803942 -152.21127) (xy 43.823596 -152.164561)
			(xy 43.849261 -152.120865) (xy 43.880485 -152.080952) (xy 43.898312 -152.062942) (xy 43.907675 -152.053192)
			(xy 43.921352 -152.029887) (xy 43.928439 -152.00381) (xy 43.928438 -151.976787) (xy 43.921351 -151.950711)
			(xy 43.907674 -151.927405) (xy 43.898312 -151.917654) (xy 43.878846 -151.898018) (xy 43.845305 -151.85406)
			(xy 43.818461 -151.805721) (xy 43.798875 -151.754012) (xy 43.786959 -151.700019) (xy 43.782962 -151.644871)
			(xy 37.986208 -151.644871) (xy 37.986208 -152.693116) (xy 39.821144 -154.528052) (xy 49.996289 -154.528052)
			(xy 49.996289 -154.473548) (xy 50.004047 -154.419598) (xy 50.019404 -154.367301) (xy 50.042047 -154.317722)
			(xy 50.071517 -154.271871) (xy 50.107212 -154.230681) (xy 50.148406 -154.19499) (xy 50.194261 -154.165526)
			(xy 50.243842 -154.142888) (xy 50.296141 -154.127537) (xy 50.350092 -154.119786) (xy 50.377344 -154.119326)
			(xy 50.407031 -154.119911) (xy 50.465689 -154.129102) (xy 50.522215 -154.147271) (xy 50.575243 -154.173978)
			(xy 50.623492 -154.20858) (xy 50.665798 -154.250239) (xy 50.683922 -154.273758) (xy 50.692348 -154.284365)
			(xy 50.713661 -154.301072) (xy 50.738615 -154.311591) (xy 50.765456 -154.315181) (xy 50.792297 -154.311591)
			(xy 50.817251 -154.301072) (xy 50.838564 -154.284365) (xy 50.84699 -154.273758) (xy 50.86512 -154.250243)
			(xy 50.907427 -154.208585) (xy 50.955675 -154.173982) (xy 51.008701 -154.147271) (xy 51.065225 -154.129095)
			(xy 51.123881 -154.119893) (xy 51.153568 -154.119326) (xy 51.180825 -154.119719) (xy 51.234784 -154.127473)
			(xy 51.28709 -154.142827) (xy 51.336679 -154.16547) (xy 51.38254 -154.19494) (xy 51.423741 -154.230637)
			(xy 51.459441 -154.271834) (xy 51.488915 -154.317693) (xy 51.511561 -154.36728) (xy 51.52692 -154.419585)
			(xy 51.534679 -154.473543) (xy 51.534679 -154.528057) (xy 51.52692 -154.582015) (xy 51.511561 -154.63432)
			(xy 51.488915 -154.683907) (xy 51.459441 -154.729766) (xy 51.423741 -154.770963) (xy 51.38254 -154.80666)
			(xy 51.336679 -154.83613) (xy 51.28709 -154.858773) (xy 51.234784 -154.874127) (xy 51.180825 -154.881881)
			(xy 51.153568 -154.882342) (xy 51.123881 -154.88176) (xy 51.065222 -154.87257) (xy 51.008695 -154.854402)
			(xy 50.955667 -154.827694) (xy 50.907418 -154.793091) (xy 50.865114 -154.75143) (xy 50.84699 -154.72791)
			(xy 50.838564 -154.717303) (xy 50.817251 -154.700596) (xy 50.792297 -154.690077) (xy 50.765456 -154.686487)
			(xy 50.738615 -154.690077) (xy 50.713661 -154.700596) (xy 50.692348 -154.717303) (xy 50.683922 -154.72791)
			(xy 50.665776 -154.751412) (xy 50.623474 -154.793073) (xy 50.575229 -154.827678) (xy 50.522206 -154.854392)
			(xy 50.465685 -154.87257) (xy 50.40703 -154.881774) (xy 50.377344 -154.882342) (xy 50.350092 -154.881814)
			(xy 50.296141 -154.874063) (xy 50.243842 -154.858712) (xy 50.194261 -154.836074) (xy 50.148406 -154.80661)
			(xy 50.107212 -154.770919) (xy 50.071517 -154.729729) (xy 50.042047 -154.683878) (xy 50.019404 -154.634299)
			(xy 50.004047 -154.582002) (xy 49.996289 -154.528052) (xy 39.821144 -154.528052) (xy 42.643552 -157.35046)
			(xy 49.89957 -157.35046) (xy 50.333148 -156.916882) (xy 50.333148 -156.871162) (xy 50.318416 -156.85643)
			(xy 50.297519 -156.834824) (xy 50.262108 -156.786258) (xy 50.234754 -156.732737) (xy 50.216134 -156.675589)
			(xy 50.20671 -156.616227) (xy 50.206148 -156.586174) (xy 50.206653 -156.558924) (xy 50.214412 -156.504979)
			(xy 50.229769 -156.452688) (xy 50.25241 -156.403113) (xy 50.281874 -156.357265) (xy 50.317564 -156.316076)
			(xy 50.358751 -156.280385) (xy 50.404597 -156.250918) (xy 50.454171 -156.228275) (xy 50.506462 -156.212916)
			(xy 50.560406 -156.205155) (xy 50.587656 -156.204666) (xy 50.58791 -156.204666) (xy 50.617749 -156.205247)
			(xy 50.676695 -156.214559) (xy 50.705258 -156.223208) (xy 50.719167 -156.227239) (xy 50.748099 -156.228148)
			(xy 50.776118 -156.220883) (xy 50.800963 -156.206032) (xy 50.820629 -156.184792) (xy 50.833527 -156.158879)
			(xy 50.836576 -156.144722) (xy 50.843165 -156.111884) (xy 50.866284 -156.049031) (xy 50.88255 -156.019754)
			(xy 50.889618 -156.006804) (xy 50.896647 -155.978161) (xy 50.895197 -155.948704) (xy 50.885389 -155.92089)
			(xy 50.868042 -155.897039) (xy 50.844601 -155.879141) (xy 50.830988 -155.87345) (xy 50.80422 -155.862735)
			(xy 50.753979 -155.83445) (xy 50.70857 -155.798922) (xy 50.669027 -155.756963) (xy 50.636253 -155.709528)
			(xy 50.610993 -155.6577) (xy 50.593825 -155.60266) (xy 50.585139 -155.545662) (xy 50.584608 -155.516834)
			(xy 50.585094 -155.489583) (xy 50.59285 -155.435635) (xy 50.608205 -155.38334) (xy 50.630847 -155.333763)
			(xy 50.660313 -155.287913) (xy 50.696004 -155.246722) (xy 50.737195 -155.211031) (xy 50.783045 -155.181565)
			(xy 50.832622 -155.158923) (xy 50.884917 -155.143568) (xy 50.938865 -155.135812) (xy 50.993367 -155.135812)
			(xy 51.047315 -155.143568) (xy 51.09961 -155.158923) (xy 51.149187 -155.181565) (xy 51.195037 -155.211031)
			(xy 51.236228 -155.246722) (xy 51.271919 -155.287913) (xy 51.301385 -155.333763) (xy 51.324027 -155.38334)
			(xy 51.339382 -155.435635) (xy 51.347138 -155.489583) (xy 51.347624 -155.516834) (xy 51.347624 -155.517088)
			(xy 51.347224 -155.542292) (xy 51.340585 -155.59226) (xy 51.327409 -155.640914) (xy 51.307926 -155.687404)
			(xy 51.295554 -155.709366) (xy 51.28846 -155.722303) (xy 51.281434 -155.750951) (xy 51.282888 -155.780412)
			(xy 51.292701 -155.808229) (xy 51.310054 -155.832081) (xy 51.3335 -155.84998) (xy 51.347116 -155.85567)
			(xy 51.373892 -155.866366) (xy 51.424134 -155.894654) (xy 51.469543 -155.930184) (xy 51.509085 -155.972146)
			(xy 51.541859 -156.019583) (xy 51.567117 -156.071414) (xy 51.584283 -156.126457) (xy 51.592966 -156.183457)
			(xy 51.593496 -156.212286) (xy 51.593032 -156.239539) (xy 51.585276 -156.293491) (xy 51.569921 -156.345789)
			(xy 51.54728 -156.39537) (xy 51.517812 -156.441224) (xy 51.482118 -156.482417) (xy 51.440925 -156.518111)
			(xy 51.395072 -156.547579) (xy 51.345491 -156.570221) (xy 51.293193 -156.585576) (xy 51.239241 -156.593331)
			(xy 51.211988 -156.593794) (xy 51.211734 -156.593794) (xy 51.181895 -156.593227) (xy 51.122949 -156.583906)
			(xy 51.094386 -156.575252) (xy 51.080457 -156.571302) (xy 51.051539 -156.570385) (xy 51.02353 -156.577636)
			(xy 50.998691 -156.592471) (xy 50.979026 -156.613693) (xy 50.966122 -156.639589) (xy 50.963068 -156.653738)
			(xy 50.958213 -156.678553) (xy 50.94279 -156.726709) (xy 50.921131 -156.7724) (xy 50.893616 -156.814823)
			(xy 50.860729 -156.853232) (xy 50.842164 -156.8704) (xy 50.842164 -157.022292) (xy 50.841527 -157.047288)
			(xy 50.831723 -157.096311) (xy 50.81255 -157.142481) (xy 50.784743 -157.184028) (xy 50.767488 -157.202124)
			(xy 50.184812 -157.7848) (xy 50.166705 -157.802043) (xy 50.125164 -157.829856) (xy 50.078996 -157.849032)
			(xy 50.029975 -157.858836) (xy 50.00498 -157.859476) (xy 42.538142 -157.859476) (xy 42.513147 -157.858815)
			(xy 42.464126 -157.849018) (xy 42.417955 -157.829852) (xy 42.376407 -157.802052) (xy 42.35831 -157.7848)
			(xy 37.551868 -152.978358) (xy 37.534579 -152.960289) (xy 37.506762 -152.918739) (xy 37.487585 -152.87256)
			(xy 37.477786 -152.823527) (xy 37.477192 -152.798526) (xy 37.477192 -143.883888) (xy 37.477801 -143.85889)
			(xy 37.48761 -143.809865) (xy 37.506792 -143.763694) (xy 37.534608 -143.72215) (xy 37.551868 -143.704056)
			(xy 43.435524 -137.8204) (xy 43.435524 -125.31979) (xy 39.46144 -121.34596) (xy 32.08147 -121.34596)
			(xy 31.446814 -121.980452) (xy 33.357564 -121.980452) (xy 33.361635 -121.92483) (xy 33.373761 -121.870393)
			(xy 33.393684 -121.818302) (xy 33.42098 -121.769667) (xy 33.455066 -121.725524) (xy 33.495215 -121.686815)
			(xy 33.540573 -121.654364) (xy 33.590173 -121.628863) (xy 33.642957 -121.610856) (xy 33.6978 -121.600726)
			(xy 33.753534 -121.598689) (xy 33.808971 -121.604789) (xy 33.862928 -121.618895) (xy 33.914257 -121.640707)
			(xy 33.961863 -121.669761) (xy 34.004731 -121.705436) (xy 34.041948 -121.746973) (xy 34.072721 -121.793486)
			(xy 34.096393 -121.843983) (xy 34.112461 -121.89739) (xy 34.120581 -121.952566) (xy 34.12109 -121.980452)
			(xy 34.68065 -121.980452) (xy 34.684721 -121.92483) (xy 34.696847 -121.870393) (xy 34.71677 -121.818302)
			(xy 34.744066 -121.769667) (xy 34.778152 -121.725524) (xy 34.818301 -121.686815) (xy 34.863659 -121.654364)
			(xy 34.913259 -121.628863) (xy 34.966043 -121.610856) (xy 35.020886 -121.600726) (xy 35.07662 -121.598689)
			(xy 35.132057 -121.604789) (xy 35.186014 -121.618895) (xy 35.237343 -121.640707) (xy 35.284949 -121.669761)
			(xy 35.327817 -121.705436) (xy 35.365034 -121.746973) (xy 35.395807 -121.793486) (xy 35.419479 -121.843983)
			(xy 35.435547 -121.89739) (xy 35.443667 -121.952566) (xy 35.444176 -121.980452) (xy 35.443667 -122.008338)
			(xy 35.435547 -122.063514) (xy 35.419479 -122.116921) (xy 35.395807 -122.167418) (xy 35.365034 -122.213931)
			(xy 35.327817 -122.255468) (xy 35.284949 -122.291143) (xy 35.237343 -122.320197) (xy 35.186014 -122.342009)
			(xy 35.132057 -122.356115) (xy 35.07662 -122.362215) (xy 35.020886 -122.360178) (xy 34.966043 -122.350048)
			(xy 34.913259 -122.332041) (xy 34.863659 -122.30654) (xy 34.818301 -122.274089) (xy 34.778152 -122.23538)
			(xy 34.744066 -122.191237) (xy 34.71677 -122.142602) (xy 34.696847 -122.090511) (xy 34.684721 -122.036074)
			(xy 34.68065 -121.980452) (xy 34.12109 -121.980452) (xy 34.120581 -122.008338) (xy 34.112461 -122.063514)
			(xy 34.096393 -122.116921) (xy 34.072721 -122.167418) (xy 34.041948 -122.213931) (xy 34.004731 -122.255468)
			(xy 33.961863 -122.291143) (xy 33.914257 -122.320197) (xy 33.862928 -122.342009) (xy 33.808971 -122.356115)
			(xy 33.753534 -122.362215) (xy 33.6978 -122.360178) (xy 33.642957 -122.350048) (xy 33.590173 -122.332041)
			(xy 33.540573 -122.30654) (xy 33.495215 -122.274089) (xy 33.455066 -122.23538) (xy 33.42098 -122.191237)
			(xy 33.393684 -122.142602) (xy 33.373761 -122.090511) (xy 33.361635 -122.036074) (xy 33.357564 -121.980452)
			(xy 31.446814 -121.980452) (xy 31.098236 -122.32894) (xy 31.098236 -123.657907) (xy 31.386782 -123.657907)
			(xy 31.386818 -123.603386) (xy 31.394616 -123.549426) (xy 31.410017 -123.497126) (xy 31.432707 -123.447551)
			(xy 31.462224 -123.401711) (xy 31.497966 -123.360541) (xy 31.539206 -123.324879) (xy 31.585103 -123.295451)
			(xy 31.634722 -123.272857) (xy 31.687052 -123.257558) (xy 31.741027 -123.249865) (xy 31.768288 -123.249436)
			(xy 31.789624 -123.249436) (xy 32.34944 -122.68962) (xy 32.367528 -122.672355) (xy 32.409075 -122.644546)
			(xy 32.455249 -122.625375) (xy 32.504275 -122.615579) (xy 32.529272 -122.614944) (xy 40.266874 -122.614944)
			(xy 40.29187 -122.61559) (xy 40.340892 -122.62539) (xy 40.387063 -122.644561) (xy 40.42861 -122.672366)
			(xy 40.446706 -122.68962) (xy 43.095672 -125.338586) (xy 43.11291 -125.356698) (xy 43.140725 -125.398237)
			(xy 43.159903 -125.444403) (xy 43.169708 -125.493423) (xy 43.170348 -125.518418) (xy 43.170348 -137.622026)
			(xy 43.169736 -137.647023) (xy 43.159926 -137.696048) (xy 43.140745 -137.742218) (xy 43.11293 -137.783763)
			(xy 43.095672 -137.801858) (xy 37.196776 -143.700754) (xy 37.196776 -154.721306) (xy 37.196142 -154.746288)
			(xy 37.186405 -154.795295) (xy 37.167304 -154.841464) (xy 37.139572 -154.883026) (xy 37.122354 -154.901138)
			(xy 35.979608 -156.044138) (xy 35.979608 -159.08147) (xy 50.99304 -159.08147) (xy 50.993427 -159.054214)
			(xy 51.001189 -159.000258) (xy 51.016552 -158.947956) (xy 51.039201 -158.898372) (xy 51.068677 -158.852517)
			(xy 51.104379 -158.811323) (xy 51.145579 -158.77563) (xy 51.191441 -158.746164) (xy 51.241029 -158.723524)
			(xy 51.293334 -158.708173) (xy 51.347292 -158.700422) (xy 51.374548 -158.699962) (xy 51.402122 -158.700442)
			(xy 51.456695 -158.708388) (xy 51.509556 -158.724109) (xy 51.559603 -158.747276) (xy 51.605792 -158.777408)
			(xy 51.647163 -158.813875) (xy 51.665378 -158.834582) (xy 51.675276 -158.84548) (xy 51.699926 -158.861555)
			(xy 51.728134 -158.869939) (xy 51.757562 -158.869939) (xy 51.78577 -158.861555) (xy 51.81042 -158.84548)
			(xy 51.820318 -158.834582) (xy 51.838512 -158.813855) (xy 51.879885 -158.777387) (xy 51.926079 -158.747257)
			(xy 51.97613 -158.724094) (xy 52.028995 -158.708381) (xy 52.083572 -158.700445) (xy 52.111148 -158.699962)
			(xy 52.137649 -158.700415) (xy 52.19014 -158.707762) (xy 52.241107 -158.722307) (xy 52.289569 -158.74377)
			(xy 52.334592 -158.771737) (xy 52.355242 -158.788354) (xy 52.367396 -158.797784) (xy 52.395794 -158.809573)
			(xy 52.426411 -158.812397) (xy 52.456486 -158.806003) (xy 52.483306 -158.790967) (xy 52.504451 -158.768645)
			(xy 52.511706 -158.75508) (xy 52.523817 -158.731395) (xy 52.553737 -158.687413) (xy 52.589605 -158.64813)
			(xy 52.630693 -158.614345) (xy 52.653184 -158.60014) (xy 52.665431 -158.592248) (xy 52.685104 -158.570769)
			(xy 52.697907 -158.544607) (xy 52.702796 -158.515894) (xy 52.699373 -158.486969) (xy 52.694078 -158.473394)
			(xy 52.684593 -158.450182) (xy 52.671241 -158.40185) (xy 52.664511 -158.352161) (xy 52.664106 -158.32709)
			(xy 52.66454 -158.302021) (xy 52.671286 -158.252338) (xy 52.684614 -158.204004) (xy 52.694078 -158.180786)
			(xy 52.699333 -158.167207) (xy 52.702713 -158.138299) (xy 52.697811 -158.10961) (xy 52.685024 -158.083464)
			(xy 52.665389 -158.06198) (xy 52.653184 -158.05404) (xy 52.630024 -158.039514) (xy 52.587899 -158.004668)
			(xy 52.551317 -157.964041) (xy 52.521063 -157.918506) (xy 52.497786 -157.869039) (xy 52.481986 -157.816703)
			(xy 52.474001 -157.762619) (xy 52.474003 -157.70795) (xy 52.481993 -157.653867) (xy 52.497797 -157.601532)
			(xy 52.521079 -157.552067) (xy 52.551336 -157.506534) (xy 52.587922 -157.465911) (xy 52.630049 -157.431068)
			(xy 52.653184 -157.4165) (xy 52.66539 -157.408551) (xy 52.685063 -157.387088) (xy 52.697871 -157.360941)
			(xy 52.702771 -157.332241) (xy 52.699363 -157.303326) (xy 52.694078 -157.289754) (xy 52.684581 -157.266547)
			(xy 52.671233 -157.218213) (xy 52.664508 -157.168522) (xy 52.664106 -157.14345) (xy 52.664627 -157.115565)
			(xy 52.672939 -157.060418) (xy 52.689377 -157.007126) (xy 52.713575 -156.95688) (xy 52.744991 -156.910801)
			(xy 52.782924 -156.869919) (xy 52.826526 -156.835147) (xy 52.874824 -156.807262) (xy 52.926739 -156.786887)
			(xy 52.98111 -156.774477) (xy 53.036724 -156.77031) (xy 53.092338 -156.774477) (xy 53.146709 -156.786887)
			(xy 53.198624 -156.807262) (xy 53.246922 -156.835147) (xy 53.290524 -156.869919) (xy 53.328457 -156.910801)
			(xy 53.359873 -156.95688) (xy 53.384071 -157.007126) (xy 53.400509 -157.060418) (xy 53.408821 -157.115565)
			(xy 53.409342 -157.14345) (xy 53.408875 -157.170782) (xy 53.400906 -157.224863) (xy 53.385118 -157.277198)
			(xy 53.36185 -157.326662) (xy 53.331601 -157.372195) (xy 53.295022 -157.412817) (xy 53.252897 -157.447655)
			(xy 53.229764 -157.46222) (xy 53.217537 -157.470138) (xy 53.19787 -157.491612) (xy 53.185068 -157.517767)
			(xy 53.180173 -157.546472) (xy 53.183584 -157.575392) (xy 53.18887 -157.588966) (xy 53.198345 -157.612181)
			(xy 53.211701 -157.660512) (xy 53.218435 -157.710199) (xy 53.218842 -157.73527) (xy 53.218431 -157.76034)
			(xy 53.211677 -157.810023) (xy 53.198339 -157.858357) (xy 53.18887 -157.881574) (xy 53.183624 -157.895151)
			(xy 53.180262 -157.924051) (xy 53.185173 -157.952729) (xy 53.197961 -157.978863) (xy 53.217591 -158.000338)
			(xy 53.229764 -158.00832) (xy 53.252885 -158.022903) (xy 53.295003 -158.057747) (xy 53.331579 -158.098369)
			(xy 53.361829 -158.143898) (xy 53.385103 -158.193358) (xy 53.400902 -158.245688) (xy 53.408888 -158.299764)
			(xy 53.408889 -158.354426) (xy 53.400905 -158.408502) (xy 53.385107 -158.460832) (xy 53.361834 -158.510292)
			(xy 53.331585 -158.555823) (xy 53.29501 -158.596446) (xy 53.252893 -158.631291) (xy 53.229764 -158.64586)
			(xy 53.217509 -158.653739) (xy 53.197842 -158.675225) (xy 53.185043 -158.70139) (xy 53.180156 -158.730104)
			(xy 53.183577 -158.75903) (xy 53.18887 -158.772606) (xy 53.198357 -158.795817) (xy 53.211708 -158.844149)
			(xy 53.218438 -158.893838) (xy 53.218842 -158.91891) (xy 53.21837 -158.945752) (xy 53.210665 -158.998881)
			(xy 53.195416 -159.050354) (xy 53.172938 -159.099106) (xy 53.143697 -159.144127) (xy 53.108298 -159.184487)
			(xy 53.067473 -159.219349) (xy 53.022069 -159.247993) (xy 52.973024 -159.269824) (xy 52.947316 -159.277558)
			(xy 52.932841 -159.282276) (xy 52.907286 -159.298788) (xy 52.887726 -159.322092) (xy 52.875894 -159.350122)
			(xy 52.87284 -159.380393) (xy 52.878835 -159.410222) (xy 52.885594 -159.423862) (xy 52.900228 -159.452008)
			(xy 52.920955 -159.511959) (xy 52.931453 -159.574517) (xy 52.932076 -159.606234) (xy 52.931855 -159.624253)
			(xy 52.928421 -159.660128) (xy 52.925218 -159.677862) (xy 52.922936 -159.693077) (xy 52.926453 -159.723622)
			(xy 52.938901 -159.751736) (xy 52.959153 -159.774871) (xy 52.985373 -159.790931) (xy 53.000148 -159.79521)
			(xy 53.027191 -159.802611) (xy 53.078917 -159.824241) (xy 53.126922 -159.853205) (xy 53.170174 -159.88888)
			(xy 53.207741 -159.930499) (xy 53.238815 -159.977165) (xy 53.262728 -160.027876) (xy 53.278965 -160.08154)
			(xy 53.287177 -160.137001) (xy 53.287676 -160.165034) (xy 53.287254 -160.192288) (xy 53.279492 -160.246239)
			(xy 53.264131 -160.298537) (xy 53.241483 -160.348117) (xy 53.21201 -160.393968) (xy 53.176312 -160.435159)
			(xy 53.135115 -160.47085) (xy 53.089259 -160.500315) (xy 53.039675 -160.522954) (xy 52.987375 -160.538306)
			(xy 52.933422 -160.546058) (xy 52.906168 -160.546542) (xy 52.878594 -160.54605) (xy 52.824022 -160.538105)
			(xy 52.771161 -160.522387) (xy 52.721115 -160.499222) (xy 52.674925 -160.469093) (xy 52.633554 -160.432628)
			(xy 52.615338 -160.411922) (xy 52.60544 -160.401024) (xy 52.58079 -160.384949) (xy 52.552582 -160.376565)
			(xy 52.523154 -160.376565) (xy 52.494946 -160.384949) (xy 52.470296 -160.401024) (xy 52.460398 -160.411922)
			(xy 52.442183 -160.432628) (xy 52.400812 -160.469093) (xy 52.354622 -160.49922) (xy 52.304575 -160.522383)
			(xy 52.251714 -160.538099) (xy 52.197142 -160.546039) (xy 52.141994 -160.546039) (xy 52.087422 -160.538099)
			(xy 52.034561 -160.522383) (xy 51.984514 -160.49922) (xy 51.938324 -160.469093) (xy 51.896953 -160.432628)
			(xy 51.878738 -160.411922) (xy 51.86884 -160.401024) (xy 51.84419 -160.384949) (xy 51.815982 -160.376565)
			(xy 51.786554 -160.376565) (xy 51.758346 -160.384949) (xy 51.733696 -160.401024) (xy 51.723798 -160.411922)
			(xy 51.705596 -160.432642) (xy 51.664225 -160.46911) (xy 51.618033 -160.499241) (xy 51.567983 -160.522405)
			(xy 51.515119 -160.53812) (xy 51.460543 -160.546058) (xy 51.432968 -160.546542) (xy 51.405718 -160.546052)
			(xy 51.351772 -160.538292) (xy 51.299479 -160.522935) (xy 51.249904 -160.500292) (xy 51.204055 -160.470826)
			(xy 51.162866 -160.435135) (xy 51.127175 -160.393946) (xy 51.097709 -160.348098) (xy 51.075066 -160.298523)
			(xy 51.059708 -160.24623) (xy 51.051948 -160.192284) (xy 51.05146 -160.165034) (xy 51.052043 -160.137181)
			(xy 51.060161 -160.08207) (xy 51.0762 -160.028722) (xy 51.09982 -159.978272) (xy 51.130519 -159.931788)
			(xy 51.167647 -159.890258) (xy 51.210414 -159.854563) (xy 51.257914 -159.825461) (xy 51.309138 -159.803569)
			(xy 51.33594 -159.795972) (xy 51.350063 -159.791719) (xy 51.375204 -159.77632) (xy 51.394916 -159.754396)
			(xy 51.407566 -159.727764) (xy 51.412104 -159.698632) (xy 51.410616 -159.683958) (xy 51.408945 -159.670942)
			(xy 51.407166 -159.644757) (xy 51.40706 -159.631634) (xy 51.407158 -159.617485) (xy 51.409189 -159.589262)
			(xy 51.411124 -159.575246) (xy 51.412683 -159.561896) (xy 51.409585 -159.535209) (xy 51.39962 -159.510259)
			(xy 51.38348 -159.488781) (xy 51.362288 -159.472267) (xy 51.337516 -159.461867) (xy 51.324256 -159.459676)
			(xy 51.297113 -159.45553) (xy 51.244287 -159.440561) (xy 51.194152 -159.418174) (xy 51.147744 -159.388832)
			(xy 51.106021 -159.353141) (xy 51.069844 -159.311838) (xy 51.039961 -159.265777) (xy 51.016989 -159.215907)
			(xy 51.001402 -159.16326) (xy 50.993522 -159.108923) (xy 50.99304 -159.08147) (xy 35.979608 -159.08147)
			(xy 35.979608 -161.891218) (xy 43.505377 -161.891218) (xy 43.509413 -161.807771) (xy 43.521485 -161.725103)
			(xy 43.541478 -161.643986) (xy 43.569207 -161.565177) (xy 43.604413 -161.489412) (xy 43.646767 -161.417399)
			(xy 43.695873 -161.34981) (xy 43.751274 -161.287276) (xy 43.812451 -161.230381) (xy 43.878834 -161.179655)
			(xy 43.949802 -161.135574) (xy 44.024694 -161.098548) (xy 44.10281 -161.068922) (xy 44.18342 -161.046974)
			(xy 44.265772 -161.032909) (xy 44.349098 -161.026857) (xy 44.432618 -161.028876) (xy 44.515554 -161.038946)
			(xy 44.59713 -161.056974) (xy 44.676586 -161.082791) (xy 44.753179 -161.116156) (xy 44.826195 -161.156757)
			(xy 44.894951 -161.204216) (xy 44.958805 -161.258089) (xy 45.017162 -161.317874) (xy 45.069477 -161.383011)
			(xy 45.11526 -161.452894) (xy 45.154085 -161.526869) (xy 45.18559 -161.604246) (xy 45.209479 -161.684303)
			(xy 45.22553 -161.766291) (xy 45.233593 -161.849446) (xy 45.234098 -161.891218) (xy 45.233593 -161.93299)
			(xy 45.22553 -162.016145) (xy 45.209479 -162.098133) (xy 45.18559 -162.17819) (xy 45.154085 -162.255567)
			(xy 45.11526 -162.329542) (xy 45.069477 -162.399425) (xy 45.017162 -162.464562) (xy 44.958805 -162.524347)
			(xy 44.894951 -162.57822) (xy 44.826195 -162.625679) (xy 44.753179 -162.66628) (xy 44.676586 -162.699645)
			(xy 44.59713 -162.725462) (xy 44.515554 -162.74349) (xy 44.432618 -162.75356) (xy 44.349098 -162.755579)
			(xy 44.265772 -162.749527) (xy 44.18342 -162.735462) (xy 44.10281 -162.713514) (xy 44.024694 -162.683888)
			(xy 43.949802 -162.646862) (xy 43.878834 -162.602781) (xy 43.812451 -162.552055) (xy 43.751274 -162.49516)
			(xy 43.695873 -162.432626) (xy 43.646767 -162.365037) (xy 43.604413 -162.293024) (xy 43.569207 -162.217259)
			(xy 43.541478 -162.13845) (xy 43.521485 -162.057333) (xy 43.509413 -161.974665) (xy 43.505377 -161.891218)
			(xy 35.979608 -161.891218) (xy 35.979608 -163.164052) (xy 49.996289 -163.164052) (xy 49.996289 -163.109548)
			(xy 50.004047 -163.055598) (xy 50.019404 -163.003301) (xy 50.042047 -162.953722) (xy 50.071517 -162.907871)
			(xy 50.107212 -162.866681) (xy 50.148406 -162.83099) (xy 50.194261 -162.801526) (xy 50.243842 -162.778888)
			(xy 50.296141 -162.763537) (xy 50.350092 -162.755786) (xy 50.377344 -162.755326) (xy 50.407031 -162.755911)
			(xy 50.465689 -162.765102) (xy 50.522215 -162.783271) (xy 50.575243 -162.809978) (xy 50.623492 -162.84458)
			(xy 50.665798 -162.886239) (xy 50.683922 -162.909758) (xy 50.692348 -162.920365) (xy 50.713661 -162.937072)
			(xy 50.738615 -162.947591) (xy 50.765456 -162.951181) (xy 50.792297 -162.947591) (xy 50.817251 -162.937072)
			(xy 50.838564 -162.920365) (xy 50.84699 -162.909758) (xy 50.86512 -162.886243) (xy 50.907427 -162.844585)
			(xy 50.955675 -162.809982) (xy 51.008701 -162.783271) (xy 51.065225 -162.765095) (xy 51.123881 -162.755893)
			(xy 51.153568 -162.755326) (xy 51.180825 -162.755719) (xy 51.234784 -162.763473) (xy 51.28709 -162.778827)
			(xy 51.336679 -162.80147) (xy 51.38254 -162.83094) (xy 51.423741 -162.866637) (xy 51.459441 -162.907834)
			(xy 51.488915 -162.953693) (xy 51.511561 -163.00328) (xy 51.52692 -163.055585) (xy 51.534679 -163.109543)
			(xy 51.534679 -163.164057) (xy 51.52692 -163.218015) (xy 51.511561 -163.27032) (xy 51.488915 -163.319907)
			(xy 51.459441 -163.365766) (xy 51.423741 -163.406963) (xy 51.38254 -163.44266) (xy 51.336679 -163.47213)
			(xy 51.28709 -163.494773) (xy 51.234784 -163.510127) (xy 51.180825 -163.517881) (xy 51.153568 -163.518342)
			(xy 51.123881 -163.51776) (xy 51.065222 -163.50857) (xy 51.008695 -163.490402) (xy 50.955667 -163.463694)
			(xy 50.907418 -163.429091) (xy 50.865114 -163.38743) (xy 50.84699 -163.36391) (xy 50.838564 -163.353303)
			(xy 50.817251 -163.336596) (xy 50.792297 -163.326077) (xy 50.765456 -163.322487) (xy 50.738615 -163.326077)
			(xy 50.713661 -163.336596) (xy 50.692348 -163.353303) (xy 50.683922 -163.36391) (xy 50.665776 -163.387412)
			(xy 50.623474 -163.429073) (xy 50.575229 -163.463678) (xy 50.522206 -163.490392) (xy 50.465685 -163.50857)
			(xy 50.40703 -163.517774) (xy 50.377344 -163.518342) (xy 50.350092 -163.517814) (xy 50.296141 -163.510063)
			(xy 50.243842 -163.494712) (xy 50.194261 -163.472074) (xy 50.148406 -163.44261) (xy 50.107212 -163.406919)
			(xy 50.071517 -163.365729) (xy 50.042047 -163.319878) (xy 50.019404 -163.270299) (xy 50.004047 -163.218002)
			(xy 49.996289 -163.164052) (xy 35.979608 -163.164052) (xy 35.979608 -164.433688) (xy 43.480986 -164.433688)
			(xy 43.480986 -164.348992) (xy 43.489037 -164.264678) (xy 43.505066 -164.181512) (xy 43.528927 -164.100245)
			(xy 43.560406 -164.021615) (xy 43.599217 -163.946334) (xy 43.645007 -163.875082) (xy 43.697363 -163.808506)
			(xy 43.755811 -163.747208) (xy 43.819821 -163.691743) (xy 43.888813 -163.642614) (xy 43.962163 -163.600265)
			(xy 44.039206 -163.565081) (xy 44.119245 -163.537379) (xy 44.201554 -163.517411) (xy 44.285389 -163.505358)
			(xy 44.36999 -163.501328) (xy 44.454591 -163.505358) (xy 44.538426 -163.517411) (xy 44.620735 -163.537379)
			(xy 44.700774 -163.565081) (xy 44.777817 -163.600265) (xy 44.851167 -163.642614) (xy 44.920159 -163.691743)
			(xy 44.984169 -163.747208) (xy 45.042617 -163.808506) (xy 45.094973 -163.875082) (xy 45.140763 -163.946334)
			(xy 45.179574 -164.021615) (xy 45.211053 -164.100245) (xy 45.234914 -164.181512) (xy 45.250943 -164.264678)
			(xy 45.258994 -164.348992) (xy 45.259498 -164.39134) (xy 45.258994 -164.433688) (xy 45.250943 -164.518002)
			(xy 45.234914 -164.601168) (xy 45.211053 -164.682435) (xy 45.179574 -164.761065) (xy 45.140763 -164.836346)
			(xy 45.094973 -164.907598) (xy 45.042617 -164.974174) (xy 44.984169 -165.035472) (xy 44.920159 -165.090937)
			(xy 44.851167 -165.140066) (xy 44.777817 -165.182415) (xy 44.700774 -165.217599) (xy 44.620735 -165.245301)
			(xy 44.603629 -165.249451) (xy 50.206652 -165.249451) (xy 50.206652 -165.194949) (xy 50.214408 -165.141001)
			(xy 50.229762 -165.088707) (xy 50.252401 -165.039129) (xy 50.281865 -164.993277) (xy 50.317554 -164.952086)
			(xy 50.358742 -164.916392) (xy 50.40459 -164.886922) (xy 50.454165 -164.864277) (xy 50.506458 -164.848917)
			(xy 50.560405 -164.841155) (xy 50.587656 -164.840666) (xy 50.617561 -164.841202) (xy 50.67664 -164.850514)
			(xy 50.705258 -164.859208) (xy 50.719167 -164.863239) (xy 50.748099 -164.864148) (xy 50.776118 -164.856883)
			(xy 50.800963 -164.842032) (xy 50.820629 -164.820792) (xy 50.833527 -164.794879) (xy 50.836576 -164.780722)
			(xy 50.843165 -164.747884) (xy 50.866284 -164.685031) (xy 50.88255 -164.655754) (xy 50.889618 -164.642804)
			(xy 50.896647 -164.614161) (xy 50.895197 -164.584704) (xy 50.885389 -164.55689) (xy 50.868042 -164.533039)
			(xy 50.844601 -164.515141) (xy 50.830988 -164.50945) (xy 50.80422 -164.498735) (xy 50.753979 -164.47045)
			(xy 50.70857 -164.434922) (xy 50.669027 -164.392963) (xy 50.636253 -164.345528) (xy 50.610993 -164.2937)
			(xy 50.593825 -164.23866) (xy 50.585139 -164.181662) (xy 50.584608 -164.152834) (xy 50.585094 -164.125583)
			(xy 50.59285 -164.071635) (xy 50.608205 -164.01934) (xy 50.630847 -163.969763) (xy 50.660313 -163.923913)
			(xy 50.696004 -163.882722) (xy 50.737195 -163.847031) (xy 50.783045 -163.817565) (xy 50.832622 -163.794923)
			(xy 50.884917 -163.779568) (xy 50.938865 -163.771812) (xy 50.993367 -163.771812) (xy 51.047315 -163.779568)
			(xy 51.09961 -163.794923) (xy 51.149187 -163.817565) (xy 51.195037 -163.847031) (xy 51.236228 -163.882722)
			(xy 51.271919 -163.923913) (xy 51.301385 -163.969763) (xy 51.324027 -164.01934) (xy 51.339382 -164.071635)
			(xy 51.347138 -164.125583) (xy 51.347624 -164.152834) (xy 51.347239 -164.17807) (xy 51.340617 -164.228104)
			(xy 51.32744 -164.276824) (xy 51.30794 -164.323376) (xy 51.295554 -164.345366) (xy 51.28846 -164.358303)
			(xy 51.281434 -164.386951) (xy 51.282888 -164.416412) (xy 51.292701 -164.444229) (xy 51.310054 -164.468081)
			(xy 51.3335 -164.48598) (xy 51.347116 -164.49167) (xy 51.373892 -164.502366) (xy 51.424134 -164.530654)
			(xy 51.469543 -164.566184) (xy 51.509085 -164.608146) (xy 51.541859 -164.655583) (xy 51.567117 -164.707414)
			(xy 51.584283 -164.762457) (xy 51.592966 -164.819457) (xy 51.593496 -164.848286) (xy 51.593032 -164.875539)
			(xy 51.585276 -164.929491) (xy 51.569921 -164.981789) (xy 51.54728 -165.03137) (xy 51.517812 -165.077224)
			(xy 51.482118 -165.118417) (xy 51.440925 -165.154111) (xy 51.395072 -165.183579) (xy 51.345491 -165.206221)
			(xy 51.293193 -165.221576) (xy 51.239241 -165.229331) (xy 51.211988 -165.229794) (xy 51.182083 -165.229273)
			(xy 51.123003 -165.219951) (xy 51.094386 -165.211252) (xy 51.080457 -165.207302) (xy 51.051539 -165.206385)
			(xy 51.02353 -165.213636) (xy 50.998691 -165.228471) (xy 50.979026 -165.249693) (xy 50.966122 -165.275589)
			(xy 50.963068 -165.289738) (xy 50.957919 -165.315816) (xy 50.941346 -165.36632) (xy 50.917921 -165.414034)
			(xy 50.888096 -165.458032) (xy 50.852451 -165.497463) (xy 50.811676 -165.531561) (xy 50.76656 -165.559667)
			(xy 50.717979 -165.581236) (xy 50.666873 -165.595849) (xy 50.614233 -165.603225) (xy 50.587656 -165.603682)
			(xy 50.560405 -165.603245) (xy 50.506458 -165.595483) (xy 50.454165 -165.580123) (xy 50.40459 -165.557478)
			(xy 50.358742 -165.528008) (xy 50.317554 -165.492314) (xy 50.281865 -165.451123) (xy 50.252401 -165.405271)
			(xy 50.229762 -165.355693) (xy 50.214408 -165.303399) (xy 50.206652 -165.249451) (xy 44.603629 -165.249451)
			(xy 44.538426 -165.265269) (xy 44.454591 -165.277322) (xy 44.36999 -165.281353) (xy 44.285389 -165.277322)
			(xy 44.201554 -165.265269) (xy 44.119245 -165.245301) (xy 44.039206 -165.217599) (xy 43.962163 -165.182415)
			(xy 43.888813 -165.140066) (xy 43.819821 -165.090937) (xy 43.755811 -165.035472) (xy 43.697363 -164.974174)
			(xy 43.645007 -164.907598) (xy 43.599217 -164.836346) (xy 43.560406 -164.761065) (xy 43.528927 -164.682435)
			(xy 43.505066 -164.601168) (xy 43.489037 -164.518002) (xy 43.480986 -164.433688) (xy 35.979608 -164.433688)
			(xy 35.979608 -167.71747) (xy 50.99304 -167.71747) (xy 50.993427 -167.690214) (xy 51.001189 -167.636258)
			(xy 51.016552 -167.583956) (xy 51.039201 -167.534372) (xy 51.068677 -167.488517) (xy 51.104379 -167.447323)
			(xy 51.145579 -167.41163) (xy 51.191441 -167.382164) (xy 51.241029 -167.359524) (xy 51.293334 -167.344173)
			(xy 51.347292 -167.336422) (xy 51.374548 -167.335962) (xy 51.402122 -167.336442) (xy 51.456695 -167.344388)
			(xy 51.509556 -167.360109) (xy 51.559603 -167.383276) (xy 51.605792 -167.413408) (xy 51.647163 -167.449875)
			(xy 51.665378 -167.470582) (xy 51.675276 -167.48148) (xy 51.699926 -167.497555) (xy 51.728134 -167.505939)
			(xy 51.757562 -167.505939) (xy 51.78577 -167.497555) (xy 51.81042 -167.48148) (xy 51.820318 -167.470582)
			(xy 51.838512 -167.449855) (xy 51.879885 -167.413387) (xy 51.926079 -167.383257) (xy 51.97613 -167.360094)
			(xy 52.028995 -167.344381) (xy 52.083572 -167.336445) (xy 52.111148 -167.335962) (xy 52.137649 -167.336415)
			(xy 52.19014 -167.343762) (xy 52.241107 -167.358307) (xy 52.289569 -167.37977) (xy 52.334592 -167.407737)
			(xy 52.355242 -167.424354) (xy 52.367396 -167.433784) (xy 52.395794 -167.445573) (xy 52.426411 -167.448397)
			(xy 52.456486 -167.442003) (xy 52.483306 -167.426967) (xy 52.504451 -167.404645) (xy 52.511706 -167.39108)
			(xy 52.523817 -167.367395) (xy 52.553737 -167.323413) (xy 52.589605 -167.28413) (xy 52.630693 -167.250345)
			(xy 52.653184 -167.23614) (xy 52.665431 -167.228248) (xy 52.685104 -167.206769) (xy 52.697907 -167.180607)
			(xy 52.702796 -167.151894) (xy 52.699373 -167.122969) (xy 52.694078 -167.109394) (xy 52.684593 -167.086182)
			(xy 52.671241 -167.03785) (xy 52.664511 -166.988161) (xy 52.664106 -166.96309) (xy 52.66454 -166.938021)
			(xy 52.671286 -166.888338) (xy 52.684614 -166.840004) (xy 52.694078 -166.816786) (xy 52.699333 -166.803207)
			(xy 52.702713 -166.774299) (xy 52.697811 -166.74561) (xy 52.685024 -166.719464) (xy 52.665389 -166.69798)
			(xy 52.653184 -166.69004) (xy 52.630024 -166.675514) (xy 52.587899 -166.640668) (xy 52.551317 -166.600041)
			(xy 52.521063 -166.554506) (xy 52.497786 -166.505039) (xy 52.481986 -166.452703) (xy 52.474001 -166.398619)
			(xy 52.474003 -166.34395) (xy 52.481993 -166.289867) (xy 52.497797 -166.237532) (xy 52.521079 -166.188067)
			(xy 52.551336 -166.142534) (xy 52.587922 -166.101911) (xy 52.630049 -166.067068) (xy 52.653184 -166.0525)
			(xy 52.66539 -166.044551) (xy 52.685063 -166.023088) (xy 52.697871 -165.996941) (xy 52.702771 -165.968241)
			(xy 52.699363 -165.939326) (xy 52.694078 -165.925754) (xy 52.684581 -165.902547) (xy 52.671233 -165.854213)
			(xy 52.664508 -165.804522) (xy 52.664106 -165.77945) (xy 52.664627 -165.751565) (xy 52.672939 -165.696418)
			(xy 52.689377 -165.643126) (xy 52.713575 -165.59288) (xy 52.744991 -165.546801) (xy 52.782924 -165.505919)
			(xy 52.826526 -165.471147) (xy 52.874824 -165.443262) (xy 52.926739 -165.422887) (xy 52.98111 -165.410477)
			(xy 53.036724 -165.40631) (xy 53.092338 -165.410477) (xy 53.146709 -165.422887) (xy 53.198624 -165.443262)
			(xy 53.246922 -165.471147) (xy 53.290524 -165.505919) (xy 53.328457 -165.546801) (xy 53.359873 -165.59288)
			(xy 53.384071 -165.643126) (xy 53.400509 -165.696418) (xy 53.408821 -165.751565) (xy 53.409342 -165.77945)
			(xy 53.408875 -165.806782) (xy 53.400906 -165.860863) (xy 53.385118 -165.913198) (xy 53.36185 -165.962662)
			(xy 53.331601 -166.008195) (xy 53.295022 -166.048817) (xy 53.252897 -166.083655) (xy 53.229764 -166.09822)
			(xy 53.217537 -166.106138) (xy 53.19787 -166.127612) (xy 53.185068 -166.153767) (xy 53.180173 -166.182472)
			(xy 53.183584 -166.211392) (xy 53.18887 -166.224966) (xy 53.198345 -166.248181) (xy 53.211701 -166.296512)
			(xy 53.218435 -166.346199) (xy 53.218842 -166.37127) (xy 53.218431 -166.39634) (xy 53.211677 -166.446023)
			(xy 53.198339 -166.494357) (xy 53.18887 -166.517574) (xy 53.183624 -166.531151) (xy 53.180262 -166.560051)
			(xy 53.185173 -166.588729) (xy 53.197961 -166.614863) (xy 53.217591 -166.636338) (xy 53.229764 -166.64432)
			(xy 53.252885 -166.658903) (xy 53.295003 -166.693747) (xy 53.331579 -166.734369) (xy 53.361829 -166.779898)
			(xy 53.385103 -166.829358) (xy 53.400902 -166.881688) (xy 53.408888 -166.935764) (xy 53.408889 -166.990426)
			(xy 53.400905 -167.044502) (xy 53.385107 -167.096832) (xy 53.361834 -167.146292) (xy 53.331585 -167.191823)
			(xy 53.29501 -167.232446) (xy 53.252893 -167.267291) (xy 53.229764 -167.28186) (xy 53.217509 -167.289739)
			(xy 53.197842 -167.311225) (xy 53.185043 -167.33739) (xy 53.180156 -167.366104) (xy 53.183577 -167.39503)
			(xy 53.18887 -167.408606) (xy 53.198357 -167.431817) (xy 53.211708 -167.480149) (xy 53.218438 -167.529838)
			(xy 53.218842 -167.55491) (xy 53.21837 -167.581752) (xy 53.210665 -167.634881) (xy 53.195416 -167.686354)
			(xy 53.172938 -167.735106) (xy 53.143697 -167.780127) (xy 53.108298 -167.820487) (xy 53.067473 -167.855349)
			(xy 53.022069 -167.883993) (xy 52.973024 -167.905824) (xy 52.947316 -167.913558) (xy 52.932841 -167.918276)
			(xy 52.907286 -167.934788) (xy 52.887726 -167.958092) (xy 52.875894 -167.986122) (xy 52.87284 -168.016393)
			(xy 52.878835 -168.046222) (xy 52.885594 -168.059862) (xy 52.900228 -168.088008) (xy 52.920955 -168.147959)
			(xy 52.931453 -168.210517) (xy 52.932076 -168.242234) (xy 52.931855 -168.260253) (xy 52.928421 -168.296128)
			(xy 52.925218 -168.313862) (xy 52.922936 -168.329077) (xy 52.926453 -168.359622) (xy 52.938901 -168.387736)
			(xy 52.959153 -168.410871) (xy 52.985373 -168.426931) (xy 53.000148 -168.43121) (xy 53.027191 -168.438611)
			(xy 53.078917 -168.460241) (xy 53.126922 -168.489205) (xy 53.170174 -168.52488) (xy 53.207741 -168.566499)
			(xy 53.238815 -168.613165) (xy 53.262728 -168.663876) (xy 53.278965 -168.71754) (xy 53.287177 -168.773001)
			(xy 53.287676 -168.801034) (xy 53.287254 -168.828288) (xy 53.279492 -168.882239) (xy 53.264131 -168.934537)
			(xy 53.241483 -168.984117) (xy 53.21201 -169.029968) (xy 53.176312 -169.071159) (xy 53.135115 -169.10685)
			(xy 53.089259 -169.136315) (xy 53.039675 -169.158954) (xy 52.987375 -169.174306) (xy 52.933422 -169.182058)
			(xy 52.906168 -169.182542) (xy 52.878594 -169.18205) (xy 52.824022 -169.174105) (xy 52.771161 -169.158387)
			(xy 52.721115 -169.135222) (xy 52.674925 -169.105093) (xy 52.633554 -169.068628) (xy 52.615338 -169.047922)
			(xy 52.60544 -169.037024) (xy 52.58079 -169.020949) (xy 52.552582 -169.012565) (xy 52.523154 -169.012565)
			(xy 52.494946 -169.020949) (xy 52.470296 -169.037024) (xy 52.460398 -169.047922) (xy 52.442183 -169.068628)
			(xy 52.400812 -169.105093) (xy 52.354622 -169.13522) (xy 52.304575 -169.158383) (xy 52.251714 -169.174099)
			(xy 52.197142 -169.182039) (xy 52.141994 -169.182039) (xy 52.087422 -169.174099) (xy 52.034561 -169.158383)
			(xy 51.984514 -169.13522) (xy 51.938324 -169.105093) (xy 51.896953 -169.068628) (xy 51.878738 -169.047922)
			(xy 51.86884 -169.037024) (xy 51.84419 -169.020949) (xy 51.815982 -169.012565) (xy 51.786554 -169.012565)
			(xy 51.758346 -169.020949) (xy 51.733696 -169.037024) (xy 51.723798 -169.047922) (xy 51.705596 -169.068642)
			(xy 51.664225 -169.10511) (xy 51.618033 -169.135241) (xy 51.567983 -169.158405) (xy 51.515119 -169.17412)
			(xy 51.460543 -169.182058) (xy 51.432968 -169.182542) (xy 51.405718 -169.182052) (xy 51.351772 -169.174292)
			(xy 51.299479 -169.158935) (xy 51.249904 -169.136292) (xy 51.204055 -169.106826) (xy 51.162866 -169.071135)
			(xy 51.127175 -169.029946) (xy 51.097709 -168.984098) (xy 51.075066 -168.934523) (xy 51.059708 -168.88223)
			(xy 51.051948 -168.828284) (xy 51.05146 -168.801034) (xy 51.052043 -168.773181) (xy 51.060161 -168.71807)
			(xy 51.0762 -168.664722) (xy 51.09982 -168.614272) (xy 51.130519 -168.567788) (xy 51.167647 -168.526258)
			(xy 51.210414 -168.490563) (xy 51.257914 -168.461461) (xy 51.309138 -168.439569) (xy 51.33594 -168.431972)
			(xy 51.350063 -168.427719) (xy 51.375204 -168.41232) (xy 51.394916 -168.390396) (xy 51.407566 -168.363764)
			(xy 51.412104 -168.334632) (xy 51.410616 -168.319958) (xy 51.408945 -168.306942) (xy 51.407166 -168.280757)
			(xy 51.40706 -168.267634) (xy 51.407158 -168.253485) (xy 51.409189 -168.225262) (xy 51.411124 -168.211246)
			(xy 51.412683 -168.197896) (xy 51.409585 -168.171209) (xy 51.39962 -168.146259) (xy 51.38348 -168.124781)
			(xy 51.362288 -168.108267) (xy 51.337516 -168.097867) (xy 51.324256 -168.095676) (xy 51.297113 -168.09153)
			(xy 51.244287 -168.076561) (xy 51.194152 -168.054174) (xy 51.147744 -168.024832) (xy 51.106021 -167.989141)
			(xy 51.069844 -167.947838) (xy 51.039961 -167.901777) (xy 51.016989 -167.851907) (xy 51.001402 -167.79926)
			(xy 50.993522 -167.744923) (xy 50.99304 -167.71747) (xy 35.979608 -167.71747) (xy 35.979608 -169.407078)
			(xy 36.374303 -169.801794) (xy 43.431209 -169.801794) (xy 43.435245 -169.718347) (xy 43.447317 -169.635679)
			(xy 43.46731 -169.554562) (xy 43.495039 -169.475753) (xy 43.530245 -169.399988) (xy 43.572599 -169.327975)
			(xy 43.621705 -169.260386) (xy 43.677106 -169.197852) (xy 43.738283 -169.140957) (xy 43.804666 -169.090231)
			(xy 43.875634 -169.04615) (xy 43.950526 -169.009124) (xy 44.028642 -168.979498) (xy 44.109252 -168.95755)
			(xy 44.191604 -168.943485) (xy 44.27493 -168.937433) (xy 44.35845 -168.939452) (xy 44.441386 -168.949522)
			(xy 44.522962 -168.96755) (xy 44.602418 -168.993367) (xy 44.679011 -169.026732) (xy 44.752027 -169.067333)
			(xy 44.820783 -169.114792) (xy 44.884637 -169.168665) (xy 44.942994 -169.22845) (xy 44.995309 -169.293587)
			(xy 45.041092 -169.36347) (xy 45.079917 -169.437445) (xy 45.111422 -169.514822) (xy 45.135311 -169.594879)
			(xy 45.151362 -169.676867) (xy 45.159425 -169.760022) (xy 45.15993 -169.801794) (xy 45.159425 -169.843566)
			(xy 45.151362 -169.926721) (xy 45.135311 -170.008709) (xy 45.111422 -170.088766) (xy 45.079917 -170.166143)
			(xy 45.041092 -170.240118) (xy 44.995309 -170.310001) (xy 44.942994 -170.375138) (xy 44.884637 -170.434923)
			(xy 44.820783 -170.488796) (xy 44.752027 -170.536255) (xy 44.679011 -170.576856) (xy 44.602418 -170.610221)
			(xy 44.522962 -170.636038) (xy 44.441386 -170.654066) (xy 44.35845 -170.664136) (xy 44.27493 -170.666155)
			(xy 44.191604 -170.660103) (xy 44.109252 -170.646038) (xy 44.028642 -170.62409) (xy 43.950526 -170.594464)
			(xy 43.875634 -170.557438) (xy 43.804666 -170.513357) (xy 43.738283 -170.462631) (xy 43.677106 -170.405736)
			(xy 43.621705 -170.343202) (xy 43.572599 -170.275613) (xy 43.530245 -170.2036) (xy 43.495039 -170.127835)
			(xy 43.46731 -170.049026) (xy 43.447317 -169.967909) (xy 43.435245 -169.885241) (xy 43.431209 -169.801794)
			(xy 36.374303 -169.801794) (xy 37.428602 -170.856148) (xy 50.017172 -170.856148) (xy 50.017649 -170.828574)
			(xy 50.025597 -170.774002) (xy 50.041318 -170.721142) (xy 50.064486 -170.671096) (xy 50.094617 -170.624907)
			(xy 50.131084 -170.583538) (xy 50.173128 -170.54785) (xy 50.196242 -170.532806) (xy 50.208147 -170.524733)
			(xy 50.227333 -170.503326) (xy 50.239787 -170.477417) (xy 50.244521 -170.449062) (xy 50.24116 -170.420513)
			(xy 50.229971 -170.394033) (xy 50.21184 -170.371725) (xy 50.200306 -170.363134) (xy 50.178981 -170.347755)
			(xy 50.140292 -170.312157) (xy 50.10686 -170.27158) (xy 50.079321 -170.226795) (xy 50.058196 -170.178651)
			(xy 50.043886 -170.128062) (xy 50.036663 -170.075985) (xy 50.036222 -170.049698) (xy 50.036708 -170.022447)
			(xy 50.044464 -169.968499) (xy 50.059819 -169.916204) (xy 50.082461 -169.866627) (xy 50.111927 -169.820777)
			(xy 50.147618 -169.779586) (xy 50.188809 -169.743895) (xy 50.234659 -169.714429) (xy 50.284236 -169.691787)
			(xy 50.336531 -169.676432) (xy 50.390479 -169.668676) (xy 50.444981 -169.668676) (xy 50.498929 -169.676432)
			(xy 50.551224 -169.691787) (xy 50.600801 -169.714429) (xy 50.646651 -169.743895) (xy 50.687842 -169.779586)
			(xy 50.723533 -169.820777) (xy 50.752999 -169.866627) (xy 50.775641 -169.916204) (xy 50.790996 -169.968499)
			(xy 50.798752 -170.022447) (xy 50.799238 -170.049698) (xy 50.798792 -170.077273) (xy 50.790838 -170.131847)
			(xy 50.775111 -170.184707) (xy 50.751938 -170.234752) (xy 50.721802 -170.280941) (xy 50.685331 -170.32231)
			(xy 50.643284 -170.357997) (xy 50.620168 -170.37304) (xy 50.608219 -170.381053) (xy 50.58903 -170.402473)
			(xy 50.576576 -170.428395) (xy 50.571846 -170.456762) (xy 50.575216 -170.485322) (xy 50.586418 -170.51181)
			(xy 50.599378 -170.527747) (xy 52.354526 -170.527747) (xy 52.354526 -170.473253) (xy 52.362281 -170.419314)
			(xy 52.377633 -170.367027) (xy 52.40027 -170.317458) (xy 52.429731 -170.271614) (xy 52.465416 -170.23043)
			(xy 52.506598 -170.194743) (xy 52.55244 -170.16528) (xy 52.602009 -170.14264) (xy 52.654294 -170.127285)
			(xy 52.708233 -170.119528) (xy 52.73548 -170.11904) (xy 52.765603 -170.119626) (xy 52.825098 -170.129104)
			(xy 52.882366 -170.147811) (xy 52.935983 -170.175284) (xy 52.984619 -170.210839) (xy 53.006244 -170.231816)
			(xy 53.015966 -170.241034) (xy 53.039128 -170.254479) (xy 53.064989 -170.261441) (xy 53.091771 -170.261441)
			(xy 53.117632 -170.254479) (xy 53.140794 -170.241034) (xy 53.150516 -170.231816) (xy 53.172113 -170.210806)
			(xy 53.220749 -170.175241) (xy 53.274373 -170.147766) (xy 53.331649 -170.129065) (xy 53.391154 -170.119603)
			(xy 53.42128 -170.11904) (xy 53.448537 -170.119406) (xy 53.502497 -170.127161) (xy 53.554804 -170.142517)
			(xy 53.604393 -170.165162) (xy 53.650254 -170.194633) (xy 53.691455 -170.230331) (xy 53.727155 -170.27153)
			(xy 53.756629 -170.317389) (xy 53.779276 -170.366977) (xy 53.794635 -170.419283) (xy 53.802393 -170.473243)
			(xy 53.802393 -170.527757) (xy 53.794635 -170.581717) (xy 53.779276 -170.634023) (xy 53.756629 -170.683611)
			(xy 53.727155 -170.72947) (xy 53.691455 -170.770669) (xy 53.650254 -170.806367) (xy 53.604393 -170.835838)
			(xy 53.554804 -170.858483) (xy 53.502497 -170.873839) (xy 53.448537 -170.881594) (xy 53.42128 -170.882056)
			(xy 53.391156 -170.881496) (xy 53.331659 -170.872012) (xy 53.274391 -170.853299) (xy 53.220775 -170.82582)
			(xy 53.172141 -170.79026) (xy 53.150516 -170.76928) (xy 53.140794 -170.760062) (xy 53.117632 -170.746617)
			(xy 53.091771 -170.739655) (xy 53.064989 -170.739655) (xy 53.039128 -170.746617) (xy 53.015966 -170.760062)
			(xy 53.006244 -170.76928) (xy 52.98462 -170.790261) (xy 52.935991 -170.82583) (xy 52.882375 -170.85331)
			(xy 52.825104 -170.872018) (xy 52.765604 -170.881488) (xy 52.73548 -170.882056) (xy 52.708233 -170.881472)
			(xy 52.654294 -170.873715) (xy 52.602009 -170.85836) (xy 52.55244 -170.83572) (xy 52.506598 -170.806257)
			(xy 52.465416 -170.77057) (xy 52.429731 -170.729386) (xy 52.40027 -170.683542) (xy 52.377633 -170.633973)
			(xy 52.362281 -170.581686) (xy 52.354526 -170.527747) (xy 50.599378 -170.527747) (xy 50.604562 -170.534121)
			(xy 50.616104 -170.542712) (xy 50.637453 -170.558059) (xy 50.676141 -170.593663) (xy 50.709571 -170.634245)
			(xy 50.737107 -170.679036) (xy 50.758228 -170.727185) (xy 50.772533 -170.777779) (xy 50.779751 -170.829859)
			(xy 50.780188 -170.856148) (xy 50.779702 -170.883399) (xy 50.771946 -170.937347) (xy 50.756591 -170.989642)
			(xy 50.733949 -171.039219) (xy 50.704483 -171.085069) (xy 50.668792 -171.12626) (xy 50.627601 -171.161951)
			(xy 50.581751 -171.191417) (xy 50.532174 -171.214059) (xy 50.479879 -171.229414) (xy 50.425931 -171.23717)
			(xy 50.371429 -171.23717) (xy 50.317481 -171.229414) (xy 50.265186 -171.214059) (xy 50.215609 -171.191417)
			(xy 50.169759 -171.161951) (xy 50.128568 -171.12626) (xy 50.092877 -171.085069) (xy 50.063411 -171.039219)
			(xy 50.040769 -170.989642) (xy 50.025414 -170.937347) (xy 50.017658 -170.883399) (xy 50.017172 -170.856148)
			(xy 37.428602 -170.856148) (xy 38.91664 -172.344264) (xy 43.406818 -172.344264) (xy 43.406818 -172.259568)
			(xy 43.414869 -172.175254) (xy 43.430898 -172.092088) (xy 43.454759 -172.010821) (xy 43.486238 -171.932191)
			(xy 43.525049 -171.85691) (xy 43.570839 -171.785658) (xy 43.623195 -171.719082) (xy 43.681643 -171.657784)
			(xy 43.745653 -171.602319) (xy 43.814645 -171.55319) (xy 43.887995 -171.510841) (xy 43.965038 -171.475657)
			(xy 44.045077 -171.447955) (xy 44.127386 -171.427987) (xy 44.211221 -171.415934) (xy 44.295822 -171.411904)
			(xy 44.380423 -171.415934) (xy 44.464258 -171.427987) (xy 44.546567 -171.447955) (xy 44.626606 -171.475657)
			(xy 44.703649 -171.510841) (xy 44.776999 -171.55319) (xy 44.845991 -171.602319) (xy 44.910001 -171.657784)
			(xy 44.968449 -171.719082) (xy 45.020805 -171.785658) (xy 45.066595 -171.85691) (xy 45.105406 -171.932191)
			(xy 45.136885 -172.010821) (xy 45.160746 -172.092088) (xy 45.176775 -172.175254) (xy 45.184826 -172.259568)
			(xy 45.185173 -172.288752) (xy 48.725285 -172.288752) (xy 48.725285 -172.234248) (xy 48.733042 -172.180299)
			(xy 48.748399 -172.128003) (xy 48.771041 -172.078425) (xy 48.80051 -172.032574) (xy 48.836204 -171.991384)
			(xy 48.877396 -171.955693) (xy 48.923249 -171.926228) (xy 48.972829 -171.903589) (xy 49.025126 -171.888236)
			(xy 49.079076 -171.880483) (xy 49.106328 -171.880022) (xy 49.136703 -171.88062) (xy 49.196685 -171.89025)
			(xy 49.254384 -171.909263) (xy 49.308341 -171.937178) (xy 49.357193 -171.97329) (xy 49.37887 -171.994576)
			(xy 49.388621 -172.003887) (xy 49.411894 -172.017482) (xy 49.437911 -172.024524) (xy 49.464863 -172.024524)
			(xy 49.49088 -172.017482) (xy 49.514153 -172.003887) (xy 49.523904 -171.994576) (xy 49.54556 -171.973266)
			(xy 49.594415 -171.937152) (xy 49.648377 -171.909238) (xy 49.706081 -171.890229) (xy 49.766069 -171.880607)
			(xy 49.796446 -171.880022) (xy 49.823697 -171.880451) (xy 49.877644 -171.888213) (xy 49.929938 -171.903574)
			(xy 49.979513 -171.926219) (xy 50.025361 -171.955689) (xy 50.066549 -171.991383) (xy 50.102238 -172.032576)
			(xy 50.131703 -172.078428) (xy 50.133776 -172.082968) (xy 50.422554 -172.082968) (xy 50.426625 -172.027346)
			(xy 50.438751 -171.972909) (xy 50.458674 -171.920818) (xy 50.48597 -171.872183) (xy 50.520056 -171.82804)
			(xy 50.560205 -171.789331) (xy 50.605563 -171.75688) (xy 50.655163 -171.731379) (xy 50.707947 -171.713372)
			(xy 50.76279 -171.703242) (xy 50.818524 -171.701205) (xy 50.873961 -171.707305) (xy 50.927918 -171.721411)
			(xy 50.979247 -171.743223) (xy 51.026853 -171.772277) (xy 51.069721 -171.807952) (xy 51.106938 -171.849489)
			(xy 51.137711 -171.896002) (xy 51.161383 -171.946499) (xy 51.177451 -171.999906) (xy 51.185571 -172.055082)
			(xy 51.18608 -172.082968) (xy 51.185571 -172.110854) (xy 51.177451 -172.16603) (xy 51.161383 -172.219437)
			(xy 51.137711 -172.269934) (xy 51.106938 -172.316447) (xy 51.069721 -172.357984) (xy 51.026853 -172.393659)
			(xy 50.979247 -172.422713) (xy 50.927918 -172.444525) (xy 50.873961 -172.458631) (xy 50.818524 -172.464731)
			(xy 50.76279 -172.462694) (xy 50.707947 -172.452564) (xy 50.655163 -172.434557) (xy 50.605563 -172.409056)
			(xy 50.560205 -172.376605) (xy 50.520056 -172.337896) (xy 50.48597 -172.293753) (xy 50.458674 -172.245118)
			(xy 50.438751 -172.193027) (xy 50.426625 -172.13859) (xy 50.422554 -172.082968) (xy 50.133776 -172.082968)
			(xy 50.154342 -172.128006) (xy 50.169696 -172.180301) (xy 50.177452 -172.234249) (xy 50.177452 -172.288751)
			(xy 50.169696 -172.342699) (xy 50.154342 -172.394994) (xy 50.131703 -172.444572) (xy 50.102238 -172.490424)
			(xy 50.066549 -172.531617) (xy 50.025361 -172.567311) (xy 49.979513 -172.596781) (xy 49.929938 -172.619426)
			(xy 49.877644 -172.634787) (xy 49.823697 -172.642549) (xy 49.796446 -172.643038) (xy 49.76607 -172.642468)
			(xy 49.706086 -172.632833) (xy 49.648386 -172.613814) (xy 49.59443 -172.585893) (xy 49.545579 -172.549774)
			(xy 49.523904 -172.528484) (xy 49.514176 -172.519126) (xy 49.490915 -172.50545) (xy 49.464879 -172.498363)
			(xy 49.437895 -172.498363) (xy 49.411859 -172.50545) (xy 49.388598 -172.519126) (xy 49.37887 -172.528484)
			(xy 49.357174 -172.549751) (xy 49.30833 -172.585872) (xy 49.254379 -172.613795) (xy 49.196683 -172.632814)
			(xy 49.136703 -172.642447) (xy 49.106328 -172.643038) (xy 49.079076 -172.642517) (xy 49.025126 -172.634764)
			(xy 48.972829 -172.619411) (xy 48.923249 -172.596772) (xy 48.877396 -172.567307) (xy 48.836204 -172.531616)
			(xy 48.80051 -172.490426) (xy 48.771041 -172.444575) (xy 48.748399 -172.394997) (xy 48.733042 -172.342701)
			(xy 48.725285 -172.288752) (xy 45.185173 -172.288752) (xy 45.18533 -172.301916) (xy 45.184826 -172.344264)
			(xy 45.176775 -172.428578) (xy 45.160746 -172.511744) (xy 45.136885 -172.593011) (xy 45.105406 -172.671641)
			(xy 45.066595 -172.746922) (xy 45.020805 -172.818174) (xy 44.968449 -172.88475) (xy 44.910001 -172.946048)
			(xy 44.845991 -173.001513) (xy 44.776999 -173.050642) (xy 44.703649 -173.092991) (xy 44.626606 -173.128175)
			(xy 44.546567 -173.155877) (xy 44.464258 -173.175845) (xy 44.380423 -173.187898) (xy 44.295822 -173.191929)
			(xy 44.211221 -173.187898) (xy 44.127386 -173.175845) (xy 44.045077 -173.155877) (xy 43.965038 -173.128175)
			(xy 43.887995 -173.092991) (xy 43.814645 -173.050642) (xy 43.745653 -173.001513) (xy 43.681643 -172.946048)
			(xy 43.623195 -172.88475) (xy 43.570839 -172.818174) (xy 43.525049 -172.746922) (xy 43.486238 -172.671641)
			(xy 43.454759 -172.593011) (xy 43.430898 -172.511744) (xy 43.414869 -172.428578) (xy 43.406818 -172.344264)
			(xy 38.91664 -172.344264) (xy 40.831516 -174.25924) (xy 49.041558 -174.25924) (xy 49.059728 -174.239613)
			(xy 49.100598 -174.205112) (xy 49.145883 -174.176654) (xy 49.194698 -174.154797) (xy 49.246087 -174.139968)
			(xy 49.299042 -174.132457) (xy 49.325784 -174.131986) (xy 49.350659 -174.132354) (xy 49.399986 -174.138825)
			(xy 49.448052 -174.151659) (xy 49.494039 -174.170637) (xy 49.537167 -174.195438) (xy 49.557178 -174.210218)
			(xy 49.569675 -174.219055) (xy 49.598406 -174.229566) (xy 49.62896 -174.231114) (xy 49.658606 -174.223559)
			(xy 49.684693 -174.207578) (xy 49.704889 -174.184599) (xy 49.71161 -174.170848) (xy 49.723254 -174.14601)
			(xy 49.752631 -174.099682) (xy 49.788337 -174.058036) (xy 49.829637 -174.021931) (xy 49.875681 -173.99211)
			(xy 49.925519 -173.969188) (xy 49.978125 -173.953636) (xy 50.032416 -173.945775) (xy 50.059844 -173.945296)
			(xy 50.087093 -173.945777) (xy 50.141037 -173.953538) (xy 50.193327 -173.968898) (xy 50.242899 -173.991541)
			(xy 50.288745 -174.021009) (xy 50.32993 -174.056701) (xy 50.365617 -174.097891) (xy 50.39508 -174.143739)
			(xy 50.417718 -174.193314) (xy 50.433071 -174.245606) (xy 50.440826 -174.29955) (xy 50.440826 -174.35405)
			(xy 50.433071 -174.407994) (xy 50.417718 -174.460286) (xy 50.39508 -174.509861) (xy 50.365617 -174.555709)
			(xy 50.32993 -174.596899) (xy 50.288745 -174.632591) (xy 50.242899 -174.662059) (xy 50.193327 -174.684702)
			(xy 50.141037 -174.700062) (xy 50.087093 -174.707823) (xy 50.059844 -174.708312) (xy 50.03497 -174.707929)
			(xy 49.985643 -174.701462) (xy 49.937577 -174.688631) (xy 49.89159 -174.669656) (xy 49.848462 -174.644859)
			(xy 49.82845 -174.63008) (xy 49.815931 -174.621277) (xy 49.787208 -174.610762) (xy 49.75666 -174.60921)
			(xy 49.72702 -174.616758) (xy 49.700935 -174.632732) (xy 49.68074 -174.655703) (xy 49.674018 -174.66945)
			(xy 49.662351 -174.694277) (xy 49.632977 -174.740604) (xy 49.597274 -174.78225) (xy 49.555977 -174.818355)
			(xy 49.509937 -174.848178) (xy 49.460103 -174.871102) (xy 49.407499 -174.886657) (xy 49.353211 -174.894521)
			(xy 49.325784 -174.895002) (xy 49.299039 -174.894542) (xy 49.246077 -174.887051) (xy 49.194682 -174.872231)
			(xy 49.145862 -174.850373) (xy 49.100576 -174.821907) (xy 49.059713 -174.787391) (xy 49.041558 -174.767748)
			(xy 40.726106 -174.767748) (xy 40.701124 -174.767115) (xy 40.652117 -174.757379) (xy 40.605947 -174.738278)
			(xy 40.564385 -174.710545) (xy 40.546274 -174.693326) (xy 35.545268 -169.69232) (xy 35.52804 -169.674199)
			(xy 35.500221 -169.632664) (xy 35.48104 -169.586501) (xy 35.471233 -169.537482) (xy 35.470592 -169.512488)
			(xy 35.470592 -155.938728) (xy 35.471226 -155.913732) (xy 35.481028 -155.864708) (xy 35.500202 -155.818537)
			(xy 35.528012 -155.776991) (xy 35.545268 -155.758896) (xy 36.688268 -154.615896) (xy 36.688268 -143.595344)
			(xy 36.688859 -143.570359) (xy 36.698608 -143.52135) (xy 36.717721 -143.47518) (xy 36.745466 -143.433621)
			(xy 36.76269 -143.415512) (xy 42.661332 -137.516616) (xy 42.661332 -125.623828) (xy 40.161464 -123.12396)
			(xy 32.634682 -123.12396) (xy 32.149288 -123.6091) (xy 32.149288 -123.630436) (xy 32.14892 -123.657714)
			(xy 32.141216 -123.711724) (xy 32.125897 -123.764085) (xy 32.103277 -123.813731) (xy 32.073816 -123.859648)
			(xy 32.038116 -123.900902) (xy 31.996904 -123.93665) (xy 31.951021 -123.966164) (xy 31.901402 -123.988842)
			(xy 31.849058 -124.004221) (xy 31.795058 -124.011989) (xy 31.76778 -124.012452) (xy 31.74052 -124.011899)
			(xy 31.686555 -124.004134) (xy 31.634245 -123.988765) (xy 31.584656 -123.966105) (xy 31.538799 -123.936617)
			(xy 31.497606 -123.9009) (xy 31.461919 -123.859682) (xy 31.432463 -123.813803) (xy 31.409839 -123.764198)
			(xy 31.394508 -123.711877) (xy 31.386782 -123.657907) (xy 31.098236 -123.657907) (xy 31.098236 -123.909836)
			(xy 31.731458 -124.543058) (xy 31.752794 -124.543058) (xy 31.780069 -124.543519) (xy 31.834072 -124.551217)
			(xy 31.886428 -124.566527) (xy 31.93607 -124.589138) (xy 31.981985 -124.61859) (xy 32.023238 -124.65428)
			(xy 32.058986 -124.695482) (xy 32.088503 -124.741355) (xy 32.111184 -124.790965) (xy 32.126569 -124.8433)
			(xy 32.134343 -124.897292) (xy 32.13481 -124.924566) (xy 32.134345 -124.951832) (xy 32.126585 -125.005809)
			(xy 32.111219 -125.058131) (xy 32.08856 -125.107732) (xy 32.05907 -125.153601) (xy 32.023348 -125.194804)
			(xy 31.982125 -125.230502) (xy 31.936238 -125.259966) (xy 31.886624 -125.282596) (xy 31.834293 -125.297932)
			(xy 31.780312 -125.30566) (xy 31.725781 -125.305624) (xy 31.67181 -125.297824) (xy 31.619499 -125.282418)
			(xy 31.569915 -125.259722) (xy 31.524068 -125.230197) (xy 31.482892 -125.194444) (xy 31.447226 -125.153194)
			(xy 31.417796 -125.107285) (xy 31.395203 -125.057654) (xy 31.379907 -125.005311) (xy 31.37222 -124.951324)
			(xy 31.371794 -124.924058) (xy 31.371794 -124.902722) (xy 30.66415 -124.195078) (xy 30.646903 -124.17699)
			(xy 30.619167 -124.135423) (xy 30.600066 -124.089246) (xy 30.590334 -124.040232) (xy 30.589728 -124.015246)
			(xy 28.560776 -124.015246) (xy 28.560776 -124.208032) (xy 28.988004 -124.63526) (xy 29.93517 -124.63526)
			(xy 29.960166 -124.635904) (xy 30.009189 -124.645704) (xy 30.05536 -124.664875) (xy 30.096906 -124.692681)
			(xy 30.115002 -124.709936) (xy 31.105094 -125.700028) (xy 31.24327 -125.700028) (xy 31.261431 -125.680392)
			(xy 31.302303 -125.645893) (xy 31.347591 -125.617436) (xy 31.396408 -125.59558) (xy 31.447797 -125.580753)
			(xy 31.500753 -125.573245) (xy 31.527496 -125.572774) (xy 31.554748 -125.573273) (xy 31.608697 -125.581029)
			(xy 31.660992 -125.596384) (xy 31.710571 -125.619025) (xy 31.756422 -125.648492) (xy 31.797613 -125.684184)
			(xy 31.833306 -125.725375) (xy 31.862773 -125.771226) (xy 31.885414 -125.820804) (xy 31.90077 -125.8731)
			(xy 31.908527 -125.927048) (xy 31.908527 -125.981552) (xy 31.90077 -126.0355) (xy 31.89389 -126.05893)
			(xy 33.07918 -126.05893) (xy 33.083251 -126.003308) (xy 33.095377 -125.948871) (xy 33.1153 -125.89678)
			(xy 33.142596 -125.848145) (xy 33.176682 -125.804002) (xy 33.216831 -125.765293) (xy 33.262189 -125.732842)
			(xy 33.311789 -125.707341) (xy 33.364573 -125.689334) (xy 33.419416 -125.679204) (xy 33.47515 -125.677167)
			(xy 33.530587 -125.683267) (xy 33.584544 -125.697373) (xy 33.635873 -125.719185) (xy 33.683479 -125.748239)
			(xy 33.726347 -125.783914) (xy 33.763564 -125.825451) (xy 33.794337 -125.871964) (xy 33.818009 -125.922461)
			(xy 33.834077 -125.975868) (xy 33.842197 -126.031044) (xy 33.842706 -126.05893) (xy 33.842197 -126.086816)
			(xy 33.834077 -126.141992) (xy 33.818009 -126.195399) (xy 33.794337 -126.245896) (xy 33.763564 -126.292409)
			(xy 33.726347 -126.333946) (xy 33.683479 -126.369621) (xy 33.635873 -126.398675) (xy 33.584544 -126.420487)
			(xy 33.530587 -126.434593) (xy 33.47515 -126.440693) (xy 33.419416 -126.438656) (xy 33.364573 -126.428526)
			(xy 33.311789 -126.410519) (xy 33.262189 -126.385018) (xy 33.216831 -126.352567) (xy 33.176682 -126.313858)
			(xy 33.142596 -126.269715) (xy 33.1153 -126.22108) (xy 33.095377 -126.168989) (xy 33.083251 -126.114552)
			(xy 33.07918 -126.05893) (xy 31.89389 -126.05893) (xy 31.885414 -126.087796) (xy 31.862773 -126.137374)
			(xy 31.833306 -126.183225) (xy 31.797613 -126.224416) (xy 31.756422 -126.260108) (xy 31.710571 -126.289575)
			(xy 31.660992 -126.312216) (xy 31.608697 -126.327571) (xy 31.554748 -126.335327) (xy 31.527496 -126.33579)
			(xy 31.500753 -126.335293) (xy 31.447794 -126.327805) (xy 31.3964 -126.31299) (xy 31.347581 -126.29114)
			(xy 31.302294 -126.262682) (xy 31.261428 -126.228175) (xy 31.24327 -126.208536) (xy 30.999684 -126.208536)
			(xy 30.974701 -126.20792) (xy 30.925693 -126.198179) (xy 30.879523 -126.179073) (xy 30.837962 -126.151335)
			(xy 30.819852 -126.134114) (xy 29.82976 -125.144276) (xy 28.882594 -125.144276) (xy 28.857598 -125.143644)
			(xy 28.808575 -125.133838) (xy 28.762405 -125.114664) (xy 28.720858 -125.086855) (xy 28.702762 -125.0696)
			(xy 28.126436 -124.493274) (xy 28.109181 -124.475178) (xy 28.081369 -124.433634) (xy 28.062195 -124.387463)
			(xy 28.052396 -124.338438) (xy 28.05176 -124.313442) (xy 21.820378 -124.313442) (xy 21.820378 -131.616704)
			(xy 23.917148 -131.616704) (xy 23.917148 -130.542538) (xy 23.917641 -130.517551) (xy 23.925461 -130.468192)
			(xy 23.940914 -130.420667) (xy 23.963618 -130.376148) (xy 23.993014 -130.335734) (xy 24.010366 -130.317748)
			(xy 24.550116 -129.778252) (xy 24.550116 -125.47473) (xy 24.550607 -125.449756) (xy 24.558397 -125.400419)
			(xy 24.573805 -125.352907) (xy 24.596452 -125.308389) (xy 24.625781 -125.267959) (xy 24.64308 -125.24994)
			(xy 25.40889 -124.48413) (xy 25.426892 -124.4668) (xy 25.467319 -124.437433) (xy 25.511836 -124.41474)
			(xy 25.55935 -124.399277) (xy 25.608697 -124.391425) (xy 25.63368 -124.390912) (xy 26.427176 -124.390912)
			(xy 26.450773 -124.375899) (xy 26.501402 -124.352142) (xy 26.554955 -124.336024) (xy 26.610287 -124.327889)
			(xy 26.63825 -124.327412) (xy 26.665501 -124.327898) (xy 26.719449 -124.335654) (xy 26.771744 -124.351009)
			(xy 26.821321 -124.373651) (xy 26.867171 -124.403117) (xy 26.908362 -124.438808) (xy 26.944053 -124.479999)
			(xy 26.973519 -124.525849) (xy 26.996161 -124.575426) (xy 27.011516 -124.627721) (xy 27.019272 -124.681669)
			(xy 27.019272 -124.736171) (xy 27.011516 -124.790119) (xy 26.996161 -124.842414) (xy 26.973519 -124.891991)
			(xy 26.944053 -124.937841) (xy 26.908362 -124.979032) (xy 26.867171 -125.014723) (xy 26.821321 -125.044189)
			(xy 26.771744 -125.066831) (xy 26.719449 -125.082186) (xy 26.665501 -125.089942) (xy 26.63825 -125.090428)
			(xy 26.610284 -125.089958) (xy 26.554945 -125.081849) (xy 26.501385 -125.065739) (xy 26.450754 -125.041973)
			(xy 26.427176 -125.026928) (xy 25.765252 -125.026928) (xy 25.185624 -125.606302) (xy 25.185624 -126.560834)
			(xy 27.732988 -126.560834) (xy 27.737059 -126.505212) (xy 27.749185 -126.450775) (xy 27.769108 -126.398684)
			(xy 27.796404 -126.350049) (xy 27.83049 -126.305906) (xy 27.870639 -126.267197) (xy 27.915997 -126.234746)
			(xy 27.965597 -126.209245) (xy 28.018381 -126.191238) (xy 28.073224 -126.181108) (xy 28.128958 -126.179071)
			(xy 28.184395 -126.185171) (xy 28.238352 -126.199277) (xy 28.289681 -126.221089) (xy 28.337287 -126.250143)
			(xy 28.380155 -126.285818) (xy 28.417372 -126.327355) (xy 28.448145 -126.373868) (xy 28.468635 -126.417578)
			(xy 29.186376 -126.417578) (xy 29.190447 -126.361956) (xy 29.202573 -126.307519) (xy 29.222496 -126.255428)
			(xy 29.249792 -126.206793) (xy 29.283878 -126.16265) (xy 29.324027 -126.123941) (xy 29.369385 -126.09149)
			(xy 29.418985 -126.065989) (xy 29.471769 -126.047982) (xy 29.526612 -126.037852) (xy 29.582346 -126.035815)
			(xy 29.637783 -126.041915) (xy 29.69174 -126.056021) (xy 29.743069 -126.077833) (xy 29.790675 -126.106887)
			(xy 29.833543 -126.142562) (xy 29.87076 -126.184099) (xy 29.901533 -126.230612) (xy 29.925205 -126.281109)
			(xy 29.941273 -126.334516) (xy 29.949393 -126.389692) (xy 29.949902 -126.417578) (xy 29.949393 -126.445464)
			(xy 29.941273 -126.50064) (xy 29.925205 -126.554047) (xy 29.901533 -126.604544) (xy 29.87076 -126.651057)
			(xy 29.833543 -126.692594) (xy 29.790675 -126.728269) (xy 29.743069 -126.757323) (xy 29.69174 -126.779135)
			(xy 29.637783 -126.793241) (xy 29.582346 -126.799341) (xy 29.526612 -126.797304) (xy 29.471769 -126.787174)
			(xy 29.418985 -126.769167) (xy 29.369385 -126.743666) (xy 29.324027 -126.711215) (xy 29.283878 -126.672506)
			(xy 29.249792 -126.628363) (xy 29.222496 -126.579728) (xy 29.202573 -126.527637) (xy 29.190447 -126.4732)
			(xy 29.186376 -126.417578) (xy 28.468635 -126.417578) (xy 28.471817 -126.424365) (xy 28.487885 -126.477772)
			(xy 28.496005 -126.532948) (xy 28.496514 -126.560834) (xy 28.496005 -126.58872) (xy 28.487885 -126.643896)
			(xy 28.471817 -126.697303) (xy 28.448145 -126.7478) (xy 28.417372 -126.794313) (xy 28.380155 -126.83585)
			(xy 28.337287 -126.871525) (xy 28.289681 -126.900579) (xy 28.238352 -126.922391) (xy 28.184395 -126.936497)
			(xy 28.128958 -126.942597) (xy 28.073224 -126.94056) (xy 28.018381 -126.93043) (xy 27.965597 -126.912423)
			(xy 27.915997 -126.886922) (xy 27.870639 -126.854471) (xy 27.83049 -126.815762) (xy 27.796404 -126.771619)
			(xy 27.769108 -126.722984) (xy 27.749185 -126.670893) (xy 27.737059 -126.616456) (xy 27.732988 -126.560834)
			(xy 25.185624 -126.560834) (xy 25.185624 -128.364996) (xy 25.623518 -128.364996) (xy 25.627589 -128.309374)
			(xy 25.639715 -128.254937) (xy 25.659638 -128.202846) (xy 25.686934 -128.154211) (xy 25.72102 -128.110068)
			(xy 25.761169 -128.071359) (xy 25.806527 -128.038908) (xy 25.856127 -128.013407) (xy 25.908911 -127.9954)
			(xy 25.963754 -127.98527) (xy 26.019488 -127.983233) (xy 26.074925 -127.989333) (xy 26.128882 -128.003439)
			(xy 26.180211 -128.025251) (xy 26.227817 -128.054305) (xy 26.270685 -128.08998) (xy 26.307902 -128.131517)
			(xy 26.338675 -128.17803) (xy 26.362347 -128.228527) (xy 26.378415 -128.281934) (xy 26.386535 -128.33711)
			(xy 26.387044 -128.364996) (xy 26.386547 -128.392219) (xy 27.67692 -128.392219) (xy 27.676924 -128.337725)
			(xy 27.684683 -128.283785) (xy 27.70004 -128.231499) (xy 27.722681 -128.18193) (xy 27.752145 -128.136088)
			(xy 27.787834 -128.094906) (xy 27.82902 -128.059221) (xy 27.874865 -128.029761) (xy 27.924436 -128.007126)
			(xy 27.976724 -127.991775) (xy 28.030665 -127.984021) (xy 28.085159 -127.984023) (xy 28.139099 -127.99178)
			(xy 28.191386 -128.007134) (xy 28.240956 -128.029773) (xy 28.286799 -128.059236) (xy 28.327983 -128.094923)
			(xy 28.363669 -128.136107) (xy 28.393131 -128.181951) (xy 28.415769 -128.231521) (xy 28.431122 -128.283809)
			(xy 28.438878 -128.337749) (xy 28.439364 -128.364996) (xy 28.43892 -128.391702) (xy 28.431524 -128.4446)
			(xy 28.424632 -128.470406) (xy 28.421138 -128.484151) (xy 28.421089 -128.512502) (xy 28.428848 -128.539771)
			(xy 28.443814 -128.563849) (xy 28.464831 -128.582877) (xy 28.490274 -128.595383) (xy 28.518178 -128.600401)
			(xy 28.532328 -128.599438) (xy 28.56992 -128.59766) (xy 28.59717 -128.598159) (xy 28.651116 -128.605917)
			(xy 28.703408 -128.621274) (xy 28.752984 -128.643915) (xy 28.798832 -128.67338) (xy 28.840022 -128.70907)
			(xy 28.875713 -128.750258) (xy 28.90518 -128.796106) (xy 28.927822 -128.84568) (xy 28.94318 -128.897972)
			(xy 28.95094 -128.951918) (xy 28.951428 -128.979168) (xy 28.950983 -129.006005) (xy 28.943447 -129.059147)
			(xy 28.928534 -129.110708) (xy 28.906538 -129.159668) (xy 28.877895 -129.20506) (xy 28.843169 -129.245987)
			(xy 28.823412 -129.264156) (xy 28.812991 -129.274041) (xy 28.797685 -129.298332) (xy 28.789743 -129.325924)
			(xy 28.789794 -129.354636) (xy 28.797834 -129.382199) (xy 28.813226 -129.406436) (xy 28.823666 -129.416302)
			(xy 28.843522 -129.434453) (xy 28.878376 -129.475433) (xy 28.907127 -129.520903) (xy 28.929204 -129.569962)
			(xy 28.94417 -129.621636) (xy 28.951729 -129.674899) (xy 28.95219 -129.701798) (xy 28.951704 -129.729049)
			(xy 28.943948 -129.782997) (xy 28.928593 -129.835292) (xy 28.905951 -129.884869) (xy 28.876485 -129.930719)
			(xy 28.840794 -129.97191) (xy 28.799603 -130.007601) (xy 28.753753 -130.037067) (xy 28.704176 -130.059709)
			(xy 28.651881 -130.075064) (xy 28.597933 -130.08282) (xy 28.543431 -130.08282) (xy 28.489483 -130.075064)
			(xy 28.437188 -130.059709) (xy 28.387611 -130.037067) (xy 28.341761 -130.007601) (xy 28.30057 -129.97191)
			(xy 28.264879 -129.930719) (xy 28.235413 -129.884869) (xy 28.212771 -129.835292) (xy 28.197416 -129.782997)
			(xy 28.18966 -129.729049) (xy 28.189174 -129.701798) (xy 28.189663 -129.674963) (xy 28.19719 -129.621822)
			(xy 28.212094 -129.570262) (xy 28.234082 -129.521302) (xy 28.262718 -129.475909) (xy 28.297436 -129.43498)
			(xy 28.31719 -129.41681) (xy 28.327545 -129.406861) (xy 28.342854 -129.382587) (xy 28.350803 -129.355013)
			(xy 28.350764 -129.326315) (xy 28.342741 -129.298762) (xy 28.327366 -129.27453) (xy 28.316936 -129.264664)
			(xy 28.297112 -129.246479) (xy 28.262256 -129.205507) (xy 28.233501 -129.160043) (xy 28.211418 -129.110991)
			(xy 28.196444 -129.059324) (xy 28.188878 -129.006065) (xy 28.188412 -128.979168) (xy 28.188866 -128.952462)
			(xy 28.196255 -128.899564) (xy 28.203144 -128.873758) (xy 28.206593 -128.860001) (xy 28.206656 -128.831653)
			(xy 28.198909 -128.804385) (xy 28.183951 -128.780305) (xy 28.162938 -128.761277) (xy 28.137498 -128.748772)
			(xy 28.109597 -128.743759) (xy 28.095448 -128.744726) (xy 28.057856 -128.746504) (xy 28.030609 -128.745975)
			(xy 27.97667 -128.738213) (xy 27.924384 -128.722855) (xy 27.874816 -128.700212) (xy 27.828975 -128.670745)
			(xy 27.787794 -128.635055) (xy 27.752112 -128.593867) (xy 27.722654 -128.548021) (xy 27.70002 -128.498449)
			(xy 27.684671 -128.44616) (xy 27.67692 -128.392219) (xy 26.386547 -128.392219) (xy 26.386535 -128.392882)
			(xy 26.378415 -128.448058) (xy 26.362347 -128.501465) (xy 26.338675 -128.551962) (xy 26.307902 -128.598475)
			(xy 26.270685 -128.640012) (xy 26.227817 -128.675687) (xy 26.180211 -128.704741) (xy 26.128882 -128.726553)
			(xy 26.074925 -128.740659) (xy 26.019488 -128.746759) (xy 25.963754 -128.744722) (xy 25.908911 -128.734592)
			(xy 25.856127 -128.716585) (xy 25.806527 -128.691084) (xy 25.761169 -128.658633) (xy 25.72102 -128.619924)
			(xy 25.686934 -128.575781) (xy 25.659638 -128.527146) (xy 25.639715 -128.475055) (xy 25.627589 -128.420618)
			(xy 25.623518 -128.364996) (xy 25.185624 -128.364996) (xy 25.185624 -129.909824) (xy 25.185121 -129.934798)
			(xy 25.177337 -129.984135) (xy 25.161933 -130.031647) (xy 25.139288 -130.076166) (xy 25.109959 -130.116596)
			(xy 25.09266 -130.134614) (xy 24.553164 -130.67411) (xy 24.553164 -131.485132) (xy 24.921972 -131.85394)
			(xy 25.446228 -131.85394) (xy 25.459993 -131.853466) (xy 25.486503 -131.846027) (xy 25.510062 -131.831776)
			(xy 25.528959 -131.811752) (xy 25.541821 -131.787407) (xy 25.547713 -131.760511) (xy 25.546207 -131.733019)
			(xy 25.54224 -131.719828) (xy 25.532853 -131.690097) (xy 25.522773 -131.628573) (xy 25.522174 -131.5974)
			(xy 25.522829 -131.564741) (xy 25.533946 -131.500375) (xy 25.544272 -131.469384) (xy 25.548512 -131.456463)
			(xy 25.550554 -131.429351) (xy 25.545376 -131.40266) (xy 25.533345 -131.378277) (xy 25.515313 -131.357929)
			(xy 25.492555 -131.343053) (xy 25.46668 -131.334703) (xy 25.439519 -131.333468) (xy 25.426162 -131.336034)
			(xy 25.405486 -131.340428) (xy 25.363478 -131.345136) (xy 25.342342 -131.345432) (xy 25.315085 -131.34499)
			(xy 25.261125 -131.337238) (xy 25.208818 -131.321884) (xy 25.159229 -131.299243) (xy 25.113366 -131.269775)
			(xy 25.072164 -131.23408) (xy 25.036462 -131.192884) (xy 25.006986 -131.147026) (xy 24.984337 -131.09744)
			(xy 24.968976 -131.045135) (xy 24.961214 -130.991177) (xy 24.961212 -130.936663) (xy 24.968967 -130.882704)
			(xy 24.984323 -130.830398) (xy 25.006967 -130.780809) (xy 25.036438 -130.734948) (xy 25.072136 -130.693749)
			(xy 25.113334 -130.658049) (xy 25.159193 -130.628576) (xy 25.208781 -130.60593) (xy 25.261086 -130.590571)
			(xy 25.315045 -130.582813) (xy 25.369559 -130.582813) (xy 25.423518 -130.590572) (xy 25.475823 -130.605931)
			(xy 25.52541 -130.628578) (xy 25.571269 -130.658051) (xy 25.612467 -130.693752) (xy 25.648164 -130.734952)
			(xy 25.677635 -130.780813) (xy 25.700278 -130.830401) (xy 25.715093 -130.880866) (xy 27.573222 -130.880866)
			(xy 27.577293 -130.825244) (xy 27.589419 -130.770807) (xy 27.609342 -130.718716) (xy 27.636638 -130.670081)
			(xy 27.670724 -130.625938) (xy 27.710873 -130.587229) (xy 27.756231 -130.554778) (xy 27.805831 -130.529277)
			(xy 27.858615 -130.51127) (xy 27.913458 -130.50114) (xy 27.969192 -130.499103) (xy 28.024629 -130.505203)
			(xy 28.078586 -130.519309) (xy 28.129915 -130.541121) (xy 28.177521 -130.570175) (xy 28.220389 -130.60585)
			(xy 28.257606 -130.647387) (xy 28.288379 -130.6939) (xy 28.312051 -130.744397) (xy 28.328119 -130.797804)
			(xy 28.336239 -130.85298) (xy 28.336748 -130.880866) (xy 28.336239 -130.908752) (xy 28.328119 -130.963928)
			(xy 28.312051 -131.017335) (xy 28.288379 -131.067832) (xy 28.257606 -131.114345) (xy 28.220389 -131.155882)
			(xy 28.177521 -131.191557) (xy 28.129915 -131.220611) (xy 28.078586 -131.242423) (xy 28.024629 -131.256529)
			(xy 27.969192 -131.262629) (xy 27.913458 -131.260592) (xy 27.858615 -131.250462) (xy 27.805831 -131.232455)
			(xy 27.756231 -131.206954) (xy 27.710873 -131.174503) (xy 27.670724 -131.135794) (xy 27.636638 -131.091651)
			(xy 27.609342 -131.043016) (xy 27.589419 -130.990925) (xy 27.577293 -130.936488) (xy 27.573222 -130.880866)
			(xy 25.715093 -130.880866) (xy 25.715634 -130.882708) (xy 25.723389 -130.936667) (xy 25.72385 -130.963924)
			(xy 25.72318 -130.996583) (xy 25.712073 -131.060948) (xy 25.701752 -131.09194) (xy 25.697687 -131.10491)
			(xy 25.695635 -131.131995) (xy 25.700795 -131.158664) (xy 25.712802 -131.183029) (xy 25.730807 -131.203368)
			(xy 25.753536 -131.218241) (xy 25.779382 -131.226598) (xy 25.806516 -131.227846) (xy 25.819862 -131.22529)
			(xy 25.840537 -131.220891) (xy 25.882546 -131.216187) (xy 25.903682 -131.215892) (xy 25.930934 -131.216372)
			(xy 25.984885 -131.224127) (xy 26.037182 -131.23948) (xy 26.086762 -131.262121) (xy 26.132616 -131.291587)
			(xy 26.173808 -131.327279) (xy 26.209502 -131.36847) (xy 26.238971 -131.414322) (xy 26.261613 -131.463901)
			(xy 26.27697 -131.516198) (xy 26.284727 -131.570148) (xy 26.28519 -131.5974) (xy 26.284769 -131.623602)
			(xy 26.277591 -131.675513) (xy 26.263369 -131.725951) (xy 26.242373 -131.773966) (xy 26.229056 -131.796536)
			(xy 26.221436 -131.808728) (xy 26.221436 -131.94792) (xy 26.220927 -131.972894) (xy 26.213144 -132.02223)
			(xy 26.197741 -132.069742) (xy 26.175098 -132.114261) (xy 26.14577 -132.154691) (xy 26.128472 -132.17271)
			(xy 26.036524 -132.264658) (xy 26.43708 -132.264658) (xy 26.441151 -132.209036) (xy 26.453277 -132.154599)
			(xy 26.4732 -132.102508) (xy 26.500496 -132.053873) (xy 26.534582 -132.00973) (xy 26.574731 -131.971021)
			(xy 26.620089 -131.93857) (xy 26.669689 -131.913069) (xy 26.722473 -131.895062) (xy 26.777316 -131.884932)
			(xy 26.83305 -131.882895) (xy 26.888487 -131.888995) (xy 26.942444 -131.903101) (xy 26.993773 -131.924913)
			(xy 27.041379 -131.953967) (xy 27.084247 -131.989642) (xy 27.121464 -132.031179) (xy 27.152237 -132.077692)
			(xy 27.175909 -132.128189) (xy 27.191977 -132.181596) (xy 27.200097 -132.236772) (xy 27.200606 -132.264658)
			(xy 27.200097 -132.292544) (xy 27.191977 -132.34772) (xy 27.175909 -132.401127) (xy 27.152237 -132.451624)
			(xy 27.121464 -132.498137) (xy 27.084247 -132.539674) (xy 27.041379 -132.575349) (xy 26.993773 -132.604403)
			(xy 26.942444 -132.626215) (xy 26.888487 -132.640321) (xy 26.83305 -132.646421) (xy 26.777316 -132.644384)
			(xy 26.722473 -132.634254) (xy 26.669689 -132.616247) (xy 26.620089 -132.590746) (xy 26.574731 -132.558295)
			(xy 26.534582 -132.519586) (xy 26.500496 -132.475443) (xy 26.4732 -132.426808) (xy 26.453277 -132.374717)
			(xy 26.441151 -132.32028) (xy 26.43708 -132.264658) (xy 26.036524 -132.264658) (xy 25.904444 -132.396738)
			(xy 25.886422 -132.414046) (xy 25.846001 -132.443417) (xy 25.801489 -132.466115) (xy 25.753979 -132.481583)
			(xy 25.704636 -132.489441) (xy 25.679654 -132.489956) (xy 24.7904 -132.489956) (xy 24.76541 -132.489515)
			(xy 24.716048 -132.481687) (xy 24.668521 -132.466223) (xy 24.624003 -132.443506) (xy 24.583593 -132.414096)
			(xy 24.56561 -132.396738) (xy 24.010366 -131.841494) (xy 23.993034 -131.823493) (xy 23.963666 -131.783067)
			(xy 23.940973 -131.73855) (xy 23.925511 -131.691034) (xy 23.917659 -131.641687) (xy 23.917148 -131.616704)
			(xy 21.820378 -131.616704) (xy 21.820378 -133.6802) (xy 24.987502 -133.6802) (xy 24.991573 -133.624578)
			(xy 25.003699 -133.570141) (xy 25.023622 -133.51805) (xy 25.050918 -133.469415) (xy 25.085004 -133.425272)
			(xy 25.125153 -133.386563) (xy 25.170511 -133.354112) (xy 25.220111 -133.328611) (xy 25.272895 -133.310604)
			(xy 25.327738 -133.300474) (xy 25.383472 -133.298437) (xy 25.438909 -133.304537) (xy 25.492866 -133.318643)
			(xy 25.544195 -133.340455) (xy 25.591801 -133.369509) (xy 25.634669 -133.405184) (xy 25.671886 -133.446721)
			(xy 25.702659 -133.493234) (xy 25.726331 -133.543731) (xy 25.742399 -133.597138) (xy 25.750519 -133.652314)
			(xy 25.751028 -133.6802) (xy 25.750519 -133.708086) (xy 25.742399 -133.763262) (xy 25.726331 -133.816669)
			(xy 25.702659 -133.867166) (xy 25.671886 -133.913679) (xy 25.634669 -133.955216) (xy 25.591801 -133.990891)
			(xy 25.544195 -134.019945) (xy 25.492866 -134.041757) (xy 25.438909 -134.055863) (xy 25.383472 -134.061963)
			(xy 25.327738 -134.059926) (xy 25.272895 -134.049796) (xy 25.220111 -134.031789) (xy 25.170511 -134.006288)
			(xy 25.125153 -133.973837) (xy 25.085004 -133.935128) (xy 25.050918 -133.890985) (xy 25.023622 -133.84235)
			(xy 25.003699 -133.790259) (xy 24.991573 -133.735822) (xy 24.987502 -133.6802) (xy 21.820378 -133.6802)
			(xy 21.820378 -134.187057) (xy 28.166707 -134.187057) (xy 28.166707 -134.132543) (xy 28.174466 -134.078583)
			(xy 28.189825 -134.026277) (xy 28.212472 -133.976689) (xy 28.241945 -133.930829) (xy 28.277646 -133.88963)
			(xy 28.318846 -133.853932) (xy 28.364708 -133.824461) (xy 28.414297 -133.801817) (xy 28.466605 -133.786461)
			(xy 28.520565 -133.778705) (xy 28.547822 -133.778244) (xy 28.5742 -133.778728) (xy 28.626454 -133.785982)
			(xy 28.677212 -133.800363) (xy 28.725505 -133.821597) (xy 28.770415 -133.84928) (xy 28.811084 -133.882882)
			(xy 28.846739 -133.921766) (xy 28.876699 -133.965189) (xy 28.888944 -133.988556) (xy 28.895646 -134.000915)
			(xy 28.914621 -134.021643) (xy 28.938535 -134.036405) (xy 28.965571 -134.044077) (xy 28.993673 -134.044077)
			(xy 29.020709 -134.036405) (xy 29.044623 -134.021643) (xy 29.063598 -134.000915) (xy 29.0703 -133.988556)
			(xy 29.082506 -133.965166) (xy 29.112475 -133.921743) (xy 29.148136 -133.88286) (xy 29.188811 -133.849256)
			(xy 29.233725 -133.821571) (xy 29.282022 -133.800334) (xy 29.332783 -133.785948) (xy 29.385042 -133.778688)
			(xy 29.411422 -133.778244) (xy 29.437962 -133.778742) (xy 29.490529 -133.786115) (xy 29.541566 -133.800702)
			(xy 29.59009 -133.822221) (xy 29.635162 -133.850258) (xy 29.675915 -133.884271) (xy 29.71156 -133.923603)
			(xy 29.741411 -133.967495) (xy 29.75356 -133.991096) (xy 29.760607 -134.004333) (xy 29.781101 -134.026212)
			(xy 29.807058 -134.04121) (xy 29.836249 -134.048038) (xy 29.866165 -134.04611) (xy 29.894238 -134.035592)
			(xy 29.906468 -134.02691) (xy 29.931543 -134.008577) (xy 29.986405 -133.979453) (xy 30.045259 -133.9596)
			(xy 30.106552 -133.949541) (xy 30.137608 -133.948932) (xy 30.164862 -133.949338) (xy 30.218814 -133.957097)
			(xy 30.271114 -133.972454) (xy 30.320695 -133.995098) (xy 30.366549 -134.024568) (xy 30.407743 -134.060263)
			(xy 30.443437 -134.101457) (xy 30.472906 -134.147312) (xy 30.495549 -134.196894) (xy 30.510905 -134.249194)
			(xy 30.518662 -134.303146) (xy 30.518662 -134.357654) (xy 30.510905 -134.411606) (xy 30.495549 -134.463906)
			(xy 30.472906 -134.513488) (xy 30.443437 -134.559343) (xy 30.407743 -134.600537) (xy 30.366549 -134.636232)
			(xy 30.320695 -134.665702) (xy 30.271114 -134.688346) (xy 30.218814 -134.703703) (xy 30.164862 -134.711462)
			(xy 30.137608 -134.711948) (xy 30.111066 -134.711513) (xy 30.058496 -134.70413) (xy 30.007457 -134.689533)
			(xy 29.958933 -134.668005) (xy 29.913861 -134.639959) (xy 29.873109 -134.605939) (xy 29.837466 -134.566599)
			(xy 29.807618 -134.5227) (xy 29.79547 -134.499096) (xy 29.788388 -134.48588) (xy 29.767901 -134.464005)
			(xy 29.741952 -134.449007) (xy 29.71277 -134.442176) (xy 29.68286 -134.444097) (xy 29.654792 -134.454606)
			(xy 29.642562 -134.463282) (xy 29.617477 -134.4816) (xy 29.562619 -134.510728) (xy 29.503768 -134.530585)
			(xy 29.442477 -134.540648) (xy 29.411422 -134.54126) (xy 29.38504 -134.540875) (xy 29.332779 -134.533611)
			(xy 29.282017 -134.519218) (xy 29.23372 -134.497972) (xy 29.18881 -134.470275) (xy 29.148143 -134.436658)
			(xy 29.112493 -134.39776) (xy 29.082541 -134.354322) (xy 29.0703 -134.330948) (xy 29.063598 -134.318589)
			(xy 29.044623 -134.297861) (xy 29.020709 -134.283099) (xy 28.993673 -134.275427) (xy 28.965571 -134.275427)
			(xy 28.938535 -134.283099) (xy 28.914621 -134.297861) (xy 28.895646 -134.318589) (xy 28.888944 -134.330948)
			(xy 28.876706 -134.35432) (xy 28.846742 -134.397742) (xy 28.811085 -134.436626) (xy 28.770415 -134.470231)
			(xy 28.725505 -134.497917) (xy 28.677213 -134.519158) (xy 28.626456 -134.533548) (xy 28.574201 -134.540813)
			(xy 28.547822 -134.54126) (xy 28.520565 -134.540895) (xy 28.466605 -134.533139) (xy 28.414297 -134.517783)
			(xy 28.364708 -134.495139) (xy 28.318847 -134.465668) (xy 28.277646 -134.42997) (xy 28.241945 -134.388771)
			(xy 28.212472 -134.342911) (xy 28.189825 -134.293323) (xy 28.174466 -134.241017) (xy 28.166707 -134.187057)
			(xy 21.820378 -134.187057) (xy 21.820378 -135.140557) (xy 32.578423 -135.140557) (xy 32.578423 -135.086043)
			(xy 32.586182 -135.032083) (xy 32.601542 -134.979777) (xy 32.62419 -134.930189) (xy 32.653665 -134.88433)
			(xy 32.689366 -134.843133) (xy 32.730568 -134.807436) (xy 32.776431 -134.777967) (xy 32.826022 -134.755325)
			(xy 32.87833 -134.739972) (xy 32.932291 -134.73222) (xy 32.959548 -134.73176) (xy 32.98633 -134.732183)
			(xy 33.039367 -134.739689) (xy 33.090834 -134.754533) (xy 33.139722 -134.776423) (xy 33.185071 -134.804931)
			(xy 33.225992 -134.839496) (xy 33.26168 -134.87944) (xy 33.291437 -134.92398) (xy 33.303464 -134.947914)
			(xy 33.309986 -134.960369) (xy 33.328576 -134.98144) (xy 33.352213 -134.996636) (xy 33.379101 -135.004802)
			(xy 33.407196 -135.005317) (xy 33.434365 -134.998143) (xy 33.458543 -134.983824) (xy 33.477894 -134.963448)
			(xy 33.48482 -134.951216) (xy 33.497242 -134.928438) (xy 33.527358 -134.886189) (xy 33.562922 -134.848411)
			(xy 33.603278 -134.815801) (xy 33.647681 -134.788962) (xy 33.695312 -134.768389) (xy 33.745292 -134.75446)
			(xy 33.796698 -134.747434) (xy 33.82264 -134.747) (xy 33.84989 -134.747473) (xy 33.903834 -134.755234)
			(xy 33.956126 -134.770593) (xy 34.005699 -134.793237) (xy 34.051545 -134.822705) (xy 34.092731 -134.858397)
			(xy 34.128419 -134.899587) (xy 34.157883 -134.945436) (xy 34.180521 -134.995012) (xy 34.195875 -135.047305)
			(xy 34.20363 -135.10125) (xy 34.20363 -135.15575) (xy 34.195875 -135.209695) (xy 34.180521 -135.261988)
			(xy 34.157883 -135.311564) (xy 34.128419 -135.357413) (xy 34.092731 -135.398603) (xy 34.051545 -135.434295)
			(xy 34.005699 -135.463763) (xy 33.956126 -135.486407) (xy 33.903834 -135.501766) (xy 33.84989 -135.509527)
			(xy 33.82264 -135.510016) (xy 33.795859 -135.509561) (xy 33.742826 -135.502055) (xy 33.691361 -135.487213)
			(xy 33.642475 -135.465326) (xy 33.597127 -135.436823) (xy 33.556206 -135.402264) (xy 33.520515 -135.362326)
			(xy 33.490754 -135.317793) (xy 33.478724 -135.293862) (xy 33.472219 -135.281399) (xy 33.453623 -135.260331)
			(xy 33.429984 -135.245139) (xy 33.403095 -135.236976) (xy 33.374999 -135.236462) (xy 33.347829 -135.243636)
			(xy 33.32365 -135.257954) (xy 33.304296 -135.278328) (xy 33.297368 -135.29056) (xy 33.284913 -135.313319)
			(xy 33.254798 -135.355564) (xy 33.219236 -135.393339) (xy 33.178885 -135.425948) (xy 33.134487 -135.452788)
			(xy 33.086863 -135.473366) (xy 33.036889 -135.487301) (xy 32.985488 -135.494337) (xy 32.959548 -135.494776)
			(xy 32.932291 -135.49438) (xy 32.87833 -135.486628) (xy 32.826022 -135.471275) (xy 32.776431 -135.448633)
			(xy 32.730568 -135.419164) (xy 32.689366 -135.383467) (xy 32.653665 -135.34227) (xy 32.62419 -135.296411)
			(xy 32.601542 -135.246823) (xy 32.586182 -135.194517) (xy 32.578423 -135.140557) (xy 21.820378 -135.140557)
			(xy 21.820378 -137.279888) (xy 33.298892 -137.279888) (xy 33.299358 -137.253509) (xy 33.306612 -137.201253)
			(xy 33.320994 -137.150494) (xy 33.34223 -137.102199) (xy 33.369914 -137.057289) (xy 33.403521 -137.01662)
			(xy 33.442408 -136.980967) (xy 33.485835 -136.95101) (xy 33.509204 -136.938766) (xy 33.521569 -136.932079)
			(xy 33.542292 -136.913098) (xy 33.557047 -136.889181) (xy 33.564715 -136.862146) (xy 33.564714 -136.834044)
			(xy 33.557043 -136.807009) (xy 33.542285 -136.783094) (xy 33.52156 -136.764115) (xy 33.509204 -136.75741)
			(xy 33.48583 -136.745175) (xy 33.442405 -136.715213) (xy 33.403519 -136.679557) (xy 33.369913 -136.638886)
			(xy 33.342226 -136.593976) (xy 33.320987 -136.545682) (xy 33.306599 -136.494923) (xy 33.299336 -136.442667)
			(xy 33.298892 -136.416288) (xy 33.299378 -136.389037) (xy 33.307134 -136.335089) (xy 33.322489 -136.282794)
			(xy 33.345131 -136.233217) (xy 33.374597 -136.187367) (xy 33.410288 -136.146176) (xy 33.451479 -136.110485)
			(xy 33.497329 -136.081019) (xy 33.546906 -136.058377) (xy 33.599201 -136.043022) (xy 33.653149 -136.035266)
			(xy 33.707651 -136.035266) (xy 33.761599 -136.043022) (xy 33.813894 -136.058377) (xy 33.863471 -136.081019)
			(xy 33.909321 -136.110485) (xy 33.950512 -136.146176) (xy 33.986203 -136.187367) (xy 34.015669 -136.233217)
			(xy 34.038311 -136.282794) (xy 34.053666 -136.335089) (xy 34.061422 -136.389037) (xy 34.061908 -136.416288)
			(xy 34.061505 -136.442669) (xy 34.05424 -136.494928) (xy 34.039849 -136.545689) (xy 34.018604 -136.593984)
			(xy 33.99091 -136.638893) (xy 33.957296 -136.679561) (xy 33.918402 -136.715212) (xy 33.874968 -136.745168)
			(xy 33.851596 -136.75741) (xy 33.839252 -136.764132) (xy 33.818532 -136.783108) (xy 33.803777 -136.807018)
			(xy 33.796107 -136.834047) (xy 33.796106 -136.862143) (xy 33.803772 -136.889173) (xy 33.818525 -136.913084)
			(xy 33.839243 -136.932062) (xy 33.851596 -136.938766) (xy 33.87496 -136.951019) (xy 33.918385 -136.980979)
			(xy 33.957271 -137.016632) (xy 33.990878 -137.0573) (xy 34.018565 -137.102207) (xy 34.039807 -137.150499)
			(xy 34.054197 -137.201255) (xy 34.061462 -137.25351) (xy 34.061908 -137.279888) (xy 34.061422 -137.307139)
			(xy 34.053666 -137.361087) (xy 34.038311 -137.413382) (xy 34.015669 -137.462959) (xy 33.986203 -137.508809)
			(xy 33.950512 -137.55) (xy 33.909321 -137.585691) (xy 33.863471 -137.615157) (xy 33.813894 -137.637799)
			(xy 33.761599 -137.653154) (xy 33.707651 -137.66091) (xy 33.653149 -137.66091) (xy 33.599201 -137.653154)
			(xy 33.546906 -137.637799) (xy 33.497329 -137.615157) (xy 33.451479 -137.585691) (xy 33.410288 -137.55)
			(xy 33.374597 -137.508809) (xy 33.345131 -137.462959) (xy 33.322489 -137.413382) (xy 33.307134 -137.361087)
			(xy 33.299378 -137.307139) (xy 33.298892 -137.279888) (xy 21.820378 -137.279888) (xy 21.820378 -151.36368)
			(xy 21.820948 -151.378654) (xy 21.829711 -151.407296) (xy 21.8464 -151.432166) (xy 21.869584 -151.45113)
			(xy 21.897269 -151.462559) (xy 21.927079 -151.46547) (xy 21.956453 -151.459614) (xy 21.982867 -151.445493)
			(xy 21.99386 -151.435308) (xy 26.569416 -146.859498) (xy 26.587401 -146.842143) (xy 26.627813 -146.81274)
			(xy 26.672331 -146.790028) (xy 26.719857 -146.774569) (xy 26.769218 -146.766743) (xy 26.794206 -146.76628)
			(xy 34.102548 -146.76628) (xy 34.386012 -146.482816) (xy 35.049968 -145.819114) (xy 35.049968 -141.29512)
			(xy 34.94024 -141.29512) (xy 34.915258 -141.294605) (xy 34.865914 -141.286747) (xy 34.818402 -141.271281)
			(xy 34.773888 -141.248586) (xy 34.733464 -141.219219) (xy 34.71545 -141.201902) (xy 34.642044 -141.128242)
			(xy 34.588704 -141.074902) (xy 34.571418 -141.056904) (xy 34.542104 -141.016522) (xy 34.519458 -140.972056)
			(xy 34.504036 -140.924599) (xy 34.496216 -140.875316) (xy 34.49574 -140.850366) (xy 34.49574 -140.468858)
			(xy 34.496225 -140.443906) (xy 34.504021 -140.394616) (xy 34.519432 -140.347153) (xy 34.542077 -140.302684)
			(xy 34.5714 -140.262304) (xy 34.588704 -140.244322) (xy 34.642044 -140.190982) (xy 34.71545 -140.117322)
			(xy 34.733435 -140.099968) (xy 34.773847 -140.070567) (xy 34.818366 -140.047858) (xy 34.865892 -140.032403)
			(xy 34.915252 -140.024582) (xy 34.94024 -140.024104) (xy 35.049968 -140.024104) (xy 35.049968 -132.293106)
			(xy 34.471356 -131.714748) (xy 34.398712 -131.642104) (xy 34.098738 -131.342384) (xy 34.081381 -131.3244)
			(xy 34.051974 -131.283989) (xy 34.02926 -131.239471) (xy 34.013799 -131.191945) (xy 34.005972 -131.142583)
			(xy 34.00552 -131.117594) (xy 34.00552 -125.012958) (xy 33.273746 -124.281184) (xy 33.259776 -124.277628)
			(xy 33.232372 -124.270529) (xy 33.179879 -124.249339) (xy 33.131098 -124.220617) (xy 33.087102 -124.184995)
			(xy 33.048859 -124.143258) (xy 33.01721 -124.096323) (xy 32.992852 -124.045224) (xy 32.97632 -123.991083)
			(xy 32.967978 -123.935093) (xy 32.967422 -123.906788) (xy 32.967886 -123.879536) (xy 32.975645 -123.825588)
			(xy 32.991002 -123.773294) (xy 33.013646 -123.723717) (xy 33.043114 -123.677868) (xy 33.078809 -123.636679)
			(xy 33.120001 -123.600989) (xy 33.165854 -123.571526) (xy 33.215433 -123.548887) (xy 33.26773 -123.533536)
			(xy 33.321678 -123.525783) (xy 33.34893 -123.52528) (xy 33.377235 -123.525797) (xy 33.433223 -123.534167)
			(xy 33.487359 -123.550717) (xy 33.538456 -123.575085) (xy 33.585391 -123.606736) (xy 33.627134 -123.644975)
			(xy 33.662768 -123.688963) (xy 33.691511 -123.737733) (xy 33.712732 -123.790215) (xy 33.71977 -123.817634)
			(xy 33.723326 -123.831604) (xy 33.752028 -123.860306) (xy 33.763514 -123.869894) (xy 33.790611 -123.882547)
			(xy 33.820211 -123.886807) (xy 33.849777 -123.882309) (xy 33.876771 -123.869438) (xy 33.898878 -123.849298)
			(xy 33.914201 -123.823616) (xy 33.918398 -123.809252) (xy 33.924954 -123.781164) (xy 33.945385 -123.727229)
			(xy 33.973705 -123.676985) (xy 34.009268 -123.631578) (xy 34.051263 -123.592045) (xy 34.098732 -123.559286)
			(xy 34.150593 -123.534049) (xy 34.205663 -123.516909) (xy 34.262686 -123.508257) (xy 34.291524 -123.507754)
			(xy 34.319499 -123.508247) (xy 34.374847 -123.516426) (xy 34.428406 -123.532604) (xy 34.479027 -123.556434)
			(xy 34.502598 -123.571508) (xy 36.168584 -123.571508) (xy 36.193536 -123.571971) (xy 36.242825 -123.579775)
			(xy 36.290287 -123.595194) (xy 36.334752 -123.617849) (xy 36.375125 -123.64718) (xy 36.39312 -123.664472)
			(xy 36.6903 -123.961652) (xy 36.804417 -124.075698) (xy 37.74643 -124.075698) (xy 37.750503 -124.020039)
			(xy 37.762638 -123.965566) (xy 37.782574 -123.91344) (xy 37.809888 -123.864772) (xy 37.843996 -123.8206)
			(xy 37.884173 -123.781865) (xy 37.929561 -123.749393) (xy 37.979193 -123.723875) (xy 38.032013 -123.705856)
			(xy 38.086892 -123.695719) (xy 38.142663 -123.693681) (xy 38.198137 -123.699784) (xy 38.25213 -123.7139)
			(xy 38.303493 -123.735727) (xy 38.351131 -123.7648) (xy 38.394027 -123.800499) (xy 38.431269 -123.842063)
			(xy 38.462063 -123.888607) (xy 38.485751 -123.939138) (xy 38.501829 -123.99258) (xy 38.509955 -124.047794)
			(xy 38.510464 -124.075698) (xy 38.509955 -124.103602) (xy 38.501829 -124.158816) (xy 38.485751 -124.212258)
			(xy 38.462063 -124.262789) (xy 38.431269 -124.309333) (xy 38.394027 -124.350897) (xy 38.351131 -124.386596)
			(xy 38.303493 -124.415669) (xy 38.25213 -124.437496) (xy 38.198137 -124.451612) (xy 38.142663 -124.457715)
			(xy 38.086892 -124.455677) (xy 38.032013 -124.44554) (xy 37.979193 -124.427521) (xy 37.929561 -124.402003)
			(xy 37.884173 -124.369531) (xy 37.843996 -124.330796) (xy 37.809888 -124.286624) (xy 37.782574 -124.237956)
			(xy 37.762638 -124.18583) (xy 37.750503 -124.131357) (xy 37.74643 -124.075698) (xy 36.804417 -124.075698)
			(xy 37.09797 -124.369068) (xy 37.115324 -124.387053) (xy 37.144723 -124.427466) (xy 37.167429 -124.471985)
			(xy 37.182883 -124.519511) (xy 37.190701 -124.56887) (xy 37.191188 -124.593858) (xy 37.191188 -125.592953)
			(xy 37.60644 -125.592953) (xy 37.60644 -125.538447) (xy 37.614197 -125.484496) (xy 37.629552 -125.432198)
			(xy 37.652194 -125.382617) (xy 37.681661 -125.336763) (xy 37.717354 -125.295569) (xy 37.758545 -125.259874)
			(xy 37.804398 -125.230404) (xy 37.853977 -125.20776) (xy 37.906274 -125.192401) (xy 37.960225 -125.184641)
			(xy 37.987478 -125.184154) (xy 38.014784 -125.184653) (xy 38.068836 -125.192463) (xy 38.121222 -125.207899)
			(xy 38.170873 -125.230644) (xy 38.216775 -125.260235) (xy 38.257989 -125.296067) (xy 38.259611 -125.297946)
			(xy 41.053256 -125.297946) (xy 41.057329 -125.242287) (xy 41.069464 -125.187814) (xy 41.0894 -125.135688)
			(xy 41.116714 -125.08702) (xy 41.150822 -125.042848) (xy 41.190999 -125.004113) (xy 41.236387 -124.971641)
			(xy 41.286019 -124.946123) (xy 41.338839 -124.928104) (xy 41.393718 -124.917967) (xy 41.449489 -124.915929)
			(xy 41.504963 -124.922032) (xy 41.558956 -124.936148) (xy 41.610319 -124.957975) (xy 41.657957 -124.987048)
			(xy 41.700853 -125.022747) (xy 41.738095 -125.064311) (xy 41.768889 -125.110855) (xy 41.792577 -125.161386)
			(xy 41.808655 -125.214828) (xy 41.816781 -125.270042) (xy 41.81729 -125.297946) (xy 41.816781 -125.32585)
			(xy 41.808655 -125.381064) (xy 41.792577 -125.434506) (xy 41.768889 -125.485037) (xy 41.738095 -125.531581)
			(xy 41.700853 -125.573145) (xy 41.657957 -125.608844) (xy 41.610319 -125.637917) (xy 41.558956 -125.659744)
			(xy 41.504963 -125.67386) (xy 41.449489 -125.679963) (xy 41.393718 -125.677925) (xy 41.338839 -125.667788)
			(xy 41.286019 -125.649769) (xy 41.236387 -125.624251) (xy 41.190999 -125.591779) (xy 41.150822 -125.553044)
			(xy 41.116714 -125.508872) (xy 41.0894 -125.460204) (xy 41.069464 -125.408078) (xy 41.057329 -125.353605)
			(xy 41.053256 -125.297946) (xy 38.259611 -125.297946) (xy 38.293675 -125.337409) (xy 38.323104 -125.383415)
			(xy 38.345673 -125.433146) (xy 38.353746 -125.459236) (xy 38.358068 -125.472334) (xy 38.372585 -125.495772)
			(xy 38.392846 -125.514469) (xy 38.417371 -125.527061) (xy 38.444372 -125.53263) (xy 38.471878 -125.530769)
			(xy 38.497883 -125.521615) (xy 38.509448 -125.5141) (xy 38.533577 -125.497991) (xy 38.58567 -125.472456)
			(xy 38.641027 -125.455098) (xy 38.698373 -125.446316) (xy 38.72738 -125.445774) (xy 38.754633 -125.446272)
			(xy 38.808583 -125.454026) (xy 38.860881 -125.46938) (xy 38.910461 -125.49202) (xy 38.956315 -125.521486)
			(xy 38.997508 -125.557178) (xy 39.033202 -125.598369) (xy 39.06267 -125.644221) (xy 39.085313 -125.6938)
			(xy 39.10067 -125.746097) (xy 39.108427 -125.800048) (xy 39.108427 -125.854552) (xy 39.10067 -125.908503)
			(xy 39.085313 -125.9608) (xy 39.06267 -126.010379) (xy 39.033202 -126.056231) (xy 38.997508 -126.097422)
			(xy 38.956315 -126.133114) (xy 38.910461 -126.16258) (xy 38.860881 -126.18522) (xy 38.808583 -126.200574)
			(xy 38.754633 -126.208328) (xy 38.72738 -126.20879) (xy 38.700074 -126.208297) (xy 38.646024 -126.200482)
			(xy 38.593639 -126.185043) (xy 38.543989 -126.162295) (xy 38.498089 -126.132703) (xy 38.456875 -126.096871)
			(xy 38.421189 -126.055531) (xy 38.391759 -126.009527) (xy 38.369187 -125.959797) (xy 38.361112 -125.933708)
			(xy 38.356831 -125.920593) (xy 38.342313 -125.897145) (xy 38.322046 -125.87844) (xy 38.297511 -125.865846)
			(xy 38.2705 -125.86028) (xy 38.242985 -125.862151) (xy 38.216975 -125.87132) (xy 38.20541 -125.878844)
			(xy 38.181288 -125.894965) (xy 38.129193 -125.920499) (xy 38.073834 -125.937854) (xy 38.016486 -125.946631)
			(xy 37.987478 -125.94717) (xy 37.960225 -125.946759) (xy 37.906274 -125.938999) (xy 37.853977 -125.92364)
			(xy 37.804398 -125.900996) (xy 37.758545 -125.871526) (xy 37.717354 -125.835831) (xy 37.681661 -125.794637)
			(xy 37.652194 -125.748783) (xy 37.629552 -125.699202) (xy 37.614197 -125.646904) (xy 37.60644 -125.592953)
			(xy 37.191188 -125.592953) (xy 37.191188 -127.198628) (xy 41.572686 -127.198628) (xy 41.576757 -127.143006)
			(xy 41.588883 -127.088569) (xy 41.608806 -127.036478) (xy 41.636102 -126.987843) (xy 41.670188 -126.9437)
			(xy 41.710337 -126.904991) (xy 41.755695 -126.87254) (xy 41.805295 -126.847039) (xy 41.858079 -126.829032)
			(xy 41.912922 -126.818902) (xy 41.968656 -126.816865) (xy 42.024093 -126.822965) (xy 42.07805 -126.837071)
			(xy 42.129379 -126.858883) (xy 42.176985 -126.887937) (xy 42.219853 -126.923612) (xy 42.25707 -126.965149)
			(xy 42.287843 -127.011662) (xy 42.311515 -127.062159) (xy 42.327583 -127.115566) (xy 42.335703 -127.170742)
			(xy 42.336212 -127.198628) (xy 42.335703 -127.226514) (xy 42.327583 -127.28169) (xy 42.311515 -127.335097)
			(xy 42.287843 -127.385594) (xy 42.25707 -127.432107) (xy 42.219853 -127.473644) (xy 42.176985 -127.509319)
			(xy 42.129379 -127.538373) (xy 42.07805 -127.560185) (xy 42.024093 -127.574291) (xy 41.968656 -127.580391)
			(xy 41.912922 -127.578354) (xy 41.858079 -127.568224) (xy 41.805295 -127.550217) (xy 41.755695 -127.524716)
			(xy 41.710337 -127.492265) (xy 41.670188 -127.453556) (xy 41.636102 -127.409413) (xy 41.608806 -127.360778)
			(xy 41.588883 -127.308687) (xy 41.576757 -127.25425) (xy 41.572686 -127.198628) (xy 37.191188 -127.198628)
			(xy 37.191188 -127.798322) (xy 40.5798 -127.798322) (xy 40.583871 -127.7427) (xy 40.595997 -127.688263)
			(xy 40.61592 -127.636172) (xy 40.643216 -127.587537) (xy 40.677302 -127.543394) (xy 40.717451 -127.504685)
			(xy 40.762809 -127.472234) (xy 40.812409 -127.446733) (xy 40.865193 -127.428726) (xy 40.920036 -127.418596)
			(xy 40.97577 -127.416559) (xy 41.031207 -127.422659) (xy 41.085164 -127.436765) (xy 41.136493 -127.458577)
			(xy 41.184099 -127.487631) (xy 41.226967 -127.523306) (xy 41.264184 -127.564843) (xy 41.294957 -127.611356)
			(xy 41.318629 -127.661853) (xy 41.334697 -127.71526) (xy 41.342817 -127.770436) (xy 41.343326 -127.798322)
			(xy 41.342817 -127.826208) (xy 41.334697 -127.881384) (xy 41.318629 -127.934791) (xy 41.294957 -127.985288)
			(xy 41.264184 -128.031801) (xy 41.226967 -128.073338) (xy 41.184099 -128.109013) (xy 41.136493 -128.138067)
			(xy 41.085164 -128.159879) (xy 41.031207 -128.173985) (xy 40.97577 -128.180085) (xy 40.920036 -128.178048)
			(xy 40.865193 -128.167918) (xy 40.812409 -128.149911) (xy 40.762809 -128.12441) (xy 40.717451 -128.091959)
			(xy 40.677302 -128.05325) (xy 40.643216 -128.009107) (xy 40.61592 -127.960472) (xy 40.595997 -127.908381)
			(xy 40.583871 -127.853944) (xy 40.5798 -127.798322) (xy 37.191188 -127.798322) (xy 37.191188 -128.72974)
			(xy 37.58387 -128.72974) (xy 37.587941 -128.674118) (xy 37.600067 -128.619681) (xy 37.61999 -128.56759)
			(xy 37.647286 -128.518955) (xy 37.681372 -128.474812) (xy 37.721521 -128.436103) (xy 37.766879 -128.403652)
			(xy 37.816479 -128.378151) (xy 37.869263 -128.360144) (xy 37.924106 -128.350014) (xy 37.97984 -128.347977)
			(xy 38.035277 -128.354077) (xy 38.089234 -128.368183) (xy 38.140563 -128.389995) (xy 38.188169 -128.419049)
			(xy 38.231037 -128.454724) (xy 38.268254 -128.496261) (xy 38.299027 -128.542774) (xy 38.322699 -128.593271)
			(xy 38.338767 -128.646678) (xy 38.346887 -128.701854) (xy 38.347396 -128.72974) (xy 38.346887 -128.757626)
			(xy 38.338767 -128.812802) (xy 38.322699 -128.866209) (xy 38.299027 -128.916706) (xy 38.268254 -128.963219)
			(xy 38.231037 -129.004756) (xy 38.188169 -129.040431) (xy 38.140563 -129.069485) (xy 38.089234 -129.091297)
			(xy 38.035277 -129.105403) (xy 37.97984 -129.111503) (xy 37.924106 -129.109466) (xy 37.869263 -129.099336)
			(xy 37.816479 -129.081329) (xy 37.766879 -129.055828) (xy 37.721521 -129.023377) (xy 37.681372 -128.984668)
			(xy 37.647286 -128.940525) (xy 37.61999 -128.89189) (xy 37.600067 -128.839799) (xy 37.587941 -128.785362)
			(xy 37.58387 -128.72974) (xy 37.191188 -128.72974) (xy 37.191188 -129.553208) (xy 40.257982 -129.553208)
			(xy 40.262053 -129.497586) (xy 40.274179 -129.443149) (xy 40.294102 -129.391058) (xy 40.321398 -129.342423)
			(xy 40.355484 -129.29828) (xy 40.395633 -129.259571) (xy 40.440991 -129.22712) (xy 40.490591 -129.201619)
			(xy 40.543375 -129.183612) (xy 40.598218 -129.173482) (xy 40.653952 -129.171445) (xy 40.709389 -129.177545)
			(xy 40.763346 -129.191651) (xy 40.814675 -129.213463) (xy 40.862281 -129.242517) (xy 40.905149 -129.278192)
			(xy 40.942366 -129.319729) (xy 40.973139 -129.366242) (xy 40.996811 -129.416739) (xy 41.012879 -129.470146)
			(xy 41.020999 -129.525322) (xy 41.021508 -129.553208) (xy 41.020999 -129.581094) (xy 41.012879 -129.63627)
			(xy 40.996811 -129.689677) (xy 40.973139 -129.740174) (xy 40.942366 -129.786687) (xy 40.905149 -129.828224)
			(xy 40.862281 -129.863899) (xy 40.814675 -129.892953) (xy 40.763346 -129.914765) (xy 40.709389 -129.928871)
			(xy 40.653952 -129.934971) (xy 40.598218 -129.932934) (xy 40.543375 -129.922804) (xy 40.490591 -129.904797)
			(xy 40.440991 -129.879296) (xy 40.395633 -129.846845) (xy 40.355484 -129.808136) (xy 40.321398 -129.763993)
			(xy 40.294102 -129.715358) (xy 40.274179 -129.663267) (xy 40.262053 -129.60883) (xy 40.257982 -129.553208)
			(xy 37.191188 -129.553208) (xy 37.191188 -130.76174) (xy 37.59454 -130.76174) (xy 37.595112 -130.732636)
			(xy 37.60397 -130.675106) (xy 37.621457 -130.619587) (xy 37.647168 -130.567366) (xy 37.680507 -130.519651)
			(xy 37.720701 -130.477549) (xy 37.76682 -130.442035) (xy 37.817794 -130.413932) (xy 37.872443 -130.393892)
			(xy 37.900864 -130.387598) (xy 37.914157 -130.384444) (xy 37.938548 -130.372167) (xy 37.95881 -130.35386)
			(xy 37.973489 -130.330834) (xy 37.981534 -130.30474) (xy 37.982369 -130.277446) (xy 37.975935 -130.250908)
			(xy 37.969698 -130.238754) (xy 37.95827 -130.217443) (xy 37.940305 -130.172547) (xy 37.92817 -130.125737)
			(xy 37.922061 -130.077767) (xy 37.921692 -130.053588) (xy 37.921692 -130.053334) (xy 37.922178 -130.026083)
			(xy 37.929934 -129.972135) (xy 37.945289 -129.91984) (xy 37.967931 -129.870263) (xy 37.997397 -129.824413)
			(xy 38.033088 -129.783222) (xy 38.074279 -129.747531) (xy 38.120129 -129.718065) (xy 38.169706 -129.695423)
			(xy 38.222001 -129.680068) (xy 38.275949 -129.672312) (xy 38.330451 -129.672312) (xy 38.384399 -129.680068)
			(xy 38.436694 -129.695423) (xy 38.486271 -129.718065) (xy 38.532121 -129.747531) (xy 38.573312 -129.783222)
			(xy 38.609003 -129.824413) (xy 38.638469 -129.870263) (xy 38.661111 -129.91984) (xy 38.676466 -129.972135)
			(xy 38.684222 -130.026083) (xy 38.684708 -130.053334) (xy 38.684075 -130.082435) (xy 38.675221 -130.13996)
			(xy 38.65774 -130.195476) (xy 38.632037 -130.247695) (xy 38.598705 -130.295408) (xy 38.558519 -130.337511)
			(xy 38.512409 -130.373027) (xy 38.461443 -130.401133) (xy 38.406801 -130.421179) (xy 38.378384 -130.427476)
			(xy 38.365068 -130.430554) (xy 38.340661 -130.442834) (xy 38.320388 -130.461152) (xy 38.305705 -130.484193)
			(xy 38.297664 -130.510306) (xy 38.296843 -130.537616) (xy 38.3033 -130.564164) (xy 38.30955 -130.57632)
			(xy 38.320972 -130.597634) (xy 38.338938 -130.642529) (xy 38.351074 -130.689339) (xy 38.357186 -130.737308)
			(xy 38.357556 -130.761486) (xy 38.357556 -130.76174) (xy 38.35718 -130.782822) (xy 38.66718 -130.782822)
			(xy 38.671251 -130.7272) (xy 38.683377 -130.672763) (xy 38.7033 -130.620672) (xy 38.730596 -130.572037)
			(xy 38.764682 -130.527894) (xy 38.804831 -130.489185) (xy 38.850189 -130.456734) (xy 38.899789 -130.431233)
			(xy 38.952573 -130.413226) (xy 39.007416 -130.403096) (xy 39.06315 -130.401059) (xy 39.118587 -130.407159)
			(xy 39.172544 -130.421265) (xy 39.223873 -130.443077) (xy 39.271479 -130.472131) (xy 39.314347 -130.507806)
			(xy 39.351564 -130.549343) (xy 39.382337 -130.595856) (xy 39.406009 -130.646353) (xy 39.422077 -130.69976)
			(xy 39.430197 -130.754936) (xy 39.430706 -130.782822) (xy 39.430197 -130.810708) (xy 39.422077 -130.865884)
			(xy 39.406009 -130.919291) (xy 39.382337 -130.969788) (xy 39.351564 -131.016301) (xy 39.314347 -131.057838)
			(xy 39.271479 -131.093513) (xy 39.223873 -131.122567) (xy 39.172544 -131.144379) (xy 39.118587 -131.158485)
			(xy 39.06315 -131.164585) (xy 39.007416 -131.162548) (xy 38.952573 -131.152418) (xy 38.899789 -131.134411)
			(xy 38.850189 -131.10891) (xy 38.804831 -131.076459) (xy 38.764682 -131.03775) (xy 38.730596 -130.993607)
			(xy 38.7033 -130.944972) (xy 38.683377 -130.892881) (xy 38.671251 -130.838444) (xy 38.66718 -130.782822)
			(xy 38.35718 -130.782822) (xy 38.35707 -130.788991) (xy 38.349314 -130.842939) (xy 38.333959 -130.895234)
			(xy 38.311317 -130.944811) (xy 38.281851 -130.990661) (xy 38.24616 -131.031852) (xy 38.204969 -131.067543)
			(xy 38.159119 -131.097009) (xy 38.109542 -131.119651) (xy 38.057247 -131.135006) (xy 38.003299 -131.142762)
			(xy 37.948797 -131.142762) (xy 37.894849 -131.135006) (xy 37.842554 -131.119651) (xy 37.792977 -131.097009)
			(xy 37.747127 -131.067543) (xy 37.705936 -131.031852) (xy 37.670245 -130.990661) (xy 37.640779 -130.944811)
			(xy 37.618137 -130.895234) (xy 37.602782 -130.842939) (xy 37.595026 -130.788991) (xy 37.59454 -130.76174)
			(xy 37.191188 -130.76174) (xy 37.191188 -130.824986) (xy 37.19067 -130.849967) (xy 37.182809 -130.899308)
			(xy 37.167338 -130.946816) (xy 37.14464 -130.991326) (xy 37.115269 -131.031745) (xy 37.09797 -131.049776)
			(xy 36.186872 -131.96062) (xy 36.186872 -132.049774) (xy 37.591998 -132.049774) (xy 37.596069 -131.994152)
			(xy 37.608195 -131.939715) (xy 37.628118 -131.887624) (xy 37.655414 -131.838989) (xy 37.6895 -131.794846)
			(xy 37.729649 -131.756137) (xy 37.775007 -131.723686) (xy 37.824607 -131.698185) (xy 37.877391 -131.680178)
			(xy 37.932234 -131.670048) (xy 37.987968 -131.668011) (xy 38.043405 -131.674111) (xy 38.097362 -131.688217)
			(xy 38.148691 -131.710029) (xy 38.196297 -131.739083) (xy 38.239165 -131.774758) (xy 38.276382 -131.816295)
			(xy 38.307155 -131.862808) (xy 38.330827 -131.913305) (xy 38.346895 -131.966712) (xy 38.355015 -132.021888)
			(xy 38.355524 -132.049774) (xy 38.355015 -132.07766) (xy 38.346895 -132.132836) (xy 38.330827 -132.186243)
			(xy 38.307155 -132.23674) (xy 38.276382 -132.283253) (xy 38.239165 -132.32479) (xy 38.196297 -132.360465)
			(xy 38.148691 -132.389519) (xy 38.097362 -132.411331) (xy 38.043405 -132.425437) (xy 37.987968 -132.431537)
			(xy 37.932234 -132.4295) (xy 37.877391 -132.41937) (xy 37.824607 -132.401363) (xy 37.775007 -132.375862)
			(xy 37.729649 -132.343411) (xy 37.6895 -132.304702) (xy 37.655414 -132.260559) (xy 37.628118 -132.211924)
			(xy 37.608195 -132.159833) (xy 37.596069 -132.105396) (xy 37.591998 -132.049774) (xy 36.186872 -132.049774)
			(xy 36.186872 -132.532882) (xy 38.89832 -132.532882) (xy 38.902391 -132.47726) (xy 38.914517 -132.422823)
			(xy 38.93444 -132.370732) (xy 38.961736 -132.322097) (xy 38.995822 -132.277954) (xy 39.035971 -132.239245)
			(xy 39.081329 -132.206794) (xy 39.130929 -132.181293) (xy 39.183713 -132.163286) (xy 39.238556 -132.153156)
			(xy 39.29429 -132.151119) (xy 39.349727 -132.157219) (xy 39.403684 -132.171325) (xy 39.455013 -132.193137)
			(xy 39.502619 -132.222191) (xy 39.545487 -132.257866) (xy 39.582704 -132.299403) (xy 39.613477 -132.345916)
			(xy 39.637149 -132.396413) (xy 39.653217 -132.44982) (xy 39.661337 -132.504996) (xy 39.661846 -132.532882)
			(xy 39.661337 -132.560768) (xy 39.653217 -132.615944) (xy 39.637149 -132.669351) (xy 39.613477 -132.719848)
			(xy 39.582704 -132.766361) (xy 39.545487 -132.807898) (xy 39.502619 -132.843573) (xy 39.455013 -132.872627)
			(xy 39.403684 -132.894439) (xy 39.349727 -132.908545) (xy 39.29429 -132.914645) (xy 39.238556 -132.912608)
			(xy 39.183713 -132.902478) (xy 39.130929 -132.884471) (xy 39.081329 -132.85897) (xy 39.035971 -132.826519)
			(xy 38.995822 -132.78781) (xy 38.961736 -132.743667) (xy 38.93444 -132.695032) (xy 38.914517 -132.642941)
			(xy 38.902391 -132.588504) (xy 38.89832 -132.532882) (xy 36.186872 -132.532882) (xy 36.186872 -133.838696)
			(xy 38.067994 -133.838696) (xy 38.072065 -133.783074) (xy 38.084191 -133.728637) (xy 38.104114 -133.676546)
			(xy 38.13141 -133.627911) (xy 38.165496 -133.583768) (xy 38.205645 -133.545059) (xy 38.251003 -133.512608)
			(xy 38.300603 -133.487107) (xy 38.353387 -133.4691) (xy 38.40823 -133.45897) (xy 38.463964 -133.456933)
			(xy 38.519401 -133.463033) (xy 38.573358 -133.477139) (xy 38.624687 -133.498951) (xy 38.672293 -133.528005)
			(xy 38.715161 -133.56368) (xy 38.752378 -133.605217) (xy 38.783151 -133.65173) (xy 38.806823 -133.702227)
			(xy 38.822891 -133.755634) (xy 38.831011 -133.81081) (xy 38.83152 -133.838696) (xy 38.831011 -133.866582)
			(xy 38.822891 -133.921758) (xy 38.806823 -133.975165) (xy 38.783151 -134.025662) (xy 38.752378 -134.072175)
			(xy 38.715161 -134.113712) (xy 38.672293 -134.149387) (xy 38.624687 -134.178441) (xy 38.573358 -134.200253)
			(xy 38.519401 -134.214359) (xy 38.463964 -134.220459) (xy 38.40823 -134.218422) (xy 38.353387 -134.208292)
			(xy 38.300603 -134.190285) (xy 38.251003 -134.164784) (xy 38.205645 -134.132333) (xy 38.165496 -134.093624)
			(xy 38.13141 -134.049481) (xy 38.104114 -134.000846) (xy 38.084191 -133.948755) (xy 38.072065 -133.894318)
			(xy 38.067994 -133.838696) (xy 36.186872 -133.838696) (xy 36.186872 -146.060668) (xy 36.186356 -146.08565)
			(xy 36.178496 -146.134992) (xy 36.163027 -146.182501) (xy 36.140329 -146.227012) (xy 36.110958 -146.267433)
			(xy 36.093654 -146.285458) (xy 34.638234 -147.740878) (xy 34.620249 -147.758231) (xy 34.579836 -147.78763)
			(xy 34.535317 -147.810336) (xy 34.487791 -147.825789) (xy 34.438432 -147.833608) (xy 34.413444 -147.834096)
			(xy 27.105102 -147.834096) (xy 21.820378 -153.11882) (xy 21.820378 -153.766012) (xy 24.445731 -153.766012)
			(xy 24.449724 -153.556271) (xy 24.4617 -153.346834) (xy 24.481641 -153.138005) (xy 24.509518 -152.930086)
			(xy 24.54529 -152.723379) (xy 24.588905 -152.518184) (xy 24.640301 -152.314799) (xy 24.699403 -152.113517)
			(xy 24.766125 -151.914631) (xy 24.84037 -151.71843) (xy 24.92203 -151.525198) (xy 25.010988 -151.335214)
			(xy 25.107115 -151.148755) (xy 25.21027 -150.966091) (xy 25.320305 -150.787486) (xy 25.437059 -150.6132)
			(xy 25.560364 -150.443485) (xy 25.690041 -150.278587) (xy 25.825902 -150.118746) (xy 25.967749 -149.964193)
			(xy 26.115378 -149.815153) (xy 26.268573 -149.67184) (xy 26.427114 -149.534464) (xy 26.590769 -149.403223)
			(xy 26.759303 -149.278308) (xy 26.932469 -149.1599) (xy 27.110019 -149.04817) (xy 27.291693 -148.94328)
			(xy 27.477228 -148.845383) (xy 27.666356 -148.754621) (xy 27.858803 -148.671124) (xy 28.054288 -148.595014)
			(xy 28.25253 -148.526402) (xy 28.45324 -148.465387) (xy 28.656127 -148.412058) (xy 28.860897 -148.366491)
			(xy 29.067254 -148.328752) (xy 29.274898 -148.298898) (xy 29.483528 -148.27697) (xy 29.692841 -148.263001)
			(xy 29.902535 -148.25701) (xy 30.112304 -148.259007) (xy 30.321846 -148.268989) (xy 30.530856 -148.286941)
			(xy 30.73903 -148.312837) (xy 30.946068 -148.346639) (xy 31.151669 -148.388299) (xy 31.355535 -148.437757)
			(xy 31.55737 -148.49494) (xy 31.756882 -148.559765) (xy 31.953781 -148.632139) (xy 32.147782 -148.711956)
			(xy 32.338604 -148.799102) (xy 32.52597 -148.893449) (xy 32.709608 -148.99486) (xy 32.889252 -149.10319)
			(xy 33.064642 -149.21828) (xy 33.235523 -149.339964) (xy 33.401647 -149.468065) (xy 33.562774 -149.602398)
			(xy 33.718671 -149.742767) (xy 33.86911 -149.88897) (xy 34.013874 -150.040794) (xy 34.152753 -150.19802)
			(xy 34.285546 -150.360419) (xy 34.41206 -150.527755) (xy 34.532112 -150.699787) (xy 34.645527 -150.876264)
			(xy 34.752141 -151.056932) (xy 34.8518 -151.241527) (xy 34.944359 -151.429782) (xy 35.029684 -151.621425)
			(xy 35.107651 -151.816177) (xy 35.178147 -152.013757) (xy 35.24107 -152.213876) (xy 35.296329 -152.416247)
			(xy 35.343843 -152.620574) (xy 35.383544 -152.826562) (xy 35.415374 -153.033913) (xy 35.439287 -153.242324)
			(xy 35.455248 -153.451495) (xy 35.463235 -153.661122) (xy 35.463734 -153.766012) (xy 35.463235 -153.870902)
			(xy 35.455248 -154.080529) (xy 35.439287 -154.2897) (xy 35.415374 -154.498111) (xy 35.383544 -154.705462)
			(xy 35.343843 -154.91145) (xy 35.296329 -155.115777) (xy 35.24107 -155.318148) (xy 35.178147 -155.518267)
			(xy 35.107651 -155.715847) (xy 35.029684 -155.910599) (xy 34.944359 -156.102242) (xy 34.8518 -156.290497)
			(xy 34.752141 -156.475092) (xy 34.645527 -156.65576) (xy 34.532112 -156.832237) (xy 34.41206 -157.004269)
			(xy 34.285546 -157.171605) (xy 34.152753 -157.334004) (xy 34.013874 -157.49123) (xy 33.86911 -157.643054)
			(xy 33.718671 -157.789257) (xy 33.562774 -157.929626) (xy 33.401647 -158.063959) (xy 33.235523 -158.19206)
			(xy 33.064642 -158.313744) (xy 32.889252 -158.428834) (xy 32.709608 -158.537164) (xy 32.52597 -158.638575)
			(xy 32.338604 -158.732922) (xy 32.147782 -158.820068) (xy 31.953781 -158.899885) (xy 31.756882 -158.972259)
			(xy 31.55737 -159.037084) (xy 31.355535 -159.094267) (xy 31.151669 -159.143725) (xy 30.946068 -159.185385)
			(xy 30.73903 -159.219187) (xy 30.530856 -159.245083) (xy 30.321846 -159.263035) (xy 30.112304 -159.273017)
			(xy 29.902535 -159.275014) (xy 29.692841 -159.269023) (xy 29.483528 -159.255054) (xy 29.274898 -159.233126)
			(xy 29.067254 -159.203272) (xy 28.860897 -159.165533) (xy 28.656127 -159.119966) (xy 28.45324 -159.066637)
			(xy 28.25253 -159.005622) (xy 28.054288 -158.93701) (xy 27.858803 -158.8609) (xy 27.666356 -158.777403)
			(xy 27.477228 -158.686641) (xy 27.291693 -158.588744) (xy 27.110019 -158.483854) (xy 26.932469 -158.372124)
			(xy 26.759303 -158.253716) (xy 26.590769 -158.128801) (xy 26.427114 -157.99756) (xy 26.268573 -157.860184)
			(xy 26.115378 -157.716871) (xy 25.967749 -157.567831) (xy 25.825902 -157.413278) (xy 25.690041 -157.253437)
			(xy 25.560364 -157.088539) (xy 25.437059 -156.918824) (xy 25.320305 -156.744538) (xy 25.21027 -156.565933)
			(xy 25.107115 -156.383269) (xy 25.010988 -156.19681) (xy 24.92203 -156.006826) (xy 24.84037 -155.813594)
			(xy 24.766125 -155.617393) (xy 24.699403 -155.418507) (xy 24.640301 -155.217225) (xy 24.588905 -155.01384)
			(xy 24.54529 -154.808645) (xy 24.509518 -154.601938) (xy 24.481641 -154.394019) (xy 24.4617 -154.18519)
			(xy 24.449724 -153.975753) (xy 24.445731 -153.766012) (xy 21.820378 -153.766012) (xy 21.820378 -159.093154)
			(xy 21.820846 -159.106778) (xy 21.828113 -159.133041) (xy 21.842061 -159.156451) (xy 21.8617 -159.175342)
			(xy 21.885633 -159.188373) (xy 21.912158 -159.194616) (xy 21.925788 -159.1945) (xy 21.960586 -159.192976)
			(xy 21.986966 -159.19342) (xy 22.039222 -159.200682) (xy 22.089982 -159.21507) (xy 22.138277 -159.236308)
			(xy 22.183188 -159.263994) (xy 22.22386 -159.2976) (xy 22.259517 -159.336485) (xy 22.289482 -159.379909)
			(xy 22.301708 -159.403288) (xy 22.30841 -159.415647) (xy 22.327385 -159.436375) (xy 22.351299 -159.451137)
			(xy 22.378335 -159.458809) (xy 22.406437 -159.458809) (xy 22.433473 -159.451137) (xy 22.457387 -159.436375)
			(xy 22.476362 -159.415647) (xy 22.483064 -159.403288) (xy 22.495308 -159.379919) (xy 22.525267 -159.336494)
			(xy 22.56092 -159.297608) (xy 22.601589 -159.264003) (xy 22.646499 -159.236319) (xy 22.694793 -159.215084)
			(xy 22.745552 -159.200703) (xy 22.797808 -159.193449) (xy 22.824186 -159.192976) (xy 22.851441 -159.193438)
			(xy 22.905395 -159.201194) (xy 22.957697 -159.216549) (xy 23.007281 -159.239192) (xy 23.053138 -159.268661)
			(xy 23.094334 -159.304356) (xy 23.130031 -159.345551) (xy 23.159502 -159.391406) (xy 23.182146 -159.44099)
			(xy 23.197503 -159.493291) (xy 23.205261 -159.547245) (xy 23.205261 -159.601755) (xy 23.197503 -159.655709)
			(xy 23.182146 -159.70801) (xy 23.159502 -159.757594) (xy 23.130031 -159.803449) (xy 23.094334 -159.844644)
			(xy 23.053138 -159.880339) (xy 23.007281 -159.909808) (xy 22.957697 -159.932451) (xy 22.905395 -159.947806)
			(xy 22.851441 -159.955562) (xy 22.824186 -159.955992) (xy 22.797808 -159.955546) (xy 22.745554 -159.94828)
			(xy 22.694799 -159.933889) (xy 22.646508 -159.912648) (xy 22.601602 -159.884959) (xy 22.560935 -159.851351)
			(xy 22.525284 -159.812465) (xy 22.495325 -159.76904) (xy 22.483064 -159.74568) (xy 22.476362 -159.733321)
			(xy 22.457387 -159.712593) (xy 22.433473 -159.697831) (xy 22.406437 -159.690159) (xy 22.378335 -159.690159)
			(xy 22.351299 -159.697831) (xy 22.327385 -159.712593) (xy 22.30841 -159.733321) (xy 22.301708 -159.74568)
			(xy 22.289466 -159.769053) (xy 22.259512 -159.812488) (xy 22.223861 -159.851384) (xy 22.183193 -159.884999)
			(xy 22.138284 -159.912694) (xy 22.089988 -159.933939) (xy 22.039227 -159.948332) (xy 21.986967 -159.955596)
			(xy 21.960586 -159.955992) (xy 21.925788 -159.954468) (xy 21.912149 -159.954383) (xy 21.885601 -159.960588)
			(xy 21.861642 -159.973598) (xy 21.841981 -159.992486) (xy 21.82802 -160.015904) (xy 21.820756 -160.042183)
			(xy 21.820378 -160.055814) (xy 21.820378 -161.154364) (xy 25.594308 -161.154364) (xy 25.598379 -161.098742)
			(xy 25.610505 -161.044305) (xy 25.630428 -160.992214) (xy 25.657724 -160.943579) (xy 25.69181 -160.899436)
			(xy 25.731959 -160.860727) (xy 25.777317 -160.828276) (xy 25.826917 -160.802775) (xy 25.879701 -160.784768)
			(xy 25.934544 -160.774638) (xy 25.990278 -160.772601) (xy 26.045715 -160.778701) (xy 26.099672 -160.792807)
			(xy 26.151001 -160.814619) (xy 26.198607 -160.843673) (xy 26.241475 -160.879348) (xy 26.278692 -160.920885)
			(xy 26.309465 -160.967398) (xy 26.309713 -160.967928) (xy 26.570432 -160.967928) (xy 26.570946 -160.940755)
			(xy 26.578642 -160.886956) (xy 26.593896 -160.834795) (xy 26.6164 -160.785326) (xy 26.645697 -160.739553)
			(xy 26.681194 -160.698402) (xy 26.722173 -160.662705) (xy 26.767804 -160.633187) (xy 26.817163 -160.610444)
			(xy 26.86925 -160.594938) (xy 26.89606 -160.590484) (xy 26.90991 -160.587923) (xy 26.935569 -160.576339)
			(xy 26.957091 -160.558192) (xy 26.972845 -160.53486) (xy 26.981632 -160.508114) (xy 26.982786 -160.479985)
			(xy 26.97622 -160.45261) (xy 26.96972 -160.440116) (xy 26.958083 -160.418595) (xy 26.939749 -160.373234)
			(xy 26.927352 -160.325905) (xy 26.921095 -160.277381) (xy 26.920698 -160.252918) (xy 26.921172 -160.225665)
			(xy 26.928927 -160.171714) (xy 26.944281 -160.119416) (xy 26.966922 -160.069836) (xy 26.996388 -160.023982)
			(xy 27.032081 -159.982789) (xy 27.073273 -159.947096) (xy 27.119125 -159.917627) (xy 27.168705 -159.894985)
			(xy 27.221003 -159.879629) (xy 27.274953 -159.871873) (xy 27.302206 -159.87141) (xy 27.329163 -159.871906)
			(xy 27.38254 -159.879496) (xy 27.434317 -159.894525) (xy 27.483463 -159.916692) (xy 27.528999 -159.945556)
			(xy 27.570019 -159.980543) (xy 27.58821 -160.000442) (xy 27.5982 -160.011136) (xy 27.622961 -160.026717)
			(xy 27.651124 -160.034637) (xy 27.680377 -160.034246) (xy 27.708318 -160.025576) (xy 27.732653 -160.009339)
			(xy 27.742388 -159.99841) (xy 27.760611 -159.977409) (xy 27.802113 -159.940408) (xy 27.848545 -159.909821)
			(xy 27.898924 -159.886295) (xy 27.952183 -159.870329) (xy 28.007195 -159.86226) (xy 28.034996 -159.861758)
			(xy 28.062246 -159.862281) (xy 28.11619 -159.870036) (xy 28.168482 -159.885389) (xy 28.218057 -159.908028)
			(xy 28.263906 -159.93749) (xy 28.305095 -159.973178) (xy 28.340787 -160.014364) (xy 28.370254 -160.060209)
			(xy 28.392897 -160.109782) (xy 28.408255 -160.162073) (xy 28.416016 -160.216016) (xy 28.416504 -160.243266)
			(xy 28.41498 -160.278064) (xy 28.414165 -160.293081) (xy 28.420272 -160.322513) (xy 28.434692 -160.348886)
			(xy 28.456174 -160.369911) (xy 28.482851 -160.383762) (xy 28.49753 -160.38703) (xy 28.526432 -160.392984)
			(xy 28.582076 -160.412623) (xy 28.634041 -160.440578) (xy 28.681095 -160.476185) (xy 28.702 -160.497012)
			(xy 28.713208 -160.507706) (xy 28.740419 -160.522471) (xy 28.770798 -160.528431) (xy 28.801571 -160.525042)
			(xy 28.829926 -160.512612) (xy 28.841954 -160.502854) (xy 28.862902 -160.485138) (xy 28.908953 -160.455318)
			(xy 28.958804 -160.43241) (xy 29.011425 -160.416888) (xy 29.065728 -160.409072) (xy 29.09316 -160.40862)
			(xy 29.122313 -160.409181) (xy 29.179938 -160.41806) (xy 29.235541 -160.435603) (xy 29.287829 -160.4614)
			(xy 29.335584 -160.494852) (xy 29.377693 -160.535179) (xy 29.413177 -160.581443) (xy 29.427678 -160.60674)
			(xy 29.435187 -160.619327) (xy 29.455948 -160.639992) (xy 29.481718 -160.653918) (xy 29.510381 -160.659958)
			(xy 29.53958 -160.657617) (xy 29.566914 -160.647087) (xy 29.590137 -160.629234) (xy 29.599128 -160.617662)
			(xy 29.61455 -160.596998) (xy 29.650085 -160.559636) (xy 29.690329 -160.5274) (xy 29.734547 -160.500876)
			(xy 29.781933 -160.480549) (xy 29.831626 -160.466789) (xy 29.882719 -160.459845) (xy 29.9085 -160.45942)
			(xy 29.934856 -160.459881) (xy 29.987065 -160.467149) (xy 30.037778 -160.481532) (xy 30.086028 -160.502757)
			(xy 30.130899 -160.53042) (xy 30.171536 -160.563994) (xy 30.189678 -160.583118) (xy 30.198948 -160.592739)
			(xy 30.221445 -160.607141) (xy 30.246909 -160.615206) (xy 30.273594 -160.616381) (xy 30.299669 -160.610586)
			(xy 30.323344 -160.598219) (xy 30.333442 -160.589468) (xy 30.354685 -160.570621) (xy 30.4017 -160.53877)
			(xy 30.452918 -160.514243) (xy 30.507207 -160.497582) (xy 30.563366 -160.489155) (xy 30.59176 -160.48863)
			(xy 30.619017 -160.489014) (xy 30.672978 -160.496767) (xy 30.725286 -160.512121) (xy 30.774876 -160.534764)
			(xy 30.820739 -160.564234) (xy 30.861941 -160.599931) (xy 30.897642 -160.641129) (xy 30.927117 -160.686989)
			(xy 30.949765 -160.736576) (xy 30.965124 -160.788883) (xy 30.972883 -160.842843) (xy 30.972883 -160.897357)
			(xy 30.965124 -160.951317) (xy 30.949765 -161.003624) (xy 30.927117 -161.053211) (xy 30.897642 -161.099071)
			(xy 30.861941 -161.140269) (xy 30.826616 -161.170874) (xy 33.5186 -161.170874) (xy 33.522671 -161.115252)
			(xy 33.534797 -161.060815) (xy 33.55472 -161.008724) (xy 33.582016 -160.960089) (xy 33.616102 -160.915946)
			(xy 33.656251 -160.877237) (xy 33.701609 -160.844786) (xy 33.751209 -160.819285) (xy 33.803993 -160.801278)
			(xy 33.858836 -160.791148) (xy 33.91457 -160.789111) (xy 33.970007 -160.795211) (xy 34.023964 -160.809317)
			(xy 34.075293 -160.831129) (xy 34.122899 -160.860183) (xy 34.165767 -160.895858) (xy 34.202984 -160.937395)
			(xy 34.233757 -160.983908) (xy 34.257429 -161.034405) (xy 34.273497 -161.087812) (xy 34.281617 -161.142988)
			(xy 34.282126 -161.170874) (xy 34.281617 -161.19876) (xy 34.273497 -161.253936) (xy 34.257429 -161.307343)
			(xy 34.233757 -161.35784) (xy 34.202984 -161.404353) (xy 34.165767 -161.44589) (xy 34.122899 -161.481565)
			(xy 34.075293 -161.510619) (xy 34.023964 -161.532431) (xy 33.970007 -161.546537) (xy 33.91457 -161.552637)
			(xy 33.858836 -161.5506) (xy 33.803993 -161.54047) (xy 33.751209 -161.522463) (xy 33.701609 -161.496962)
			(xy 33.656251 -161.464511) (xy 33.616102 -161.425802) (xy 33.582016 -161.381659) (xy 33.55472 -161.333024)
			(xy 33.534797 -161.280933) (xy 33.522671 -161.226496) (xy 33.5186 -161.170874) (xy 30.826616 -161.170874)
			(xy 30.820739 -161.175966) (xy 30.774876 -161.205436) (xy 30.725286 -161.228079) (xy 30.672978 -161.243433)
			(xy 30.619017 -161.251186) (xy 30.59176 -161.251646) (xy 30.565402 -161.251223) (xy 30.513191 -161.243949)
			(xy 30.462478 -161.229559) (xy 30.414227 -161.208327) (xy 30.369357 -161.180657) (xy 30.328723 -161.147075)
			(xy 30.310582 -161.127948) (xy 30.301256 -161.118382) (xy 30.278778 -161.103969) (xy 30.253326 -161.095892)
			(xy 30.22665 -161.094705) (xy 30.200582 -161.100491) (xy 30.176913 -161.112851) (xy 30.166818 -161.121598)
			(xy 30.145586 -161.140458) (xy 30.098569 -161.172308) (xy 30.047348 -161.196834) (xy 29.993056 -161.213491)
			(xy 29.936895 -161.221913) (xy 29.9085 -161.222436) (xy 29.879345 -161.22193) (xy 29.821716 -161.213043)
			(xy 29.76611 -161.195493) (xy 29.713822 -161.169687) (xy 29.666068 -161.136226) (xy 29.62396 -161.09589)
			(xy 29.58848 -161.049617) (xy 29.573982 -161.024316) (xy 29.566526 -161.011692) (xy 29.545759 -160.991013)
			(xy 29.519977 -160.977081) (xy 29.491299 -160.971041) (xy 29.462087 -160.973391) (xy 29.434744 -160.983937)
			(xy 29.41152 -161.001811) (xy 29.402532 -161.013394) (xy 29.387061 -161.03402) (xy 29.351535 -161.071385)
			(xy 29.311301 -161.103626) (xy 29.267092 -161.130155) (xy 29.219712 -161.150488) (xy 29.170026 -161.164256)
			(xy 29.118939 -161.171207) (xy 29.09316 -161.171636) (xy 29.067638 -161.171269) (xy 29.017049 -161.164468)
			(xy 28.967819 -161.15098) (xy 28.920828 -161.131046) (xy 28.876916 -161.105023) (xy 28.836868 -161.073374)
			(xy 28.81884 -161.055304) (xy 28.807683 -161.044552) (xy 28.780455 -161.02979) (xy 28.750059 -161.02384)
			(xy 28.719275 -161.027244) (xy 28.690915 -161.039693) (xy 28.678886 -161.049462) (xy 28.657912 -161.067146)
			(xy 28.611869 -161.096973) (xy 28.562025 -161.119889) (xy 28.509409 -161.135419) (xy 28.45511 -161.143241)
			(xy 28.42768 -161.143696) (xy 28.400428 -161.143241) (xy 28.346478 -161.135481) (xy 28.294182 -161.120123)
			(xy 28.244604 -161.097479) (xy 28.198753 -161.068009) (xy 28.157563 -161.032314) (xy 28.121872 -160.991121)
			(xy 28.092406 -160.945268) (xy 28.069766 -160.895688) (xy 28.054412 -160.84339) (xy 28.046657 -160.78944)
			(xy 28.046172 -160.762188) (xy 28.047696 -160.72739) (xy 28.048492 -160.712374) (xy 28.042378 -160.682951)
			(xy 28.027959 -160.656584) (xy 28.006486 -160.635559) (xy 27.97982 -160.6217) (xy 27.965146 -160.618424)
			(xy 27.94033 -160.613351) (xy 27.892202 -160.597564) (xy 27.846588 -160.575544) (xy 27.804291 -160.54768)
			(xy 27.766054 -160.514462) (xy 27.748992 -160.495742) (xy 27.738999 -160.485052) (xy 27.714238 -160.469473)
			(xy 27.686077 -160.461554) (xy 27.656825 -160.461945) (xy 27.628885 -160.470613) (xy 27.604549 -160.486847)
			(xy 27.594814 -160.497774) (xy 27.576613 -160.51873) (xy 27.535206 -160.555693) (xy 27.48888 -160.586264)
			(xy 27.438613 -160.6098) (xy 27.385466 -160.625802) (xy 27.358086 -160.630362) (xy 27.344215 -160.632826)
			(xy 27.318551 -160.644429) (xy 27.297027 -160.662594) (xy 27.281276 -160.685943) (xy 27.272494 -160.712704)
			(xy 27.271346 -160.740845) (xy 27.277921 -160.768232) (xy 27.284426 -160.78073) (xy 27.296085 -160.80224)
			(xy 27.314413 -160.847605) (xy 27.326803 -160.894938) (xy 27.333054 -160.943464) (xy 27.333448 -160.967928)
			(xy 27.332962 -160.995179) (xy 27.325206 -161.049127) (xy 27.309851 -161.101422) (xy 27.287209 -161.150999)
			(xy 27.257743 -161.196849) (xy 27.222052 -161.23804) (xy 27.180861 -161.273731) (xy 27.135011 -161.303197)
			(xy 27.085434 -161.325839) (xy 27.033139 -161.341194) (xy 26.979191 -161.34895) (xy 26.924689 -161.34895)
			(xy 26.870741 -161.341194) (xy 26.818446 -161.325839) (xy 26.768869 -161.303197) (xy 26.723019 -161.273731)
			(xy 26.681828 -161.23804) (xy 26.646137 -161.196849) (xy 26.616671 -161.150999) (xy 26.594029 -161.101422)
			(xy 26.578674 -161.049127) (xy 26.570918 -160.995179) (xy 26.570432 -160.967928) (xy 26.309713 -160.967928)
			(xy 26.333137 -161.017895) (xy 26.349205 -161.071302) (xy 26.357325 -161.126478) (xy 26.357834 -161.154364)
			(xy 26.357325 -161.18225) (xy 26.349205 -161.237426) (xy 26.333137 -161.290833) (xy 26.309465 -161.34133)
			(xy 26.278692 -161.387843) (xy 26.241475 -161.42938) (xy 26.198607 -161.465055) (xy 26.151001 -161.494109)
			(xy 26.099672 -161.515921) (xy 26.045715 -161.530027) (xy 25.990278 -161.536127) (xy 25.934544 -161.53409)
			(xy 25.879701 -161.52396) (xy 25.826917 -161.505953) (xy 25.777317 -161.480452) (xy 25.731959 -161.448001)
			(xy 25.69181 -161.409292) (xy 25.657724 -161.365149) (xy 25.630428 -161.316514) (xy 25.610505 -161.264423)
			(xy 25.598379 -161.209986) (xy 25.594308 -161.154364) (xy 21.820378 -161.154364) (xy 21.820378 -162.067748)
			(xy 30.453582 -162.067748) (xy 30.457653 -162.012126) (xy 30.469779 -161.957689) (xy 30.489702 -161.905598)
			(xy 30.516998 -161.856963) (xy 30.551084 -161.81282) (xy 30.591233 -161.774111) (xy 30.636591 -161.74166)
			(xy 30.686191 -161.716159) (xy 30.738975 -161.698152) (xy 30.793818 -161.688022) (xy 30.849552 -161.685985)
			(xy 30.904989 -161.692085) (xy 30.958946 -161.706191) (xy 31.010275 -161.728003) (xy 31.057881 -161.757057)
			(xy 31.100749 -161.792732) (xy 31.137966 -161.834269) (xy 31.168739 -161.880782) (xy 31.192411 -161.931279)
			(xy 31.208479 -161.984686) (xy 31.216599 -162.039862) (xy 31.217108 -162.067748) (xy 31.216599 -162.095634)
			(xy 31.208479 -162.15081) (xy 31.192411 -162.204217) (xy 31.168739 -162.254714) (xy 31.137966 -162.301227)
			(xy 31.100749 -162.342764) (xy 31.057881 -162.378439) (xy 31.010275 -162.407493) (xy 30.958946 -162.429305)
			(xy 30.904989 -162.443411) (xy 30.849552 -162.449511) (xy 30.793818 -162.447474) (xy 30.738975 -162.437344)
			(xy 30.686191 -162.419337) (xy 30.636591 -162.393836) (xy 30.591233 -162.361385) (xy 30.551084 -162.322676)
			(xy 30.516998 -162.278533) (xy 30.489702 -162.229898) (xy 30.469779 -162.177807) (xy 30.457653 -162.12337)
			(xy 30.453582 -162.067748) (xy 21.820378 -162.067748) (xy 21.820378 -162.586162) (xy 33.079942 -162.586162)
			(xy 33.084013 -162.53054) (xy 33.096139 -162.476103) (xy 33.116062 -162.424012) (xy 33.143358 -162.375377)
			(xy 33.177444 -162.331234) (xy 33.217593 -162.292525) (xy 33.262951 -162.260074) (xy 33.312551 -162.234573)
			(xy 33.365335 -162.216566) (xy 33.420178 -162.206436) (xy 33.475912 -162.204399) (xy 33.531349 -162.210499)
			(xy 33.585306 -162.224605) (xy 33.636635 -162.246417) (xy 33.684241 -162.275471) (xy 33.727109 -162.311146)
			(xy 33.764326 -162.352683) (xy 33.795099 -162.399196) (xy 33.818771 -162.449693) (xy 33.834839 -162.5031)
			(xy 33.842959 -162.558276) (xy 33.843468 -162.586162) (xy 33.842959 -162.614048) (xy 33.834839 -162.669224)
			(xy 33.818771 -162.722631) (xy 33.795099 -162.773128) (xy 33.764326 -162.819641) (xy 33.727109 -162.861178)
			(xy 33.684241 -162.896853) (xy 33.636635 -162.925907) (xy 33.585306 -162.947719) (xy 33.531349 -162.961825)
			(xy 33.475912 -162.967925) (xy 33.420178 -162.965888) (xy 33.365335 -162.955758) (xy 33.312551 -162.937751)
			(xy 33.262951 -162.91225) (xy 33.217593 -162.879799) (xy 33.177444 -162.84109) (xy 33.143358 -162.796947)
			(xy 33.116062 -162.748312) (xy 33.096139 -162.696221) (xy 33.084013 -162.641784) (xy 33.079942 -162.586162)
			(xy 21.820378 -162.586162) (xy 21.820378 -163.392104) (xy 22.73884 -163.392104) (xy 22.742911 -163.336482)
			(xy 22.755037 -163.282045) (xy 22.77496 -163.229954) (xy 22.802256 -163.181319) (xy 22.836342 -163.137176)
			(xy 22.876491 -163.098467) (xy 22.921849 -163.066016) (xy 22.971449 -163.040515) (xy 23.024233 -163.022508)
			(xy 23.079076 -163.012378) (xy 23.13481 -163.010341) (xy 23.190247 -163.016441) (xy 23.244204 -163.030547)
			(xy 23.295533 -163.052359) (xy 23.343139 -163.081413) (xy 23.386007 -163.117088) (xy 23.423224 -163.158625)
			(xy 23.453997 -163.205138) (xy 23.477669 -163.255635) (xy 23.493737 -163.309042) (xy 23.501857 -163.364218)
			(xy 23.502366 -163.392104) (xy 23.501857 -163.41999) (xy 23.493737 -163.475166) (xy 23.477669 -163.528573)
			(xy 23.453997 -163.57907) (xy 23.428637 -163.617402) (xy 31.594042 -163.617402) (xy 31.598113 -163.56178)
			(xy 31.610239 -163.507343) (xy 31.630162 -163.455252) (xy 31.657458 -163.406617) (xy 31.691544 -163.362474)
			(xy 31.731693 -163.323765) (xy 31.777051 -163.291314) (xy 31.826651 -163.265813) (xy 31.879435 -163.247806)
			(xy 31.934278 -163.237676) (xy 31.990012 -163.235639) (xy 32.045449 -163.241739) (xy 32.099406 -163.255845)
			(xy 32.150735 -163.277657) (xy 32.198341 -163.306711) (xy 32.241209 -163.342386) (xy 32.278426 -163.383923)
			(xy 32.309199 -163.430436) (xy 32.332871 -163.480933) (xy 32.348939 -163.53434) (xy 32.357059 -163.589516)
			(xy 32.357568 -163.617402) (xy 32.357059 -163.645288) (xy 32.348939 -163.700464) (xy 32.332871 -163.753871)
			(xy 32.309199 -163.804368) (xy 32.278426 -163.850881) (xy 32.241209 -163.892418) (xy 32.198341 -163.928093)
			(xy 32.150735 -163.957147) (xy 32.099406 -163.978959) (xy 32.045449 -163.993065) (xy 31.990012 -163.999165)
			(xy 31.934278 -163.997128) (xy 31.879435 -163.986998) (xy 31.826651 -163.968991) (xy 31.777051 -163.94349)
			(xy 31.731693 -163.911039) (xy 31.691544 -163.87233) (xy 31.657458 -163.828187) (xy 31.630162 -163.779552)
			(xy 31.610239 -163.727461) (xy 31.598113 -163.673024) (xy 31.594042 -163.617402) (xy 23.428637 -163.617402)
			(xy 23.423224 -163.625583) (xy 23.386007 -163.66712) (xy 23.343139 -163.702795) (xy 23.295533 -163.731849)
			(xy 23.244204 -163.753661) (xy 23.190247 -163.767767) (xy 23.13481 -163.773867) (xy 23.079076 -163.77183)
			(xy 23.024233 -163.7617) (xy 22.971449 -163.743693) (xy 22.921849 -163.718192) (xy 22.876491 -163.685741)
			(xy 22.836342 -163.647032) (xy 22.802256 -163.602889) (xy 22.77496 -163.554254) (xy 22.755037 -163.502163)
			(xy 22.742911 -163.447726) (xy 22.73884 -163.392104) (xy 21.820378 -163.392104) (xy 21.820378 -164.302694)
			(xy 33.044382 -164.302694) (xy 33.048453 -164.247072) (xy 33.060579 -164.192635) (xy 33.080502 -164.140544)
			(xy 33.107798 -164.091909) (xy 33.141884 -164.047766) (xy 33.182033 -164.009057) (xy 33.227391 -163.976606)
			(xy 33.276991 -163.951105) (xy 33.329775 -163.933098) (xy 33.384618 -163.922968) (xy 33.440352 -163.920931)
			(xy 33.495789 -163.927031) (xy 33.549746 -163.941137) (xy 33.601075 -163.962949) (xy 33.648681 -163.992003)
			(xy 33.691549 -164.027678) (xy 33.728766 -164.069215) (xy 33.759539 -164.115728) (xy 33.783211 -164.166225)
			(xy 33.799279 -164.219632) (xy 33.807399 -164.274808) (xy 33.807908 -164.302694) (xy 33.807399 -164.33058)
			(xy 33.799279 -164.385756) (xy 33.783211 -164.439163) (xy 33.759539 -164.48966) (xy 33.728766 -164.536173)
			(xy 33.691549 -164.57771) (xy 33.648681 -164.613385) (xy 33.601075 -164.642439) (xy 33.549746 -164.664251)
			(xy 33.495789 -164.678357) (xy 33.440352 -164.684457) (xy 33.384618 -164.68242) (xy 33.329775 -164.67229)
			(xy 33.276991 -164.654283) (xy 33.227391 -164.628782) (xy 33.182033 -164.596331) (xy 33.141884 -164.557622)
			(xy 33.107798 -164.513479) (xy 33.080502 -164.464844) (xy 33.060579 -164.412753) (xy 33.048453 -164.358316)
			(xy 33.044382 -164.302694) (xy 21.820378 -164.302694) (xy 21.820378 -164.994336) (xy 22.751794 -164.994336)
			(xy 22.755865 -164.938714) (xy 22.767991 -164.884277) (xy 22.787914 -164.832186) (xy 22.81521 -164.783551)
			(xy 22.849296 -164.739408) (xy 22.889445 -164.700699) (xy 22.934803 -164.668248) (xy 22.984403 -164.642747)
			(xy 23.037187 -164.62474) (xy 23.09203 -164.61461) (xy 23.147764 -164.612573) (xy 23.203201 -164.618673)
			(xy 23.257158 -164.632779) (xy 23.308487 -164.654591) (xy 23.356093 -164.683645) (xy 23.398961 -164.71932)
			(xy 23.436178 -164.760857) (xy 23.466951 -164.80737) (xy 23.490623 -164.857867) (xy 23.506691 -164.911274)
			(xy 23.514811 -164.96645) (xy 23.51532 -164.994336) (xy 23.514811 -165.022222) (xy 23.506691 -165.077398)
			(xy 23.490623 -165.130805) (xy 23.466951 -165.181302) (xy 23.436178 -165.227815) (xy 23.398961 -165.269352)
			(xy 23.356093 -165.305027) (xy 23.308487 -165.334081) (xy 23.257158 -165.355893) (xy 23.203201 -165.369999)
			(xy 23.147764 -165.376099) (xy 23.09203 -165.374062) (xy 23.037187 -165.363932) (xy 22.984403 -165.345925)
			(xy 22.934803 -165.320424) (xy 22.889445 -165.287973) (xy 22.849296 -165.249264) (xy 22.81521 -165.205121)
			(xy 22.787914 -165.156486) (xy 22.767991 -165.104395) (xy 22.755865 -165.049958) (xy 22.751794 -164.994336)
			(xy 21.820378 -164.994336) (xy 21.820378 -165.591236) (xy 30.677612 -165.591236) (xy 30.678089 -165.563983)
			(xy 30.685841 -165.510032) (xy 30.701194 -165.457733) (xy 30.723834 -165.408151) (xy 30.7533 -165.362297)
			(xy 30.788992 -165.321104) (xy 30.830184 -165.285409) (xy 30.876037 -165.255941) (xy 30.925618 -165.2333)
			(xy 30.977916 -165.217945) (xy 31.031867 -165.21019) (xy 31.05912 -165.209728) (xy 31.074876 -165.20987)
			(xy 31.106285 -165.21241) (xy 31.121858 -165.214808) (xy 31.136247 -165.216682) (xy 31.165042 -165.213223)
			(xy 31.191699 -165.2018) (xy 31.214065 -165.183337) (xy 31.230331 -165.159326) (xy 31.239182 -165.131707)
			(xy 31.239903 -165.102714) (xy 31.236666 -165.08857) (xy 31.230712 -165.064563) (xy 31.224341 -165.015512)
			(xy 31.223966 -164.99078) (xy 31.224477 -164.963529) (xy 31.232236 -164.909581) (xy 31.247594 -164.857286)
			(xy 31.270238 -164.80771) (xy 31.299707 -164.76186) (xy 31.335401 -164.720672) (xy 31.376594 -164.684982)
			(xy 31.422447 -164.655518) (xy 31.472026 -164.63288) (xy 31.524322 -164.617527) (xy 31.57827 -164.609774)
			(xy 31.632773 -164.609777) (xy 31.686721 -164.617537) (xy 31.739016 -164.632895) (xy 31.788592 -164.655539)
			(xy 31.834441 -164.685009) (xy 31.87563 -164.720703) (xy 31.911319 -164.761896) (xy 31.940783 -164.807748)
			(xy 31.963421 -164.857327) (xy 31.978773 -164.909624) (xy 31.986526 -164.963572) (xy 31.986523 -165.018075)
			(xy 31.978763 -165.072023) (xy 31.963404 -165.124318) (xy 31.94076 -165.173894) (xy 31.91129 -165.219743)
			(xy 31.875596 -165.260931) (xy 31.834403 -165.29662) (xy 31.78855 -165.326084) (xy 31.738971 -165.348722)
			(xy 31.686674 -165.364074) (xy 31.632726 -165.371827) (xy 31.605474 -165.372288) (xy 31.589718 -165.372146)
			(xy 31.558309 -165.369606) (xy 31.542736 -165.367208) (xy 31.528349 -165.365308) (xy 31.49955 -165.368769)
			(xy 31.472889 -165.380195) (xy 31.450522 -165.398663) (xy 31.434256 -165.422679) (xy 31.425406 -165.450303)
			(xy 31.424689 -165.4793) (xy 31.427928 -165.493446) (xy 31.433885 -165.517453) (xy 31.440254 -165.566504)
			(xy 31.440628 -165.591236) (xy 31.440072 -165.62106) (xy 31.430817 -165.679986) (xy 31.412508 -165.736754)
			(xy 31.385589 -165.789982) (xy 31.350717 -165.838374) (xy 31.330138 -165.859968) (xy 31.320921 -165.869896)
			(xy 31.307608 -165.893478) (xy 31.300954 -165.919729) (xy 31.301426 -165.946805) (xy 31.308991 -165.972808)
			(xy 31.323119 -165.995911) (xy 31.332678 -166.00551) (xy 31.351326 -166.023609) (xy 31.384039 -166.063986)
			(xy 31.410967 -166.108431) (xy 31.43161 -166.15612) (xy 31.445586 -166.206172) (xy 31.452637 -166.257657)
			(xy 31.453074 -166.28364) (xy 31.452588 -166.310891) (xy 31.444832 -166.364839) (xy 31.429477 -166.417134)
			(xy 31.406835 -166.466711) (xy 31.377369 -166.512561) (xy 31.341678 -166.553752) (xy 31.300487 -166.589443)
			(xy 31.254637 -166.618909) (xy 31.20506 -166.641551) (xy 31.152765 -166.656906) (xy 31.098817 -166.664662)
			(xy 31.044315 -166.664662) (xy 30.990367 -166.656906) (xy 30.938072 -166.641551) (xy 30.888495 -166.618909)
			(xy 30.842645 -166.589443) (xy 30.801454 -166.553752) (xy 30.765763 -166.512561) (xy 30.736297 -166.466711)
			(xy 30.713655 -166.417134) (xy 30.6983 -166.364839) (xy 30.690544 -166.310891) (xy 30.690058 -166.28364)
			(xy 30.690603 -166.253815) (xy 30.699861 -166.19489) (xy 30.718174 -166.138122) (xy 30.745094 -166.084894)
			(xy 30.779968 -166.036502) (xy 30.800548 -166.014908) (xy 30.809791 -166.005002) (xy 30.823104 -165.981413)
			(xy 30.829756 -165.955157) (xy 30.829279 -165.928075) (xy 30.821707 -165.902069) (xy 30.807572 -165.878964)
			(xy 30.798008 -165.869366) (xy 30.779346 -165.851282) (xy 30.746635 -165.810901) (xy 30.719709 -165.766453)
			(xy 30.699069 -165.71876) (xy 30.685095 -165.668707) (xy 30.678047 -165.61722) (xy 30.677612 -165.591236)
			(xy 21.820378 -165.591236) (xy 21.820378 -166.25316) (xy 23.932132 -166.25316) (xy 23.936203 -166.197538)
			(xy 23.948329 -166.143101) (xy 23.968252 -166.09101) (xy 23.995548 -166.042375) (xy 24.029634 -165.998232)
			(xy 24.069783 -165.959523) (xy 24.115141 -165.927072) (xy 24.164741 -165.901571) (xy 24.217525 -165.883564)
			(xy 24.272368 -165.873434) (xy 24.328102 -165.871397) (xy 24.383539 -165.877497) (xy 24.437496 -165.891603)
			(xy 24.488825 -165.913415) (xy 24.536431 -165.942469) (xy 24.579299 -165.978144) (xy 24.616516 -166.019681)
			(xy 24.647289 -166.066194) (xy 24.670961 -166.116691) (xy 24.687029 -166.170098) (xy 24.695149 -166.225274)
			(xy 24.695658 -166.25316) (xy 24.695149 -166.281046) (xy 24.687029 -166.336222) (xy 24.670961 -166.389629)
			(xy 24.647289 -166.440126) (xy 24.616516 -166.486639) (xy 24.579299 -166.528176) (xy 24.536431 -166.563851)
			(xy 24.488825 -166.592905) (xy 24.437496 -166.614717) (xy 24.383539 -166.628823) (xy 24.328102 -166.634923)
			(xy 24.272368 -166.632886) (xy 24.217525 -166.622756) (xy 24.164741 -166.604749) (xy 24.115141 -166.579248)
			(xy 24.069783 -166.546797) (xy 24.029634 -166.508088) (xy 23.995548 -166.463945) (xy 23.968252 -166.41531)
			(xy 23.948329 -166.363219) (xy 23.936203 -166.308782) (xy 23.932132 -166.25316) (xy 21.820378 -166.25316)
			(xy 21.820378 -167.543988) (xy 23.966422 -167.543988) (xy 23.970493 -167.488366) (xy 23.982619 -167.433929)
			(xy 24.002542 -167.381838) (xy 24.029838 -167.333203) (xy 24.063924 -167.28906) (xy 24.104073 -167.250351)
			(xy 24.149431 -167.2179) (xy 24.199031 -167.192399) (xy 24.251815 -167.174392) (xy 24.306658 -167.164262)
			(xy 24.362392 -167.162225) (xy 24.417829 -167.168325) (xy 24.471786 -167.182431) (xy 24.523115 -167.204243)
			(xy 24.570721 -167.233297) (xy 24.613589 -167.268972) (xy 24.650806 -167.310509) (xy 24.681579 -167.357022)
			(xy 24.705251 -167.407519) (xy 24.721319 -167.460926) (xy 24.729439 -167.516102) (xy 24.729948 -167.543988)
			(xy 24.729439 -167.571874) (xy 24.721319 -167.62705) (xy 24.705251 -167.680457) (xy 24.681579 -167.730954)
			(xy 24.650806 -167.777467) (xy 24.613589 -167.819004) (xy 24.570721 -167.854679) (xy 24.523115 -167.883733)
			(xy 24.471786 -167.905545) (xy 24.417829 -167.919651) (xy 24.362392 -167.925751) (xy 24.306658 -167.923714)
			(xy 24.251815 -167.913584) (xy 24.199031 -167.895577) (xy 24.149431 -167.870076) (xy 24.104073 -167.837625)
			(xy 24.063924 -167.798916) (xy 24.029838 -167.754773) (xy 24.002542 -167.706138) (xy 23.982619 -167.654047)
			(xy 23.970493 -167.59961) (xy 23.966422 -167.543988) (xy 21.820378 -167.543988) (xy 21.820378 -168.126918)
			(xy 26.807412 -168.126918) (xy 26.811483 -168.071296) (xy 26.823609 -168.016859) (xy 26.843532 -167.964768)
			(xy 26.870828 -167.916133) (xy 26.904914 -167.87199) (xy 26.945063 -167.833281) (xy 26.990421 -167.80083)
			(xy 27.040021 -167.775329) (xy 27.092805 -167.757322) (xy 27.147648 -167.747192) (xy 27.203382 -167.745155)
			(xy 27.258819 -167.751255) (xy 27.312776 -167.765361) (xy 27.364105 -167.787173) (xy 27.411711 -167.816227)
			(xy 27.454579 -167.851902) (xy 27.491796 -167.893439) (xy 27.522569 -167.939952) (xy 27.545203 -167.988234)
			(xy 29.594808 -167.988234) (xy 29.598879 -167.932612) (xy 29.611005 -167.878175) (xy 29.630928 -167.826084)
			(xy 29.658224 -167.777449) (xy 29.69231 -167.733306) (xy 29.732459 -167.694597) (xy 29.777817 -167.662146)
			(xy 29.827417 -167.636645) (xy 29.880201 -167.618638) (xy 29.935044 -167.608508) (xy 29.990778 -167.606471)
			(xy 30.046215 -167.612571) (xy 30.100172 -167.626677) (xy 30.151501 -167.648489) (xy 30.199107 -167.677543)
			(xy 30.241975 -167.713218) (xy 30.279192 -167.754755) (xy 30.309965 -167.801268) (xy 30.333637 -167.851765)
			(xy 30.349705 -167.905172) (xy 30.357825 -167.960348) (xy 30.358334 -167.988234) (xy 30.357825 -168.01612)
			(xy 30.349705 -168.071296) (xy 30.333637 -168.124703) (xy 30.309965 -168.1752) (xy 30.279192 -168.221713)
			(xy 30.241975 -168.26325) (xy 30.199107 -168.298925) (xy 30.151501 -168.327979) (xy 30.100172 -168.349791)
			(xy 30.046215 -168.363897) (xy 29.990778 -168.369997) (xy 29.935044 -168.36796) (xy 29.880201 -168.35783)
			(xy 29.827417 -168.339823) (xy 29.777817 -168.314322) (xy 29.732459 -168.281871) (xy 29.69231 -168.243162)
			(xy 29.658224 -168.199019) (xy 29.630928 -168.150384) (xy 29.611005 -168.098293) (xy 29.598879 -168.043856)
			(xy 29.594808 -167.988234) (xy 27.545203 -167.988234) (xy 27.546241 -167.990449) (xy 27.562309 -168.043856)
			(xy 27.570429 -168.099032) (xy 27.570938 -168.126918) (xy 27.570429 -168.154804) (xy 27.562309 -168.20998)
			(xy 27.546241 -168.263387) (xy 27.522569 -168.313884) (xy 27.491796 -168.360397) (xy 27.454579 -168.401934)
			(xy 27.411711 -168.437609) (xy 27.364105 -168.466663) (xy 27.312776 -168.488475) (xy 27.258819 -168.502581)
			(xy 27.203382 -168.508681) (xy 27.147648 -168.506644) (xy 27.092805 -168.496514) (xy 27.040021 -168.478507)
			(xy 26.990421 -168.453006) (xy 26.945063 -168.420555) (xy 26.904914 -168.381846) (xy 26.870828 -168.337703)
			(xy 26.843532 -168.289068) (xy 26.823609 -168.236977) (xy 26.811483 -168.18254) (xy 26.807412 -168.126918)
			(xy 21.820378 -168.126918) (xy 21.820378 -168.587928) (xy 24.769316 -168.587928) (xy 24.773387 -168.532306)
			(xy 24.785513 -168.477869) (xy 24.805436 -168.425778) (xy 24.832732 -168.377143) (xy 24.866818 -168.333)
			(xy 24.906967 -168.294291) (xy 24.952325 -168.26184) (xy 25.001925 -168.236339) (xy 25.054709 -168.218332)
			(xy 25.109552 -168.208202) (xy 25.165286 -168.206165) (xy 25.220723 -168.212265) (xy 25.27468 -168.226371)
			(xy 25.326009 -168.248183) (xy 25.373615 -168.277237) (xy 25.416483 -168.312912) (xy 25.4537 -168.354449)
			(xy 25.484473 -168.400962) (xy 25.508145 -168.451459) (xy 25.524213 -168.504866) (xy 25.532333 -168.560042)
			(xy 25.532842 -168.587928) (xy 25.532333 -168.615814) (xy 25.524213 -168.67099) (xy 25.508145 -168.724397)
			(xy 25.484473 -168.774894) (xy 25.4537 -168.821407) (xy 25.416483 -168.862944) (xy 25.373615 -168.898619)
			(xy 25.326009 -168.927673) (xy 25.27468 -168.949485) (xy 25.220723 -168.963591) (xy 25.165286 -168.969691)
			(xy 25.109552 -168.967654) (xy 25.054709 -168.957524) (xy 25.001925 -168.939517) (xy 24.952325 -168.914016)
			(xy 24.906967 -168.881565) (xy 24.866818 -168.842856) (xy 24.832732 -168.798713) (xy 24.805436 -168.750078)
			(xy 24.785513 -168.697987) (xy 24.773387 -168.64355) (xy 24.769316 -168.587928) (xy 21.820378 -168.587928)
			(xy 21.820378 -169.09796) (xy 32.975802 -169.09796) (xy 32.979873 -169.042338) (xy 32.991999 -168.987901)
			(xy 33.011922 -168.93581) (xy 33.039218 -168.887175) (xy 33.073304 -168.843032) (xy 33.113453 -168.804323)
			(xy 33.158811 -168.771872) (xy 33.208411 -168.746371) (xy 33.261195 -168.728364) (xy 33.316038 -168.718234)
			(xy 33.371772 -168.716197) (xy 33.427209 -168.722297) (xy 33.481166 -168.736403) (xy 33.532495 -168.758215)
			(xy 33.580101 -168.787269) (xy 33.622969 -168.822944) (xy 33.660186 -168.864481) (xy 33.690959 -168.910994)
			(xy 33.714631 -168.961491) (xy 33.730699 -169.014898) (xy 33.738819 -169.070074) (xy 33.739328 -169.09796)
			(xy 33.738819 -169.125846) (xy 33.730699 -169.181022) (xy 33.714631 -169.234429) (xy 33.690959 -169.284926)
			(xy 33.660186 -169.331439) (xy 33.622969 -169.372976) (xy 33.580101 -169.408651) (xy 33.532495 -169.437705)
			(xy 33.481166 -169.459517) (xy 33.427209 -169.473623) (xy 33.371772 -169.479723) (xy 33.316038 -169.477686)
			(xy 33.261195 -169.467556) (xy 33.208411 -169.449549) (xy 33.158811 -169.424048) (xy 33.113453 -169.391597)
			(xy 33.073304 -169.352888) (xy 33.039218 -169.308745) (xy 33.011922 -169.26011) (xy 32.991999 -169.208019)
			(xy 32.979873 -169.153582) (xy 32.975802 -169.09796) (xy 21.820378 -169.09796) (xy 21.820378 -169.487088)
			(xy 25.88082 -169.487088) (xy 25.884891 -169.431466) (xy 25.897017 -169.377029) (xy 25.91694 -169.324938)
			(xy 25.944236 -169.276303) (xy 25.978322 -169.23216) (xy 26.018471 -169.193451) (xy 26.063829 -169.161)
			(xy 26.113429 -169.135499) (xy 26.166213 -169.117492) (xy 26.221056 -169.107362) (xy 26.27679 -169.105325)
			(xy 26.332227 -169.111425) (xy 26.386184 -169.125531) (xy 26.437513 -169.147343) (xy 26.485119 -169.176397)
			(xy 26.527987 -169.212072) (xy 26.565204 -169.253609) (xy 26.595977 -169.300122) (xy 26.619649 -169.350619)
			(xy 26.635717 -169.404026) (xy 26.643837 -169.459202) (xy 26.644346 -169.487088) (xy 26.643837 -169.514974)
			(xy 26.635717 -169.57015) (xy 26.619649 -169.623557) (xy 26.595977 -169.674054) (xy 26.565204 -169.720567)
			(xy 26.527987 -169.762104) (xy 26.485119 -169.797779) (xy 26.437513 -169.826833) (xy 26.386184 -169.848645)
			(xy 26.332227 -169.862751) (xy 26.27679 -169.868851) (xy 26.221056 -169.866814) (xy 26.166213 -169.856684)
			(xy 26.113429 -169.838677) (xy 26.063829 -169.813176) (xy 26.018471 -169.780725) (xy 25.978322 -169.742016)
			(xy 25.944236 -169.697873) (xy 25.91694 -169.649238) (xy 25.897017 -169.597147) (xy 25.884891 -169.54271)
			(xy 25.88082 -169.487088) (xy 21.820378 -169.487088) (xy 21.820378 -169.73169) (xy 21.822156 -169.745152)
			(xy 21.823172 -169.748454) (xy 21.829585 -169.773298) (xy 21.836467 -169.824145) (xy 21.836888 -169.8498)
			(xy 21.836888 -169.854118) (xy 21.836212 -169.879539) (xy 21.828944 -169.929871) (xy 21.82241 -169.954448)
			(xy 21.820378 -169.96156) (xy 21.820378 -170.67022) (xy 30.752032 -170.67022) (xy 30.756103 -170.614598)
			(xy 30.768229 -170.560161) (xy 30.788152 -170.50807) (xy 30.815448 -170.459435) (xy 30.849534 -170.415292)
			(xy 30.889683 -170.376583) (xy 30.935041 -170.344132) (xy 30.984641 -170.318631) (xy 31.037425 -170.300624)
			(xy 31.092268 -170.290494) (xy 31.148002 -170.288457) (xy 31.203439 -170.294557) (xy 31.257396 -170.308663)
			(xy 31.308725 -170.330475) (xy 31.356331 -170.359529) (xy 31.399199 -170.395204) (xy 31.436416 -170.436741)
			(xy 31.467189 -170.483254) (xy 31.490861 -170.533751) (xy 31.506929 -170.587158) (xy 31.515049 -170.642334)
			(xy 31.515558 -170.67022) (xy 31.515049 -170.698106) (xy 31.506929 -170.753282) (xy 31.490861 -170.806689)
			(xy 31.467189 -170.857186) (xy 31.436416 -170.903699) (xy 31.399199 -170.945236) (xy 31.356331 -170.980911)
			(xy 31.308725 -171.009965) (xy 31.257396 -171.031777) (xy 31.203439 -171.045883) (xy 31.148002 -171.051983)
			(xy 31.092268 -171.049946) (xy 31.037425 -171.039816) (xy 30.984641 -171.021809) (xy 30.935041 -170.996308)
			(xy 30.889683 -170.963857) (xy 30.849534 -170.925148) (xy 30.815448 -170.881005) (xy 30.788152 -170.83237)
			(xy 30.768229 -170.780279) (xy 30.756103 -170.725842) (xy 30.752032 -170.67022) (xy 21.820378 -170.67022)
			(xy 21.820378 -171.709842) (xy 18.73758 -174.79264) (xy 21.571964 -174.79264) (xy 21.576035 -174.737018)
			(xy 21.588161 -174.682581) (xy 21.608084 -174.63049) (xy 21.63538 -174.581855) (xy 21.669466 -174.537712)
			(xy 21.709615 -174.499003) (xy 21.754973 -174.466552) (xy 21.804573 -174.441051) (xy 21.857357 -174.423044)
			(xy 21.9122 -174.412914) (xy 21.967934 -174.410877) (xy 22.023371 -174.416977) (xy 22.077328 -174.431083)
			(xy 22.128657 -174.452895) (xy 22.176263 -174.481949) (xy 22.219131 -174.517624) (xy 22.256348 -174.559161)
			(xy 22.287121 -174.605674) (xy 22.310793 -174.656171) (xy 22.326861 -174.709578) (xy 22.334981 -174.764754)
			(xy 22.33549 -174.79264) (xy 22.334981 -174.820526) (xy 22.326861 -174.875702) (xy 22.314406 -174.9171)
			(xy 25.556462 -174.9171) (xy 25.560533 -174.861478) (xy 25.572659 -174.807041) (xy 25.592582 -174.75495)
			(xy 25.619878 -174.706315) (xy 25.653964 -174.662172) (xy 25.694113 -174.623463) (xy 25.739471 -174.591012)
			(xy 25.789071 -174.565511) (xy 25.841855 -174.547504) (xy 25.896698 -174.537374) (xy 25.952432 -174.535337)
			(xy 26.007869 -174.541437) (xy 26.061826 -174.555543) (xy 26.113155 -174.577355) (xy 26.160761 -174.606409)
			(xy 26.203629 -174.642084) (xy 26.240846 -174.683621) (xy 26.271619 -174.730134) (xy 26.295291 -174.780631)
			(xy 26.311359 -174.834038) (xy 26.319479 -174.889214) (xy 26.319988 -174.9171) (xy 26.319479 -174.944986)
			(xy 26.311359 -175.000162) (xy 26.295291 -175.053569) (xy 26.271619 -175.104066) (xy 26.240846 -175.150579)
			(xy 26.203629 -175.192116) (xy 26.160761 -175.227791) (xy 26.113155 -175.256845) (xy 26.061826 -175.278657)
			(xy 26.007869 -175.292763) (xy 25.952432 -175.298863) (xy 25.896698 -175.296826) (xy 25.841855 -175.286696)
			(xy 25.789071 -175.268689) (xy 25.739471 -175.243188) (xy 25.694113 -175.210737) (xy 25.653964 -175.172028)
			(xy 25.619878 -175.127885) (xy 25.592582 -175.07925) (xy 25.572659 -175.027159) (xy 25.560533 -174.972722)
			(xy 25.556462 -174.9171) (xy 22.314406 -174.9171) (xy 22.310793 -174.929109) (xy 22.287121 -174.979606)
			(xy 22.256348 -175.026119) (xy 22.219131 -175.067656) (xy 22.176263 -175.103331) (xy 22.128657 -175.132385)
			(xy 22.077328 -175.154197) (xy 22.023371 -175.168303) (xy 21.967934 -175.174403) (xy 21.9122 -175.172366)
			(xy 21.857357 -175.162236) (xy 21.804573 -175.144229) (xy 21.754973 -175.118728) (xy 21.709615 -175.086277)
			(xy 21.669466 -175.047568) (xy 21.63538 -175.003425) (xy 21.608084 -174.95479) (xy 21.588161 -174.902699)
			(xy 21.576035 -174.848262) (xy 21.571964 -174.79264) (xy 18.73758 -174.79264) (xy 18.320004 -175.210216)
			(xy 20.264372 -175.210216) (xy 20.268443 -175.154594) (xy 20.280569 -175.100157) (xy 20.300492 -175.048066)
			(xy 20.327788 -174.999431) (xy 20.361874 -174.955288) (xy 20.402023 -174.916579) (xy 20.447381 -174.884128)
			(xy 20.496981 -174.858627) (xy 20.549765 -174.84062) (xy 20.604608 -174.83049) (xy 20.660342 -174.828453)
			(xy 20.715779 -174.834553) (xy 20.769736 -174.848659) (xy 20.821065 -174.870471) (xy 20.868671 -174.899525)
			(xy 20.911539 -174.9352) (xy 20.948756 -174.976737) (xy 20.979529 -175.02325) (xy 21.003201 -175.073747)
			(xy 21.019269 -175.127154) (xy 21.027389 -175.18233) (xy 21.027898 -175.210216) (xy 21.027389 -175.238102)
			(xy 21.019269 -175.293278) (xy 21.003201 -175.346685) (xy 20.979529 -175.397182) (xy 20.948756 -175.443695)
			(xy 20.911539 -175.485232) (xy 20.868671 -175.520907) (xy 20.821065 -175.549961) (xy 20.769736 -175.571773)
			(xy 20.715779 -175.585879) (xy 20.660342 -175.591979) (xy 20.604608 -175.589942) (xy 20.549765 -175.579812)
			(xy 20.496981 -175.561805) (xy 20.447381 -175.536304) (xy 20.402023 -175.503853) (xy 20.361874 -175.465144)
			(xy 20.327788 -175.421001) (xy 20.300492 -175.372366) (xy 20.280569 -175.320275) (xy 20.268443 -175.265838)
			(xy 20.264372 -175.210216) (xy 18.320004 -175.210216) (xy 17.69618 -175.83404) (xy 23.37714 -175.83404)
			(xy 23.381229 -175.778158) (xy 23.393412 -175.723468) (xy 23.413428 -175.671134) (xy 23.440851 -175.622272)
			(xy 23.475096 -175.577924) (xy 23.515432 -175.539034) (xy 23.561002 -175.506432) (xy 23.610833 -175.480813)
			(xy 23.663863 -175.462721) (xy 23.718961 -175.452544) (xy 23.774955 -175.450498) (xy 23.83065 -175.456626)
			(xy 23.884859 -175.470798) (xy 23.936427 -175.492712) (xy 23.984255 -175.521901) (xy 24.027323 -175.557742)
			(xy 24.064713 -175.599472) (xy 24.095629 -175.646202) (xy 24.119412 -175.696935) (xy 24.135554 -175.750591)
			(xy 24.141855 -175.7934) (xy 25.541222 -175.7934) (xy 25.545293 -175.737778) (xy 25.557419 -175.683341)
			(xy 25.577342 -175.63125) (xy 25.604638 -175.582615) (xy 25.638724 -175.538472) (xy 25.678873 -175.499763)
			(xy 25.724231 -175.467312) (xy 25.773831 -175.441811) (xy 25.826615 -175.423804) (xy 25.881458 -175.413674)
			(xy 25.937192 -175.411637) (xy 25.992629 -175.417737) (xy 26.046586 -175.431843) (xy 26.097915 -175.453655)
			(xy 26.145521 -175.482709) (xy 26.156993 -175.492256) (xy 35.295733 -175.492256) (xy 35.295733 -175.437744)
			(xy 35.303491 -175.383786) (xy 35.31885 -175.331482) (xy 35.341497 -175.281896) (xy 35.370971 -175.236039)
			(xy 35.406671 -175.194842) (xy 35.447871 -175.159147) (xy 35.493731 -175.129678) (xy 35.54332 -175.107036)
			(xy 35.595625 -175.091683) (xy 35.649584 -175.08393) (xy 35.67684 -175.08347) (xy 35.70421 -175.083954)
			(xy 35.758389 -175.091765) (xy 35.810892 -175.107249) (xy 35.86064 -175.130087) (xy 35.906607 -175.159809)
			(xy 35.927538 -175.17745) (xy 35.938866 -175.186686) (xy 35.965423 -175.198862) (xy 35.99434 -175.203035)
			(xy 36.023257 -175.198862) (xy 36.049814 -175.186686) (xy 36.061142 -175.17745) (xy 36.082092 -175.159832)
			(xy 36.128059 -175.130116) (xy 36.177802 -175.107275) (xy 36.230299 -175.091779) (xy 36.284472 -175.083946)
			(xy 36.31184 -175.08347) (xy 36.339088 -175.084003) (xy 36.393028 -175.091764) (xy 36.445315 -175.107121)
			(xy 36.494884 -175.129763) (xy 36.540727 -175.159229) (xy 36.58191 -175.194918) (xy 36.617595 -175.236105)
			(xy 36.633929 -175.261524) (xy 51.230528 -175.261524) (xy 51.234599 -175.205902) (xy 51.246725 -175.151465)
			(xy 51.266648 -175.099374) (xy 51.293944 -175.050739) (xy 51.32803 -175.006596) (xy 51.368179 -174.967887)
			(xy 51.413537 -174.935436) (xy 51.463137 -174.909935) (xy 51.515921 -174.891928) (xy 51.570764 -174.881798)
			(xy 51.626498 -174.879761) (xy 51.681935 -174.885861) (xy 51.735892 -174.899967) (xy 51.787221 -174.921779)
			(xy 51.834827 -174.950833) (xy 51.877695 -174.986508) (xy 51.914912 -175.028045) (xy 51.945685 -175.074558)
			(xy 51.969357 -175.125055) (xy 51.985425 -175.178462) (xy 51.993545 -175.233638) (xy 51.994054 -175.261524)
			(xy 51.993957 -175.266858) (xy 52.228748 -175.266858) (xy 52.232819 -175.211236) (xy 52.244945 -175.156799)
			(xy 52.264868 -175.104708) (xy 52.292164 -175.056073) (xy 52.32625 -175.01193) (xy 52.366399 -174.973221)
			(xy 52.411757 -174.94077) (xy 52.461357 -174.915269) (xy 52.514141 -174.897262) (xy 52.568984 -174.887132)
			(xy 52.624718 -174.885095) (xy 52.680155 -174.891195) (xy 52.734112 -174.905301) (xy 52.785441 -174.927113)
			(xy 52.833047 -174.956167) (xy 52.875915 -174.991842) (xy 52.913132 -175.033379) (xy 52.943905 -175.079892)
			(xy 52.967577 -175.130389) (xy 52.983645 -175.183796) (xy 52.991765 -175.238972) (xy 52.992274 -175.266858)
			(xy 52.991765 -175.294744) (xy 52.983645 -175.34992) (xy 52.967577 -175.403327) (xy 52.943905 -175.453824)
			(xy 52.913132 -175.500337) (xy 52.875915 -175.541874) (xy 52.833047 -175.577549) (xy 52.785441 -175.606603)
			(xy 52.734112 -175.628415) (xy 52.680155 -175.642521) (xy 52.624718 -175.648621) (xy 52.568984 -175.646584)
			(xy 52.514141 -175.636454) (xy 52.461357 -175.618447) (xy 52.411757 -175.592946) (xy 52.366399 -175.560495)
			(xy 52.32625 -175.521786) (xy 52.292164 -175.477643) (xy 52.264868 -175.429008) (xy 52.244945 -175.376917)
			(xy 52.232819 -175.32248) (xy 52.228748 -175.266858) (xy 51.993957 -175.266858) (xy 51.993545 -175.28941)
			(xy 51.985425 -175.344586) (xy 51.969357 -175.397993) (xy 51.945685 -175.44849) (xy 51.914912 -175.495003)
			(xy 51.877695 -175.53654) (xy 51.834827 -175.572215) (xy 51.787221 -175.601269) (xy 51.735892 -175.623081)
			(xy 51.681935 -175.637187) (xy 51.626498 -175.643287) (xy 51.570764 -175.64125) (xy 51.515921 -175.63112)
			(xy 51.463137 -175.613113) (xy 51.413537 -175.587612) (xy 51.368179 -175.555161) (xy 51.32803 -175.516452)
			(xy 51.293944 -175.472309) (xy 51.266648 -175.423674) (xy 51.246725 -175.371583) (xy 51.234599 -175.317146)
			(xy 51.230528 -175.261524) (xy 36.633929 -175.261524) (xy 36.647056 -175.281951) (xy 36.669693 -175.331523)
			(xy 36.685045 -175.383811) (xy 36.6928 -175.437752) (xy 36.6928 -175.492248) (xy 36.685045 -175.546189)
			(xy 36.669693 -175.598477) (xy 36.647056 -175.648049) (xy 36.617595 -175.693895) (xy 36.58191 -175.735082)
			(xy 36.540727 -175.770771) (xy 36.494884 -175.800237) (xy 36.445315 -175.822879) (xy 36.393028 -175.838236)
			(xy 36.339088 -175.845997) (xy 36.31184 -175.846486) (xy 36.28447 -175.846) (xy 36.230292 -175.838187)
			(xy 36.177789 -175.822703) (xy 36.128042 -175.799866) (xy 36.082074 -175.770145) (xy 36.061142 -175.752506)
			(xy 36.049814 -175.74327) (xy 36.023257 -175.731094) (xy 35.99434 -175.726921) (xy 35.965423 -175.731094)
			(xy 35.938866 -175.74327) (xy 35.927538 -175.752506) (xy 35.906603 -175.770142) (xy 35.860631 -175.799854)
			(xy 35.810884 -175.82269) (xy 35.758384 -175.838182) (xy 35.704209 -175.846011) (xy 35.67684 -175.846486)
			(xy 35.649584 -175.84607) (xy 35.595625 -175.838317) (xy 35.54332 -175.822964) (xy 35.493731 -175.800322)
			(xy 35.447871 -175.770853) (xy 35.406671 -175.735158) (xy 35.370971 -175.693961) (xy 35.341497 -175.648104)
			(xy 35.31885 -175.598518) (xy 35.303491 -175.546214) (xy 35.295733 -175.492256) (xy 26.156993 -175.492256)
			(xy 26.188389 -175.518384) (xy 26.225606 -175.559921) (xy 26.256379 -175.606434) (xy 26.280051 -175.656931)
			(xy 26.296119 -175.710338) (xy 26.304239 -175.765514) (xy 26.304748 -175.7934) (xy 26.304239 -175.821286)
			(xy 26.296119 -175.876462) (xy 26.280051 -175.929869) (xy 26.256379 -175.980366) (xy 26.225606 -176.026879)
			(xy 26.188389 -176.068416) (xy 26.145521 -176.104091) (xy 26.097915 -176.133145) (xy 26.046586 -176.154957)
			(xy 25.992629 -176.169063) (xy 25.937192 -176.175163) (xy 25.881458 -176.173126) (xy 25.826615 -176.162996)
			(xy 25.773831 -176.144989) (xy 25.724231 -176.119488) (xy 25.678873 -176.087037) (xy 25.638724 -176.048328)
			(xy 25.604638 -176.004185) (xy 25.577342 -175.95555) (xy 25.557419 -175.903459) (xy 25.545293 -175.849022)
			(xy 25.541222 -175.7934) (xy 24.141855 -175.7934) (xy 24.143713 -175.806025) (xy 24.144224 -175.83404)
			(xy 24.143713 -175.862055) (xy 24.135554 -175.917489) (xy 24.119412 -175.971145) (xy 24.095629 -176.021878)
			(xy 24.064713 -176.068608) (xy 24.027323 -176.110338) (xy 23.984255 -176.146179) (xy 23.936427 -176.175368)
			(xy 23.923164 -176.181004) (xy 51.225448 -176.181004) (xy 51.229519 -176.125382) (xy 51.241645 -176.070945)
			(xy 51.261568 -176.018854) (xy 51.288864 -175.970219) (xy 51.32295 -175.926076) (xy 51.363099 -175.887367)
			(xy 51.408457 -175.854916) (xy 51.458057 -175.829415) (xy 51.510841 -175.811408) (xy 51.565684 -175.801278)
			(xy 51.621418 -175.799241) (xy 51.676855 -175.805341) (xy 51.730812 -175.819447) (xy 51.782141 -175.841259)
			(xy 51.829747 -175.870313) (xy 51.872615 -175.905988) (xy 51.909832 -175.947525) (xy 51.940605 -175.994038)
			(xy 51.964277 -176.044535) (xy 51.980345 -176.097942) (xy 51.988465 -176.153118) (xy 51.988974 -176.181004)
			(xy 51.988928 -176.183544) (xy 52.231542 -176.183544) (xy 52.235613 -176.127922) (xy 52.247739 -176.073485)
			(xy 52.267662 -176.021394) (xy 52.294958 -175.972759) (xy 52.329044 -175.928616) (xy 52.369193 -175.889907)
			(xy 52.414551 -175.857456) (xy 52.464151 -175.831955) (xy 52.516935 -175.813948) (xy 52.571778 -175.803818)
			(xy 52.627512 -175.801781) (xy 52.682949 -175.807881) (xy 52.736906 -175.821987) (xy 52.788235 -175.843799)
			(xy 52.835841 -175.872853) (xy 52.878709 -175.908528) (xy 52.915926 -175.950065) (xy 52.946699 -175.996578)
			(xy 52.970371 -176.047075) (xy 52.986439 -176.100482) (xy 52.994559 -176.155658) (xy 52.995068 -176.183544)
			(xy 52.994559 -176.21143) (xy 52.986439 -176.266606) (xy 52.970371 -176.320013) (xy 52.946699 -176.37051)
			(xy 52.915926 -176.417023) (xy 52.878709 -176.45856) (xy 52.835841 -176.494235) (xy 52.788235 -176.523289)
			(xy 52.736906 -176.545101) (xy 52.682949 -176.559207) (xy 52.627512 -176.565307) (xy 52.571778 -176.56327)
			(xy 52.516935 -176.55314) (xy 52.464151 -176.535133) (xy 52.414551 -176.509632) (xy 52.369193 -176.477181)
			(xy 52.329044 -176.438472) (xy 52.294958 -176.394329) (xy 52.267662 -176.345694) (xy 52.247739 -176.293603)
			(xy 52.235613 -176.239166) (xy 52.231542 -176.183544) (xy 51.988928 -176.183544) (xy 51.988465 -176.20889)
			(xy 51.980345 -176.264066) (xy 51.964277 -176.317473) (xy 51.940605 -176.36797) (xy 51.909832 -176.414483)
			(xy 51.872615 -176.45602) (xy 51.829747 -176.491695) (xy 51.782141 -176.520749) (xy 51.730812 -176.542561)
			(xy 51.676855 -176.556667) (xy 51.621418 -176.562767) (xy 51.565684 -176.56073) (xy 51.510841 -176.5506)
			(xy 51.458057 -176.532593) (xy 51.408457 -176.507092) (xy 51.363099 -176.474641) (xy 51.32295 -176.435932)
			(xy 51.288864 -176.391789) (xy 51.261568 -176.343154) (xy 51.241645 -176.291063) (xy 51.229519 -176.236626)
			(xy 51.225448 -176.181004) (xy 23.923164 -176.181004) (xy 23.884859 -176.197282) (xy 23.83065 -176.211454)
			(xy 23.774955 -176.217582) (xy 23.718961 -176.215536) (xy 23.663863 -176.205359) (xy 23.610833 -176.187267)
			(xy 23.561002 -176.161648) (xy 23.515432 -176.129046) (xy 23.475096 -176.090156) (xy 23.440851 -176.045808)
			(xy 23.413428 -175.996946) (xy 23.393412 -175.944612) (xy 23.381229 -175.889922) (xy 23.37714 -175.83404)
			(xy 17.69618 -175.83404) (xy 16.338804 -177.191416) (xy 20.962872 -177.191416) (xy 20.966943 -177.135794)
			(xy 20.979069 -177.081357) (xy 20.998992 -177.029266) (xy 21.026288 -176.980631) (xy 21.060374 -176.936488)
			(xy 21.100523 -176.897779) (xy 21.145881 -176.865328) (xy 21.195481 -176.839827) (xy 21.248265 -176.82182)
			(xy 21.303108 -176.81169) (xy 21.358842 -176.809653) (xy 21.414279 -176.815753) (xy 21.468236 -176.829859)
			(xy 21.519565 -176.851671) (xy 21.567171 -176.880725) (xy 21.610039 -176.9164) (xy 21.647256 -176.957937)
			(xy 21.678029 -177.00445) (xy 21.701701 -177.054947) (xy 21.716624 -177.104548) (xy 25.632662 -177.104548)
			(xy 25.636733 -177.048926) (xy 25.648859 -176.994489) (xy 25.668782 -176.942398) (xy 25.696078 -176.893763)
			(xy 25.730164 -176.84962) (xy 25.770313 -176.810911) (xy 25.815671 -176.77846) (xy 25.865271 -176.752959)
			(xy 25.918055 -176.734952) (xy 25.972898 -176.724822) (xy 26.028632 -176.722785) (xy 26.084069 -176.728885)
			(xy 26.138026 -176.742991) (xy 26.189355 -176.764803) (xy 26.236961 -176.793857) (xy 26.279829 -176.829532)
			(xy 26.317046 -176.871069) (xy 26.347819 -176.917582) (xy 26.353804 -176.930349) (xy 49.335704 -176.930349)
			(xy 49.335704 -176.875851) (xy 49.34346 -176.821908) (xy 49.358813 -176.769618) (xy 49.381452 -176.720045)
			(xy 49.410916 -176.674198) (xy 49.446604 -176.633011) (xy 49.48779 -176.597322) (xy 49.533636 -176.567857)
			(xy 49.583208 -176.545217) (xy 49.635498 -176.529862) (xy 49.689441 -176.522105) (xy 49.71669 -176.521618)
			(xy 49.74406 -176.522086) (xy 49.798239 -176.529902) (xy 49.850743 -176.545391) (xy 49.90049 -176.568232)
			(xy 49.946456 -176.597957) (xy 49.967388 -176.615598) (xy 49.978716 -176.624834) (xy 50.005273 -176.63701)
			(xy 50.03419 -176.641183) (xy 50.063107 -176.63701) (xy 50.089664 -176.624834) (xy 50.100992 -176.615598)
			(xy 50.121925 -176.597957) (xy 50.167893 -176.568233) (xy 50.217639 -176.545387) (xy 50.270141 -176.529891)
			(xy 50.324319 -176.522062) (xy 50.379061 -176.522062) (xy 50.433239 -176.529891) (xy 50.485741 -176.545387)
			(xy 50.535487 -176.568233) (xy 50.581455 -176.597957) (xy 50.602388 -176.615598) (xy 50.613716 -176.624834)
			(xy 50.640273 -176.63701) (xy 50.66919 -176.641183) (xy 50.698107 -176.63701) (xy 50.724664 -176.624834)
			(xy 50.735992 -176.615598) (xy 50.756916 -176.597949) (xy 50.802891 -176.568239) (xy 50.852641 -176.545405)
			(xy 50.905143 -176.529916) (xy 50.95932 -176.52209) (xy 50.98669 -176.521618) (xy 51.013944 -176.522065)
			(xy 51.067897 -176.529821) (xy 51.120196 -176.545177) (xy 51.169778 -176.56782) (xy 51.215633 -176.59729)
			(xy 51.256826 -176.632985) (xy 51.29252 -176.67418) (xy 51.321987 -176.720036) (xy 51.344629 -176.769619)
			(xy 51.359982 -176.821919) (xy 51.367736 -176.875872) (xy 51.368198 -176.903126) (xy 51.367748 -176.930497)
			(xy 51.359926 -176.984677) (xy 51.344433 -177.03718) (xy 51.321588 -177.086926) (xy 51.291861 -177.132893)
			(xy 51.274218 -177.153824) (xy 51.264955 -177.165132) (xy 51.252778 -177.191696) (xy 51.24861 -177.22062)
			(xy 51.252789 -177.249541) (xy 51.264976 -177.276101) (xy 51.274218 -177.287428) (xy 51.29184 -177.308374)
			(xy 51.321553 -177.354343) (xy 51.344392 -177.404087) (xy 51.359888 -177.456585) (xy 51.367721 -177.510758)
			(xy 51.368198 -177.538126) (xy 51.367746 -177.565378) (xy 51.359986 -177.619328) (xy 51.344627 -177.671624)
			(xy 51.321982 -177.721202) (xy 51.292512 -177.767053) (xy 51.256817 -177.808243) (xy 51.215624 -177.843934)
			(xy 51.16977 -177.873399) (xy 51.12019 -177.89604) (xy 51.067893 -177.911394) (xy 51.013942 -177.919149)
			(xy 50.98669 -177.919634) (xy 50.959319 -177.91919) (xy 50.905138 -177.911369) (xy 50.852634 -177.895876)
			(xy 50.802888 -177.873029) (xy 50.756922 -177.843298) (xy 50.735992 -177.825654) (xy 50.724664 -177.816418)
			(xy 50.698107 -177.804242) (xy 50.66919 -177.800069) (xy 50.640273 -177.804242) (xy 50.613716 -177.816418)
			(xy 50.602388 -177.825654) (xy 50.581428 -177.843258) (xy 50.535463 -177.872977) (xy 50.485723 -177.89582)
			(xy 50.433228 -177.911319) (xy 50.379057 -177.919156) (xy 50.35169 -177.919634) (xy 50.32444 -177.919132)
			(xy 50.270494 -177.911374) (xy 50.218201 -177.896019) (xy 50.168626 -177.873379) (xy 50.122776 -177.843914)
			(xy 50.081587 -177.808224) (xy 50.045896 -177.767036) (xy 50.016429 -177.721189) (xy 49.993786 -177.671614)
			(xy 49.978429 -177.619322) (xy 49.97067 -177.565376) (xy 49.970182 -177.538126) (xy 49.970663 -177.511891)
			(xy 49.977854 -177.459916) (xy 49.992105 -177.409419) (xy 50.013145 -177.361352) (xy 50.040578 -177.316625)
			(xy 50.073885 -177.276082) (xy 50.092864 -177.257964) (xy 50.100207 -177.250412) (xy 50.108638 -177.231137)
			(xy 50.108646 -177.210098) (xy 50.100228 -177.190817) (xy 50.092864 -177.183288) (xy 50.071528 -177.161952)
			(xy 50.063999 -177.15458) (xy 50.044714 -177.146149) (xy 50.023666 -177.146149) (xy 50.004381 -177.15458)
			(xy 49.996852 -177.161952) (xy 49.978741 -177.180941) (xy 49.938201 -177.214257) (xy 49.893474 -177.241698)
			(xy 49.845406 -177.262746) (xy 49.794905 -177.277002) (xy 49.742927 -177.284197) (xy 49.71669 -177.284634)
			(xy 49.689441 -177.284095) (xy 49.635498 -177.276338) (xy 49.583208 -177.260983) (xy 49.533636 -177.238343)
			(xy 49.48779 -177.208878) (xy 49.446604 -177.173189) (xy 49.410916 -177.132002) (xy 49.381452 -177.086155)
			(xy 49.358813 -177.036582) (xy 49.34346 -176.984292) (xy 49.335704 -176.930349) (xy 26.353804 -176.930349)
			(xy 26.371491 -176.968079) (xy 26.387559 -177.021486) (xy 26.395679 -177.076662) (xy 26.396188 -177.104548)
			(xy 26.395679 -177.132434) (xy 26.387559 -177.18761) (xy 26.371491 -177.241017) (xy 26.347819 -177.291514)
			(xy 26.317046 -177.338027) (xy 26.279829 -177.379564) (xy 26.236961 -177.415239) (xy 26.189355 -177.444293)
			(xy 26.138026 -177.466105) (xy 26.084069 -177.480211) (xy 26.028632 -177.486311) (xy 25.972898 -177.484274)
			(xy 25.918055 -177.474144) (xy 25.865271 -177.456137) (xy 25.815671 -177.430636) (xy 25.770313 -177.398185)
			(xy 25.730164 -177.359476) (xy 25.696078 -177.315333) (xy 25.668782 -177.266698) (xy 25.648859 -177.214607)
			(xy 25.636733 -177.16017) (xy 25.632662 -177.104548) (xy 21.716624 -177.104548) (xy 21.717769 -177.108354)
			(xy 21.725889 -177.16353) (xy 21.726398 -177.191416) (xy 21.725889 -177.219302) (xy 21.717769 -177.274478)
			(xy 21.701701 -177.327885) (xy 21.678029 -177.378382) (xy 21.647256 -177.424895) (xy 21.610039 -177.466432)
			(xy 21.567171 -177.502107) (xy 21.519565 -177.531161) (xy 21.468236 -177.552973) (xy 21.414279 -177.567079)
			(xy 21.358842 -177.573179) (xy 21.303108 -177.571142) (xy 21.248265 -177.561012) (xy 21.195481 -177.543005)
			(xy 21.145881 -177.517504) (xy 21.100523 -177.485053) (xy 21.060374 -177.446344) (xy 21.026288 -177.402201)
			(xy 20.998992 -177.353566) (xy 20.979069 -177.301475) (xy 20.966943 -177.247038) (xy 20.962872 -177.191416)
			(xy 16.338804 -177.191416) (xy 15.784576 -177.745644) (xy 24.330912 -177.745644) (xy 24.334983 -177.690022)
			(xy 24.347109 -177.635585) (xy 24.367032 -177.583494) (xy 24.394328 -177.534859) (xy 24.428414 -177.490716)
			(xy 24.468563 -177.452007) (xy 24.513921 -177.419556) (xy 24.563521 -177.394055) (xy 24.616305 -177.376048)
			(xy 24.671148 -177.365918) (xy 24.726882 -177.363881) (xy 24.782319 -177.369981) (xy 24.836276 -177.384087)
			(xy 24.887605 -177.405899) (xy 24.935211 -177.434953) (xy 24.978079 -177.470628) (xy 25.015296 -177.512165)
			(xy 25.023956 -177.525254) (xy 35.243449 -177.525254) (xy 35.243449 -177.470746) (xy 35.251207 -177.416793)
			(xy 35.266564 -177.364493) (xy 35.289208 -177.314911) (xy 35.318678 -177.269056) (xy 35.354374 -177.227863)
			(xy 35.395569 -177.192168) (xy 35.441425 -177.1627) (xy 35.491008 -177.140058) (xy 35.543308 -177.124704)
			(xy 35.597262 -177.116948) (xy 35.624516 -177.116486) (xy 35.651886 -177.116946) (xy 35.706066 -177.124766)
			(xy 35.758569 -177.140257) (xy 35.808315 -177.163099) (xy 35.854282 -177.192825) (xy 35.875214 -177.210466)
			(xy 35.886542 -177.219702) (xy 35.913099 -177.231878) (xy 35.942016 -177.236051) (xy 35.970933 -177.231878)
			(xy 35.99749 -177.219702) (xy 36.008818 -177.210466) (xy 36.029766 -177.192847) (xy 36.075735 -177.163133)
			(xy 36.125478 -177.140294) (xy 36.177975 -177.124798) (xy 36.232148 -177.116964) (xy 36.259516 -177.116486)
			(xy 36.286766 -177.116985) (xy 36.340711 -177.124743) (xy 36.393003 -177.140099) (xy 36.442578 -177.162741)
			(xy 36.488425 -177.192207) (xy 36.529613 -177.227898) (xy 36.565302 -177.269087) (xy 36.594767 -177.314936)
			(xy 36.617406 -177.364512) (xy 36.63276 -177.416804) (xy 36.640516 -177.47075) (xy 36.640516 -177.52525)
			(xy 36.63276 -177.579196) (xy 36.617406 -177.631488) (xy 36.594767 -177.681064) (xy 36.565302 -177.726913)
			(xy 36.529613 -177.768102) (xy 36.488425 -177.803793) (xy 36.442578 -177.833259) (xy 36.393003 -177.855901)
			(xy 36.340711 -177.871257) (xy 36.286766 -177.879015) (xy 36.259516 -177.879502) (xy 36.232146 -177.879026)
			(xy 36.177967 -177.871211) (xy 36.125464 -177.855724) (xy 36.075717 -177.832884) (xy 36.02975 -177.803162)
			(xy 36.008818 -177.785522) (xy 35.99749 -177.776286) (xy 35.970933 -177.76411) (xy 35.942016 -177.759937)
			(xy 35.913099 -177.76411) (xy 35.886542 -177.776286) (xy 35.875214 -177.785522) (xy 35.85429 -177.803171)
			(xy 35.808315 -177.832881) (xy 35.758565 -177.855715) (xy 35.706063 -177.871203) (xy 35.651886 -177.879029)
			(xy 35.624516 -177.879502) (xy 35.597262 -177.879052) (xy 35.543308 -177.871296) (xy 35.491008 -177.855942)
			(xy 35.441425 -177.8333) (xy 35.395569 -177.803832) (xy 35.354374 -177.768137) (xy 35.318678 -177.726944)
			(xy 35.289208 -177.681089) (xy 35.266564 -177.631507) (xy 35.251207 -177.579207) (xy 35.243449 -177.525254)
			(xy 25.023956 -177.525254) (xy 25.046069 -177.558678) (xy 25.069741 -177.609175) (xy 25.085809 -177.662582)
			(xy 25.093929 -177.717758) (xy 25.094438 -177.745644) (xy 25.093929 -177.77353) (xy 25.085809 -177.828706)
			(xy 25.069741 -177.882113) (xy 25.046069 -177.93261) (xy 25.015296 -177.979123) (xy 24.978079 -178.02066)
			(xy 24.935211 -178.056335) (xy 24.887605 -178.085389) (xy 24.836276 -178.107201) (xy 24.782319 -178.121307)
			(xy 24.726882 -178.127407) (xy 24.671148 -178.12537) (xy 24.616305 -178.11524) (xy 24.563521 -178.097233)
			(xy 24.513921 -178.071732) (xy 24.468563 -178.039281) (xy 24.428414 -178.000572) (xy 24.394328 -177.956429)
			(xy 24.367032 -177.907794) (xy 24.347109 -177.855703) (xy 24.334983 -177.801266) (xy 24.330912 -177.745644)
			(xy 15.784576 -177.745644) (xy 15.695676 -177.834544) (xy 15.695676 -178.265328) (xy 19.450302 -178.265328)
			(xy 19.454373 -178.209706) (xy 19.466499 -178.155269) (xy 19.486422 -178.103178) (xy 19.513718 -178.054543)
			(xy 19.547804 -178.0104) (xy 19.587953 -177.971691) (xy 19.633311 -177.93924) (xy 19.682911 -177.913739)
			(xy 19.735695 -177.895732) (xy 19.790538 -177.885602) (xy 19.846272 -177.883565) (xy 19.901709 -177.889665)
			(xy 19.955666 -177.903771) (xy 20.006995 -177.925583) (xy 20.054601 -177.954637) (xy 20.097469 -177.990312)
			(xy 20.134686 -178.031849) (xy 20.165459 -178.078362) (xy 20.189131 -178.128859) (xy 20.205199 -178.182266)
			(xy 20.213319 -178.237442) (xy 20.213828 -178.265328) (xy 20.213319 -178.293214) (xy 20.205199 -178.34839)
			(xy 20.189131 -178.401797) (xy 20.165459 -178.452294) (xy 20.134686 -178.498807) (xy 20.097469 -178.540344)
			(xy 20.054601 -178.576019) (xy 20.006995 -178.605073) (xy 19.955666 -178.626885) (xy 19.901709 -178.640991)
			(xy 19.846272 -178.647091) (xy 19.790538 -178.645054) (xy 19.735695 -178.634924) (xy 19.682911 -178.616917)
			(xy 19.633311 -178.591416) (xy 19.587953 -178.558965) (xy 19.547804 -178.520256) (xy 19.513718 -178.476113)
			(xy 19.486422 -178.427478) (xy 19.466499 -178.375387) (xy 19.454373 -178.32095) (xy 19.450302 -178.265328)
			(xy 15.695676 -178.265328) (xy 15.695676 -179.105814) (xy 20.700998 -179.105814) (xy 20.705069 -179.050192)
			(xy 20.717195 -178.995755) (xy 20.737118 -178.943664) (xy 20.764414 -178.895029) (xy 20.7985 -178.850886)
			(xy 20.838649 -178.812177) (xy 20.884007 -178.779726) (xy 20.933607 -178.754225) (xy 20.986391 -178.736218)
			(xy 21.041234 -178.726088) (xy 21.096968 -178.724051) (xy 21.152405 -178.730151) (xy 21.206362 -178.744257)
			(xy 21.257691 -178.766069) (xy 21.305297 -178.795123) (xy 21.348165 -178.830798) (xy 21.385382 -178.872335)
			(xy 21.416155 -178.918848) (xy 21.439827 -178.969345) (xy 21.455895 -179.022752) (xy 21.464015 -179.077928)
			(xy 21.464524 -179.105814) (xy 21.464015 -179.1337) (xy 21.455895 -179.188876) (xy 21.439827 -179.242283)
			(xy 21.416155 -179.29278) (xy 21.385382 -179.339293) (xy 21.348165 -179.38083) (xy 21.305297 -179.416505)
			(xy 21.257691 -179.445559) (xy 21.206362 -179.467371) (xy 21.152405 -179.481477) (xy 21.096968 -179.487577)
			(xy 21.041234 -179.48554) (xy 20.986391 -179.47541) (xy 20.933607 -179.457403) (xy 20.884007 -179.431902)
			(xy 20.838649 -179.399451) (xy 20.7985 -179.360742) (xy 20.764414 -179.316599) (xy 20.737118 -179.267964)
			(xy 20.717195 -179.215873) (xy 20.705069 -179.161436) (xy 20.700998 -179.105814) (xy 15.695676 -179.105814)
			(xy 15.695676 -179.563354) (xy 35.249545 -179.563354) (xy 35.249545 -179.508846) (xy 35.257302 -179.454892)
			(xy 35.272659 -179.402592) (xy 35.295303 -179.35301) (xy 35.324773 -179.307155) (xy 35.360469 -179.265961)
			(xy 35.401665 -179.230266) (xy 35.44752 -179.200798) (xy 35.497103 -179.178155) (xy 35.549404 -179.1628)
			(xy 35.603358 -179.155044) (xy 35.630612 -179.154582) (xy 35.657983 -179.155021) (xy 35.712164 -179.162842)
			(xy 35.764669 -179.178337) (xy 35.814415 -179.201185) (xy 35.86038 -179.230917) (xy 35.88131 -179.248562)
			(xy 35.892638 -179.257798) (xy 35.919195 -179.269974) (xy 35.948112 -179.274147) (xy 35.977029 -179.269974)
			(xy 36.003586 -179.257798) (xy 36.014914 -179.248562) (xy 36.035863 -179.230943) (xy 36.081831 -179.20123)
			(xy 36.131575 -179.17839) (xy 36.184072 -179.162894) (xy 36.238244 -179.155059) (xy 36.265612 -179.154582)
			(xy 36.292862 -179.155089) (xy 36.346807 -179.162847) (xy 36.399099 -179.178203) (xy 36.448673 -179.200844)
			(xy 36.494521 -179.23031) (xy 36.535708 -179.266) (xy 36.571398 -179.307189) (xy 36.600862 -179.353037)
			(xy 36.623502 -179.402612) (xy 36.638856 -179.454905) (xy 36.646612 -179.50885) (xy 36.646612 -179.56335)
			(xy 36.646611 -179.563354) (xy 40.532745 -179.563354) (xy 40.532745 -179.508846) (xy 40.540502 -179.454892)
			(xy 40.555859 -179.402592) (xy 40.578503 -179.35301) (xy 40.607973 -179.307155) (xy 40.643669 -179.265961)
			(xy 40.684865 -179.230266) (xy 40.73072 -179.200798) (xy 40.780303 -179.178155) (xy 40.832604 -179.1628)
			(xy 40.886558 -179.155044) (xy 40.913812 -179.154582) (xy 40.941183 -179.155021) (xy 40.995364 -179.162842)
			(xy 41.047869 -179.178337) (xy 41.097615 -179.201185) (xy 41.14358 -179.230917) (xy 41.16451 -179.248562)
			(xy 41.175838 -179.257798) (xy 41.202395 -179.269974) (xy 41.231312 -179.274147) (xy 41.260229 -179.269974)
			(xy 41.286786 -179.257798) (xy 41.298114 -179.248562) (xy 41.319063 -179.230943) (xy 41.365031 -179.20123)
			(xy 41.414775 -179.17839) (xy 41.467272 -179.162894) (xy 41.521444 -179.155059) (xy 41.548812 -179.154582)
			(xy 41.576062 -179.155089) (xy 41.630007 -179.162847) (xy 41.682299 -179.178203) (xy 41.731873 -179.200844)
			(xy 41.777721 -179.23031) (xy 41.818908 -179.266) (xy 41.854598 -179.307189) (xy 41.884062 -179.353037)
			(xy 41.906702 -179.402612) (xy 41.922056 -179.454905) (xy 41.929812 -179.50885) (xy 41.929812 -179.56335)
			(xy 41.922056 -179.617295) (xy 41.906702 -179.669588) (xy 41.884062 -179.719163) (xy 41.854598 -179.765011)
			(xy 41.818908 -179.8062) (xy 41.777721 -179.84189) (xy 41.731873 -179.871356) (xy 41.682299 -179.893997)
			(xy 41.630007 -179.909353) (xy 41.576062 -179.917111) (xy 41.548812 -179.917598) (xy 41.521442 -179.917125)
			(xy 41.467263 -179.909309) (xy 41.41476 -179.893822) (xy 41.365013 -179.870981) (xy 41.319046 -179.841258)
			(xy 41.298114 -179.823618) (xy 41.286786 -179.814382) (xy 41.260229 -179.802206) (xy 41.231312 -179.798033)
			(xy 41.202395 -179.802206) (xy 41.175838 -179.814382) (xy 41.16451 -179.823618) (xy 41.143587 -179.841269)
			(xy 41.097612 -179.870978) (xy 41.047862 -179.893812) (xy 40.995359 -179.9093) (xy 40.941182 -179.917125)
			(xy 40.913812 -179.917598) (xy 40.886558 -179.917156) (xy 40.832604 -179.9094) (xy 40.780303 -179.894045)
			(xy 40.73072 -179.871402) (xy 40.684865 -179.841934) (xy 40.643669 -179.806239) (xy 40.607973 -179.765045)
			(xy 40.578503 -179.71919) (xy 40.555859 -179.669608) (xy 40.540502 -179.617308) (xy 40.532745 -179.563354)
			(xy 36.646611 -179.563354) (xy 36.638856 -179.617295) (xy 36.623502 -179.669588) (xy 36.600862 -179.719163)
			(xy 36.571398 -179.765011) (xy 36.535708 -179.8062) (xy 36.494521 -179.84189) (xy 36.448673 -179.871356)
			(xy 36.399099 -179.893997) (xy 36.346807 -179.909353) (xy 36.292862 -179.917111) (xy 36.265612 -179.917598)
			(xy 36.238242 -179.917125) (xy 36.184063 -179.909309) (xy 36.13156 -179.893822) (xy 36.081813 -179.870981)
			(xy 36.035846 -179.841258) (xy 36.014914 -179.823618) (xy 36.003586 -179.814382) (xy 35.977029 -179.802206)
			(xy 35.948112 -179.798033) (xy 35.919195 -179.802206) (xy 35.892638 -179.814382) (xy 35.88131 -179.823618)
			(xy 35.860387 -179.841269) (xy 35.814412 -179.870978) (xy 35.764662 -179.893812) (xy 35.712159 -179.9093)
			(xy 35.657982 -179.917125) (xy 35.630612 -179.917598) (xy 35.603358 -179.917156) (xy 35.549404 -179.9094)
			(xy 35.497103 -179.894045) (xy 35.44752 -179.871402) (xy 35.401665 -179.841934) (xy 35.360469 -179.806239)
			(xy 35.324773 -179.765045) (xy 35.295303 -179.71919) (xy 35.272659 -179.669608) (xy 35.257302 -179.617308)
			(xy 35.249545 -179.563354) (xy 15.695676 -179.563354) (xy 15.695676 -181.176422) (xy 56.742582 -181.176422)
			(xy 56.746653 -181.1208) (xy 56.758779 -181.066363) (xy 56.778702 -181.014272) (xy 56.805998 -180.965637)
			(xy 56.840084 -180.921494) (xy 56.880233 -180.882785) (xy 56.925591 -180.850334) (xy 56.975191 -180.824833)
			(xy 57.027975 -180.806826) (xy 57.082818 -180.796696) (xy 57.138552 -180.794659) (xy 57.193989 -180.800759)
			(xy 57.247946 -180.814865) (xy 57.299275 -180.836677) (xy 57.346881 -180.865731) (xy 57.389749 -180.901406)
			(xy 57.426966 -180.942943) (xy 57.457739 -180.989456) (xy 57.481411 -181.039953) (xy 57.497479 -181.09336)
			(xy 57.505599 -181.148536) (xy 57.506108 -181.176422) (xy 57.505599 -181.204308) (xy 57.497479 -181.259484)
			(xy 57.481411 -181.312891) (xy 57.457739 -181.363388) (xy 57.426966 -181.409901) (xy 57.389749 -181.451438)
			(xy 57.346881 -181.487113) (xy 57.299275 -181.516167) (xy 57.247946 -181.537979) (xy 57.193989 -181.552085)
			(xy 57.138552 -181.558185) (xy 57.082818 -181.556148) (xy 57.027975 -181.546018) (xy 56.975191 -181.528011)
			(xy 56.925591 -181.50251) (xy 56.880233 -181.470059) (xy 56.840084 -181.43135) (xy 56.805998 -181.387207)
			(xy 56.778702 -181.338572) (xy 56.758779 -181.286481) (xy 56.746653 -181.232044) (xy 56.742582 -181.176422)
			(xy 15.695676 -181.176422) (xy 15.695676 -181.954932) (xy 23.963628 -181.954932) (xy 23.967699 -181.89931)
			(xy 23.979825 -181.844873) (xy 23.999748 -181.792782) (xy 24.027044 -181.744147) (xy 24.06113 -181.700004)
			(xy 24.101279 -181.661295) (xy 24.146637 -181.628844) (xy 24.196237 -181.603343) (xy 24.249021 -181.585336)
			(xy 24.303864 -181.575206) (xy 24.359598 -181.573169) (xy 24.415035 -181.579269) (xy 24.468992 -181.593375)
			(xy 24.520321 -181.615187) (xy 24.567927 -181.644241) (xy 24.610795 -181.679916) (xy 24.648012 -181.721453)
			(xy 24.678785 -181.767966) (xy 24.702457 -181.818463) (xy 24.718525 -181.87187) (xy 24.726645 -181.927046)
			(xy 24.727154 -181.954932) (xy 24.726645 -181.982818) (xy 24.718525 -182.037994) (xy 24.702457 -182.091401)
			(xy 24.678785 -182.141898) (xy 24.648012 -182.188411) (xy 24.610795 -182.229948) (xy 24.567927 -182.265623)
			(xy 24.520321 -182.294677) (xy 24.468992 -182.316489) (xy 24.415035 -182.330595) (xy 24.359598 -182.336695)
			(xy 24.303864 -182.334658) (xy 24.249021 -182.324528) (xy 24.196237 -182.306521) (xy 24.146637 -182.28102)
			(xy 24.101279 -182.248569) (xy 24.06113 -182.20986) (xy 24.027044 -182.165717) (xy 23.999748 -182.117082)
			(xy 23.979825 -182.064991) (xy 23.967699 -182.010554) (xy 23.963628 -181.954932) (xy 15.695676 -181.954932)
			(xy 15.695676 -182.822088) (xy 57.385202 -182.822088) (xy 57.389273 -182.766466) (xy 57.401399 -182.712029)
			(xy 57.421322 -182.659938) (xy 57.448618 -182.611303) (xy 57.482704 -182.56716) (xy 57.522853 -182.528451)
			(xy 57.568211 -182.496) (xy 57.617811 -182.470499) (xy 57.670595 -182.452492) (xy 57.725438 -182.442362)
			(xy 57.781172 -182.440325) (xy 57.836609 -182.446425) (xy 57.890566 -182.460531) (xy 57.941895 -182.482343)
			(xy 57.989501 -182.511397) (xy 58.032369 -182.547072) (xy 58.069586 -182.588609) (xy 58.100359 -182.635122)
			(xy 58.124031 -182.685619) (xy 58.140099 -182.739026) (xy 58.148219 -182.794202) (xy 58.148728 -182.822088)
			(xy 58.148219 -182.849974) (xy 58.140099 -182.90515) (xy 58.124031 -182.958557) (xy 58.100359 -183.009054)
			(xy 58.069586 -183.055567) (xy 58.032369 -183.097104) (xy 57.989501 -183.132779) (xy 57.941895 -183.161833)
			(xy 57.890566 -183.183645) (xy 57.836609 -183.197751) (xy 57.781172 -183.203851) (xy 57.725438 -183.201814)
			(xy 57.670595 -183.191684) (xy 57.617811 -183.173677) (xy 57.568211 -183.148176) (xy 57.522853 -183.115725)
			(xy 57.482704 -183.077016) (xy 57.448618 -183.032873) (xy 57.421322 -182.984238) (xy 57.401399 -182.932147)
			(xy 57.389273 -182.87771) (xy 57.385202 -182.822088) (xy 15.695676 -182.822088) (xy 15.695676 -183.07685)
			(xy 16.51635 -183.897524)
		)
		(stroke
			(width 0)
			(type solid)
		)
		(fill yes)
		(layer "In2.Cu")
		(net "GND")
	)
	(gr_poly
		(pts
			(xy 368.608864 -235.932726) (xy 368.608864 -233.774234) (xy 368.608436 -233.760935) (xy 368.601568 -233.73524)
			(xy 368.588291 -233.712193) (xy 368.569507 -233.693363) (xy 368.546494 -233.680029) (xy 368.520816 -233.673097)
			(xy 368.507518 -233.672634) (xy 368.481593 -233.672067) (xy 368.430395 -233.663846) (xy 368.38111 -233.647729)
			(xy 368.334947 -233.624111) (xy 368.29304 -233.593573) (xy 368.256418 -233.556864) (xy 368.225979 -233.514885)
			(xy 368.202471 -233.468667) (xy 368.186471 -233.419344) (xy 368.178371 -233.368127) (xy 368.178371 -233.316273)
			(xy 368.186471 -233.265056) (xy 368.202471 -233.215733) (xy 368.225979 -233.169515) (xy 368.256418 -233.127536)
			(xy 368.29304 -233.090827) (xy 368.334947 -233.060289) (xy 368.38111 -233.036671) (xy 368.430395 -233.020554)
			(xy 368.481593 -233.012333) (xy 368.507518 -233.011726) (xy 368.520819 -233.011265) (xy 368.546504 -233.004335)
			(xy 368.569526 -232.991002) (xy 368.58832 -232.972173) (xy 368.601609 -232.949126) (xy 368.608491 -232.923428)
			(xy 368.608864 -232.910126) (xy 368.608864 -232.146602) (xy 368.608432 -232.133306) (xy 368.601559 -232.107617)
			(xy 368.58828 -232.084578) (xy 368.569497 -232.065755) (xy 368.546487 -232.052426) (xy 368.520813 -232.045497)
			(xy 368.507518 -232.045002) (xy 368.481587 -232.044434) (xy 368.430379 -232.036212) (xy 368.381084 -232.020092)
			(xy 368.334912 -231.996469) (xy 368.292996 -231.965925) (xy 368.256366 -231.929208) (xy 368.225921 -231.887221)
			(xy 368.202408 -231.840993) (xy 368.186405 -231.79166) (xy 368.178303 -231.740432) (xy 368.178303 -231.688568)
			(xy 368.186405 -231.637341) (xy 368.202408 -231.588008) (xy 368.225921 -231.54178) (xy 368.256366 -231.499792)
			(xy 368.292996 -231.463075) (xy 368.334912 -231.432531) (xy 368.381084 -231.408908) (xy 368.430379 -231.392788)
			(xy 368.481587 -231.384566) (xy 368.507518 -231.384094) (xy 368.520817 -231.383633) (xy 368.546499 -231.376702)
			(xy 368.569517 -231.363369) (xy 368.588306 -231.344538) (xy 368.601589 -231.321491) (xy 368.608463 -231.295794)
			(xy 368.608864 -231.282494) (xy 368.608864 -230.878126) (xy 368.654838 -230.832152) (xy 368.65814 -230.81869)
			(xy 368.664867 -230.794302) (xy 368.68471 -230.747767) (xy 368.711412 -230.704799) (xy 368.74435 -230.666402)
			(xy 368.782754 -230.633472) (xy 368.825727 -230.606779) (xy 368.872266 -230.586945) (xy 368.896646 -230.580184)
			(xy 368.910108 -230.576882) (xy 369.116864 -230.370126) (xy 369.146074 -230.370126) (xy 369.156087 -230.369643)
			(xy 369.174592 -230.361989) (xy 369.18876 -230.347836) (xy 369.196433 -230.329339) (xy 369.196874 -230.319326)
			(xy 369.186206 -230.288338) (xy 369.170097 -230.266541) (xy 369.144473 -230.218786) (xy 369.127002 -230.167483)
			(xy 369.118155 -230.114014) (xy 369.117626 -230.086916) (xy 369.117626 -230.086662) (xy 369.118135 -230.060695)
			(xy 369.12626 -230.0094) (xy 369.142308 -229.960007) (xy 369.165886 -229.913733) (xy 369.196412 -229.871717)
			(xy 369.233135 -229.834994) (xy 369.275151 -229.804468) (xy 369.321425 -229.78089) (xy 369.370818 -229.764842)
			(xy 369.422113 -229.756717) (xy 369.474047 -229.756717) (xy 369.525342 -229.764842) (xy 369.574735 -229.78089)
			(xy 369.621009 -229.804468) (xy 369.663025 -229.834994) (xy 369.699748 -229.871717) (xy 369.730274 -229.913733)
			(xy 369.753852 -229.960007) (xy 369.7699 -230.0094) (xy 369.778025 -230.060695) (xy 369.778534 -230.086662)
			(xy 369.778104 -230.110618) (xy 369.771179 -230.158026) (xy 369.757485 -230.203939) (xy 369.7478 -230.225854)
			(xy 369.74211 -230.239279) (xy 369.737842 -230.268113) (xy 369.741891 -230.296977) (xy 369.753926 -230.323524)
			(xy 369.772968 -230.345592) (xy 369.797467 -230.361383) (xy 369.825428 -230.369614) (xy 369.840002 -230.370126)
			(xy 370.935758 -230.370126) (xy 370.950342 -230.36966) (xy 370.978325 -230.361433) (xy 371.002844 -230.345636)
			(xy 371.021903 -230.323556) (xy 371.033948 -230.296992) (xy 371.037999 -230.268108) (xy 371.033726 -230.239255)
			(xy 371.02796 -230.225854) (xy 371.018254 -230.203947) (xy 371.004558 -230.158032) (xy 370.99764 -230.110619)
			(xy 370.997226 -230.086662) (xy 370.997735 -230.060695) (xy 371.00586 -230.0094) (xy 371.021908 -229.960007)
			(xy 371.045486 -229.913733) (xy 371.076012 -229.871717) (xy 371.112735 -229.834994) (xy 371.154751 -229.804468)
			(xy 371.201025 -229.78089) (xy 371.250418 -229.764842) (xy 371.301713 -229.756717) (xy 371.353647 -229.756717)
			(xy 371.404942 -229.764842) (xy 371.454335 -229.78089) (xy 371.500609 -229.804468) (xy 371.542625 -229.834994)
			(xy 371.579348 -229.871717) (xy 371.609874 -229.913733) (xy 371.633452 -229.960007) (xy 371.6495 -230.0094)
			(xy 371.657625 -230.060695) (xy 371.658134 -230.086662) (xy 371.657704 -230.110618) (xy 371.650779 -230.158026)
			(xy 371.637085 -230.203939) (xy 371.6274 -230.225854) (xy 371.62171 -230.239279) (xy 371.617442 -230.268113)
			(xy 371.621491 -230.296977) (xy 371.633526 -230.323524) (xy 371.652568 -230.345592) (xy 371.677067 -230.361383)
			(xy 371.705028 -230.369614) (xy 371.719602 -230.370126) (xy 371.875558 -230.370126) (xy 371.890142 -230.36966)
			(xy 371.918125 -230.361433) (xy 371.942644 -230.345636) (xy 371.961703 -230.323556) (xy 371.973748 -230.296992)
			(xy 371.977799 -230.268108) (xy 371.973526 -230.239255) (xy 371.96776 -230.225854) (xy 371.958054 -230.203947)
			(xy 371.944358 -230.158032) (xy 371.93744 -230.110619) (xy 371.937026 -230.086662) (xy 371.937535 -230.060695)
			(xy 371.94566 -230.0094) (xy 371.961708 -229.960007) (xy 371.985286 -229.913733) (xy 372.015812 -229.871717)
			(xy 372.052535 -229.834994) (xy 372.094551 -229.804468) (xy 372.140825 -229.78089) (xy 372.190218 -229.764842)
			(xy 372.241513 -229.756717) (xy 372.293447 -229.756717) (xy 372.344742 -229.764842) (xy 372.394135 -229.78089)
			(xy 372.440409 -229.804468) (xy 372.482425 -229.834994) (xy 372.519148 -229.871717) (xy 372.549674 -229.913733)
			(xy 372.573252 -229.960007) (xy 372.5893 -230.0094) (xy 372.597425 -230.060695) (xy 372.597934 -230.086662)
			(xy 372.597504 -230.110618) (xy 372.590579 -230.158026) (xy 372.576885 -230.203939) (xy 372.5672 -230.225854)
			(xy 372.56151 -230.239279) (xy 372.557242 -230.268113) (xy 372.561291 -230.296977) (xy 372.573326 -230.323524)
			(xy 372.592368 -230.345592) (xy 372.616867 -230.361383) (xy 372.644828 -230.369614) (xy 372.659402 -230.370126)
			(xy 372.815612 -230.370126) (xy 372.83019 -230.369653) (xy 372.858159 -230.361417) (xy 372.882664 -230.345618)
			(xy 372.901711 -230.323543) (xy 372.913749 -230.296988) (xy 372.917799 -230.268114) (xy 372.913531 -230.239272)
			(xy 372.907814 -230.225854) (xy 372.898107 -230.203947) (xy 372.884408 -230.158032) (xy 372.877489 -230.110619)
			(xy 372.87708 -230.086662) (xy 372.877589 -230.060695) (xy 372.885714 -230.0094) (xy 372.901762 -229.960007)
			(xy 372.92534 -229.913733) (xy 372.955866 -229.871717) (xy 372.992589 -229.834994) (xy 373.034605 -229.804468)
			(xy 373.080879 -229.78089) (xy 373.130272 -229.764842) (xy 373.181567 -229.756717) (xy 373.233501 -229.756717)
			(xy 373.284796 -229.764842) (xy 373.334189 -229.78089) (xy 373.380463 -229.804468) (xy 373.422479 -229.834994)
			(xy 373.459202 -229.871717) (xy 373.489728 -229.913733) (xy 373.513306 -229.960007) (xy 373.529354 -230.0094)
			(xy 373.537479 -230.060695) (xy 373.537988 -230.086662) (xy 373.537558 -230.110618) (xy 373.530635 -230.158027)
			(xy 373.516943 -230.20394) (xy 373.507254 -230.225854) (xy 373.501565 -230.239281) (xy 373.4973 -230.268118)
			(xy 373.501349 -230.296985) (xy 373.513383 -230.323536) (xy 373.532423 -230.345608) (xy 373.55692 -230.361408)
			(xy 373.584881 -230.36965) (xy 373.599456 -230.370126) (xy 373.755158 -230.370126) (xy 373.769742 -230.36966)
			(xy 373.797725 -230.361433) (xy 373.822244 -230.345636) (xy 373.841303 -230.323556) (xy 373.853348 -230.296992)
			(xy 373.857399 -230.268108) (xy 373.853126 -230.239255) (xy 373.84736 -230.225854) (xy 373.837654 -230.203947)
			(xy 373.823958 -230.158032) (xy 373.81704 -230.110619) (xy 373.816626 -230.086662) (xy 373.817135 -230.060695)
			(xy 373.82526 -230.0094) (xy 373.841308 -229.960007) (xy 373.864886 -229.913733) (xy 373.895412 -229.871717)
			(xy 373.932135 -229.834994) (xy 373.974151 -229.804468) (xy 374.020425 -229.78089) (xy 374.069818 -229.764842)
			(xy 374.121113 -229.756717) (xy 374.173047 -229.756717) (xy 374.224342 -229.764842) (xy 374.273735 -229.78089)
			(xy 374.320009 -229.804468) (xy 374.362025 -229.834994) (xy 374.398748 -229.871717) (xy 374.429274 -229.913733)
			(xy 374.452852 -229.960007) (xy 374.4689 -230.0094) (xy 374.477025 -230.060695) (xy 374.477534 -230.086662)
			(xy 374.477104 -230.110618) (xy 374.470179 -230.158026) (xy 374.456485 -230.203939) (xy 374.4468 -230.225854)
			(xy 374.44111 -230.239279) (xy 374.436842 -230.268113) (xy 374.440891 -230.296977) (xy 374.452926 -230.323524)
			(xy 374.471968 -230.345592) (xy 374.496467 -230.361383) (xy 374.524428 -230.369614) (xy 374.539002 -230.370126)
			(xy 374.628664 -230.370126) (xy 374.781572 -230.217218) (xy 374.772174 -230.1875) (xy 374.76482 -230.162942)
			(xy 374.756915 -230.112293) (xy 374.756426 -230.086662) (xy 374.756991 -230.059352) (xy 374.765975 -230.005477)
			(xy 374.783694 -229.953811) (xy 374.809664 -229.905761) (xy 374.84318 -229.862634) (xy 374.883329 -229.825602)
			(xy 374.929019 -229.795674) (xy 374.953784 -229.784148) (xy 374.984264 -229.770686) (xy 374.984264 -229.613714)
			(xy 374.983794 -229.599504) (xy 374.975964 -229.572186) (xy 374.960905 -229.548084) (xy 374.939787 -229.529067)
			(xy 374.914244 -229.51661) (xy 374.886256 -229.511676) (xy 374.857993 -229.514649) (xy 374.831645 -229.525298)
			(xy 374.82018 -229.533704) (xy 374.798258 -229.550033) (xy 374.750177 -229.576028) (xy 374.698476 -229.593763)
			(xy 374.644563 -229.602755) (xy 374.617234 -229.6033) (xy 374.591259 -229.60282) (xy 374.539949 -229.594698)
			(xy 374.490541 -229.578649) (xy 374.444252 -229.555067) (xy 374.402223 -229.524535) (xy 374.365487 -229.487803)
			(xy 374.33495 -229.445777) (xy 374.311364 -229.39949) (xy 374.29531 -229.350084) (xy 374.287183 -229.298775)
			(xy 374.287183 -229.246825) (xy 374.29531 -229.195516) (xy 374.311364 -229.14611) (xy 374.33495 -229.099823)
			(xy 374.365487 -229.057797) (xy 374.402223 -229.021065) (xy 374.444252 -228.990533) (xy 374.490541 -228.966951)
			(xy 374.539949 -228.950902) (xy 374.591259 -228.94278) (xy 374.617234 -228.942392) (xy 374.644561 -228.942957)
			(xy 374.698471 -228.951949) (xy 374.750169 -228.969683) (xy 374.798248 -228.995675) (xy 374.82018 -229.011988)
			(xy 374.831667 -229.020359) (xy 374.858012 -229.030995) (xy 374.886268 -229.033962) (xy 374.914247 -229.029029)
			(xy 374.939785 -229.016579) (xy 374.960905 -228.997575) (xy 374.975972 -228.973489) (xy 374.98382 -228.946183)
			(xy 374.984264 -228.931978) (xy 374.984264 -228.775006) (xy 374.953784 -228.761544) (xy 374.93064 -228.750845)
			(xy 374.887678 -228.723389) (xy 374.849442 -228.689661) (xy 374.816838 -228.650461) (xy 374.790641 -228.60672)
			(xy 374.771471 -228.559475) (xy 374.759783 -228.509847) (xy 374.755855 -228.459012) (xy 374.759779 -228.408177)
			(xy 374.771463 -228.358548) (xy 374.79063 -228.311301) (xy 374.816824 -228.267558) (xy 374.849425 -228.228357)
			(xy 374.887659 -228.194626) (xy 374.930618 -228.167166) (xy 374.953784 -228.156516) (xy 374.984264 -228.143054)
			(xy 374.984264 -227.985828) (xy 374.983796 -227.971617) (xy 374.975968 -227.944295) (xy 374.96091 -227.920189)
			(xy 374.93979 -227.90117) (xy 374.914245 -227.88871) (xy 374.886255 -227.883776) (xy 374.857989 -227.88675)
			(xy 374.831638 -227.897402) (xy 374.82018 -227.905818) (xy 374.798258 -227.922146) (xy 374.750177 -227.94814)
			(xy 374.698476 -227.965874) (xy 374.644563 -227.974866) (xy 374.617234 -227.975414) (xy 374.591266 -227.974934)
			(xy 374.539969 -227.966814) (xy 374.490574 -227.950769) (xy 374.444297 -227.927194) (xy 374.402278 -227.89667)
			(xy 374.365552 -227.859947) (xy 374.335024 -227.817932) (xy 374.311444 -227.771658) (xy 374.295394 -227.722264)
			(xy 374.287269 -227.670968) (xy 374.287269 -227.619032) (xy 374.295394 -227.567736) (xy 374.311444 -227.518342)
			(xy 374.335024 -227.472068) (xy 374.365552 -227.430053) (xy 374.402278 -227.39333) (xy 374.444297 -227.362806)
			(xy 374.490574 -227.339231) (xy 374.539969 -227.323186) (xy 374.591266 -227.315066) (xy 374.617234 -227.314506)
			(xy 374.644561 -227.315071) (xy 374.698471 -227.324064) (xy 374.750169 -227.341798) (xy 374.798246 -227.367791)
			(xy 374.82018 -227.384102) (xy 374.831668 -227.392472) (xy 374.858014 -227.403107) (xy 374.88627 -227.406073)
			(xy 374.914249 -227.40114) (xy 374.939788 -227.388691) (xy 374.960909 -227.369688) (xy 374.975978 -227.345602)
			(xy 374.983829 -227.318297) (xy 374.984264 -227.304092) (xy 374.984264 -227.146866) (xy 374.954038 -227.133658)
			(xy 374.93089 -227.122962) (xy 374.887919 -227.095509) (xy 374.849675 -227.061782) (xy 374.817064 -227.022582)
			(xy 374.79086 -226.978839) (xy 374.771685 -226.93159) (xy 374.759994 -226.881957) (xy 374.756064 -226.831118)
			(xy 374.759988 -226.780278) (xy 374.771674 -226.730643) (xy 374.790844 -226.683393) (xy 374.817043 -226.639647)
			(xy 374.84965 -226.600443) (xy 374.887891 -226.566713) (xy 374.930858 -226.539255) (xy 374.954038 -226.52863)
			(xy 374.984264 -226.515422) (xy 374.984264 -226.358196) (xy 374.983792 -226.343988) (xy 374.975958 -226.316674)
			(xy 374.9609 -226.292577) (xy 374.939782 -226.273564) (xy 374.914242 -226.261109) (xy 374.886258 -226.256176)
			(xy 374.857999 -226.259148) (xy 374.831653 -226.269793) (xy 374.82018 -226.278186) (xy 374.798259 -226.294516)
			(xy 374.750178 -226.320512) (xy 374.698477 -226.338248) (xy 374.644563 -226.347241) (xy 374.617234 -226.347782)
			(xy 374.591261 -226.347302) (xy 374.539953 -226.33918) (xy 374.490548 -226.323132) (xy 374.444262 -226.299552)
			(xy 374.402234 -226.269021) (xy 374.365501 -226.232292) (xy 374.334966 -226.190267) (xy 374.311381 -226.143984)
			(xy 374.295328 -226.09458) (xy 374.287201 -226.043273) (xy 374.287201 -225.991327) (xy 374.295328 -225.94002)
			(xy 374.311381 -225.890616) (xy 374.334966 -225.844333) (xy 374.365501 -225.802308) (xy 374.402234 -225.765579)
			(xy 374.444262 -225.735048) (xy 374.490548 -225.711468) (xy 374.539953 -225.69542) (xy 374.591261 -225.687298)
			(xy 374.617234 -225.686874) (xy 374.644561 -225.687439) (xy 374.698472 -225.696431) (xy 374.75017 -225.714164)
			(xy 374.79825 -225.740155) (xy 374.82018 -225.75647) (xy 374.831666 -225.764842) (xy 374.85801 -225.77548)
			(xy 374.886265 -225.778447) (xy 374.914244 -225.773515) (xy 374.939782 -225.761064) (xy 374.9609 -225.742059)
			(xy 374.975964 -225.717971) (xy 374.983808 -225.690665) (xy 374.984264 -225.67646) (xy 374.984264 -225.592894)
			(xy 374.615964 -225.224594) (xy 374.615964 -224.782126) (xy 374.579134 -224.718626) (xy 374.556274 -224.714308)
			(xy 374.531342 -224.70916) (xy 374.483336 -224.692222) (xy 374.438496 -224.668121) (xy 374.397885 -224.637426)
			(xy 374.362462 -224.600864) (xy 374.333068 -224.559301) (xy 374.310397 -224.513722) (xy 374.294987 -224.465203)
			(xy 374.287201 -224.414896) (xy 374.28678 -224.389442) (xy 374.287295 -224.363107) (xy 374.295655 -224.311106)
			(xy 374.312153 -224.261087) (xy 374.336372 -224.214317) (xy 374.367701 -224.171978) (xy 374.405345 -224.135141)
			(xy 374.448354 -224.104739) (xy 374.495638 -224.081539) (xy 374.546003 -224.06613) (xy 374.572022 -224.062036)
			(xy 374.615964 -224.05594) (xy 374.615964 -223.095058) (xy 374.572022 -223.088962) (xy 374.546003 -223.084855)
			(xy 374.495629 -223.069468) (xy 374.448332 -223.046286) (xy 374.405312 -223.015895) (xy 374.367658 -222.979065)
			(xy 374.336322 -222.936728) (xy 374.312098 -222.889957) (xy 374.295601 -222.839935) (xy 374.287247 -222.78793)
			(xy 374.287248 -222.735258) (xy 374.295604 -222.683253) (xy 374.312103 -222.633232) (xy 374.336328 -222.586461)
			(xy 374.367666 -222.544126) (xy 374.405322 -222.507297) (xy 374.448343 -222.476908) (xy 374.49564 -222.453727)
			(xy 374.546015 -222.438343) (xy 374.572022 -222.43415) (xy 374.615964 -222.428054) (xy 374.615964 -221.467426)
			(xy 374.572022 -221.46133) (xy 374.546002 -221.457222) (xy 374.495626 -221.441833) (xy 374.448329 -221.418647)
			(xy 374.40531 -221.388252) (xy 374.367657 -221.351416) (xy 374.336325 -221.309074) (xy 374.312108 -221.262297)
			(xy 374.295618 -221.21227) (xy 374.287273 -221.160261) (xy 374.28678 -221.133924) (xy 374.287391 -221.105943)
			(xy 374.296839 -221.050784) (xy 374.305576 -221.024196) (xy 374.313196 -221.002098) (xy 374.109488 -220.649038)
			(xy 374.086374 -220.64472) (xy 374.061428 -220.639586) (xy 374.013389 -220.62267) (xy 373.968515 -220.598584)
			(xy 373.927868 -220.567898) (xy 373.892411 -220.531338) (xy 373.862983 -220.489771) (xy 373.840282 -220.44418)
			(xy 373.824845 -220.395647) (xy 373.817037 -220.345319) (xy 373.816626 -220.319854) (xy 373.817135 -220.293887)
			(xy 373.82526 -220.242592) (xy 373.841308 -220.193199) (xy 373.864886 -220.146925) (xy 373.895412 -220.104909)
			(xy 373.932135 -220.068186) (xy 373.974151 -220.03766) (xy 374.020425 -220.014082) (xy 374.069818 -219.998034)
			(xy 374.121113 -219.989909) (xy 374.173047 -219.989909) (xy 374.224342 -219.998034) (xy 374.273735 -220.014082)
			(xy 374.320009 -220.03766) (xy 374.362025 -220.068186) (xy 374.398748 -220.104909) (xy 374.429274 -220.146925)
			(xy 374.452852 -220.193199) (xy 374.4689 -220.242592) (xy 374.477025 -220.293887) (xy 374.477534 -220.319854)
			(xy 374.477534 -220.320616) (xy 374.476923 -220.348332) (xy 374.467599 -220.402975) (xy 374.458992 -220.429328)
			(xy 374.451118 -220.451172) (xy 374.521222 -220.572584) (xy 374.526342 -220.580632) (xy 374.541258 -220.5925)
			(xy 374.559475 -220.598106) (xy 374.578483 -220.596678) (xy 374.595658 -220.588412) (xy 374.608633 -220.574449)
			(xy 374.615618 -220.556714) (xy 374.615964 -220.547184) (xy 374.615964 -219.83954) (xy 374.572022 -219.833444)
			(xy 374.545997 -219.829336) (xy 374.495609 -219.813948) (xy 374.448301 -219.790762) (xy 374.405269 -219.760365)
			(xy 374.367604 -219.723527) (xy 374.336259 -219.681181) (xy 374.312028 -219.634399) (xy 374.295525 -219.584365)
			(xy 374.287167 -219.532348) (xy 374.287166 -219.479663) (xy 374.295522 -219.427645) (xy 374.312024 -219.377611)
			(xy 374.336253 -219.330828) (xy 374.367597 -219.288481) (xy 374.405261 -219.251642) (xy 374.448292 -219.221244)
			(xy 374.4956 -219.198056) (xy 374.545987 -219.182666) (xy 374.572022 -219.178632) (xy 374.615964 -219.172536)
			(xy 374.615964 -218.211908) (xy 374.572022 -218.205812) (xy 374.546003 -218.201704) (xy 374.495628 -218.186315)
			(xy 374.448332 -218.163129) (xy 374.405315 -218.132733) (xy 374.367664 -218.095897) (xy 374.336334 -218.053554)
			(xy 374.312119 -218.006777) (xy 374.295631 -217.956751) (xy 374.287289 -217.904743) (xy 374.28678 -217.878406)
			(xy 374.287393 -217.850426) (xy 374.296843 -217.795268) (xy 374.305576 -217.768678) (xy 374.313196 -217.74658)
			(xy 374.109488 -217.39352) (xy 374.086374 -217.389202) (xy 374.061428 -217.384067) (xy 374.013391 -217.367152)
			(xy 373.968519 -217.343065) (xy 373.927873 -217.312378) (xy 373.892418 -217.275818) (xy 373.862992 -217.234251)
			(xy 373.840293 -217.188661) (xy 373.824858 -217.140127) (xy 373.817054 -217.0898) (xy 373.816626 -217.064336)
			(xy 373.817135 -217.038369) (xy 373.82526 -216.987074) (xy 373.841308 -216.937681) (xy 373.864886 -216.891407)
			(xy 373.895412 -216.849391) (xy 373.932135 -216.812668) (xy 373.974151 -216.782142) (xy 374.020425 -216.758564)
			(xy 374.069818 -216.742516) (xy 374.121113 -216.734391) (xy 374.173047 -216.734391) (xy 374.224342 -216.742516)
			(xy 374.273735 -216.758564) (xy 374.320009 -216.782142) (xy 374.362025 -216.812668) (xy 374.398748 -216.849391)
			(xy 374.429274 -216.891407) (xy 374.452852 -216.937681) (xy 374.4689 -216.987074) (xy 374.477025 -217.038369)
			(xy 374.477534 -217.064336) (xy 374.477534 -217.065098) (xy 374.476924 -217.092814) (xy 374.467603 -217.147459)
			(xy 374.458992 -217.17381) (xy 374.451118 -217.195654) (xy 374.521222 -217.317066) (xy 374.52634 -217.325116)
			(xy 374.541254 -217.336988) (xy 374.559473 -217.342597) (xy 374.578481 -217.341169) (xy 374.595658 -217.332901)
			(xy 374.608631 -217.318935) (xy 374.615612 -217.301197) (xy 374.615964 -217.291666) (xy 374.615964 -216.584022)
			(xy 374.572022 -216.577926) (xy 374.545998 -216.573818) (xy 374.495614 -216.55843) (xy 374.448308 -216.535245)
			(xy 374.405278 -216.50485) (xy 374.367616 -216.468013) (xy 374.336273 -216.425669) (xy 374.312043 -216.37889)
			(xy 374.295541 -216.328859) (xy 374.287184 -216.276844) (xy 374.287184 -216.224162) (xy 374.29554 -216.172147)
			(xy 374.312041 -216.122115) (xy 374.33627 -216.075335) (xy 374.367612 -216.032991) (xy 374.405274 -215.996154)
			(xy 374.448303 -215.965758) (xy 374.495608 -215.942572) (xy 374.545993 -215.927183) (xy 374.572022 -215.923114)
			(xy 374.615964 -215.917018) (xy 374.615964 -215.319102) (xy 374.227598 -214.930736) (xy 368.381788 -214.930736)
			(xy 368.153188 -215.15959) (xy 368.153188 -215.452198) (xy 368.15268 -215.478614) (xy 368.150528 -215.536959)
			(xy 368.138419 -215.653092) (xy 368.11746 -215.767959) (xy 368.10315 -215.824562) (xy 368.099867 -215.838874)
			(xy 368.100753 -215.868212) (xy 368.109964 -215.896081) (xy 368.126737 -215.920167) (xy 368.149681 -215.938474)
			(xy 368.163094 -215.94445) (xy 368.18709 -215.954744) (xy 368.231757 -215.981778) (xy 368.271616 -216.015502)
			(xy 368.305676 -216.055074) (xy 368.333088 -216.099511) (xy 368.35317 -216.147705) (xy 368.365422 -216.198459)
			(xy 368.369539 -216.250508) (xy 368.367483 -216.276487) (xy 368.648489 -216.276487) (xy 368.648489 -216.224553)
			(xy 368.656614 -216.173258) (xy 368.672662 -216.123865) (xy 368.69624 -216.077591) (xy 368.726766 -216.035575)
			(xy 368.763489 -215.998852) (xy 368.805505 -215.968326) (xy 368.851779 -215.944748) (xy 368.901172 -215.9287)
			(xy 368.952467 -215.920575) (xy 369.004401 -215.920575) (xy 369.055696 -215.9287) (xy 369.105089 -215.944748)
			(xy 369.151363 -215.968326) (xy 369.193379 -215.998852) (xy 369.230102 -216.035575) (xy 369.260628 -216.077591)
			(xy 369.284206 -216.123865) (xy 369.300254 -216.173258) (xy 369.308379 -216.224553) (xy 369.308888 -216.25052)
			(xy 369.308379 -216.276487) (xy 369.588289 -216.276487) (xy 369.588289 -216.224553) (xy 369.596414 -216.173258)
			(xy 369.612462 -216.123865) (xy 369.63604 -216.077591) (xy 369.666566 -216.035575) (xy 369.703289 -215.998852)
			(xy 369.745305 -215.968326) (xy 369.791579 -215.944748) (xy 369.840972 -215.9287) (xy 369.892267 -215.920575)
			(xy 369.944201 -215.920575) (xy 369.995496 -215.9287) (xy 370.044889 -215.944748) (xy 370.091163 -215.968326)
			(xy 370.133179 -215.998852) (xy 370.169902 -216.035575) (xy 370.200428 -216.077591) (xy 370.224006 -216.123865)
			(xy 370.240054 -216.173258) (xy 370.248179 -216.224553) (xy 370.248688 -216.25052) (xy 370.248179 -216.276487)
			(xy 370.528089 -216.276487) (xy 370.528089 -216.224553) (xy 370.536214 -216.173258) (xy 370.552262 -216.123865)
			(xy 370.57584 -216.077591) (xy 370.606366 -216.035575) (xy 370.643089 -215.998852) (xy 370.685105 -215.968326)
			(xy 370.731379 -215.944748) (xy 370.780772 -215.9287) (xy 370.832067 -215.920575) (xy 370.884001 -215.920575)
			(xy 370.935296 -215.9287) (xy 370.984689 -215.944748) (xy 371.030963 -215.968326) (xy 371.072979 -215.998852)
			(xy 371.109702 -216.035575) (xy 371.140228 -216.077591) (xy 371.163806 -216.123865) (xy 371.179854 -216.173258)
			(xy 371.187979 -216.224553) (xy 371.188488 -216.25052) (xy 371.187979 -216.276487) (xy 371.467889 -216.276487)
			(xy 371.467889 -216.224553) (xy 371.476014 -216.173258) (xy 371.492062 -216.123865) (xy 371.51564 -216.077591)
			(xy 371.546166 -216.035575) (xy 371.582889 -215.998852) (xy 371.624905 -215.968326) (xy 371.671179 -215.944748)
			(xy 371.720572 -215.9287) (xy 371.771867 -215.920575) (xy 371.823801 -215.920575) (xy 371.875096 -215.9287)
			(xy 371.924489 -215.944748) (xy 371.970763 -215.968326) (xy 372.012779 -215.998852) (xy 372.049502 -216.035575)
			(xy 372.080028 -216.077591) (xy 372.103606 -216.123865) (xy 372.119654 -216.173258) (xy 372.127779 -216.224553)
			(xy 372.128288 -216.25052) (xy 372.127779 -216.276487) (xy 372.407689 -216.276487) (xy 372.407689 -216.224553)
			(xy 372.415814 -216.173258) (xy 372.431862 -216.123865) (xy 372.45544 -216.077591) (xy 372.485966 -216.035575)
			(xy 372.522689 -215.998852) (xy 372.564705 -215.968326) (xy 372.610979 -215.944748) (xy 372.660372 -215.9287)
			(xy 372.711667 -215.920575) (xy 372.763601 -215.920575) (xy 372.814896 -215.9287) (xy 372.864289 -215.944748)
			(xy 372.910563 -215.968326) (xy 372.952579 -215.998852) (xy 372.989302 -216.035575) (xy 373.019828 -216.077591)
			(xy 373.043406 -216.123865) (xy 373.059454 -216.173258) (xy 373.067579 -216.224553) (xy 373.068088 -216.25052)
			(xy 373.067579 -216.276487) (xy 373.347489 -216.276487) (xy 373.347489 -216.224553) (xy 373.355614 -216.173258)
			(xy 373.371662 -216.123865) (xy 373.39524 -216.077591) (xy 373.425766 -216.035575) (xy 373.462489 -215.998852)
			(xy 373.504505 -215.968326) (xy 373.550779 -215.944748) (xy 373.600172 -215.9287) (xy 373.651467 -215.920575)
			(xy 373.703401 -215.920575) (xy 373.754696 -215.9287) (xy 373.804089 -215.944748) (xy 373.850363 -215.968326)
			(xy 373.892379 -215.998852) (xy 373.929102 -216.035575) (xy 373.959628 -216.077591) (xy 373.983206 -216.123865)
			(xy 373.999254 -216.173258) (xy 374.007379 -216.224553) (xy 374.007888 -216.25052) (xy 374.007379 -216.276487)
			(xy 373.999254 -216.327782) (xy 373.983206 -216.377175) (xy 373.959628 -216.423449) (xy 373.929102 -216.465465)
			(xy 373.892379 -216.502188) (xy 373.850363 -216.532714) (xy 373.804089 -216.556292) (xy 373.754696 -216.57234)
			(xy 373.703401 -216.580465) (xy 373.651467 -216.580465) (xy 373.600172 -216.57234) (xy 373.550779 -216.556292)
			(xy 373.504505 -216.532714) (xy 373.462489 -216.502188) (xy 373.425766 -216.465465) (xy 373.39524 -216.423449)
			(xy 373.371662 -216.377175) (xy 373.355614 -216.327782) (xy 373.347489 -216.276487) (xy 373.067579 -216.276487)
			(xy 373.059454 -216.327782) (xy 373.043406 -216.377175) (xy 373.019828 -216.423449) (xy 372.989302 -216.465465)
			(xy 372.952579 -216.502188) (xy 372.910563 -216.532714) (xy 372.864289 -216.556292) (xy 372.814896 -216.57234)
			(xy 372.763601 -216.580465) (xy 372.711667 -216.580465) (xy 372.660372 -216.57234) (xy 372.610979 -216.556292)
			(xy 372.564705 -216.532714) (xy 372.522689 -216.502188) (xy 372.485966 -216.465465) (xy 372.45544 -216.423449)
			(xy 372.431862 -216.377175) (xy 372.415814 -216.327782) (xy 372.407689 -216.276487) (xy 372.127779 -216.276487)
			(xy 372.119654 -216.327782) (xy 372.103606 -216.377175) (xy 372.080028 -216.423449) (xy 372.049502 -216.465465)
			(xy 372.012779 -216.502188) (xy 371.970763 -216.532714) (xy 371.924489 -216.556292) (xy 371.875096 -216.57234)
			(xy 371.823801 -216.580465) (xy 371.771867 -216.580465) (xy 371.720572 -216.57234) (xy 371.671179 -216.556292)
			(xy 371.624905 -216.532714) (xy 371.582889 -216.502188) (xy 371.546166 -216.465465) (xy 371.51564 -216.423449)
			(xy 371.492062 -216.377175) (xy 371.476014 -216.327782) (xy 371.467889 -216.276487) (xy 371.187979 -216.276487)
			(xy 371.179854 -216.327782) (xy 371.163806 -216.377175) (xy 371.140228 -216.423449) (xy 371.109702 -216.465465)
			(xy 371.072979 -216.502188) (xy 371.030963 -216.532714) (xy 370.984689 -216.556292) (xy 370.935296 -216.57234)
			(xy 370.884001 -216.580465) (xy 370.832067 -216.580465) (xy 370.780772 -216.57234) (xy 370.731379 -216.556292)
			(xy 370.685105 -216.532714) (xy 370.643089 -216.502188) (xy 370.606366 -216.465465) (xy 370.57584 -216.423449)
			(xy 370.552262 -216.377175) (xy 370.536214 -216.327782) (xy 370.528089 -216.276487) (xy 370.248179 -216.276487)
			(xy 370.240054 -216.327782) (xy 370.224006 -216.377175) (xy 370.200428 -216.423449) (xy 370.169902 -216.465465)
			(xy 370.133179 -216.502188) (xy 370.091163 -216.532714) (xy 370.044889 -216.556292) (xy 369.995496 -216.57234)
			(xy 369.944201 -216.580465) (xy 369.892267 -216.580465) (xy 369.840972 -216.57234) (xy 369.791579 -216.556292)
			(xy 369.745305 -216.532714) (xy 369.703289 -216.502188) (xy 369.666566 -216.465465) (xy 369.63604 -216.423449)
			(xy 369.612462 -216.377175) (xy 369.596414 -216.327782) (xy 369.588289 -216.276487) (xy 369.308379 -216.276487)
			(xy 369.300254 -216.327782) (xy 369.284206 -216.377175) (xy 369.260628 -216.423449) (xy 369.230102 -216.465465)
			(xy 369.193379 -216.502188) (xy 369.151363 -216.532714) (xy 369.105089 -216.556292) (xy 369.055696 -216.57234)
			(xy 369.004401 -216.580465) (xy 368.952467 -216.580465) (xy 368.901172 -216.57234) (xy 368.851779 -216.556292)
			(xy 368.805505 -216.532714) (xy 368.763489 -216.502188) (xy 368.726766 -216.465465) (xy 368.69624 -216.423449)
			(xy 368.672662 -216.377175) (xy 368.656614 -216.327782) (xy 368.648489 -216.276487) (xy 368.367483 -216.276487)
			(xy 368.36542 -216.302556) (xy 368.353165 -216.353309) (xy 368.333081 -216.401503) (xy 368.305667 -216.445938)
			(xy 368.271606 -216.485509) (xy 368.231745 -216.51923) (xy 368.187076 -216.546263) (xy 368.163094 -216.55659)
			(xy 368.149711 -216.562593) (xy 368.126843 -216.580945) (xy 368.110114 -216.605024) (xy 368.100896 -216.632858)
			(xy 368.099944 -216.662164) (xy 368.10315 -216.676478) (xy 368.11966 -216.74582) (xy 368.17173 -216.795096)
			(xy 368.182487 -216.805102) (xy 368.208345 -216.81902) (xy 368.237095 -216.825002) (xy 368.266359 -216.822552)
			(xy 368.293715 -216.811874) (xy 368.305588 -216.803224) (xy 368.32747 -216.786968) (xy 368.375444 -216.761091)
			(xy 368.427009 -216.743425) (xy 368.480773 -216.734449) (xy 368.508026 -216.733882) (xy 368.50828 -216.733882)
			(xy 368.534249 -216.734363) (xy 368.585549 -216.742486) (xy 368.634946 -216.758535) (xy 368.681223 -216.782114)
			(xy 368.723242 -216.812643) (xy 368.759968 -216.84937) (xy 368.790495 -216.89139) (xy 368.814071 -216.937669)
			(xy 368.830118 -216.987067) (xy 368.838238 -217.038367) (xy 368.838734 -217.064336) (xy 368.838734 -217.065098)
			(xy 368.838179 -217.090303) (xy 369.118389 -217.090303) (xy 369.118389 -217.038369) (xy 369.126514 -216.987074)
			(xy 369.142562 -216.937681) (xy 369.16614 -216.891407) (xy 369.196666 -216.849391) (xy 369.233389 -216.812668)
			(xy 369.275405 -216.782142) (xy 369.321679 -216.758564) (xy 369.371072 -216.742516) (xy 369.422367 -216.734391)
			(xy 369.474301 -216.734391) (xy 369.525596 -216.742516) (xy 369.574989 -216.758564) (xy 369.621263 -216.782142)
			(xy 369.663279 -216.812668) (xy 369.700002 -216.849391) (xy 369.730528 -216.891407) (xy 369.754106 -216.937681)
			(xy 369.770154 -216.987074) (xy 369.778279 -217.038369) (xy 369.778788 -217.064336) (xy 370.057426 -217.064336)
			(xy 370.057935 -217.038369) (xy 370.06606 -216.987074) (xy 370.082108 -216.937681) (xy 370.105686 -216.891407)
			(xy 370.136212 -216.849391) (xy 370.172935 -216.812668) (xy 370.214951 -216.782142) (xy 370.261225 -216.758564)
			(xy 370.310618 -216.742516) (xy 370.361913 -216.734391) (xy 370.413847 -216.734391) (xy 370.465142 -216.742516)
			(xy 370.514535 -216.758564) (xy 370.560809 -216.782142) (xy 370.602825 -216.812668) (xy 370.639548 -216.849391)
			(xy 370.670074 -216.891407) (xy 370.693652 -216.937681) (xy 370.7097 -216.987074) (xy 370.717825 -217.038369)
			(xy 370.718334 -217.064336) (xy 370.718334 -217.065098) (xy 370.717802 -217.090303) (xy 370.997989 -217.090303)
			(xy 370.997989 -217.038369) (xy 371.006114 -216.987074) (xy 371.022162 -216.937681) (xy 371.04574 -216.891407)
			(xy 371.076266 -216.849391) (xy 371.112989 -216.812668) (xy 371.155005 -216.782142) (xy 371.201279 -216.758564)
			(xy 371.250672 -216.742516) (xy 371.301967 -216.734391) (xy 371.353901 -216.734391) (xy 371.405196 -216.742516)
			(xy 371.454589 -216.758564) (xy 371.500863 -216.782142) (xy 371.542879 -216.812668) (xy 371.579602 -216.849391)
			(xy 371.610128 -216.891407) (xy 371.633706 -216.937681) (xy 371.649754 -216.987074) (xy 371.657879 -217.038369)
			(xy 371.658388 -217.064336) (xy 371.937026 -217.064336) (xy 371.937535 -217.038369) (xy 371.94566 -216.987074)
			(xy 371.961708 -216.937681) (xy 371.985286 -216.891407) (xy 372.015812 -216.849391) (xy 372.052535 -216.812668)
			(xy 372.094551 -216.782142) (xy 372.140825 -216.758564) (xy 372.190218 -216.742516) (xy 372.241513 -216.734391)
			(xy 372.293447 -216.734391) (xy 372.344742 -216.742516) (xy 372.394135 -216.758564) (xy 372.440409 -216.782142)
			(xy 372.482425 -216.812668) (xy 372.519148 -216.849391) (xy 372.549674 -216.891407) (xy 372.573252 -216.937681)
			(xy 372.5893 -216.987074) (xy 372.597425 -217.038369) (xy 372.597934 -217.064336) (xy 372.597934 -217.065098)
			(xy 372.597402 -217.090303) (xy 372.877589 -217.090303) (xy 372.877589 -217.038369) (xy 372.885714 -216.987074)
			(xy 372.901762 -216.937681) (xy 372.92534 -216.891407) (xy 372.955866 -216.849391) (xy 372.992589 -216.812668)
			(xy 373.034605 -216.782142) (xy 373.080879 -216.758564) (xy 373.130272 -216.742516) (xy 373.181567 -216.734391)
			(xy 373.233501 -216.734391) (xy 373.284796 -216.742516) (xy 373.334189 -216.758564) (xy 373.380463 -216.782142)
			(xy 373.422479 -216.812668) (xy 373.459202 -216.849391) (xy 373.489728 -216.891407) (xy 373.513306 -216.937681)
			(xy 373.529354 -216.987074) (xy 373.537479 -217.038369) (xy 373.537988 -217.064336) (xy 373.537479 -217.090303)
			(xy 373.529354 -217.141598) (xy 373.513306 -217.190991) (xy 373.489728 -217.237265) (xy 373.459202 -217.279281)
			(xy 373.422479 -217.316004) (xy 373.380463 -217.34653) (xy 373.334189 -217.370108) (xy 373.284796 -217.386156)
			(xy 373.233501 -217.394281) (xy 373.181567 -217.394281) (xy 373.130272 -217.386156) (xy 373.080879 -217.370108)
			(xy 373.034605 -217.34653) (xy 372.992589 -217.316004) (xy 372.955866 -217.279281) (xy 372.92534 -217.237265)
			(xy 372.901762 -217.190991) (xy 372.885714 -217.141598) (xy 372.877589 -217.090303) (xy 372.597402 -217.090303)
			(xy 372.597349 -217.092816) (xy 372.588023 -217.147463) (xy 372.579392 -217.17381) (xy 372.571518 -217.195654)
			(xy 372.775734 -217.549222) (xy 372.798594 -217.55354) (xy 372.823503 -217.558766) (xy 372.871485 -217.575722)
			(xy 372.916302 -217.599831) (xy 372.956895 -217.630524) (xy 372.992305 -217.667074) (xy 373.021696 -217.70862)
			(xy 373.044372 -217.754178) (xy 373.0598 -217.802674) (xy 373.067613 -217.852961) (xy 373.068088 -217.878406)
			(xy 373.067579 -217.904373) (xy 373.059454 -217.955668) (xy 373.043406 -218.005061) (xy 373.019828 -218.051335)
			(xy 372.989302 -218.093351) (xy 372.952579 -218.130074) (xy 372.910563 -218.1606) (xy 372.864289 -218.184178)
			(xy 372.814896 -218.200226) (xy 372.763601 -218.208351) (xy 372.711667 -218.208351) (xy 372.660372 -218.200226)
			(xy 372.610979 -218.184178) (xy 372.564705 -218.1606) (xy 372.522689 -218.130074) (xy 372.485966 -218.093351)
			(xy 372.45544 -218.051335) (xy 372.431862 -218.005061) (xy 372.415814 -217.955668) (xy 372.407689 -217.904373)
			(xy 372.40718 -217.878406) (xy 372.407735 -217.85042) (xy 372.417184 -217.795252) (xy 372.425976 -217.768678)
			(xy 372.433596 -217.74658) (xy 372.229888 -217.39352) (xy 372.206774 -217.389202) (xy 372.181829 -217.384082)
			(xy 372.133805 -217.367147) (xy 372.088946 -217.343047) (xy 372.048313 -217.312353) (xy 372.012868 -217.275792)
			(xy 371.983449 -217.234227) (xy 371.960751 -217.188643) (xy 371.945313 -217.140117) (xy 371.937498 -217.089797)
			(xy 371.937026 -217.064336) (xy 371.658388 -217.064336) (xy 371.657879 -217.090303) (xy 371.649754 -217.141598)
			(xy 371.633706 -217.190991) (xy 371.610128 -217.237265) (xy 371.579602 -217.279281) (xy 371.542879 -217.316004)
			(xy 371.500863 -217.34653) (xy 371.454589 -217.370108) (xy 371.405196 -217.386156) (xy 371.353901 -217.394281)
			(xy 371.301967 -217.394281) (xy 371.250672 -217.386156) (xy 371.201279 -217.370108) (xy 371.155005 -217.34653)
			(xy 371.112989 -217.316004) (xy 371.076266 -217.279281) (xy 371.04574 -217.237265) (xy 371.022162 -217.190991)
			(xy 371.006114 -217.141598) (xy 370.997989 -217.090303) (xy 370.717802 -217.090303) (xy 370.717749 -217.092816)
			(xy 370.708423 -217.147463) (xy 370.699792 -217.17381) (xy 370.691918 -217.195654) (xy 370.896134 -217.549222)
			(xy 370.918994 -217.55354) (xy 370.943903 -217.558766) (xy 370.991885 -217.575722) (xy 371.036702 -217.599831)
			(xy 371.077295 -217.630524) (xy 371.112705 -217.667074) (xy 371.142096 -217.70862) (xy 371.164772 -217.754178)
			(xy 371.1802 -217.802674) (xy 371.188013 -217.852961) (xy 371.188488 -217.878406) (xy 371.187979 -217.904373)
			(xy 371.179854 -217.955668) (xy 371.163806 -218.005061) (xy 371.140228 -218.051335) (xy 371.109702 -218.093351)
			(xy 371.072979 -218.130074) (xy 371.030963 -218.1606) (xy 370.984689 -218.184178) (xy 370.935296 -218.200226)
			(xy 370.884001 -218.208351) (xy 370.832067 -218.208351) (xy 370.780772 -218.200226) (xy 370.731379 -218.184178)
			(xy 370.685105 -218.1606) (xy 370.643089 -218.130074) (xy 370.606366 -218.093351) (xy 370.57584 -218.051335)
			(xy 370.552262 -218.005061) (xy 370.536214 -217.955668) (xy 370.528089 -217.904373) (xy 370.52758 -217.878406)
			(xy 370.528135 -217.85042) (xy 370.537584 -217.795252) (xy 370.546376 -217.768678) (xy 370.553996 -217.74658)
			(xy 370.350288 -217.39352) (xy 370.327174 -217.389202) (xy 370.302229 -217.384082) (xy 370.254205 -217.367147)
			(xy 370.209346 -217.343047) (xy 370.168713 -217.312353) (xy 370.133268 -217.275792) (xy 370.103849 -217.234227)
			(xy 370.081151 -217.188643) (xy 370.065713 -217.140117) (xy 370.057898 -217.089797) (xy 370.057426 -217.064336)
			(xy 369.778788 -217.064336) (xy 369.778279 -217.090303) (xy 369.770154 -217.141598) (xy 369.754106 -217.190991)
			(xy 369.730528 -217.237265) (xy 369.700002 -217.279281) (xy 369.663279 -217.316004) (xy 369.621263 -217.34653)
			(xy 369.574989 -217.370108) (xy 369.525596 -217.386156) (xy 369.474301 -217.394281) (xy 369.422367 -217.394281)
			(xy 369.371072 -217.386156) (xy 369.321679 -217.370108) (xy 369.275405 -217.34653) (xy 369.233389 -217.316004)
			(xy 369.196666 -217.279281) (xy 369.16614 -217.237265) (xy 369.142562 -217.190991) (xy 369.126514 -217.141598)
			(xy 369.118389 -217.090303) (xy 368.838179 -217.090303) (xy 368.838124 -217.092814) (xy 368.828803 -217.147459)
			(xy 368.820192 -217.17381) (xy 368.812318 -217.195654) (xy 369.016534 -217.549222) (xy 369.039394 -217.55354)
			(xy 369.06432 -217.558693) (xy 369.112315 -217.575639) (xy 369.157142 -217.599746) (xy 369.197741 -217.630444)
			(xy 369.23315 -217.667006) (xy 369.262532 -217.708567) (xy 369.285191 -217.754143) (xy 369.300591 -217.802656)
			(xy 369.308367 -217.852957) (xy 369.308888 -217.878406) (xy 369.308378 -217.904374) (xy 369.300253 -217.95567)
			(xy 369.284205 -218.005064) (xy 369.260627 -218.05134) (xy 369.230101 -218.093358) (xy 369.193379 -218.130083)
			(xy 369.151364 -218.160613) (xy 369.10509 -218.184194) (xy 369.055697 -218.200247) (xy 369.004402 -218.208376)
			(xy 368.978434 -218.20886) (xy 368.97818 -218.20886) (xy 368.954265 -218.208441) (xy 368.906936 -218.201547)
			(xy 368.861097 -218.187891) (xy 368.817711 -218.16776) (xy 368.777685 -218.141577) (xy 368.759486 -218.126056)
			(xy 368.747739 -218.116342) (xy 368.719979 -218.103777) (xy 368.689749 -218.099958) (xy 368.659737 -218.105223)
			(xy 368.632613 -218.119104) (xy 368.610787 -218.140366) (xy 368.596203 -218.16712) (xy 368.592608 -218.181936)
			(xy 368.581412 -218.234675) (xy 368.552525 -218.338559) (xy 368.516372 -218.440143) (xy 368.473134 -218.53892)
			(xy 368.423026 -218.634395) (xy 368.387252 -218.692222) (xy 369.117626 -218.692222) (xy 369.118059 -218.66677)
			(xy 369.125847 -218.616464) (xy 369.14126 -218.567949) (xy 369.163931 -218.522372) (xy 369.193324 -218.480811)
			(xy 369.228744 -218.44425) (xy 369.269352 -218.413554) (xy 369.314188 -218.38945) (xy 369.36219 -218.372507)
			(xy 369.38712 -218.367356) (xy 369.40998 -218.363038) (xy 369.613942 -218.00947) (xy 369.606322 -217.987626)
			(xy 369.5977 -217.961212) (xy 369.588375 -217.906439) (xy 369.58778 -217.87866) (xy 369.58778 -217.878406)
			(xy 369.588289 -217.852439) (xy 369.596414 -217.801144) (xy 369.612462 -217.751751) (xy 369.63604 -217.705477)
			(xy 369.666566 -217.663461) (xy 369.703289 -217.626738) (xy 369.745305 -217.596212) (xy 369.791579 -217.572634)
			(xy 369.840972 -217.556586) (xy 369.892267 -217.548461) (xy 369.944201 -217.548461) (xy 369.995496 -217.556586)
			(xy 370.044889 -217.572634) (xy 370.091163 -217.596212) (xy 370.133179 -217.626738) (xy 370.169902 -217.663461)
			(xy 370.200428 -217.705477) (xy 370.224006 -217.751751) (xy 370.240054 -217.801144) (xy 370.248179 -217.852439)
			(xy 370.248688 -217.878406) (xy 370.248184 -217.903878) (xy 370.240364 -217.954219) (xy 370.224912 -218.002763)
			(xy 370.202193 -218.04836) (xy 370.172745 -218.089931) (xy 370.137266 -218.12649) (xy 370.096597 -218.15717)
			(xy 370.051701 -218.181246) (xy 370.003642 -218.198147) (xy 369.978686 -218.203272) (xy 369.955572 -218.20759)
			(xy 369.752118 -218.560396) (xy 369.759738 -218.582494) (xy 369.768472 -218.609083) (xy 369.777922 -218.664242)
			(xy 369.778534 -218.692222) (xy 370.997226 -218.692222) (xy 370.997659 -218.66677) (xy 371.005447 -218.616464)
			(xy 371.02086 -218.567949) (xy 371.043531 -218.522372) (xy 371.072924 -218.480811) (xy 371.108344 -218.44425)
			(xy 371.148952 -218.413554) (xy 371.193788 -218.38945) (xy 371.24179 -218.372507) (xy 371.26672 -218.367356)
			(xy 371.28958 -218.363038) (xy 371.493542 -218.00947) (xy 371.485922 -217.987626) (xy 371.4773 -217.961212)
			(xy 371.467975 -217.906439) (xy 371.46738 -217.87866) (xy 371.46738 -217.878406) (xy 371.467889 -217.852439)
			(xy 371.476014 -217.801144) (xy 371.492062 -217.751751) (xy 371.51564 -217.705477) (xy 371.546166 -217.663461)
			(xy 371.582889 -217.626738) (xy 371.624905 -217.596212) (xy 371.671179 -217.572634) (xy 371.720572 -217.556586)
			(xy 371.771867 -217.548461) (xy 371.823801 -217.548461) (xy 371.875096 -217.556586) (xy 371.924489 -217.572634)
			(xy 371.970763 -217.596212) (xy 372.012779 -217.626738) (xy 372.049502 -217.663461) (xy 372.080028 -217.705477)
			(xy 372.103606 -217.751751) (xy 372.119654 -217.801144) (xy 372.127779 -217.852439) (xy 372.128288 -217.878406)
			(xy 372.127784 -217.903878) (xy 372.119964 -217.954219) (xy 372.104512 -218.002763) (xy 372.081793 -218.04836)
			(xy 372.052345 -218.089931) (xy 372.016866 -218.12649) (xy 371.976197 -218.15717) (xy 371.931301 -218.181246)
			(xy 371.883242 -218.198147) (xy 371.858286 -218.203272) (xy 371.835172 -218.20759) (xy 371.631718 -218.560396)
			(xy 371.639338 -218.582494) (xy 371.648072 -218.609083) (xy 371.657522 -218.664242) (xy 371.658134 -218.692222)
			(xy 372.876826 -218.692222) (xy 372.877259 -218.66677) (xy 372.885047 -218.616464) (xy 372.90046 -218.567949)
			(xy 372.923131 -218.522372) (xy 372.952524 -218.480811) (xy 372.987944 -218.44425) (xy 373.028552 -218.413554)
			(xy 373.073388 -218.38945) (xy 373.12139 -218.372507) (xy 373.14632 -218.367356) (xy 373.16918 -218.363038)
			(xy 373.373142 -218.00947) (xy 373.365522 -217.987626) (xy 373.3569 -217.961212) (xy 373.347575 -217.906439)
			(xy 373.34698 -217.87866) (xy 373.34698 -217.878406) (xy 373.347489 -217.852439) (xy 373.355614 -217.801144)
			(xy 373.371662 -217.751751) (xy 373.39524 -217.705477) (xy 373.425766 -217.663461) (xy 373.462489 -217.626738)
			(xy 373.504505 -217.596212) (xy 373.550779 -217.572634) (xy 373.600172 -217.556586) (xy 373.651467 -217.548461)
			(xy 373.703401 -217.548461) (xy 373.754696 -217.556586) (xy 373.804089 -217.572634) (xy 373.850363 -217.596212)
			(xy 373.892379 -217.626738) (xy 373.929102 -217.663461) (xy 373.959628 -217.705477) (xy 373.983206 -217.751751)
			(xy 373.999254 -217.801144) (xy 374.007379 -217.852439) (xy 374.007888 -217.878406) (xy 374.007384 -217.903878)
			(xy 373.999564 -217.954219) (xy 373.984112 -218.002763) (xy 373.961393 -218.04836) (xy 373.931945 -218.089931)
			(xy 373.896466 -218.12649) (xy 373.855797 -218.15717) (xy 373.810901 -218.181246) (xy 373.762842 -218.198147)
			(xy 373.737886 -218.203272) (xy 373.714772 -218.20759) (xy 373.511318 -218.560396) (xy 373.518938 -218.582494)
			(xy 373.527672 -218.609083) (xy 373.537122 -218.664242) (xy 373.537734 -218.692222) (xy 373.537225 -218.718189)
			(xy 373.5291 -218.769484) (xy 373.513052 -218.818877) (xy 373.489474 -218.865151) (xy 373.458948 -218.907167)
			(xy 373.422225 -218.94389) (xy 373.380209 -218.974416) (xy 373.333935 -218.997994) (xy 373.284542 -219.014042)
			(xy 373.233247 -219.022167) (xy 373.181313 -219.022167) (xy 373.130018 -219.014042) (xy 373.080625 -218.997994)
			(xy 373.034351 -218.974416) (xy 372.992335 -218.94389) (xy 372.955612 -218.907167) (xy 372.925086 -218.865151)
			(xy 372.901508 -218.818877) (xy 372.88546 -218.769484) (xy 372.877335 -218.718189) (xy 372.876826 -218.692222)
			(xy 371.658134 -218.692222) (xy 371.657625 -218.718189) (xy 371.6495 -218.769484) (xy 371.633452 -218.818877)
			(xy 371.609874 -218.865151) (xy 371.579348 -218.907167) (xy 371.542625 -218.94389) (xy 371.500609 -218.974416)
			(xy 371.454335 -218.997994) (xy 371.404942 -219.014042) (xy 371.353647 -219.022167) (xy 371.301713 -219.022167)
			(xy 371.250418 -219.014042) (xy 371.201025 -218.997994) (xy 371.154751 -218.974416) (xy 371.112735 -218.94389)
			(xy 371.076012 -218.907167) (xy 371.045486 -218.865151) (xy 371.021908 -218.818877) (xy 371.00586 -218.769484)
			(xy 370.997735 -218.718189) (xy 370.997226 -218.692222) (xy 369.778534 -218.692222) (xy 369.778025 -218.718189)
			(xy 369.7699 -218.769484) (xy 369.753852 -218.818877) (xy 369.730274 -218.865151) (xy 369.699748 -218.907167)
			(xy 369.663025 -218.94389) (xy 369.621009 -218.974416) (xy 369.574735 -218.997994) (xy 369.525342 -219.014042)
			(xy 369.474047 -219.022167) (xy 369.422113 -219.022167) (xy 369.370818 -219.014042) (xy 369.321425 -218.997994)
			(xy 369.275151 -218.974416) (xy 369.233135 -218.94389) (xy 369.196412 -218.907167) (xy 369.165886 -218.865151)
			(xy 369.142308 -218.818877) (xy 369.12626 -218.769484) (xy 369.118135 -218.718189) (xy 369.117626 -218.692222)
			(xy 368.387252 -218.692222) (xy 368.366298 -218.726092) (xy 368.303235 -218.813552) (xy 368.234151 -218.89634)
			(xy 368.159392 -218.97404) (xy 368.11966 -219.010484) (xy 368.10315 -219.08008) (xy 368.09987 -219.094391)
			(xy 368.10076 -219.123725) (xy 368.109974 -219.151589) (xy 368.126748 -219.175671) (xy 368.14969 -219.193973)
			(xy 368.163094 -219.199968) (xy 368.187088 -219.210262) (xy 368.231753 -219.237296) (xy 368.271609 -219.271018)
			(xy 368.305666 -219.310589) (xy 368.333076 -219.355024) (xy 368.353156 -219.403217) (xy 368.365406 -219.453968)
			(xy 368.369523 -219.506014) (xy 368.367465 -219.532005) (xy 368.648489 -219.532005) (xy 368.648489 -219.480071)
			(xy 368.656614 -219.428776) (xy 368.672662 -219.379383) (xy 368.69624 -219.333109) (xy 368.726766 -219.291093)
			(xy 368.763489 -219.25437) (xy 368.805505 -219.223844) (xy 368.851779 -219.200266) (xy 368.901172 -219.184218)
			(xy 368.952467 -219.176093) (xy 369.004401 -219.176093) (xy 369.055696 -219.184218) (xy 369.105089 -219.200266)
			(xy 369.151363 -219.223844) (xy 369.193379 -219.25437) (xy 369.230102 -219.291093) (xy 369.260628 -219.333109)
			(xy 369.284206 -219.379383) (xy 369.300254 -219.428776) (xy 369.308379 -219.480071) (xy 369.308888 -219.506038)
			(xy 369.308379 -219.532005) (xy 369.588289 -219.532005) (xy 369.588289 -219.480071) (xy 369.596414 -219.428776)
			(xy 369.612462 -219.379383) (xy 369.63604 -219.333109) (xy 369.666566 -219.291093) (xy 369.703289 -219.25437)
			(xy 369.745305 -219.223844) (xy 369.791579 -219.200266) (xy 369.840972 -219.184218) (xy 369.892267 -219.176093)
			(xy 369.944201 -219.176093) (xy 369.995496 -219.184218) (xy 370.044889 -219.200266) (xy 370.091163 -219.223844)
			(xy 370.133179 -219.25437) (xy 370.169902 -219.291093) (xy 370.200428 -219.333109) (xy 370.224006 -219.379383)
			(xy 370.240054 -219.428776) (xy 370.248179 -219.480071) (xy 370.248688 -219.506038) (xy 370.248179 -219.532005)
			(xy 370.528089 -219.532005) (xy 370.528089 -219.480071) (xy 370.536214 -219.428776) (xy 370.552262 -219.379383)
			(xy 370.57584 -219.333109) (xy 370.606366 -219.291093) (xy 370.643089 -219.25437) (xy 370.685105 -219.223844)
			(xy 370.731379 -219.200266) (xy 370.780772 -219.184218) (xy 370.832067 -219.176093) (xy 370.884001 -219.176093)
			(xy 370.935296 -219.184218) (xy 370.984689 -219.200266) (xy 371.030963 -219.223844) (xy 371.072979 -219.25437)
			(xy 371.109702 -219.291093) (xy 371.140228 -219.333109) (xy 371.163806 -219.379383) (xy 371.179854 -219.428776)
			(xy 371.187979 -219.480071) (xy 371.188488 -219.506038) (xy 371.187979 -219.532005) (xy 371.467889 -219.532005)
			(xy 371.467889 -219.480071) (xy 371.476014 -219.428776) (xy 371.492062 -219.379383) (xy 371.51564 -219.333109)
			(xy 371.546166 -219.291093) (xy 371.582889 -219.25437) (xy 371.624905 -219.223844) (xy 371.671179 -219.200266)
			(xy 371.720572 -219.184218) (xy 371.771867 -219.176093) (xy 371.823801 -219.176093) (xy 371.875096 -219.184218)
			(xy 371.924489 -219.200266) (xy 371.970763 -219.223844) (xy 372.012779 -219.25437) (xy 372.049502 -219.291093)
			(xy 372.080028 -219.333109) (xy 372.103606 -219.379383) (xy 372.119654 -219.428776) (xy 372.127779 -219.480071)
			(xy 372.128288 -219.506038) (xy 372.127779 -219.532005) (xy 372.407689 -219.532005) (xy 372.407689 -219.480071)
			(xy 372.415814 -219.428776) (xy 372.431862 -219.379383) (xy 372.45544 -219.333109) (xy 372.485966 -219.291093)
			(xy 372.522689 -219.25437) (xy 372.564705 -219.223844) (xy 372.610979 -219.200266) (xy 372.660372 -219.184218)
			(xy 372.711667 -219.176093) (xy 372.763601 -219.176093) (xy 372.814896 -219.184218) (xy 372.864289 -219.200266)
			(xy 372.910563 -219.223844) (xy 372.952579 -219.25437) (xy 372.989302 -219.291093) (xy 373.019828 -219.333109)
			(xy 373.043406 -219.379383) (xy 373.059454 -219.428776) (xy 373.067579 -219.480071) (xy 373.068088 -219.506038)
			(xy 373.067579 -219.532005) (xy 373.347489 -219.532005) (xy 373.347489 -219.480071) (xy 373.355614 -219.428776)
			(xy 373.371662 -219.379383) (xy 373.39524 -219.333109) (xy 373.425766 -219.291093) (xy 373.462489 -219.25437)
			(xy 373.504505 -219.223844) (xy 373.550779 -219.200266) (xy 373.600172 -219.184218) (xy 373.651467 -219.176093)
			(xy 373.703401 -219.176093) (xy 373.754696 -219.184218) (xy 373.804089 -219.200266) (xy 373.850363 -219.223844)
			(xy 373.892379 -219.25437) (xy 373.929102 -219.291093) (xy 373.959628 -219.333109) (xy 373.983206 -219.379383)
			(xy 373.999254 -219.428776) (xy 374.007379 -219.480071) (xy 374.007888 -219.506038) (xy 374.007379 -219.532005)
			(xy 373.999254 -219.5833) (xy 373.983206 -219.632693) (xy 373.959628 -219.678967) (xy 373.929102 -219.720983)
			(xy 373.892379 -219.757706) (xy 373.850363 -219.788232) (xy 373.804089 -219.81181) (xy 373.754696 -219.827858)
			(xy 373.703401 -219.835983) (xy 373.651467 -219.835983) (xy 373.600172 -219.827858) (xy 373.550779 -219.81181)
			(xy 373.504505 -219.788232) (xy 373.462489 -219.757706) (xy 373.425766 -219.720983) (xy 373.39524 -219.678967)
			(xy 373.371662 -219.632693) (xy 373.355614 -219.5833) (xy 373.347489 -219.532005) (xy 373.067579 -219.532005)
			(xy 373.059454 -219.5833) (xy 373.043406 -219.632693) (xy 373.019828 -219.678967) (xy 372.989302 -219.720983)
			(xy 372.952579 -219.757706) (xy 372.910563 -219.788232) (xy 372.864289 -219.81181) (xy 372.814896 -219.827858)
			(xy 372.763601 -219.835983) (xy 372.711667 -219.835983) (xy 372.660372 -219.827858) (xy 372.610979 -219.81181)
			(xy 372.564705 -219.788232) (xy 372.522689 -219.757706) (xy 372.485966 -219.720983) (xy 372.45544 -219.678967)
			(xy 372.431862 -219.632693) (xy 372.415814 -219.5833) (xy 372.407689 -219.532005) (xy 372.127779 -219.532005)
			(xy 372.119654 -219.5833) (xy 372.103606 -219.632693) (xy 372.080028 -219.678967) (xy 372.049502 -219.720983)
			(xy 372.012779 -219.757706) (xy 371.970763 -219.788232) (xy 371.924489 -219.81181) (xy 371.875096 -219.827858)
			(xy 371.823801 -219.835983) (xy 371.771867 -219.835983) (xy 371.720572 -219.827858) (xy 371.671179 -219.81181)
			(xy 371.624905 -219.788232) (xy 371.582889 -219.757706) (xy 371.546166 -219.720983) (xy 371.51564 -219.678967)
			(xy 371.492062 -219.632693) (xy 371.476014 -219.5833) (xy 371.467889 -219.532005) (xy 371.187979 -219.532005)
			(xy 371.179854 -219.5833) (xy 371.163806 -219.632693) (xy 371.140228 -219.678967) (xy 371.109702 -219.720983)
			(xy 371.072979 -219.757706) (xy 371.030963 -219.788232) (xy 370.984689 -219.81181) (xy 370.935296 -219.827858)
			(xy 370.884001 -219.835983) (xy 370.832067 -219.835983) (xy 370.780772 -219.827858) (xy 370.731379 -219.81181)
			(xy 370.685105 -219.788232) (xy 370.643089 -219.757706) (xy 370.606366 -219.720983) (xy 370.57584 -219.678967)
			(xy 370.552262 -219.632693) (xy 370.536214 -219.5833) (xy 370.528089 -219.532005) (xy 370.248179 -219.532005)
			(xy 370.240054 -219.5833) (xy 370.224006 -219.632693) (xy 370.200428 -219.678967) (xy 370.169902 -219.720983)
			(xy 370.133179 -219.757706) (xy 370.091163 -219.788232) (xy 370.044889 -219.81181) (xy 369.995496 -219.827858)
			(xy 369.944201 -219.835983) (xy 369.892267 -219.835983) (xy 369.840972 -219.827858) (xy 369.791579 -219.81181)
			(xy 369.745305 -219.788232) (xy 369.703289 -219.757706) (xy 369.666566 -219.720983) (xy 369.63604 -219.678967)
			(xy 369.612462 -219.632693) (xy 369.596414 -219.5833) (xy 369.588289 -219.532005) (xy 369.308379 -219.532005)
			(xy 369.300254 -219.5833) (xy 369.284206 -219.632693) (xy 369.260628 -219.678967) (xy 369.230102 -219.720983)
			(xy 369.193379 -219.757706) (xy 369.151363 -219.788232) (xy 369.105089 -219.81181) (xy 369.055696 -219.827858)
			(xy 369.004401 -219.835983) (xy 368.952467 -219.835983) (xy 368.901172 -219.827858) (xy 368.851779 -219.81181)
			(xy 368.805505 -219.788232) (xy 368.763489 -219.757706) (xy 368.726766 -219.720983) (xy 368.69624 -219.678967)
			(xy 368.672662 -219.632693) (xy 368.656614 -219.5833) (xy 368.648489 -219.532005) (xy 368.367465 -219.532005)
			(xy 368.365402 -219.55806) (xy 368.353147 -219.60881) (xy 368.333063 -219.657001) (xy 368.305649 -219.701434)
			(xy 368.271589 -219.741002) (xy 368.231729 -219.774721) (xy 368.187063 -219.801751) (xy 368.163094 -219.812108)
			(xy 368.149712 -219.818111) (xy 368.126848 -219.836463) (xy 368.110124 -219.860543) (xy 368.10091 -219.888375)
			(xy 368.099963 -219.917678) (xy 368.10315 -219.931996) (xy 368.11966 -220.001338) (xy 368.17173 -220.050614)
			(xy 368.182484 -220.060626) (xy 368.208341 -220.074556) (xy 368.237095 -220.080543) (xy 368.266363 -220.078091)
			(xy 368.29372 -220.067403) (xy 368.305588 -220.058742) (xy 368.327472 -220.04249) (xy 368.375447 -220.016619)
			(xy 368.427012 -219.998958) (xy 368.480774 -219.989984) (xy 368.508026 -219.9894) (xy 368.50828 -219.9894)
			(xy 368.53425 -219.989908) (xy 368.58555 -219.998029) (xy 368.634948 -220.014076) (xy 368.681228 -220.037651)
			(xy 368.72325 -220.068177) (xy 368.75998 -220.104899) (xy 368.790514 -220.146916) (xy 368.814099 -220.193191)
			(xy 368.830155 -220.242586) (xy 368.838287 -220.293885) (xy 368.838734 -220.319854) (xy 368.838734 -220.320616)
			(xy 368.838178 -220.345821) (xy 369.118389 -220.345821) (xy 369.118389 -220.293887) (xy 369.126514 -220.242592)
			(xy 369.142562 -220.193199) (xy 369.16614 -220.146925) (xy 369.196666 -220.104909) (xy 369.233389 -220.068186)
			(xy 369.275405 -220.03766) (xy 369.321679 -220.014082) (xy 369.371072 -219.998034) (xy 369.422367 -219.989909)
			(xy 369.474301 -219.989909) (xy 369.525596 -219.998034) (xy 369.574989 -220.014082) (xy 369.621263 -220.03766)
			(xy 369.663279 -220.068186) (xy 369.700002 -220.104909) (xy 369.730528 -220.146925) (xy 369.754106 -220.193199)
			(xy 369.770154 -220.242592) (xy 369.778279 -220.293887) (xy 369.778788 -220.319854) (xy 370.057426 -220.319854)
			(xy 370.057935 -220.293887) (xy 370.06606 -220.242592) (xy 370.082108 -220.193199) (xy 370.105686 -220.146925)
			(xy 370.136212 -220.104909) (xy 370.172935 -220.068186) (xy 370.214951 -220.03766) (xy 370.261225 -220.014082)
			(xy 370.310618 -219.998034) (xy 370.361913 -219.989909) (xy 370.413847 -219.989909) (xy 370.465142 -219.998034)
			(xy 370.514535 -220.014082) (xy 370.560809 -220.03766) (xy 370.602825 -220.068186) (xy 370.639548 -220.104909)
			(xy 370.670074 -220.146925) (xy 370.693652 -220.193199) (xy 370.7097 -220.242592) (xy 370.717825 -220.293887)
			(xy 370.718334 -220.319854) (xy 370.718334 -220.320616) (xy 370.717806 -220.345821) (xy 370.997989 -220.345821)
			(xy 370.997989 -220.293887) (xy 371.006114 -220.242592) (xy 371.022162 -220.193199) (xy 371.04574 -220.146925)
			(xy 371.076266 -220.104909) (xy 371.112989 -220.068186) (xy 371.155005 -220.03766) (xy 371.201279 -220.014082)
			(xy 371.250672 -219.998034) (xy 371.301967 -219.989909) (xy 371.353901 -219.989909) (xy 371.405196 -219.998034)
			(xy 371.454589 -220.014082) (xy 371.500863 -220.03766) (xy 371.542879 -220.068186) (xy 371.579602 -220.104909)
			(xy 371.610128 -220.146925) (xy 371.633706 -220.193199) (xy 371.649754 -220.242592) (xy 371.657879 -220.293887)
			(xy 371.658388 -220.319854) (xy 371.937026 -220.319854) (xy 371.937535 -220.293887) (xy 371.94566 -220.242592)
			(xy 371.961708 -220.193199) (xy 371.985286 -220.146925) (xy 372.015812 -220.104909) (xy 372.052535 -220.068186)
			(xy 372.094551 -220.03766) (xy 372.140825 -220.014082) (xy 372.190218 -219.998034) (xy 372.241513 -219.989909)
			(xy 372.293447 -219.989909) (xy 372.344742 -219.998034) (xy 372.394135 -220.014082) (xy 372.440409 -220.03766)
			(xy 372.482425 -220.068186) (xy 372.519148 -220.104909) (xy 372.549674 -220.146925) (xy 372.573252 -220.193199)
			(xy 372.5893 -220.242592) (xy 372.597425 -220.293887) (xy 372.597934 -220.319854) (xy 372.597934 -220.320616)
			(xy 372.597406 -220.345821) (xy 372.877589 -220.345821) (xy 372.877589 -220.293887) (xy 372.885714 -220.242592)
			(xy 372.901762 -220.193199) (xy 372.92534 -220.146925) (xy 372.955866 -220.104909) (xy 372.992589 -220.068186)
			(xy 373.034605 -220.03766) (xy 373.080879 -220.014082) (xy 373.130272 -219.998034) (xy 373.181567 -219.989909)
			(xy 373.233501 -219.989909) (xy 373.284796 -219.998034) (xy 373.334189 -220.014082) (xy 373.380463 -220.03766)
			(xy 373.422479 -220.068186) (xy 373.459202 -220.104909) (xy 373.489728 -220.146925) (xy 373.513306 -220.193199)
			(xy 373.529354 -220.242592) (xy 373.537479 -220.293887) (xy 373.537988 -220.319854) (xy 373.537479 -220.345821)
			(xy 373.529354 -220.397116) (xy 373.513306 -220.446509) (xy 373.489728 -220.492783) (xy 373.459202 -220.534799)
			(xy 373.422479 -220.571522) (xy 373.380463 -220.602048) (xy 373.334189 -220.625626) (xy 373.284796 -220.641674)
			(xy 373.233501 -220.649799) (xy 373.181567 -220.649799) (xy 373.130272 -220.641674) (xy 373.080879 -220.625626)
			(xy 373.034605 -220.602048) (xy 372.992589 -220.571522) (xy 372.955866 -220.534799) (xy 372.92534 -220.492783)
			(xy 372.901762 -220.446509) (xy 372.885714 -220.397116) (xy 372.877589 -220.345821) (xy 372.597406 -220.345821)
			(xy 372.597353 -220.348334) (xy 372.588024 -220.402981) (xy 372.579392 -220.429328) (xy 372.571518 -220.451172)
			(xy 372.775734 -220.80474) (xy 372.798594 -220.809058) (xy 372.823507 -220.814267) (xy 372.87149 -220.831224)
			(xy 372.916308 -220.855335) (xy 372.956902 -220.886029) (xy 372.992312 -220.922582) (xy 373.021702 -220.96413)
			(xy 373.044378 -221.009691) (xy 373.059803 -221.058189) (xy 373.067614 -221.108478) (xy 373.068088 -221.133924)
			(xy 373.067579 -221.159891) (xy 373.059454 -221.211186) (xy 373.043406 -221.260579) (xy 373.019828 -221.306853)
			(xy 372.989302 -221.348869) (xy 372.952579 -221.385592) (xy 372.910563 -221.416118) (xy 372.864289 -221.439696)
			(xy 372.814896 -221.455744) (xy 372.763601 -221.463869) (xy 372.711667 -221.463869) (xy 372.660372 -221.455744)
			(xy 372.610979 -221.439696) (xy 372.564705 -221.416118) (xy 372.522689 -221.385592) (xy 372.485966 -221.348869)
			(xy 372.45544 -221.306853) (xy 372.431862 -221.260579) (xy 372.415814 -221.211186) (xy 372.407689 -221.159891)
			(xy 372.40718 -221.133924) (xy 372.40774 -221.105938) (xy 372.417185 -221.050771) (xy 372.425976 -221.024196)
			(xy 372.433596 -221.002098) (xy 372.229888 -220.649038) (xy 372.206774 -220.64472) (xy 372.181833 -220.639583)
			(xy 372.13381 -220.622649) (xy 372.088952 -220.598551) (xy 372.04832 -220.567859) (xy 372.012875 -220.5313)
			(xy 371.983455 -220.489738) (xy 371.960756 -220.444156) (xy 371.945316 -220.395632) (xy 371.9375 -220.345314)
			(xy 371.937026 -220.319854) (xy 371.658388 -220.319854) (xy 371.657879 -220.345821) (xy 371.649754 -220.397116)
			(xy 371.633706 -220.446509) (xy 371.610128 -220.492783) (xy 371.579602 -220.534799) (xy 371.542879 -220.571522)
			(xy 371.500863 -220.602048) (xy 371.454589 -220.625626) (xy 371.405196 -220.641674) (xy 371.353901 -220.649799)
			(xy 371.301967 -220.649799) (xy 371.250672 -220.641674) (xy 371.201279 -220.625626) (xy 371.155005 -220.602048)
			(xy 371.112989 -220.571522) (xy 371.076266 -220.534799) (xy 371.04574 -220.492783) (xy 371.022162 -220.446509)
			(xy 371.006114 -220.397116) (xy 370.997989 -220.345821) (xy 370.717806 -220.345821) (xy 370.717753 -220.348334)
			(xy 370.708424 -220.402981) (xy 370.699792 -220.429328) (xy 370.691918 -220.451172) (xy 370.896134 -220.80474)
			(xy 370.918994 -220.809058) (xy 370.943907 -220.814267) (xy 370.99189 -220.831224) (xy 371.036708 -220.855335)
			(xy 371.077302 -220.886029) (xy 371.112712 -220.922582) (xy 371.142102 -220.96413) (xy 371.164778 -221.009691)
			(xy 371.180203 -221.058189) (xy 371.188014 -221.108478) (xy 371.188488 -221.133924) (xy 371.187979 -221.159891)
			(xy 371.179854 -221.211186) (xy 371.163806 -221.260579) (xy 371.140228 -221.306853) (xy 371.109702 -221.348869)
			(xy 371.072979 -221.385592) (xy 371.030963 -221.416118) (xy 370.984689 -221.439696) (xy 370.935296 -221.455744)
			(xy 370.884001 -221.463869) (xy 370.832067 -221.463869) (xy 370.780772 -221.455744) (xy 370.731379 -221.439696)
			(xy 370.685105 -221.416118) (xy 370.643089 -221.385592) (xy 370.606366 -221.348869) (xy 370.57584 -221.306853)
			(xy 370.552262 -221.260579) (xy 370.536214 -221.211186) (xy 370.528089 -221.159891) (xy 370.52758 -221.133924)
			(xy 370.52814 -221.105938) (xy 370.537585 -221.050771) (xy 370.546376 -221.024196) (xy 370.553996 -221.002098)
			(xy 370.350288 -220.649038) (xy 370.327174 -220.64472) (xy 370.302233 -220.639583) (xy 370.25421 -220.622649)
			(xy 370.209352 -220.598551) (xy 370.16872 -220.567859) (xy 370.133275 -220.5313) (xy 370.103855 -220.489738)
			(xy 370.081156 -220.444156) (xy 370.065716 -220.395632) (xy 370.0579 -220.345314) (xy 370.057426 -220.319854)
			(xy 369.778788 -220.319854) (xy 369.778279 -220.345821) (xy 369.770154 -220.397116) (xy 369.754106 -220.446509)
			(xy 369.730528 -220.492783) (xy 369.700002 -220.534799) (xy 369.663279 -220.571522) (xy 369.621263 -220.602048)
			(xy 369.574989 -220.625626) (xy 369.525596 -220.641674) (xy 369.474301 -220.649799) (xy 369.422367 -220.649799)
			(xy 369.371072 -220.641674) (xy 369.321679 -220.625626) (xy 369.275405 -220.602048) (xy 369.233389 -220.571522)
			(xy 369.196666 -220.534799) (xy 369.16614 -220.492783) (xy 369.142562 -220.446509) (xy 369.126514 -220.397116)
			(xy 369.118389 -220.345821) (xy 368.838178 -220.345821) (xy 368.838123 -220.348332) (xy 368.828799 -220.402975)
			(xy 368.820192 -220.429328) (xy 368.812318 -220.451172) (xy 369.016534 -220.80474) (xy 369.039394 -220.809058)
			(xy 369.064323 -220.81421) (xy 369.112324 -220.831154) (xy 369.157157 -220.855259) (xy 369.197764 -220.885956)
			(xy 369.233182 -220.922517) (xy 369.262573 -220.964077) (xy 369.285243 -221.009654) (xy 369.300654 -221.058168)
			(xy 369.308442 -221.108472) (xy 369.308888 -221.133924) (xy 369.308377 -221.159891) (xy 369.30025 -221.211185)
			(xy 369.2842 -221.260577) (xy 369.260621 -221.30685) (xy 369.230095 -221.348865) (xy 369.193373 -221.385588)
			(xy 369.151358 -221.416116) (xy 369.105086 -221.439696) (xy 369.055695 -221.455748) (xy 369.004401 -221.463876)
			(xy 368.978434 -221.464378) (xy 368.97818 -221.464378) (xy 368.954265 -221.463959) (xy 368.906935 -221.457065)
			(xy 368.861096 -221.44341) (xy 368.817709 -221.42328) (xy 368.777683 -221.397097) (xy 368.759486 -221.381574)
			(xy 368.747703 -221.371965) (xy 368.719988 -221.359503) (xy 368.689834 -221.35574) (xy 368.659907 -221.361011)
			(xy 368.632853 -221.37485) (xy 368.611065 -221.396031) (xy 368.596468 -221.422684) (xy 368.592862 -221.437454)
			(xy 368.581658 -221.4902) (xy 368.552752 -221.594094) (xy 368.516576 -221.695687) (xy 368.473312 -221.794468)
			(xy 368.423176 -221.889946) (xy 368.387403 -221.94774) (xy 369.117626 -221.94774) (xy 369.118075 -221.922288)
			(xy 369.125861 -221.871984) (xy 369.141271 -221.823469) (xy 369.16394 -221.777892) (xy 369.193331 -221.73633)
			(xy 369.228749 -221.699769) (xy 369.269355 -221.669073) (xy 369.31419 -221.644968) (xy 369.362191 -221.628025)
			(xy 369.38712 -221.622874) (xy 369.40998 -221.618556) (xy 369.613942 -221.264988) (xy 369.606322 -221.243144)
			(xy 369.597704 -221.216728) (xy 369.588377 -221.161957) (xy 369.58778 -221.134178) (xy 369.58778 -221.133924)
			(xy 369.588289 -221.107957) (xy 369.596414 -221.056662) (xy 369.612462 -221.007269) (xy 369.63604 -220.960995)
			(xy 369.666566 -220.918979) (xy 369.703289 -220.882256) (xy 369.745305 -220.85173) (xy 369.791579 -220.828152)
			(xy 369.840972 -220.812104) (xy 369.892267 -220.803979) (xy 369.944201 -220.803979) (xy 369.995496 -220.812104)
			(xy 370.044889 -220.828152) (xy 370.091163 -220.85173) (xy 370.133179 -220.882256) (xy 370.169902 -220.918979)
			(xy 370.200428 -220.960995) (xy 370.224006 -221.007269) (xy 370.240054 -221.056662) (xy 370.248179 -221.107957)
			(xy 370.248688 -221.133924) (xy 370.2482 -221.159397) (xy 370.240378 -221.209738) (xy 370.224923 -221.258282)
			(xy 370.202202 -221.30388) (xy 370.172752 -221.34545) (xy 370.137271 -221.382009) (xy 370.0966 -221.412689)
			(xy 370.051703 -221.436765) (xy 370.003642 -221.453665) (xy 369.978686 -221.45879) (xy 369.955572 -221.463108)
			(xy 369.752118 -221.815914) (xy 369.759738 -221.838012) (xy 369.768477 -221.8646) (xy 369.777924 -221.919759)
			(xy 369.778534 -221.94774) (xy 370.997226 -221.94774) (xy 370.997675 -221.922288) (xy 371.005461 -221.871984)
			(xy 371.020871 -221.823469) (xy 371.04354 -221.777892) (xy 371.072931 -221.73633) (xy 371.108349 -221.699769)
			(xy 371.148955 -221.669073) (xy 371.19379 -221.644968) (xy 371.241791 -221.628025) (xy 371.26672 -221.622874)
			(xy 371.28958 -221.618556) (xy 371.493542 -221.264988) (xy 371.485922 -221.243144) (xy 371.477304 -221.216728)
			(xy 371.467977 -221.161957) (xy 371.46738 -221.134178) (xy 371.46738 -221.133924) (xy 371.467889 -221.107957)
			(xy 371.476014 -221.056662) (xy 371.492062 -221.007269) (xy 371.51564 -220.960995) (xy 371.546166 -220.918979)
			(xy 371.582889 -220.882256) (xy 371.624905 -220.85173) (xy 371.671179 -220.828152) (xy 371.720572 -220.812104)
			(xy 371.771867 -220.803979) (xy 371.823801 -220.803979) (xy 371.875096 -220.812104) (xy 371.924489 -220.828152)
			(xy 371.970763 -220.85173) (xy 372.012779 -220.882256) (xy 372.049502 -220.918979) (xy 372.080028 -220.960995)
			(xy 372.103606 -221.007269) (xy 372.119654 -221.056662) (xy 372.127779 -221.107957) (xy 372.128288 -221.133924)
			(xy 372.1278 -221.159397) (xy 372.119978 -221.209738) (xy 372.104523 -221.258282) (xy 372.081802 -221.30388)
			(xy 372.052352 -221.34545) (xy 372.016871 -221.382009) (xy 371.9762 -221.412689) (xy 371.931303 -221.436765)
			(xy 371.883242 -221.453665) (xy 371.858286 -221.45879) (xy 371.835172 -221.463108) (xy 371.631718 -221.815914)
			(xy 371.639338 -221.838012) (xy 371.648077 -221.8646) (xy 371.657524 -221.919759) (xy 371.658134 -221.94774)
			(xy 372.876826 -221.94774) (xy 372.877275 -221.922288) (xy 372.885061 -221.871984) (xy 372.900471 -221.823469)
			(xy 372.92314 -221.777892) (xy 372.952531 -221.73633) (xy 372.987949 -221.699769) (xy 373.028555 -221.669073)
			(xy 373.07339 -221.644968) (xy 373.121391 -221.628025) (xy 373.14632 -221.622874) (xy 373.16918 -221.618556)
			(xy 373.373142 -221.264988) (xy 373.365522 -221.243144) (xy 373.356904 -221.216728) (xy 373.347577 -221.161957)
			(xy 373.34698 -221.134178) (xy 373.34698 -221.133924) (xy 373.347489 -221.107957) (xy 373.355614 -221.056662)
			(xy 373.371662 -221.007269) (xy 373.39524 -220.960995) (xy 373.425766 -220.918979) (xy 373.462489 -220.882256)
			(xy 373.504505 -220.85173) (xy 373.550779 -220.828152) (xy 373.600172 -220.812104) (xy 373.651467 -220.803979)
			(xy 373.703401 -220.803979) (xy 373.754696 -220.812104) (xy 373.804089 -220.828152) (xy 373.850363 -220.85173)
			(xy 373.892379 -220.882256) (xy 373.929102 -220.918979) (xy 373.959628 -220.960995) (xy 373.983206 -221.007269)
			(xy 373.999254 -221.056662) (xy 374.007379 -221.107957) (xy 374.007888 -221.133924) (xy 374.0074 -221.159397)
			(xy 373.999578 -221.209738) (xy 373.984123 -221.258282) (xy 373.961402 -221.30388) (xy 373.931952 -221.34545)
			(xy 373.896471 -221.382009) (xy 373.8558 -221.412689) (xy 373.810903 -221.436765) (xy 373.762842 -221.453665)
			(xy 373.737886 -221.45879) (xy 373.714772 -221.463108) (xy 373.511318 -221.815914) (xy 373.518938 -221.838012)
			(xy 373.527677 -221.8646) (xy 373.537124 -221.919759) (xy 373.537734 -221.94774) (xy 373.537225 -221.973707)
			(xy 373.5291 -222.025002) (xy 373.513052 -222.074395) (xy 373.489474 -222.120669) (xy 373.458948 -222.162685)
			(xy 373.422225 -222.199408) (xy 373.380209 -222.229934) (xy 373.333935 -222.253512) (xy 373.284542 -222.26956)
			(xy 373.233247 -222.277685) (xy 373.181313 -222.277685) (xy 373.130018 -222.26956) (xy 373.080625 -222.253512)
			(xy 373.034351 -222.229934) (xy 372.992335 -222.199408) (xy 372.955612 -222.162685) (xy 372.925086 -222.120669)
			(xy 372.901508 -222.074395) (xy 372.88546 -222.025002) (xy 372.877335 -221.973707) (xy 372.876826 -221.94774)
			(xy 371.658134 -221.94774) (xy 371.657625 -221.973707) (xy 371.6495 -222.025002) (xy 371.633452 -222.074395)
			(xy 371.609874 -222.120669) (xy 371.579348 -222.162685) (xy 371.542625 -222.199408) (xy 371.500609 -222.229934)
			(xy 371.454335 -222.253512) (xy 371.404942 -222.26956) (xy 371.353647 -222.277685) (xy 371.301713 -222.277685)
			(xy 371.250418 -222.26956) (xy 371.201025 -222.253512) (xy 371.154751 -222.229934) (xy 371.112735 -222.199408)
			(xy 371.076012 -222.162685) (xy 371.045486 -222.120669) (xy 371.021908 -222.074395) (xy 371.00586 -222.025002)
			(xy 370.997735 -221.973707) (xy 370.997226 -221.94774) (xy 369.778534 -221.94774) (xy 369.778025 -221.973707)
			(xy 369.7699 -222.025002) (xy 369.753852 -222.074395) (xy 369.730274 -222.120669) (xy 369.699748 -222.162685)
			(xy 369.663025 -222.199408) (xy 369.621009 -222.229934) (xy 369.574735 -222.253512) (xy 369.525342 -222.26956)
			(xy 369.474047 -222.277685) (xy 369.422113 -222.277685) (xy 369.370818 -222.26956) (xy 369.321425 -222.253512)
			(xy 369.275151 -222.229934) (xy 369.233135 -222.199408) (xy 369.196412 -222.162685) (xy 369.165886 -222.120669)
			(xy 369.142308 -222.074395) (xy 369.12626 -222.025002) (xy 369.118135 -221.973707) (xy 369.117626 -221.94774)
			(xy 368.387403 -221.94774) (xy 368.366418 -221.981642) (xy 368.303322 -222.069099) (xy 368.234204 -222.151877)
			(xy 368.159409 -222.229565) (xy 368.11966 -222.266002) (xy 368.10315 -222.335598) (xy 368.099873 -222.349908)
			(xy 368.100767 -222.379239) (xy 368.109984 -222.407098) (xy 368.126758 -222.431175) (xy 368.149699 -222.449473)
			(xy 368.163094 -222.455486) (xy 368.185597 -222.46512) (xy 368.22772 -222.490051) (xy 368.265707 -222.520922)
			(xy 368.298727 -222.557056) (xy 368.326058 -222.597663) (xy 368.347102 -222.641857) (xy 368.3614 -222.688671)
			(xy 368.368638 -222.737082) (xy 368.369088 -222.761556) (xy 368.368642 -222.786019) (xy 368.368418 -222.787523)
			(xy 368.648489 -222.787523) (xy 368.648489 -222.735589) (xy 368.656614 -222.684294) (xy 368.672662 -222.634901)
			(xy 368.69624 -222.588627) (xy 368.726766 -222.546611) (xy 368.763489 -222.509888) (xy 368.805505 -222.479362)
			(xy 368.851779 -222.455784) (xy 368.901172 -222.439736) (xy 368.952467 -222.431611) (xy 369.004401 -222.431611)
			(xy 369.055696 -222.439736) (xy 369.105089 -222.455784) (xy 369.151363 -222.479362) (xy 369.193379 -222.509888)
			(xy 369.230102 -222.546611) (xy 369.260628 -222.588627) (xy 369.284206 -222.634901) (xy 369.300254 -222.684294)
			(xy 369.308379 -222.735589) (xy 369.308888 -222.761556) (xy 369.308379 -222.787523) (xy 369.588289 -222.787523)
			(xy 369.588289 -222.735589) (xy 369.596414 -222.684294) (xy 369.612462 -222.634901) (xy 369.63604 -222.588627)
			(xy 369.666566 -222.546611) (xy 369.703289 -222.509888) (xy 369.745305 -222.479362) (xy 369.791579 -222.455784)
			(xy 369.840972 -222.439736) (xy 369.892267 -222.431611) (xy 369.944201 -222.431611) (xy 369.995496 -222.439736)
			(xy 370.044889 -222.455784) (xy 370.091163 -222.479362) (xy 370.133179 -222.509888) (xy 370.169902 -222.546611)
			(xy 370.200428 -222.588627) (xy 370.224006 -222.634901) (xy 370.240054 -222.684294) (xy 370.248179 -222.735589)
			(xy 370.248688 -222.761556) (xy 370.248179 -222.787523) (xy 370.528089 -222.787523) (xy 370.528089 -222.735589)
			(xy 370.536214 -222.684294) (xy 370.552262 -222.634901) (xy 370.57584 -222.588627) (xy 370.606366 -222.546611)
			(xy 370.643089 -222.509888) (xy 370.685105 -222.479362) (xy 370.731379 -222.455784) (xy 370.780772 -222.439736)
			(xy 370.832067 -222.431611) (xy 370.884001 -222.431611) (xy 370.935296 -222.439736) (xy 370.984689 -222.455784)
			(xy 371.030963 -222.479362) (xy 371.072979 -222.509888) (xy 371.109702 -222.546611) (xy 371.140228 -222.588627)
			(xy 371.163806 -222.634901) (xy 371.179854 -222.684294) (xy 371.187979 -222.735589) (xy 371.188488 -222.761556)
			(xy 371.187979 -222.787523) (xy 371.467889 -222.787523) (xy 371.467889 -222.735589) (xy 371.476014 -222.684294)
			(xy 371.492062 -222.634901) (xy 371.51564 -222.588627) (xy 371.546166 -222.546611) (xy 371.582889 -222.509888)
			(xy 371.624905 -222.479362) (xy 371.671179 -222.455784) (xy 371.720572 -222.439736) (xy 371.771867 -222.431611)
			(xy 371.823801 -222.431611) (xy 371.875096 -222.439736) (xy 371.924489 -222.455784) (xy 371.970763 -222.479362)
			(xy 372.012779 -222.509888) (xy 372.049502 -222.546611) (xy 372.080028 -222.588627) (xy 372.103606 -222.634901)
			(xy 372.119654 -222.684294) (xy 372.127779 -222.735589) (xy 372.128288 -222.761556) (xy 372.127779 -222.787523)
			(xy 372.407689 -222.787523) (xy 372.407689 -222.735589) (xy 372.415814 -222.684294) (xy 372.431862 -222.634901)
			(xy 372.45544 -222.588627) (xy 372.485966 -222.546611) (xy 372.522689 -222.509888) (xy 372.564705 -222.479362)
			(xy 372.610979 -222.455784) (xy 372.660372 -222.439736) (xy 372.711667 -222.431611) (xy 372.763601 -222.431611)
			(xy 372.814896 -222.439736) (xy 372.864289 -222.455784) (xy 372.910563 -222.479362) (xy 372.952579 -222.509888)
			(xy 372.989302 -222.546611) (xy 373.019828 -222.588627) (xy 373.043406 -222.634901) (xy 373.059454 -222.684294)
			(xy 373.067579 -222.735589) (xy 373.068088 -222.761556) (xy 373.067579 -222.787523) (xy 373.347489 -222.787523)
			(xy 373.347489 -222.735589) (xy 373.355614 -222.684294) (xy 373.371662 -222.634901) (xy 373.39524 -222.588627)
			(xy 373.425766 -222.546611) (xy 373.462489 -222.509888) (xy 373.504505 -222.479362) (xy 373.550779 -222.455784)
			(xy 373.600172 -222.439736) (xy 373.651467 -222.431611) (xy 373.703401 -222.431611) (xy 373.754696 -222.439736)
			(xy 373.804089 -222.455784) (xy 373.850363 -222.479362) (xy 373.892379 -222.509888) (xy 373.929102 -222.546611)
			(xy 373.959628 -222.588627) (xy 373.983206 -222.634901) (xy 373.999254 -222.684294) (xy 374.007379 -222.735589)
			(xy 374.007888 -222.761556) (xy 374.007379 -222.787523) (xy 373.999254 -222.838818) (xy 373.983206 -222.888211)
			(xy 373.959628 -222.934485) (xy 373.929102 -222.976501) (xy 373.892379 -223.013224) (xy 373.850363 -223.04375)
			(xy 373.804089 -223.067328) (xy 373.754696 -223.083376) (xy 373.703401 -223.091501) (xy 373.651467 -223.091501)
			(xy 373.600172 -223.083376) (xy 373.550779 -223.067328) (xy 373.504505 -223.04375) (xy 373.462489 -223.013224)
			(xy 373.425766 -222.976501) (xy 373.39524 -222.934485) (xy 373.371662 -222.888211) (xy 373.355614 -222.838818)
			(xy 373.347489 -222.787523) (xy 373.067579 -222.787523) (xy 373.059454 -222.838818) (xy 373.043406 -222.888211)
			(xy 373.019828 -222.934485) (xy 372.989302 -222.976501) (xy 372.952579 -223.013224) (xy 372.910563 -223.04375)
			(xy 372.864289 -223.067328) (xy 372.814896 -223.083376) (xy 372.763601 -223.091501) (xy 372.711667 -223.091501)
			(xy 372.660372 -223.083376) (xy 372.610979 -223.067328) (xy 372.564705 -223.04375) (xy 372.522689 -223.013224)
			(xy 372.485966 -222.976501) (xy 372.45544 -222.934485) (xy 372.431862 -222.888211) (xy 372.415814 -222.838818)
			(xy 372.407689 -222.787523) (xy 372.127779 -222.787523) (xy 372.119654 -222.838818) (xy 372.103606 -222.888211)
			(xy 372.080028 -222.934485) (xy 372.049502 -222.976501) (xy 372.012779 -223.013224) (xy 371.970763 -223.04375)
			(xy 371.924489 -223.067328) (xy 371.875096 -223.083376) (xy 371.823801 -223.091501) (xy 371.771867 -223.091501)
			(xy 371.720572 -223.083376) (xy 371.671179 -223.067328) (xy 371.624905 -223.04375) (xy 371.582889 -223.013224)
			(xy 371.546166 -222.976501) (xy 371.51564 -222.934485) (xy 371.492062 -222.888211) (xy 371.476014 -222.838818)
			(xy 371.467889 -222.787523) (xy 371.187979 -222.787523) (xy 371.179854 -222.838818) (xy 371.163806 -222.888211)
			(xy 371.140228 -222.934485) (xy 371.109702 -222.976501) (xy 371.072979 -223.013224) (xy 371.030963 -223.04375)
			(xy 370.984689 -223.067328) (xy 370.935296 -223.083376) (xy 370.884001 -223.091501) (xy 370.832067 -223.091501)
			(xy 370.780772 -223.083376) (xy 370.731379 -223.067328) (xy 370.685105 -223.04375) (xy 370.643089 -223.013224)
			(xy 370.606366 -222.976501) (xy 370.57584 -222.934485) (xy 370.552262 -222.888211) (xy 370.536214 -222.838818)
			(xy 370.528089 -222.787523) (xy 370.248179 -222.787523) (xy 370.240054 -222.838818) (xy 370.224006 -222.888211)
			(xy 370.200428 -222.934485) (xy 370.169902 -222.976501) (xy 370.133179 -223.013224) (xy 370.091163 -223.04375)
			(xy 370.044889 -223.067328) (xy 369.995496 -223.083376) (xy 369.944201 -223.091501) (xy 369.892267 -223.091501)
			(xy 369.840972 -223.083376) (xy 369.791579 -223.067328) (xy 369.745305 -223.04375) (xy 369.703289 -223.013224)
			(xy 369.666566 -222.976501) (xy 369.63604 -222.934485) (xy 369.612462 -222.888211) (xy 369.596414 -222.838818)
			(xy 369.588289 -222.787523) (xy 369.308379 -222.787523) (xy 369.300254 -222.838818) (xy 369.284206 -222.888211)
			(xy 369.260628 -222.934485) (xy 369.230102 -222.976501) (xy 369.193379 -223.013224) (xy 369.151363 -223.04375)
			(xy 369.105089 -223.067328) (xy 369.055696 -223.083376) (xy 369.004401 -223.091501) (xy 368.952467 -223.091501)
			(xy 368.901172 -223.083376) (xy 368.851779 -223.067328) (xy 368.805505 -223.04375) (xy 368.763489 -223.013224)
			(xy 368.726766 -222.976501) (xy 368.69624 -222.934485) (xy 368.672662 -222.888211) (xy 368.656614 -222.838818)
			(xy 368.648489 -222.787523) (xy 368.368418 -222.787523) (xy 368.361423 -222.834409) (xy 368.347151 -222.881206)
			(xy 368.326137 -222.92539) (xy 368.298841 -222.965993) (xy 368.265859 -223.00213) (xy 368.227911 -223.033012)
			(xy 368.185826 -223.057963) (xy 368.163348 -223.067626) (xy 368.149962 -223.073626) (xy 368.12709 -223.091974)
			(xy 368.11036 -223.116054) (xy 368.101145 -223.143891) (xy 368.100203 -223.173197) (xy 368.103404 -223.187514)
			(xy 368.108818 -223.208471) (xy 368.118598 -223.250642) (xy 368.122962 -223.271842) (xy 368.126548 -223.286624)
			(xy 368.141119 -223.313306) (xy 368.162903 -223.334512) (xy 368.189967 -223.348359) (xy 368.219909 -223.35362)
			(xy 368.250072 -223.349827) (xy 368.27778 -223.337317) (xy 368.289586 -223.327722) (xy 368.307781 -223.312254)
			(xy 368.347783 -223.28617) (xy 368.391121 -223.26611) (xy 368.436893 -223.252492) (xy 368.484149 -223.245599)
			(xy 368.508026 -223.245172) (xy 368.50828 -223.245172) (xy 368.53425 -223.245653) (xy 368.58555 -223.253776)
			(xy 368.634947 -223.269824) (xy 368.681226 -223.293403) (xy 368.723245 -223.323932) (xy 368.759972 -223.360659)
			(xy 368.7905 -223.402679) (xy 368.814078 -223.448958) (xy 368.830125 -223.498356) (xy 368.838247 -223.549656)
			(xy 368.838734 -223.575626) (xy 368.838264 -223.601075) (xy 368.838184 -223.601593) (xy 369.118389 -223.601593)
			(xy 369.118389 -223.549659) (xy 369.126514 -223.498364) (xy 369.142562 -223.448971) (xy 369.16614 -223.402697)
			(xy 369.196666 -223.360681) (xy 369.233389 -223.323958) (xy 369.275405 -223.293432) (xy 369.321679 -223.269854)
			(xy 369.371072 -223.253806) (xy 369.422367 -223.245681) (xy 369.474301 -223.245681) (xy 369.525596 -223.253806)
			(xy 369.574989 -223.269854) (xy 369.621263 -223.293432) (xy 369.663279 -223.323958) (xy 369.700002 -223.360681)
			(xy 369.730528 -223.402697) (xy 369.754106 -223.448971) (xy 369.770154 -223.498364) (xy 369.778279 -223.549659)
			(xy 369.778788 -223.575626) (xy 369.778279 -223.601593) (xy 369.770154 -223.652888) (xy 369.754106 -223.702281)
			(xy 369.730528 -223.748555) (xy 369.700002 -223.790571) (xy 369.663279 -223.827294) (xy 369.621263 -223.85782)
			(xy 369.574989 -223.881398) (xy 369.525596 -223.897446) (xy 369.474301 -223.905571) (xy 369.422367 -223.905571)
			(xy 369.371072 -223.897446) (xy 369.321679 -223.881398) (xy 369.275405 -223.85782) (xy 369.233389 -223.827294)
			(xy 369.196666 -223.790571) (xy 369.16614 -223.748555) (xy 369.142562 -223.702281) (xy 369.126514 -223.652888)
			(xy 369.118389 -223.601593) (xy 368.838184 -223.601593) (xy 368.830459 -223.651372) (xy 368.81504 -223.699878)
			(xy 368.792368 -223.745449) (xy 368.762981 -223.787007) (xy 368.727572 -223.82357) (xy 368.686978 -223.854275)
			(xy 368.642158 -223.878396) (xy 368.594171 -223.895364) (xy 368.56924 -223.900492) (xy 368.546126 -223.90481)
			(xy 368.342672 -224.257616) (xy 368.350292 -224.279714) (xy 368.359082 -224.306289) (xy 368.368526 -224.361457)
			(xy 368.369088 -224.389442) (xy 368.64798 -224.389442) (xy 368.648489 -224.363475) (xy 368.656614 -224.31218)
			(xy 368.672662 -224.262787) (xy 368.69624 -224.216513) (xy 368.726766 -224.174497) (xy 368.763489 -224.137774)
			(xy 368.805505 -224.107248) (xy 368.851779 -224.08367) (xy 368.901172 -224.067622) (xy 368.952467 -224.059497)
			(xy 369.004401 -224.059497) (xy 369.055696 -224.067622) (xy 369.105089 -224.08367) (xy 369.151363 -224.107248)
			(xy 369.193379 -224.137774) (xy 369.230102 -224.174497) (xy 369.260628 -224.216513) (xy 369.284206 -224.262787)
			(xy 369.300254 -224.31218) (xy 369.308379 -224.363475) (xy 369.308888 -224.389442) (xy 369.58778 -224.389442)
			(xy 369.588187 -224.363988) (xy 369.595974 -224.31368) (xy 369.611387 -224.265161) (xy 369.63406 -224.219581)
			(xy 369.663456 -224.178019) (xy 369.69888 -224.141457) (xy 369.739493 -224.110763) (xy 369.784334 -224.086661)
			(xy 369.832342 -224.069724) (xy 369.857274 -224.064576) (xy 369.880134 -224.060258) (xy 370.083842 -223.707198)
			(xy 370.076222 -223.685354) (xy 370.067498 -223.658762) (xy 370.058041 -223.603606) (xy 370.057426 -223.575626)
			(xy 370.057935 -223.549659) (xy 370.06606 -223.498364) (xy 370.082108 -223.448971) (xy 370.105686 -223.402697)
			(xy 370.136212 -223.360681) (xy 370.172935 -223.323958) (xy 370.214951 -223.293432) (xy 370.261225 -223.269854)
			(xy 370.310618 -223.253806) (xy 370.361913 -223.245681) (xy 370.413847 -223.245681) (xy 370.465142 -223.253806)
			(xy 370.514535 -223.269854) (xy 370.560809 -223.293432) (xy 370.602825 -223.323958) (xy 370.639548 -223.360681)
			(xy 370.670074 -223.402697) (xy 370.693652 -223.448971) (xy 370.7097 -223.498364) (xy 370.717825 -223.549659)
			(xy 370.718334 -223.575626) (xy 370.717886 -223.601078) (xy 370.717806 -223.601593) (xy 370.997989 -223.601593)
			(xy 370.997989 -223.549659) (xy 371.006114 -223.498364) (xy 371.022162 -223.448971) (xy 371.04574 -223.402697)
			(xy 371.076266 -223.360681) (xy 371.112989 -223.323958) (xy 371.155005 -223.293432) (xy 371.201279 -223.269854)
			(xy 371.250672 -223.253806) (xy 371.301967 -223.245681) (xy 371.353901 -223.245681) (xy 371.405196 -223.253806)
			(xy 371.454589 -223.269854) (xy 371.500863 -223.293432) (xy 371.542879 -223.323958) (xy 371.579602 -223.360681)
			(xy 371.610128 -223.402697) (xy 371.633706 -223.448971) (xy 371.649754 -223.498364) (xy 371.657879 -223.549659)
			(xy 371.658388 -223.575626) (xy 371.657879 -223.601593) (xy 371.649754 -223.652888) (xy 371.633706 -223.702281)
			(xy 371.610128 -223.748555) (xy 371.579602 -223.790571) (xy 371.542879 -223.827294) (xy 371.500863 -223.85782)
			(xy 371.454589 -223.881398) (xy 371.405196 -223.897446) (xy 371.353901 -223.905571) (xy 371.301967 -223.905571)
			(xy 371.250672 -223.897446) (xy 371.201279 -223.881398) (xy 371.155005 -223.85782) (xy 371.112989 -223.827294)
			(xy 371.076266 -223.790571) (xy 371.04574 -223.748555) (xy 371.022162 -223.702281) (xy 371.006114 -223.652888)
			(xy 370.997989 -223.601593) (xy 370.717806 -223.601593) (xy 370.710104 -223.651385) (xy 370.694697 -223.699901)
			(xy 370.672029 -223.74548) (xy 370.642638 -223.787043) (xy 370.607219 -223.823605) (xy 370.56661 -223.8543)
			(xy 370.521774 -223.878403) (xy 370.47377 -223.895342) (xy 370.44884 -223.900492) (xy 370.425726 -223.90481)
			(xy 370.222272 -224.257616) (xy 370.229892 -224.279714) (xy 370.238633 -224.306301) (xy 370.248078 -224.361461)
			(xy 370.248688 -224.389442) (xy 370.52758 -224.389442) (xy 370.528089 -224.363475) (xy 370.536214 -224.31218)
			(xy 370.552262 -224.262787) (xy 370.57584 -224.216513) (xy 370.606366 -224.174497) (xy 370.643089 -224.137774)
			(xy 370.685105 -224.107248) (xy 370.731379 -224.08367) (xy 370.780772 -224.067622) (xy 370.832067 -224.059497)
			(xy 370.884001 -224.059497) (xy 370.935296 -224.067622) (xy 370.984689 -224.08367) (xy 371.030963 -224.107248)
			(xy 371.072979 -224.137774) (xy 371.109702 -224.174497) (xy 371.140228 -224.216513) (xy 371.163806 -224.262787)
			(xy 371.179854 -224.31218) (xy 371.187979 -224.363475) (xy 371.188488 -224.389442) (xy 371.46738 -224.389442)
			(xy 371.467787 -224.363988) (xy 371.475574 -224.31368) (xy 371.490987 -224.265161) (xy 371.51366 -224.219581)
			(xy 371.543056 -224.178019) (xy 371.57848 -224.141457) (xy 371.619093 -224.110763) (xy 371.663934 -224.086661)
			(xy 371.711942 -224.069724) (xy 371.736874 -224.064576) (xy 371.759734 -224.060258) (xy 371.963442 -223.707198)
			(xy 371.955822 -223.685354) (xy 371.947098 -223.658762) (xy 371.937641 -223.603606) (xy 371.937026 -223.575626)
			(xy 371.937535 -223.549659) (xy 371.94566 -223.498364) (xy 371.961708 -223.448971) (xy 371.985286 -223.402697)
			(xy 372.015812 -223.360681) (xy 372.052535 -223.323958) (xy 372.094551 -223.293432) (xy 372.140825 -223.269854)
			(xy 372.190218 -223.253806) (xy 372.241513 -223.245681) (xy 372.293447 -223.245681) (xy 372.344742 -223.253806)
			(xy 372.394135 -223.269854) (xy 372.440409 -223.293432) (xy 372.482425 -223.323958) (xy 372.519148 -223.360681)
			(xy 372.549674 -223.402697) (xy 372.573252 -223.448971) (xy 372.5893 -223.498364) (xy 372.597425 -223.549659)
			(xy 372.597934 -223.575626) (xy 372.597486 -223.601078) (xy 372.597406 -223.601593) (xy 372.877589 -223.601593)
			(xy 372.877589 -223.549659) (xy 372.885714 -223.498364) (xy 372.901762 -223.448971) (xy 372.92534 -223.402697)
			(xy 372.955866 -223.360681) (xy 372.992589 -223.323958) (xy 373.034605 -223.293432) (xy 373.080879 -223.269854)
			(xy 373.130272 -223.253806) (xy 373.181567 -223.245681) (xy 373.233501 -223.245681) (xy 373.284796 -223.253806)
			(xy 373.334189 -223.269854) (xy 373.380463 -223.293432) (xy 373.422479 -223.323958) (xy 373.459202 -223.360681)
			(xy 373.489728 -223.402697) (xy 373.513306 -223.448971) (xy 373.529354 -223.498364) (xy 373.537479 -223.549659)
			(xy 373.537988 -223.575626) (xy 373.537479 -223.601593) (xy 373.529354 -223.652888) (xy 373.513306 -223.702281)
			(xy 373.489728 -223.748555) (xy 373.459202 -223.790571) (xy 373.422479 -223.827294) (xy 373.380463 -223.85782)
			(xy 373.334189 -223.881398) (xy 373.284796 -223.897446) (xy 373.233501 -223.905571) (xy 373.181567 -223.905571)
			(xy 373.130272 -223.897446) (xy 373.080879 -223.881398) (xy 373.034605 -223.85782) (xy 372.992589 -223.827294)
			(xy 372.955866 -223.790571) (xy 372.92534 -223.748555) (xy 372.901762 -223.702281) (xy 372.885714 -223.652888)
			(xy 372.877589 -223.601593) (xy 372.597406 -223.601593) (xy 372.589704 -223.651385) (xy 372.574297 -223.699901)
			(xy 372.551629 -223.74548) (xy 372.522238 -223.787043) (xy 372.486819 -223.823605) (xy 372.44621 -223.8543)
			(xy 372.401374 -223.878403) (xy 372.35337 -223.895342) (xy 372.32844 -223.900492) (xy 372.305326 -223.90481)
			(xy 372.101872 -224.257616) (xy 372.109492 -224.279714) (xy 372.118233 -224.306301) (xy 372.127678 -224.361461)
			(xy 372.128288 -224.389442) (xy 372.40718 -224.389442) (xy 372.407689 -224.363475) (xy 372.415814 -224.31218)
			(xy 372.431862 -224.262787) (xy 372.45544 -224.216513) (xy 372.485966 -224.174497) (xy 372.522689 -224.137774)
			(xy 372.564705 -224.107248) (xy 372.610979 -224.08367) (xy 372.660372 -224.067622) (xy 372.711667 -224.059497)
			(xy 372.763601 -224.059497) (xy 372.814896 -224.067622) (xy 372.864289 -224.08367) (xy 372.910563 -224.107248)
			(xy 372.952579 -224.137774) (xy 372.989302 -224.174497) (xy 373.019828 -224.216513) (xy 373.043406 -224.262787)
			(xy 373.059454 -224.31218) (xy 373.067579 -224.363475) (xy 373.068088 -224.389442) (xy 373.34698 -224.389442)
			(xy 373.347387 -224.363988) (xy 373.355174 -224.31368) (xy 373.370587 -224.265161) (xy 373.39326 -224.219581)
			(xy 373.422656 -224.178019) (xy 373.45808 -224.141457) (xy 373.498693 -224.110763) (xy 373.543534 -224.086661)
			(xy 373.591542 -224.069724) (xy 373.616474 -224.064576) (xy 373.639334 -224.060258) (xy 373.843042 -223.707198)
			(xy 373.835422 -223.685354) (xy 373.826698 -223.658762) (xy 373.817241 -223.603606) (xy 373.816626 -223.575626)
			(xy 373.817135 -223.549659) (xy 373.82526 -223.498364) (xy 373.841308 -223.448971) (xy 373.864886 -223.402697)
			(xy 373.895412 -223.360681) (xy 373.932135 -223.323958) (xy 373.974151 -223.293432) (xy 374.020425 -223.269854)
			(xy 374.069818 -223.253806) (xy 374.121113 -223.245681) (xy 374.173047 -223.245681) (xy 374.224342 -223.253806)
			(xy 374.273735 -223.269854) (xy 374.320009 -223.293432) (xy 374.362025 -223.323958) (xy 374.398748 -223.360681)
			(xy 374.429274 -223.402697) (xy 374.452852 -223.448971) (xy 374.4689 -223.498364) (xy 374.477025 -223.549659)
			(xy 374.477534 -223.575626) (xy 374.477086 -223.601078) (xy 374.469304 -223.651385) (xy 374.453897 -223.699901)
			(xy 374.431229 -223.74548) (xy 374.401838 -223.787043) (xy 374.366419 -223.823605) (xy 374.32581 -223.8543)
			(xy 374.280974 -223.878403) (xy 374.23297 -223.895342) (xy 374.20804 -223.900492) (xy 374.184926 -223.90481)
			(xy 373.981472 -224.257616) (xy 373.989092 -224.279714) (xy 373.997833 -224.306301) (xy 374.007278 -224.361461)
			(xy 374.007888 -224.389442) (xy 374.007379 -224.415409) (xy 373.999254 -224.466704) (xy 373.983206 -224.516097)
			(xy 373.959628 -224.562371) (xy 373.929102 -224.604387) (xy 373.892379 -224.64111) (xy 373.850363 -224.671636)
			(xy 373.804089 -224.695214) (xy 373.754696 -224.711262) (xy 373.703401 -224.719387) (xy 373.651467 -224.719387)
			(xy 373.600172 -224.711262) (xy 373.550779 -224.695214) (xy 373.504505 -224.671636) (xy 373.462489 -224.64111)
			(xy 373.425766 -224.604387) (xy 373.39524 -224.562371) (xy 373.371662 -224.516097) (xy 373.355614 -224.466704)
			(xy 373.347489 -224.415409) (xy 373.34698 -224.389442) (xy 373.068088 -224.389442) (xy 373.067546 -224.417428)
			(xy 373.058089 -224.472596) (xy 373.049292 -224.49917) (xy 373.041672 -224.521268) (xy 373.24538 -224.874074)
			(xy 373.26824 -224.878392) (xy 373.293167 -224.883535) (xy 373.341153 -224.900502) (xy 373.385972 -224.924622)
			(xy 373.426566 -224.955325) (xy 373.461975 -224.991886) (xy 373.491362 -225.033442) (xy 373.514035 -225.07901)
			(xy 373.529456 -225.127515) (xy 373.537262 -225.17781) (xy 373.537734 -225.203258) (xy 373.537225 -225.229225)
			(xy 373.5291 -225.28052) (xy 373.513052 -225.329913) (xy 373.489474 -225.376187) (xy 373.458948 -225.418203)
			(xy 373.422225 -225.454926) (xy 373.380209 -225.485452) (xy 373.333935 -225.50903) (xy 373.284542 -225.525078)
			(xy 373.233247 -225.533203) (xy 373.181313 -225.533203) (xy 373.130018 -225.525078) (xy 373.080625 -225.50903)
			(xy 373.034351 -225.485452) (xy 372.992335 -225.454926) (xy 372.955612 -225.418203) (xy 372.925086 -225.376187)
			(xy 372.901508 -225.329913) (xy 372.88546 -225.28052) (xy 372.877335 -225.229225) (xy 372.876826 -225.203258)
			(xy 372.877367 -225.175272) (xy 372.886825 -225.120104) (xy 372.895622 -225.09353) (xy 372.903242 -225.071432)
			(xy 372.699534 -224.718626) (xy 372.676674 -224.714308) (xy 372.651749 -224.709155) (xy 372.603763 -224.69219)
			(xy 372.558944 -224.668072) (xy 372.51835 -224.63737) (xy 372.48294 -224.60081) (xy 372.453552 -224.559256)
			(xy 372.43088 -224.513688) (xy 372.415458 -224.465184) (xy 372.407652 -224.41489) (xy 372.40718 -224.389442)
			(xy 372.128288 -224.389442) (xy 372.127779 -224.415409) (xy 372.119654 -224.466704) (xy 372.103606 -224.516097)
			(xy 372.080028 -224.562371) (xy 372.049502 -224.604387) (xy 372.012779 -224.64111) (xy 371.970763 -224.671636)
			(xy 371.924489 -224.695214) (xy 371.875096 -224.711262) (xy 371.823801 -224.719387) (xy 371.771867 -224.719387)
			(xy 371.720572 -224.711262) (xy 371.671179 -224.695214) (xy 371.624905 -224.671636) (xy 371.582889 -224.64111)
			(xy 371.546166 -224.604387) (xy 371.51564 -224.562371) (xy 371.492062 -224.516097) (xy 371.476014 -224.466704)
			(xy 371.467889 -224.415409) (xy 371.46738 -224.389442) (xy 371.188488 -224.389442) (xy 371.187946 -224.417428)
			(xy 371.178489 -224.472596) (xy 371.169692 -224.49917) (xy 371.162072 -224.521268) (xy 371.36578 -224.874074)
			(xy 371.38864 -224.878392) (xy 371.413567 -224.883535) (xy 371.461553 -224.900502) (xy 371.506372 -224.924622)
			(xy 371.546966 -224.955325) (xy 371.582375 -224.991886) (xy 371.611762 -225.033442) (xy 371.634435 -225.07901)
			(xy 371.649856 -225.127515) (xy 371.657662 -225.17781) (xy 371.658134 -225.203258) (xy 371.657625 -225.229225)
			(xy 371.6495 -225.28052) (xy 371.633452 -225.329913) (xy 371.609874 -225.376187) (xy 371.579348 -225.418203)
			(xy 371.542625 -225.454926) (xy 371.500609 -225.485452) (xy 371.454335 -225.50903) (xy 371.404942 -225.525078)
			(xy 371.353647 -225.533203) (xy 371.301713 -225.533203) (xy 371.250418 -225.525078) (xy 371.201025 -225.50903)
			(xy 371.154751 -225.485452) (xy 371.112735 -225.454926) (xy 371.076012 -225.418203) (xy 371.045486 -225.376187)
			(xy 371.021908 -225.329913) (xy 371.00586 -225.28052) (xy 370.997735 -225.229225) (xy 370.997226 -225.203258)
			(xy 370.997767 -225.175272) (xy 371.007225 -225.120104) (xy 371.016022 -225.09353) (xy 371.023642 -225.071432)
			(xy 370.819934 -224.718626) (xy 370.797074 -224.714308) (xy 370.772149 -224.709155) (xy 370.724163 -224.69219)
			(xy 370.679344 -224.668072) (xy 370.63875 -224.63737) (xy 370.60334 -224.60081) (xy 370.573952 -224.559256)
			(xy 370.55128 -224.513688) (xy 370.535858 -224.465184) (xy 370.528052 -224.41489) (xy 370.52758 -224.389442)
			(xy 370.248688 -224.389442) (xy 370.248179 -224.415409) (xy 370.240054 -224.466704) (xy 370.224006 -224.516097)
			(xy 370.200428 -224.562371) (xy 370.169902 -224.604387) (xy 370.133179 -224.64111) (xy 370.091163 -224.671636)
			(xy 370.044889 -224.695214) (xy 369.995496 -224.711262) (xy 369.944201 -224.719387) (xy 369.892267 -224.719387)
			(xy 369.840972 -224.711262) (xy 369.791579 -224.695214) (xy 369.745305 -224.671636) (xy 369.703289 -224.64111)
			(xy 369.666566 -224.604387) (xy 369.63604 -224.562371) (xy 369.612462 -224.516097) (xy 369.596414 -224.466704)
			(xy 369.588289 -224.415409) (xy 369.58778 -224.389442) (xy 369.308888 -224.389442) (xy 369.308346 -224.417428)
			(xy 369.298889 -224.472596) (xy 369.290092 -224.49917) (xy 369.282472 -224.521268) (xy 369.48618 -224.874074)
			(xy 369.50904 -224.878392) (xy 369.533967 -224.883535) (xy 369.581953 -224.900502) (xy 369.626772 -224.924622)
			(xy 369.667366 -224.955325) (xy 369.702775 -224.991886) (xy 369.732162 -225.033442) (xy 369.754835 -225.07901)
			(xy 369.770256 -225.127515) (xy 369.778062 -225.17781) (xy 369.778534 -225.203258) (xy 369.778025 -225.229225)
			(xy 369.7699 -225.28052) (xy 369.753852 -225.329913) (xy 369.730274 -225.376187) (xy 369.699748 -225.418203)
			(xy 369.663025 -225.454926) (xy 369.621009 -225.485452) (xy 369.574735 -225.50903) (xy 369.525342 -225.525078)
			(xy 369.474047 -225.533203) (xy 369.422113 -225.533203) (xy 369.370818 -225.525078) (xy 369.321425 -225.50903)
			(xy 369.275151 -225.485452) (xy 369.233135 -225.454926) (xy 369.196412 -225.418203) (xy 369.165886 -225.376187)
			(xy 369.142308 -225.329913) (xy 369.12626 -225.28052) (xy 369.118135 -225.229225) (xy 369.117626 -225.203258)
			(xy 369.118167 -225.175272) (xy 369.127625 -225.120104) (xy 369.136422 -225.09353) (xy 369.144042 -225.071432)
			(xy 368.940334 -224.718626) (xy 368.917474 -224.714308) (xy 368.892549 -224.709155) (xy 368.844563 -224.69219)
			(xy 368.799744 -224.668072) (xy 368.75915 -224.63737) (xy 368.72374 -224.60081) (xy 368.694352 -224.559256)
			(xy 368.67168 -224.513688) (xy 368.656258 -224.465184) (xy 368.648452 -224.41489) (xy 368.64798 -224.389442)
			(xy 368.369088 -224.389442) (xy 368.368505 -224.4174) (xy 368.359094 -224.472519) (xy 368.34053 -224.525264)
			(xy 368.327432 -224.54997) (xy 368.313462 -224.575116) (xy 368.399314 -224.723706) (xy 368.419757 -224.760095)
			(xy 368.454987 -224.835767) (xy 368.469672 -224.874836) (xy 368.479288 -224.873768) (xy 368.498605 -224.872625)
			(xy 368.50828 -224.87255) (xy 368.534274 -224.873032) (xy 368.585621 -224.881162) (xy 368.635065 -224.897224)
			(xy 368.681386 -224.920824) (xy 368.723446 -224.951379) (xy 368.760208 -224.988139) (xy 368.790766 -225.030197)
			(xy 368.814368 -225.076517) (xy 368.830434 -225.125959) (xy 368.838567 -225.177306) (xy 368.838567 -225.229294)
			(xy 368.830434 -225.280641) (xy 368.814368 -225.330083) (xy 368.790766 -225.376403) (xy 368.760208 -225.418461)
			(xy 368.723446 -225.455221) (xy 368.681386 -225.485776) (xy 368.635065 -225.509376) (xy 368.585621 -225.525438)
			(xy 368.534274 -225.533568) (xy 368.50828 -225.533966) (xy 368.498605 -225.533887) (xy 368.479289 -225.532743)
			(xy 368.469672 -225.53168) (xy 368.454965 -225.57079) (xy 368.419678 -225.646535) (xy 368.377931 -225.718922)
			(xy 368.330043 -225.787401) (xy 368.303556 -225.819716) (xy 368.318964 -225.841269) (xy 368.343441 -225.888253)
			(xy 368.360114 -225.938538) (xy 368.368556 -225.990839) (xy 368.369088 -226.017328) (xy 368.368577 -226.043295)
			(xy 368.648489 -226.043295) (xy 368.648489 -225.991361) (xy 368.656614 -225.940066) (xy 368.672662 -225.890673)
			(xy 368.69624 -225.844399) (xy 368.726766 -225.802383) (xy 368.763489 -225.76566) (xy 368.805505 -225.735134)
			(xy 368.851779 -225.711556) (xy 368.901172 -225.695508) (xy 368.952467 -225.687383) (xy 369.004401 -225.687383)
			(xy 369.055696 -225.695508) (xy 369.105089 -225.711556) (xy 369.151363 -225.735134) (xy 369.193379 -225.76566)
			(xy 369.230102 -225.802383) (xy 369.260628 -225.844399) (xy 369.284206 -225.890673) (xy 369.300254 -225.940066)
			(xy 369.308379 -225.991361) (xy 369.308888 -226.017328) (xy 369.308379 -226.043295) (xy 369.588289 -226.043295)
			(xy 369.588289 -225.991361) (xy 369.596414 -225.940066) (xy 369.612462 -225.890673) (xy 369.63604 -225.844399)
			(xy 369.666566 -225.802383) (xy 369.703289 -225.76566) (xy 369.745305 -225.735134) (xy 369.791579 -225.711556)
			(xy 369.840972 -225.695508) (xy 369.892267 -225.687383) (xy 369.944201 -225.687383) (xy 369.995496 -225.695508)
			(xy 370.044889 -225.711556) (xy 370.091163 -225.735134) (xy 370.133179 -225.76566) (xy 370.169902 -225.802383)
			(xy 370.200428 -225.844399) (xy 370.224006 -225.890673) (xy 370.240054 -225.940066) (xy 370.248179 -225.991361)
			(xy 370.248688 -226.017328) (xy 370.248179 -226.043295) (xy 370.528089 -226.043295) (xy 370.528089 -225.991361)
			(xy 370.536214 -225.940066) (xy 370.552262 -225.890673) (xy 370.57584 -225.844399) (xy 370.606366 -225.802383)
			(xy 370.643089 -225.76566) (xy 370.685105 -225.735134) (xy 370.731379 -225.711556) (xy 370.780772 -225.695508)
			(xy 370.832067 -225.687383) (xy 370.884001 -225.687383) (xy 370.935296 -225.695508) (xy 370.984689 -225.711556)
			(xy 371.030963 -225.735134) (xy 371.072979 -225.76566) (xy 371.109702 -225.802383) (xy 371.140228 -225.844399)
			(xy 371.163806 -225.890673) (xy 371.179854 -225.940066) (xy 371.187979 -225.991361) (xy 371.188488 -226.017328)
			(xy 371.187979 -226.043295) (xy 371.467889 -226.043295) (xy 371.467889 -225.991361) (xy 371.476014 -225.940066)
			(xy 371.492062 -225.890673) (xy 371.51564 -225.844399) (xy 371.546166 -225.802383) (xy 371.582889 -225.76566)
			(xy 371.624905 -225.735134) (xy 371.671179 -225.711556) (xy 371.720572 -225.695508) (xy 371.771867 -225.687383)
			(xy 371.823801 -225.687383) (xy 371.875096 -225.695508) (xy 371.924489 -225.711556) (xy 371.970763 -225.735134)
			(xy 372.012779 -225.76566) (xy 372.049502 -225.802383) (xy 372.080028 -225.844399) (xy 372.103606 -225.890673)
			(xy 372.119654 -225.940066) (xy 372.127779 -225.991361) (xy 372.128288 -226.017328) (xy 372.127779 -226.043295)
			(xy 372.407689 -226.043295) (xy 372.407689 -225.991361) (xy 372.415814 -225.940066) (xy 372.431862 -225.890673)
			(xy 372.45544 -225.844399) (xy 372.485966 -225.802383) (xy 372.522689 -225.76566) (xy 372.564705 -225.735134)
			(xy 372.610979 -225.711556) (xy 372.660372 -225.695508) (xy 372.711667 -225.687383) (xy 372.763601 -225.687383)
			(xy 372.814896 -225.695508) (xy 372.864289 -225.711556) (xy 372.910563 -225.735134) (xy 372.952579 -225.76566)
			(xy 372.989302 -225.802383) (xy 373.019828 -225.844399) (xy 373.043406 -225.890673) (xy 373.059454 -225.940066)
			(xy 373.067579 -225.991361) (xy 373.068088 -226.017328) (xy 373.067579 -226.043295) (xy 373.347489 -226.043295)
			(xy 373.347489 -225.991361) (xy 373.355614 -225.940066) (xy 373.371662 -225.890673) (xy 373.39524 -225.844399)
			(xy 373.425766 -225.802383) (xy 373.462489 -225.76566) (xy 373.504505 -225.735134) (xy 373.550779 -225.711556)
			(xy 373.600172 -225.695508) (xy 373.651467 -225.687383) (xy 373.703401 -225.687383) (xy 373.754696 -225.695508)
			(xy 373.804089 -225.711556) (xy 373.850363 -225.735134) (xy 373.892379 -225.76566) (xy 373.929102 -225.802383)
			(xy 373.959628 -225.844399) (xy 373.983206 -225.890673) (xy 373.999254 -225.940066) (xy 374.007379 -225.991361)
			(xy 374.007888 -226.017328) (xy 374.007379 -226.043295) (xy 373.999254 -226.09459) (xy 373.983206 -226.143983)
			(xy 373.959628 -226.190257) (xy 373.929102 -226.232273) (xy 373.892379 -226.268996) (xy 373.850363 -226.299522)
			(xy 373.804089 -226.3231) (xy 373.754696 -226.339148) (xy 373.703401 -226.347273) (xy 373.651467 -226.347273)
			(xy 373.600172 -226.339148) (xy 373.550779 -226.3231) (xy 373.504505 -226.299522) (xy 373.462489 -226.268996)
			(xy 373.425766 -226.232273) (xy 373.39524 -226.190257) (xy 373.371662 -226.143983) (xy 373.355614 -226.09459)
			(xy 373.347489 -226.043295) (xy 373.067579 -226.043295) (xy 373.059454 -226.09459) (xy 373.043406 -226.143983)
			(xy 373.019828 -226.190257) (xy 372.989302 -226.232273) (xy 372.952579 -226.268996) (xy 372.910563 -226.299522)
			(xy 372.864289 -226.3231) (xy 372.814896 -226.339148) (xy 372.763601 -226.347273) (xy 372.711667 -226.347273)
			(xy 372.660372 -226.339148) (xy 372.610979 -226.3231) (xy 372.564705 -226.299522) (xy 372.522689 -226.268996)
			(xy 372.485966 -226.232273) (xy 372.45544 -226.190257) (xy 372.431862 -226.143983) (xy 372.415814 -226.09459)
			(xy 372.407689 -226.043295) (xy 372.127779 -226.043295) (xy 372.119654 -226.09459) (xy 372.103606 -226.143983)
			(xy 372.080028 -226.190257) (xy 372.049502 -226.232273) (xy 372.012779 -226.268996) (xy 371.970763 -226.299522)
			(xy 371.924489 -226.3231) (xy 371.875096 -226.339148) (xy 371.823801 -226.347273) (xy 371.771867 -226.347273)
			(xy 371.720572 -226.339148) (xy 371.671179 -226.3231) (xy 371.624905 -226.299522) (xy 371.582889 -226.268996)
			(xy 371.546166 -226.232273) (xy 371.51564 -226.190257) (xy 371.492062 -226.143983) (xy 371.476014 -226.09459)
			(xy 371.467889 -226.043295) (xy 371.187979 -226.043295) (xy 371.179854 -226.09459) (xy 371.163806 -226.143983)
			(xy 371.140228 -226.190257) (xy 371.109702 -226.232273) (xy 371.072979 -226.268996) (xy 371.030963 -226.299522)
			(xy 370.984689 -226.3231) (xy 370.935296 -226.339148) (xy 370.884001 -226.347273) (xy 370.832067 -226.347273)
			(xy 370.780772 -226.339148) (xy 370.731379 -226.3231) (xy 370.685105 -226.299522) (xy 370.643089 -226.268996)
			(xy 370.606366 -226.232273) (xy 370.57584 -226.190257) (xy 370.552262 -226.143983) (xy 370.536214 -226.09459)
			(xy 370.528089 -226.043295) (xy 370.248179 -226.043295) (xy 370.240054 -226.09459) (xy 370.224006 -226.143983)
			(xy 370.200428 -226.190257) (xy 370.169902 -226.232273) (xy 370.133179 -226.268996) (xy 370.091163 -226.299522)
			(xy 370.044889 -226.3231) (xy 369.995496 -226.339148) (xy 369.944201 -226.347273) (xy 369.892267 -226.347273)
			(xy 369.840972 -226.339148) (xy 369.791579 -226.3231) (xy 369.745305 -226.299522) (xy 369.703289 -226.268996)
			(xy 369.666566 -226.232273) (xy 369.63604 -226.190257) (xy 369.612462 -226.143983) (xy 369.596414 -226.09459)
			(xy 369.588289 -226.043295) (xy 369.308379 -226.043295) (xy 369.300254 -226.09459) (xy 369.284206 -226.143983)
			(xy 369.260628 -226.190257) (xy 369.230102 -226.232273) (xy 369.193379 -226.268996) (xy 369.151363 -226.299522)
			(xy 369.105089 -226.3231) (xy 369.055696 -226.339148) (xy 369.004401 -226.347273) (xy 368.952467 -226.347273)
			(xy 368.901172 -226.339148) (xy 368.851779 -226.3231) (xy 368.805505 -226.299522) (xy 368.763489 -226.268996)
			(xy 368.726766 -226.232273) (xy 368.69624 -226.190257) (xy 368.672662 -226.143983) (xy 368.656614 -226.09459)
			(xy 368.648489 -226.043295) (xy 368.368577 -226.043295) (xy 368.360449 -226.094588) (xy 368.344398 -226.143979)
			(xy 368.32082 -226.190252) (xy 368.290294 -226.232267) (xy 368.253571 -226.26899) (xy 368.211557 -226.299517)
			(xy 368.165285 -226.323096) (xy 368.115894 -226.339148) (xy 368.064601 -226.347276) (xy 368.038634 -226.347782)
			(xy 368.011127 -226.347237) (xy 367.956872 -226.33813) (xy 367.904875 -226.320162) (xy 367.856572 -226.29383)
			(xy 367.813299 -226.25986) (xy 367.77625 -226.219191) (xy 367.746449 -226.172948) (xy 367.735104 -226.147884)
			(xy 367.693788 -226.154741) (xy 367.610358 -226.162119) (xy 367.56848 -226.162616) (xy 367.526729 -226.162112)
			(xy 367.443551 -226.15474) (xy 367.402364 -226.147884) (xy 367.390995 -226.172938) (xy 367.361194 -226.219182)
			(xy 367.324148 -226.259854) (xy 367.28088 -226.293832) (xy 367.232584 -226.320177) (xy 367.180593 -226.338163)
			(xy 367.126341 -226.347293) (xy 367.098834 -226.347782) (xy 367.072862 -226.347302) (xy 367.021557 -226.339181)
			(xy 366.972154 -226.323135) (xy 366.92587 -226.299557) (xy 366.883844 -226.26903) (xy 366.847111 -226.232303)
			(xy 366.816575 -226.190283) (xy 366.792989 -226.144003) (xy 366.776933 -226.094603) (xy 366.768803 -226.0433)
			(xy 366.76838 -226.017328) (xy 366.768449 -226.005925) (xy 366.769975 -225.983172) (xy 366.771428 -225.971862)
			(xy 366.772979 -225.95728) (xy 366.768615 -225.928294) (xy 366.756178 -225.901751) (xy 366.736698 -225.879848)
			(xy 366.711788 -225.864397) (xy 366.697768 -225.860102) (xy 366.676848 -225.854271) (xy 366.635313 -225.841569)
			(xy 366.61471 -225.834702) (xy 366.60009 -225.830414) (xy 366.569648 -225.8297) (xy 366.540346 -225.837986)
			(xy 366.514786 -225.854537) (xy 366.495236 -225.877883) (xy 366.483431 -225.905952) (xy 366.480419 -225.936253)
			(xy 366.482884 -225.951288) (xy 366.485973 -225.967495) (xy 366.489279 -226.000323) (xy 366.489488 -226.01682)
			(xy 366.489488 -226.017328) (xy 366.488977 -226.043295) (xy 366.480849 -226.094588) (xy 366.464798 -226.143979)
			(xy 366.44122 -226.190252) (xy 366.410694 -226.232267) (xy 366.373971 -226.26899) (xy 366.331957 -226.299517)
			(xy 366.285685 -226.323096) (xy 366.236294 -226.339148) (xy 366.185001 -226.347276) (xy 366.159034 -226.347782)
			(xy 366.131527 -226.347237) (xy 366.077272 -226.33813) (xy 366.025275 -226.320162) (xy 365.976972 -226.29383)
			(xy 365.933699 -226.25986) (xy 365.89665 -226.219191) (xy 365.866849 -226.172948) (xy 365.855504 -226.147884)
			(xy 365.814188 -226.154741) (xy 365.730758 -226.162119) (xy 365.68888 -226.162616) (xy 365.647129 -226.162112)
			(xy 365.563951 -226.15474) (xy 365.522764 -226.147884) (xy 365.511395 -226.172938) (xy 365.481594 -226.219182)
			(xy 365.444548 -226.259854) (xy 365.40128 -226.293832) (xy 365.352984 -226.320177) (xy 365.300993 -226.338163)
			(xy 365.246741 -226.347293) (xy 365.219234 -226.347782) (xy 365.193262 -226.347302) (xy 365.141957 -226.339181)
			(xy 365.092554 -226.323135) (xy 365.04627 -226.299557) (xy 365.004244 -226.26903) (xy 364.967511 -226.232303)
			(xy 364.936975 -226.190283) (xy 364.913389 -226.144003) (xy 364.897333 -226.094603) (xy 364.889203 -226.0433)
			(xy 364.88878 -226.017328) (xy 364.88878 -226.017074) (xy 364.889294 -225.990656) (xy 364.897701 -225.938495)
			(xy 364.91431 -225.888339) (xy 364.938698 -225.841469) (xy 364.954058 -225.81997) (xy 364.925369 -225.784943)
			(xy 364.873976 -225.710396) (xy 364.851442 -225.671126) (xy 364.646718 -225.671126) (xy 364.62424 -225.710326)
			(xy 364.572974 -225.784746) (xy 364.544356 -225.819716) (xy 364.559764 -225.841269) (xy 364.584241 -225.888253)
			(xy 364.600914 -225.938538) (xy 364.609356 -225.990839) (xy 364.609888 -226.017328) (xy 364.609377 -226.043295)
			(xy 364.601249 -226.094588) (xy 364.585198 -226.143979) (xy 364.56162 -226.190252) (xy 364.531094 -226.232267)
			(xy 364.494371 -226.26899) (xy 364.452357 -226.299517) (xy 364.406085 -226.323096) (xy 364.356694 -226.339148)
			(xy 364.305401 -226.347276) (xy 364.279434 -226.347782) (xy 364.251927 -226.347237) (xy 364.197672 -226.33813)
			(xy 364.145675 -226.320162) (xy 364.097372 -226.29383) (xy 364.054099 -226.25986) (xy 364.01705 -226.219191)
			(xy 363.987249 -226.172948) (xy 363.975904 -226.147884) (xy 363.934588 -226.154741) (xy 363.851158 -226.162119)
			(xy 363.80928 -226.162616) (xy 363.767529 -226.162112) (xy 363.684351 -226.15474) (xy 363.643164 -226.147884)
			(xy 363.631795 -226.172938) (xy 363.601994 -226.219182) (xy 363.564948 -226.259854) (xy 363.52168 -226.293832)
			(xy 363.473384 -226.320177) (xy 363.421393 -226.338163) (xy 363.367141 -226.347293) (xy 363.339634 -226.347782)
			(xy 363.313662 -226.347302) (xy 363.262357 -226.339181) (xy 363.212954 -226.323135) (xy 363.16667 -226.299557)
			(xy 363.124644 -226.26903) (xy 363.087911 -226.232303) (xy 363.057375 -226.190283) (xy 363.033789 -226.144003)
			(xy 363.017733 -226.094603) (xy 363.009603 -226.0433) (xy 363.00918 -226.017328) (xy 363.00918 -226.017074)
			(xy 363.009694 -225.990656) (xy 363.018101 -225.938495) (xy 363.03471 -225.888339) (xy 363.059098 -225.841469)
			(xy 363.074458 -225.81997) (xy 363.045769 -225.784943) (xy 362.994376 -225.710396) (xy 362.971842 -225.671126)
			(xy 362.767118 -225.671126) (xy 362.74464 -225.710326) (xy 362.693374 -225.784746) (xy 362.664756 -225.819716)
			(xy 362.680164 -225.841269) (xy 362.704641 -225.888253) (xy 362.721314 -225.938538) (xy 362.729756 -225.990839)
			(xy 362.730288 -226.017328) (xy 362.729777 -226.043295) (xy 362.721649 -226.094588) (xy 362.705598 -226.143979)
			(xy 362.68202 -226.190252) (xy 362.651494 -226.232267) (xy 362.614771 -226.26899) (xy 362.572757 -226.299517)
			(xy 362.526485 -226.323096) (xy 362.477094 -226.339148) (xy 362.425801 -226.347276) (xy 362.399834 -226.347782)
			(xy 362.372327 -226.347237) (xy 362.318072 -226.33813) (xy 362.266075 -226.320162) (xy 362.217772 -226.29383)
			(xy 362.174499 -226.25986) (xy 362.13745 -226.219191) (xy 362.107649 -226.172948) (xy 362.096304 -226.147884)
			(xy 362.054988 -226.154741) (xy 361.971558 -226.162119) (xy 361.92968 -226.162616) (xy 361.887929 -226.162112)
			(xy 361.804751 -226.15474) (xy 361.763564 -226.147884) (xy 361.752195 -226.172938) (xy 361.722394 -226.219182)
			(xy 361.685348 -226.259854) (xy 361.64208 -226.293832) (xy 361.593784 -226.320177) (xy 361.541793 -226.338163)
			(xy 361.487541 -226.347293) (xy 361.460034 -226.347782) (xy 361.434062 -226.347302) (xy 361.382757 -226.339181)
			(xy 361.333354 -226.323135) (xy 361.28707 -226.299557) (xy 361.245044 -226.26903) (xy 361.208311 -226.232303)
			(xy 361.177775 -226.190283) (xy 361.154189 -226.144003) (xy 361.138133 -226.094603) (xy 361.130003 -226.0433)
			(xy 361.12958 -226.017328) (xy 361.12958 -226.017074) (xy 361.130094 -225.990656) (xy 361.138501 -225.938495)
			(xy 361.15511 -225.888339) (xy 361.179498 -225.841469) (xy 361.194858 -225.81997) (xy 361.166169 -225.784943)
			(xy 361.114776 -225.710396) (xy 361.092242 -225.671126) (xy 360.887518 -225.671126) (xy 360.86504 -225.710326)
			(xy 360.813774 -225.784746) (xy 360.785156 -225.819716) (xy 360.800564 -225.841269) (xy 360.825041 -225.888253)
			(xy 360.841714 -225.938538) (xy 360.850156 -225.990839) (xy 360.850688 -226.017328) (xy 360.850177 -226.043295)
			(xy 360.842049 -226.094588) (xy 360.825998 -226.143979) (xy 360.80242 -226.190252) (xy 360.771894 -226.232267)
			(xy 360.735171 -226.26899) (xy 360.693157 -226.299517) (xy 360.646885 -226.323096) (xy 360.597494 -226.339148)
			(xy 360.546201 -226.347276) (xy 360.520234 -226.347782) (xy 360.492727 -226.347237) (xy 360.438472 -226.33813)
			(xy 360.386475 -226.320162) (xy 360.338172 -226.29383) (xy 360.294899 -226.25986) (xy 360.25785 -226.219191)
			(xy 360.228049 -226.172948) (xy 360.216704 -226.147884) (xy 360.175388 -226.154741) (xy 360.091958 -226.162119)
			(xy 360.05008 -226.162616) (xy 360.008329 -226.162112) (xy 359.925151 -226.15474) (xy 359.883964 -226.147884)
			(xy 359.872595 -226.172938) (xy 359.842794 -226.219182) (xy 359.805748 -226.259854) (xy 359.76248 -226.293832)
			(xy 359.714184 -226.320177) (xy 359.662193 -226.338163) (xy 359.607941 -226.347293) (xy 359.580434 -226.347782)
			(xy 359.554462 -226.347302) (xy 359.503157 -226.339181) (xy 359.453754 -226.323135) (xy 359.40747 -226.299557)
			(xy 359.365444 -226.26903) (xy 359.328711 -226.232303) (xy 359.298175 -226.190283) (xy 359.274589 -226.144003)
			(xy 359.258533 -226.094603) (xy 359.250403 -226.0433) (xy 359.24998 -226.017328) (xy 359.24998 -226.017074)
			(xy 359.250494 -225.990656) (xy 359.258901 -225.938495) (xy 359.27551 -225.888339) (xy 359.299898 -225.841469)
			(xy 359.315258 -225.81997) (xy 359.286569 -225.784943) (xy 359.235176 -225.710396) (xy 359.212642 -225.671126)
			(xy 359.007918 -225.671126) (xy 358.98544 -225.710326) (xy 358.934174 -225.784746) (xy 358.905556 -225.819716)
			(xy 358.920964 -225.841269) (xy 358.945441 -225.888253) (xy 358.962114 -225.938538) (xy 358.970556 -225.990839)
			(xy 358.971088 -226.017328) (xy 358.970577 -226.043295) (xy 358.962449 -226.094588) (xy 358.946398 -226.143979)
			(xy 358.92282 -226.190252) (xy 358.892294 -226.232267) (xy 358.855571 -226.26899) (xy 358.813557 -226.299517)
			(xy 358.767285 -226.323096) (xy 358.717894 -226.339148) (xy 358.666601 -226.347276) (xy 358.640634 -226.347782)
			(xy 358.613127 -226.347237) (xy 358.558872 -226.33813) (xy 358.506875 -226.320162) (xy 358.458572 -226.29383)
			(xy 358.415299 -226.25986) (xy 358.37825 -226.219191) (xy 358.348449 -226.172948) (xy 358.337104 -226.147884)
			(xy 358.295788 -226.154741) (xy 358.212358 -226.162119) (xy 358.17048 -226.162616) (xy 358.128729 -226.162112)
			(xy 358.045551 -226.15474) (xy 358.004364 -226.147884) (xy 357.992995 -226.172938) (xy 357.963194 -226.219182)
			(xy 357.926148 -226.259854) (xy 357.88288 -226.293832) (xy 357.834584 -226.320177) (xy 357.782593 -226.338163)
			(xy 357.728341 -226.347293) (xy 357.700834 -226.347782) (xy 357.674862 -226.347302) (xy 357.623557 -226.339181)
			(xy 357.574154 -226.323135) (xy 357.52787 -226.299557) (xy 357.485844 -226.26903) (xy 357.449111 -226.232303)
			(xy 357.418575 -226.190283) (xy 357.394989 -226.144003) (xy 357.378933 -226.094603) (xy 357.370803 -226.0433)
			(xy 357.37038 -226.017328) (xy 357.37038 -226.017074) (xy 357.370894 -225.990656) (xy 357.379301 -225.938495)
			(xy 357.39591 -225.888339) (xy 357.420298 -225.841469) (xy 357.435658 -225.81997) (xy 357.406969 -225.784943)
			(xy 357.355576 -225.710396) (xy 357.333042 -225.671126) (xy 357.128318 -225.671126) (xy 357.10584 -225.710326)
			(xy 357.054574 -225.784746) (xy 357.025956 -225.819716) (xy 357.041364 -225.841269) (xy 357.065841 -225.888253)
			(xy 357.082514 -225.938538) (xy 357.090956 -225.990839) (xy 357.091488 -226.017328) (xy 357.090977 -226.043295)
			(xy 357.082849 -226.094588) (xy 357.066798 -226.143979) (xy 357.04322 -226.190252) (xy 357.012694 -226.232267)
			(xy 356.975971 -226.26899) (xy 356.933957 -226.299517) (xy 356.887685 -226.323096) (xy 356.838294 -226.339148)
			(xy 356.787001 -226.347276) (xy 356.761034 -226.347782) (xy 356.733527 -226.347237) (xy 356.679272 -226.33813)
			(xy 356.627275 -226.320162) (xy 356.578972 -226.29383) (xy 356.535699 -226.25986) (xy 356.49865 -226.219191)
			(xy 356.468849 -226.172948) (xy 356.457504 -226.147884) (xy 356.416188 -226.154741) (xy 356.332758 -226.162119)
			(xy 356.29088 -226.162616) (xy 356.249129 -226.162112) (xy 356.165951 -226.15474) (xy 356.124764 -226.147884)
			(xy 356.113395 -226.172938) (xy 356.083594 -226.219182) (xy 356.046548 -226.259854) (xy 356.00328 -226.293832)
			(xy 355.954984 -226.320177) (xy 355.902993 -226.338163) (xy 355.848741 -226.347293) (xy 355.821234 -226.347782)
			(xy 355.795262 -226.347302) (xy 355.743957 -226.339181) (xy 355.694554 -226.323135) (xy 355.64827 -226.299557)
			(xy 355.606244 -226.26903) (xy 355.569511 -226.232303) (xy 355.538975 -226.190283) (xy 355.515389 -226.144003)
			(xy 355.499333 -226.094603) (xy 355.491203 -226.0433) (xy 355.49078 -226.017328) (xy 355.49078 -226.017074)
			(xy 355.491294 -225.990656) (xy 355.499701 -225.938495) (xy 355.51631 -225.888339) (xy 355.540698 -225.841469)
			(xy 355.556058 -225.81997) (xy 355.527369 -225.784943) (xy 355.475976 -225.710396) (xy 355.453442 -225.671126)
			(xy 355.248718 -225.671126) (xy 355.22624 -225.710326) (xy 355.174974 -225.784746) (xy 355.146356 -225.819716)
			(xy 355.161764 -225.841269) (xy 355.186241 -225.888253) (xy 355.202914 -225.938538) (xy 355.211356 -225.990839)
			(xy 355.211888 -226.017328) (xy 355.211377 -226.043295) (xy 355.203249 -226.094588) (xy 355.187198 -226.143979)
			(xy 355.16362 -226.190252) (xy 355.133094 -226.232267) (xy 355.096371 -226.26899) (xy 355.054357 -226.299517)
			(xy 355.008085 -226.323096) (xy 354.958694 -226.339148) (xy 354.907401 -226.347276) (xy 354.881434 -226.347782)
			(xy 354.853927 -226.347237) (xy 354.799672 -226.33813) (xy 354.747675 -226.320162) (xy 354.699372 -226.29383)
			(xy 354.656099 -226.25986) (xy 354.61905 -226.219191) (xy 354.589249 -226.172948) (xy 354.577904 -226.147884)
			(xy 354.536588 -226.154741) (xy 354.453158 -226.162119) (xy 354.41128 -226.162616) (xy 354.369529 -226.162112)
			(xy 354.286351 -226.15474) (xy 354.245164 -226.147884) (xy 354.233795 -226.172938) (xy 354.203994 -226.219182)
			(xy 354.166948 -226.259854) (xy 354.12368 -226.293832) (xy 354.075384 -226.320177) (xy 354.023393 -226.338163)
			(xy 353.969141 -226.347293) (xy 353.941634 -226.347782) (xy 353.915662 -226.347302) (xy 353.864357 -226.339181)
			(xy 353.814954 -226.323135) (xy 353.76867 -226.299557) (xy 353.726644 -226.26903) (xy 353.689911 -226.232303)
			(xy 353.659375 -226.190283) (xy 353.635789 -226.144003) (xy 353.619733 -226.094603) (xy 353.611603 -226.0433)
			(xy 353.61118 -226.017328) (xy 353.61118 -226.017074) (xy 353.611694 -225.990656) (xy 353.620101 -225.938495)
			(xy 353.63671 -225.888339) (xy 353.661098 -225.841469) (xy 353.676458 -225.81997) (xy 353.647769 -225.784943)
			(xy 353.596376 -225.710396) (xy 353.573842 -225.671126) (xy 353.357942 -225.671126) (xy 353.34413 -225.671582)
			(xy 353.317515 -225.678979) (xy 353.293859 -225.693244) (xy 353.274896 -225.71333) (xy 353.262014 -225.737766)
			(xy 353.256158 -225.764762) (xy 353.257756 -225.792339) (xy 353.266692 -225.818478) (xy 353.274122 -225.83013)
			(xy 353.28786 -225.850892) (xy 353.309602 -225.895675) (xy 353.324371 -225.943216) (xy 353.33183 -225.992437)
			(xy 353.332288 -226.017328) (xy 353.331779 -226.043295) (xy 353.323654 -226.09459) (xy 353.307606 -226.143983)
			(xy 353.284028 -226.190257) (xy 353.253502 -226.232273) (xy 353.216779 -226.268996) (xy 353.174763 -226.299522)
			(xy 353.128489 -226.3231) (xy 353.079096 -226.339148) (xy 353.027801 -226.347273) (xy 352.975867 -226.347273)
			(xy 352.924572 -226.339148) (xy 352.875179 -226.3231) (xy 352.828905 -226.299522) (xy 352.786889 -226.268996)
			(xy 352.750166 -226.232273) (xy 352.71964 -226.190257) (xy 352.696062 -226.143983) (xy 352.680014 -226.09459)
			(xy 352.671889 -226.043295) (xy 352.67138 -226.017328) (xy 352.671837 -225.992438) (xy 352.679315 -225.943223)
			(xy 352.694091 -225.895687) (xy 352.715831 -225.850906) (xy 352.729546 -225.83013) (xy 352.736971 -225.818474)
			(xy 352.745901 -225.792332) (xy 352.747496 -225.764752) (xy 352.74164 -225.737755) (xy 352.728761 -225.713316)
			(xy 352.709802 -225.693223) (xy 352.686151 -225.678948) (xy 352.659539 -225.671536) (xy 352.645726 -225.671126)
			(xy 352.418142 -225.671126) (xy 352.40433 -225.671582) (xy 352.377715 -225.678979) (xy 352.354059 -225.693244)
			(xy 352.335096 -225.71333) (xy 352.322214 -225.737766) (xy 352.316358 -225.764762) (xy 352.317956 -225.792339)
			(xy 352.326892 -225.818478) (xy 352.334322 -225.83013) (xy 352.34806 -225.850892) (xy 352.369802 -225.895675)
			(xy 352.384571 -225.943216) (xy 352.39203 -225.992437) (xy 352.392488 -226.017328) (xy 352.391979 -226.043295)
			(xy 352.383854 -226.09459) (xy 352.367806 -226.143983) (xy 352.344228 -226.190257) (xy 352.313702 -226.232273)
			(xy 352.276979 -226.268996) (xy 352.234963 -226.299522) (xy 352.188689 -226.3231) (xy 352.139296 -226.339148)
			(xy 352.088001 -226.347273) (xy 352.036067 -226.347273) (xy 351.984772 -226.339148) (xy 351.935379 -226.3231)
			(xy 351.889105 -226.299522) (xy 351.847089 -226.268996) (xy 351.810366 -226.232273) (xy 351.77984 -226.190257)
			(xy 351.756262 -226.143983) (xy 351.740214 -226.09459) (xy 351.732089 -226.043295) (xy 351.73158 -226.017328)
			(xy 351.732037 -225.992438) (xy 351.739515 -225.943223) (xy 351.754291 -225.895687) (xy 351.776031 -225.850906)
			(xy 351.789746 -225.83013) (xy 351.797171 -225.818474) (xy 351.806101 -225.792332) (xy 351.807696 -225.764752)
			(xy 351.80184 -225.737755) (xy 351.788961 -225.713316) (xy 351.770002 -225.693223) (xy 351.746351 -225.678948)
			(xy 351.719739 -225.671536) (xy 351.705926 -225.671126) (xy 351.478342 -225.671126) (xy 351.46453 -225.671582)
			(xy 351.437915 -225.678979) (xy 351.414259 -225.693244) (xy 351.395296 -225.71333) (xy 351.382414 -225.737766)
			(xy 351.376558 -225.764762) (xy 351.378156 -225.792339) (xy 351.387092 -225.818478) (xy 351.394522 -225.83013)
			(xy 351.40826 -225.850892) (xy 351.430002 -225.895675) (xy 351.444771 -225.943216) (xy 351.45223 -225.992437)
			(xy 351.452688 -226.017328) (xy 351.452177 -226.043295) (xy 351.444049 -226.094588) (xy 351.427998 -226.143979)
			(xy 351.40442 -226.190252) (xy 351.373894 -226.232267) (xy 351.337171 -226.26899) (xy 351.295157 -226.299517)
			(xy 351.248885 -226.323096) (xy 351.199494 -226.339148) (xy 351.148201 -226.347276) (xy 351.122234 -226.347782)
			(xy 351.12198 -226.347782) (xy 351.094359 -226.347229) (xy 351.039887 -226.338044) (xy 350.987706 -226.319916)
			(xy 350.939271 -226.293352) (xy 350.917256 -226.276662) (xy 350.905795 -226.268194) (xy 350.879447 -226.257369)
			(xy 350.851134 -226.254245) (xy 350.82306 -226.259063) (xy 350.79741 -226.27145) (xy 350.77618 -226.29044)
			(xy 350.761022 -226.314557) (xy 350.753116 -226.341922) (xy 350.752664 -226.356164) (xy 350.752664 -226.51466)
			(xy 350.783398 -226.527868) (xy 350.806714 -226.538489) (xy 350.850024 -226.565859) (xy 350.888591 -226.599586)
			(xy 350.92149 -226.638861) (xy 350.947933 -226.682743) (xy 350.967286 -226.730181) (xy 350.979085 -226.780037)
			(xy 350.983048 -226.831118) (xy 350.981029 -226.857111) (xy 351.262189 -226.857111) (xy 351.262189 -226.805177)
			(xy 351.270314 -226.753882) (xy 351.286362 -226.704489) (xy 351.30994 -226.658215) (xy 351.340466 -226.616199)
			(xy 351.377189 -226.579476) (xy 351.419205 -226.54895) (xy 351.465479 -226.525372) (xy 351.514872 -226.509324)
			(xy 351.566167 -226.501199) (xy 351.618101 -226.501199) (xy 351.669396 -226.509324) (xy 351.718789 -226.525372)
			(xy 351.765063 -226.54895) (xy 351.807079 -226.579476) (xy 351.843802 -226.616199) (xy 351.874328 -226.658215)
			(xy 351.897906 -226.704489) (xy 351.913954 -226.753882) (xy 351.922079 -226.805177) (xy 351.922588 -226.831144)
			(xy 351.922079 -226.857111) (xy 352.201989 -226.857111) (xy 352.201989 -226.805177) (xy 352.210114 -226.753882)
			(xy 352.226162 -226.704489) (xy 352.24974 -226.658215) (xy 352.280266 -226.616199) (xy 352.316989 -226.579476)
			(xy 352.359005 -226.54895) (xy 352.405279 -226.525372) (xy 352.454672 -226.509324) (xy 352.505967 -226.501199)
			(xy 352.557901 -226.501199) (xy 352.609196 -226.509324) (xy 352.658589 -226.525372) (xy 352.704863 -226.54895)
			(xy 352.746879 -226.579476) (xy 352.783602 -226.616199) (xy 352.814128 -226.658215) (xy 352.837706 -226.704489)
			(xy 352.853754 -226.753882) (xy 352.861879 -226.805177) (xy 352.862388 -226.831144) (xy 352.861879 -226.857111)
			(xy 353.141535 -226.857111) (xy 353.141535 -226.805177) (xy 353.14966 -226.753882) (xy 353.165708 -226.704489)
			(xy 353.189286 -226.658215) (xy 353.219812 -226.616199) (xy 353.256535 -226.579476) (xy 353.298551 -226.54895)
			(xy 353.344825 -226.525372) (xy 353.394218 -226.509324) (xy 353.445513 -226.501199) (xy 353.497447 -226.501199)
			(xy 353.548742 -226.509324) (xy 353.598135 -226.525372) (xy 353.644409 -226.54895) (xy 353.686425 -226.579476)
			(xy 353.723148 -226.616199) (xy 353.753674 -226.658215) (xy 353.777252 -226.704489) (xy 353.7933 -226.753882)
			(xy 353.801425 -226.805177) (xy 353.801934 -226.831144) (xy 353.801425 -226.857111) (xy 354.081589 -226.857111)
			(xy 354.081589 -226.805177) (xy 354.089714 -226.753882) (xy 354.105762 -226.704489) (xy 354.12934 -226.658215)
			(xy 354.159866 -226.616199) (xy 354.196589 -226.579476) (xy 354.238605 -226.54895) (xy 354.284879 -226.525372)
			(xy 354.334272 -226.509324) (xy 354.385567 -226.501199) (xy 354.437501 -226.501199) (xy 354.488796 -226.509324)
			(xy 354.538189 -226.525372) (xy 354.584463 -226.54895) (xy 354.626479 -226.579476) (xy 354.663202 -226.616199)
			(xy 354.693728 -226.658215) (xy 354.717306 -226.704489) (xy 354.733354 -226.753882) (xy 354.741479 -226.805177)
			(xy 354.741988 -226.831144) (xy 354.741479 -226.857111) (xy 355.021135 -226.857111) (xy 355.021135 -226.805177)
			(xy 355.02926 -226.753882) (xy 355.045308 -226.704489) (xy 355.068886 -226.658215) (xy 355.099412 -226.616199)
			(xy 355.136135 -226.579476) (xy 355.178151 -226.54895) (xy 355.224425 -226.525372) (xy 355.273818 -226.509324)
			(xy 355.325113 -226.501199) (xy 355.377047 -226.501199) (xy 355.428342 -226.509324) (xy 355.477735 -226.525372)
			(xy 355.524009 -226.54895) (xy 355.566025 -226.579476) (xy 355.602748 -226.616199) (xy 355.633274 -226.658215)
			(xy 355.656852 -226.704489) (xy 355.6729 -226.753882) (xy 355.681025 -226.805177) (xy 355.681534 -226.831144)
			(xy 355.681025 -226.857111) (xy 355.961189 -226.857111) (xy 355.961189 -226.805177) (xy 355.969314 -226.753882)
			(xy 355.985362 -226.704489) (xy 356.00894 -226.658215) (xy 356.039466 -226.616199) (xy 356.076189 -226.579476)
			(xy 356.118205 -226.54895) (xy 356.164479 -226.525372) (xy 356.213872 -226.509324) (xy 356.265167 -226.501199)
			(xy 356.317101 -226.501199) (xy 356.368396 -226.509324) (xy 356.417789 -226.525372) (xy 356.464063 -226.54895)
			(xy 356.506079 -226.579476) (xy 356.542802 -226.616199) (xy 356.573328 -226.658215) (xy 356.596906 -226.704489)
			(xy 356.612954 -226.753882) (xy 356.621079 -226.805177) (xy 356.621588 -226.831144) (xy 356.621079 -226.857111)
			(xy 356.900735 -226.857111) (xy 356.900735 -226.805177) (xy 356.90886 -226.753882) (xy 356.924908 -226.704489)
			(xy 356.948486 -226.658215) (xy 356.979012 -226.616199) (xy 357.015735 -226.579476) (xy 357.057751 -226.54895)
			(xy 357.104025 -226.525372) (xy 357.153418 -226.509324) (xy 357.204713 -226.501199) (xy 357.256647 -226.501199)
			(xy 357.307942 -226.509324) (xy 357.357335 -226.525372) (xy 357.403609 -226.54895) (xy 357.445625 -226.579476)
			(xy 357.482348 -226.616199) (xy 357.512874 -226.658215) (xy 357.536452 -226.704489) (xy 357.5525 -226.753882)
			(xy 357.560625 -226.805177) (xy 357.561134 -226.831144) (xy 357.560625 -226.857111) (xy 357.840789 -226.857111)
			(xy 357.840789 -226.805177) (xy 357.848914 -226.753882) (xy 357.864962 -226.704489) (xy 357.88854 -226.658215)
			(xy 357.919066 -226.616199) (xy 357.955789 -226.579476) (xy 357.997805 -226.54895) (xy 358.044079 -226.525372)
			(xy 358.093472 -226.509324) (xy 358.144767 -226.501199) (xy 358.196701 -226.501199) (xy 358.247996 -226.509324)
			(xy 358.297389 -226.525372) (xy 358.343663 -226.54895) (xy 358.385679 -226.579476) (xy 358.422402 -226.616199)
			(xy 358.452928 -226.658215) (xy 358.476506 -226.704489) (xy 358.492554 -226.753882) (xy 358.500679 -226.805177)
			(xy 358.501188 -226.831144) (xy 358.500679 -226.857111) (xy 358.780335 -226.857111) (xy 358.780335 -226.805177)
			(xy 358.78846 -226.753882) (xy 358.804508 -226.704489) (xy 358.828086 -226.658215) (xy 358.858612 -226.616199)
			(xy 358.895335 -226.579476) (xy 358.937351 -226.54895) (xy 358.983625 -226.525372) (xy 359.033018 -226.509324)
			(xy 359.084313 -226.501199) (xy 359.136247 -226.501199) (xy 359.187542 -226.509324) (xy 359.236935 -226.525372)
			(xy 359.283209 -226.54895) (xy 359.325225 -226.579476) (xy 359.361948 -226.616199) (xy 359.392474 -226.658215)
			(xy 359.416052 -226.704489) (xy 359.4321 -226.753882) (xy 359.440225 -226.805177) (xy 359.440734 -226.831144)
			(xy 359.440225 -226.857111) (xy 359.720389 -226.857111) (xy 359.720389 -226.805177) (xy 359.728514 -226.753882)
			(xy 359.744562 -226.704489) (xy 359.76814 -226.658215) (xy 359.798666 -226.616199) (xy 359.835389 -226.579476)
			(xy 359.877405 -226.54895) (xy 359.923679 -226.525372) (xy 359.973072 -226.509324) (xy 360.024367 -226.501199)
			(xy 360.076301 -226.501199) (xy 360.127596 -226.509324) (xy 360.176989 -226.525372) (xy 360.223263 -226.54895)
			(xy 360.265279 -226.579476) (xy 360.302002 -226.616199) (xy 360.332528 -226.658215) (xy 360.356106 -226.704489)
			(xy 360.372154 -226.753882) (xy 360.380279 -226.805177) (xy 360.380788 -226.831144) (xy 360.380279 -226.857111)
			(xy 360.659935 -226.857111) (xy 360.659935 -226.805177) (xy 360.66806 -226.753882) (xy 360.684108 -226.704489)
			(xy 360.707686 -226.658215) (xy 360.738212 -226.616199) (xy 360.774935 -226.579476) (xy 360.816951 -226.54895)
			(xy 360.863225 -226.525372) (xy 360.912618 -226.509324) (xy 360.963913 -226.501199) (xy 361.015847 -226.501199)
			(xy 361.067142 -226.509324) (xy 361.116535 -226.525372) (xy 361.162809 -226.54895) (xy 361.204825 -226.579476)
			(xy 361.241548 -226.616199) (xy 361.272074 -226.658215) (xy 361.295652 -226.704489) (xy 361.3117 -226.753882)
			(xy 361.319825 -226.805177) (xy 361.320334 -226.831144) (xy 361.319825 -226.857111) (xy 361.599989 -226.857111)
			(xy 361.599989 -226.805177) (xy 361.608114 -226.753882) (xy 361.624162 -226.704489) (xy 361.64774 -226.658215)
			(xy 361.678266 -226.616199) (xy 361.714989 -226.579476) (xy 361.757005 -226.54895) (xy 361.803279 -226.525372)
			(xy 361.852672 -226.509324) (xy 361.903967 -226.501199) (xy 361.955901 -226.501199) (xy 362.007196 -226.509324)
			(xy 362.056589 -226.525372) (xy 362.102863 -226.54895) (xy 362.144879 -226.579476) (xy 362.181602 -226.616199)
			(xy 362.212128 -226.658215) (xy 362.235706 -226.704489) (xy 362.251754 -226.753882) (xy 362.259879 -226.805177)
			(xy 362.260388 -226.831144) (xy 362.259879 -226.857111) (xy 362.539789 -226.857111) (xy 362.539789 -226.805177)
			(xy 362.547914 -226.753882) (xy 362.563962 -226.704489) (xy 362.58754 -226.658215) (xy 362.618066 -226.616199)
			(xy 362.654789 -226.579476) (xy 362.696805 -226.54895) (xy 362.743079 -226.525372) (xy 362.792472 -226.509324)
			(xy 362.843767 -226.501199) (xy 362.895701 -226.501199) (xy 362.946996 -226.509324) (xy 362.996389 -226.525372)
			(xy 363.042663 -226.54895) (xy 363.084679 -226.579476) (xy 363.121402 -226.616199) (xy 363.151928 -226.658215)
			(xy 363.175506 -226.704489) (xy 363.191554 -226.753882) (xy 363.199679 -226.805177) (xy 363.200188 -226.831144)
			(xy 363.199679 -226.857111) (xy 363.479589 -226.857111) (xy 363.479589 -226.805177) (xy 363.487714 -226.753882)
			(xy 363.503762 -226.704489) (xy 363.52734 -226.658215) (xy 363.557866 -226.616199) (xy 363.594589 -226.579476)
			(xy 363.636605 -226.54895) (xy 363.682879 -226.525372) (xy 363.732272 -226.509324) (xy 363.783567 -226.501199)
			(xy 363.835501 -226.501199) (xy 363.886796 -226.509324) (xy 363.936189 -226.525372) (xy 363.982463 -226.54895)
			(xy 364.024479 -226.579476) (xy 364.061202 -226.616199) (xy 364.091728 -226.658215) (xy 364.115306 -226.704489)
			(xy 364.131354 -226.753882) (xy 364.139479 -226.805177) (xy 364.139988 -226.831144) (xy 364.139479 -226.857111)
			(xy 364.419135 -226.857111) (xy 364.419135 -226.805177) (xy 364.42726 -226.753882) (xy 364.443308 -226.704489)
			(xy 364.466886 -226.658215) (xy 364.497412 -226.616199) (xy 364.534135 -226.579476) (xy 364.576151 -226.54895)
			(xy 364.622425 -226.525372) (xy 364.671818 -226.509324) (xy 364.723113 -226.501199) (xy 364.775047 -226.501199)
			(xy 364.826342 -226.509324) (xy 364.875735 -226.525372) (xy 364.922009 -226.54895) (xy 364.964025 -226.579476)
			(xy 365.000748 -226.616199) (xy 365.031274 -226.658215) (xy 365.054852 -226.704489) (xy 365.0709 -226.753882)
			(xy 365.079025 -226.805177) (xy 365.079534 -226.831144) (xy 365.079025 -226.857111) (xy 365.359189 -226.857111)
			(xy 365.359189 -226.805177) (xy 365.367314 -226.753882) (xy 365.383362 -226.704489) (xy 365.40694 -226.658215)
			(xy 365.437466 -226.616199) (xy 365.474189 -226.579476) (xy 365.516205 -226.54895) (xy 365.562479 -226.525372)
			(xy 365.611872 -226.509324) (xy 365.663167 -226.501199) (xy 365.715101 -226.501199) (xy 365.766396 -226.509324)
			(xy 365.815789 -226.525372) (xy 365.862063 -226.54895) (xy 365.904079 -226.579476) (xy 365.940802 -226.616199)
			(xy 365.971328 -226.658215) (xy 365.994906 -226.704489) (xy 366.010954 -226.753882) (xy 366.019079 -226.805177)
			(xy 366.019588 -226.831144) (xy 366.019079 -226.857111) (xy 366.298735 -226.857111) (xy 366.298735 -226.805177)
			(xy 366.30686 -226.753882) (xy 366.322908 -226.704489) (xy 366.346486 -226.658215) (xy 366.377012 -226.616199)
			(xy 366.413735 -226.579476) (xy 366.455751 -226.54895) (xy 366.502025 -226.525372) (xy 366.551418 -226.509324)
			(xy 366.602713 -226.501199) (xy 366.654647 -226.501199) (xy 366.705942 -226.509324) (xy 366.755335 -226.525372)
			(xy 366.801609 -226.54895) (xy 366.843625 -226.579476) (xy 366.880348 -226.616199) (xy 366.910874 -226.658215)
			(xy 366.934452 -226.704489) (xy 366.9505 -226.753882) (xy 366.958625 -226.805177) (xy 366.959134 -226.831144)
			(xy 366.958625 -226.857111) (xy 367.238789 -226.857111) (xy 367.238789 -226.805177) (xy 367.246914 -226.753882)
			(xy 367.262962 -226.704489) (xy 367.28654 -226.658215) (xy 367.317066 -226.616199) (xy 367.353789 -226.579476)
			(xy 367.395805 -226.54895) (xy 367.442079 -226.525372) (xy 367.491472 -226.509324) (xy 367.542767 -226.501199)
			(xy 367.594701 -226.501199) (xy 367.645996 -226.509324) (xy 367.695389 -226.525372) (xy 367.741663 -226.54895)
			(xy 367.783679 -226.579476) (xy 367.820402 -226.616199) (xy 367.850928 -226.658215) (xy 367.874506 -226.704489)
			(xy 367.890554 -226.753882) (xy 367.898679 -226.805177) (xy 367.899188 -226.831144) (xy 367.898679 -226.857111)
			(xy 368.178335 -226.857111) (xy 368.178335 -226.805177) (xy 368.18646 -226.753882) (xy 368.202508 -226.704489)
			(xy 368.226086 -226.658215) (xy 368.256612 -226.616199) (xy 368.293335 -226.579476) (xy 368.335351 -226.54895)
			(xy 368.381625 -226.525372) (xy 368.431018 -226.509324) (xy 368.482313 -226.501199) (xy 368.534247 -226.501199)
			(xy 368.585542 -226.509324) (xy 368.634935 -226.525372) (xy 368.681209 -226.54895) (xy 368.723225 -226.579476)
			(xy 368.759948 -226.616199) (xy 368.790474 -226.658215) (xy 368.814052 -226.704489) (xy 368.8301 -226.753882)
			(xy 368.838225 -226.805177) (xy 368.838734 -226.831144) (xy 368.838225 -226.857111) (xy 369.118389 -226.857111)
			(xy 369.118389 -226.805177) (xy 369.126514 -226.753882) (xy 369.142562 -226.704489) (xy 369.16614 -226.658215)
			(xy 369.196666 -226.616199) (xy 369.233389 -226.579476) (xy 369.275405 -226.54895) (xy 369.321679 -226.525372)
			(xy 369.371072 -226.509324) (xy 369.422367 -226.501199) (xy 369.474301 -226.501199) (xy 369.525596 -226.509324)
			(xy 369.574989 -226.525372) (xy 369.621263 -226.54895) (xy 369.663279 -226.579476) (xy 369.700002 -226.616199)
			(xy 369.730528 -226.658215) (xy 369.754106 -226.704489) (xy 369.770154 -226.753882) (xy 369.778279 -226.805177)
			(xy 369.778788 -226.831144) (xy 369.778279 -226.857111) (xy 370.057935 -226.857111) (xy 370.057935 -226.805177)
			(xy 370.06606 -226.753882) (xy 370.082108 -226.704489) (xy 370.105686 -226.658215) (xy 370.136212 -226.616199)
			(xy 370.172935 -226.579476) (xy 370.214951 -226.54895) (xy 370.261225 -226.525372) (xy 370.310618 -226.509324)
			(xy 370.361913 -226.501199) (xy 370.413847 -226.501199) (xy 370.465142 -226.509324) (xy 370.514535 -226.525372)
			(xy 370.560809 -226.54895) (xy 370.602825 -226.579476) (xy 370.639548 -226.616199) (xy 370.670074 -226.658215)
			(xy 370.693652 -226.704489) (xy 370.7097 -226.753882) (xy 370.717825 -226.805177) (xy 370.718334 -226.831144)
			(xy 370.717825 -226.857111) (xy 370.997735 -226.857111) (xy 370.997735 -226.805177) (xy 371.00586 -226.753882)
			(xy 371.021908 -226.704489) (xy 371.045486 -226.658215) (xy 371.076012 -226.616199) (xy 371.112735 -226.579476)
			(xy 371.154751 -226.54895) (xy 371.201025 -226.525372) (xy 371.250418 -226.509324) (xy 371.301713 -226.501199)
			(xy 371.353647 -226.501199) (xy 371.404942 -226.509324) (xy 371.454335 -226.525372) (xy 371.500609 -226.54895)
			(xy 371.542625 -226.579476) (xy 371.579348 -226.616199) (xy 371.609874 -226.658215) (xy 371.633452 -226.704489)
			(xy 371.6495 -226.753882) (xy 371.657625 -226.805177) (xy 371.658134 -226.831144) (xy 371.657625 -226.857111)
			(xy 371.937789 -226.857111) (xy 371.937789 -226.805177) (xy 371.945914 -226.753882) (xy 371.961962 -226.704489)
			(xy 371.98554 -226.658215) (xy 372.016066 -226.616199) (xy 372.052789 -226.579476) (xy 372.094805 -226.54895)
			(xy 372.141079 -226.525372) (xy 372.190472 -226.509324) (xy 372.241767 -226.501199) (xy 372.293701 -226.501199)
			(xy 372.344996 -226.509324) (xy 372.394389 -226.525372) (xy 372.440663 -226.54895) (xy 372.482679 -226.579476)
			(xy 372.519402 -226.616199) (xy 372.549928 -226.658215) (xy 372.573506 -226.704489) (xy 372.589554 -226.753882)
			(xy 372.597679 -226.805177) (xy 372.598188 -226.831144) (xy 372.597679 -226.857111) (xy 372.877335 -226.857111)
			(xy 372.877335 -226.805177) (xy 372.88546 -226.753882) (xy 372.901508 -226.704489) (xy 372.925086 -226.658215)
			(xy 372.955612 -226.616199) (xy 372.992335 -226.579476) (xy 373.034351 -226.54895) (xy 373.080625 -226.525372)
			(xy 373.130018 -226.509324) (xy 373.181313 -226.501199) (xy 373.233247 -226.501199) (xy 373.284542 -226.509324)
			(xy 373.333935 -226.525372) (xy 373.380209 -226.54895) (xy 373.422225 -226.579476) (xy 373.458948 -226.616199)
			(xy 373.489474 -226.658215) (xy 373.513052 -226.704489) (xy 373.5291 -226.753882) (xy 373.537225 -226.805177)
			(xy 373.537734 -226.831144) (xy 373.537225 -226.857111) (xy 373.817135 -226.857111) (xy 373.817135 -226.805177)
			(xy 373.82526 -226.753882) (xy 373.841308 -226.704489) (xy 373.864886 -226.658215) (xy 373.895412 -226.616199)
			(xy 373.932135 -226.579476) (xy 373.974151 -226.54895) (xy 374.020425 -226.525372) (xy 374.069818 -226.509324)
			(xy 374.121113 -226.501199) (xy 374.173047 -226.501199) (xy 374.224342 -226.509324) (xy 374.273735 -226.525372)
			(xy 374.320009 -226.54895) (xy 374.362025 -226.579476) (xy 374.398748 -226.616199) (xy 374.429274 -226.658215)
			(xy 374.452852 -226.704489) (xy 374.4689 -226.753882) (xy 374.477025 -226.805177) (xy 374.477534 -226.831144)
			(xy 374.477025 -226.857111) (xy 374.4689 -226.908406) (xy 374.452852 -226.957799) (xy 374.429274 -227.004073)
			(xy 374.398748 -227.046089) (xy 374.362025 -227.082812) (xy 374.320009 -227.113338) (xy 374.273735 -227.136916)
			(xy 374.224342 -227.152964) (xy 374.173047 -227.161089) (xy 374.121113 -227.161089) (xy 374.069818 -227.152964)
			(xy 374.020425 -227.136916) (xy 373.974151 -227.113338) (xy 373.932135 -227.082812) (xy 373.895412 -227.046089)
			(xy 373.864886 -227.004073) (xy 373.841308 -226.957799) (xy 373.82526 -226.908406) (xy 373.817135 -226.857111)
			(xy 373.537225 -226.857111) (xy 373.5291 -226.908406) (xy 373.513052 -226.957799) (xy 373.489474 -227.004073)
			(xy 373.458948 -227.046089) (xy 373.422225 -227.082812) (xy 373.380209 -227.113338) (xy 373.333935 -227.136916)
			(xy 373.284542 -227.152964) (xy 373.233247 -227.161089) (xy 373.181313 -227.161089) (xy 373.130018 -227.152964)
			(xy 373.080625 -227.136916) (xy 373.034351 -227.113338) (xy 372.992335 -227.082812) (xy 372.955612 -227.046089)
			(xy 372.925086 -227.004073) (xy 372.901508 -226.957799) (xy 372.88546 -226.908406) (xy 372.877335 -226.857111)
			(xy 372.597679 -226.857111) (xy 372.589554 -226.908406) (xy 372.573506 -226.957799) (xy 372.549928 -227.004073)
			(xy 372.519402 -227.046089) (xy 372.482679 -227.082812) (xy 372.440663 -227.113338) (xy 372.394389 -227.136916)
			(xy 372.344996 -227.152964) (xy 372.293701 -227.161089) (xy 372.241767 -227.161089) (xy 372.190472 -227.152964)
			(xy 372.141079 -227.136916) (xy 372.094805 -227.113338) (xy 372.052789 -227.082812) (xy 372.016066 -227.046089)
			(xy 371.98554 -227.004073) (xy 371.961962 -226.957799) (xy 371.945914 -226.908406) (xy 371.937789 -226.857111)
			(xy 371.657625 -226.857111) (xy 371.6495 -226.908406) (xy 371.633452 -226.957799) (xy 371.609874 -227.004073)
			(xy 371.579348 -227.046089) (xy 371.542625 -227.082812) (xy 371.500609 -227.113338) (xy 371.454335 -227.136916)
			(xy 371.404942 -227.152964) (xy 371.353647 -227.161089) (xy 371.301713 -227.161089) (xy 371.250418 -227.152964)
			(xy 371.201025 -227.136916) (xy 371.154751 -227.113338) (xy 371.112735 -227.082812) (xy 371.076012 -227.046089)
			(xy 371.045486 -227.004073) (xy 371.021908 -226.957799) (xy 371.00586 -226.908406) (xy 370.997735 -226.857111)
			(xy 370.717825 -226.857111) (xy 370.7097 -226.908406) (xy 370.693652 -226.957799) (xy 370.670074 -227.004073)
			(xy 370.639548 -227.046089) (xy 370.602825 -227.082812) (xy 370.560809 -227.113338) (xy 370.514535 -227.136916)
			(xy 370.465142 -227.152964) (xy 370.413847 -227.161089) (xy 370.361913 -227.161089) (xy 370.310618 -227.152964)
			(xy 370.261225 -227.136916) (xy 370.214951 -227.113338) (xy 370.172935 -227.082812) (xy 370.136212 -227.046089)
			(xy 370.105686 -227.004073) (xy 370.082108 -226.957799) (xy 370.06606 -226.908406) (xy 370.057935 -226.857111)
			(xy 369.778279 -226.857111) (xy 369.770154 -226.908406) (xy 369.754106 -226.957799) (xy 369.730528 -227.004073)
			(xy 369.700002 -227.046089) (xy 369.663279 -227.082812) (xy 369.621263 -227.113338) (xy 369.574989 -227.136916)
			(xy 369.525596 -227.152964) (xy 369.474301 -227.161089) (xy 369.422367 -227.161089) (xy 369.371072 -227.152964)
			(xy 369.321679 -227.136916) (xy 369.275405 -227.113338) (xy 369.233389 -227.082812) (xy 369.196666 -227.046089)
			(xy 369.16614 -227.004073) (xy 369.142562 -226.957799) (xy 369.126514 -226.908406) (xy 369.118389 -226.857111)
			(xy 368.838225 -226.857111) (xy 368.8301 -226.908406) (xy 368.814052 -226.957799) (xy 368.790474 -227.004073)
			(xy 368.759948 -227.046089) (xy 368.723225 -227.082812) (xy 368.681209 -227.113338) (xy 368.634935 -227.136916)
			(xy 368.585542 -227.152964) (xy 368.534247 -227.161089) (xy 368.482313 -227.161089) (xy 368.431018 -227.152964)
			(xy 368.381625 -227.136916) (xy 368.335351 -227.113338) (xy 368.293335 -227.082812) (xy 368.256612 -227.046089)
			(xy 368.226086 -227.004073) (xy 368.202508 -226.957799) (xy 368.18646 -226.908406) (xy 368.178335 -226.857111)
			(xy 367.898679 -226.857111) (xy 367.890554 -226.908406) (xy 367.874506 -226.957799) (xy 367.850928 -227.004073)
			(xy 367.820402 -227.046089) (xy 367.783679 -227.082812) (xy 367.741663 -227.113338) (xy 367.695389 -227.136916)
			(xy 367.645996 -227.152964) (xy 367.594701 -227.161089) (xy 367.542767 -227.161089) (xy 367.491472 -227.152964)
			(xy 367.442079 -227.136916) (xy 367.395805 -227.113338) (xy 367.353789 -227.082812) (xy 367.317066 -227.046089)
			(xy 367.28654 -227.004073) (xy 367.262962 -226.957799) (xy 367.246914 -226.908406) (xy 367.238789 -226.857111)
			(xy 366.958625 -226.857111) (xy 366.9505 -226.908406) (xy 366.934452 -226.957799) (xy 366.910874 -227.004073)
			(xy 366.880348 -227.046089) (xy 366.843625 -227.082812) (xy 366.801609 -227.113338) (xy 366.755335 -227.136916)
			(xy 366.705942 -227.152964) (xy 366.654647 -227.161089) (xy 366.602713 -227.161089) (xy 366.551418 -227.152964)
			(xy 366.502025 -227.136916) (xy 366.455751 -227.113338) (xy 366.413735 -227.082812) (xy 366.377012 -227.046089)
			(xy 366.346486 -227.004073) (xy 366.322908 -226.957799) (xy 366.30686 -226.908406) (xy 366.298735 -226.857111)
			(xy 366.019079 -226.857111) (xy 366.010954 -226.908406) (xy 365.994906 -226.957799) (xy 365.971328 -227.004073)
			(xy 365.940802 -227.046089) (xy 365.904079 -227.082812) (xy 365.862063 -227.113338) (xy 365.815789 -227.136916)
			(xy 365.766396 -227.152964) (xy 365.715101 -227.161089) (xy 365.663167 -227.161089) (xy 365.611872 -227.152964)
			(xy 365.562479 -227.136916) (xy 365.516205 -227.113338) (xy 365.474189 -227.082812) (xy 365.437466 -227.046089)
			(xy 365.40694 -227.004073) (xy 365.383362 -226.957799) (xy 365.367314 -226.908406) (xy 365.359189 -226.857111)
			(xy 365.079025 -226.857111) (xy 365.0709 -226.908406) (xy 365.054852 -226.957799) (xy 365.031274 -227.004073)
			(xy 365.000748 -227.046089) (xy 364.964025 -227.082812) (xy 364.922009 -227.113338) (xy 364.875735 -227.136916)
			(xy 364.826342 -227.152964) (xy 364.775047 -227.161089) (xy 364.723113 -227.161089) (xy 364.671818 -227.152964)
			(xy 364.622425 -227.136916) (xy 364.576151 -227.113338) (xy 364.534135 -227.082812) (xy 364.497412 -227.046089)
			(xy 364.466886 -227.004073) (xy 364.443308 -226.957799) (xy 364.42726 -226.908406) (xy 364.419135 -226.857111)
			(xy 364.139479 -226.857111) (xy 364.131354 -226.908406) (xy 364.115306 -226.957799) (xy 364.091728 -227.004073)
			(xy 364.061202 -227.046089) (xy 364.024479 -227.082812) (xy 363.982463 -227.113338) (xy 363.936189 -227.136916)
			(xy 363.886796 -227.152964) (xy 363.835501 -227.161089) (xy 363.783567 -227.161089) (xy 363.732272 -227.152964)
			(xy 363.682879 -227.136916) (xy 363.636605 -227.113338) (xy 363.594589 -227.082812) (xy 363.557866 -227.046089)
			(xy 363.52734 -227.004073) (xy 363.503762 -226.957799) (xy 363.487714 -226.908406) (xy 363.479589 -226.857111)
			(xy 363.199679 -226.857111) (xy 363.191554 -226.908406) (xy 363.175506 -226.957799) (xy 363.151928 -227.004073)
			(xy 363.121402 -227.046089) (xy 363.084679 -227.082812) (xy 363.042663 -227.113338) (xy 362.996389 -227.136916)
			(xy 362.946996 -227.152964) (xy 362.895701 -227.161089) (xy 362.843767 -227.161089) (xy 362.792472 -227.152964)
			(xy 362.743079 -227.136916) (xy 362.696805 -227.113338) (xy 362.654789 -227.082812) (xy 362.618066 -227.046089)
			(xy 362.58754 -227.004073) (xy 362.563962 -226.957799) (xy 362.547914 -226.908406) (xy 362.539789 -226.857111)
			(xy 362.259879 -226.857111) (xy 362.251754 -226.908406) (xy 362.235706 -226.957799) (xy 362.212128 -227.004073)
			(xy 362.181602 -227.046089) (xy 362.144879 -227.082812) (xy 362.102863 -227.113338) (xy 362.056589 -227.136916)
			(xy 362.007196 -227.152964) (xy 361.955901 -227.161089) (xy 361.903967 -227.161089) (xy 361.852672 -227.152964)
			(xy 361.803279 -227.136916) (xy 361.757005 -227.113338) (xy 361.714989 -227.082812) (xy 361.678266 -227.046089)
			(xy 361.64774 -227.004073) (xy 361.624162 -226.957799) (xy 361.608114 -226.908406) (xy 361.599989 -226.857111)
			(xy 361.319825 -226.857111) (xy 361.3117 -226.908406) (xy 361.295652 -226.957799) (xy 361.272074 -227.004073)
			(xy 361.241548 -227.046089) (xy 361.204825 -227.082812) (xy 361.162809 -227.113338) (xy 361.116535 -227.136916)
			(xy 361.067142 -227.152964) (xy 361.015847 -227.161089) (xy 360.963913 -227.161089) (xy 360.912618 -227.152964)
			(xy 360.863225 -227.136916) (xy 360.816951 -227.113338) (xy 360.774935 -227.082812) (xy 360.738212 -227.046089)
			(xy 360.707686 -227.004073) (xy 360.684108 -226.957799) (xy 360.66806 -226.908406) (xy 360.659935 -226.857111)
			(xy 360.380279 -226.857111) (xy 360.372154 -226.908406) (xy 360.356106 -226.957799) (xy 360.332528 -227.004073)
			(xy 360.302002 -227.046089) (xy 360.265279 -227.082812) (xy 360.223263 -227.113338) (xy 360.176989 -227.136916)
			(xy 360.127596 -227.152964) (xy 360.076301 -227.161089) (xy 360.024367 -227.161089) (xy 359.973072 -227.152964)
			(xy 359.923679 -227.136916) (xy 359.877405 -227.113338) (xy 359.835389 -227.082812) (xy 359.798666 -227.046089)
			(xy 359.76814 -227.004073) (xy 359.744562 -226.957799) (xy 359.728514 -226.908406) (xy 359.720389 -226.857111)
			(xy 359.440225 -226.857111) (xy 359.4321 -226.908406) (xy 359.416052 -226.957799) (xy 359.392474 -227.004073)
			(xy 359.361948 -227.046089) (xy 359.325225 -227.082812) (xy 359.283209 -227.113338) (xy 359.236935 -227.136916)
			(xy 359.187542 -227.152964) (xy 359.136247 -227.161089) (xy 359.084313 -227.161089) (xy 359.033018 -227.152964)
			(xy 358.983625 -227.136916) (xy 358.937351 -227.113338) (xy 358.895335 -227.082812) (xy 358.858612 -227.046089)
			(xy 358.828086 -227.004073) (xy 358.804508 -226.957799) (xy 358.78846 -226.908406) (xy 358.780335 -226.857111)
			(xy 358.500679 -226.857111) (xy 358.492554 -226.908406) (xy 358.476506 -226.957799) (xy 358.452928 -227.004073)
			(xy 358.422402 -227.046089) (xy 358.385679 -227.082812) (xy 358.343663 -227.113338) (xy 358.297389 -227.136916)
			(xy 358.247996 -227.152964) (xy 358.196701 -227.161089) (xy 358.144767 -227.161089) (xy 358.093472 -227.152964)
			(xy 358.044079 -227.136916) (xy 357.997805 -227.113338) (xy 357.955789 -227.082812) (xy 357.919066 -227.046089)
			(xy 357.88854 -227.004073) (xy 357.864962 -226.957799) (xy 357.848914 -226.908406) (xy 357.840789 -226.857111)
			(xy 357.560625 -226.857111) (xy 357.5525 -226.908406) (xy 357.536452 -226.957799) (xy 357.512874 -227.004073)
			(xy 357.482348 -227.046089) (xy 357.445625 -227.082812) (xy 357.403609 -227.113338) (xy 357.357335 -227.136916)
			(xy 357.307942 -227.152964) (xy 357.256647 -227.161089) (xy 357.204713 -227.161089) (xy 357.153418 -227.152964)
			(xy 357.104025 -227.136916) (xy 357.057751 -227.113338) (xy 357.015735 -227.082812) (xy 356.979012 -227.046089)
			(xy 356.948486 -227.004073) (xy 356.924908 -226.957799) (xy 356.90886 -226.908406) (xy 356.900735 -226.857111)
			(xy 356.621079 -226.857111) (xy 356.612954 -226.908406) (xy 356.596906 -226.957799) (xy 356.573328 -227.004073)
			(xy 356.542802 -227.046089) (xy 356.506079 -227.082812) (xy 356.464063 -227.113338) (xy 356.417789 -227.136916)
			(xy 356.368396 -227.152964) (xy 356.317101 -227.161089) (xy 356.265167 -227.161089) (xy 356.213872 -227.152964)
			(xy 356.164479 -227.136916) (xy 356.118205 -227.113338) (xy 356.076189 -227.082812) (xy 356.039466 -227.046089)
			(xy 356.00894 -227.004073) (xy 355.985362 -226.957799) (xy 355.969314 -226.908406) (xy 355.961189 -226.857111)
			(xy 355.681025 -226.857111) (xy 355.6729 -226.908406) (xy 355.656852 -226.957799) (xy 355.633274 -227.004073)
			(xy 355.602748 -227.046089) (xy 355.566025 -227.082812) (xy 355.524009 -227.113338) (xy 355.477735 -227.136916)
			(xy 355.428342 -227.152964) (xy 355.377047 -227.161089) (xy 355.325113 -227.161089) (xy 355.273818 -227.152964)
			(xy 355.224425 -227.136916) (xy 355.178151 -227.113338) (xy 355.136135 -227.082812) (xy 355.099412 -227.046089)
			(xy 355.068886 -227.004073) (xy 355.045308 -226.957799) (xy 355.02926 -226.908406) (xy 355.021135 -226.857111)
			(xy 354.741479 -226.857111) (xy 354.733354 -226.908406) (xy 354.717306 -226.957799) (xy 354.693728 -227.004073)
			(xy 354.663202 -227.046089) (xy 354.626479 -227.082812) (xy 354.584463 -227.113338) (xy 354.538189 -227.136916)
			(xy 354.488796 -227.152964) (xy 354.437501 -227.161089) (xy 354.385567 -227.161089) (xy 354.334272 -227.152964)
			(xy 354.284879 -227.136916) (xy 354.238605 -227.113338) (xy 354.196589 -227.082812) (xy 354.159866 -227.046089)
			(xy 354.12934 -227.004073) (xy 354.105762 -226.957799) (xy 354.089714 -226.908406) (xy 354.081589 -226.857111)
			(xy 353.801425 -226.857111) (xy 353.7933 -226.908406) (xy 353.777252 -226.957799) (xy 353.753674 -227.004073)
			(xy 353.723148 -227.046089) (xy 353.686425 -227.082812) (xy 353.644409 -227.113338) (xy 353.598135 -227.136916)
			(xy 353.548742 -227.152964) (xy 353.497447 -227.161089) (xy 353.445513 -227.161089) (xy 353.394218 -227.152964)
			(xy 353.344825 -227.136916) (xy 353.298551 -227.113338) (xy 353.256535 -227.082812) (xy 353.219812 -227.046089)
			(xy 353.189286 -227.004073) (xy 353.165708 -226.957799) (xy 353.14966 -226.908406) (xy 353.141535 -226.857111)
			(xy 352.861879 -226.857111) (xy 352.853754 -226.908406) (xy 352.837706 -226.957799) (xy 352.814128 -227.004073)
			(xy 352.783602 -227.046089) (xy 352.746879 -227.082812) (xy 352.704863 -227.113338) (xy 352.658589 -227.136916)
			(xy 352.609196 -227.152964) (xy 352.557901 -227.161089) (xy 352.505967 -227.161089) (xy 352.454672 -227.152964)
			(xy 352.405279 -227.136916) (xy 352.359005 -227.113338) (xy 352.316989 -227.082812) (xy 352.280266 -227.046089)
			(xy 352.24974 -227.004073) (xy 352.226162 -226.957799) (xy 352.210114 -226.908406) (xy 352.201989 -226.857111)
			(xy 351.922079 -226.857111) (xy 351.913954 -226.908406) (xy 351.897906 -226.957799) (xy 351.874328 -227.004073)
			(xy 351.843802 -227.046089) (xy 351.807079 -227.082812) (xy 351.765063 -227.113338) (xy 351.718789 -227.136916)
			(xy 351.669396 -227.152964) (xy 351.618101 -227.161089) (xy 351.566167 -227.161089) (xy 351.514872 -227.152964)
			(xy 351.465479 -227.136916) (xy 351.419205 -227.113338) (xy 351.377189 -227.082812) (xy 351.340466 -227.046089)
			(xy 351.30994 -227.004073) (xy 351.286362 -226.957799) (xy 351.270314 -226.908406) (xy 351.262189 -226.857111)
			(xy 350.981029 -226.857111) (xy 350.97908 -226.882197) (xy 350.967275 -226.932052) (xy 350.947917 -226.979488)
			(xy 350.92147 -227.023368) (xy 350.888566 -227.062639) (xy 350.849996 -227.096362) (xy 350.806683 -227.123727)
			(xy 350.783398 -227.13442) (xy 350.752664 -227.147628) (xy 350.752664 -227.670927) (xy 351.732089 -227.670927)
			(xy 351.732089 -227.618993) (xy 351.740214 -227.567698) (xy 351.756262 -227.518305) (xy 351.77984 -227.472031)
			(xy 351.810366 -227.430015) (xy 351.847089 -227.393292) (xy 351.889105 -227.362766) (xy 351.935379 -227.339188)
			(xy 351.984772 -227.32314) (xy 352.036067 -227.315015) (xy 352.088001 -227.315015) (xy 352.139296 -227.32314)
			(xy 352.188689 -227.339188) (xy 352.234963 -227.362766) (xy 352.276979 -227.393292) (xy 352.313702 -227.430015)
			(xy 352.344228 -227.472031) (xy 352.367806 -227.518305) (xy 352.383854 -227.567698) (xy 352.391979 -227.618993)
			(xy 352.392488 -227.64496) (xy 352.391979 -227.670927) (xy 352.671889 -227.670927) (xy 352.671889 -227.618993)
			(xy 352.680014 -227.567698) (xy 352.696062 -227.518305) (xy 352.71964 -227.472031) (xy 352.750166 -227.430015)
			(xy 352.786889 -227.393292) (xy 352.828905 -227.362766) (xy 352.875179 -227.339188) (xy 352.924572 -227.32314)
			(xy 352.975867 -227.315015) (xy 353.027801 -227.315015) (xy 353.079096 -227.32314) (xy 353.128489 -227.339188)
			(xy 353.174763 -227.362766) (xy 353.216779 -227.393292) (xy 353.253502 -227.430015) (xy 353.284028 -227.472031)
			(xy 353.307606 -227.518305) (xy 353.323654 -227.567698) (xy 353.331779 -227.618993) (xy 353.332288 -227.64496)
			(xy 353.331779 -227.670927) (xy 353.611689 -227.670927) (xy 353.611689 -227.618993) (xy 353.619814 -227.567698)
			(xy 353.635862 -227.518305) (xy 353.65944 -227.472031) (xy 353.689966 -227.430015) (xy 353.726689 -227.393292)
			(xy 353.768705 -227.362766) (xy 353.814979 -227.339188) (xy 353.864372 -227.32314) (xy 353.915667 -227.315015)
			(xy 353.967601 -227.315015) (xy 354.018896 -227.32314) (xy 354.068289 -227.339188) (xy 354.114563 -227.362766)
			(xy 354.156579 -227.393292) (xy 354.193302 -227.430015) (xy 354.223828 -227.472031) (xy 354.247406 -227.518305)
			(xy 354.263454 -227.567698) (xy 354.271579 -227.618993) (xy 354.272088 -227.64496) (xy 354.271579 -227.670927)
			(xy 354.551489 -227.670927) (xy 354.551489 -227.618993) (xy 354.559614 -227.567698) (xy 354.575662 -227.518305)
			(xy 354.59924 -227.472031) (xy 354.629766 -227.430015) (xy 354.666489 -227.393292) (xy 354.708505 -227.362766)
			(xy 354.754779 -227.339188) (xy 354.804172 -227.32314) (xy 354.855467 -227.315015) (xy 354.907401 -227.315015)
			(xy 354.958696 -227.32314) (xy 355.008089 -227.339188) (xy 355.054363 -227.362766) (xy 355.096379 -227.393292)
			(xy 355.133102 -227.430015) (xy 355.163628 -227.472031) (xy 355.187206 -227.518305) (xy 355.203254 -227.567698)
			(xy 355.211379 -227.618993) (xy 355.211888 -227.64496) (xy 355.211379 -227.670927) (xy 355.491289 -227.670927)
			(xy 355.491289 -227.618993) (xy 355.499414 -227.567698) (xy 355.515462 -227.518305) (xy 355.53904 -227.472031)
			(xy 355.569566 -227.430015) (xy 355.606289 -227.393292) (xy 355.648305 -227.362766) (xy 355.694579 -227.339188)
			(xy 355.743972 -227.32314) (xy 355.795267 -227.315015) (xy 355.847201 -227.315015) (xy 355.898496 -227.32314)
			(xy 355.947889 -227.339188) (xy 355.994163 -227.362766) (xy 356.036179 -227.393292) (xy 356.072902 -227.430015)
			(xy 356.103428 -227.472031) (xy 356.127006 -227.518305) (xy 356.143054 -227.567698) (xy 356.151179 -227.618993)
			(xy 356.151688 -227.64496) (xy 356.151179 -227.670927) (xy 356.431089 -227.670927) (xy 356.431089 -227.618993)
			(xy 356.439214 -227.567698) (xy 356.455262 -227.518305) (xy 356.47884 -227.472031) (xy 356.509366 -227.430015)
			(xy 356.546089 -227.393292) (xy 356.588105 -227.362766) (xy 356.634379 -227.339188) (xy 356.683772 -227.32314)
			(xy 356.735067 -227.315015) (xy 356.787001 -227.315015) (xy 356.838296 -227.32314) (xy 356.887689 -227.339188)
			(xy 356.933963 -227.362766) (xy 356.975979 -227.393292) (xy 357.012702 -227.430015) (xy 357.043228 -227.472031)
			(xy 357.066806 -227.518305) (xy 357.082854 -227.567698) (xy 357.090979 -227.618993) (xy 357.091488 -227.64496)
			(xy 357.090979 -227.670927) (xy 357.370889 -227.670927) (xy 357.370889 -227.618993) (xy 357.379014 -227.567698)
			(xy 357.395062 -227.518305) (xy 357.41864 -227.472031) (xy 357.449166 -227.430015) (xy 357.485889 -227.393292)
			(xy 357.527905 -227.362766) (xy 357.574179 -227.339188) (xy 357.623572 -227.32314) (xy 357.674867 -227.315015)
			(xy 357.726801 -227.315015) (xy 357.778096 -227.32314) (xy 357.827489 -227.339188) (xy 357.873763 -227.362766)
			(xy 357.915779 -227.393292) (xy 357.952502 -227.430015) (xy 357.983028 -227.472031) (xy 358.006606 -227.518305)
			(xy 358.022654 -227.567698) (xy 358.030779 -227.618993) (xy 358.031288 -227.64496) (xy 358.030779 -227.670927)
			(xy 358.310689 -227.670927) (xy 358.310689 -227.618993) (xy 358.318814 -227.567698) (xy 358.334862 -227.518305)
			(xy 358.35844 -227.472031) (xy 358.388966 -227.430015) (xy 358.425689 -227.393292) (xy 358.467705 -227.362766)
			(xy 358.513979 -227.339188) (xy 358.563372 -227.32314) (xy 358.614667 -227.315015) (xy 358.666601 -227.315015)
			(xy 358.717896 -227.32314) (xy 358.767289 -227.339188) (xy 358.813563 -227.362766) (xy 358.855579 -227.393292)
			(xy 358.892302 -227.430015) (xy 358.922828 -227.472031) (xy 358.946406 -227.518305) (xy 358.962454 -227.567698)
			(xy 358.970579 -227.618993) (xy 358.971088 -227.64496) (xy 358.970579 -227.670927) (xy 359.250489 -227.670927)
			(xy 359.250489 -227.618993) (xy 359.258614 -227.567698) (xy 359.274662 -227.518305) (xy 359.29824 -227.472031)
			(xy 359.328766 -227.430015) (xy 359.365489 -227.393292) (xy 359.407505 -227.362766) (xy 359.453779 -227.339188)
			(xy 359.503172 -227.32314) (xy 359.554467 -227.315015) (xy 359.606401 -227.315015) (xy 359.657696 -227.32314)
			(xy 359.707089 -227.339188) (xy 359.753363 -227.362766) (xy 359.795379 -227.393292) (xy 359.832102 -227.430015)
			(xy 359.862628 -227.472031) (xy 359.886206 -227.518305) (xy 359.902254 -227.567698) (xy 359.910379 -227.618993)
			(xy 359.910888 -227.64496) (xy 359.910379 -227.670927) (xy 360.190289 -227.670927) (xy 360.190289 -227.618993)
			(xy 360.198414 -227.567698) (xy 360.214462 -227.518305) (xy 360.23804 -227.472031) (xy 360.268566 -227.430015)
			(xy 360.305289 -227.393292) (xy 360.347305 -227.362766) (xy 360.393579 -227.339188) (xy 360.442972 -227.32314)
			(xy 360.494267 -227.315015) (xy 360.546201 -227.315015) (xy 360.597496 -227.32314) (xy 360.646889 -227.339188)
			(xy 360.693163 -227.362766) (xy 360.735179 -227.393292) (xy 360.771902 -227.430015) (xy 360.802428 -227.472031)
			(xy 360.826006 -227.518305) (xy 360.842054 -227.567698) (xy 360.850179 -227.618993) (xy 360.850688 -227.64496)
			(xy 360.850179 -227.670927) (xy 361.130089 -227.670927) (xy 361.130089 -227.618993) (xy 361.138214 -227.567698)
			(xy 361.154262 -227.518305) (xy 361.17784 -227.472031) (xy 361.208366 -227.430015) (xy 361.245089 -227.393292)
			(xy 361.287105 -227.362766) (xy 361.333379 -227.339188) (xy 361.382772 -227.32314) (xy 361.434067 -227.315015)
			(xy 361.486001 -227.315015) (xy 361.537296 -227.32314) (xy 361.586689 -227.339188) (xy 361.632963 -227.362766)
			(xy 361.674979 -227.393292) (xy 361.711702 -227.430015) (xy 361.742228 -227.472031) (xy 361.765806 -227.518305)
			(xy 361.781854 -227.567698) (xy 361.789979 -227.618993) (xy 361.790488 -227.64496) (xy 361.789979 -227.670927)
			(xy 362.070143 -227.670927) (xy 362.070143 -227.618993) (xy 362.078268 -227.567698) (xy 362.094316 -227.518305)
			(xy 362.117894 -227.472031) (xy 362.14842 -227.430015) (xy 362.185143 -227.393292) (xy 362.227159 -227.362766)
			(xy 362.273433 -227.339188) (xy 362.322826 -227.32314) (xy 362.374121 -227.315015) (xy 362.426055 -227.315015)
			(xy 362.47735 -227.32314) (xy 362.526743 -227.339188) (xy 362.573017 -227.362766) (xy 362.615033 -227.393292)
			(xy 362.651756 -227.430015) (xy 362.682282 -227.472031) (xy 362.70586 -227.518305) (xy 362.721908 -227.567698)
			(xy 362.730033 -227.618993) (xy 362.730542 -227.64496) (xy 362.730033 -227.670927) (xy 363.009689 -227.670927)
			(xy 363.009689 -227.618993) (xy 363.017814 -227.567698) (xy 363.033862 -227.518305) (xy 363.05744 -227.472031)
			(xy 363.087966 -227.430015) (xy 363.124689 -227.393292) (xy 363.166705 -227.362766) (xy 363.212979 -227.339188)
			(xy 363.262372 -227.32314) (xy 363.313667 -227.315015) (xy 363.365601 -227.315015) (xy 363.416896 -227.32314)
			(xy 363.466289 -227.339188) (xy 363.512563 -227.362766) (xy 363.554579 -227.393292) (xy 363.591302 -227.430015)
			(xy 363.621828 -227.472031) (xy 363.645406 -227.518305) (xy 363.661454 -227.567698) (xy 363.669579 -227.618993)
			(xy 363.670088 -227.64496) (xy 363.669579 -227.670927) (xy 363.949489 -227.670927) (xy 363.949489 -227.618993)
			(xy 363.957614 -227.567698) (xy 363.973662 -227.518305) (xy 363.99724 -227.472031) (xy 364.027766 -227.430015)
			(xy 364.064489 -227.393292) (xy 364.106505 -227.362766) (xy 364.152779 -227.339188) (xy 364.202172 -227.32314)
			(xy 364.253467 -227.315015) (xy 364.305401 -227.315015) (xy 364.356696 -227.32314) (xy 364.406089 -227.339188)
			(xy 364.452363 -227.362766) (xy 364.494379 -227.393292) (xy 364.531102 -227.430015) (xy 364.561628 -227.472031)
			(xy 364.585206 -227.518305) (xy 364.601254 -227.567698) (xy 364.609379 -227.618993) (xy 364.609888 -227.64496)
			(xy 364.609379 -227.670927) (xy 364.889289 -227.670927) (xy 364.889289 -227.618993) (xy 364.897414 -227.567698)
			(xy 364.913462 -227.518305) (xy 364.93704 -227.472031) (xy 364.967566 -227.430015) (xy 365.004289 -227.393292)
			(xy 365.046305 -227.362766) (xy 365.092579 -227.339188) (xy 365.141972 -227.32314) (xy 365.193267 -227.315015)
			(xy 365.245201 -227.315015) (xy 365.296496 -227.32314) (xy 365.345889 -227.339188) (xy 365.392163 -227.362766)
			(xy 365.434179 -227.393292) (xy 365.470902 -227.430015) (xy 365.501428 -227.472031) (xy 365.525006 -227.518305)
			(xy 365.541054 -227.567698) (xy 365.549179 -227.618993) (xy 365.549688 -227.64496) (xy 365.549179 -227.670927)
			(xy 365.829089 -227.670927) (xy 365.829089 -227.618993) (xy 365.837214 -227.567698) (xy 365.853262 -227.518305)
			(xy 365.87684 -227.472031) (xy 365.907366 -227.430015) (xy 365.944089 -227.393292) (xy 365.986105 -227.362766)
			(xy 366.032379 -227.339188) (xy 366.081772 -227.32314) (xy 366.133067 -227.315015) (xy 366.185001 -227.315015)
			(xy 366.236296 -227.32314) (xy 366.285689 -227.339188) (xy 366.331963 -227.362766) (xy 366.373979 -227.393292)
			(xy 366.410702 -227.430015) (xy 366.441228 -227.472031) (xy 366.464806 -227.518305) (xy 366.480854 -227.567698)
			(xy 366.488979 -227.618993) (xy 366.489488 -227.64496) (xy 366.488979 -227.670927) (xy 366.768889 -227.670927)
			(xy 366.768889 -227.618993) (xy 366.777014 -227.567698) (xy 366.793062 -227.518305) (xy 366.81664 -227.472031)
			(xy 366.847166 -227.430015) (xy 366.883889 -227.393292) (xy 366.925905 -227.362766) (xy 366.972179 -227.339188)
			(xy 367.021572 -227.32314) (xy 367.072867 -227.315015) (xy 367.124801 -227.315015) (xy 367.176096 -227.32314)
			(xy 367.225489 -227.339188) (xy 367.271763 -227.362766) (xy 367.313779 -227.393292) (xy 367.350502 -227.430015)
			(xy 367.381028 -227.472031) (xy 367.404606 -227.518305) (xy 367.420654 -227.567698) (xy 367.428779 -227.618993)
			(xy 367.429288 -227.64496) (xy 367.428779 -227.670927) (xy 367.708689 -227.670927) (xy 367.708689 -227.618993)
			(xy 367.716814 -227.567698) (xy 367.732862 -227.518305) (xy 367.75644 -227.472031) (xy 367.786966 -227.430015)
			(xy 367.823689 -227.393292) (xy 367.865705 -227.362766) (xy 367.911979 -227.339188) (xy 367.961372 -227.32314)
			(xy 368.012667 -227.315015) (xy 368.064601 -227.315015) (xy 368.115896 -227.32314) (xy 368.165289 -227.339188)
			(xy 368.211563 -227.362766) (xy 368.253579 -227.393292) (xy 368.290302 -227.430015) (xy 368.320828 -227.472031)
			(xy 368.344406 -227.518305) (xy 368.360454 -227.567698) (xy 368.368579 -227.618993) (xy 368.369088 -227.64496)
			(xy 368.368579 -227.670927) (xy 368.648489 -227.670927) (xy 368.648489 -227.618993) (xy 368.656614 -227.567698)
			(xy 368.672662 -227.518305) (xy 368.69624 -227.472031) (xy 368.726766 -227.430015) (xy 368.763489 -227.393292)
			(xy 368.805505 -227.362766) (xy 368.851779 -227.339188) (xy 368.901172 -227.32314) (xy 368.952467 -227.315015)
			(xy 369.004401 -227.315015) (xy 369.055696 -227.32314) (xy 369.105089 -227.339188) (xy 369.151363 -227.362766)
			(xy 369.193379 -227.393292) (xy 369.230102 -227.430015) (xy 369.260628 -227.472031) (xy 369.284206 -227.518305)
			(xy 369.300254 -227.567698) (xy 369.308379 -227.618993) (xy 369.308888 -227.64496) (xy 369.308379 -227.670927)
			(xy 369.588035 -227.670927) (xy 369.588035 -227.618993) (xy 369.59616 -227.567698) (xy 369.612208 -227.518305)
			(xy 369.635786 -227.472031) (xy 369.666312 -227.430015) (xy 369.703035 -227.393292) (xy 369.745051 -227.362766)
			(xy 369.791325 -227.339188) (xy 369.840718 -227.32314) (xy 369.892013 -227.315015) (xy 369.943947 -227.315015)
			(xy 369.995242 -227.32314) (xy 370.044635 -227.339188) (xy 370.090909 -227.362766) (xy 370.132925 -227.393292)
			(xy 370.169648 -227.430015) (xy 370.200174 -227.472031) (xy 370.223752 -227.518305) (xy 370.2398 -227.567698)
			(xy 370.247925 -227.618993) (xy 370.248434 -227.64496) (xy 370.247925 -227.670927) (xy 370.528089 -227.670927)
			(xy 370.528089 -227.618993) (xy 370.536214 -227.567698) (xy 370.552262 -227.518305) (xy 370.57584 -227.472031)
			(xy 370.606366 -227.430015) (xy 370.643089 -227.393292) (xy 370.685105 -227.362766) (xy 370.731379 -227.339188)
			(xy 370.780772 -227.32314) (xy 370.832067 -227.315015) (xy 370.884001 -227.315015) (xy 370.935296 -227.32314)
			(xy 370.984689 -227.339188) (xy 371.030963 -227.362766) (xy 371.072979 -227.393292) (xy 371.109702 -227.430015)
			(xy 371.140228 -227.472031) (xy 371.163806 -227.518305) (xy 371.179854 -227.567698) (xy 371.187979 -227.618993)
			(xy 371.188488 -227.64496) (xy 371.187979 -227.670927) (xy 371.467889 -227.670927) (xy 371.467889 -227.618993)
			(xy 371.476014 -227.567698) (xy 371.492062 -227.518305) (xy 371.51564 -227.472031) (xy 371.546166 -227.430015)
			(xy 371.582889 -227.393292) (xy 371.624905 -227.362766) (xy 371.671179 -227.339188) (xy 371.720572 -227.32314)
			(xy 371.771867 -227.315015) (xy 371.823801 -227.315015) (xy 371.875096 -227.32314) (xy 371.924489 -227.339188)
			(xy 371.970763 -227.362766) (xy 372.012779 -227.393292) (xy 372.049502 -227.430015) (xy 372.080028 -227.472031)
			(xy 372.103606 -227.518305) (xy 372.119654 -227.567698) (xy 372.127779 -227.618993) (xy 372.128288 -227.64496)
			(xy 372.127779 -227.670927) (xy 372.407689 -227.670927) (xy 372.407689 -227.618993) (xy 372.415814 -227.567698)
			(xy 372.431862 -227.518305) (xy 372.45544 -227.472031) (xy 372.485966 -227.430015) (xy 372.522689 -227.393292)
			(xy 372.564705 -227.362766) (xy 372.610979 -227.339188) (xy 372.660372 -227.32314) (xy 372.711667 -227.315015)
			(xy 372.763601 -227.315015) (xy 372.814896 -227.32314) (xy 372.864289 -227.339188) (xy 372.910563 -227.362766)
			(xy 372.952579 -227.393292) (xy 372.989302 -227.430015) (xy 373.019828 -227.472031) (xy 373.043406 -227.518305)
			(xy 373.059454 -227.567698) (xy 373.067579 -227.618993) (xy 373.068088 -227.64496) (xy 373.067579 -227.670927)
			(xy 373.347489 -227.670927) (xy 373.347489 -227.618993) (xy 373.355614 -227.567698) (xy 373.371662 -227.518305)
			(xy 373.39524 -227.472031) (xy 373.425766 -227.430015) (xy 373.462489 -227.393292) (xy 373.504505 -227.362766)
			(xy 373.550779 -227.339188) (xy 373.600172 -227.32314) (xy 373.651467 -227.315015) (xy 373.703401 -227.315015)
			(xy 373.754696 -227.32314) (xy 373.804089 -227.339188) (xy 373.850363 -227.362766) (xy 373.892379 -227.393292)
			(xy 373.929102 -227.430015) (xy 373.959628 -227.472031) (xy 373.983206 -227.518305) (xy 373.999254 -227.567698)
			(xy 374.007379 -227.618993) (xy 374.007888 -227.64496) (xy 374.007379 -227.670927) (xy 373.999254 -227.722222)
			(xy 373.983206 -227.771615) (xy 373.959628 -227.817889) (xy 373.929102 -227.859905) (xy 373.892379 -227.896628)
			(xy 373.850363 -227.927154) (xy 373.804089 -227.950732) (xy 373.754696 -227.96678) (xy 373.703401 -227.974905)
			(xy 373.651467 -227.974905) (xy 373.600172 -227.96678) (xy 373.550779 -227.950732) (xy 373.504505 -227.927154)
			(xy 373.462489 -227.896628) (xy 373.425766 -227.859905) (xy 373.39524 -227.817889) (xy 373.371662 -227.771615)
			(xy 373.355614 -227.722222) (xy 373.347489 -227.670927) (xy 373.067579 -227.670927) (xy 373.059454 -227.722222)
			(xy 373.043406 -227.771615) (xy 373.019828 -227.817889) (xy 372.989302 -227.859905) (xy 372.952579 -227.896628)
			(xy 372.910563 -227.927154) (xy 372.864289 -227.950732) (xy 372.814896 -227.96678) (xy 372.763601 -227.974905)
			(xy 372.711667 -227.974905) (xy 372.660372 -227.96678) (xy 372.610979 -227.950732) (xy 372.564705 -227.927154)
			(xy 372.522689 -227.896628) (xy 372.485966 -227.859905) (xy 372.45544 -227.817889) (xy 372.431862 -227.771615)
			(xy 372.415814 -227.722222) (xy 372.407689 -227.670927) (xy 372.127779 -227.670927) (xy 372.119654 -227.722222)
			(xy 372.103606 -227.771615) (xy 372.080028 -227.817889) (xy 372.049502 -227.859905) (xy 372.012779 -227.896628)
			(xy 371.970763 -227.927154) (xy 371.924489 -227.950732) (xy 371.875096 -227.96678) (xy 371.823801 -227.974905)
			(xy 371.771867 -227.974905) (xy 371.720572 -227.96678) (xy 371.671179 -227.950732) (xy 371.624905 -227.927154)
			(xy 371.582889 -227.896628) (xy 371.546166 -227.859905) (xy 371.51564 -227.817889) (xy 371.492062 -227.771615)
			(xy 371.476014 -227.722222) (xy 371.467889 -227.670927) (xy 371.187979 -227.670927) (xy 371.179854 -227.722222)
			(xy 371.163806 -227.771615) (xy 371.140228 -227.817889) (xy 371.109702 -227.859905) (xy 371.072979 -227.896628)
			(xy 371.030963 -227.927154) (xy 370.984689 -227.950732) (xy 370.935296 -227.96678) (xy 370.884001 -227.974905)
			(xy 370.832067 -227.974905) (xy 370.780772 -227.96678) (xy 370.731379 -227.950732) (xy 370.685105 -227.927154)
			(xy 370.643089 -227.896628) (xy 370.606366 -227.859905) (xy 370.57584 -227.817889) (xy 370.552262 -227.771615)
			(xy 370.536214 -227.722222) (xy 370.528089 -227.670927) (xy 370.247925 -227.670927) (xy 370.2398 -227.722222)
			(xy 370.223752 -227.771615) (xy 370.200174 -227.817889) (xy 370.169648 -227.859905) (xy 370.132925 -227.896628)
			(xy 370.090909 -227.927154) (xy 370.044635 -227.950732) (xy 369.995242 -227.96678) (xy 369.943947 -227.974905)
			(xy 369.892013 -227.974905) (xy 369.840718 -227.96678) (xy 369.791325 -227.950732) (xy 369.745051 -227.927154)
			(xy 369.703035 -227.896628) (xy 369.666312 -227.859905) (xy 369.635786 -227.817889) (xy 369.612208 -227.771615)
			(xy 369.59616 -227.722222) (xy 369.588035 -227.670927) (xy 369.308379 -227.670927) (xy 369.300254 -227.722222)
			(xy 369.284206 -227.771615) (xy 369.260628 -227.817889) (xy 369.230102 -227.859905) (xy 369.193379 -227.896628)
			(xy 369.151363 -227.927154) (xy 369.105089 -227.950732) (xy 369.055696 -227.96678) (xy 369.004401 -227.974905)
			(xy 368.952467 -227.974905) (xy 368.901172 -227.96678) (xy 368.851779 -227.950732) (xy 368.805505 -227.927154)
			(xy 368.763489 -227.896628) (xy 368.726766 -227.859905) (xy 368.69624 -227.817889) (xy 368.672662 -227.771615)
			(xy 368.656614 -227.722222) (xy 368.648489 -227.670927) (xy 368.368579 -227.670927) (xy 368.360454 -227.722222)
			(xy 368.344406 -227.771615) (xy 368.320828 -227.817889) (xy 368.290302 -227.859905) (xy 368.253579 -227.896628)
			(xy 368.211563 -227.927154) (xy 368.165289 -227.950732) (xy 368.115896 -227.96678) (xy 368.064601 -227.974905)
			(xy 368.012667 -227.974905) (xy 367.961372 -227.96678) (xy 367.911979 -227.950732) (xy 367.865705 -227.927154)
			(xy 367.823689 -227.896628) (xy 367.786966 -227.859905) (xy 367.75644 -227.817889) (xy 367.732862 -227.771615)
			(xy 367.716814 -227.722222) (xy 367.708689 -227.670927) (xy 367.428779 -227.670927) (xy 367.420654 -227.722222)
			(xy 367.404606 -227.771615) (xy 367.381028 -227.817889) (xy 367.350502 -227.859905) (xy 367.313779 -227.896628)
			(xy 367.271763 -227.927154) (xy 367.225489 -227.950732) (xy 367.176096 -227.96678) (xy 367.124801 -227.974905)
			(xy 367.072867 -227.974905) (xy 367.021572 -227.96678) (xy 366.972179 -227.950732) (xy 366.925905 -227.927154)
			(xy 366.883889 -227.896628) (xy 366.847166 -227.859905) (xy 366.81664 -227.817889) (xy 366.793062 -227.771615)
			(xy 366.777014 -227.722222) (xy 366.768889 -227.670927) (xy 366.488979 -227.670927) (xy 366.480854 -227.722222)
			(xy 366.464806 -227.771615) (xy 366.441228 -227.817889) (xy 366.410702 -227.859905) (xy 366.373979 -227.896628)
			(xy 366.331963 -227.927154) (xy 366.285689 -227.950732) (xy 366.236296 -227.96678) (xy 366.185001 -227.974905)
			(xy 366.133067 -227.974905) (xy 366.081772 -227.96678) (xy 366.032379 -227.950732) (xy 365.986105 -227.927154)
			(xy 365.944089 -227.896628) (xy 365.907366 -227.859905) (xy 365.87684 -227.817889) (xy 365.853262 -227.771615)
			(xy 365.837214 -227.722222) (xy 365.829089 -227.670927) (xy 365.549179 -227.670927) (xy 365.541054 -227.722222)
			(xy 365.525006 -227.771615) (xy 365.501428 -227.817889) (xy 365.470902 -227.859905) (xy 365.434179 -227.896628)
			(xy 365.392163 -227.927154) (xy 365.345889 -227.950732) (xy 365.296496 -227.96678) (xy 365.245201 -227.974905)
			(xy 365.193267 -227.974905) (xy 365.141972 -227.96678) (xy 365.092579 -227.950732) (xy 365.046305 -227.927154)
			(xy 365.004289 -227.896628) (xy 364.967566 -227.859905) (xy 364.93704 -227.817889) (xy 364.913462 -227.771615)
			(xy 364.897414 -227.722222) (xy 364.889289 -227.670927) (xy 364.609379 -227.670927) (xy 364.601254 -227.722222)
			(xy 364.585206 -227.771615) (xy 364.561628 -227.817889) (xy 364.531102 -227.859905) (xy 364.494379 -227.896628)
			(xy 364.452363 -227.927154) (xy 364.406089 -227.950732) (xy 364.356696 -227.96678) (xy 364.305401 -227.974905)
			(xy 364.253467 -227.974905) (xy 364.202172 -227.96678) (xy 364.152779 -227.950732) (xy 364.106505 -227.927154)
			(xy 364.064489 -227.896628) (xy 364.027766 -227.859905) (xy 363.99724 -227.817889) (xy 363.973662 -227.771615)
			(xy 363.957614 -227.722222) (xy 363.949489 -227.670927) (xy 363.669579 -227.670927) (xy 363.661454 -227.722222)
			(xy 363.645406 -227.771615) (xy 363.621828 -227.817889) (xy 363.591302 -227.859905) (xy 363.554579 -227.896628)
			(xy 363.512563 -227.927154) (xy 363.466289 -227.950732) (xy 363.416896 -227.96678) (xy 363.365601 -227.974905)
			(xy 363.313667 -227.974905) (xy 363.262372 -227.96678) (xy 363.212979 -227.950732) (xy 363.166705 -227.927154)
			(xy 363.124689 -227.896628) (xy 363.087966 -227.859905) (xy 363.05744 -227.817889) (xy 363.033862 -227.771615)
			(xy 363.017814 -227.722222) (xy 363.009689 -227.670927) (xy 362.730033 -227.670927) (xy 362.721908 -227.722222)
			(xy 362.70586 -227.771615) (xy 362.682282 -227.817889) (xy 362.651756 -227.859905) (xy 362.615033 -227.896628)
			(xy 362.573017 -227.927154) (xy 362.526743 -227.950732) (xy 362.47735 -227.96678) (xy 362.426055 -227.974905)
			(xy 362.374121 -227.974905) (xy 362.322826 -227.96678) (xy 362.273433 -227.950732) (xy 362.227159 -227.927154)
			(xy 362.185143 -227.896628) (xy 362.14842 -227.859905) (xy 362.117894 -227.817889) (xy 362.094316 -227.771615)
			(xy 362.078268 -227.722222) (xy 362.070143 -227.670927) (xy 361.789979 -227.670927) (xy 361.781854 -227.722222)
			(xy 361.765806 -227.771615) (xy 361.742228 -227.817889) (xy 361.711702 -227.859905) (xy 361.674979 -227.896628)
			(xy 361.632963 -227.927154) (xy 361.586689 -227.950732) (xy 361.537296 -227.96678) (xy 361.486001 -227.974905)
			(xy 361.434067 -227.974905) (xy 361.382772 -227.96678) (xy 361.333379 -227.950732) (xy 361.287105 -227.927154)
			(xy 361.245089 -227.896628) (xy 361.208366 -227.859905) (xy 361.17784 -227.817889) (xy 361.154262 -227.771615)
			(xy 361.138214 -227.722222) (xy 361.130089 -227.670927) (xy 360.850179 -227.670927) (xy 360.842054 -227.722222)
			(xy 360.826006 -227.771615) (xy 360.802428 -227.817889) (xy 360.771902 -227.859905) (xy 360.735179 -227.896628)
			(xy 360.693163 -227.927154) (xy 360.646889 -227.950732) (xy 360.597496 -227.96678) (xy 360.546201 -227.974905)
			(xy 360.494267 -227.974905) (xy 360.442972 -227.96678) (xy 360.393579 -227.950732) (xy 360.347305 -227.927154)
			(xy 360.305289 -227.896628) (xy 360.268566 -227.859905) (xy 360.23804 -227.817889) (xy 360.214462 -227.771615)
			(xy 360.198414 -227.722222) (xy 360.190289 -227.670927) (xy 359.910379 -227.670927) (xy 359.902254 -227.722222)
			(xy 359.886206 -227.771615) (xy 359.862628 -227.817889) (xy 359.832102 -227.859905) (xy 359.795379 -227.896628)
			(xy 359.753363 -227.927154) (xy 359.707089 -227.950732) (xy 359.657696 -227.96678) (xy 359.606401 -227.974905)
			(xy 359.554467 -227.974905) (xy 359.503172 -227.96678) (xy 359.453779 -227.950732) (xy 359.407505 -227.927154)
			(xy 359.365489 -227.896628) (xy 359.328766 -227.859905) (xy 359.29824 -227.817889) (xy 359.274662 -227.771615)
			(xy 359.258614 -227.722222) (xy 359.250489 -227.670927) (xy 358.970579 -227.670927) (xy 358.962454 -227.722222)
			(xy 358.946406 -227.771615) (xy 358.922828 -227.817889) (xy 358.892302 -227.859905) (xy 358.855579 -227.896628)
			(xy 358.813563 -227.927154) (xy 358.767289 -227.950732) (xy 358.717896 -227.96678) (xy 358.666601 -227.974905)
			(xy 358.614667 -227.974905) (xy 358.563372 -227.96678) (xy 358.513979 -227.950732) (xy 358.467705 -227.927154)
			(xy 358.425689 -227.896628) (xy 358.388966 -227.859905) (xy 358.35844 -227.817889) (xy 358.334862 -227.771615)
			(xy 358.318814 -227.722222) (xy 358.310689 -227.670927) (xy 358.030779 -227.670927) (xy 358.022654 -227.722222)
			(xy 358.006606 -227.771615) (xy 357.983028 -227.817889) (xy 357.952502 -227.859905) (xy 357.915779 -227.896628)
			(xy 357.873763 -227.927154) (xy 357.827489 -227.950732) (xy 357.778096 -227.96678) (xy 357.726801 -227.974905)
			(xy 357.674867 -227.974905) (xy 357.623572 -227.96678) (xy 357.574179 -227.950732) (xy 357.527905 -227.927154)
			(xy 357.485889 -227.896628) (xy 357.449166 -227.859905) (xy 357.41864 -227.817889) (xy 357.395062 -227.771615)
			(xy 357.379014 -227.722222) (xy 357.370889 -227.670927) (xy 357.090979 -227.670927) (xy 357.082854 -227.722222)
			(xy 357.066806 -227.771615) (xy 357.043228 -227.817889) (xy 357.012702 -227.859905) (xy 356.975979 -227.896628)
			(xy 356.933963 -227.927154) (xy 356.887689 -227.950732) (xy 356.838296 -227.96678) (xy 356.787001 -227.974905)
			(xy 356.735067 -227.974905) (xy 356.683772 -227.96678) (xy 356.634379 -227.950732) (xy 356.588105 -227.927154)
			(xy 356.546089 -227.896628) (xy 356.509366 -227.859905) (xy 356.47884 -227.817889) (xy 356.455262 -227.771615)
			(xy 356.439214 -227.722222) (xy 356.431089 -227.670927) (xy 356.151179 -227.670927) (xy 356.143054 -227.722222)
			(xy 356.127006 -227.771615) (xy 356.103428 -227.817889) (xy 356.072902 -227.859905) (xy 356.036179 -227.896628)
			(xy 355.994163 -227.927154) (xy 355.947889 -227.950732) (xy 355.898496 -227.96678) (xy 355.847201 -227.974905)
			(xy 355.795267 -227.974905) (xy 355.743972 -227.96678) (xy 355.694579 -227.950732) (xy 355.648305 -227.927154)
			(xy 355.606289 -227.896628) (xy 355.569566 -227.859905) (xy 355.53904 -227.817889) (xy 355.515462 -227.771615)
			(xy 355.499414 -227.722222) (xy 355.491289 -227.670927) (xy 355.211379 -227.670927) (xy 355.203254 -227.722222)
			(xy 355.187206 -227.771615) (xy 355.163628 -227.817889) (xy 355.133102 -227.859905) (xy 355.096379 -227.896628)
			(xy 355.054363 -227.927154) (xy 355.008089 -227.950732) (xy 354.958696 -227.96678) (xy 354.907401 -227.974905)
			(xy 354.855467 -227.974905) (xy 354.804172 -227.96678) (xy 354.754779 -227.950732) (xy 354.708505 -227.927154)
			(xy 354.666489 -227.896628) (xy 354.629766 -227.859905) (xy 354.59924 -227.817889) (xy 354.575662 -227.771615)
			(xy 354.559614 -227.722222) (xy 354.551489 -227.670927) (xy 354.271579 -227.670927) (xy 354.263454 -227.722222)
			(xy 354.247406 -227.771615) (xy 354.223828 -227.817889) (xy 354.193302 -227.859905) (xy 354.156579 -227.896628)
			(xy 354.114563 -227.927154) (xy 354.068289 -227.950732) (xy 354.018896 -227.96678) (xy 353.967601 -227.974905)
			(xy 353.915667 -227.974905) (xy 353.864372 -227.96678) (xy 353.814979 -227.950732) (xy 353.768705 -227.927154)
			(xy 353.726689 -227.896628) (xy 353.689966 -227.859905) (xy 353.65944 -227.817889) (xy 353.635862 -227.771615)
			(xy 353.619814 -227.722222) (xy 353.611689 -227.670927) (xy 353.331779 -227.670927) (xy 353.323654 -227.722222)
			(xy 353.307606 -227.771615) (xy 353.284028 -227.817889) (xy 353.253502 -227.859905) (xy 353.216779 -227.896628)
			(xy 353.174763 -227.927154) (xy 353.128489 -227.950732) (xy 353.079096 -227.96678) (xy 353.027801 -227.974905)
			(xy 352.975867 -227.974905) (xy 352.924572 -227.96678) (xy 352.875179 -227.950732) (xy 352.828905 -227.927154)
			(xy 352.786889 -227.896628) (xy 352.750166 -227.859905) (xy 352.71964 -227.817889) (xy 352.696062 -227.771615)
			(xy 352.680014 -227.722222) (xy 352.671889 -227.670927) (xy 352.391979 -227.670927) (xy 352.383854 -227.722222)
			(xy 352.367806 -227.771615) (xy 352.344228 -227.817889) (xy 352.313702 -227.859905) (xy 352.276979 -227.896628)
			(xy 352.234963 -227.927154) (xy 352.188689 -227.950732) (xy 352.139296 -227.96678) (xy 352.088001 -227.974905)
			(xy 352.036067 -227.974905) (xy 351.984772 -227.96678) (xy 351.935379 -227.950732) (xy 351.889105 -227.927154)
			(xy 351.847089 -227.896628) (xy 351.810366 -227.859905) (xy 351.77984 -227.817889) (xy 351.756262 -227.771615)
			(xy 351.740214 -227.722222) (xy 351.732089 -227.670927) (xy 350.752664 -227.670927) (xy 350.752664 -228.142546)
			(xy 350.783398 -228.155754) (xy 350.808374 -228.16716) (xy 350.85446 -228.197002) (xy 350.89498 -228.234051)
			(xy 350.928818 -228.277287) (xy 350.955046 -228.325522) (xy 350.97294 -228.377428) (xy 350.98201 -228.431578)
			(xy 350.982534 -228.45903) (xy 350.982021 -228.485251) (xy 351.262189 -228.485251) (xy 351.262189 -228.433317)
			(xy 351.270314 -228.382022) (xy 351.286362 -228.332629) (xy 351.30994 -228.286355) (xy 351.340466 -228.244339)
			(xy 351.377189 -228.207616) (xy 351.419205 -228.17709) (xy 351.465479 -228.153512) (xy 351.514872 -228.137464)
			(xy 351.566167 -228.129339) (xy 351.618101 -228.129339) (xy 351.669396 -228.137464) (xy 351.718789 -228.153512)
			(xy 351.765063 -228.17709) (xy 351.807079 -228.207616) (xy 351.843802 -228.244339) (xy 351.874328 -228.286355)
			(xy 351.897906 -228.332629) (xy 351.913954 -228.382022) (xy 351.922079 -228.433317) (xy 351.922588 -228.459284)
			(xy 351.922084 -228.484997) (xy 352.201735 -228.484997) (xy 352.201735 -228.433063) (xy 352.20986 -228.381768)
			(xy 352.225908 -228.332375) (xy 352.249486 -228.286101) (xy 352.280012 -228.244085) (xy 352.316735 -228.207362)
			(xy 352.358751 -228.176836) (xy 352.405025 -228.153258) (xy 352.454418 -228.13721) (xy 352.505713 -228.129085)
			(xy 352.557647 -228.129085) (xy 352.608942 -228.13721) (xy 352.658335 -228.153258) (xy 352.704609 -228.176836)
			(xy 352.746625 -228.207362) (xy 352.783348 -228.244085) (xy 352.813874 -228.286101) (xy 352.837452 -228.332375)
			(xy 352.8535 -228.381768) (xy 352.861625 -228.433063) (xy 352.862134 -228.45903) (xy 352.861625 -228.484997)
			(xy 353.141535 -228.484997) (xy 353.141535 -228.433063) (xy 353.14966 -228.381768) (xy 353.165708 -228.332375)
			(xy 353.189286 -228.286101) (xy 353.219812 -228.244085) (xy 353.256535 -228.207362) (xy 353.298551 -228.176836)
			(xy 353.344825 -228.153258) (xy 353.394218 -228.13721) (xy 353.445513 -228.129085) (xy 353.497447 -228.129085)
			(xy 353.548742 -228.13721) (xy 353.598135 -228.153258) (xy 353.644409 -228.176836) (xy 353.686425 -228.207362)
			(xy 353.723148 -228.244085) (xy 353.753674 -228.286101) (xy 353.777252 -228.332375) (xy 353.7933 -228.381768)
			(xy 353.801425 -228.433063) (xy 353.801934 -228.45903) (xy 353.801425 -228.484997) (xy 354.081335 -228.484997)
			(xy 354.081335 -228.433063) (xy 354.08946 -228.381768) (xy 354.105508 -228.332375) (xy 354.129086 -228.286101)
			(xy 354.159612 -228.244085) (xy 354.196335 -228.207362) (xy 354.238351 -228.176836) (xy 354.284625 -228.153258)
			(xy 354.334018 -228.13721) (xy 354.385313 -228.129085) (xy 354.437247 -228.129085) (xy 354.488542 -228.13721)
			(xy 354.537935 -228.153258) (xy 354.584209 -228.176836) (xy 354.626225 -228.207362) (xy 354.662948 -228.244085)
			(xy 354.693474 -228.286101) (xy 354.717052 -228.332375) (xy 354.7331 -228.381768) (xy 354.741225 -228.433063)
			(xy 354.741734 -228.45903) (xy 354.741225 -228.484997) (xy 355.021135 -228.484997) (xy 355.021135 -228.433063)
			(xy 355.02926 -228.381768) (xy 355.045308 -228.332375) (xy 355.068886 -228.286101) (xy 355.099412 -228.244085)
			(xy 355.136135 -228.207362) (xy 355.178151 -228.176836) (xy 355.224425 -228.153258) (xy 355.273818 -228.13721)
			(xy 355.325113 -228.129085) (xy 355.377047 -228.129085) (xy 355.428342 -228.13721) (xy 355.477735 -228.153258)
			(xy 355.524009 -228.176836) (xy 355.566025 -228.207362) (xy 355.602748 -228.244085) (xy 355.633274 -228.286101)
			(xy 355.656852 -228.332375) (xy 355.6729 -228.381768) (xy 355.681025 -228.433063) (xy 355.681534 -228.45903)
			(xy 355.681025 -228.484997) (xy 355.960935 -228.484997) (xy 355.960935 -228.433063) (xy 355.96906 -228.381768)
			(xy 355.985108 -228.332375) (xy 356.008686 -228.286101) (xy 356.039212 -228.244085) (xy 356.075935 -228.207362)
			(xy 356.117951 -228.176836) (xy 356.164225 -228.153258) (xy 356.213618 -228.13721) (xy 356.264913 -228.129085)
			(xy 356.316847 -228.129085) (xy 356.368142 -228.13721) (xy 356.417535 -228.153258) (xy 356.463809 -228.176836)
			(xy 356.505825 -228.207362) (xy 356.542548 -228.244085) (xy 356.573074 -228.286101) (xy 356.596652 -228.332375)
			(xy 356.6127 -228.381768) (xy 356.620825 -228.433063) (xy 356.621334 -228.45903) (xy 356.620825 -228.484997)
			(xy 356.900735 -228.484997) (xy 356.900735 -228.433063) (xy 356.90886 -228.381768) (xy 356.924908 -228.332375)
			(xy 356.948486 -228.286101) (xy 356.979012 -228.244085) (xy 357.015735 -228.207362) (xy 357.057751 -228.176836)
			(xy 357.104025 -228.153258) (xy 357.153418 -228.13721) (xy 357.204713 -228.129085) (xy 357.256647 -228.129085)
			(xy 357.307942 -228.13721) (xy 357.357335 -228.153258) (xy 357.403609 -228.176836) (xy 357.445625 -228.207362)
			(xy 357.482348 -228.244085) (xy 357.512874 -228.286101) (xy 357.536452 -228.332375) (xy 357.5525 -228.381768)
			(xy 357.560625 -228.433063) (xy 357.561134 -228.45903) (xy 357.560625 -228.484997) (xy 357.840535 -228.484997)
			(xy 357.840535 -228.433063) (xy 357.84866 -228.381768) (xy 357.864708 -228.332375) (xy 357.888286 -228.286101)
			(xy 357.918812 -228.244085) (xy 357.955535 -228.207362) (xy 357.997551 -228.176836) (xy 358.043825 -228.153258)
			(xy 358.093218 -228.13721) (xy 358.144513 -228.129085) (xy 358.196447 -228.129085) (xy 358.247742 -228.13721)
			(xy 358.297135 -228.153258) (xy 358.343409 -228.176836) (xy 358.385425 -228.207362) (xy 358.422148 -228.244085)
			(xy 358.452674 -228.286101) (xy 358.476252 -228.332375) (xy 358.4923 -228.381768) (xy 358.500425 -228.433063)
			(xy 358.500934 -228.45903) (xy 358.500425 -228.484997) (xy 358.780589 -228.484997) (xy 358.780589 -228.433063)
			(xy 358.788714 -228.381768) (xy 358.804762 -228.332375) (xy 358.82834 -228.286101) (xy 358.858866 -228.244085)
			(xy 358.895589 -228.207362) (xy 358.937605 -228.176836) (xy 358.983879 -228.153258) (xy 359.033272 -228.13721)
			(xy 359.084567 -228.129085) (xy 359.136501 -228.129085) (xy 359.187796 -228.13721) (xy 359.237189 -228.153258)
			(xy 359.283463 -228.176836) (xy 359.325479 -228.207362) (xy 359.362202 -228.244085) (xy 359.392728 -228.286101)
			(xy 359.416306 -228.332375) (xy 359.432354 -228.381768) (xy 359.440479 -228.433063) (xy 359.440988 -228.45903)
			(xy 359.440479 -228.484997) (xy 359.720135 -228.484997) (xy 359.720135 -228.433063) (xy 359.72826 -228.381768)
			(xy 359.744308 -228.332375) (xy 359.767886 -228.286101) (xy 359.798412 -228.244085) (xy 359.835135 -228.207362)
			(xy 359.877151 -228.176836) (xy 359.923425 -228.153258) (xy 359.972818 -228.13721) (xy 360.024113 -228.129085)
			(xy 360.076047 -228.129085) (xy 360.127342 -228.13721) (xy 360.176735 -228.153258) (xy 360.223009 -228.176836)
			(xy 360.265025 -228.207362) (xy 360.301748 -228.244085) (xy 360.332274 -228.286101) (xy 360.355852 -228.332375)
			(xy 360.3719 -228.381768) (xy 360.380025 -228.433063) (xy 360.380534 -228.45903) (xy 360.380025 -228.484997)
			(xy 360.659935 -228.484997) (xy 360.659935 -228.433063) (xy 360.66806 -228.381768) (xy 360.684108 -228.332375)
			(xy 360.707686 -228.286101) (xy 360.738212 -228.244085) (xy 360.774935 -228.207362) (xy 360.816951 -228.176836)
			(xy 360.863225 -228.153258) (xy 360.912618 -228.13721) (xy 360.963913 -228.129085) (xy 361.015847 -228.129085)
			(xy 361.067142 -228.13721) (xy 361.116535 -228.153258) (xy 361.162809 -228.176836) (xy 361.204825 -228.207362)
			(xy 361.241548 -228.244085) (xy 361.272074 -228.286101) (xy 361.295652 -228.332375) (xy 361.3117 -228.381768)
			(xy 361.319825 -228.433063) (xy 361.320334 -228.45903) (xy 361.319825 -228.484997) (xy 361.599735 -228.484997)
			(xy 361.599735 -228.433063) (xy 361.60786 -228.381768) (xy 361.623908 -228.332375) (xy 361.647486 -228.286101)
			(xy 361.678012 -228.244085) (xy 361.714735 -228.207362) (xy 361.756751 -228.176836) (xy 361.803025 -228.153258)
			(xy 361.852418 -228.13721) (xy 361.903713 -228.129085) (xy 361.955647 -228.129085) (xy 362.006942 -228.13721)
			(xy 362.056335 -228.153258) (xy 362.102609 -228.176836) (xy 362.144625 -228.207362) (xy 362.181348 -228.244085)
			(xy 362.211874 -228.286101) (xy 362.235452 -228.332375) (xy 362.2515 -228.381768) (xy 362.259625 -228.433063)
			(xy 362.260134 -228.45903) (xy 362.259625 -228.484997) (xy 363.479335 -228.484997) (xy 363.479335 -228.433063)
			(xy 363.48746 -228.381768) (xy 363.503508 -228.332375) (xy 363.527086 -228.286101) (xy 363.557612 -228.244085)
			(xy 363.594335 -228.207362) (xy 363.636351 -228.176836) (xy 363.682625 -228.153258) (xy 363.732018 -228.13721)
			(xy 363.783313 -228.129085) (xy 363.835247 -228.129085) (xy 363.886542 -228.13721) (xy 363.935935 -228.153258)
			(xy 363.982209 -228.176836) (xy 364.024225 -228.207362) (xy 364.060948 -228.244085) (xy 364.091474 -228.286101)
			(xy 364.115052 -228.332375) (xy 364.1311 -228.381768) (xy 364.139225 -228.433063) (xy 364.139734 -228.45903)
			(xy 364.139225 -228.484997) (xy 365.358935 -228.484997) (xy 365.358935 -228.433063) (xy 365.36706 -228.381768)
			(xy 365.383108 -228.332375) (xy 365.406686 -228.286101) (xy 365.437212 -228.244085) (xy 365.473935 -228.207362)
			(xy 365.515951 -228.176836) (xy 365.562225 -228.153258) (xy 365.611618 -228.13721) (xy 365.662913 -228.129085)
			(xy 365.714847 -228.129085) (xy 365.766142 -228.13721) (xy 365.815535 -228.153258) (xy 365.861809 -228.176836)
			(xy 365.903825 -228.207362) (xy 365.940548 -228.244085) (xy 365.971074 -228.286101) (xy 365.994652 -228.332375)
			(xy 366.0107 -228.381768) (xy 366.018825 -228.433063) (xy 366.019334 -228.45903) (xy 366.018825 -228.484997)
			(xy 367.238535 -228.484997) (xy 367.238535 -228.433063) (xy 367.24666 -228.381768) (xy 367.262708 -228.332375)
			(xy 367.286286 -228.286101) (xy 367.316812 -228.244085) (xy 367.353535 -228.207362) (xy 367.395551 -228.176836)
			(xy 367.441825 -228.153258) (xy 367.491218 -228.13721) (xy 367.542513 -228.129085) (xy 367.594447 -228.129085)
			(xy 367.645742 -228.13721) (xy 367.695135 -228.153258) (xy 367.741409 -228.176836) (xy 367.783425 -228.207362)
			(xy 367.820148 -228.244085) (xy 367.850674 -228.286101) (xy 367.874252 -228.332375) (xy 367.8903 -228.381768)
			(xy 367.898425 -228.433063) (xy 367.898934 -228.45903) (xy 367.898425 -228.484997) (xy 368.178335 -228.484997)
			(xy 368.178335 -228.433063) (xy 368.18646 -228.381768) (xy 368.202508 -228.332375) (xy 368.226086 -228.286101)
			(xy 368.256612 -228.244085) (xy 368.293335 -228.207362) (xy 368.335351 -228.176836) (xy 368.381625 -228.153258)
			(xy 368.431018 -228.13721) (xy 368.482313 -228.129085) (xy 368.534247 -228.129085) (xy 368.585542 -228.13721)
			(xy 368.634935 -228.153258) (xy 368.681209 -228.176836) (xy 368.723225 -228.207362) (xy 368.759948 -228.244085)
			(xy 368.790474 -228.286101) (xy 368.814052 -228.332375) (xy 368.8301 -228.381768) (xy 368.838225 -228.433063)
			(xy 368.838734 -228.45903) (xy 368.838225 -228.484997) (xy 369.118135 -228.484997) (xy 369.118135 -228.433063)
			(xy 369.12626 -228.381768) (xy 369.142308 -228.332375) (xy 369.165886 -228.286101) (xy 369.196412 -228.244085)
			(xy 369.233135 -228.207362) (xy 369.275151 -228.176836) (xy 369.321425 -228.153258) (xy 369.370818 -228.13721)
			(xy 369.422113 -228.129085) (xy 369.474047 -228.129085) (xy 369.525342 -228.13721) (xy 369.574735 -228.153258)
			(xy 369.621009 -228.176836) (xy 369.663025 -228.207362) (xy 369.699748 -228.244085) (xy 369.730274 -228.286101)
			(xy 369.753852 -228.332375) (xy 369.7699 -228.381768) (xy 369.778025 -228.433063) (xy 369.778534 -228.45903)
			(xy 369.778025 -228.484997) (xy 370.057935 -228.484997) (xy 370.057935 -228.433063) (xy 370.06606 -228.381768)
			(xy 370.082108 -228.332375) (xy 370.105686 -228.286101) (xy 370.136212 -228.244085) (xy 370.172935 -228.207362)
			(xy 370.214951 -228.176836) (xy 370.261225 -228.153258) (xy 370.310618 -228.13721) (xy 370.361913 -228.129085)
			(xy 370.413847 -228.129085) (xy 370.465142 -228.13721) (xy 370.514535 -228.153258) (xy 370.560809 -228.176836)
			(xy 370.602825 -228.207362) (xy 370.639548 -228.244085) (xy 370.670074 -228.286101) (xy 370.693652 -228.332375)
			(xy 370.7097 -228.381768) (xy 370.717825 -228.433063) (xy 370.718334 -228.45903) (xy 370.717825 -228.484997)
			(xy 370.997735 -228.484997) (xy 370.997735 -228.433063) (xy 371.00586 -228.381768) (xy 371.021908 -228.332375)
			(xy 371.045486 -228.286101) (xy 371.076012 -228.244085) (xy 371.112735 -228.207362) (xy 371.154751 -228.176836)
			(xy 371.201025 -228.153258) (xy 371.250418 -228.13721) (xy 371.301713 -228.129085) (xy 371.353647 -228.129085)
			(xy 371.404942 -228.13721) (xy 371.454335 -228.153258) (xy 371.500609 -228.176836) (xy 371.542625 -228.207362)
			(xy 371.579348 -228.244085) (xy 371.609874 -228.286101) (xy 371.633452 -228.332375) (xy 371.6495 -228.381768)
			(xy 371.657625 -228.433063) (xy 371.658134 -228.45903) (xy 371.657625 -228.484997) (xy 371.937535 -228.484997)
			(xy 371.937535 -228.433063) (xy 371.94566 -228.381768) (xy 371.961708 -228.332375) (xy 371.985286 -228.286101)
			(xy 372.015812 -228.244085) (xy 372.052535 -228.207362) (xy 372.094551 -228.176836) (xy 372.140825 -228.153258)
			(xy 372.190218 -228.13721) (xy 372.241513 -228.129085) (xy 372.293447 -228.129085) (xy 372.344742 -228.13721)
			(xy 372.394135 -228.153258) (xy 372.440409 -228.176836) (xy 372.482425 -228.207362) (xy 372.519148 -228.244085)
			(xy 372.549674 -228.286101) (xy 372.573252 -228.332375) (xy 372.5893 -228.381768) (xy 372.597425 -228.433063)
			(xy 372.597934 -228.45903) (xy 372.597425 -228.484997) (xy 372.877335 -228.484997) (xy 372.877335 -228.433063)
			(xy 372.88546 -228.381768) (xy 372.901508 -228.332375) (xy 372.925086 -228.286101) (xy 372.955612 -228.244085)
			(xy 372.992335 -228.207362) (xy 373.034351 -228.176836) (xy 373.080625 -228.153258) (xy 373.130018 -228.13721)
			(xy 373.181313 -228.129085) (xy 373.233247 -228.129085) (xy 373.284542 -228.13721) (xy 373.333935 -228.153258)
			(xy 373.380209 -228.176836) (xy 373.422225 -228.207362) (xy 373.458948 -228.244085) (xy 373.489474 -228.286101)
			(xy 373.513052 -228.332375) (xy 373.5291 -228.381768) (xy 373.537225 -228.433063) (xy 373.537734 -228.45903)
			(xy 373.537225 -228.484997) (xy 373.817389 -228.484997) (xy 373.817389 -228.433063) (xy 373.825514 -228.381768)
			(xy 373.841562 -228.332375) (xy 373.86514 -228.286101) (xy 373.895666 -228.244085) (xy 373.932389 -228.207362)
			(xy 373.974405 -228.176836) (xy 374.020679 -228.153258) (xy 374.070072 -228.13721) (xy 374.121367 -228.129085)
			(xy 374.173301 -228.129085) (xy 374.224596 -228.13721) (xy 374.273989 -228.153258) (xy 374.320263 -228.176836)
			(xy 374.362279 -228.207362) (xy 374.399002 -228.244085) (xy 374.429528 -228.286101) (xy 374.453106 -228.332375)
			(xy 374.469154 -228.381768) (xy 374.477279 -228.433063) (xy 374.477788 -228.45903) (xy 374.477279 -228.484997)
			(xy 374.469154 -228.536292) (xy 374.453106 -228.585685) (xy 374.429528 -228.631959) (xy 374.399002 -228.673975)
			(xy 374.362279 -228.710698) (xy 374.320263 -228.741224) (xy 374.273989 -228.764802) (xy 374.224596 -228.78085)
			(xy 374.173301 -228.788975) (xy 374.121367 -228.788975) (xy 374.070072 -228.78085) (xy 374.020679 -228.764802)
			(xy 373.974405 -228.741224) (xy 373.932389 -228.710698) (xy 373.895666 -228.673975) (xy 373.86514 -228.631959)
			(xy 373.841562 -228.585685) (xy 373.825514 -228.536292) (xy 373.817389 -228.484997) (xy 373.537225 -228.484997)
			(xy 373.5291 -228.536292) (xy 373.513052 -228.585685) (xy 373.489474 -228.631959) (xy 373.458948 -228.673975)
			(xy 373.422225 -228.710698) (xy 373.380209 -228.741224) (xy 373.333935 -228.764802) (xy 373.284542 -228.78085)
			(xy 373.233247 -228.788975) (xy 373.181313 -228.788975) (xy 373.130018 -228.78085) (xy 373.080625 -228.764802)
			(xy 373.034351 -228.741224) (xy 372.992335 -228.710698) (xy 372.955612 -228.673975) (xy 372.925086 -228.631959)
			(xy 372.901508 -228.585685) (xy 372.88546 -228.536292) (xy 372.877335 -228.484997) (xy 372.597425 -228.484997)
			(xy 372.5893 -228.536292) (xy 372.573252 -228.585685) (xy 372.549674 -228.631959) (xy 372.519148 -228.673975)
			(xy 372.482425 -228.710698) (xy 372.440409 -228.741224) (xy 372.394135 -228.764802) (xy 372.344742 -228.78085)
			(xy 372.293447 -228.788975) (xy 372.241513 -228.788975) (xy 372.190218 -228.78085) (xy 372.140825 -228.764802)
			(xy 372.094551 -228.741224) (xy 372.052535 -228.710698) (xy 372.015812 -228.673975) (xy 371.985286 -228.631959)
			(xy 371.961708 -228.585685) (xy 371.94566 -228.536292) (xy 371.937535 -228.484997) (xy 371.657625 -228.484997)
			(xy 371.6495 -228.536292) (xy 371.633452 -228.585685) (xy 371.609874 -228.631959) (xy 371.579348 -228.673975)
			(xy 371.542625 -228.710698) (xy 371.500609 -228.741224) (xy 371.454335 -228.764802) (xy 371.404942 -228.78085)
			(xy 371.353647 -228.788975) (xy 371.301713 -228.788975) (xy 371.250418 -228.78085) (xy 371.201025 -228.764802)
			(xy 371.154751 -228.741224) (xy 371.112735 -228.710698) (xy 371.076012 -228.673975) (xy 371.045486 -228.631959)
			(xy 371.021908 -228.585685) (xy 371.00586 -228.536292) (xy 370.997735 -228.484997) (xy 370.717825 -228.484997)
			(xy 370.7097 -228.536292) (xy 370.693652 -228.585685) (xy 370.670074 -228.631959) (xy 370.639548 -228.673975)
			(xy 370.602825 -228.710698) (xy 370.560809 -228.741224) (xy 370.514535 -228.764802) (xy 370.465142 -228.78085)
			(xy 370.413847 -228.788975) (xy 370.361913 -228.788975) (xy 370.310618 -228.78085) (xy 370.261225 -228.764802)
			(xy 370.214951 -228.741224) (xy 370.172935 -228.710698) (xy 370.136212 -228.673975) (xy 370.105686 -228.631959)
			(xy 370.082108 -228.585685) (xy 370.06606 -228.536292) (xy 370.057935 -228.484997) (xy 369.778025 -228.484997)
			(xy 369.7699 -228.536292) (xy 369.753852 -228.585685) (xy 369.730274 -228.631959) (xy 369.699748 -228.673975)
			(xy 369.663025 -228.710698) (xy 369.621009 -228.741224) (xy 369.574735 -228.764802) (xy 369.525342 -228.78085)
			(xy 369.474047 -228.788975) (xy 369.422113 -228.788975) (xy 369.370818 -228.78085) (xy 369.321425 -228.764802)
			(xy 369.275151 -228.741224) (xy 369.233135 -228.710698) (xy 369.196412 -228.673975) (xy 369.165886 -228.631959)
			(xy 369.142308 -228.585685) (xy 369.12626 -228.536292) (xy 369.118135 -228.484997) (xy 368.838225 -228.484997)
			(xy 368.8301 -228.536292) (xy 368.814052 -228.585685) (xy 368.790474 -228.631959) (xy 368.759948 -228.673975)
			(xy 368.723225 -228.710698) (xy 368.681209 -228.741224) (xy 368.634935 -228.764802) (xy 368.585542 -228.78085)
			(xy 368.534247 -228.788975) (xy 368.482313 -228.788975) (xy 368.431018 -228.78085) (xy 368.381625 -228.764802)
			(xy 368.335351 -228.741224) (xy 368.293335 -228.710698) (xy 368.256612 -228.673975) (xy 368.226086 -228.631959)
			(xy 368.202508 -228.585685) (xy 368.18646 -228.536292) (xy 368.178335 -228.484997) (xy 367.898425 -228.484997)
			(xy 367.8903 -228.536292) (xy 367.874252 -228.585685) (xy 367.850674 -228.631959) (xy 367.820148 -228.673975)
			(xy 367.783425 -228.710698) (xy 367.741409 -228.741224) (xy 367.695135 -228.764802) (xy 367.645742 -228.78085)
			(xy 367.594447 -228.788975) (xy 367.542513 -228.788975) (xy 367.491218 -228.78085) (xy 367.441825 -228.764802)
			(xy 367.395551 -228.741224) (xy 367.353535 -228.710698) (xy 367.316812 -228.673975) (xy 367.286286 -228.631959)
			(xy 367.262708 -228.585685) (xy 367.24666 -228.536292) (xy 367.238535 -228.484997) (xy 366.018825 -228.484997)
			(xy 366.0107 -228.536292) (xy 365.994652 -228.585685) (xy 365.971074 -228.631959) (xy 365.940548 -228.673975)
			(xy 365.903825 -228.710698) (xy 365.861809 -228.741224) (xy 365.815535 -228.764802) (xy 365.766142 -228.78085)
			(xy 365.714847 -228.788975) (xy 365.662913 -228.788975) (xy 365.611618 -228.78085) (xy 365.562225 -228.764802)
			(xy 365.515951 -228.741224) (xy 365.473935 -228.710698) (xy 365.437212 -228.673975) (xy 365.406686 -228.631959)
			(xy 365.383108 -228.585685) (xy 365.36706 -228.536292) (xy 365.358935 -228.484997) (xy 364.139225 -228.484997)
			(xy 364.1311 -228.536292) (xy 364.115052 -228.585685) (xy 364.091474 -228.631959) (xy 364.060948 -228.673975)
			(xy 364.024225 -228.710698) (xy 363.982209 -228.741224) (xy 363.935935 -228.764802) (xy 363.886542 -228.78085)
			(xy 363.835247 -228.788975) (xy 363.783313 -228.788975) (xy 363.732018 -228.78085) (xy 363.682625 -228.764802)
			(xy 363.636351 -228.741224) (xy 363.594335 -228.710698) (xy 363.557612 -228.673975) (xy 363.527086 -228.631959)
			(xy 363.503508 -228.585685) (xy 363.48746 -228.536292) (xy 363.479335 -228.484997) (xy 362.259625 -228.484997)
			(xy 362.2515 -228.536292) (xy 362.235452 -228.585685) (xy 362.211874 -228.631959) (xy 362.181348 -228.673975)
			(xy 362.144625 -228.710698) (xy 362.102609 -228.741224) (xy 362.056335 -228.764802) (xy 362.006942 -228.78085)
			(xy 361.955647 -228.788975) (xy 361.903713 -228.788975) (xy 361.852418 -228.78085) (xy 361.803025 -228.764802)
			(xy 361.756751 -228.741224) (xy 361.714735 -228.710698) (xy 361.678012 -228.673975) (xy 361.647486 -228.631959)
			(xy 361.623908 -228.585685) (xy 361.60786 -228.536292) (xy 361.599735 -228.484997) (xy 361.319825 -228.484997)
			(xy 361.3117 -228.536292) (xy 361.295652 -228.585685) (xy 361.272074 -228.631959) (xy 361.241548 -228.673975)
			(xy 361.204825 -228.710698) (xy 361.162809 -228.741224) (xy 361.116535 -228.764802) (xy 361.067142 -228.78085)
			(xy 361.015847 -228.788975) (xy 360.963913 -228.788975) (xy 360.912618 -228.78085) (xy 360.863225 -228.764802)
			(xy 360.816951 -228.741224) (xy 360.774935 -228.710698) (xy 360.738212 -228.673975) (xy 360.707686 -228.631959)
			(xy 360.684108 -228.585685) (xy 360.66806 -228.536292) (xy 360.659935 -228.484997) (xy 360.380025 -228.484997)
			(xy 360.3719 -228.536292) (xy 360.355852 -228.585685) (xy 360.332274 -228.631959) (xy 360.301748 -228.673975)
			(xy 360.265025 -228.710698) (xy 360.223009 -228.741224) (xy 360.176735 -228.764802) (xy 360.127342 -228.78085)
			(xy 360.076047 -228.788975) (xy 360.024113 -228.788975) (xy 359.972818 -228.78085) (xy 359.923425 -228.764802)
			(xy 359.877151 -228.741224) (xy 359.835135 -228.710698) (xy 359.798412 -228.673975) (xy 359.767886 -228.631959)
			(xy 359.744308 -228.585685) (xy 359.72826 -228.536292) (xy 359.720135 -228.484997) (xy 359.440479 -228.484997)
			(xy 359.432354 -228.536292) (xy 359.416306 -228.585685) (xy 359.392728 -228.631959) (xy 359.362202 -228.673975)
			(xy 359.325479 -228.710698) (xy 359.283463 -228.741224) (xy 359.237189 -228.764802) (xy 359.187796 -228.78085)
			(xy 359.136501 -228.788975) (xy 359.084567 -228.788975) (xy 359.033272 -228.78085) (xy 358.983879 -228.764802)
			(xy 358.937605 -228.741224) (xy 358.895589 -228.710698) (xy 358.858866 -228.673975) (xy 358.82834 -228.631959)
			(xy 358.804762 -228.585685) (xy 358.788714 -228.536292) (xy 358.780589 -228.484997) (xy 358.500425 -228.484997)
			(xy 358.4923 -228.536292) (xy 358.476252 -228.585685) (xy 358.452674 -228.631959) (xy 358.422148 -228.673975)
			(xy 358.385425 -228.710698) (xy 358.343409 -228.741224) (xy 358.297135 -228.764802) (xy 358.247742 -228.78085)
			(xy 358.196447 -228.788975) (xy 358.144513 -228.788975) (xy 358.093218 -228.78085) (xy 358.043825 -228.764802)
			(xy 357.997551 -228.741224) (xy 357.955535 -228.710698) (xy 357.918812 -228.673975) (xy 357.888286 -228.631959)
			(xy 357.864708 -228.585685) (xy 357.84866 -228.536292) (xy 357.840535 -228.484997) (xy 357.560625 -228.484997)
			(xy 357.5525 -228.536292) (xy 357.536452 -228.585685) (xy 357.512874 -228.631959) (xy 357.482348 -228.673975)
			(xy 357.445625 -228.710698) (xy 357.403609 -228.741224) (xy 357.357335 -228.764802) (xy 357.307942 -228.78085)
			(xy 357.256647 -228.788975) (xy 357.204713 -228.788975) (xy 357.153418 -228.78085) (xy 357.104025 -228.764802)
			(xy 357.057751 -228.741224) (xy 357.015735 -228.710698) (xy 356.979012 -228.673975) (xy 356.948486 -228.631959)
			(xy 356.924908 -228.585685) (xy 356.90886 -228.536292) (xy 356.900735 -228.484997) (xy 356.620825 -228.484997)
			(xy 356.6127 -228.536292) (xy 356.596652 -228.585685) (xy 356.573074 -228.631959) (xy 356.542548 -228.673975)
			(xy 356.505825 -228.710698) (xy 356.463809 -228.741224) (xy 356.417535 -228.764802) (xy 356.368142 -228.78085)
			(xy 356.316847 -228.788975) (xy 356.264913 -228.788975) (xy 356.213618 -228.78085) (xy 356.164225 -228.764802)
			(xy 356.117951 -228.741224) (xy 356.075935 -228.710698) (xy 356.039212 -228.673975) (xy 356.008686 -228.631959)
			(xy 355.985108 -228.585685) (xy 355.96906 -228.536292) (xy 355.960935 -228.484997) (xy 355.681025 -228.484997)
			(xy 355.6729 -228.536292) (xy 355.656852 -228.585685) (xy 355.633274 -228.631959) (xy 355.602748 -228.673975)
			(xy 355.566025 -228.710698) (xy 355.524009 -228.741224) (xy 355.477735 -228.764802) (xy 355.428342 -228.78085)
			(xy 355.377047 -228.788975) (xy 355.325113 -228.788975) (xy 355.273818 -228.78085) (xy 355.224425 -228.764802)
			(xy 355.178151 -228.741224) (xy 355.136135 -228.710698) (xy 355.099412 -228.673975) (xy 355.068886 -228.631959)
			(xy 355.045308 -228.585685) (xy 355.02926 -228.536292) (xy 355.021135 -228.484997) (xy 354.741225 -228.484997)
			(xy 354.7331 -228.536292) (xy 354.717052 -228.585685) (xy 354.693474 -228.631959) (xy 354.662948 -228.673975)
			(xy 354.626225 -228.710698) (xy 354.584209 -228.741224) (xy 354.537935 -228.764802) (xy 354.488542 -228.78085)
			(xy 354.437247 -228.788975) (xy 354.385313 -228.788975) (xy 354.334018 -228.78085) (xy 354.284625 -228.764802)
			(xy 354.238351 -228.741224) (xy 354.196335 -228.710698) (xy 354.159612 -228.673975) (xy 354.129086 -228.631959)
			(xy 354.105508 -228.585685) (xy 354.08946 -228.536292) (xy 354.081335 -228.484997) (xy 353.801425 -228.484997)
			(xy 353.7933 -228.536292) (xy 353.777252 -228.585685) (xy 353.753674 -228.631959) (xy 353.723148 -228.673975)
			(xy 353.686425 -228.710698) (xy 353.644409 -228.741224) (xy 353.598135 -228.764802) (xy 353.548742 -228.78085)
			(xy 353.497447 -228.788975) (xy 353.445513 -228.788975) (xy 353.394218 -228.78085) (xy 353.344825 -228.764802)
			(xy 353.298551 -228.741224) (xy 353.256535 -228.710698) (xy 353.219812 -228.673975) (xy 353.189286 -228.631959)
			(xy 353.165708 -228.585685) (xy 353.14966 -228.536292) (xy 353.141535 -228.484997) (xy 352.861625 -228.484997)
			(xy 352.8535 -228.536292) (xy 352.837452 -228.585685) (xy 352.813874 -228.631959) (xy 352.783348 -228.673975)
			(xy 352.746625 -228.710698) (xy 352.704609 -228.741224) (xy 352.658335 -228.764802) (xy 352.608942 -228.78085)
			(xy 352.557647 -228.788975) (xy 352.505713 -228.788975) (xy 352.454418 -228.78085) (xy 352.405025 -228.764802)
			(xy 352.358751 -228.741224) (xy 352.316735 -228.710698) (xy 352.280012 -228.673975) (xy 352.249486 -228.631959)
			(xy 352.225908 -228.585685) (xy 352.20986 -228.536292) (xy 352.201735 -228.484997) (xy 351.922084 -228.484997)
			(xy 351.922079 -228.485251) (xy 351.913954 -228.536546) (xy 351.897906 -228.585939) (xy 351.874328 -228.632213)
			(xy 351.843802 -228.674229) (xy 351.807079 -228.710952) (xy 351.765063 -228.741478) (xy 351.718789 -228.765056)
			(xy 351.669396 -228.781104) (xy 351.618101 -228.789229) (xy 351.566167 -228.789229) (xy 351.514872 -228.781104)
			(xy 351.465479 -228.765056) (xy 351.419205 -228.741478) (xy 351.377189 -228.710952) (xy 351.340466 -228.674229)
			(xy 351.30994 -228.632213) (xy 351.286362 -228.585939) (xy 351.270314 -228.536546) (xy 351.262189 -228.485251)
			(xy 350.982021 -228.485251) (xy 350.982009 -228.485843) (xy 350.973343 -228.538763) (xy 350.956242 -228.589589)
			(xy 350.931156 -228.636985) (xy 350.898743 -228.679706) (xy 350.879664 -228.698552) (xy 350.870138 -228.708182)
			(xy 350.85609 -228.731332) (xy 350.848616 -228.757359) (xy 350.848241 -228.784435) (xy 350.85499 -228.810658)
			(xy 350.868391 -228.834188) (xy 350.877632 -228.844094) (xy 350.955864 -228.922326) (xy 362.258864 -228.922326)
			(xy 362.294678 -228.95814) (xy 362.322364 -228.951536) (xy 362.341318 -228.947271) (xy 362.3799 -228.942691)
			(xy 362.399326 -228.942392) (xy 362.399834 -228.942392) (xy 362.4258 -228.942877) (xy 362.477093 -228.951007)
			(xy 362.526482 -228.96706) (xy 362.572751 -228.990643) (xy 362.614762 -229.021173) (xy 362.651479 -229.057899)
			(xy 362.681999 -229.099917) (xy 362.70557 -229.146192) (xy 362.721612 -229.195585) (xy 362.729729 -229.24688)
			(xy 362.730288 -229.272846) (xy 362.730288 -229.273354) (xy 362.729994 -229.29278) (xy 362.729278 -229.298813)
			(xy 363.009689 -229.298813) (xy 363.009689 -229.246879) (xy 363.017814 -229.195584) (xy 363.033862 -229.146191)
			(xy 363.05744 -229.099917) (xy 363.087966 -229.057901) (xy 363.124689 -229.021178) (xy 363.166705 -228.990652)
			(xy 363.212979 -228.967074) (xy 363.262372 -228.951026) (xy 363.313667 -228.942901) (xy 363.365601 -228.942901)
			(xy 363.416896 -228.951026) (xy 363.466289 -228.967074) (xy 363.512563 -228.990652) (xy 363.554579 -229.021178)
			(xy 363.591302 -229.057901) (xy 363.621828 -229.099917) (xy 363.645406 -229.146191) (xy 363.661454 -229.195584)
			(xy 363.669579 -229.246879) (xy 363.670088 -229.272846) (xy 363.669579 -229.298813) (xy 363.949489 -229.298813)
			(xy 363.949489 -229.246879) (xy 363.957614 -229.195584) (xy 363.973662 -229.146191) (xy 363.99724 -229.099917)
			(xy 364.027766 -229.057901) (xy 364.064489 -229.021178) (xy 364.106505 -228.990652) (xy 364.152779 -228.967074)
			(xy 364.202172 -228.951026) (xy 364.253467 -228.942901) (xy 364.305401 -228.942901) (xy 364.356696 -228.951026)
			(xy 364.406089 -228.967074) (xy 364.452363 -228.990652) (xy 364.494379 -229.021178) (xy 364.531102 -229.057901)
			(xy 364.561628 -229.099917) (xy 364.585206 -229.146191) (xy 364.601254 -229.195584) (xy 364.609379 -229.246879)
			(xy 364.609888 -229.272846) (xy 364.609379 -229.298813) (xy 364.889289 -229.298813) (xy 364.889289 -229.246879)
			(xy 364.897414 -229.195584) (xy 364.913462 -229.146191) (xy 364.93704 -229.099917) (xy 364.967566 -229.057901)
			(xy 365.004289 -229.021178) (xy 365.046305 -228.990652) (xy 365.092579 -228.967074) (xy 365.141972 -228.951026)
			(xy 365.193267 -228.942901) (xy 365.245201 -228.942901) (xy 365.296496 -228.951026) (xy 365.345889 -228.967074)
			(xy 365.392163 -228.990652) (xy 365.434179 -229.021178) (xy 365.470902 -229.057901) (xy 365.501428 -229.099917)
			(xy 365.525006 -229.146191) (xy 365.541054 -229.195584) (xy 365.549179 -229.246879) (xy 365.549688 -229.272846)
			(xy 365.549179 -229.298813) (xy 365.829089 -229.298813) (xy 365.829089 -229.246879) (xy 365.837214 -229.195584)
			(xy 365.853262 -229.146191) (xy 365.87684 -229.099917) (xy 365.907366 -229.057901) (xy 365.944089 -229.021178)
			(xy 365.986105 -228.990652) (xy 366.032379 -228.967074) (xy 366.081772 -228.951026) (xy 366.133067 -228.942901)
			(xy 366.185001 -228.942901) (xy 366.236296 -228.951026) (xy 366.285689 -228.967074) (xy 366.331963 -228.990652)
			(xy 366.373979 -229.021178) (xy 366.410702 -229.057901) (xy 366.441228 -229.099917) (xy 366.464806 -229.146191)
			(xy 366.480854 -229.195584) (xy 366.488979 -229.246879) (xy 366.489488 -229.272846) (xy 366.488979 -229.298813)
			(xy 366.768889 -229.298813) (xy 366.768889 -229.246879) (xy 366.777014 -229.195584) (xy 366.793062 -229.146191)
			(xy 366.81664 -229.099917) (xy 366.847166 -229.057901) (xy 366.883889 -229.021178) (xy 366.925905 -228.990652)
			(xy 366.972179 -228.967074) (xy 367.021572 -228.951026) (xy 367.072867 -228.942901) (xy 367.124801 -228.942901)
			(xy 367.176096 -228.951026) (xy 367.225489 -228.967074) (xy 367.271763 -228.990652) (xy 367.313779 -229.021178)
			(xy 367.350502 -229.057901) (xy 367.381028 -229.099917) (xy 367.404606 -229.146191) (xy 367.420654 -229.195584)
			(xy 367.428779 -229.246879) (xy 367.429288 -229.272846) (xy 367.428779 -229.298813) (xy 367.708689 -229.298813)
			(xy 367.708689 -229.246879) (xy 367.716814 -229.195584) (xy 367.732862 -229.146191) (xy 367.75644 -229.099917)
			(xy 367.786966 -229.057901) (xy 367.823689 -229.021178) (xy 367.865705 -228.990652) (xy 367.911979 -228.967074)
			(xy 367.961372 -228.951026) (xy 368.012667 -228.942901) (xy 368.064601 -228.942901) (xy 368.115896 -228.951026)
			(xy 368.165289 -228.967074) (xy 368.211563 -228.990652) (xy 368.253579 -229.021178) (xy 368.290302 -229.057901)
			(xy 368.320828 -229.099917) (xy 368.344406 -229.146191) (xy 368.360454 -229.195584) (xy 368.368579 -229.246879)
			(xy 368.369088 -229.272846) (xy 368.368579 -229.298813) (xy 368.648489 -229.298813) (xy 368.648489 -229.246879)
			(xy 368.656614 -229.195584) (xy 368.672662 -229.146191) (xy 368.69624 -229.099917) (xy 368.726766 -229.057901)
			(xy 368.763489 -229.021178) (xy 368.805505 -228.990652) (xy 368.851779 -228.967074) (xy 368.901172 -228.951026)
			(xy 368.952467 -228.942901) (xy 369.004401 -228.942901) (xy 369.055696 -228.951026) (xy 369.105089 -228.967074)
			(xy 369.151363 -228.990652) (xy 369.193379 -229.021178) (xy 369.230102 -229.057901) (xy 369.260628 -229.099917)
			(xy 369.284206 -229.146191) (xy 369.300254 -229.195584) (xy 369.308379 -229.246879) (xy 369.308888 -229.272846)
			(xy 369.308379 -229.298813) (xy 369.588289 -229.298813) (xy 369.588289 -229.246879) (xy 369.596414 -229.195584)
			(xy 369.612462 -229.146191) (xy 369.63604 -229.099917) (xy 369.666566 -229.057901) (xy 369.703289 -229.021178)
			(xy 369.745305 -228.990652) (xy 369.791579 -228.967074) (xy 369.840972 -228.951026) (xy 369.892267 -228.942901)
			(xy 369.944201 -228.942901) (xy 369.995496 -228.951026) (xy 370.044889 -228.967074) (xy 370.091163 -228.990652)
			(xy 370.133179 -229.021178) (xy 370.169902 -229.057901) (xy 370.200428 -229.099917) (xy 370.224006 -229.146191)
			(xy 370.240054 -229.195584) (xy 370.248179 -229.246879) (xy 370.248688 -229.272846) (xy 370.248179 -229.298813)
			(xy 370.527835 -229.298813) (xy 370.527835 -229.246879) (xy 370.53596 -229.195584) (xy 370.552008 -229.146191)
			(xy 370.575586 -229.099917) (xy 370.606112 -229.057901) (xy 370.642835 -229.021178) (xy 370.684851 -228.990652)
			(xy 370.731125 -228.967074) (xy 370.780518 -228.951026) (xy 370.831813 -228.942901) (xy 370.883747 -228.942901)
			(xy 370.935042 -228.951026) (xy 370.984435 -228.967074) (xy 371.030709 -228.990652) (xy 371.072725 -229.021178)
			(xy 371.109448 -229.057901) (xy 371.139974 -229.099917) (xy 371.163552 -229.146191) (xy 371.1796 -229.195584)
			(xy 371.187725 -229.246879) (xy 371.188234 -229.272846) (xy 371.187725 -229.298813) (xy 371.467889 -229.298813)
			(xy 371.467889 -229.246879) (xy 371.476014 -229.195584) (xy 371.492062 -229.146191) (xy 371.51564 -229.099917)
			(xy 371.546166 -229.057901) (xy 371.582889 -229.021178) (xy 371.624905 -228.990652) (xy 371.671179 -228.967074)
			(xy 371.720572 -228.951026) (xy 371.771867 -228.942901) (xy 371.823801 -228.942901) (xy 371.875096 -228.951026)
			(xy 371.924489 -228.967074) (xy 371.970763 -228.990652) (xy 372.012779 -229.021178) (xy 372.049502 -229.057901)
			(xy 372.080028 -229.099917) (xy 372.103606 -229.146191) (xy 372.119654 -229.195584) (xy 372.127779 -229.246879)
			(xy 372.128288 -229.272846) (xy 372.127779 -229.298813) (xy 372.407689 -229.298813) (xy 372.407689 -229.246879)
			(xy 372.415814 -229.195584) (xy 372.431862 -229.146191) (xy 372.45544 -229.099917) (xy 372.485966 -229.057901)
			(xy 372.522689 -229.021178) (xy 372.564705 -228.990652) (xy 372.610979 -228.967074) (xy 372.660372 -228.951026)
			(xy 372.711667 -228.942901) (xy 372.763601 -228.942901) (xy 372.814896 -228.951026) (xy 372.864289 -228.967074)
			(xy 372.910563 -228.990652) (xy 372.952579 -229.021178) (xy 372.989302 -229.057901) (xy 373.019828 -229.099917)
			(xy 373.043406 -229.146191) (xy 373.059454 -229.195584) (xy 373.067579 -229.246879) (xy 373.068088 -229.272846)
			(xy 373.067579 -229.298813) (xy 373.347489 -229.298813) (xy 373.347489 -229.246879) (xy 373.355614 -229.195584)
			(xy 373.371662 -229.146191) (xy 373.39524 -229.099917) (xy 373.425766 -229.057901) (xy 373.462489 -229.021178)
			(xy 373.504505 -228.990652) (xy 373.550779 -228.967074) (xy 373.600172 -228.951026) (xy 373.651467 -228.942901)
			(xy 373.703401 -228.942901) (xy 373.754696 -228.951026) (xy 373.804089 -228.967074) (xy 373.850363 -228.990652)
			(xy 373.892379 -229.021178) (xy 373.929102 -229.057901) (xy 373.959628 -229.099917) (xy 373.983206 -229.146191)
			(xy 373.999254 -229.195584) (xy 374.007379 -229.246879) (xy 374.007888 -229.272846) (xy 374.007379 -229.298813)
			(xy 373.999254 -229.350108) (xy 373.983206 -229.399501) (xy 373.959628 -229.445775) (xy 373.929102 -229.487791)
			(xy 373.892379 -229.524514) (xy 373.850363 -229.55504) (xy 373.804089 -229.578618) (xy 373.754696 -229.594666)
			(xy 373.703401 -229.602791) (xy 373.651467 -229.602791) (xy 373.600172 -229.594666) (xy 373.550779 -229.578618)
			(xy 373.504505 -229.55504) (xy 373.462489 -229.524514) (xy 373.425766 -229.487791) (xy 373.39524 -229.445775)
			(xy 373.371662 -229.399501) (xy 373.355614 -229.350108) (xy 373.347489 -229.298813) (xy 373.067579 -229.298813)
			(xy 373.059454 -229.350108) (xy 373.043406 -229.399501) (xy 373.019828 -229.445775) (xy 372.989302 -229.487791)
			(xy 372.952579 -229.524514) (xy 372.910563 -229.55504) (xy 372.864289 -229.578618) (xy 372.814896 -229.594666)
			(xy 372.763601 -229.602791) (xy 372.711667 -229.602791) (xy 372.660372 -229.594666) (xy 372.610979 -229.578618)
			(xy 372.564705 -229.55504) (xy 372.522689 -229.524514) (xy 372.485966 -229.487791) (xy 372.45544 -229.445775)
			(xy 372.431862 -229.399501) (xy 372.415814 -229.350108) (xy 372.407689 -229.298813) (xy 372.127779 -229.298813)
			(xy 372.119654 -229.350108) (xy 372.103606 -229.399501) (xy 372.080028 -229.445775) (xy 372.049502 -229.487791)
			(xy 372.012779 -229.524514) (xy 371.970763 -229.55504) (xy 371.924489 -229.578618) (xy 371.875096 -229.594666)
			(xy 371.823801 -229.602791) (xy 371.771867 -229.602791) (xy 371.720572 -229.594666) (xy 371.671179 -229.578618)
			(xy 371.624905 -229.55504) (xy 371.582889 -229.524514) (xy 371.546166 -229.487791) (xy 371.51564 -229.445775)
			(xy 371.492062 -229.399501) (xy 371.476014 -229.350108) (xy 371.467889 -229.298813) (xy 371.187725 -229.298813)
			(xy 371.1796 -229.350108) (xy 371.163552 -229.399501) (xy 371.139974 -229.445775) (xy 371.109448 -229.487791)
			(xy 371.072725 -229.524514) (xy 371.030709 -229.55504) (xy 370.984435 -229.578618) (xy 370.935042 -229.594666)
			(xy 370.883747 -229.602791) (xy 370.831813 -229.602791) (xy 370.780518 -229.594666) (xy 370.731125 -229.578618)
			(xy 370.684851 -229.55504) (xy 370.642835 -229.524514) (xy 370.606112 -229.487791) (xy 370.575586 -229.445775)
			(xy 370.552008 -229.399501) (xy 370.53596 -229.350108) (xy 370.527835 -229.298813) (xy 370.248179 -229.298813)
			(xy 370.240054 -229.350108) (xy 370.224006 -229.399501) (xy 370.200428 -229.445775) (xy 370.169902 -229.487791)
			(xy 370.133179 -229.524514) (xy 370.091163 -229.55504) (xy 370.044889 -229.578618) (xy 369.995496 -229.594666)
			(xy 369.944201 -229.602791) (xy 369.892267 -229.602791) (xy 369.840972 -229.594666) (xy 369.791579 -229.578618)
			(xy 369.745305 -229.55504) (xy 369.703289 -229.524514) (xy 369.666566 -229.487791) (xy 369.63604 -229.445775)
			(xy 369.612462 -229.399501) (xy 369.596414 -229.350108) (xy 369.588289 -229.298813) (xy 369.308379 -229.298813)
			(xy 369.300254 -229.350108) (xy 369.284206 -229.399501) (xy 369.260628 -229.445775) (xy 369.230102 -229.487791)
			(xy 369.193379 -229.524514) (xy 369.151363 -229.55504) (xy 369.105089 -229.578618) (xy 369.055696 -229.594666)
			(xy 369.004401 -229.602791) (xy 368.952467 -229.602791) (xy 368.901172 -229.594666) (xy 368.851779 -229.578618)
			(xy 368.805505 -229.55504) (xy 368.763489 -229.524514) (xy 368.726766 -229.487791) (xy 368.69624 -229.445775)
			(xy 368.672662 -229.399501) (xy 368.656614 -229.350108) (xy 368.648489 -229.298813) (xy 368.368579 -229.298813)
			(xy 368.360454 -229.350108) (xy 368.344406 -229.399501) (xy 368.320828 -229.445775) (xy 368.290302 -229.487791)
			(xy 368.253579 -229.524514) (xy 368.211563 -229.55504) (xy 368.165289 -229.578618) (xy 368.115896 -229.594666)
			(xy 368.064601 -229.602791) (xy 368.012667 -229.602791) (xy 367.961372 -229.594666) (xy 367.911979 -229.578618)
			(xy 367.865705 -229.55504) (xy 367.823689 -229.524514) (xy 367.786966 -229.487791) (xy 367.75644 -229.445775)
			(xy 367.732862 -229.399501) (xy 367.716814 -229.350108) (xy 367.708689 -229.298813) (xy 367.428779 -229.298813)
			(xy 367.420654 -229.350108) (xy 367.404606 -229.399501) (xy 367.381028 -229.445775) (xy 367.350502 -229.487791)
			(xy 367.313779 -229.524514) (xy 367.271763 -229.55504) (xy 367.225489 -229.578618) (xy 367.176096 -229.594666)
			(xy 367.124801 -229.602791) (xy 367.072867 -229.602791) (xy 367.021572 -229.594666) (xy 366.972179 -229.578618)
			(xy 366.925905 -229.55504) (xy 366.883889 -229.524514) (xy 366.847166 -229.487791) (xy 366.81664 -229.445775)
			(xy 366.793062 -229.399501) (xy 366.777014 -229.350108) (xy 366.768889 -229.298813) (xy 366.488979 -229.298813)
			(xy 366.480854 -229.350108) (xy 366.464806 -229.399501) (xy 366.441228 -229.445775) (xy 366.410702 -229.487791)
			(xy 366.373979 -229.524514) (xy 366.331963 -229.55504) (xy 366.285689 -229.578618) (xy 366.236296 -229.594666)
			(xy 366.185001 -229.602791) (xy 366.133067 -229.602791) (xy 366.081772 -229.594666) (xy 366.032379 -229.578618)
			(xy 365.986105 -229.55504) (xy 365.944089 -229.524514) (xy 365.907366 -229.487791) (xy 365.87684 -229.445775)
			(xy 365.853262 -229.399501) (xy 365.837214 -229.350108) (xy 365.829089 -229.298813) (xy 365.549179 -229.298813)
			(xy 365.541054 -229.350108) (xy 365.525006 -229.399501) (xy 365.501428 -229.445775) (xy 365.470902 -229.487791)
			(xy 365.434179 -229.524514) (xy 365.392163 -229.55504) (xy 365.345889 -229.578618) (xy 365.296496 -229.594666)
			(xy 365.245201 -229.602791) (xy 365.193267 -229.602791) (xy 365.141972 -229.594666) (xy 365.092579 -229.578618)
			(xy 365.046305 -229.55504) (xy 365.004289 -229.524514) (xy 364.967566 -229.487791) (xy 364.93704 -229.445775)
			(xy 364.913462 -229.399501) (xy 364.897414 -229.350108) (xy 364.889289 -229.298813) (xy 364.609379 -229.298813)
			(xy 364.601254 -229.350108) (xy 364.585206 -229.399501) (xy 364.561628 -229.445775) (xy 364.531102 -229.487791)
			(xy 364.494379 -229.524514) (xy 364.452363 -229.55504) (xy 364.406089 -229.578618) (xy 364.356696 -229.594666)
			(xy 364.305401 -229.602791) (xy 364.253467 -229.602791) (xy 364.202172 -229.594666) (xy 364.152779 -229.578618)
			(xy 364.106505 -229.55504) (xy 364.064489 -229.524514) (xy 364.027766 -229.487791) (xy 363.99724 -229.445775)
			(xy 363.973662 -229.399501) (xy 363.957614 -229.350108) (xy 363.949489 -229.298813) (xy 363.669579 -229.298813)
			(xy 363.661454 -229.350108) (xy 363.645406 -229.399501) (xy 363.621828 -229.445775) (xy 363.591302 -229.487791)
			(xy 363.554579 -229.524514) (xy 363.512563 -229.55504) (xy 363.466289 -229.578618) (xy 363.416896 -229.594666)
			(xy 363.365601 -229.602791) (xy 363.313667 -229.602791) (xy 363.262372 -229.594666) (xy 363.212979 -229.578618)
			(xy 363.166705 -229.55504) (xy 363.124689 -229.524514) (xy 363.087966 -229.487791) (xy 363.05744 -229.445775)
			(xy 363.033862 -229.399501) (xy 363.017814 -229.350108) (xy 363.009689 -229.298813) (xy 362.729278 -229.298813)
			(xy 362.725412 -229.331362) (xy 362.721144 -229.350316) (xy 362.71454 -229.378002) (xy 363.335824 -229.999286)
			(xy 363.346346 -230.009106) (xy 363.371554 -230.02297) (xy 363.399627 -230.029258) (xy 363.42834 -230.027471)
			(xy 363.455417 -230.017751) (xy 363.478711 -230.000869) (xy 363.496376 -229.978162) (xy 363.502194 -229.964996)
			(xy 363.511687 -229.942234) (xy 363.536443 -229.899582) (xy 363.567267 -229.861087) (xy 363.603475 -229.827605)
			(xy 363.644261 -229.799882) (xy 363.688717 -229.778534) (xy 363.735853 -229.764037) (xy 363.784622 -229.756713)
			(xy 363.80928 -229.756208) (xy 363.835249 -229.756716) (xy 363.886549 -229.764837) (xy 363.935947 -229.780884)
			(xy 363.982226 -229.80446) (xy 364.024248 -229.834985) (xy 364.060977 -229.871708) (xy 364.09151 -229.913724)
			(xy 364.115094 -229.96) (xy 364.131149 -230.009395) (xy 364.13928 -230.060693) (xy 364.139734 -230.086662)
			(xy 364.139272 -230.111319) (xy 364.139075 -230.112629) (xy 364.419135 -230.112629) (xy 364.419135 -230.060695)
			(xy 364.42726 -230.0094) (xy 364.443308 -229.960007) (xy 364.466886 -229.913733) (xy 364.497412 -229.871717)
			(xy 364.534135 -229.834994) (xy 364.576151 -229.804468) (xy 364.622425 -229.78089) (xy 364.671818 -229.764842)
			(xy 364.723113 -229.756717) (xy 364.775047 -229.756717) (xy 364.826342 -229.764842) (xy 364.875735 -229.78089)
			(xy 364.922009 -229.804468) (xy 364.964025 -229.834994) (xy 365.000748 -229.871717) (xy 365.031274 -229.913733)
			(xy 365.054852 -229.960007) (xy 365.0709 -230.0094) (xy 365.079025 -230.060695) (xy 365.079534 -230.086662)
			(xy 365.079025 -230.112629) (xy 365.358935 -230.112629) (xy 365.358935 -230.060695) (xy 365.36706 -230.0094)
			(xy 365.383108 -229.960007) (xy 365.406686 -229.913733) (xy 365.437212 -229.871717) (xy 365.473935 -229.834994)
			(xy 365.515951 -229.804468) (xy 365.562225 -229.78089) (xy 365.611618 -229.764842) (xy 365.662913 -229.756717)
			(xy 365.714847 -229.756717) (xy 365.766142 -229.764842) (xy 365.815535 -229.78089) (xy 365.861809 -229.804468)
			(xy 365.903825 -229.834994) (xy 365.940548 -229.871717) (xy 365.971074 -229.913733) (xy 365.994652 -229.960007)
			(xy 366.0107 -230.0094) (xy 366.018825 -230.060695) (xy 366.019334 -230.086662) (xy 366.018825 -230.112629)
			(xy 366.298735 -230.112629) (xy 366.298735 -230.060695) (xy 366.30686 -230.0094) (xy 366.322908 -229.960007)
			(xy 366.346486 -229.913733) (xy 366.377012 -229.871717) (xy 366.413735 -229.834994) (xy 366.455751 -229.804468)
			(xy 366.502025 -229.78089) (xy 366.551418 -229.764842) (xy 366.602713 -229.756717) (xy 366.654647 -229.756717)
			(xy 366.705942 -229.764842) (xy 366.755335 -229.78089) (xy 366.801609 -229.804468) (xy 366.843625 -229.834994)
			(xy 366.880348 -229.871717) (xy 366.910874 -229.913733) (xy 366.934452 -229.960007) (xy 366.9505 -230.0094)
			(xy 366.958625 -230.060695) (xy 366.959134 -230.086662) (xy 366.958625 -230.112629) (xy 367.238535 -230.112629)
			(xy 367.238535 -230.060695) (xy 367.24666 -230.0094) (xy 367.262708 -229.960007) (xy 367.286286 -229.913733)
			(xy 367.316812 -229.871717) (xy 367.353535 -229.834994) (xy 367.395551 -229.804468) (xy 367.441825 -229.78089)
			(xy 367.491218 -229.764842) (xy 367.542513 -229.756717) (xy 367.594447 -229.756717) (xy 367.645742 -229.764842)
			(xy 367.695135 -229.78089) (xy 367.741409 -229.804468) (xy 367.783425 -229.834994) (xy 367.820148 -229.871717)
			(xy 367.850674 -229.913733) (xy 367.874252 -229.960007) (xy 367.8903 -230.0094) (xy 367.898425 -230.060695)
			(xy 367.898934 -230.086662) (xy 367.898425 -230.112629) (xy 368.178335 -230.112629) (xy 368.178335 -230.060695)
			(xy 368.18646 -230.0094) (xy 368.202508 -229.960007) (xy 368.226086 -229.913733) (xy 368.256612 -229.871717)
			(xy 368.293335 -229.834994) (xy 368.335351 -229.804468) (xy 368.381625 -229.78089) (xy 368.431018 -229.764842)
			(xy 368.482313 -229.756717) (xy 368.534247 -229.756717) (xy 368.585542 -229.764842) (xy 368.634935 -229.78089)
			(xy 368.681209 -229.804468) (xy 368.723225 -229.834994) (xy 368.759948 -229.871717) (xy 368.790474 -229.913733)
			(xy 368.814052 -229.960007) (xy 368.8301 -230.0094) (xy 368.838225 -230.060695) (xy 368.838734 -230.086662)
			(xy 368.838225 -230.112629) (xy 368.8301 -230.163924) (xy 368.814052 -230.213317) (xy 368.790474 -230.259591)
			(xy 368.759948 -230.301607) (xy 368.723225 -230.33833) (xy 368.681209 -230.368856) (xy 368.634935 -230.392434)
			(xy 368.585542 -230.408482) (xy 368.534247 -230.416607) (xy 368.482313 -230.416607) (xy 368.431018 -230.408482)
			(xy 368.381625 -230.392434) (xy 368.335351 -230.368856) (xy 368.293335 -230.33833) (xy 368.256612 -230.301607)
			(xy 368.226086 -230.259591) (xy 368.202508 -230.213317) (xy 368.18646 -230.163924) (xy 368.178335 -230.112629)
			(xy 367.898425 -230.112629) (xy 367.8903 -230.163924) (xy 367.874252 -230.213317) (xy 367.850674 -230.259591)
			(xy 367.820148 -230.301607) (xy 367.783425 -230.33833) (xy 367.741409 -230.368856) (xy 367.695135 -230.392434)
			(xy 367.645742 -230.408482) (xy 367.594447 -230.416607) (xy 367.542513 -230.416607) (xy 367.491218 -230.408482)
			(xy 367.441825 -230.392434) (xy 367.395551 -230.368856) (xy 367.353535 -230.33833) (xy 367.316812 -230.301607)
			(xy 367.286286 -230.259591) (xy 367.262708 -230.213317) (xy 367.24666 -230.163924) (xy 367.238535 -230.112629)
			(xy 366.958625 -230.112629) (xy 366.9505 -230.163924) (xy 366.934452 -230.213317) (xy 366.910874 -230.259591)
			(xy 366.880348 -230.301607) (xy 366.843625 -230.33833) (xy 366.801609 -230.368856) (xy 366.755335 -230.392434)
			(xy 366.705942 -230.408482) (xy 366.654647 -230.416607) (xy 366.602713 -230.416607) (xy 366.551418 -230.408482)
			(xy 366.502025 -230.392434) (xy 366.455751 -230.368856) (xy 366.413735 -230.33833) (xy 366.377012 -230.301607)
			(xy 366.346486 -230.259591) (xy 366.322908 -230.213317) (xy 366.30686 -230.163924) (xy 366.298735 -230.112629)
			(xy 366.018825 -230.112629) (xy 366.0107 -230.163924) (xy 365.994652 -230.213317) (xy 365.971074 -230.259591)
			(xy 365.940548 -230.301607) (xy 365.903825 -230.33833) (xy 365.861809 -230.368856) (xy 365.815535 -230.392434)
			(xy 365.766142 -230.408482) (xy 365.714847 -230.416607) (xy 365.662913 -230.416607) (xy 365.611618 -230.408482)
			(xy 365.562225 -230.392434) (xy 365.515951 -230.368856) (xy 365.473935 -230.33833) (xy 365.437212 -230.301607)
			(xy 365.406686 -230.259591) (xy 365.383108 -230.213317) (xy 365.36706 -230.163924) (xy 365.358935 -230.112629)
			(xy 365.079025 -230.112629) (xy 365.0709 -230.163924) (xy 365.054852 -230.213317) (xy 365.031274 -230.259591)
			(xy 365.000748 -230.301607) (xy 364.964025 -230.33833) (xy 364.922009 -230.368856) (xy 364.875735 -230.392434)
			(xy 364.826342 -230.408482) (xy 364.775047 -230.416607) (xy 364.723113 -230.416607) (xy 364.671818 -230.408482)
			(xy 364.622425 -230.392434) (xy 364.576151 -230.368856) (xy 364.534135 -230.33833) (xy 364.497412 -230.301607)
			(xy 364.466886 -230.259591) (xy 364.443308 -230.213317) (xy 364.42726 -230.163924) (xy 364.419135 -230.112629)
			(xy 364.139075 -230.112629) (xy 364.131929 -230.160083) (xy 364.117417 -230.207213) (xy 364.096058 -230.251661)
			(xy 364.068326 -230.292439) (xy 364.034839 -230.328639) (xy 363.996341 -230.359457) (xy 363.953688 -230.384208)
			(xy 363.930946 -230.393748) (xy 363.917759 -230.399525) (xy 363.895043 -230.417192) (xy 363.878156 -230.440494)
			(xy 363.868436 -230.46758) (xy 363.866655 -230.496302) (xy 363.872955 -230.524381) (xy 363.886835 -230.54959)
			(xy 363.896656 -230.560118) (xy 363.989112 -230.652574) (xy 363.996266 -230.659084) (xy 364.01404 -230.666674)
			(xy 364.03336 -230.667171) (xy 364.051501 -230.660506) (xy 364.058962 -230.654352) (xy 364.077244 -230.638569)
			(xy 364.117527 -230.611927) (xy 364.161257 -230.59143) (xy 364.207505 -230.577514) (xy 364.255286 -230.570477)
			(xy 364.279434 -230.570024) (xy 364.305401 -230.570536) (xy 364.356696 -230.578665) (xy 364.406087 -230.594718)
			(xy 364.452359 -230.618299) (xy 364.494373 -230.648828) (xy 364.531094 -230.685553) (xy 364.561619 -230.72757)
			(xy 364.585195 -230.773845) (xy 364.601243 -230.823238) (xy 364.609367 -230.874533) (xy 364.609367 -230.926445)
			(xy 364.889289 -230.926445) (xy 364.889289 -230.874511) (xy 364.897414 -230.823216) (xy 364.913462 -230.773823)
			(xy 364.93704 -230.727549) (xy 364.967566 -230.685533) (xy 365.004289 -230.64881) (xy 365.046305 -230.618284)
			(xy 365.092579 -230.594706) (xy 365.141972 -230.578658) (xy 365.193267 -230.570533) (xy 365.245201 -230.570533)
			(xy 365.296496 -230.578658) (xy 365.345889 -230.594706) (xy 365.392163 -230.618284) (xy 365.434179 -230.64881)
			(xy 365.470902 -230.685533) (xy 365.501428 -230.727549) (xy 365.525006 -230.773823) (xy 365.541054 -230.823216)
			(xy 365.549179 -230.874511) (xy 365.549688 -230.900478) (xy 365.549179 -230.926445) (xy 365.829089 -230.926445)
			(xy 365.829089 -230.874511) (xy 365.837214 -230.823216) (xy 365.853262 -230.773823) (xy 365.87684 -230.727549)
			(xy 365.907366 -230.685533) (xy 365.944089 -230.64881) (xy 365.986105 -230.618284) (xy 366.032379 -230.594706)
			(xy 366.081772 -230.578658) (xy 366.133067 -230.570533) (xy 366.185001 -230.570533) (xy 366.236296 -230.578658)
			(xy 366.285689 -230.594706) (xy 366.331963 -230.618284) (xy 366.373979 -230.64881) (xy 366.410702 -230.685533)
			(xy 366.441228 -230.727549) (xy 366.464806 -230.773823) (xy 366.480854 -230.823216) (xy 366.488979 -230.874511)
			(xy 366.489488 -230.900478) (xy 366.488979 -230.926445) (xy 366.768889 -230.926445) (xy 366.768889 -230.874511)
			(xy 366.777014 -230.823216) (xy 366.793062 -230.773823) (xy 366.81664 -230.727549) (xy 366.847166 -230.685533)
			(xy 366.883889 -230.64881) (xy 366.925905 -230.618284) (xy 366.972179 -230.594706) (xy 367.021572 -230.578658)
			(xy 367.072867 -230.570533) (xy 367.124801 -230.570533) (xy 367.176096 -230.578658) (xy 367.225489 -230.594706)
			(xy 367.271763 -230.618284) (xy 367.313779 -230.64881) (xy 367.350502 -230.685533) (xy 367.381028 -230.727549)
			(xy 367.404606 -230.773823) (xy 367.420654 -230.823216) (xy 367.428779 -230.874511) (xy 367.429288 -230.900478)
			(xy 367.428779 -230.926445) (xy 367.708689 -230.926445) (xy 367.708689 -230.874511) (xy 367.716814 -230.823216)
			(xy 367.732862 -230.773823) (xy 367.75644 -230.727549) (xy 367.786966 -230.685533) (xy 367.823689 -230.64881)
			(xy 367.865705 -230.618284) (xy 367.911979 -230.594706) (xy 367.961372 -230.578658) (xy 368.012667 -230.570533)
			(xy 368.064601 -230.570533) (xy 368.115896 -230.578658) (xy 368.165289 -230.594706) (xy 368.211563 -230.618284)
			(xy 368.253579 -230.64881) (xy 368.290302 -230.685533) (xy 368.320828 -230.727549) (xy 368.344406 -230.773823)
			(xy 368.360454 -230.823216) (xy 368.368579 -230.874511) (xy 368.369088 -230.900478) (xy 368.368579 -230.926445)
			(xy 368.360454 -230.97774) (xy 368.344406 -231.027133) (xy 368.320828 -231.073407) (xy 368.290302 -231.115423)
			(xy 368.253579 -231.152146) (xy 368.211563 -231.182672) (xy 368.165289 -231.20625) (xy 368.115896 -231.222298)
			(xy 368.064601 -231.230423) (xy 368.012667 -231.230423) (xy 367.961372 -231.222298) (xy 367.911979 -231.20625)
			(xy 367.865705 -231.182672) (xy 367.823689 -231.152146) (xy 367.786966 -231.115423) (xy 367.75644 -231.073407)
			(xy 367.732862 -231.027133) (xy 367.716814 -230.97774) (xy 367.708689 -230.926445) (xy 367.428779 -230.926445)
			(xy 367.420654 -230.97774) (xy 367.404606 -231.027133) (xy 367.381028 -231.073407) (xy 367.350502 -231.115423)
			(xy 367.313779 -231.152146) (xy 367.271763 -231.182672) (xy 367.225489 -231.20625) (xy 367.176096 -231.222298)
			(xy 367.124801 -231.230423) (xy 367.072867 -231.230423) (xy 367.021572 -231.222298) (xy 366.972179 -231.20625)
			(xy 366.925905 -231.182672) (xy 366.883889 -231.152146) (xy 366.847166 -231.115423) (xy 366.81664 -231.073407)
			(xy 366.793062 -231.027133) (xy 366.777014 -230.97774) (xy 366.768889 -230.926445) (xy 366.488979 -230.926445)
			(xy 366.480854 -230.97774) (xy 366.464806 -231.027133) (xy 366.441228 -231.073407) (xy 366.410702 -231.115423)
			(xy 366.373979 -231.152146) (xy 366.331963 -231.182672) (xy 366.285689 -231.20625) (xy 366.236296 -231.222298)
			(xy 366.185001 -231.230423) (xy 366.133067 -231.230423) (xy 366.081772 -231.222298) (xy 366.032379 -231.20625)
			(xy 365.986105 -231.182672) (xy 365.944089 -231.152146) (xy 365.907366 -231.115423) (xy 365.87684 -231.073407)
			(xy 365.853262 -231.027133) (xy 365.837214 -230.97774) (xy 365.829089 -230.926445) (xy 365.549179 -230.926445)
			(xy 365.541054 -230.97774) (xy 365.525006 -231.027133) (xy 365.501428 -231.073407) (xy 365.470902 -231.115423)
			(xy 365.434179 -231.152146) (xy 365.392163 -231.182672) (xy 365.345889 -231.20625) (xy 365.296496 -231.222298)
			(xy 365.245201 -231.230423) (xy 365.193267 -231.230423) (xy 365.141972 -231.222298) (xy 365.092579 -231.20625)
			(xy 365.046305 -231.182672) (xy 365.004289 -231.152146) (xy 364.967566 -231.115423) (xy 364.93704 -231.073407)
			(xy 364.913462 -231.027133) (xy 364.897414 -230.97774) (xy 364.889289 -230.926445) (xy 364.609367 -230.926445)
			(xy 364.609367 -230.926467) (xy 364.601243 -230.977762) (xy 364.585195 -231.027155) (xy 364.561619 -231.07343)
			(xy 364.531094 -231.115447) (xy 364.494373 -231.152172) (xy 364.452359 -231.182701) (xy 364.406087 -231.206282)
			(xy 364.356696 -231.222335) (xy 364.305401 -231.230464) (xy 364.279434 -231.230932) (xy 364.278672 -231.230932)
			(xy 364.256489 -231.230521) (xy 364.212527 -231.224533) (xy 364.191042 -231.218994) (xy 364.178043 -231.215808)
			(xy 364.151288 -231.215606) (xy 364.1254 -231.222363) (xy 364.102157 -231.235615) (xy 364.083155 -231.254451)
			(xy 364.069702 -231.277578) (xy 364.06272 -231.303407) (xy 364.062264 -231.316784) (xy 364.062264 -231.50195)
			(xy 364.078407 -231.521918) (xy 364.104958 -231.565864) (xy 364.124391 -231.613388) (xy 364.13624 -231.663347)
			(xy 364.140217 -231.714537) (xy 364.138193 -231.740515) (xy 364.419135 -231.740515) (xy 364.419135 -231.688581)
			(xy 364.42726 -231.637286) (xy 364.443308 -231.587893) (xy 364.466886 -231.541619) (xy 364.497412 -231.499603)
			(xy 364.534135 -231.46288) (xy 364.576151 -231.432354) (xy 364.622425 -231.408776) (xy 364.671818 -231.392728)
			(xy 364.723113 -231.384603) (xy 364.775047 -231.384603) (xy 364.826342 -231.392728) (xy 364.875735 -231.408776)
			(xy 364.922009 -231.432354) (xy 364.964025 -231.46288) (xy 365.000748 -231.499603) (xy 365.031274 -231.541619)
			(xy 365.054852 -231.587893) (xy 365.0709 -231.637286) (xy 365.079025 -231.688581) (xy 365.079534 -231.714548)
			(xy 365.079025 -231.740515) (xy 365.358935 -231.740515) (xy 365.358935 -231.688581) (xy 365.36706 -231.637286)
			(xy 365.383108 -231.587893) (xy 365.406686 -231.541619) (xy 365.437212 -231.499603) (xy 365.473935 -231.46288)
			(xy 365.515951 -231.432354) (xy 365.562225 -231.408776) (xy 365.611618 -231.392728) (xy 365.662913 -231.384603)
			(xy 365.714847 -231.384603) (xy 365.766142 -231.392728) (xy 365.815535 -231.408776) (xy 365.861809 -231.432354)
			(xy 365.903825 -231.46288) (xy 365.940548 -231.499603) (xy 365.971074 -231.541619) (xy 365.994652 -231.587893)
			(xy 366.0107 -231.637286) (xy 366.018825 -231.688581) (xy 366.019334 -231.714548) (xy 366.018825 -231.740515)
			(xy 366.298735 -231.740515) (xy 366.298735 -231.688581) (xy 366.30686 -231.637286) (xy 366.322908 -231.587893)
			(xy 366.346486 -231.541619) (xy 366.377012 -231.499603) (xy 366.413735 -231.46288) (xy 366.455751 -231.432354)
			(xy 366.502025 -231.408776) (xy 366.551418 -231.392728) (xy 366.602713 -231.384603) (xy 366.654647 -231.384603)
			(xy 366.705942 -231.392728) (xy 366.755335 -231.408776) (xy 366.801609 -231.432354) (xy 366.843625 -231.46288)
			(xy 366.880348 -231.499603) (xy 366.910874 -231.541619) (xy 366.934452 -231.587893) (xy 366.9505 -231.637286)
			(xy 366.958625 -231.688581) (xy 366.959134 -231.714548) (xy 366.958625 -231.740515) (xy 367.239043 -231.740515)
			(xy 367.239043 -231.688581) (xy 367.247168 -231.637286) (xy 367.263216 -231.587893) (xy 367.286794 -231.541619)
			(xy 367.31732 -231.499603) (xy 367.354043 -231.46288) (xy 367.396059 -231.432354) (xy 367.442333 -231.408776)
			(xy 367.491726 -231.392728) (xy 367.543021 -231.384603) (xy 367.594955 -231.384603) (xy 367.64625 -231.392728)
			(xy 367.695643 -231.408776) (xy 367.741917 -231.432354) (xy 367.783933 -231.46288) (xy 367.820656 -231.499603)
			(xy 367.851182 -231.541619) (xy 367.87476 -231.587893) (xy 367.890808 -231.637286) (xy 367.898933 -231.688581)
			(xy 367.899442 -231.714548) (xy 367.898933 -231.740515) (xy 367.890808 -231.79181) (xy 367.87476 -231.841203)
			(xy 367.851182 -231.887477) (xy 367.820656 -231.929493) (xy 367.783933 -231.966216) (xy 367.741917 -231.996742)
			(xy 367.695643 -232.02032) (xy 367.64625 -232.036368) (xy 367.594955 -232.044493) (xy 367.543021 -232.044493)
			(xy 367.491726 -232.036368) (xy 367.442333 -232.02032) (xy 367.396059 -231.996742) (xy 367.354043 -231.966216)
			(xy 367.31732 -231.929493) (xy 367.286794 -231.887477) (xy 367.263216 -231.841203) (xy 367.247168 -231.79181)
			(xy 367.239043 -231.740515) (xy 366.958625 -231.740515) (xy 366.9505 -231.79181) (xy 366.934452 -231.841203)
			(xy 366.910874 -231.887477) (xy 366.880348 -231.929493) (xy 366.843625 -231.966216) (xy 366.801609 -231.996742)
			(xy 366.755335 -232.02032) (xy 366.705942 -232.036368) (xy 366.654647 -232.044493) (xy 366.602713 -232.044493)
			(xy 366.551418 -232.036368) (xy 366.502025 -232.02032) (xy 366.455751 -231.996742) (xy 366.413735 -231.966216)
			(xy 366.377012 -231.929493) (xy 366.346486 -231.887477) (xy 366.322908 -231.841203) (xy 366.30686 -231.79181)
			(xy 366.298735 -231.740515) (xy 366.018825 -231.740515) (xy 366.0107 -231.79181) (xy 365.994652 -231.841203)
			(xy 365.971074 -231.887477) (xy 365.940548 -231.929493) (xy 365.903825 -231.966216) (xy 365.861809 -231.996742)
			(xy 365.815535 -232.02032) (xy 365.766142 -232.036368) (xy 365.714847 -232.044493) (xy 365.662913 -232.044493)
			(xy 365.611618 -232.036368) (xy 365.562225 -232.02032) (xy 365.515951 -231.996742) (xy 365.473935 -231.966216)
			(xy 365.437212 -231.929493) (xy 365.406686 -231.887477) (xy 365.383108 -231.841203) (xy 365.36706 -231.79181)
			(xy 365.358935 -231.740515) (xy 365.079025 -231.740515) (xy 365.0709 -231.79181) (xy 365.054852 -231.841203)
			(xy 365.031274 -231.887477) (xy 365.000748 -231.929493) (xy 364.964025 -231.966216) (xy 364.922009 -231.996742)
			(xy 364.875735 -232.02032) (xy 364.826342 -232.036368) (xy 364.775047 -232.044493) (xy 364.723113 -232.044493)
			(xy 364.671818 -232.036368) (xy 364.622425 -232.02032) (xy 364.576151 -231.996742) (xy 364.534135 -231.966216)
			(xy 364.497412 -231.929493) (xy 364.466886 -231.887477) (xy 364.443308 -231.841203) (xy 364.42726 -231.79181)
			(xy 364.419135 -231.740515) (xy 364.138193 -231.740515) (xy 364.136228 -231.765726) (xy 364.124369 -231.815682)
			(xy 364.104925 -231.863202) (xy 364.078364 -231.907142) (xy 364.062264 -231.927146) (xy 364.062264 -232.112058)
			(xy 364.062664 -232.125442) (xy 364.069624 -232.151291) (xy 364.083074 -232.174435) (xy 364.102086 -232.193279)
			(xy 364.125349 -232.206522) (xy 364.151258 -232.213251) (xy 364.178026 -232.213001) (xy 364.191042 -232.209848)
			(xy 364.21252 -232.204277) (xy 364.256486 -232.198293) (xy 364.278672 -232.19791) (xy 364.279434 -232.19791)
			(xy 364.305402 -232.198422) (xy 364.356699 -232.206551) (xy 364.406092 -232.222605) (xy 364.452366 -232.246187)
			(xy 364.494382 -232.276717) (xy 364.531105 -232.313444) (xy 364.561631 -232.355463) (xy 364.585208 -232.401739)
			(xy 364.601257 -232.451134) (xy 364.609381 -232.502432) (xy 364.609381 -232.554331) (xy 364.889289 -232.554331)
			(xy 364.889289 -232.502397) (xy 364.897414 -232.451102) (xy 364.913462 -232.401709) (xy 364.93704 -232.355435)
			(xy 364.967566 -232.313419) (xy 365.004289 -232.276696) (xy 365.046305 -232.24617) (xy 365.092579 -232.222592)
			(xy 365.141972 -232.206544) (xy 365.193267 -232.198419) (xy 365.245201 -232.198419) (xy 365.296496 -232.206544)
			(xy 365.345889 -232.222592) (xy 365.392163 -232.24617) (xy 365.434179 -232.276696) (xy 365.470902 -232.313419)
			(xy 365.501428 -232.355435) (xy 365.525006 -232.401709) (xy 365.541054 -232.451102) (xy 365.549179 -232.502397)
			(xy 365.549688 -232.528364) (xy 365.549179 -232.554331) (xy 365.829089 -232.554331) (xy 365.829089 -232.502397)
			(xy 365.837214 -232.451102) (xy 365.853262 -232.401709) (xy 365.87684 -232.355435) (xy 365.907366 -232.313419)
			(xy 365.944089 -232.276696) (xy 365.986105 -232.24617) (xy 366.032379 -232.222592) (xy 366.081772 -232.206544)
			(xy 366.133067 -232.198419) (xy 366.185001 -232.198419) (xy 366.236296 -232.206544) (xy 366.285689 -232.222592)
			(xy 366.331963 -232.24617) (xy 366.373979 -232.276696) (xy 366.410702 -232.313419) (xy 366.441228 -232.355435)
			(xy 366.464806 -232.401709) (xy 366.480854 -232.451102) (xy 366.488979 -232.502397) (xy 366.489488 -232.528364)
			(xy 366.488979 -232.554331) (xy 366.768889 -232.554331) (xy 366.768889 -232.502397) (xy 366.777014 -232.451102)
			(xy 366.793062 -232.401709) (xy 366.81664 -232.355435) (xy 366.847166 -232.313419) (xy 366.883889 -232.276696)
			(xy 366.925905 -232.24617) (xy 366.972179 -232.222592) (xy 367.021572 -232.206544) (xy 367.072867 -232.198419)
			(xy 367.124801 -232.198419) (xy 367.176096 -232.206544) (xy 367.225489 -232.222592) (xy 367.271763 -232.24617)
			(xy 367.313779 -232.276696) (xy 367.350502 -232.313419) (xy 367.381028 -232.355435) (xy 367.404606 -232.401709)
			(xy 367.420654 -232.451102) (xy 367.428779 -232.502397) (xy 367.429288 -232.528364) (xy 367.428779 -232.554331)
			(xy 367.708435 -232.554331) (xy 367.708435 -232.502397) (xy 367.71656 -232.451102) (xy 367.732608 -232.401709)
			(xy 367.756186 -232.355435) (xy 367.786712 -232.313419) (xy 367.823435 -232.276696) (xy 367.865451 -232.24617)
			(xy 367.911725 -232.222592) (xy 367.961118 -232.206544) (xy 368.012413 -232.198419) (xy 368.064347 -232.198419)
			(xy 368.115642 -232.206544) (xy 368.165035 -232.222592) (xy 368.211309 -232.24617) (xy 368.253325 -232.276696)
			(xy 368.290048 -232.313419) (xy 368.320574 -232.355435) (xy 368.344152 -232.401709) (xy 368.3602 -232.451102)
			(xy 368.368325 -232.502397) (xy 368.368834 -232.528364) (xy 368.368325 -232.554331) (xy 368.3602 -232.605626)
			(xy 368.344152 -232.655019) (xy 368.320574 -232.701293) (xy 368.290048 -232.743309) (xy 368.253325 -232.780032)
			(xy 368.211309 -232.810558) (xy 368.165035 -232.834136) (xy 368.115642 -232.850184) (xy 368.064347 -232.858309)
			(xy 368.012413 -232.858309) (xy 367.961118 -232.850184) (xy 367.911725 -232.834136) (xy 367.865451 -232.810558)
			(xy 367.823435 -232.780032) (xy 367.786712 -232.743309) (xy 367.756186 -232.701293) (xy 367.732608 -232.655019)
			(xy 367.71656 -232.605626) (xy 367.708435 -232.554331) (xy 367.428779 -232.554331) (xy 367.420654 -232.605626)
			(xy 367.404606 -232.655019) (xy 367.381028 -232.701293) (xy 367.350502 -232.743309) (xy 367.313779 -232.780032)
			(xy 367.271763 -232.810558) (xy 367.225489 -232.834136) (xy 367.176096 -232.850184) (xy 367.124801 -232.858309)
			(xy 367.072867 -232.858309) (xy 367.021572 -232.850184) (xy 366.972179 -232.834136) (xy 366.925905 -232.810558)
			(xy 366.883889 -232.780032) (xy 366.847166 -232.743309) (xy 366.81664 -232.701293) (xy 366.793062 -232.655019)
			(xy 366.777014 -232.605626) (xy 366.768889 -232.554331) (xy 366.488979 -232.554331) (xy 366.480854 -232.605626)
			(xy 366.464806 -232.655019) (xy 366.441228 -232.701293) (xy 366.410702 -232.743309) (xy 366.373979 -232.780032)
			(xy 366.331963 -232.810558) (xy 366.285689 -232.834136) (xy 366.236296 -232.850184) (xy 366.185001 -232.858309)
			(xy 366.133067 -232.858309) (xy 366.081772 -232.850184) (xy 366.032379 -232.834136) (xy 365.986105 -232.810558)
			(xy 365.944089 -232.780032) (xy 365.907366 -232.743309) (xy 365.87684 -232.701293) (xy 365.853262 -232.655019)
			(xy 365.837214 -232.605626) (xy 365.829089 -232.554331) (xy 365.549179 -232.554331) (xy 365.541054 -232.605626)
			(xy 365.525006 -232.655019) (xy 365.501428 -232.701293) (xy 365.470902 -232.743309) (xy 365.434179 -232.780032)
			(xy 365.392163 -232.810558) (xy 365.345889 -232.834136) (xy 365.296496 -232.850184) (xy 365.245201 -232.858309)
			(xy 365.193267 -232.858309) (xy 365.141972 -232.850184) (xy 365.092579 -232.834136) (xy 365.046305 -232.810558)
			(xy 365.004289 -232.780032) (xy 364.967566 -232.743309) (xy 364.93704 -232.701293) (xy 364.913462 -232.655019)
			(xy 364.897414 -232.605626) (xy 364.889289 -232.554331) (xy 364.609381 -232.554331) (xy 364.609381 -232.554368)
			(xy 364.601257 -232.605666) (xy 364.585208 -232.655061) (xy 364.561631 -232.701337) (xy 364.531105 -232.743356)
			(xy 364.494382 -232.780083) (xy 364.452366 -232.810613) (xy 364.406092 -232.834195) (xy 364.356699 -232.850249)
			(xy 364.305402 -232.858378) (xy 364.279434 -232.858818) (xy 364.278672 -232.858818) (xy 364.256489 -232.858407)
			(xy 364.212527 -232.852419) (xy 364.191042 -232.84688) (xy 364.178042 -232.843695) (xy 364.151286 -232.843493)
			(xy 364.125397 -232.850249) (xy 364.102153 -232.863501) (xy 364.083149 -232.882337) (xy 364.069693 -232.905464)
			(xy 364.062708 -232.931292) (xy 364.062264 -232.94467) (xy 364.062264 -233.129582) (xy 364.078412 -233.14955)
			(xy 364.104973 -233.193498) (xy 364.124417 -233.241025) (xy 364.136275 -233.290989) (xy 364.140261 -233.342185)
			(xy 364.138242 -233.368147) (xy 364.419135 -233.368147) (xy 364.419135 -233.316213) (xy 364.42726 -233.264918)
			(xy 364.443308 -233.215525) (xy 364.466886 -233.169251) (xy 364.497412 -233.127235) (xy 364.534135 -233.090512)
			(xy 364.576151 -233.059986) (xy 364.622425 -233.036408) (xy 364.671818 -233.02036) (xy 364.723113 -233.012235)
			(xy 364.775047 -233.012235) (xy 364.826342 -233.02036) (xy 364.875735 -233.036408) (xy 364.922009 -233.059986)
			(xy 364.964025 -233.090512) (xy 365.000748 -233.127235) (xy 365.031274 -233.169251) (xy 365.054852 -233.215525)
			(xy 365.0709 -233.264918) (xy 365.079025 -233.316213) (xy 365.079534 -233.34218) (xy 365.079025 -233.368147)
			(xy 365.358935 -233.368147) (xy 365.358935 -233.316213) (xy 365.36706 -233.264918) (xy 365.383108 -233.215525)
			(xy 365.406686 -233.169251) (xy 365.437212 -233.127235) (xy 365.473935 -233.090512) (xy 365.515951 -233.059986)
			(xy 365.562225 -233.036408) (xy 365.611618 -233.02036) (xy 365.662913 -233.012235) (xy 365.714847 -233.012235)
			(xy 365.766142 -233.02036) (xy 365.815535 -233.036408) (xy 365.861809 -233.059986) (xy 365.903825 -233.090512)
			(xy 365.940548 -233.127235) (xy 365.971074 -233.169251) (xy 365.994652 -233.215525) (xy 366.0107 -233.264918)
			(xy 366.018825 -233.316213) (xy 366.019334 -233.34218) (xy 366.018825 -233.368147) (xy 366.298735 -233.368147)
			(xy 366.298735 -233.316213) (xy 366.30686 -233.264918) (xy 366.322908 -233.215525) (xy 366.346486 -233.169251)
			(xy 366.377012 -233.127235) (xy 366.413735 -233.090512) (xy 366.455751 -233.059986) (xy 366.502025 -233.036408)
			(xy 366.551418 -233.02036) (xy 366.602713 -233.012235) (xy 366.654647 -233.012235) (xy 366.705942 -233.02036)
			(xy 366.755335 -233.036408) (xy 366.801609 -233.059986) (xy 366.843625 -233.090512) (xy 366.880348 -233.127235)
			(xy 366.910874 -233.169251) (xy 366.934452 -233.215525) (xy 366.9505 -233.264918) (xy 366.958625 -233.316213)
			(xy 366.959134 -233.34218) (xy 366.958625 -233.368147) (xy 367.238535 -233.368147) (xy 367.238535 -233.316213)
			(xy 367.24666 -233.264918) (xy 367.262708 -233.215525) (xy 367.286286 -233.169251) (xy 367.316812 -233.127235)
			(xy 367.353535 -233.090512) (xy 367.395551 -233.059986) (xy 367.441825 -233.036408) (xy 367.491218 -233.02036)
			(xy 367.542513 -233.012235) (xy 367.594447 -233.012235) (xy 367.645742 -233.02036) (xy 367.695135 -233.036408)
			(xy 367.741409 -233.059986) (xy 367.783425 -233.090512) (xy 367.820148 -233.127235) (xy 367.850674 -233.169251)
			(xy 367.874252 -233.215525) (xy 367.8903 -233.264918) (xy 367.898425 -233.316213) (xy 367.898934 -233.34218)
			(xy 367.898425 -233.368147) (xy 367.8903 -233.419442) (xy 367.874252 -233.468835) (xy 367.850674 -233.515109)
			(xy 367.820148 -233.557125) (xy 367.783425 -233.593848) (xy 367.741409 -233.624374) (xy 367.695135 -233.647952)
			(xy 367.645742 -233.664) (xy 367.594447 -233.672125) (xy 367.542513 -233.672125) (xy 367.491218 -233.664)
			(xy 367.441825 -233.647952) (xy 367.395551 -233.624374) (xy 367.353535 -233.593848) (xy 367.316812 -233.557125)
			(xy 367.286286 -233.515109) (xy 367.262708 -233.468835) (xy 367.24666 -233.419442) (xy 367.238535 -233.368147)
			(xy 366.958625 -233.368147) (xy 366.9505 -233.419442) (xy 366.934452 -233.468835) (xy 366.910874 -233.515109)
			(xy 366.880348 -233.557125) (xy 366.843625 -233.593848) (xy 366.801609 -233.624374) (xy 366.755335 -233.647952)
			(xy 366.705942 -233.664) (xy 366.654647 -233.672125) (xy 366.602713 -233.672125) (xy 366.551418 -233.664)
			(xy 366.502025 -233.647952) (xy 366.455751 -233.624374) (xy 366.413735 -233.593848) (xy 366.377012 -233.557125)
			(xy 366.346486 -233.515109) (xy 366.322908 -233.468835) (xy 366.30686 -233.419442) (xy 366.298735 -233.368147)
			(xy 366.018825 -233.368147) (xy 366.0107 -233.419442) (xy 365.994652 -233.468835) (xy 365.971074 -233.515109)
			(xy 365.940548 -233.557125) (xy 365.903825 -233.593848) (xy 365.861809 -233.624374) (xy 365.815535 -233.647952)
			(xy 365.766142 -233.664) (xy 365.714847 -233.672125) (xy 365.662913 -233.672125) (xy 365.611618 -233.664)
			(xy 365.562225 -233.647952) (xy 365.515951 -233.624374) (xy 365.473935 -233.593848) (xy 365.437212 -233.557125)
			(xy 365.406686 -233.515109) (xy 365.383108 -233.468835) (xy 365.36706 -233.419442) (xy 365.358935 -233.368147)
			(xy 365.079025 -233.368147) (xy 365.0709 -233.419442) (xy 365.054852 -233.468835) (xy 365.031274 -233.515109)
			(xy 365.000748 -233.557125) (xy 364.964025 -233.593848) (xy 364.922009 -233.624374) (xy 364.875735 -233.647952)
			(xy 364.826342 -233.664) (xy 364.775047 -233.672125) (xy 364.723113 -233.672125) (xy 364.671818 -233.664)
			(xy 364.622425 -233.647952) (xy 364.576151 -233.624374) (xy 364.534135 -233.593848) (xy 364.497412 -233.557125)
			(xy 364.466886 -233.515109) (xy 364.443308 -233.468835) (xy 364.42726 -233.419442) (xy 364.419135 -233.368147)
			(xy 364.138242 -233.368147) (xy 364.13628 -233.393381) (xy 364.124427 -233.443345) (xy 364.104987 -233.490875)
			(xy 364.07843 -233.534825) (xy 364.062264 -233.554778) (xy 364.062264 -233.739944) (xy 364.062662 -233.75333)
			(xy 364.06962 -233.779181) (xy 364.083069 -233.802329) (xy 364.102082 -233.821176) (xy 364.125347 -233.834421)
			(xy 364.151258 -233.841151) (xy 364.178028 -233.840901) (xy 364.191042 -233.837734) (xy 364.21252 -233.832164)
			(xy 364.256486 -233.826179) (xy 364.278672 -233.825796) (xy 364.279434 -233.825796) (xy 364.305396 -233.826308)
			(xy 364.356679 -233.834435) (xy 364.406059 -233.850484) (xy 364.452321 -233.87406) (xy 364.494326 -233.904582)
			(xy 364.53104 -233.9413) (xy 364.561558 -233.983308) (xy 364.585129 -234.029572) (xy 364.601173 -234.078954)
			(xy 364.609295 -234.130238) (xy 364.609295 -234.182162) (xy 364.609286 -234.182217) (xy 364.889289 -234.182217)
			(xy 364.889289 -234.130283) (xy 364.897414 -234.078988) (xy 364.913462 -234.029595) (xy 364.93704 -233.983321)
			(xy 364.967566 -233.941305) (xy 365.004289 -233.904582) (xy 365.046305 -233.874056) (xy 365.092579 -233.850478)
			(xy 365.141972 -233.83443) (xy 365.193267 -233.826305) (xy 365.245201 -233.826305) (xy 365.296496 -233.83443)
			(xy 365.345889 -233.850478) (xy 365.392163 -233.874056) (xy 365.434179 -233.904582) (xy 365.470902 -233.941305)
			(xy 365.501428 -233.983321) (xy 365.525006 -234.029595) (xy 365.541054 -234.078988) (xy 365.549179 -234.130283)
			(xy 365.549688 -234.15625) (xy 365.549179 -234.182217) (xy 365.829089 -234.182217) (xy 365.829089 -234.130283)
			(xy 365.837214 -234.078988) (xy 365.853262 -234.029595) (xy 365.87684 -233.983321) (xy 365.907366 -233.941305)
			(xy 365.944089 -233.904582) (xy 365.986105 -233.874056) (xy 366.032379 -233.850478) (xy 366.081772 -233.83443)
			(xy 366.133067 -233.826305) (xy 366.185001 -233.826305) (xy 366.236296 -233.83443) (xy 366.285689 -233.850478)
			(xy 366.331963 -233.874056) (xy 366.373979 -233.904582) (xy 366.410702 -233.941305) (xy 366.441228 -233.983321)
			(xy 366.464806 -234.029595) (xy 366.480854 -234.078988) (xy 366.488979 -234.130283) (xy 366.489488 -234.15625)
			(xy 366.488979 -234.182217) (xy 366.768889 -234.182217) (xy 366.768889 -234.130283) (xy 366.777014 -234.078988)
			(xy 366.793062 -234.029595) (xy 366.81664 -233.983321) (xy 366.847166 -233.941305) (xy 366.883889 -233.904582)
			(xy 366.925905 -233.874056) (xy 366.972179 -233.850478) (xy 367.021572 -233.83443) (xy 367.072867 -233.826305)
			(xy 367.124801 -233.826305) (xy 367.176096 -233.83443) (xy 367.225489 -233.850478) (xy 367.271763 -233.874056)
			(xy 367.313779 -233.904582) (xy 367.350502 -233.941305) (xy 367.381028 -233.983321) (xy 367.404606 -234.029595)
			(xy 367.420654 -234.078988) (xy 367.428779 -234.130283) (xy 367.429288 -234.15625) (xy 367.428779 -234.182217)
			(xy 367.708689 -234.182217) (xy 367.708689 -234.130283) (xy 367.716814 -234.078988) (xy 367.732862 -234.029595)
			(xy 367.75644 -233.983321) (xy 367.786966 -233.941305) (xy 367.823689 -233.904582) (xy 367.865705 -233.874056)
			(xy 367.911979 -233.850478) (xy 367.961372 -233.83443) (xy 368.012667 -233.826305) (xy 368.064601 -233.826305)
			(xy 368.115896 -233.83443) (xy 368.165289 -233.850478) (xy 368.211563 -233.874056) (xy 368.253579 -233.904582)
			(xy 368.290302 -233.941305) (xy 368.320828 -233.983321) (xy 368.344406 -234.029595) (xy 368.360454 -234.078988)
			(xy 368.368579 -234.130283) (xy 368.369088 -234.15625) (xy 368.368579 -234.182217) (xy 368.360454 -234.233512)
			(xy 368.344406 -234.282905) (xy 368.320828 -234.329179) (xy 368.290302 -234.371195) (xy 368.253579 -234.407918)
			(xy 368.211563 -234.438444) (xy 368.165289 -234.462022) (xy 368.115896 -234.47807) (xy 368.064601 -234.486195)
			(xy 368.012667 -234.486195) (xy 367.961372 -234.47807) (xy 367.911979 -234.462022) (xy 367.865705 -234.438444)
			(xy 367.823689 -234.407918) (xy 367.786966 -234.371195) (xy 367.75644 -234.329179) (xy 367.732862 -234.282905)
			(xy 367.716814 -234.233512) (xy 367.708689 -234.182217) (xy 367.428779 -234.182217) (xy 367.420654 -234.233512)
			(xy 367.404606 -234.282905) (xy 367.381028 -234.329179) (xy 367.350502 -234.371195) (xy 367.313779 -234.407918)
			(xy 367.271763 -234.438444) (xy 367.225489 -234.462022) (xy 367.176096 -234.47807) (xy 367.124801 -234.486195)
			(xy 367.072867 -234.486195) (xy 367.021572 -234.47807) (xy 366.972179 -234.462022) (xy 366.925905 -234.438444)
			(xy 366.883889 -234.407918) (xy 366.847166 -234.371195) (xy 366.81664 -234.329179) (xy 366.793062 -234.282905)
			(xy 366.777014 -234.233512) (xy 366.768889 -234.182217) (xy 366.488979 -234.182217) (xy 366.480854 -234.233512)
			(xy 366.464806 -234.282905) (xy 366.441228 -234.329179) (xy 366.410702 -234.371195) (xy 366.373979 -234.407918)
			(xy 366.331963 -234.438444) (xy 366.285689 -234.462022) (xy 366.236296 -234.47807) (xy 366.185001 -234.486195)
			(xy 366.133067 -234.486195) (xy 366.081772 -234.47807) (xy 366.032379 -234.462022) (xy 365.986105 -234.438444)
			(xy 365.944089 -234.407918) (xy 365.907366 -234.371195) (xy 365.87684 -234.329179) (xy 365.853262 -234.282905)
			(xy 365.837214 -234.233512) (xy 365.829089 -234.182217) (xy 365.549179 -234.182217) (xy 365.541054 -234.233512)
			(xy 365.525006 -234.282905) (xy 365.501428 -234.329179) (xy 365.470902 -234.371195) (xy 365.434179 -234.407918)
			(xy 365.392163 -234.438444) (xy 365.345889 -234.462022) (xy 365.296496 -234.47807) (xy 365.245201 -234.486195)
			(xy 365.193267 -234.486195) (xy 365.141972 -234.47807) (xy 365.092579 -234.462022) (xy 365.046305 -234.438444)
			(xy 365.004289 -234.407918) (xy 364.967566 -234.371195) (xy 364.93704 -234.329179) (xy 364.913462 -234.282905)
			(xy 364.897414 -234.233512) (xy 364.889289 -234.182217) (xy 364.609286 -234.182217) (xy 364.601173 -234.233446)
			(xy 364.585129 -234.282828) (xy 364.561558 -234.329092) (xy 364.53104 -234.3711) (xy 364.494326 -234.407818)
			(xy 364.452321 -234.43834) (xy 364.406059 -234.461916) (xy 364.356679 -234.477965) (xy 364.305396 -234.486092)
			(xy 364.279434 -234.486704) (xy 364.278672 -234.486704) (xy 364.256489 -234.486293) (xy 364.212527 -234.480304)
			(xy 364.191042 -234.474766) (xy 364.178042 -234.471581) (xy 364.151285 -234.471379) (xy 364.125394 -234.478136)
			(xy 364.102148 -234.491387) (xy 364.083143 -234.510223) (xy 364.069685 -234.533349) (xy 364.062696 -234.559178)
			(xy 364.062264 -234.572556) (xy 364.062264 -235.881926) (xy 364.443264 -236.262926) (xy 368.278664 -236.262926)
		)
		(stroke
			(width 0)
			(type solid)
		)
		(fill yes)
		(layer "In2.Cu")
		(net "PVCCINFAON_CPU0")
	)
	(gr_poly
		(pts
			(xy 432.700684 -185.270648) (xy 432.699033 -185.257885) (xy 432.697253 -185.232209) (xy 432.697128 -185.21934)
			(xy 432.697614 -185.192071) (xy 432.705376 -185.138087) (xy 432.720741 -185.085757) (xy 432.743398 -185.036147)
			(xy 432.772884 -184.990266) (xy 432.808599 -184.949049) (xy 432.849816 -184.913334) (xy 432.895697 -184.883848)
			(xy 432.945307 -184.861191) (xy 432.997637 -184.845826) (xy 433.051621 -184.838064) (xy 433.106159 -184.838064)
			(xy 433.160143 -184.845826) (xy 433.212473 -184.861191) (xy 433.262083 -184.883848) (xy 433.307964 -184.913334)
			(xy 433.349181 -184.949049) (xy 433.384896 -184.990266) (xy 433.414382 -185.036147) (xy 433.437039 -185.085757)
			(xy 433.452404 -185.138087) (xy 433.460166 -185.192071) (xy 433.460652 -185.21934) (xy 433.460518 -185.232208)
			(xy 433.458738 -185.257884) (xy 433.457096 -185.270648) (xy 434.77688 -185.270648) (xy 434.79114 -185.270173)
			(xy 434.818551 -185.262295) (xy 434.842716 -185.247147) (xy 434.861753 -185.22591) (xy 434.874178 -185.200238)
			(xy 434.879022 -185.172132) (xy 434.875909 -185.143782) (xy 434.87086 -185.13044) (xy 434.859445 -185.104969)
			(xy 434.843365 -185.051521) (xy 434.835269 -184.996296) (xy 434.834792 -184.968388) (xy 434.834792 -184.963816)
			(xy 434.835587 -184.936778) (xy 434.843868 -184.883324) (xy 434.859615 -184.831576) (xy 434.882514 -184.782571)
			(xy 434.912104 -184.73729) (xy 434.947792 -184.696643) (xy 434.988864 -184.661444) (xy 435.034496 -184.632399)
			(xy 435.083772 -184.610089) (xy 435.135705 -184.594963) (xy 435.189254 -184.587324) (xy 435.243346 -184.587324)
			(xy 435.296895 -184.594963) (xy 435.348828 -184.610089) (xy 435.398104 -184.632399) (xy 435.443736 -184.661444)
			(xy 435.484808 -184.696643) (xy 435.520496 -184.73729) (xy 435.550086 -184.782571) (xy 435.572985 -184.831576)
			(xy 435.588732 -184.883324) (xy 435.597013 -184.936778) (xy 435.597808 -184.963816) (xy 435.597808 -184.968388)
			(xy 435.597296 -184.996292) (xy 435.589175 -185.051507) (xy 435.573119 -185.104956) (xy 435.56174 -185.13044)
			(xy 435.556772 -185.143803) (xy 435.553661 -185.17213) (xy 435.558502 -185.200213) (xy 435.570917 -185.225863)
			(xy 435.589938 -185.247083) (xy 435.614083 -185.262219) (xy 435.641471 -185.27009) (xy 435.65572 -185.270648)
			(xy 447.46164 -185.270648) (xy 449.09994 -183.632348) (xy 449.09994 -174.71898) (xy 449.072508 -174.712376)
			(xy 449.044423 -174.705817) (xy 448.990495 -174.685382) (xy 448.940258 -174.657059) (xy 448.89486 -174.621494)
			(xy 448.855334 -174.579498) (xy 448.822582 -174.53203) (xy 448.797352 -174.480171) (xy 448.780218 -174.425104)
			(xy 448.771572 -174.368086) (xy 448.77101 -174.33925) (xy 448.771531 -174.310548) (xy 448.780135 -174.253791)
			(xy 448.797142 -174.198963) (xy 448.822167 -174.1473) (xy 448.854647 -174.099967) (xy 448.893848 -174.058031)
			(xy 448.938888 -174.02244) (xy 448.988749 -173.993994) (xy 449.042309 -173.973336) (xy 449.070222 -173.966632)
			(xy 449.09994 -173.959266) (xy 449.09994 -167.911272) (xy 448.773296 -167.584628) (xy 448.637152 -167.448738)
			(xy 446.62217 -165.433756) (xy 442.251846 -165.433756) (xy 442.22685 -165.433119) (xy 442.177827 -165.423318)
			(xy 442.131656 -165.404144) (xy 442.090113 -165.376332) (xy 442.072014 -165.35908) (xy 433.296568 -156.583634)
			(xy 433.279309 -156.56554) (xy 433.251494 -156.523995) (xy 433.232315 -156.477824) (xy 433.222507 -156.428799)
			(xy 433.221892 -156.403802) (xy 433.221892 -146.958558) (xy 431.51679 -145.253456) (xy 426.968158 -145.253456)
			(xy 426.943161 -145.25282) (xy 426.894137 -145.243022) (xy 426.847965 -145.223849) (xy 426.80642 -145.196038)
			(xy 426.788326 -145.17878) (xy 426.159168 -144.549622) (xy 426.14191 -144.531527) (xy 426.114097 -144.489983)
			(xy 426.09492 -144.443811) (xy 426.085114 -144.394787) (xy 426.084492 -144.36979) (xy 426.084492 -143.576294)
			(xy 426.085085 -143.551293) (xy 426.09488 -143.502257) (xy 426.114054 -143.456076) (xy 426.14187 -143.414522)
			(xy 426.159168 -143.396462) (xy 426.565314 -142.990316) (xy 426.583411 -142.973064) (xy 426.624958 -142.945262)
			(xy 426.671129 -142.926095) (xy 426.720151 -142.916299) (xy 426.745146 -142.91564) (xy 427.191678 -142.91564)
			(xy 427.196504 -142.883382) (xy 427.200072 -142.85573) (xy 427.214199 -142.801795) (xy 427.236027 -142.750491)
			(xy 427.265089 -142.702911) (xy 427.300768 -142.660068) (xy 427.342302 -142.622874) (xy 427.388808 -142.592122)
			(xy 427.439296 -142.568467) (xy 427.492688 -142.552412) (xy 427.547849 -142.544301) (xy 427.575726 -142.543784)
			(xy 427.602976 -142.544272) (xy 427.656922 -142.552031) (xy 427.709214 -142.567388) (xy 427.758788 -142.590031)
			(xy 427.804636 -142.619498) (xy 427.845824 -142.655189) (xy 427.881513 -142.696379) (xy 427.910978 -142.742228)
			(xy 427.933618 -142.791803) (xy 427.948973 -142.844096) (xy 427.95673 -142.898042) (xy 427.957234 -142.925292)
			(xy 427.956789 -142.951671) (xy 427.949527 -143.003928) (xy 427.935139 -143.054687) (xy 427.9139 -143.102982)
			(xy 427.886214 -143.147893) (xy 427.852609 -143.188565) (xy 427.813724 -143.224223) (xy 427.770301 -143.254188)
			(xy 427.746922 -143.266414) (xy 427.734563 -143.273117) (xy 427.713835 -143.292094) (xy 427.699074 -143.316009)
			(xy 427.691401 -143.343045) (xy 427.6914 -143.371148) (xy 427.699071 -143.398185) (xy 427.71383 -143.422101)
			(xy 427.734558 -143.441079) (xy 427.746922 -143.44777) (xy 427.77029 -143.460015) (xy 427.813714 -143.489974)
			(xy 427.852598 -143.525628) (xy 427.886201 -143.566297) (xy 427.913884 -143.611207) (xy 427.935117 -143.659501)
			(xy 427.949498 -143.710259) (xy 427.956751 -143.762514) (xy 427.957234 -143.788892) (xy 427.95673 -143.816627)
			(xy 427.948686 -143.871511) (xy 427.932781 -143.924653) (xy 427.909351 -143.974932) (xy 427.878888 -144.021289)
			(xy 427.842034 -144.062747) (xy 427.799567 -144.098434) (xy 427.752381 -144.127596) (xy 427.70147 -144.14962)
			(xy 427.647907 -144.164041) (xy 427.62043 -144.16786) (xy 427.606714 -144.169384) (xy 427.578229 -144.171173)
			(xy 427.52129 -144.167288) (xy 427.465564 -144.154968) (xy 427.412294 -144.134486) (xy 427.362667 -144.106301)
			(xy 427.317792 -144.071039) (xy 427.278668 -144.029488) (xy 427.246167 -143.982574) (xy 427.221016 -143.931343)
			(xy 427.203773 -143.876938) (xy 427.19879 -143.848836) (xy 427.191932 -143.805656) (xy 427.008798 -143.805656)
			(xy 426.974508 -143.839946) (xy 426.974508 -144.106138) (xy 427.23181 -144.36344) (xy 431.780442 -144.36344)
			(xy 431.805439 -144.364076) (xy 431.854463 -144.373874) (xy 431.900635 -144.393047) (xy 431.942181 -144.420857)
			(xy 431.960274 -144.438116) (xy 434.037232 -146.515074) (xy 434.05449 -146.533168) (xy 434.082304 -146.574713)
			(xy 434.101482 -146.620884) (xy 434.111288 -146.669909) (xy 434.111908 -146.694906) (xy 434.111908 -153.774902)
			(xy 436.385725 -153.774902) (xy 436.389718 -153.565161) (xy 436.401694 -153.355724) (xy 436.421635 -153.146895)
			(xy 436.449512 -152.938976) (xy 436.485284 -152.732269) (xy 436.528899 -152.527074) (xy 436.580295 -152.323689)
			(xy 436.639397 -152.122407) (xy 436.706119 -151.923521) (xy 436.780364 -151.72732) (xy 436.862024 -151.534088)
			(xy 436.950982 -151.344104) (xy 437.047109 -151.157645) (xy 437.150264 -150.974981) (xy 437.260299 -150.796376)
			(xy 437.377053 -150.62209) (xy 437.500358 -150.452375) (xy 437.630035 -150.287477) (xy 437.765896 -150.127636)
			(xy 437.907743 -149.973083) (xy 438.055372 -149.824043) (xy 438.208567 -149.68073) (xy 438.367108 -149.543354)
			(xy 438.530763 -149.412113) (xy 438.699297 -149.287198) (xy 438.872463 -149.16879) (xy 439.050013 -149.05706)
			(xy 439.231687 -148.95217) (xy 439.417222 -148.854273) (xy 439.60635 -148.763511) (xy 439.798797 -148.680014)
			(xy 439.994282 -148.603904) (xy 440.192524 -148.535292) (xy 440.393234 -148.474277) (xy 440.596121 -148.420948)
			(xy 440.800891 -148.375381) (xy 441.007248 -148.337642) (xy 441.214892 -148.307788) (xy 441.423522 -148.28586)
			(xy 441.632835 -148.271891) (xy 441.842529 -148.2659) (xy 442.052298 -148.267897) (xy 442.26184 -148.277879)
			(xy 442.47085 -148.295831) (xy 442.679024 -148.321727) (xy 442.886062 -148.355529) (xy 443.091663 -148.397189)
			(xy 443.295529 -148.446647) (xy 443.497364 -148.50383) (xy 443.696876 -148.568655) (xy 443.893775 -148.641029)
			(xy 444.087776 -148.720846) (xy 444.278598 -148.807992) (xy 444.465964 -148.902339) (xy 444.649602 -149.00375)
			(xy 444.829246 -149.11208) (xy 445.004636 -149.22717) (xy 445.175517 -149.348854) (xy 445.341641 -149.476955)
			(xy 445.502768 -149.611288) (xy 445.658665 -149.751657) (xy 445.809104 -149.89786) (xy 445.953868 -150.049684)
			(xy 446.092747 -150.20691) (xy 446.22554 -150.369309) (xy 446.352054 -150.536645) (xy 446.472106 -150.708677)
			(xy 446.585521 -150.885154) (xy 446.692135 -151.065822) (xy 446.791794 -151.250417) (xy 446.884353 -151.438672)
			(xy 446.969678 -151.630315) (xy 447.047645 -151.825067) (xy 447.118141 -152.022647) (xy 447.181064 -152.222766)
			(xy 447.236323 -152.425137) (xy 447.283837 -152.629464) (xy 447.323538 -152.835452) (xy 447.355368 -153.042803)
			(xy 447.379281 -153.251214) (xy 447.395242 -153.460385) (xy 447.403229 -153.670012) (xy 447.403728 -153.774902)
			(xy 447.403229 -153.879792) (xy 447.395242 -154.089419) (xy 447.379281 -154.29859) (xy 447.355368 -154.507001)
			(xy 447.323538 -154.714352) (xy 447.283837 -154.92034) (xy 447.236323 -155.124667) (xy 447.181064 -155.327038)
			(xy 447.118141 -155.527157) (xy 447.047645 -155.724737) (xy 446.969678 -155.919489) (xy 446.884353 -156.111132)
			(xy 446.791794 -156.299387) (xy 446.692135 -156.483982) (xy 446.585521 -156.66465) (xy 446.472106 -156.841127)
			(xy 446.352054 -157.013159) (xy 446.22554 -157.180495) (xy 446.092747 -157.342894) (xy 445.953868 -157.50012)
			(xy 445.809104 -157.651944) (xy 445.658665 -157.798147) (xy 445.502768 -157.938516) (xy 445.341641 -158.072849)
			(xy 445.175517 -158.20095) (xy 445.004636 -158.322634) (xy 444.829246 -158.437724) (xy 444.649602 -158.546054)
			(xy 444.465964 -158.647465) (xy 444.278598 -158.741812) (xy 444.087776 -158.828958) (xy 443.893775 -158.908775)
			(xy 443.696876 -158.981149) (xy 443.497364 -159.045974) (xy 443.295529 -159.103157) (xy 443.091663 -159.152615)
			(xy 442.886062 -159.194275) (xy 442.679024 -159.228077) (xy 442.47085 -159.253973) (xy 442.26184 -159.271925)
			(xy 442.052298 -159.281907) (xy 441.842529 -159.283904) (xy 441.632835 -159.277913) (xy 441.423522 -159.263944)
			(xy 441.214892 -159.242016) (xy 441.007248 -159.212162) (xy 440.800891 -159.174423) (xy 440.596121 -159.128856)
			(xy 440.393234 -159.075527) (xy 440.192524 -159.014512) (xy 439.994282 -158.9459) (xy 439.798797 -158.86979)
			(xy 439.60635 -158.786293) (xy 439.417222 -158.695531) (xy 439.231687 -158.597634) (xy 439.050013 -158.492744)
			(xy 438.872463 -158.381014) (xy 438.699297 -158.262606) (xy 438.530763 -158.137691) (xy 438.367108 -158.00645)
			(xy 438.208567 -157.869074) (xy 438.055372 -157.725761) (xy 437.907743 -157.576721) (xy 437.765896 -157.422168)
			(xy 437.630035 -157.262327) (xy 437.500358 -157.097429) (xy 437.377053 -156.927714) (xy 437.260299 -156.753428)
			(xy 437.150264 -156.574823) (xy 437.047109 -156.392159) (xy 436.950982 -156.2057) (xy 436.862024 -156.015716)
			(xy 436.780364 -155.822484) (xy 436.706119 -155.626283) (xy 436.639397 -155.427397) (xy 436.580295 -155.226115)
			(xy 436.528899 -155.02273) (xy 436.485284 -154.817535) (xy 436.449512 -154.610828) (xy 436.421635 -154.402909)
			(xy 436.401694 -154.19408) (xy 436.389718 -153.984643) (xy 436.385725 -153.774902) (xy 434.111908 -153.774902)
			(xy 434.111908 -156.14015) (xy 442.515498 -164.54374) (xy 446.885822 -164.54374) (xy 446.910819 -164.544374)
			(xy 446.959846 -164.554169) (xy 447.006021 -164.573339) (xy 447.047569 -164.601148) (xy 447.065654 -164.618416)
			(xy 447.30797 -164.860986) (xy 448.348608 -165.90137) (xy 448.931538 -166.4843) (xy 448.942815 -166.493509)
			(xy 448.969255 -166.50567) (xy 448.998052 -166.509884) (xy 449.026868 -166.50581) (xy 449.053367 -166.493777)
			(xy 449.075399 -166.474762) (xy 449.091178 -166.450308) (xy 449.099422 -166.422397) (xy 449.09994 -166.407846)
			(xy 449.09994 -151.160226) (xy 445.30645 -147.366736) (xy 436.27548 -147.366736) (xy 436.24919 -147.366348)
			(xy 436.196982 -147.360103) (xy 436.17134 -147.35429) (xy 436.141765 -147.346628) (xy 436.084902 -147.32429)
			(xy 436.031636 -147.294372) (xy 435.982971 -147.257437) (xy 435.961028 -147.23618) (xy 433.351432 -144.626584)
			(xy 433.332836 -144.607545) (xy 433.299855 -144.565775) (xy 433.285646 -144.543272) (xy 433.278256 -144.530899)
			(xy 433.264908 -144.505352) (xy 433.258976 -144.492218) (xy 433.246784 -144.461484) (xy 433.240688 -144.444212)
			(xy 433.236878 -144.42948) (xy 433.236624 -144.42948) (xy 433.234084 -144.419574) (xy 433.227907 -144.393144)
			(xy 433.221282 -144.339271) (xy 433.220876 -144.312132) (xy 433.220876 -139.066016) (xy 433.221351 -139.036879)
			(xy 433.228956 -138.979103) (xy 433.244036 -138.922813) (xy 433.266335 -138.868974) (xy 433.29547 -138.818506)
			(xy 433.330944 -138.772272) (xy 433.372148 -138.731065) (xy 433.418379 -138.695588) (xy 433.468845 -138.666449)
			(xy 433.522683 -138.644146) (xy 433.578971 -138.629062) (xy 433.636747 -138.621453) (xy 433.665884 -138.621008)
			(xy 433.688396 -138.621295) (xy 433.733187 -138.625879) (xy 433.755292 -138.630152) (xy 433.769961 -138.632621)
			(xy 433.799571 -138.629925) (xy 433.827152 -138.618818) (xy 433.850367 -138.600241) (xy 433.867251 -138.575767)
			(xy 433.876374 -138.547469) (xy 433.877212 -138.532616) (xy 433.878176 -138.505698) (xy 433.886742 -138.452521)
			(xy 433.902703 -138.401078) (xy 433.925742 -138.352392) (xy 433.955401 -138.307431) (xy 433.991089 -138.267089)
			(xy 434.032098 -138.232168) (xy 434.077612 -138.203364) (xy 434.126724 -138.181248) (xy 434.17846 -138.166262)
			(xy 434.231789 -138.158701) (xy 434.25872 -138.15822) (xy 434.285968 -138.158708) (xy 434.33991 -138.166466)
			(xy 434.392198 -138.181822) (xy 434.441769 -138.204462) (xy 434.487614 -138.233927) (xy 434.528799 -138.269616)
			(xy 434.564485 -138.310802) (xy 434.593947 -138.356648) (xy 434.616585 -138.40622) (xy 434.631938 -138.45851)
			(xy 434.639694 -138.512452) (xy 434.639694 -138.566948) (xy 434.631938 -138.62089) (xy 434.616585 -138.67318)
			(xy 434.593947 -138.722752) (xy 434.564485 -138.768598) (xy 434.528799 -138.809784) (xy 434.487614 -138.845473)
			(xy 434.441769 -138.874938) (xy 434.392198 -138.897578) (xy 434.33991 -138.912934) (xy 434.285968 -138.920692)
			(xy 434.25872 -138.921236) (xy 434.24803 -138.92119) (xy 434.226682 -138.920044) (xy 434.216048 -138.91895)
			(xy 434.201868 -138.918627) (xy 434.174217 -138.924887) (xy 434.149349 -138.938502) (xy 434.129176 -138.958423)
			(xy 434.11525 -138.983118) (xy 434.108642 -139.010689) (xy 434.10886 -139.024868) (xy 434.110384 -139.045442)
			(xy 434.110892 -139.066016) (xy 434.110892 -144.127982) (xy 434.68798 -144.70507) (xy 435.98668 -144.70507)
			(xy 435.990751 -144.649448) (xy 436.002877 -144.595011) (xy 436.0228 -144.54292) (xy 436.050096 -144.494285)
			(xy 436.084182 -144.450142) (xy 436.124331 -144.411433) (xy 436.169689 -144.378982) (xy 436.219289 -144.353481)
			(xy 436.272073 -144.335474) (xy 436.326916 -144.325344) (xy 436.38265 -144.323307) (xy 436.438087 -144.329407)
			(xy 436.492044 -144.343513) (xy 436.543373 -144.365325) (xy 436.590979 -144.394379) (xy 436.633847 -144.430054)
			(xy 436.671064 -144.471591) (xy 436.701837 -144.518104) (xy 436.725509 -144.568601) (xy 436.741577 -144.622008)
			(xy 436.749697 -144.677184) (xy 436.750206 -144.70507) (xy 436.749697 -144.732956) (xy 436.741577 -144.788132)
			(xy 436.725509 -144.841539) (xy 436.701837 -144.892036) (xy 436.671064 -144.938549) (xy 436.633847 -144.980086)
			(xy 436.590979 -145.015761) (xy 436.543373 -145.044815) (xy 436.492044 -145.066627) (xy 436.438087 -145.080733)
			(xy 436.38265 -145.086833) (xy 436.326916 -145.084796) (xy 436.272073 -145.074666) (xy 436.219289 -145.056659)
			(xy 436.169689 -145.031158) (xy 436.124331 -144.998707) (xy 436.084182 -144.959998) (xy 436.050096 -144.915855)
			(xy 436.0228 -144.86722) (xy 436.002877 -144.815129) (xy 435.990751 -144.760692) (xy 435.98668 -144.70507)
			(xy 434.68798 -144.70507) (xy 436.45963 -146.47672) (xy 445.4906 -146.47672) (xy 445.51689 -146.477106)
			(xy 445.569099 -146.483349) (xy 445.59474 -146.489166) (xy 445.624316 -146.496826) (xy 445.681182 -146.51916)
			(xy 445.734452 -146.549075) (xy 445.783121 -146.586006) (xy 445.805052 -146.607276) (xy 448.926458 -149.728428)
			(xy 448.937424 -149.738645) (xy 448.963839 -149.752776) (xy 448.993217 -149.758637) (xy 449.023033 -149.755725)
			(xy 449.050722 -149.744289) (xy 449.073903 -149.725313) (xy 449.090584 -149.70043) (xy 449.09933 -149.671778)
			(xy 449.09994 -149.6568) (xy 449.09994 -137.478262) (xy 449.062602 -137.468102) (xy 449.03327 -137.459643)
			(xy 448.976456 -137.437302) (xy 448.922348 -137.409027) (xy 448.89674 -137.39241) (xy 448.869524 -137.410039)
			(xy 448.811863 -137.439711) (xy 448.751213 -137.46266) (xy 448.688353 -137.478591) (xy 448.624093 -137.487299)
			(xy 448.591686 -137.488422) (xy 448.579748 -137.488676) (xy 448.578732 -137.488676) (xy 448.566652 -137.488612)
			(xy 448.542514 -137.487596) (xy 448.530472 -137.486644) (xy 448.529202 -137.48639) (xy 448.506088 -137.484358)
			(xy 448.483736 -137.480548) (xy 448.450839 -137.474494) (xy 448.386641 -137.455704) (xy 448.325072 -137.429557)
			(xy 448.266972 -137.396407) (xy 448.213135 -137.356707) (xy 448.164295 -137.311) (xy 448.12112 -137.259909)
			(xy 448.084197 -137.204131) (xy 448.054031 -137.144428) (xy 448.031033 -137.081614) (xy 448.015518 -137.016546)
			(xy 448.007698 -136.950114) (xy 448.007232 -136.916668) (xy 448.007232 -124.999242) (xy 444.132716 -121.124472)
			(xy 444.121533 -121.114897) (xy 444.095065 -121.102032) (xy 444.066028 -121.097245) (xy 444.036831 -121.100933)
			(xy 444.009897 -121.11279) (xy 443.987459 -121.131832) (xy 443.971379 -121.156479) (xy 443.962992 -121.184688)
			(xy 443.962536 -121.199402) (xy 443.962536 -126.606554) (xy 443.962021 -126.631537) (xy 443.954165 -126.680881)
			(xy 443.9387 -126.728394) (xy 443.916006 -126.772909) (xy 443.88664 -126.813335) (xy 443.869318 -126.831344)
			(xy 442.190124 -128.510538) (xy 442.17214 -128.527893) (xy 442.131728 -128.557294) (xy 442.087209 -128.580002)
			(xy 442.039682 -128.595455) (xy 441.990322 -128.603273) (xy 441.965334 -128.603756) (xy 439.18886 -128.603756)
			(xy 435.526688 -132.266182) (xy 435.508704 -132.283538) (xy 435.468292 -132.312944) (xy 435.423774 -132.335657)
			(xy 435.376248 -132.351118) (xy 435.326887 -132.358945) (xy 435.301898 -132.3594) (xy 432.680364 -132.3594)
			(xy 432.655381 -132.358886) (xy 432.606036 -132.351032) (xy 432.558522 -132.335568) (xy 432.514007 -132.312874)
			(xy 432.473581 -132.283507) (xy 432.455574 -132.266182) (xy 432.16322 -131.973574) (xy 432.14925 -131.970018)
			(xy 432.121842 -131.962923) (xy 432.069341 -131.941739) (xy 432.020553 -131.913022) (xy 431.976549 -131.877402)
			(xy 431.938299 -131.835665) (xy 431.906644 -131.788728) (xy 431.882281 -131.737625) (xy 431.865747 -131.68348)
			(xy 431.857404 -131.627485) (xy 431.856896 -131.599178) (xy 431.85715 -131.585208) (xy 431.85715 -131.584192)
			(xy 431.85861 -131.558426) (xy 431.867605 -131.507609) (xy 431.883362 -131.458466) (xy 431.905595 -131.411893)
			(xy 431.933897 -131.368739) (xy 431.967754 -131.329789) (xy 432.006548 -131.295755) (xy 432.027838 -131.28117)
			(xy 432.038847 -131.271904) (xy 432.055632 -131.248547) (xy 432.065241 -131.221438) (xy 432.066913 -131.192725)
			(xy 432.060516 -131.164683) (xy 432.046557 -131.139536) (xy 432.036728 -131.129024) (xy 431.611278 -130.703574)
			(xy 431.597308 -130.700018) (xy 431.569902 -130.692921) (xy 431.517407 -130.671733) (xy 431.468623 -130.643013)
			(xy 431.424624 -130.607392) (xy 431.386378 -130.565655) (xy 431.354728 -130.518719) (xy 431.330368 -130.467618)
			(xy 431.313836 -130.413476) (xy 431.305494 -130.357483) (xy 431.304954 -130.329178) (xy 431.305441 -130.301927)
			(xy 431.3132 -130.247979) (xy 431.328557 -130.195685) (xy 431.351199 -130.146108) (xy 431.380665 -130.100258)
			(xy 431.416356 -130.059067) (xy 431.457545 -130.023375) (xy 431.503394 -129.993906) (xy 431.55297 -129.971262)
			(xy 431.605264 -129.955904) (xy 431.659211 -129.948142) (xy 431.686462 -129.94767) (xy 431.714764 -129.94819)
			(xy 431.770744 -129.956564) (xy 431.824873 -129.973119) (xy 431.87596 -129.997492) (xy 431.922885 -130.029146)
			(xy 431.964616 -130.067389) (xy 432.000238 -130.111378) (xy 432.028968 -130.160148) (xy 432.050174 -130.212629)
			(xy 432.057302 -130.240024) (xy 432.060858 -130.253994) (xy 433.051204 -131.24434) (xy 433.820316 -131.24434)
			(xy 433.834274 -131.243861) (xy 433.861126 -131.23622) (xy 433.884907 -131.221594) (xy 433.903841 -131.201077)
			(xy 433.916514 -131.176201) (xy 433.921979 -131.148823) (xy 433.921408 -131.134866) (xy 433.920216 -131.12392)
			(xy 433.918942 -131.101935) (xy 433.918868 -131.090924) (xy 433.918868 -131.084066) (xy 433.920184 -131.049813)
			(xy 433.933608 -130.982598) (xy 433.945538 -130.950462) (xy 433.949532 -130.93642) (xy 433.950204 -130.907244)
			(xy 433.942607 -130.879067) (xy 433.927359 -130.854185) (xy 433.905702 -130.834623) (xy 433.879401 -130.821977)
			(xy 433.850599 -130.817276) (xy 433.836064 -130.818636) (xy 433.817408 -130.822196) (xy 433.779617 -130.826017)
			(xy 433.760626 -130.826256) (xy 433.759864 -130.826256) (xy 433.732611 -130.825768) (xy 433.67866 -130.818006)
			(xy 433.626363 -130.802646) (xy 433.576784 -130.78) (xy 433.530933 -130.750529) (xy 433.489742 -130.714833)
			(xy 433.45405 -130.673638) (xy 433.424583 -130.627784) (xy 433.401942 -130.578203) (xy 433.386586 -130.525904)
			(xy 433.37883 -130.471953) (xy 433.37883 -130.417447) (xy 433.386586 -130.363496) (xy 433.401942 -130.311197)
			(xy 433.424583 -130.261616) (xy 433.45405 -130.215762) (xy 433.489742 -130.174567) (xy 433.530933 -130.138871)
			(xy 433.576784 -130.1094) (xy 433.626363 -130.086754) (xy 433.67866 -130.071394) (xy 433.732611 -130.063632)
			(xy 433.759864 -130.06324) (xy 433.786957 -130.063712) (xy 433.840598 -130.071372) (xy 433.892616 -130.086545)
			(xy 433.941964 -130.108924) (xy 433.98765 -130.138059) (xy 434.028755 -130.173364) (xy 434.064452 -130.21413)
			(xy 434.094022 -130.259536) (xy 434.116871 -130.308668) (xy 434.13254 -130.360539) (xy 434.140712 -130.414104)
			(xy 434.141372 -130.441192) (xy 434.141372 -130.445256) (xy 434.141008 -130.469057) (xy 434.135083 -130.516289)
			(xy 434.12332 -130.562416) (xy 434.114956 -130.584702) (xy 434.110878 -130.598755) (xy 434.110061 -130.627994)
			(xy 434.117559 -130.656268) (xy 434.132756 -130.68126) (xy 434.154409 -130.700926) (xy 434.180745 -130.713654)
			(xy 434.209608 -130.718402) (xy 434.224176 -130.717036) (xy 434.233574 -130.715258) (xy 434.255672 -130.711956)
			(xy 434.267102 -130.710686) (xy 434.300376 -130.709162) (xy 434.327493 -130.709636) (xy 434.381182 -130.717306)
			(xy 434.433245 -130.732496) (xy 434.482636 -130.7549) (xy 434.528359 -130.784067) (xy 434.569495 -130.819411)
			(xy 434.605216 -130.860219) (xy 434.634804 -130.905671) (xy 434.657663 -130.954853) (xy 434.673333 -131.006774)
			(xy 434.67782 -131.03352) (xy 434.680903 -131.046926) (xy 434.693189 -131.071526) (xy 434.711591 -131.091957)
			(xy 434.734776 -131.10674) (xy 434.761065 -131.114802) (xy 434.788551 -131.115561) (xy 434.815244 -131.10896)
			(xy 434.839209 -131.095479) (xy 434.84927 -131.086098) (xy 438.432956 -127.502158) (xy 438.45094 -127.484802)
			(xy 438.491352 -127.455399) (xy 438.53587 -127.432689) (xy 438.583397 -127.417232) (xy 438.632758 -127.409411)
			(xy 438.657746 -127.40894) (xy 441.579508 -127.40894) (xy 441.834524 -127.153924) (xy 441.940442 -127.04826)
			(xy 442.781436 -126.207266) (xy 442.781436 -123.78944) (xy 442.569346 -123.78944) (xy 442.544364 -123.788925)
			(xy 442.495021 -123.781066) (xy 442.447511 -123.765598) (xy 442.403 -123.742899) (xy 442.362581 -123.713528)
			(xy 442.344556 -123.696222) (xy 442.21781 -123.569476) (xy 442.200455 -123.551492) (xy 442.171052 -123.511079)
			(xy 442.148341 -123.466561) (xy 442.132882 -123.419035) (xy 442.125057 -123.369674) (xy 442.124592 -123.344686)
			(xy 442.124592 -122.963178) (xy 442.125105 -122.938195) (xy 442.132957 -122.888848) (xy 442.148419 -122.841333)
			(xy 442.171112 -122.796815) (xy 442.200477 -122.756387) (xy 442.21781 -122.738388) (xy 442.344556 -122.611642)
			(xy 442.36254 -122.594287) (xy 442.402952 -122.564885) (xy 442.447471 -122.542176) (xy 442.494997 -122.526721)
			(xy 442.544358 -122.5189) (xy 442.569346 -122.518424) (xy 442.781436 -122.518424) (xy 442.781436 -120.954546)
			(xy 439.959496 -118.13286) (xy 436.83301 -118.13286) (xy 436.808029 -118.132342) (xy 436.758689 -118.124479)
			(xy 436.711182 -118.109008) (xy 436.666674 -118.086307) (xy 436.626257 -118.056934) (xy 436.60822 -118.039642)
			(xy 435.808882 -117.240304) (xy 429.456596 -117.240304) (xy 429.37811 -117.353334) (xy 429.388761 -117.378074)
			(xy 429.403787 -117.429799) (xy 429.4114 -117.483121) (xy 429.411892 -117.510052) (xy 429.411892 -117.51056)
			(xy 429.411406 -117.537829) (xy 429.403644 -117.591813) (xy 429.388279 -117.644143) (xy 429.365622 -117.693753)
			(xy 429.336136 -117.739634) (xy 429.300421 -117.780851) (xy 429.259204 -117.816566) (xy 429.213323 -117.846052)
			(xy 429.163713 -117.868709) (xy 429.111383 -117.884074) (xy 429.057399 -117.891836) (xy 429.002861 -117.891836)
			(xy 428.948877 -117.884074) (xy 428.896547 -117.868709) (xy 428.846937 -117.846052) (xy 428.801056 -117.816566)
			(xy 428.759839 -117.780851) (xy 428.724124 -117.739634) (xy 428.694638 -117.693753) (xy 428.671981 -117.644143)
			(xy 428.656616 -117.591813) (xy 428.648854 -117.537829) (xy 428.648368 -117.51056) (xy 428.648368 -117.510052)
			(xy 428.648849 -117.48312) (xy 428.656462 -117.429797) (xy 428.6715 -117.378075) (xy 428.68215 -117.353334)
			(xy 428.603664 -117.240304) (xy 428.34687 -117.240304) (xy 428.275496 -117.372892) (xy 428.292514 -117.398292)
			(xy 428.307631 -117.421884) (xy 428.331534 -117.472559) (xy 428.347774 -117.526183) (xy 428.356003 -117.581605)
			(xy 428.356522 -117.60962) (xy 428.356036 -117.636889) (xy 428.348274 -117.690873) (xy 428.332909 -117.743203)
			(xy 428.310252 -117.792813) (xy 428.280766 -117.838694) (xy 428.245051 -117.879911) (xy 428.203834 -117.915626)
			(xy 428.157953 -117.945112) (xy 428.108343 -117.967769) (xy 428.056013 -117.983134) (xy 428.002029 -117.990896)
			(xy 427.947491 -117.990896) (xy 427.893507 -117.983134) (xy 427.841177 -117.967769) (xy 427.791567 -117.945112)
			(xy 427.745686 -117.915626) (xy 427.704469 -117.879911) (xy 427.668754 -117.838694) (xy 427.639268 -117.792813)
			(xy 427.616611 -117.743203) (xy 427.601246 -117.690873) (xy 427.593484 -117.636889) (xy 427.592998 -117.60962)
			(xy 427.593512 -117.581606) (xy 427.601745 -117.526186) (xy 427.617994 -117.472565) (xy 427.641909 -117.421896)
			(xy 427.657006 -117.398292) (xy 427.674024 -117.372892) (xy 427.60265 -117.240304) (xy 411.604968 -117.240304)
			(xy 410.131006 -118.714266) (xy 410.131006 -119.916448) (xy 422.520362 -119.916448) (xy 422.524433 -119.860826)
			(xy 422.536559 -119.806389) (xy 422.556482 -119.754298) (xy 422.583778 -119.705663) (xy 422.617864 -119.66152)
			(xy 422.658013 -119.622811) (xy 422.703371 -119.59036) (xy 422.752971 -119.564859) (xy 422.805755 -119.546852)
			(xy 422.860598 -119.536722) (xy 422.916332 -119.534685) (xy 422.971769 -119.540785) (xy 423.025726 -119.554891)
			(xy 423.077055 -119.576703) (xy 423.089365 -119.584216) (xy 433.69814 -119.584216) (xy 433.702211 -119.528594)
			(xy 433.714337 -119.474157) (xy 433.73426 -119.422066) (xy 433.761556 -119.373431) (xy 433.795642 -119.329288)
			(xy 433.835791 -119.290579) (xy 433.881149 -119.258128) (xy 433.930749 -119.232627) (xy 433.983533 -119.21462)
			(xy 434.038376 -119.20449) (xy 434.09411 -119.202453) (xy 434.149547 -119.208553) (xy 434.203504 -119.222659)
			(xy 434.254833 -119.244471) (xy 434.302439 -119.273525) (xy 434.345307 -119.3092) (xy 434.382524 -119.350737)
			(xy 434.413297 -119.39725) (xy 434.436969 -119.447747) (xy 434.453037 -119.501154) (xy 434.461157 -119.55633)
			(xy 434.461666 -119.584216) (xy 434.96814 -119.584216) (xy 434.972211 -119.528594) (xy 434.984337 -119.474157)
			(xy 435.00426 -119.422066) (xy 435.031556 -119.373431) (xy 435.065642 -119.329288) (xy 435.105791 -119.290579)
			(xy 435.151149 -119.258128) (xy 435.200749 -119.232627) (xy 435.253533 -119.21462) (xy 435.308376 -119.20449)
			(xy 435.36411 -119.202453) (xy 435.419547 -119.208553) (xy 435.473504 -119.222659) (xy 435.524833 -119.244471)
			(xy 435.572439 -119.273525) (xy 435.615307 -119.3092) (xy 435.652524 -119.350737) (xy 435.683297 -119.39725)
			(xy 435.706969 -119.447747) (xy 435.723037 -119.501154) (xy 435.731157 -119.55633) (xy 435.731666 -119.584216)
			(xy 435.731157 -119.612102) (xy 435.723037 -119.667278) (xy 435.706969 -119.720685) (xy 435.683297 -119.771182)
			(xy 435.652524 -119.817695) (xy 435.615307 -119.859232) (xy 435.572439 -119.894907) (xy 435.524833 -119.923961)
			(xy 435.473504 -119.945773) (xy 435.419547 -119.959879) (xy 435.36411 -119.965979) (xy 435.308376 -119.963942)
			(xy 435.253533 -119.953812) (xy 435.200749 -119.935805) (xy 435.151149 -119.910304) (xy 435.105791 -119.877853)
			(xy 435.065642 -119.839144) (xy 435.031556 -119.795001) (xy 435.00426 -119.746366) (xy 434.984337 -119.694275)
			(xy 434.972211 -119.639838) (xy 434.96814 -119.584216) (xy 434.461666 -119.584216) (xy 434.461157 -119.612102)
			(xy 434.453037 -119.667278) (xy 434.436969 -119.720685) (xy 434.413297 -119.771182) (xy 434.382524 -119.817695)
			(xy 434.345307 -119.859232) (xy 434.302439 -119.894907) (xy 434.254833 -119.923961) (xy 434.203504 -119.945773)
			(xy 434.149547 -119.959879) (xy 434.09411 -119.965979) (xy 434.038376 -119.963942) (xy 433.983533 -119.953812)
			(xy 433.930749 -119.935805) (xy 433.881149 -119.910304) (xy 433.835791 -119.877853) (xy 433.795642 -119.839144)
			(xy 433.761556 -119.795001) (xy 433.73426 -119.746366) (xy 433.714337 -119.694275) (xy 433.702211 -119.639838)
			(xy 433.69814 -119.584216) (xy 423.089365 -119.584216) (xy 423.124661 -119.605757) (xy 423.167529 -119.641432)
			(xy 423.204746 -119.682969) (xy 423.235519 -119.729482) (xy 423.259191 -119.779979) (xy 423.275259 -119.833386)
			(xy 423.283379 -119.888562) (xy 423.283888 -119.916448) (xy 423.283379 -119.944334) (xy 423.275259 -119.99951)
			(xy 423.259191 -120.052917) (xy 423.259105 -120.0531) (xy 429.699926 -120.0531) (xy 429.703997 -119.997478)
			(xy 429.716123 -119.943041) (xy 429.736046 -119.89095) (xy 429.763342 -119.842315) (xy 429.797428 -119.798172)
			(xy 429.837577 -119.759463) (xy 429.882935 -119.727012) (xy 429.932535 -119.701511) (xy 429.985319 -119.683504)
			(xy 430.040162 -119.673374) (xy 430.095896 -119.671337) (xy 430.151333 -119.677437) (xy 430.20529 -119.691543)
			(xy 430.256619 -119.713355) (xy 430.304225 -119.742409) (xy 430.347093 -119.778084) (xy 430.38431 -119.819621)
			(xy 430.415083 -119.866134) (xy 430.438755 -119.916631) (xy 430.454823 -119.970038) (xy 430.462943 -120.025214)
			(xy 430.463452 -120.0531) (xy 430.462943 -120.080986) (xy 430.454823 -120.136162) (xy 430.438755 -120.189569)
			(xy 430.415083 -120.240066) (xy 430.38431 -120.286579) (xy 430.347093 -120.328116) (xy 430.304225 -120.363791)
			(xy 430.256619 -120.392845) (xy 430.20529 -120.414657) (xy 430.151333 -120.428763) (xy 430.095896 -120.434863)
			(xy 430.040162 -120.432826) (xy 429.985319 -120.422696) (xy 429.932535 -120.404689) (xy 429.882935 -120.379188)
			(xy 429.837577 -120.346737) (xy 429.797428 -120.308028) (xy 429.763342 -120.263885) (xy 429.736046 -120.21525)
			(xy 429.716123 -120.163159) (xy 429.703997 -120.108722) (xy 429.699926 -120.0531) (xy 423.259105 -120.0531)
			(xy 423.235519 -120.103414) (xy 423.204746 -120.149927) (xy 423.167529 -120.191464) (xy 423.124661 -120.227139)
			(xy 423.077055 -120.256193) (xy 423.025726 -120.278005) (xy 422.971769 -120.292111) (xy 422.916332 -120.298211)
			(xy 422.860598 -120.296174) (xy 422.805755 -120.286044) (xy 422.752971 -120.268037) (xy 422.703371 -120.242536)
			(xy 422.658013 -120.210085) (xy 422.617864 -120.171376) (xy 422.583778 -120.127233) (xy 422.556482 -120.078598)
			(xy 422.536559 -120.026507) (xy 422.524433 -119.97207) (xy 422.520362 -119.916448) (xy 410.131006 -119.916448)
			(xy 410.131006 -120.497346) (xy 435.408576 -120.497346) (xy 435.412647 -120.441724) (xy 435.424773 -120.387287)
			(xy 435.444696 -120.335196) (xy 435.471992 -120.286561) (xy 435.506078 -120.242418) (xy 435.546227 -120.203709)
			(xy 435.591585 -120.171258) (xy 435.641185 -120.145757) (xy 435.693969 -120.12775) (xy 435.748812 -120.11762)
			(xy 435.804546 -120.115583) (xy 435.859983 -120.121683) (xy 435.91394 -120.135789) (xy 435.965269 -120.157601)
			(xy 436.012875 -120.186655) (xy 436.055743 -120.22233) (xy 436.09296 -120.263867) (xy 436.123733 -120.31038)
			(xy 436.147405 -120.360877) (xy 436.163473 -120.414284) (xy 436.171593 -120.46946) (xy 436.172102 -120.497346)
			(xy 436.171593 -120.525232) (xy 436.163473 -120.580408) (xy 436.147405 -120.633815) (xy 436.123733 -120.684312)
			(xy 436.09296 -120.730825) (xy 436.055743 -120.772362) (xy 436.012875 -120.808037) (xy 435.965269 -120.837091)
			(xy 435.91394 -120.858903) (xy 435.859983 -120.873009) (xy 435.804546 -120.879109) (xy 435.748812 -120.877072)
			(xy 435.693969 -120.866942) (xy 435.641185 -120.848935) (xy 435.591585 -120.823434) (xy 435.546227 -120.790983)
			(xy 435.506078 -120.752274) (xy 435.471992 -120.708131) (xy 435.444696 -120.659496) (xy 435.424773 -120.607405)
			(xy 435.412647 -120.552968) (xy 435.408576 -120.497346) (xy 410.131006 -120.497346) (xy 410.131006 -122.077226)
			(xy 421.87952 -122.077226) (xy 421.883591 -122.021604) (xy 421.895717 -121.967167) (xy 421.91564 -121.915076)
			(xy 421.942936 -121.866441) (xy 421.977022 -121.822298) (xy 422.017171 -121.783589) (xy 422.062529 -121.751138)
			(xy 422.112129 -121.725637) (xy 422.164913 -121.70763) (xy 422.219756 -121.6975) (xy 422.27549 -121.695463)
			(xy 422.330927 -121.701563) (xy 422.384884 -121.715669) (xy 422.436213 -121.737481) (xy 422.44561 -121.743216)
			(xy 428.864014 -121.743216) (xy 428.8645 -121.715965) (xy 428.872256 -121.662017) (xy 428.887611 -121.609722)
			(xy 428.910253 -121.560145) (xy 428.939719 -121.514295) (xy 428.97541 -121.473104) (xy 429.016601 -121.437413)
			(xy 429.062451 -121.407947) (xy 429.112028 -121.385305) (xy 429.164323 -121.36995) (xy 429.218271 -121.362194)
			(xy 429.272773 -121.362194) (xy 429.326721 -121.36995) (xy 429.379016 -121.385305) (xy 429.428593 -121.407947)
			(xy 429.474443 -121.437413) (xy 429.515634 -121.473104) (xy 429.551325 -121.514295) (xy 429.557897 -121.524522)
			(xy 435.516018 -121.524522) (xy 435.520089 -121.4689) (xy 435.532215 -121.414463) (xy 435.552138 -121.362372)
			(xy 435.579434 -121.313737) (xy 435.61352 -121.269594) (xy 435.653669 -121.230885) (xy 435.699027 -121.198434)
			(xy 435.748627 -121.172933) (xy 435.801411 -121.154926) (xy 435.856254 -121.144796) (xy 435.911988 -121.142759)
			(xy 435.967425 -121.148859) (xy 436.021382 -121.162965) (xy 436.072711 -121.184777) (xy 436.120317 -121.213831)
			(xy 436.163185 -121.249506) (xy 436.200402 -121.291043) (xy 436.231175 -121.337556) (xy 436.254847 -121.388053)
			(xy 436.270915 -121.44146) (xy 436.279035 -121.496636) (xy 436.279544 -121.524522) (xy 436.279035 -121.552408)
			(xy 436.270915 -121.607584) (xy 436.254847 -121.660991) (xy 436.231175 -121.711488) (xy 436.200402 -121.758001)
			(xy 436.163185 -121.799538) (xy 436.120317 -121.835213) (xy 436.072711 -121.864267) (xy 436.021382 -121.886079)
			(xy 435.967425 -121.900185) (xy 435.911988 -121.906285) (xy 435.856254 -121.904248) (xy 435.801411 -121.894118)
			(xy 435.748627 -121.876111) (xy 435.699027 -121.85061) (xy 435.653669 -121.818159) (xy 435.61352 -121.77945)
			(xy 435.579434 -121.735307) (xy 435.552138 -121.686672) (xy 435.532215 -121.634581) (xy 435.520089 -121.580144)
			(xy 435.516018 -121.524522) (xy 429.557897 -121.524522) (xy 429.580791 -121.560145) (xy 429.603433 -121.609722)
			(xy 429.618788 -121.662017) (xy 429.626544 -121.715965) (xy 429.62703 -121.743216) (xy 429.626439 -121.773043)
			(xy 429.617165 -121.831972) (xy 429.598829 -121.888738) (xy 429.57188 -121.941957) (xy 429.554894 -121.966482)
			(xy 429.546539 -121.97895) (xy 429.536807 -122.007326) (xy 429.535742 -122.037306) (xy 429.543437 -122.066301)
			(xy 429.559226 -122.091808) (xy 429.570134 -122.102118) (xy 429.590087 -122.120342) (xy 429.625216 -122.161399)
			(xy 429.654204 -122.207001) (xy 429.67647 -122.256236) (xy 429.691569 -122.308119) (xy 429.6992 -122.361612)
			(xy 429.699674 -122.38863) (xy 429.699188 -122.415881) (xy 429.691432 -122.469829) (xy 429.676077 -122.522124)
			(xy 429.653435 -122.571701) (xy 429.623969 -122.617551) (xy 429.588278 -122.658742) (xy 429.547087 -122.694433)
			(xy 429.501237 -122.723899) (xy 429.45166 -122.746541) (xy 429.399365 -122.761896) (xy 429.345417 -122.769652)
			(xy 429.290915 -122.769652) (xy 429.236967 -122.761896) (xy 429.184672 -122.746541) (xy 429.135095 -122.723899)
			(xy 429.089245 -122.694433) (xy 429.048054 -122.658742) (xy 429.012363 -122.617551) (xy 428.982897 -122.571701)
			(xy 428.960255 -122.522124) (xy 428.9449 -122.469829) (xy 428.937144 -122.415881) (xy 428.936658 -122.38863)
			(xy 428.937205 -122.358801) (xy 428.94649 -122.29987) (xy 428.964838 -122.243103) (xy 428.991801 -122.189886)
			(xy 429.008794 -122.165364) (xy 429.017104 -122.152868) (xy 429.026844 -122.124503) (xy 429.027919 -122.094532)
			(xy 429.020235 -122.065542) (xy 429.004456 -122.040038) (xy 428.993554 -122.029728) (xy 428.973573 -122.011534)
			(xy 428.938446 -121.97047) (xy 428.909463 -121.924862) (xy 428.887201 -121.875621) (xy 428.872108 -121.823733)
			(xy 428.864484 -121.770235) (xy 428.864014 -121.743216) (xy 422.44561 -121.743216) (xy 422.483819 -121.766535)
			(xy 422.526687 -121.80221) (xy 422.563904 -121.843747) (xy 422.594677 -121.89026) (xy 422.618349 -121.940757)
			(xy 422.634417 -121.994164) (xy 422.642537 -122.04934) (xy 422.643046 -122.077226) (xy 422.642537 -122.105112)
			(xy 422.634417 -122.160288) (xy 422.618349 -122.213695) (xy 422.594677 -122.264192) (xy 422.563904 -122.310705)
			(xy 422.526687 -122.352242) (xy 422.483819 -122.387917) (xy 422.436213 -122.416971) (xy 422.384884 -122.438783)
			(xy 422.330927 -122.452889) (xy 422.27549 -122.458989) (xy 422.219756 -122.456952) (xy 422.164913 -122.446822)
			(xy 422.112129 -122.428815) (xy 422.062529 -122.403314) (xy 422.017171 -122.370863) (xy 421.977022 -122.332154)
			(xy 421.942936 -122.288011) (xy 421.91564 -122.239376) (xy 421.895717 -122.187285) (xy 421.883591 -122.132848)
			(xy 421.87952 -122.077226) (xy 410.131006 -122.077226) (xy 410.131006 -122.86488) (xy 435.519574 -122.86488)
			(xy 435.523645 -122.809258) (xy 435.535771 -122.754821) (xy 435.555694 -122.70273) (xy 435.58299 -122.654095)
			(xy 435.617076 -122.609952) (xy 435.657225 -122.571243) (xy 435.702583 -122.538792) (xy 435.752183 -122.513291)
			(xy 435.804967 -122.495284) (xy 435.85981 -122.485154) (xy 435.915544 -122.483117) (xy 435.970981 -122.489217)
			(xy 436.024938 -122.503323) (xy 436.076267 -122.525135) (xy 436.123873 -122.554189) (xy 436.166741 -122.589864)
			(xy 436.203958 -122.631401) (xy 436.234731 -122.677914) (xy 436.258403 -122.728411) (xy 436.274471 -122.781818)
			(xy 436.282591 -122.836994) (xy 436.2831 -122.86488) (xy 436.282591 -122.892766) (xy 436.274471 -122.947942)
			(xy 436.258403 -123.001349) (xy 436.234731 -123.051846) (xy 436.203958 -123.098359) (xy 436.166741 -123.139896)
			(xy 436.123873 -123.175571) (xy 436.076267 -123.204625) (xy 436.024938 -123.226437) (xy 435.970981 -123.240543)
			(xy 435.915544 -123.246643) (xy 435.85981 -123.244606) (xy 435.804967 -123.234476) (xy 435.752183 -123.216469)
			(xy 435.702583 -123.190968) (xy 435.657225 -123.158517) (xy 435.617076 -123.119808) (xy 435.58299 -123.075665)
			(xy 435.555694 -123.02703) (xy 435.535771 -122.974939) (xy 435.523645 -122.920502) (xy 435.519574 -122.86488)
			(xy 410.131006 -122.86488) (xy 410.131006 -123.315984) (xy 428.176434 -123.315984) (xy 428.180505 -123.260362)
			(xy 428.192631 -123.205925) (xy 428.212554 -123.153834) (xy 428.23985 -123.105199) (xy 428.273936 -123.061056)
			(xy 428.314085 -123.022347) (xy 428.359443 -122.989896) (xy 428.409043 -122.964395) (xy 428.461827 -122.946388)
			(xy 428.51667 -122.936258) (xy 428.572404 -122.934221) (xy 428.627841 -122.940321) (xy 428.681798 -122.954427)
			(xy 428.733127 -122.976239) (xy 428.780733 -123.005293) (xy 428.823601 -123.040968) (xy 428.860818 -123.082505)
			(xy 428.891591 -123.129018) (xy 428.915263 -123.179515) (xy 428.931331 -123.232922) (xy 428.939451 -123.288098)
			(xy 428.93996 -123.315984) (xy 428.939451 -123.34387) (xy 428.931331 -123.399046) (xy 428.915263 -123.452453)
			(xy 428.891591 -123.50295) (xy 428.860818 -123.549463) (xy 428.823601 -123.591) (xy 428.780733 -123.626675)
			(xy 428.733127 -123.655729) (xy 428.681798 -123.677541) (xy 428.627841 -123.691647) (xy 428.572404 -123.697747)
			(xy 428.51667 -123.69571) (xy 428.461827 -123.68558) (xy 428.409043 -123.667573) (xy 428.359443 -123.642072)
			(xy 428.314085 -123.609621) (xy 428.273936 -123.570912) (xy 428.23985 -123.526769) (xy 428.212554 -123.478134)
			(xy 428.192631 -123.426043) (xy 428.180505 -123.371606) (xy 428.176434 -123.315984) (xy 410.131006 -123.315984)
			(xy 410.131006 -123.87199) (xy 435.521606 -123.87199) (xy 435.525677 -123.816368) (xy 435.537803 -123.761931)
			(xy 435.557726 -123.70984) (xy 435.585022 -123.661205) (xy 435.619108 -123.617062) (xy 435.659257 -123.578353)
			(xy 435.704615 -123.545902) (xy 435.754215 -123.520401) (xy 435.806999 -123.502394) (xy 435.861842 -123.492264)
			(xy 435.917576 -123.490227) (xy 435.973013 -123.496327) (xy 436.02697 -123.510433) (xy 436.078299 -123.532245)
			(xy 436.125905 -123.561299) (xy 436.168773 -123.596974) (xy 436.20599 -123.638511) (xy 436.236763 -123.685024)
			(xy 436.260435 -123.735521) (xy 436.276503 -123.788928) (xy 436.284623 -123.844104) (xy 436.285132 -123.87199)
			(xy 436.284623 -123.899876) (xy 436.276503 -123.955052) (xy 436.260435 -124.008459) (xy 436.236763 -124.058956)
			(xy 436.20599 -124.105469) (xy 436.168773 -124.147006) (xy 436.125905 -124.182681) (xy 436.078299 -124.211735)
			(xy 436.02697 -124.233547) (xy 435.973013 -124.247653) (xy 435.917576 -124.253753) (xy 435.861842 -124.251716)
			(xy 435.806999 -124.241586) (xy 435.754215 -124.223579) (xy 435.704615 -124.198078) (xy 435.659257 -124.165627)
			(xy 435.619108 -124.126918) (xy 435.585022 -124.082775) (xy 435.557726 -124.03414) (xy 435.537803 -123.982049)
			(xy 435.525677 -123.927612) (xy 435.521606 -123.87199) (xy 410.131006 -123.87199) (xy 410.131006 -124.77242)
			(xy 427.805848 -124.77242) (xy 427.809919 -124.716798) (xy 427.822045 -124.662361) (xy 427.841968 -124.61027)
			(xy 427.869264 -124.561635) (xy 427.90335 -124.517492) (xy 427.943499 -124.478783) (xy 427.988857 -124.446332)
			(xy 428.038457 -124.420831) (xy 428.091241 -124.402824) (xy 428.146084 -124.392694) (xy 428.201818 -124.390657)
			(xy 428.257255 -124.396757) (xy 428.311212 -124.410863) (xy 428.362541 -124.432675) (xy 428.410147 -124.461729)
			(xy 428.453015 -124.497404) (xy 428.490232 -124.538941) (xy 428.521005 -124.585454) (xy 428.544677 -124.635951)
			(xy 428.560745 -124.689358) (xy 428.568865 -124.744534) (xy 428.569374 -124.77242) (xy 428.568865 -124.800306)
			(xy 428.560745 -124.855482) (xy 428.551652 -124.885704) (xy 435.552594 -124.885704) (xy 435.556665 -124.830082)
			(xy 435.568791 -124.775645) (xy 435.588714 -124.723554) (xy 435.61601 -124.674919) (xy 435.650096 -124.630776)
			(xy 435.690245 -124.592067) (xy 435.735603 -124.559616) (xy 435.785203 -124.534115) (xy 435.837987 -124.516108)
			(xy 435.89283 -124.505978) (xy 435.948564 -124.503941) (xy 436.004001 -124.510041) (xy 436.057958 -124.524147)
			(xy 436.109287 -124.545959) (xy 436.156893 -124.575013) (xy 436.199761 -124.610688) (xy 436.236978 -124.652225)
			(xy 436.267751 -124.698738) (xy 436.291423 -124.749235) (xy 436.307491 -124.802642) (xy 436.315611 -124.857818)
			(xy 436.31612 -124.885704) (xy 436.315611 -124.91359) (xy 436.307491 -124.968766) (xy 436.291423 -125.022173)
			(xy 436.267751 -125.07267) (xy 436.236978 -125.119183) (xy 436.199761 -125.16072) (xy 436.156893 -125.196395)
			(xy 436.109287 -125.225449) (xy 436.057958 -125.247261) (xy 436.004001 -125.261367) (xy 435.948564 -125.267467)
			(xy 435.89283 -125.26543) (xy 435.837987 -125.2553) (xy 435.785203 -125.237293) (xy 435.735603 -125.211792)
			(xy 435.690245 -125.179341) (xy 435.650096 -125.140632) (xy 435.61601 -125.096489) (xy 435.588714 -125.047854)
			(xy 435.568791 -124.995763) (xy 435.556665 -124.941326) (xy 435.552594 -124.885704) (xy 428.551652 -124.885704)
			(xy 428.544677 -124.908889) (xy 428.521005 -124.959386) (xy 428.490232 -125.005899) (xy 428.453015 -125.047436)
			(xy 428.410147 -125.083111) (xy 428.362541 -125.112165) (xy 428.311212 -125.133977) (xy 428.257255 -125.148083)
			(xy 428.201818 -125.154183) (xy 428.146084 -125.152146) (xy 428.091241 -125.142016) (xy 428.038457 -125.124009)
			(xy 427.988857 -125.098508) (xy 427.943499 -125.066057) (xy 427.90335 -125.027348) (xy 427.869264 -124.983205)
			(xy 427.841968 -124.93457) (xy 427.822045 -124.882479) (xy 427.809919 -124.828042) (xy 427.805848 -124.77242)
			(xy 410.131006 -124.77242) (xy 410.131006 -125.394212) (xy 429.170336 -125.394212) (xy 429.174407 -125.33859)
			(xy 429.186533 -125.284153) (xy 429.206456 -125.232062) (xy 429.233752 -125.183427) (xy 429.267838 -125.139284)
			(xy 429.307987 -125.100575) (xy 429.353345 -125.068124) (xy 429.402945 -125.042623) (xy 429.455729 -125.024616)
			(xy 429.510572 -125.014486) (xy 429.566306 -125.012449) (xy 429.621743 -125.018549) (xy 429.6757 -125.032655)
			(xy 429.727029 -125.054467) (xy 429.774635 -125.083521) (xy 429.817503 -125.119196) (xy 429.85472 -125.160733)
			(xy 429.885493 -125.207246) (xy 429.909165 -125.257743) (xy 429.925233 -125.31115) (xy 429.933353 -125.366326)
			(xy 429.933862 -125.394212) (xy 429.933353 -125.422098) (xy 429.925233 -125.477274) (xy 429.909165 -125.530681)
			(xy 429.885493 -125.581178) (xy 429.85472 -125.627691) (xy 429.817503 -125.669228) (xy 429.774635 -125.704903)
			(xy 429.727029 -125.733957) (xy 429.6757 -125.755769) (xy 429.621743 -125.769875) (xy 429.566306 -125.775975)
			(xy 429.510572 -125.773938) (xy 429.455729 -125.763808) (xy 429.402945 -125.745801) (xy 429.353345 -125.7203)
			(xy 429.307987 -125.687849) (xy 429.267838 -125.64914) (xy 429.233752 -125.604997) (xy 429.206456 -125.556362)
			(xy 429.186533 -125.504271) (xy 429.174407 -125.449834) (xy 429.170336 -125.394212) (xy 410.131006 -125.394212)
			(xy 410.131006 -125.80366) (xy 426.7995 -125.80366) (xy 426.803571 -125.748038) (xy 426.815697 -125.693601)
			(xy 426.83562 -125.64151) (xy 426.862916 -125.592875) (xy 426.897002 -125.548732) (xy 426.937151 -125.510023)
			(xy 426.982509 -125.477572) (xy 427.032109 -125.452071) (xy 427.084893 -125.434064) (xy 427.139736 -125.423934)
			(xy 427.19547 -125.421897) (xy 427.250907 -125.427997) (xy 427.304864 -125.442103) (xy 427.356193 -125.463915)
			(xy 427.403799 -125.492969) (xy 427.446667 -125.528644) (xy 427.483884 -125.570181) (xy 427.514657 -125.616694)
			(xy 427.538329 -125.667191) (xy 427.554397 -125.720598) (xy 427.562517 -125.775774) (xy 427.563026 -125.80366)
			(xy 427.562517 -125.831546) (xy 427.554397 -125.886722) (xy 427.55073 -125.89891) (xy 435.50408 -125.89891)
			(xy 435.508151 -125.843288) (xy 435.520277 -125.788851) (xy 435.5402 -125.73676) (xy 435.567496 -125.688125)
			(xy 435.601582 -125.643982) (xy 435.641731 -125.605273) (xy 435.687089 -125.572822) (xy 435.736689 -125.547321)
			(xy 435.789473 -125.529314) (xy 435.844316 -125.519184) (xy 435.90005 -125.517147) (xy 435.955487 -125.523247)
			(xy 436.009444 -125.537353) (xy 436.060773 -125.559165) (xy 436.108379 -125.588219) (xy 436.151247 -125.623894)
			(xy 436.188464 -125.665431) (xy 436.219237 -125.711944) (xy 436.242909 -125.762441) (xy 436.258977 -125.815848)
			(xy 436.267097 -125.871024) (xy 436.267606 -125.89891) (xy 436.267097 -125.926796) (xy 436.258977 -125.981972)
			(xy 436.242909 -126.035379) (xy 436.219237 -126.085876) (xy 436.188464 -126.132389) (xy 436.151247 -126.173926)
			(xy 436.108379 -126.209601) (xy 436.060773 -126.238655) (xy 436.009444 -126.260467) (xy 435.955487 -126.274573)
			(xy 435.90005 -126.280673) (xy 435.844316 -126.278636) (xy 435.789473 -126.268506) (xy 435.736689 -126.250499)
			(xy 435.687089 -126.224998) (xy 435.641731 -126.192547) (xy 435.601582 -126.153838) (xy 435.567496 -126.109695)
			(xy 435.5402 -126.06106) (xy 435.520277 -126.008969) (xy 435.508151 -125.954532) (xy 435.50408 -125.89891)
			(xy 427.55073 -125.89891) (xy 427.538329 -125.940129) (xy 427.514657 -125.990626) (xy 427.483884 -126.037139)
			(xy 427.446667 -126.078676) (xy 427.403799 -126.114351) (xy 427.356193 -126.143405) (xy 427.304864 -126.165217)
			(xy 427.250907 -126.179323) (xy 427.19547 -126.185423) (xy 427.139736 -126.183386) (xy 427.084893 -126.173256)
			(xy 427.032109 -126.155249) (xy 426.982509 -126.129748) (xy 426.937151 -126.097297) (xy 426.897002 -126.058588)
			(xy 426.862916 -126.014445) (xy 426.83562 -125.96581) (xy 426.815697 -125.913719) (xy 426.803571 -125.859282)
			(xy 426.7995 -125.80366) (xy 410.131006 -125.80366) (xy 410.131006 -127.458247) (xy 429.165816 -127.458247)
			(xy 429.165816 -127.403753) (xy 429.173571 -127.349814) (xy 429.188923 -127.297527) (xy 429.211559 -127.247957)
			(xy 429.241019 -127.202113) (xy 429.276704 -127.160928) (xy 429.317886 -127.12524) (xy 429.363727 -127.095775)
			(xy 429.413295 -127.073135) (xy 429.46558 -127.057778) (xy 429.519519 -127.050019) (xy 429.546766 -127.04953)
			(xy 429.576816 -127.050124) (xy 429.636173 -127.059554) (xy 429.693318 -127.078172) (xy 429.746838 -127.105515)
			(xy 429.795411 -127.14091) (xy 429.817022 -127.161798) (xy 429.827948 -127.171991) (xy 429.85427 -127.186102)
			(xy 429.883548 -127.192005) (xy 429.913282 -127.189196) (xy 429.940936 -127.177914) (xy 429.96415 -127.159121)
			(xy 429.972978 -127.147066) (xy 429.986745 -127.127393) (xy 430.018464 -127.091344) (xy 430.036224 -127.075184)
			(xy 430.045506 -127.066504) (xy 430.059824 -127.045517) (xy 430.068508 -127.021642) (xy 430.07102 -126.996361)
			(xy 430.069498 -126.983744) (xy 430.042506 -126.973126) (xy 429.991838 -126.944899) (xy 429.94602 -126.909337)
			(xy 429.906104 -126.867256) (xy 429.87301 -126.819624) (xy 429.847497 -126.767536) (xy 429.830153 -126.71219)
			(xy 429.821375 -126.654858) (xy 429.820832 -126.625858) (xy 429.821285 -126.598588) (xy 429.829053 -126.544603)
			(xy 429.844423 -126.492274) (xy 429.867084 -126.442664) (xy 429.896573 -126.396783) (xy 429.932292 -126.355566)
			(xy 429.973512 -126.319852) (xy 430.019395 -126.290366) (xy 430.069007 -126.26771) (xy 430.121339 -126.252345)
			(xy 430.175324 -126.244583) (xy 430.202594 -126.244096) (xy 430.220543 -126.244286) (xy 430.256289 -126.247591)
			(xy 430.273968 -126.2507) (xy 430.28362 -126.2507) (xy 430.310872 -126.251159) (xy 430.364821 -126.258919)
			(xy 430.417117 -126.274277) (xy 430.466695 -126.296921) (xy 430.512545 -126.32639) (xy 430.553736 -126.362084)
			(xy 430.589427 -126.403277) (xy 430.618893 -126.44913) (xy 430.641533 -126.498709) (xy 430.656887 -126.551006)
			(xy 430.664643 -126.604956) (xy 430.665128 -126.632208) (xy 430.664654 -126.659166) (xy 430.657062 -126.712545)
			(xy 430.642031 -126.764323) (xy 430.61986 -126.813469) (xy 430.59099 -126.859005) (xy 430.555998 -126.900022)
			(xy 430.536096 -126.918212) (xy 430.525502 -126.928164) (xy 430.509944 -126.952701) (xy 430.501935 -126.980629)
			(xy 430.502124 -127.009682) (xy 430.510495 -127.037504) (xy 430.52637 -127.061838) (xy 430.537112 -127.071628)
			(xy 430.544805 -127.078327) (xy 430.559545 -127.092432) (xy 430.566576 -127.099822) (xy 430.577044 -127.110092)
			(xy 430.602417 -127.124763) (xy 430.63091 -127.131636) (xy 430.660182 -127.130146) (xy 430.687829 -127.120415)
			(xy 430.711582 -127.103243) (xy 430.729488 -127.080039) (xy 430.735232 -127.066548) (xy 430.746045 -127.039951)
			(xy 430.774487 -126.990078) (xy 430.810079 -126.945029) (xy 430.852019 -126.90582) (xy 430.899358 -126.873337)
			(xy 430.95103 -126.848312) (xy 431.005868 -126.83131) (xy 431.062634 -126.822715) (xy 431.09134 -126.8222)
			(xy 431.091848 -126.8222) (xy 431.10222 -126.822278) (xy 431.122932 -126.823423) (xy 431.13325 -126.824486)
			(xy 431.146494 -126.82561) (xy 431.172767 -126.821628) (xy 431.197115 -126.810984) (xy 431.21788 -126.794402)
			(xy 431.233649 -126.773013) (xy 431.243346 -126.748272) (xy 431.246312 -126.721864) (xy 431.244756 -126.708662)
			(xy 431.242843 -126.694707) (xy 431.240806 -126.666612) (xy 431.240692 -126.652528) (xy 431.241181 -126.625276)
			(xy 431.248935 -126.571326) (xy 431.264287 -126.519028) (xy 431.286926 -126.469448) (xy 431.316391 -126.423595)
			(xy 431.352082 -126.382402) (xy 431.393273 -126.346708) (xy 431.439124 -126.31724) (xy 431.488702 -126.294597)
			(xy 431.540998 -126.27924) (xy 431.594948 -126.271483) (xy 431.6222 -126.27102) (xy 431.646145 -126.271364)
			(xy 431.693659 -126.277356) (xy 431.716942 -126.282958) (xy 431.730331 -126.285959) (xy 431.757756 -126.285459)
			(xy 431.784058 -126.277672) (xy 431.807335 -126.263162) (xy 431.825907 -126.242975) (xy 431.838431 -126.218572)
			(xy 431.841656 -126.205234) (xy 431.848089 -126.176987) (xy 431.868334 -126.122708) (xy 431.896552 -126.072114)
			(xy 431.932094 -126.026367) (xy 431.974143 -125.986519) (xy 432.021733 -125.953486) (xy 432.07377 -125.928026)
			(xy 432.129057 -125.910725) (xy 432.186324 -125.901981) (xy 432.21529 -125.90145) (xy 432.24254 -125.901997)
			(xy 432.296486 -125.909752) (xy 432.34878 -125.925105) (xy 432.398356 -125.947744) (xy 432.444205 -125.977209)
			(xy 432.485394 -126.012899) (xy 432.521085 -126.054087) (xy 432.550551 -126.099936) (xy 432.573192 -126.149511)
			(xy 432.588546 -126.201804) (xy 432.596303 -126.25575) (xy 432.596303 -126.31025) (xy 432.588546 -126.364196)
			(xy 432.573192 -126.416489) (xy 432.550551 -126.466064) (xy 432.521085 -126.511913) (xy 432.485394 -126.553101)
			(xy 432.444205 -126.588791) (xy 432.398356 -126.618256) (xy 432.34878 -126.640895) (xy 432.296486 -126.656248)
			(xy 432.24254 -126.664003) (xy 432.21529 -126.664466) (xy 432.191346 -126.664106) (xy 432.143832 -126.658124)
			(xy 432.120548 -126.652528) (xy 432.107159 -126.649527) (xy 432.079735 -126.65003) (xy 432.053435 -126.657818)
			(xy 432.030158 -126.672328) (xy 432.011586 -126.692513) (xy 431.99906 -126.716915) (xy 431.995834 -126.730252)
			(xy 431.994462 -126.736348) (xy 433.246782 -126.736348) (xy 433.250853 -126.680726) (xy 433.262979 -126.626289)
			(xy 433.282902 -126.574198) (xy 433.310198 -126.525563) (xy 433.344284 -126.48142) (xy 433.384433 -126.442711)
			(xy 433.429791 -126.41026) (xy 433.479391 -126.384759) (xy 433.532175 -126.366752) (xy 433.587018 -126.356622)
			(xy 433.642752 -126.354585) (xy 433.698189 -126.360685) (xy 433.752146 -126.374791) (xy 433.803475 -126.396603)
			(xy 433.851081 -126.425657) (xy 433.893949 -126.461332) (xy 433.931166 -126.502869) (xy 433.961939 -126.549382)
			(xy 433.985611 -126.599879) (xy 434.001679 -126.653286) (xy 434.009799 -126.708462) (xy 434.010308 -126.736348)
			(xy 434.009799 -126.764234) (xy 434.001679 -126.81941) (xy 433.985611 -126.872817) (xy 433.961939 -126.923314)
			(xy 433.931166 -126.969827) (xy 433.893949 -127.011364) (xy 433.851081 -127.047039) (xy 433.803475 -127.076093)
			(xy 433.752146 -127.097905) (xy 433.698189 -127.112011) (xy 433.642752 -127.118111) (xy 433.587018 -127.116074)
			(xy 433.532175 -127.105944) (xy 433.479391 -127.087937) (xy 433.429791 -127.062436) (xy 433.384433 -127.029985)
			(xy 433.344284 -126.991276) (xy 433.310198 -126.947133) (xy 433.282902 -126.898498) (xy 433.262979 -126.846407)
			(xy 433.250853 -126.79197) (xy 433.246782 -126.736348) (xy 431.994462 -126.736348) (xy 431.989471 -126.758516)
			(xy 431.969213 -126.812795) (xy 431.940984 -126.863387) (xy 431.905432 -126.909132) (xy 431.863374 -126.948978)
			(xy 431.815776 -126.982009) (xy 431.763733 -127.007466) (xy 431.70844 -127.024764) (xy 431.651168 -127.033506)
			(xy 431.6222 -127.034036) (xy 431.621692 -127.034036) (xy 431.61132 -127.033955) (xy 431.590608 -127.032812)
			(xy 431.58029 -127.03175) (xy 431.567042 -127.030739) (xy 431.540783 -127.034709) (xy 431.516446 -127.045337)
			(xy 431.495687 -127.0619) (xy 431.479918 -127.083269) (xy 431.470215 -127.107989) (xy 431.467237 -127.134379)
			(xy 431.468784 -127.147574) (xy 431.470701 -127.161528) (xy 431.472736 -127.189623) (xy 431.472848 -127.203708)
			(xy 431.47233 -127.230958) (xy 431.464573 -127.284902) (xy 431.44993 -127.334772) (xy 431.877976 -127.334772)
			(xy 431.882047 -127.27915) (xy 431.894173 -127.224713) (xy 431.914096 -127.172622) (xy 431.941392 -127.123987)
			(xy 431.975478 -127.079844) (xy 432.015627 -127.041135) (xy 432.060985 -127.008684) (xy 432.110585 -126.983183)
			(xy 432.163369 -126.965176) (xy 432.218212 -126.955046) (xy 432.273946 -126.953009) (xy 432.329383 -126.959109)
			(xy 432.38334 -126.973215) (xy 432.434669 -126.995027) (xy 432.482275 -127.024081) (xy 432.525143 -127.059756)
			(xy 432.56236 -127.101293) (xy 432.593133 -127.147806) (xy 432.616805 -127.198303) (xy 432.632873 -127.25171)
			(xy 432.640993 -127.306886) (xy 432.641502 -127.334772) (xy 432.640993 -127.362658) (xy 432.632873 -127.417834)
			(xy 432.616805 -127.471241) (xy 432.593133 -127.521738) (xy 432.56236 -127.568251) (xy 432.525143 -127.609788)
			(xy 432.482275 -127.645463) (xy 432.434669 -127.674517) (xy 432.38334 -127.696329) (xy 432.329383 -127.710435)
			(xy 432.273946 -127.716535) (xy 432.218212 -127.714498) (xy 432.163369 -127.704368) (xy 432.110585 -127.686361)
			(xy 432.060985 -127.66086) (xy 432.015627 -127.628409) (xy 431.975478 -127.5897) (xy 431.941392 -127.545557)
			(xy 431.914096 -127.496922) (xy 431.894173 -127.444831) (xy 431.882047 -127.390394) (xy 431.877976 -127.334772)
			(xy 431.44993 -127.334772) (xy 431.449219 -127.337194) (xy 431.42658 -127.386768) (xy 431.397117 -127.432617)
			(xy 431.361429 -127.473806) (xy 431.320242 -127.509497) (xy 431.274397 -127.538965) (xy 431.224824 -127.561608)
			(xy 431.172533 -127.576966) (xy 431.11859 -127.584727) (xy 431.09134 -127.585216) (xy 431.065389 -127.584758)
			(xy 431.013967 -127.577715) (xy 430.963974 -127.563767) (xy 430.916333 -127.543172) (xy 430.871923 -127.51631)
			(xy 430.831564 -127.483676) (xy 430.813464 -127.465074) (xy 430.803058 -127.454737) (xy 430.777668 -127.440069)
			(xy 430.74916 -127.433203) (xy 430.719876 -127.434703) (xy 430.69222 -127.444446) (xy 430.668461 -127.461632)
			(xy 430.650552 -127.48485) (xy 430.644808 -127.498348) (xy 430.634042 -127.524966) (xy 430.605595 -127.574841)
			(xy 430.569997 -127.619891) (xy 430.528051 -127.659099) (xy 430.480704 -127.69158) (xy 430.429025 -127.716602)
			(xy 430.37418 -127.733598) (xy 430.317409 -127.742185) (xy 430.2887 -127.742696) (xy 430.258649 -127.742116)
			(xy 430.199292 -127.732681) (xy 430.142148 -127.71406) (xy 430.088628 -127.686714) (xy 430.040055 -127.651317)
			(xy 430.018444 -127.630428) (xy 430.007554 -127.620193) (xy 429.981221 -127.60608) (xy 429.951932 -127.60018)
			(xy 429.922189 -127.602997) (xy 429.894529 -127.614291) (xy 429.871314 -127.633097) (xy 429.862488 -127.64516)
			(xy 429.847183 -127.666891) (xy 429.811542 -127.706322) (xy 429.77077 -127.740421) (xy 429.725659 -127.768527)
			(xy 429.677081 -127.790097) (xy 429.625978 -127.804711) (xy 429.573342 -127.812088) (xy 429.546766 -127.812546)
			(xy 429.519519 -127.811981) (xy 429.46558 -127.804222) (xy 429.413295 -127.788865) (xy 429.363727 -127.766225)
			(xy 429.317886 -127.73676) (xy 429.276704 -127.701072) (xy 429.241019 -127.659887) (xy 429.211559 -127.614043)
			(xy 429.188923 -127.564473) (xy 429.173571 -127.512186) (xy 429.165816 -127.458247) (xy 410.131006 -127.458247)
			(xy 410.131006 -147.048728) (xy 415.256472 -147.048728) (xy 415.256472 -133.27634) (xy 415.257118 -133.251344)
			(xy 415.266917 -133.202321) (xy 415.286087 -133.15615) (xy 415.313893 -133.114604) (xy 415.331148 -133.096508)
			(xy 418.18814 -130.239516) (xy 418.206227 -130.222251) (xy 418.247775 -130.194442) (xy 418.293949 -130.175271)
			(xy 418.342975 -130.165475) (xy 418.367972 -130.16484) (xy 425.446698 -130.16484) (xy 425.456858 -130.160268)
			(xy 425.482284 -130.148854) (xy 425.53565 -130.132785) (xy 425.590789 -130.124676) (xy 425.618656 -130.1242)
			(xy 425.645911 -130.124644) (xy 425.699868 -130.132396) (xy 425.752173 -130.147749) (xy 425.801759 -130.170389)
			(xy 425.847619 -130.199857) (xy 425.888818 -130.235551) (xy 425.924517 -130.276746) (xy 425.953989 -130.322602)
			(xy 425.976636 -130.372186) (xy 425.991994 -130.424489) (xy 425.999753 -130.478445) (xy 425.999753 -130.532955)
			(xy 425.991994 -130.586911) (xy 425.976636 -130.639214) (xy 425.953989 -130.688798) (xy 425.924517 -130.734654)
			(xy 425.888818 -130.775849) (xy 425.847619 -130.811543) (xy 425.801759 -130.841011) (xy 425.752173 -130.863651)
			(xy 425.699868 -130.879004) (xy 425.645911 -130.886756) (xy 425.618656 -130.887216) (xy 425.592078 -130.88676)
			(xy 425.53944 -130.879363) (xy 425.488337 -130.864733) (xy 425.439759 -130.843152) (xy 425.394646 -130.815038)
			(xy 425.353872 -130.780936) (xy 425.318225 -130.741505) (xy 425.288394 -130.697509) (xy 425.276264 -130.673856)
			(xy 418.473382 -130.673856) (xy 415.765488 -133.38175) (xy 415.765488 -146.548348) (xy 416.055048 -146.548348)
			(xy 416.055048 -134.002018) (xy 416.055689 -133.977036) (xy 416.065423 -133.928029) (xy 416.084522 -133.88186)
			(xy 416.112252 -133.840297) (xy 416.12947 -133.822186) (xy 418.56914 -131.382516) (xy 418.587227 -131.365251)
			(xy 418.628775 -131.337442) (xy 418.674949 -131.318271) (xy 418.723975 -131.308475) (xy 418.748972 -131.30784)
			(xy 419.809168 -131.30784) (xy 419.834163 -131.308491) (xy 419.883186 -131.31829) (xy 419.929356 -131.337459)
			(xy 419.970903 -131.365263) (xy 419.989 -131.382516) (xy 420.155674 -131.54914) (xy 420.687752 -131.54914)
			(xy 420.691823 -131.493518) (xy 420.703949 -131.439081) (xy 420.723872 -131.38699) (xy 420.751168 -131.338355)
			(xy 420.785254 -131.294212) (xy 420.825403 -131.255503) (xy 420.870761 -131.223052) (xy 420.920361 -131.197551)
			(xy 420.973145 -131.179544) (xy 421.027988 -131.169414) (xy 421.083722 -131.167377) (xy 421.139159 -131.173477)
			(xy 421.193116 -131.187583) (xy 421.244445 -131.209395) (xy 421.292051 -131.238449) (xy 421.334919 -131.274124)
			(xy 421.372136 -131.315661) (xy 421.402909 -131.362174) (xy 421.426581 -131.412671) (xy 421.442649 -131.466078)
			(xy 421.450769 -131.521254) (xy 421.451278 -131.54914) (xy 421.450769 -131.577026) (xy 421.442649 -131.632202)
			(xy 421.426581 -131.685609) (xy 421.402909 -131.736106) (xy 421.372136 -131.782619) (xy 421.334919 -131.824156)
			(xy 421.292051 -131.859831) (xy 421.244445 -131.888885) (xy 421.193116 -131.910697) (xy 421.139159 -131.924803)
			(xy 421.083722 -131.930903) (xy 421.027988 -131.928866) (xy 420.973145 -131.918736) (xy 420.920361 -131.900729)
			(xy 420.870761 -131.875228) (xy 420.825403 -131.842777) (xy 420.785254 -131.804068) (xy 420.751168 -131.759925)
			(xy 420.723872 -131.71129) (xy 420.703949 -131.659199) (xy 420.691823 -131.604762) (xy 420.687752 -131.54914)
			(xy 420.155674 -131.54914) (xy 420.84371 -132.236972) (xy 421.38727 -132.236972) (xy 422.24198 -131.382516)
			(xy 422.260093 -131.365279) (xy 422.301631 -131.337465) (xy 422.347797 -131.318286) (xy 422.396817 -131.30848)
			(xy 422.421812 -131.30784) (xy 424.62831 -131.30784) (xy 424.716448 -131.219956) (xy 424.734538 -131.202694)
			(xy 424.776084 -131.174882) (xy 424.822257 -131.15571) (xy 424.871283 -131.145914) (xy 424.89628 -131.14528)
			(xy 426.01515 -131.14528) (xy 426.414692 -130.745738) (xy 426.414692 -130.317748) (xy 426.415338 -130.292752)
			(xy 426.425136 -130.243729) (xy 426.444306 -130.197558) (xy 426.472113 -130.156012) (xy 426.489368 -130.137916)
			(xy 427.479968 -129.147316) (xy 427.498044 -129.130037) (xy 427.539595 -129.102231) (xy 427.585772 -129.083063)
			(xy 427.634802 -129.073272) (xy 427.6598 -129.07264) (xy 431.9524 -129.07264) (xy 431.977396 -129.073271)
			(xy 432.026419 -129.083076) (xy 432.07259 -129.102251) (xy 432.114136 -129.13006) (xy 432.132232 -129.147316)
			(xy 432.66741 -129.68224) (xy 432.86299 -129.68224) (xy 433.435506 -129.109724) (xy 433.446104 -129.098291)
			(xy 433.460449 -129.070632) (xy 433.465805 -129.039938) (xy 433.461675 -129.009054) (xy 433.448443 -128.980846)
			(xy 433.4383 -128.969008) (xy 433.419297 -128.947729) (xy 433.387209 -128.900558) (xy 433.362498 -128.849138)
			(xy 433.345713 -128.794614) (xy 433.337228 -128.738199) (xy 433.3367 -128.709674) (xy 433.33715 -128.683295)
			(xy 433.344406 -128.631037) (xy 433.35879 -128.580278) (xy 433.380028 -128.531982) (xy 433.407715 -128.487073)
			(xy 433.441324 -128.446404) (xy 433.480213 -128.410752) (xy 433.523642 -128.380795) (xy 433.547012 -128.368552)
			(xy 433.559389 -128.361886) (xy 433.580112 -128.3429) (xy 433.594866 -128.31898) (xy 433.602533 -128.291941)
			(xy 433.60253 -128.263836) (xy 433.594857 -128.236799) (xy 433.580097 -128.212882) (xy 433.55937 -128.193901)
			(xy 433.547012 -128.187196) (xy 433.523634 -128.174968) (xy 433.480208 -128.145005) (xy 433.441322 -128.109349)
			(xy 433.407716 -128.068677) (xy 433.38003 -128.023766) (xy 433.358791 -127.975471) (xy 433.344404 -127.924711)
			(xy 433.337143 -127.872454) (xy 433.3367 -127.846074) (xy 433.337186 -127.818823) (xy 433.344942 -127.764875)
			(xy 433.360297 -127.71258) (xy 433.382939 -127.663003) (xy 433.412405 -127.617153) (xy 433.448096 -127.575962)
			(xy 433.489287 -127.540271) (xy 433.535137 -127.510805) (xy 433.584714 -127.488163) (xy 433.637009 -127.472808)
			(xy 433.690957 -127.465052) (xy 433.745459 -127.465052) (xy 433.799407 -127.472808) (xy 433.851702 -127.488163)
			(xy 433.901279 -127.510805) (xy 433.947129 -127.540271) (xy 433.98832 -127.575962) (xy 434.024011 -127.617153)
			(xy 434.053477 -127.663003) (xy 434.076119 -127.71258) (xy 434.091474 -127.764875) (xy 434.09923 -127.818823)
			(xy 434.099716 -127.846074) (xy 434.099297 -127.872454) (xy 434.092035 -127.924712) (xy 434.077645 -127.975473)
			(xy 434.056402 -128.023768) (xy 434.028711 -128.068677) (xy 433.995099 -128.109345) (xy 433.956207 -128.144997)
			(xy 433.912775 -128.174953) (xy 433.889404 -128.187196) (xy 433.877071 -128.193938) (xy 433.856351 -128.21291)
			(xy 433.841595 -128.236816) (xy 433.833924 -128.263842) (xy 433.833921 -128.291935) (xy 433.841586 -128.318963)
			(xy 433.856336 -128.342872) (xy 433.877052 -128.361848) (xy 433.889404 -128.368552) (xy 433.912764 -128.380812)
			(xy 433.956188 -128.410771) (xy 433.995074 -128.446424) (xy 434.028681 -128.487091) (xy 434.056369 -128.531997)
			(xy 434.077611 -128.580288) (xy 434.092002 -128.631043) (xy 434.099269 -128.683296) (xy 434.099716 -128.709674)
			(xy 434.099278 -128.734708) (xy 434.09271 -128.784344) (xy 434.079722 -128.832698) (xy 434.070506 -128.855978)
			(xy 434.065516 -128.869357) (xy 434.062275 -128.897711) (xy 434.067019 -128.925853) (xy 434.079376 -128.951578)
			(xy 434.098379 -128.97287) (xy 434.122539 -128.988062) (xy 434.149962 -128.995963) (xy 434.164232 -128.99644)
			(xy 434.86959 -128.99644) (xy 436.881016 -126.985268) (xy 436.881016 -120.673368) (xy 436.132478 -119.92483)
			(xy 436.115261 -119.906716) (xy 436.087517 -119.865159) (xy 436.068408 -119.81899) (xy 436.058667 -119.769982)
			(xy 436.058056 -119.744998) (xy 436.058056 -118.53418) (xy 435.378352 -117.854476) (xy 433.900072 -117.854476)
			(xy 432.721766 -119.032782) (xy 432.721766 -119.054118) (xy 432.721404 -119.081397) (xy 432.713701 -119.135408)
			(xy 432.698383 -119.18777) (xy 432.675764 -119.237417) (xy 432.646303 -119.283336) (xy 432.610602 -119.32459)
			(xy 432.569389 -119.360339) (xy 432.523504 -119.389853) (xy 432.473883 -119.41253) (xy 432.421538 -119.427907)
			(xy 432.367537 -119.435672) (xy 432.340258 -119.436134) (xy 432.312997 -119.435615) (xy 432.259032 -119.427847)
			(xy 432.206723 -119.412476) (xy 432.157134 -119.389814) (xy 432.111277 -119.360323) (xy 432.070086 -119.324605)
			(xy 432.034399 -119.283385) (xy 432.004944 -119.237505) (xy 431.98232 -119.1879) (xy 431.96699 -119.135578)
			(xy 431.959264 -119.081607) (xy 431.9593 -119.027086) (xy 431.967098 -118.973125) (xy 431.982498 -118.920824)
			(xy 432.005188 -118.871248) (xy 432.034704 -118.825408) (xy 432.070446 -118.784236) (xy 432.111685 -118.748572)
			(xy 432.157581 -118.719142) (xy 432.207199 -118.696546) (xy 432.259529 -118.681245) (xy 432.313505 -118.673549)
			(xy 432.340766 -118.673118) (xy 432.362102 -118.673118) (xy 433.61483 -117.42039) (xy 433.632963 -117.403194)
			(xy 433.674514 -117.375446) (xy 433.720676 -117.356331) (xy 433.76968 -117.346583) (xy 433.794662 -117.345968)
			(xy 435.483762 -117.345968) (xy 435.508747 -117.346555) (xy 435.557756 -117.356305) (xy 435.603926 -117.37542)
			(xy 435.645485 -117.403165) (xy 435.663594 -117.42039) (xy 436.492142 -118.248938) (xy 436.509348 -118.267063)
			(xy 436.537092 -118.308617) (xy 436.556204 -118.354782) (xy 436.56595 -118.403788) (xy 436.566564 -118.42877)
			(xy 436.566564 -119.192802) (xy 436.989726 -119.192802) (xy 436.993797 -119.13718) (xy 437.005923 -119.082743)
			(xy 437.025846 -119.030652) (xy 437.053142 -118.982017) (xy 437.087228 -118.937874) (xy 437.127377 -118.899165)
			(xy 437.172735 -118.866714) (xy 437.222335 -118.841213) (xy 437.275119 -118.823206) (xy 437.329962 -118.813076)
			(xy 437.385696 -118.811039) (xy 437.441133 -118.817139) (xy 437.49509 -118.831245) (xy 437.546419 -118.853057)
			(xy 437.594025 -118.882111) (xy 437.636893 -118.917786) (xy 437.67411 -118.959323) (xy 437.704883 -119.005836)
			(xy 437.728555 -119.056333) (xy 437.744623 -119.10974) (xy 437.752743 -119.164916) (xy 437.753252 -119.192802)
			(xy 437.752743 -119.220688) (xy 437.744623 -119.275864) (xy 437.728555 -119.329271) (xy 437.704883 -119.379768)
			(xy 437.67411 -119.426281) (xy 437.636893 -119.467818) (xy 437.594025 -119.503493) (xy 437.546419 -119.532547)
			(xy 437.49509 -119.554359) (xy 437.441133 -119.568465) (xy 437.385696 -119.574565) (xy 437.329962 -119.572528)
			(xy 437.275119 -119.562398) (xy 437.222335 -119.544391) (xy 437.172735 -119.51889) (xy 437.127377 -119.486439)
			(xy 437.087228 -119.44773) (xy 437.053142 -119.403587) (xy 437.025846 -119.354952) (xy 437.005923 -119.302861)
			(xy 436.993797 -119.248424) (xy 436.989726 -119.192802) (xy 436.566564 -119.192802) (xy 436.566564 -119.639588)
			(xy 437.315102 -120.388126) (xy 437.332342 -120.40622) (xy 437.360083 -120.447784) (xy 437.379186 -120.493959)
			(xy 437.388918 -120.542972) (xy 437.389524 -120.567958) (xy 437.389524 -121.427748) (xy 439.280298 -121.427748)
			(xy 439.284369 -121.372126) (xy 439.296495 -121.317689) (xy 439.316418 -121.265598) (xy 439.343714 -121.216963)
			(xy 439.3778 -121.17282) (xy 439.417949 -121.134111) (xy 439.463307 -121.10166) (xy 439.512907 -121.076159)
			(xy 439.565691 -121.058152) (xy 439.620534 -121.048022) (xy 439.676268 -121.045985) (xy 439.731705 -121.052085)
			(xy 439.785662 -121.066191) (xy 439.836991 -121.088003) (xy 439.884597 -121.117057) (xy 439.927465 -121.152732)
			(xy 439.964682 -121.194269) (xy 439.995455 -121.240782) (xy 440.019127 -121.291279) (xy 440.035195 -121.344686)
			(xy 440.043315 -121.399862) (xy 440.043824 -121.427748) (xy 440.043315 -121.455634) (xy 440.035195 -121.51081)
			(xy 440.019127 -121.564217) (xy 439.995455 -121.614714) (xy 439.964682 -121.661227) (xy 439.927465 -121.702764)
			(xy 439.884597 -121.738439) (xy 439.836991 -121.767493) (xy 439.785662 -121.789305) (xy 439.731705 -121.803411)
			(xy 439.676268 -121.809511) (xy 439.620534 -121.807474) (xy 439.565691 -121.797344) (xy 439.512907 -121.779337)
			(xy 439.463307 -121.753836) (xy 439.417949 -121.721385) (xy 439.3778 -121.682676) (xy 439.343714 -121.638533)
			(xy 439.316418 -121.589898) (xy 439.296495 -121.537807) (xy 439.284369 -121.48337) (xy 439.280298 -121.427748)
			(xy 437.389524 -121.427748) (xy 437.389524 -122.158506) (xy 441.404246 -122.158506) (xy 441.408317 -122.102884)
			(xy 441.420443 -122.048447) (xy 441.440366 -121.996356) (xy 441.467662 -121.947721) (xy 441.501748 -121.903578)
			(xy 441.541897 -121.864869) (xy 441.587255 -121.832418) (xy 441.636855 -121.806917) (xy 441.689639 -121.78891)
			(xy 441.744482 -121.77878) (xy 441.800216 -121.776743) (xy 441.855653 -121.782843) (xy 441.90961 -121.796949)
			(xy 441.960939 -121.818761) (xy 442.008545 -121.847815) (xy 442.051413 -121.88349) (xy 442.08863 -121.925027)
			(xy 442.119403 -121.97154) (xy 442.143075 -122.022037) (xy 442.159143 -122.075444) (xy 442.167263 -122.13062)
			(xy 442.167772 -122.158506) (xy 442.167263 -122.186392) (xy 442.159143 -122.241568) (xy 442.143075 -122.294975)
			(xy 442.119403 -122.345472) (xy 442.08863 -122.391985) (xy 442.051413 -122.433522) (xy 442.008545 -122.469197)
			(xy 441.960939 -122.498251) (xy 441.90961 -122.520063) (xy 441.855653 -122.534169) (xy 441.800216 -122.540269)
			(xy 441.744482 -122.538232) (xy 441.689639 -122.528102) (xy 441.636855 -122.510095) (xy 441.587255 -122.484594)
			(xy 441.541897 -122.452143) (xy 441.501748 -122.413434) (xy 441.467662 -122.369291) (xy 441.440366 -122.320656)
			(xy 441.420443 -122.268565) (xy 441.408317 -122.214128) (xy 441.404246 -122.158506) (xy 437.389524 -122.158506)
			(xy 437.389524 -122.648726) (xy 437.90057 -122.648726) (xy 437.904641 -122.593104) (xy 437.916767 -122.538667)
			(xy 437.93669 -122.486576) (xy 437.963986 -122.437941) (xy 437.998072 -122.393798) (xy 438.038221 -122.355089)
			(xy 438.083579 -122.322638) (xy 438.133179 -122.297137) (xy 438.185963 -122.27913) (xy 438.240806 -122.269)
			(xy 438.29654 -122.266963) (xy 438.351977 -122.273063) (xy 438.405934 -122.287169) (xy 438.457263 -122.308981)
			(xy 438.504869 -122.338035) (xy 438.547737 -122.37371) (xy 438.584954 -122.415247) (xy 438.615727 -122.46176)
			(xy 438.639399 -122.512257) (xy 438.655467 -122.565664) (xy 438.663587 -122.62084) (xy 438.664096 -122.648726)
			(xy 438.663587 -122.676612) (xy 438.655467 -122.731788) (xy 438.639399 -122.785195) (xy 438.615727 -122.835692)
			(xy 438.584954 -122.882205) (xy 438.547737 -122.923742) (xy 438.504869 -122.959417) (xy 438.457263 -122.988471)
			(xy 438.405934 -123.010283) (xy 438.351977 -123.024389) (xy 438.29654 -123.030489) (xy 438.240806 -123.028452)
			(xy 438.185963 -123.018322) (xy 438.133179 -123.000315) (xy 438.083579 -122.974814) (xy 438.038221 -122.942363)
			(xy 437.998072 -122.903654) (xy 437.963986 -122.859511) (xy 437.93669 -122.810876) (xy 437.916767 -122.758785)
			(xy 437.904641 -122.704348) (xy 437.90057 -122.648726) (xy 437.389524 -122.648726) (xy 437.389524 -123.664726)
			(xy 439.889898 -123.664726) (xy 439.893969 -123.609104) (xy 439.906095 -123.554667) (xy 439.926018 -123.502576)
			(xy 439.953314 -123.453941) (xy 439.9874 -123.409798) (xy 440.027549 -123.371089) (xy 440.072907 -123.338638)
			(xy 440.122507 -123.313137) (xy 440.175291 -123.29513) (xy 440.230134 -123.285) (xy 440.285868 -123.282963)
			(xy 440.341305 -123.289063) (xy 440.395262 -123.303169) (xy 440.446591 -123.324981) (xy 440.494197 -123.354035)
			(xy 440.537065 -123.38971) (xy 440.574282 -123.431247) (xy 440.605055 -123.47776) (xy 440.628727 -123.528257)
			(xy 440.644795 -123.581664) (xy 440.652915 -123.63684) (xy 440.653424 -123.664726) (xy 440.652915 -123.692612)
			(xy 440.644795 -123.747788) (xy 440.628727 -123.801195) (xy 440.605055 -123.851692) (xy 440.574282 -123.898205)
			(xy 440.537065 -123.939742) (xy 440.494197 -123.975417) (xy 440.446591 -124.004471) (xy 440.395262 -124.026283)
			(xy 440.341305 -124.040389) (xy 440.285868 -124.046489) (xy 440.230134 -124.044452) (xy 440.175291 -124.034322)
			(xy 440.122507 -124.016315) (xy 440.072907 -123.990814) (xy 440.027549 -123.958363) (xy 439.9874 -123.919654)
			(xy 439.953314 -123.875511) (xy 439.926018 -123.826876) (xy 439.906095 -123.774785) (xy 439.893969 -123.720348)
			(xy 439.889898 -123.664726) (xy 437.389524 -123.664726) (xy 437.389524 -124.680726) (xy 439.889898 -124.680726)
			(xy 439.893969 -124.625104) (xy 439.906095 -124.570667) (xy 439.926018 -124.518576) (xy 439.953314 -124.469941)
			(xy 439.9874 -124.425798) (xy 440.027549 -124.387089) (xy 440.072907 -124.354638) (xy 440.122507 -124.329137)
			(xy 440.175291 -124.31113) (xy 440.230134 -124.301) (xy 440.285868 -124.298963) (xy 440.341305 -124.305063)
			(xy 440.395262 -124.319169) (xy 440.446591 -124.340981) (xy 440.494197 -124.370035) (xy 440.537065 -124.40571)
			(xy 440.574282 -124.447247) (xy 440.605055 -124.49376) (xy 440.628727 -124.544257) (xy 440.644795 -124.597664)
			(xy 440.652915 -124.65284) (xy 440.653424 -124.680726) (xy 440.652915 -124.708612) (xy 440.644795 -124.763788)
			(xy 440.628727 -124.817195) (xy 440.605055 -124.867692) (xy 440.574282 -124.914205) (xy 440.537065 -124.955742)
			(xy 440.494197 -124.991417) (xy 440.446591 -125.020471) (xy 440.395262 -125.042283) (xy 440.341305 -125.056389)
			(xy 440.285868 -125.062489) (xy 440.230134 -125.060452) (xy 440.175291 -125.050322) (xy 440.122507 -125.032315)
			(xy 440.072907 -125.006814) (xy 440.027549 -124.974363) (xy 439.9874 -124.935654) (xy 439.953314 -124.891511)
			(xy 439.926018 -124.842876) (xy 439.906095 -124.790785) (xy 439.893969 -124.736348) (xy 439.889898 -124.680726)
			(xy 437.389524 -124.680726) (xy 437.389524 -127.090678) (xy 437.388949 -127.115663) (xy 437.379195 -127.164674)
			(xy 437.360078 -127.210843) (xy 437.332328 -127.252402) (xy 437.315102 -127.27051) (xy 435.154832 -129.43078)
			(xy 435.136756 -129.448058) (xy 435.095205 -129.475865) (xy 435.049027 -129.495032) (xy 434.999998 -129.504824)
			(xy 434.975 -129.505456) (xy 433.75961 -129.505456) (xy 433.148232 -130.11658) (xy 433.130156 -130.133858)
			(xy 433.088605 -130.161665) (xy 433.042427 -130.180832) (xy 432.993398 -130.190624) (xy 432.9684 -130.191256)
			(xy 432.562 -130.191256) (xy 432.537004 -130.190626) (xy 432.48798 -130.180821) (xy 432.44181 -130.161645)
			(xy 432.400264 -130.133836) (xy 432.382168 -130.11658) (xy 431.84699 -129.581656) (xy 427.76521 -129.581656)
			(xy 427.017688 -130.329178) (xy 429.131728 -130.329178) (xy 429.135799 -130.273556) (xy 429.147925 -130.219119)
			(xy 429.167848 -130.167028) (xy 429.195144 -130.118393) (xy 429.22923 -130.07425) (xy 429.269379 -130.035541)
			(xy 429.314737 -130.00309) (xy 429.364337 -129.977589) (xy 429.417121 -129.959582) (xy 429.471964 -129.949452)
			(xy 429.527698 -129.947415) (xy 429.583135 -129.953515) (xy 429.637092 -129.967621) (xy 429.688421 -129.989433)
			(xy 429.736027 -130.018487) (xy 429.778895 -130.054162) (xy 429.816112 -130.095699) (xy 429.846885 -130.142212)
			(xy 429.870557 -130.192709) (xy 429.886625 -130.246116) (xy 429.894745 -130.301292) (xy 429.895254 -130.329178)
			(xy 429.894745 -130.357064) (xy 429.886625 -130.41224) (xy 429.870557 -130.465647) (xy 429.846885 -130.516144)
			(xy 429.816112 -130.562657) (xy 429.778895 -130.604194) (xy 429.736027 -130.639869) (xy 429.688421 -130.668923)
			(xy 429.637092 -130.690735) (xy 429.583135 -130.704841) (xy 429.527698 -130.710941) (xy 429.471964 -130.708904)
			(xy 429.417121 -130.698774) (xy 429.364337 -130.680767) (xy 429.314737 -130.655266) (xy 429.269379 -130.622815)
			(xy 429.22923 -130.584106) (xy 429.195144 -130.539963) (xy 429.167848 -130.491328) (xy 429.147925 -130.439237)
			(xy 429.135799 -130.3848) (xy 429.131728 -130.329178) (xy 427.017688 -130.329178) (xy 426.923708 -130.423158)
			(xy 426.923708 -130.851148) (xy 426.92306 -130.876144) (xy 426.913262 -130.925167) (xy 426.894093 -130.971338)
			(xy 426.866287 -131.012884) (xy 426.849032 -131.03098) (xy 426.300392 -131.57962) (xy 426.282297 -131.596876)
			(xy 426.240751 -131.624685) (xy 426.19458 -131.643858) (xy 426.145556 -131.653658) (xy 426.12056 -131.654296)
			(xy 425.00169 -131.654296) (xy 424.913552 -131.74218) (xy 424.895467 -131.759448) (xy 424.853919 -131.787257)
			(xy 424.807744 -131.806427) (xy 424.758717 -131.816222) (xy 424.73372 -131.816856) (xy 422.527222 -131.816856)
			(xy 421.672512 -132.671312) (xy 421.654407 -132.688557) (xy 421.612865 -132.716369) (xy 421.566697 -132.735545)
			(xy 421.517675 -132.745348) (xy 421.49268 -132.745988) (xy 420.7383 -132.745988) (xy 420.713304 -132.745349)
			(xy 420.664282 -132.735545) (xy 420.618112 -132.716372) (xy 420.576565 -132.688566) (xy 420.558468 -132.671312)
			(xy 419.703758 -131.816856) (xy 418.854382 -131.816856) (xy 417.723195 -132.947918) (xy 422.728642 -132.947918)
			(xy 422.732713 -132.892296) (xy 422.744839 -132.837859) (xy 422.764762 -132.785768) (xy 422.792058 -132.737133)
			(xy 422.826144 -132.69299) (xy 422.866293 -132.654281) (xy 422.911651 -132.62183) (xy 422.961251 -132.596329)
			(xy 423.014035 -132.578322) (xy 423.068878 -132.568192) (xy 423.124612 -132.566155) (xy 423.180049 -132.572255)
			(xy 423.234006 -132.586361) (xy 423.285335 -132.608173) (xy 423.332941 -132.637227) (xy 423.375809 -132.672902)
			(xy 423.413026 -132.714439) (xy 423.443799 -132.760952) (xy 423.467471 -132.811449) (xy 423.483539 -132.864856)
			(xy 423.491659 -132.920032) (xy 423.492168 -132.947918) (xy 423.491659 -132.975804) (xy 423.483539 -133.03098)
			(xy 423.467471 -133.084387) (xy 423.443799 -133.134884) (xy 423.413026 -133.181397) (xy 423.375809 -133.222934)
			(xy 423.332941 -133.258609) (xy 423.285335 -133.287663) (xy 423.234006 -133.309475) (xy 423.180049 -133.323581)
			(xy 423.124612 -133.329681) (xy 423.068878 -133.327644) (xy 423.014035 -133.317514) (xy 422.961251 -133.299507)
			(xy 422.911651 -133.274006) (xy 422.866293 -133.241555) (xy 422.826144 -133.202846) (xy 422.792058 -133.158703)
			(xy 422.764762 -133.110068) (xy 422.744839 -133.057977) (xy 422.732713 -133.00354) (xy 422.728642 -132.947918)
			(xy 417.723195 -132.947918) (xy 416.563556 -134.107428) (xy 416.563556 -135.142478) (xy 419.188136 -135.142478)
			(xy 419.192207 -135.086856) (xy 419.204333 -135.032419) (xy 419.224256 -134.980328) (xy 419.251552 -134.931693)
			(xy 419.285638 -134.88755) (xy 419.325787 -134.848841) (xy 419.371145 -134.81639) (xy 419.420745 -134.790889)
			(xy 419.473529 -134.772882) (xy 419.528372 -134.762752) (xy 419.584106 -134.760715) (xy 419.639543 -134.766815)
			(xy 419.6935 -134.780921) (xy 419.744829 -134.802733) (xy 419.792435 -134.831787) (xy 419.835303 -134.867462)
			(xy 419.87252 -134.908999) (xy 419.903293 -134.955512) (xy 419.926965 -135.006009) (xy 419.943033 -135.059416)
			(xy 419.951153 -135.114592) (xy 419.951662 -135.142478) (xy 419.951153 -135.170364) (xy 419.943033 -135.22554)
			(xy 419.926965 -135.278947) (xy 419.903293 -135.329444) (xy 419.87252 -135.375957) (xy 419.835303 -135.417494)
			(xy 419.792435 -135.453169) (xy 419.744829 -135.482223) (xy 419.6935 -135.504035) (xy 419.639543 -135.518141)
			(xy 419.584106 -135.524241) (xy 419.528372 -135.522204) (xy 419.473529 -135.512074) (xy 419.420745 -135.494067)
			(xy 419.371145 -135.468566) (xy 419.325787 -135.436115) (xy 419.285638 -135.397406) (xy 419.251552 -135.353263)
			(xy 419.224256 -135.304628) (xy 419.204333 -135.252537) (xy 419.192207 -135.1981) (xy 419.188136 -135.142478)
			(xy 416.563556 -135.142478) (xy 416.563556 -138.575288) (xy 419.00043 -138.575288) (xy 419.004501 -138.519666)
			(xy 419.016627 -138.465229) (xy 419.03655 -138.413138) (xy 419.063846 -138.364503) (xy 419.097932 -138.32036)
			(xy 419.138081 -138.281651) (xy 419.183439 -138.2492) (xy 419.233039 -138.223699) (xy 419.285823 -138.205692)
			(xy 419.340666 -138.195562) (xy 419.3964 -138.193525) (xy 419.451837 -138.199625) (xy 419.505794 -138.213731)
			(xy 419.557123 -138.235543) (xy 419.604729 -138.264597) (xy 419.647597 -138.300272) (xy 419.684814 -138.341809)
			(xy 419.715587 -138.388322) (xy 419.739259 -138.438819) (xy 419.755327 -138.492226) (xy 419.763447 -138.547402)
			(xy 419.763956 -138.575288) (xy 419.763447 -138.603174) (xy 419.755327 -138.65835) (xy 419.739259 -138.711757)
			(xy 419.715587 -138.762254) (xy 419.684814 -138.808767) (xy 419.647597 -138.850304) (xy 419.604729 -138.885979)
			(xy 419.557123 -138.915033) (xy 419.505794 -138.936845) (xy 419.451837 -138.950951) (xy 419.3964 -138.957051)
			(xy 419.340666 -138.955014) (xy 419.285823 -138.944884) (xy 419.233039 -138.926877) (xy 419.183439 -138.901376)
			(xy 419.138081 -138.868925) (xy 419.097932 -138.830216) (xy 419.063846 -138.786073) (xy 419.03655 -138.737438)
			(xy 419.016627 -138.685347) (xy 419.004501 -138.63091) (xy 419.00043 -138.575288) (xy 416.563556 -138.575288)
			(xy 416.563556 -139.48664) (xy 417.582602 -139.48664) (xy 417.586673 -139.431018) (xy 417.598799 -139.376581)
			(xy 417.618722 -139.32449) (xy 417.646018 -139.275855) (xy 417.680104 -139.231712) (xy 417.720253 -139.193003)
			(xy 417.765611 -139.160552) (xy 417.815211 -139.135051) (xy 417.867995 -139.117044) (xy 417.922838 -139.106914)
			(xy 417.978572 -139.104877) (xy 418.034009 -139.110977) (xy 418.087966 -139.125083) (xy 418.139295 -139.146895)
			(xy 418.186901 -139.175949) (xy 418.229769 -139.211624) (xy 418.266986 -139.253161) (xy 418.297759 -139.299674)
			(xy 418.321431 -139.350171) (xy 418.337499 -139.403578) (xy 418.345619 -139.458754) (xy 418.346128 -139.48664)
			(xy 418.345619 -139.514526) (xy 418.343667 -139.527788) (xy 419.538402 -139.527788) (xy 419.542473 -139.472166)
			(xy 419.554599 -139.417729) (xy 419.574522 -139.365638) (xy 419.601818 -139.317003) (xy 419.635904 -139.27286)
			(xy 419.676053 -139.234151) (xy 419.721411 -139.2017) (xy 419.771011 -139.176199) (xy 419.823795 -139.158192)
			(xy 419.878638 -139.148062) (xy 419.934372 -139.146025) (xy 419.989809 -139.152125) (xy 420.043766 -139.166231)
			(xy 420.095095 -139.188043) (xy 420.142701 -139.217097) (xy 420.185569 -139.252772) (xy 420.222786 -139.294309)
			(xy 420.253559 -139.340822) (xy 420.277231 -139.391319) (xy 420.293299 -139.444726) (xy 420.301419 -139.499902)
			(xy 420.301928 -139.527788) (xy 420.301419 -139.555674) (xy 420.293299 -139.61085) (xy 420.277231 -139.664257)
			(xy 420.253559 -139.714754) (xy 420.222786 -139.761267) (xy 420.185569 -139.802804) (xy 420.142701 -139.838479)
			(xy 420.095095 -139.867533) (xy 420.043766 -139.889345) (xy 419.989809 -139.903451) (xy 419.934372 -139.909551)
			(xy 419.878638 -139.907514) (xy 419.823795 -139.897384) (xy 419.771011 -139.879377) (xy 419.721411 -139.853876)
			(xy 419.676053 -139.821425) (xy 419.635904 -139.782716) (xy 419.601818 -139.738573) (xy 419.574522 -139.689938)
			(xy 419.554599 -139.637847) (xy 419.542473 -139.58341) (xy 419.538402 -139.527788) (xy 418.343667 -139.527788)
			(xy 418.337499 -139.569702) (xy 418.321431 -139.623109) (xy 418.297759 -139.673606) (xy 418.266986 -139.720119)
			(xy 418.229769 -139.761656) (xy 418.186901 -139.797331) (xy 418.139295 -139.826385) (xy 418.087966 -139.848197)
			(xy 418.034009 -139.862303) (xy 417.978572 -139.868403) (xy 417.922838 -139.866366) (xy 417.867995 -139.856236)
			(xy 417.815211 -139.838229) (xy 417.765611 -139.812728) (xy 417.720253 -139.780277) (xy 417.680104 -139.741568)
			(xy 417.646018 -139.697425) (xy 417.618722 -139.64879) (xy 417.598799 -139.596699) (xy 417.586673 -139.542262)
			(xy 417.582602 -139.48664) (xy 416.563556 -139.48664) (xy 416.563556 -142.458948) (xy 416.868862 -142.458948)
			(xy 416.872933 -142.403326) (xy 416.885059 -142.348889) (xy 416.904982 -142.296798) (xy 416.932278 -142.248163)
			(xy 416.966364 -142.20402) (xy 417.006513 -142.165311) (xy 417.051871 -142.13286) (xy 417.101471 -142.107359)
			(xy 417.154255 -142.089352) (xy 417.209098 -142.079222) (xy 417.264832 -142.077185) (xy 417.320269 -142.083285)
			(xy 417.374226 -142.097391) (xy 417.425555 -142.119203) (xy 417.473161 -142.148257) (xy 417.516029 -142.183932)
			(xy 417.553246 -142.225469) (xy 417.584019 -142.271982) (xy 417.607691 -142.322479) (xy 417.623759 -142.375886)
			(xy 417.631879 -142.431062) (xy 417.632388 -142.458948) (xy 417.631879 -142.486834) (xy 417.623759 -142.54201)
			(xy 417.607691 -142.595417) (xy 417.584019 -142.645914) (xy 417.553246 -142.692427) (xy 417.516029 -142.733964)
			(xy 417.473161 -142.769639) (xy 417.425555 -142.798693) (xy 417.374226 -142.820505) (xy 417.320269 -142.834611)
			(xy 417.264832 -142.840711) (xy 417.209098 -142.838674) (xy 417.154255 -142.828544) (xy 417.101471 -142.810537)
			(xy 417.051871 -142.785036) (xy 417.006513 -142.752585) (xy 416.966364 -142.713876) (xy 416.932278 -142.669733)
			(xy 416.904982 -142.621098) (xy 416.885059 -142.569007) (xy 416.872933 -142.51457) (xy 416.868862 -142.458948)
			(xy 416.563556 -142.458948) (xy 416.563556 -146.442938) (xy 417.303712 -147.18284) (xy 423.0878 -147.18284)
			(xy 423.112796 -147.183471) (xy 423.161819 -147.193276) (xy 423.20799 -147.212451) (xy 423.249536 -147.24026)
			(xy 423.267632 -147.257516) (xy 426.395134 -150.385018) (xy 426.412376 -150.40311) (xy 426.440114 -150.444675)
			(xy 426.459217 -150.490851) (xy 426.46895 -150.539864) (xy 426.469556 -150.56485) (xy 426.469556 -152.640792)
			(xy 426.46892 -152.665774) (xy 426.459184 -152.714781) (xy 426.440084 -152.760951) (xy 426.412352 -152.802513)
			(xy 426.395134 -152.820624) (xy 425.163488 -154.052524) (xy 425.163488 -157.29966) (xy 425.162825 -157.324655)
			(xy 425.153028 -157.373676) (xy 425.133863 -157.419846) (xy 425.106063 -157.461394) (xy 425.088812 -157.479492)
			(xy 420.66337 -161.904934) (xy 420.675816 -161.936176) (xy 420.684414 -161.958762) (xy 420.696517 -162.005549)
			(xy 420.70262 -162.05349) (xy 420.702994 -162.077654) (xy 420.702502 -162.104906) (xy 420.694751 -162.158857)
			(xy 420.6794 -162.211155) (xy 420.656762 -162.260736) (xy 420.627297 -162.30659) (xy 420.591606 -162.347784)
			(xy 420.550416 -162.383478) (xy 420.504564 -162.412946) (xy 420.454985 -162.435589) (xy 420.402688 -162.450944)
			(xy 420.348738 -162.4587) (xy 420.321486 -162.459162) (xy 420.321232 -162.459162) (xy 420.291393 -162.458593)
			(xy 420.232447 -162.449273) (xy 420.203884 -162.44062) (xy 420.189967 -162.436614) (xy 420.161038 -162.435695)
			(xy 420.133019 -162.442952) (xy 420.108173 -162.457799) (xy 420.088508 -162.479036) (xy 420.075613 -162.504949)
			(xy 420.072566 -162.519106) (xy 420.06599 -162.551947) (xy 420.042863 -162.614798) (xy 420.026592 -162.644074)
			(xy 420.019587 -162.657057) (xy 420.012541 -162.685688) (xy 420.013975 -162.715137) (xy 420.023771 -162.742948)
			(xy 420.04111 -162.766795) (xy 420.064544 -162.78469) (xy 420.078154 -162.790378) (xy 420.104942 -162.801047)
			(xy 420.155182 -162.829341) (xy 420.20059 -162.864876) (xy 420.240131 -162.906842) (xy 420.272903 -162.954283)
			(xy 420.298159 -163.006117) (xy 420.315323 -163.061162) (xy 420.324005 -163.118164) (xy 420.324534 -163.146994)
			(xy 420.324048 -163.174245) (xy 420.316292 -163.228193) (xy 420.300937 -163.280488) (xy 420.278295 -163.330065)
			(xy 420.248829 -163.375915) (xy 420.213138 -163.417106) (xy 420.171947 -163.452797) (xy 420.126097 -163.482263)
			(xy 420.07652 -163.504905) (xy 420.024225 -163.52026) (xy 419.970277 -163.528016) (xy 419.915775 -163.528016)
			(xy 419.861827 -163.52026) (xy 419.809532 -163.504905) (xy 419.759955 -163.482263) (xy 419.714105 -163.452797)
			(xy 419.672914 -163.417106) (xy 419.637223 -163.375915) (xy 419.607757 -163.330065) (xy 419.585115 -163.280488)
			(xy 419.56976 -163.228193) (xy 419.562004 -163.174245) (xy 419.561518 -163.146994) (xy 419.561518 -163.14674)
			(xy 419.561938 -163.121537) (xy 419.568572 -163.07157) (xy 419.581743 -163.022915) (xy 419.601219 -162.976425)
			(xy 419.613588 -162.954462) (xy 419.620627 -162.941499) (xy 419.627653 -162.912862) (xy 419.626205 -162.883412)
			(xy 419.616403 -162.855603) (xy 419.599064 -162.831754) (xy 419.575634 -162.813852) (xy 419.562026 -162.808158)
			(xy 419.535269 -162.797416) (xy 419.485027 -162.769136) (xy 419.439617 -162.733613) (xy 419.400072 -162.691658)
			(xy 419.367296 -162.644228) (xy 419.342035 -162.592402) (xy 419.324865 -162.537365) (xy 419.316178 -162.480369)
			(xy 419.315646 -162.451542) (xy 419.316217 -162.424294) (xy 419.323967 -162.370352) (xy 419.339314 -162.318061)
			(xy 419.361947 -162.268487) (xy 419.391405 -162.222639) (xy 419.427087 -162.18145) (xy 419.468269 -162.145757)
			(xy 419.51411 -162.116289) (xy 419.563679 -162.093645) (xy 419.615966 -162.078285) (xy 419.669906 -162.070523)
			(xy 419.697154 -162.070034) (xy 419.697408 -162.070034) (xy 419.727247 -162.070617) (xy 419.786193 -162.079927)
			(xy 419.814756 -162.088576) (xy 419.82866 -162.09263) (xy 419.857597 -162.09354) (xy 419.885621 -162.086274)
			(xy 419.910469 -162.071418) (xy 419.930134 -162.050171) (xy 419.943028 -162.024251) (xy 419.946074 -162.01009)
			(xy 419.951729 -161.981676) (xy 419.970527 -161.926878) (xy 419.997387 -161.875548) (xy 420.031693 -161.828865)
			(xy 420.072657 -161.7879) (xy 420.09568 -161.770314) (xy 420.105009 -161.753093) (xy 420.128097 -161.721458)
			(xy 420.141654 -161.707322) (xy 424.654472 -157.19425) (xy 424.654472 -153.947114) (xy 424.655102 -153.922118)
			(xy 424.664906 -153.873094) (xy 424.684081 -153.826923) (xy 424.711891 -153.785377) (xy 424.729148 -153.767282)
			(xy 425.961048 -152.535382) (xy 425.961048 -150.67026) (xy 422.98239 -147.691856) (xy 417.198302 -147.691856)
			(xy 417.173306 -147.691225) (xy 417.124282 -147.68142) (xy 417.078112 -147.662245) (xy 417.036566 -147.634436)
			(xy 417.01847 -147.61718) (xy 416.12947 -146.72818) (xy 416.112228 -146.710088) (xy 416.084489 -146.668523)
			(xy 416.065387 -146.622347) (xy 416.055654 -146.573334) (xy 416.055048 -146.548348) (xy 415.765488 -146.548348)
			(xy 415.765488 -146.943318) (xy 417.78301 -148.96084) (xy 422.4782 -148.96084) (xy 422.503196 -148.961471)
			(xy 422.552219 -148.971276) (xy 422.59839 -148.990451) (xy 422.639936 -149.01826) (xy 422.658032 -149.035516)
			(xy 423.343832 -149.721316) (xy 423.361077 -149.739422) (xy 423.388892 -149.780962) (xy 423.408069 -149.82713)
			(xy 423.417871 -149.876152) (xy 423.418508 -149.901148) (xy 423.418508 -151.018748) (xy 423.976292 -151.018748)
			(xy 423.976778 -150.991497) (xy 423.984534 -150.937549) (xy 423.999889 -150.885254) (xy 424.022531 -150.835677)
			(xy 424.051997 -150.789827) (xy 424.087688 -150.748636) (xy 424.128879 -150.712945) (xy 424.174729 -150.683479)
			(xy 424.224306 -150.660837) (xy 424.276601 -150.645482) (xy 424.330549 -150.637726) (xy 424.385051 -150.637726)
			(xy 424.438999 -150.645482) (xy 424.491294 -150.660837) (xy 424.540871 -150.683479) (xy 424.586721 -150.712945)
			(xy 424.627912 -150.748636) (xy 424.663603 -150.789827) (xy 424.693069 -150.835677) (xy 424.715711 -150.885254)
			(xy 424.731066 -150.937549) (xy 424.738822 -150.991497) (xy 424.739308 -151.018748) (xy 424.739308 -151.019002)
			(xy 424.739877 -151.034449) (xy 424.749157 -151.063917) (xy 424.766809 -151.089273) (xy 424.791224 -151.108204)
			(xy 424.820177 -151.118986) (xy 424.835574 -151.120348) (xy 424.864452 -151.122457) (xy 424.921128 -151.134291)
			(xy 424.975366 -151.154551) (xy 425.025922 -151.182773) (xy 425.071634 -151.218307) (xy 425.111453 -151.26034)
			(xy 425.144465 -151.307905) (xy 425.169913 -151.359911) (xy 425.187213 -151.415165) (xy 425.195968 -151.472399)
			(xy 425.196508 -151.501348) (xy 425.196022 -151.528599) (xy 425.188266 -151.582547) (xy 425.172911 -151.634842)
			(xy 425.150269 -151.684419) (xy 425.120803 -151.730269) (xy 425.085112 -151.77146) (xy 425.043921 -151.807151)
			(xy 424.998071 -151.836617) (xy 424.948494 -151.859259) (xy 424.896199 -151.874614) (xy 424.842251 -151.88237)
			(xy 424.787749 -151.88237) (xy 424.733801 -151.874614) (xy 424.681506 -151.859259) (xy 424.631929 -151.836617)
			(xy 424.586079 -151.807151) (xy 424.544888 -151.77146) (xy 424.509197 -151.730269) (xy 424.479731 -151.684419)
			(xy 424.457089 -151.634842) (xy 424.441734 -151.582547) (xy 424.433978 -151.528599) (xy 424.433492 -151.501348)
			(xy 424.433492 -151.501094) (xy 424.432927 -151.485647) (xy 424.423646 -151.456178) (xy 424.405993 -151.430823)
			(xy 424.381577 -151.411891) (xy 424.352623 -151.40111) (xy 424.337226 -151.399748) (xy 424.308348 -151.397643)
			(xy 424.251671 -151.385809) (xy 424.197432 -151.365548) (xy 424.146877 -151.337326) (xy 424.101165 -151.301791)
			(xy 424.061346 -151.259758) (xy 424.028333 -151.212193) (xy 424.002885 -151.160186) (xy 423.985586 -151.104931)
			(xy 423.976832 -151.047698) (xy 423.976292 -151.018748) (xy 423.418508 -151.018748) (xy 423.418508 -152.498552)
			(xy 423.417862 -152.523548) (xy 423.408064 -152.572571) (xy 423.388894 -152.618742) (xy 423.361087 -152.660288)
			(xy 423.343832 -152.678384) (xy 423.087546 -152.93467) (xy 423.087546 -152.956006) (xy 423.087093 -152.983281)
			(xy 423.079394 -153.037284) (xy 423.064082 -153.08964) (xy 423.041469 -153.139282) (xy 423.012017 -153.185197)
			(xy 422.976326 -153.226449) (xy 422.935123 -153.262198) (xy 422.88925 -153.291714) (xy 422.83964 -153.314396)
			(xy 422.787305 -153.329781) (xy 422.733313 -153.337555) (xy 422.706038 -153.338022) (xy 422.678773 -153.337533)
			(xy 422.624797 -153.329774) (xy 422.572477 -153.314409) (xy 422.522877 -153.291751) (xy 422.477008 -153.262261)
			(xy 422.435806 -153.226541) (xy 422.400109 -153.185319) (xy 422.370645 -153.139434) (xy 422.348015 -153.089821)
			(xy 422.33268 -153.037491) (xy 422.324952 -152.983511) (xy 422.324988 -152.928981) (xy 422.332788 -152.875012)
			(xy 422.348193 -152.822703) (xy 422.370889 -152.77312) (xy 422.400414 -152.727274) (xy 422.436165 -152.686099)
			(xy 422.477415 -152.650434) (xy 422.523323 -152.621006) (xy 422.572953 -152.598414) (xy 422.625294 -152.583118)
			(xy 422.67928 -152.575431) (xy 422.706546 -152.575006) (xy 422.727882 -152.575006) (xy 422.909492 -152.393142)
			(xy 422.909492 -150.006558) (xy 422.37279 -149.469856) (xy 417.6776 -149.469856) (xy 417.652604 -149.469226)
			(xy 417.60358 -149.459421) (xy 417.55741 -149.440245) (xy 417.515864 -149.412436) (xy 417.497768 -149.39518)
			(xy 415.331148 -147.22856) (xy 415.313888 -147.210468) (xy 415.286076 -147.168923) (xy 415.266904 -147.12275)
			(xy 415.257107 -147.073725) (xy 415.256472 -147.048728) (xy 410.131006 -147.048728) (xy 410.131006 -150.423949)
			(xy 420.30348 -150.423949) (xy 420.30348 -150.369451) (xy 420.311235 -150.315508) (xy 420.326587 -150.263217)
			(xy 420.349225 -150.213643) (xy 420.378687 -150.167796) (xy 420.414373 -150.126607) (xy 420.455557 -150.090915)
			(xy 420.501401 -150.061448) (xy 420.550972 -150.038804) (xy 420.603261 -150.023445) (xy 420.657203 -150.015683)
			(xy 420.684452 -150.015194) (xy 420.711821 -150.01569) (xy 420.765999 -150.023501) (xy 420.818502 -150.038983)
			(xy 420.868249 -150.061818) (xy 420.914217 -150.091536) (xy 420.93515 -150.109174) (xy 420.946478 -150.11841)
			(xy 420.973035 -150.130586) (xy 421.001952 -150.134759) (xy 421.030869 -150.130586) (xy 421.057426 -150.11841)
			(xy 421.068754 -150.109174) (xy 421.089687 -150.091533) (xy 421.135655 -150.061809) (xy 421.185401 -150.038963)
			(xy 421.237903 -150.023467) (xy 421.292081 -150.015638) (xy 421.346823 -150.015638) (xy 421.401001 -150.023467)
			(xy 421.453503 -150.038963) (xy 421.503249 -150.061809) (xy 421.549217 -150.091533) (xy 421.57015 -150.109174)
			(xy 421.581478 -150.11841) (xy 421.608035 -150.130586) (xy 421.636952 -150.134759) (xy 421.665869 -150.130586)
			(xy 421.692426 -150.11841) (xy 421.703754 -150.109174) (xy 421.724689 -150.091539) (xy 421.770662 -150.061827)
			(xy 421.820408 -150.038991) (xy 421.872908 -150.023499) (xy 421.927083 -150.015669) (xy 421.954452 -150.015194)
			(xy 421.981707 -150.01565) (xy 422.035664 -150.023402) (xy 422.087968 -150.038753) (xy 422.137554 -150.061393)
			(xy 422.183413 -150.09086) (xy 422.224612 -150.126554) (xy 422.260311 -150.167748) (xy 422.289784 -150.213604)
			(xy 422.31243 -150.263187) (xy 422.327788 -150.315489) (xy 422.335547 -150.369445) (xy 422.335547 -150.423955)
			(xy 422.327788 -150.477911) (xy 422.31243 -150.530213) (xy 422.289784 -150.579796) (xy 422.260311 -150.625652)
			(xy 422.224612 -150.666846) (xy 422.183413 -150.70254) (xy 422.137554 -150.732007) (xy 422.087968 -150.754647)
			(xy 422.035664 -150.769998) (xy 421.981707 -150.77775) (xy 421.954452 -150.77821) (xy 421.927083 -150.777711)
			(xy 421.872905 -150.769901) (xy 421.820403 -150.754419) (xy 421.770655 -150.731585) (xy 421.724687 -150.701868)
			(xy 421.703754 -150.68423) (xy 421.692426 -150.674994) (xy 421.665869 -150.662818) (xy 421.636952 -150.658645)
			(xy 421.608035 -150.662818) (xy 421.581478 -150.674994) (xy 421.57015 -150.68423) (xy 421.549217 -150.701871)
			(xy 421.503249 -150.731595) (xy 421.453503 -150.754441) (xy 421.401001 -150.769937) (xy 421.346823 -150.777766)
			(xy 421.292081 -150.777766) (xy 421.237903 -150.769937) (xy 421.185401 -150.754441) (xy 421.135655 -150.731595)
			(xy 421.089687 -150.701871) (xy 421.068754 -150.68423) (xy 421.057426 -150.674994) (xy 421.030869 -150.662818)
			(xy 421.001952 -150.658645) (xy 420.973035 -150.662818) (xy 420.946478 -150.674994) (xy 420.93515 -150.68423)
			(xy 420.914214 -150.701864) (xy 420.868242 -150.731575) (xy 420.818495 -150.754412) (xy 420.765996 -150.769904)
			(xy 420.711821 -150.777735) (xy 420.684452 -150.77821) (xy 420.657203 -150.777717) (xy 420.603261 -150.769955)
			(xy 420.550972 -150.754596) (xy 420.501401 -150.731952) (xy 420.455557 -150.702485) (xy 420.414373 -150.666793)
			(xy 420.378687 -150.625604) (xy 420.349225 -150.579757) (xy 420.326587 -150.530183) (xy 420.311235 -150.477892)
			(xy 420.30348 -150.423949) (xy 410.131006 -150.423949) (xy 410.131006 -151.116284) (xy 418.675564 -151.116284)
			(xy 418.679635 -151.060662) (xy 418.691761 -151.006225) (xy 418.711684 -150.954134) (xy 418.73898 -150.905499)
			(xy 418.773066 -150.861356) (xy 418.813215 -150.822647) (xy 418.858573 -150.790196) (xy 418.908173 -150.764695)
			(xy 418.960957 -150.746688) (xy 419.0158 -150.736558) (xy 419.071534 -150.734521) (xy 419.126971 -150.740621)
			(xy 419.180928 -150.754727) (xy 419.232257 -150.776539) (xy 419.279863 -150.805593) (xy 419.322731 -150.841268)
			(xy 419.359948 -150.882805) (xy 419.390721 -150.929318) (xy 419.414393 -150.979815) (xy 419.430461 -151.033222)
			(xy 419.438581 -151.088398) (xy 419.43909 -151.116284) (xy 419.439044 -151.118824) (xy 419.681658 -151.118824)
			(xy 419.685729 -151.063202) (xy 419.697855 -151.008765) (xy 419.717778 -150.956674) (xy 419.745074 -150.908039)
			(xy 419.77916 -150.863896) (xy 419.819309 -150.825187) (xy 419.864667 -150.792736) (xy 419.914267 -150.767235)
			(xy 419.967051 -150.749228) (xy 420.021894 -150.739098) (xy 420.077628 -150.737061) (xy 420.133065 -150.743161)
			(xy 420.187022 -150.757267) (xy 420.238351 -150.779079) (xy 420.285957 -150.808133) (xy 420.328825 -150.843808)
			(xy 420.366042 -150.885345) (xy 420.396815 -150.931858) (xy 420.420487 -150.982355) (xy 420.436555 -151.035762)
			(xy 420.444675 -151.090938) (xy 420.445184 -151.118824) (xy 420.444675 -151.14671) (xy 420.436555 -151.201886)
			(xy 420.420487 -151.255293) (xy 420.396815 -151.30579) (xy 420.366042 -151.352303) (xy 420.328825 -151.39384)
			(xy 420.285957 -151.429515) (xy 420.238351 -151.458569) (xy 420.187022 -151.480381) (xy 420.133065 -151.494487)
			(xy 420.077628 -151.500587) (xy 420.021894 -151.49855) (xy 419.967051 -151.48842) (xy 419.914267 -151.470413)
			(xy 419.864667 -151.444912) (xy 419.819309 -151.412461) (xy 419.77916 -151.373752) (xy 419.745074 -151.329609)
			(xy 419.717778 -151.280974) (xy 419.697855 -151.228883) (xy 419.685729 -151.174446) (xy 419.681658 -151.118824)
			(xy 419.439044 -151.118824) (xy 419.438581 -151.14417) (xy 419.430461 -151.199346) (xy 419.414393 -151.252753)
			(xy 419.390721 -151.30325) (xy 419.359948 -151.349763) (xy 419.322731 -151.3913) (xy 419.279863 -151.426975)
			(xy 419.232257 -151.456029) (xy 419.180928 -151.477841) (xy 419.126971 -151.491947) (xy 419.071534 -151.498047)
			(xy 419.0158 -151.49601) (xy 418.960957 -151.48588) (xy 418.908173 -151.467873) (xy 418.858573 -151.442372)
			(xy 418.813215 -151.409921) (xy 418.773066 -151.371212) (xy 418.73898 -151.327069) (xy 418.711684 -151.278434)
			(xy 418.691761 -151.226343) (xy 418.679635 -151.171906) (xy 418.675564 -151.116284) (xy 410.131006 -151.116284)
			(xy 410.131006 -152.03297) (xy 418.678358 -152.03297) (xy 418.682429 -151.977348) (xy 418.694555 -151.922911)
			(xy 418.714478 -151.87082) (xy 418.741774 -151.822185) (xy 418.77586 -151.778042) (xy 418.816009 -151.739333)
			(xy 418.861367 -151.706882) (xy 418.910967 -151.681381) (xy 418.963751 -151.663374) (xy 419.018594 -151.653244)
			(xy 419.074328 -151.651207) (xy 419.129765 -151.657307) (xy 419.183722 -151.671413) (xy 419.235051 -151.693225)
			(xy 419.282657 -151.722279) (xy 419.325525 -151.757954) (xy 419.362742 -151.799491) (xy 419.393515 -151.846004)
			(xy 419.417187 -151.896501) (xy 419.433255 -151.949908) (xy 419.441375 -152.005084) (xy 419.441884 -152.03297)
			(xy 419.441787 -152.038304) (xy 419.676578 -152.038304) (xy 419.680649 -151.982682) (xy 419.692775 -151.928245)
			(xy 419.712698 -151.876154) (xy 419.739994 -151.827519) (xy 419.77408 -151.783376) (xy 419.814229 -151.744667)
			(xy 419.859587 -151.712216) (xy 419.909187 -151.686715) (xy 419.961971 -151.668708) (xy 420.016814 -151.658578)
			(xy 420.072548 -151.656541) (xy 420.127985 -151.662641) (xy 420.181942 -151.676747) (xy 420.233271 -151.698559)
			(xy 420.280877 -151.727613) (xy 420.323745 -151.763288) (xy 420.360962 -151.804825) (xy 420.391735 -151.851338)
			(xy 420.415407 -151.901835) (xy 420.431475 -151.955242) (xy 420.439595 -152.010418) (xy 420.440104 -152.038304)
			(xy 420.439595 -152.06619) (xy 420.431475 -152.121366) (xy 420.415407 -152.174773) (xy 420.391735 -152.22527)
			(xy 420.360962 -152.271783) (xy 420.323745 -152.31332) (xy 420.280877 -152.348995) (xy 420.233271 -152.378049)
			(xy 420.181942 -152.399861) (xy 420.127985 -152.413967) (xy 420.072548 -152.420067) (xy 420.016814 -152.41803)
			(xy 419.961971 -152.4079) (xy 419.909187 -152.389893) (xy 419.859587 -152.364392) (xy 419.814229 -152.331941)
			(xy 419.77408 -152.293232) (xy 419.739994 -152.249089) (xy 419.712698 -152.200454) (xy 419.692775 -152.148363)
			(xy 419.680649 -152.093926) (xy 419.676578 -152.038304) (xy 419.441787 -152.038304) (xy 419.441375 -152.060856)
			(xy 419.433255 -152.116032) (xy 419.417187 -152.169439) (xy 419.393515 -152.219936) (xy 419.362742 -152.266449)
			(xy 419.325525 -152.307986) (xy 419.282657 -152.343661) (xy 419.235051 -152.372715) (xy 419.183722 -152.394527)
			(xy 419.129765 -152.408633) (xy 419.074328 -152.414733) (xy 419.018594 -152.412696) (xy 418.963751 -152.402566)
			(xy 418.910967 -152.384559) (xy 418.861367 -152.359058) (xy 418.816009 -152.326607) (xy 418.77586 -152.287898)
			(xy 418.741774 -152.243755) (xy 418.714478 -152.19512) (xy 418.694555 -152.143029) (xy 418.682429 -152.088592)
			(xy 418.678358 -152.03297) (xy 410.131006 -152.03297) (xy 410.131006 -152.977342) (xy 421.425622 -152.977342)
			(xy 421.429693 -152.92172) (xy 421.441819 -152.867283) (xy 421.461742 -152.815192) (xy 421.489038 -152.766557)
			(xy 421.523124 -152.722414) (xy 421.563273 -152.683705) (xy 421.608631 -152.651254) (xy 421.658231 -152.625753)
			(xy 421.711015 -152.607746) (xy 421.765858 -152.597616) (xy 421.821592 -152.595579) (xy 421.877029 -152.601679)
			(xy 421.930986 -152.615785) (xy 421.982315 -152.637597) (xy 422.029921 -152.666651) (xy 422.072789 -152.702326)
			(xy 422.110006 -152.743863) (xy 422.140779 -152.790376) (xy 422.164451 -152.840873) (xy 422.180519 -152.89428)
			(xy 422.188639 -152.949456) (xy 422.189148 -152.977342) (xy 422.188639 -153.005228) (xy 422.180519 -153.060404)
			(xy 422.164451 -153.113811) (xy 422.140779 -153.164308) (xy 422.110006 -153.210821) (xy 422.072789 -153.252358)
			(xy 422.029921 -153.288033) (xy 421.982315 -153.317087) (xy 421.930986 -153.338899) (xy 421.877029 -153.353005)
			(xy 421.821592 -153.359105) (xy 421.765858 -153.357068) (xy 421.711015 -153.346938) (xy 421.658231 -153.328931)
			(xy 421.608631 -153.30343) (xy 421.563273 -153.270979) (xy 421.523124 -153.23227) (xy 421.489038 -153.188127)
			(xy 421.461742 -153.139492) (xy 421.441819 -153.087401) (xy 421.429693 -153.032964) (xy 421.425622 -152.977342)
			(xy 410.131006 -152.977342) (xy 410.131006 -155.499308) (xy 417.524182 -155.499308) (xy 417.528253 -155.443686)
			(xy 417.540379 -155.389249) (xy 417.560302 -155.337158) (xy 417.587598 -155.288523) (xy 417.621684 -155.24438)
			(xy 417.661833 -155.205671) (xy 417.707191 -155.17322) (xy 417.756791 -155.147719) (xy 417.809575 -155.129712)
			(xy 417.864418 -155.119582) (xy 417.920152 -155.117545) (xy 417.975589 -155.123645) (xy 418.029546 -155.137751)
			(xy 418.080875 -155.159563) (xy 418.128481 -155.188617) (xy 418.162419 -155.21686) (xy 420.484552 -155.21686)
			(xy 420.488623 -155.161238) (xy 420.500749 -155.106801) (xy 420.520672 -155.05471) (xy 420.547968 -155.006075)
			(xy 420.582054 -154.961932) (xy 420.622203 -154.923223) (xy 420.667561 -154.890772) (xy 420.717161 -154.865271)
			(xy 420.769945 -154.847264) (xy 420.824788 -154.837134) (xy 420.880522 -154.835097) (xy 420.935959 -154.841197)
			(xy 420.989916 -154.855303) (xy 421.041245 -154.877115) (xy 421.088851 -154.906169) (xy 421.112505 -154.925854)
			(xy 421.450453 -154.925854) (xy 421.450453 -154.871346) (xy 421.458211 -154.817394) (xy 421.473568 -154.765094)
			(xy 421.496212 -154.715513) (xy 421.525681 -154.669659) (xy 421.561377 -154.628465) (xy 421.602572 -154.592772)
			(xy 421.648427 -154.563304) (xy 421.698009 -154.540662) (xy 421.750309 -154.525307) (xy 421.804262 -154.517552)
			(xy 421.831516 -154.51709) (xy 421.861892 -154.517675) (xy 421.921876 -154.527306) (xy 421.979575 -154.54632)
			(xy 422.033532 -154.574239) (xy 422.082383 -154.610355) (xy 422.104058 -154.631644) (xy 422.113809 -154.640955)
			(xy 422.137082 -154.65455) (xy 422.163099 -154.661592) (xy 422.190051 -154.661592) (xy 422.216068 -154.65455)
			(xy 422.239341 -154.640955) (xy 422.249092 -154.631644) (xy 422.270748 -154.610335) (xy 422.319604 -154.574222)
			(xy 422.373566 -154.546308) (xy 422.43127 -154.527299) (xy 422.491257 -154.517676) (xy 422.521634 -154.51709)
			(xy 422.548884 -154.517582) (xy 422.602827 -154.525342) (xy 422.655118 -154.5407) (xy 422.70469 -154.563343)
			(xy 422.750536 -154.592811) (xy 422.791722 -154.628502) (xy 422.82741 -154.669691) (xy 422.856873 -154.71554)
			(xy 422.879511 -154.765114) (xy 422.894865 -154.817406) (xy 422.90262 -154.87135) (xy 422.90262 -154.92585)
			(xy 422.894865 -154.979794) (xy 422.879511 -155.032086) (xy 422.856873 -155.08166) (xy 422.82741 -155.127509)
			(xy 422.791722 -155.168698) (xy 422.750536 -155.204389) (xy 422.70469 -155.233857) (xy 422.655118 -155.2565)
			(xy 422.602827 -155.271858) (xy 422.548884 -155.279618) (xy 422.521634 -155.280106) (xy 422.491257 -155.279554)
			(xy 422.431272 -155.269915) (xy 422.373572 -155.250893) (xy 422.319615 -155.222967) (xy 422.270766 -155.186844)
			(xy 422.249092 -155.165552) (xy 422.239364 -155.156194) (xy 422.216103 -155.142518) (xy 422.190067 -155.135431)
			(xy 422.163083 -155.135431) (xy 422.137047 -155.142518) (xy 422.113786 -155.156194) (xy 422.104058 -155.165552)
			(xy 422.082379 -155.186837) (xy 422.033529 -155.222953) (xy 421.979573 -155.250871) (xy 421.921874 -155.269886)
			(xy 421.861891 -155.279516) (xy 421.831516 -155.280106) (xy 421.804262 -155.279648) (xy 421.750309 -155.271893)
			(xy 421.698009 -155.256538) (xy 421.648427 -155.233896) (xy 421.602572 -155.204428) (xy 421.561377 -155.168735)
			(xy 421.525681 -155.127541) (xy 421.496212 -155.081687) (xy 421.473568 -155.032106) (xy 421.458211 -154.979806)
			(xy 421.450453 -154.925854) (xy 421.112505 -154.925854) (xy 421.131719 -154.941844) (xy 421.168936 -154.983381)
			(xy 421.199709 -155.029894) (xy 421.223381 -155.080391) (xy 421.239449 -155.133798) (xy 421.247569 -155.188974)
			(xy 421.248078 -155.21686) (xy 421.247569 -155.244746) (xy 421.239449 -155.299922) (xy 421.223381 -155.353329)
			(xy 421.199709 -155.403826) (xy 421.168936 -155.450339) (xy 421.131719 -155.491876) (xy 421.088851 -155.527551)
			(xy 421.041245 -155.556605) (xy 420.989916 -155.578417) (xy 420.935959 -155.592523) (xy 420.880522 -155.598623)
			(xy 420.824788 -155.596586) (xy 420.769945 -155.586456) (xy 420.717161 -155.568449) (xy 420.667561 -155.542948)
			(xy 420.622203 -155.510497) (xy 420.582054 -155.471788) (xy 420.547968 -155.427645) (xy 420.520672 -155.37901)
			(xy 420.500749 -155.326919) (xy 420.488623 -155.272482) (xy 420.484552 -155.21686) (xy 418.162419 -155.21686)
			(xy 418.171349 -155.224292) (xy 418.208566 -155.265829) (xy 418.239339 -155.312342) (xy 418.263011 -155.362839)
			(xy 418.279079 -155.416246) (xy 418.287199 -155.471422) (xy 418.287708 -155.499308) (xy 418.287199 -155.527194)
			(xy 418.279079 -155.58237) (xy 418.263011 -155.635777) (xy 418.239339 -155.686274) (xy 418.208566 -155.732787)
			(xy 418.171349 -155.774324) (xy 418.128481 -155.809999) (xy 418.080875 -155.839053) (xy 418.029546 -155.860865)
			(xy 417.975589 -155.874971) (xy 417.920152 -155.881071) (xy 417.864418 -155.879034) (xy 417.809575 -155.868904)
			(xy 417.756791 -155.850897) (xy 417.707191 -155.825396) (xy 417.661833 -155.792945) (xy 417.621684 -155.754236)
			(xy 417.587598 -155.710093) (xy 417.560302 -155.661458) (xy 417.540379 -155.609367) (xy 417.528253 -155.55493)
			(xy 417.524182 -155.499308) (xy 410.131006 -155.499308) (xy 410.131006 -157.648148) (xy 419.536372 -157.648148)
			(xy 419.536876 -157.621175) (xy 419.544457 -157.567765) (xy 419.559489 -157.515956) (xy 419.581671 -157.466782)
			(xy 419.610561 -157.421225) (xy 419.645583 -157.380193) (xy 419.686037 -157.344506) (xy 419.731116 -157.314876)
			(xy 419.75532 -157.302962) (xy 419.763448 -157.299152) (xy 421.398446 -155.664154) (xy 421.418623 -155.644767)
			(xy 421.463882 -155.61187) (xy 421.513725 -155.586449) (xy 421.566929 -155.569129) (xy 421.622185 -155.560334)
			(xy 421.65016 -155.55976) (xy 422.831006 -155.55976) (xy 423.173652 -155.217114) (xy 423.173652 -153.993088)
			(xy 423.174157 -153.965106) (xy 423.182934 -153.909835) (xy 423.200253 -153.856618) (xy 423.225689 -153.806769)
			(xy 423.258613 -153.761514) (xy 423.278046 -153.741374) (xy 423.633392 -153.386028) (xy 423.637202 -153.3779)
			(xy 423.649097 -153.353687) (xy 423.678739 -153.308614) (xy 423.714434 -153.268164) (xy 423.755469 -153.233143)
			(xy 423.801026 -153.20425) (xy 423.850198 -153.182061) (xy 423.902005 -153.167017) (xy 423.955414 -153.159419)
			(xy 423.982388 -153.158952) (xy 424.009637 -153.159489) (xy 424.063581 -153.167243) (xy 424.115872 -153.182595)
			(xy 424.165447 -153.205232) (xy 424.211295 -153.234693) (xy 424.252484 -153.270379) (xy 424.288176 -153.311563)
			(xy 424.317644 -153.357408) (xy 424.340287 -153.406979) (xy 424.355646 -153.459268) (xy 424.363407 -153.513211)
			(xy 424.363896 -153.54046) (xy 424.363417 -153.567434) (xy 424.355834 -153.620846) (xy 424.3408 -153.672656)
			(xy 424.318615 -153.721831) (xy 424.289721 -153.767389) (xy 424.254695 -153.80842) (xy 424.214237 -153.844106)
			(xy 424.169154 -153.873734) (xy 424.144948 -153.885646) (xy 424.13682 -153.889456) (xy 423.885868 -154.140662)
			(xy 423.885868 -155.364688) (xy 423.885413 -155.389927) (xy 423.878277 -155.4399) (xy 423.871644 -155.464256)
			(xy 423.868062 -155.478145) (xy 423.868029 -155.506818) (xy 423.875964 -155.534371) (xy 423.891243 -155.558634)
			(xy 423.912662 -155.577696) (xy 423.938535 -155.590055) (xy 423.966823 -155.594738) (xy 423.981118 -155.593542)
			(xy 423.992503 -155.592239) (xy 424.015379 -155.590839) (xy 424.026838 -155.590748) (xy 424.054084 -155.591325)
			(xy 424.108022 -155.599085) (xy 424.160306 -155.614441) (xy 424.209872 -155.637082) (xy 424.255713 -155.666546)
			(xy 424.296894 -155.702233) (xy 424.332577 -155.743418) (xy 424.362036 -155.789261) (xy 424.384672 -155.83883)
			(xy 424.400023 -155.891116) (xy 424.407778 -155.945054) (xy 424.407778 -155.999546) (xy 424.400023 -156.053484)
			(xy 424.384672 -156.10577) (xy 424.362036 -156.155339) (xy 424.332577 -156.201182) (xy 424.296894 -156.242367)
			(xy 424.255713 -156.278054) (xy 424.209872 -156.307518) (xy 424.160306 -156.330159) (xy 424.108022 -156.345515)
			(xy 424.054084 -156.353275) (xy 424.026838 -156.353764) (xy 423.997838 -156.353224) (xy 423.940504 -156.344449)
			(xy 423.88516 -156.327095) (xy 423.833081 -156.301564) (xy 423.785467 -156.268442) (xy 423.743417 -156.228494)
			(xy 423.707898 -156.182641) (xy 423.679731 -156.131939) (xy 423.659564 -156.077557) (xy 423.647862 -156.020749)
			(xy 423.645838 -155.991814) (xy 423.64469 -155.977184) (xy 423.634923 -155.949518) (xy 423.617693 -155.925771)
			(xy 423.594423 -155.907902) (xy 423.567033 -155.897386) (xy 423.537783 -155.89509) (xy 423.509088 -155.901205)
			(xy 423.483315 -155.915225) (xy 423.47261 -155.925266) (xy 423.230294 -156.167582) (xy 423.210149 -156.187004)
			(xy 423.164881 -156.219894) (xy 423.115029 -156.245308) (xy 423.061819 -156.262621) (xy 423.006557 -156.271407)
			(xy 422.97858 -156.271976) (xy 421.797734 -156.271976) (xy 421.109534 -156.960062) (xy 422.378122 -156.960062)
			(xy 422.382193 -156.90444) (xy 422.394319 -156.850003) (xy 422.414242 -156.797912) (xy 422.441538 -156.749277)
			(xy 422.475624 -156.705134) (xy 422.515773 -156.666425) (xy 422.561131 -156.633974) (xy 422.610731 -156.608473)
			(xy 422.663515 -156.590466) (xy 422.718358 -156.580336) (xy 422.774092 -156.578299) (xy 422.829529 -156.584399)
			(xy 422.883486 -156.598505) (xy 422.934815 -156.620317) (xy 422.982421 -156.649371) (xy 423.025289 -156.685046)
			(xy 423.062506 -156.726583) (xy 423.093279 -156.773096) (xy 423.116951 -156.823593) (xy 423.133019 -156.877)
			(xy 423.133431 -156.879798) (xy 423.523662 -156.879798) (xy 423.527733 -156.824176) (xy 423.539859 -156.769739)
			(xy 423.559782 -156.717648) (xy 423.587078 -156.669013) (xy 423.621164 -156.62487) (xy 423.661313 -156.586161)
			(xy 423.706671 -156.55371) (xy 423.756271 -156.528209) (xy 423.809055 -156.510202) (xy 423.863898 -156.500072)
			(xy 423.919632 -156.498035) (xy 423.975069 -156.504135) (xy 424.029026 -156.518241) (xy 424.080355 -156.540053)
			(xy 424.127961 -156.569107) (xy 424.170829 -156.604782) (xy 424.208046 -156.646319) (xy 424.238819 -156.692832)
			(xy 424.262491 -156.743329) (xy 424.278559 -156.796736) (xy 424.286679 -156.851912) (xy 424.287188 -156.879798)
			(xy 424.286679 -156.907684) (xy 424.278559 -156.96286) (xy 424.262491 -157.016267) (xy 424.238819 -157.066764)
			(xy 424.208046 -157.113277) (xy 424.170829 -157.154814) (xy 424.127961 -157.190489) (xy 424.080355 -157.219543)
			(xy 424.029026 -157.241355) (xy 423.975069 -157.255461) (xy 423.919632 -157.261561) (xy 423.863898 -157.259524)
			(xy 423.809055 -157.249394) (xy 423.756271 -157.231387) (xy 423.706671 -157.205886) (xy 423.661313 -157.173435)
			(xy 423.621164 -157.134726) (xy 423.587078 -157.090583) (xy 423.559782 -157.041948) (xy 423.539859 -156.989857)
			(xy 423.527733 -156.93542) (xy 423.523662 -156.879798) (xy 423.133431 -156.879798) (xy 423.141139 -156.932176)
			(xy 423.141648 -156.960062) (xy 423.141139 -156.987948) (xy 423.133019 -157.043124) (xy 423.116951 -157.096531)
			(xy 423.093279 -157.147028) (xy 423.062506 -157.193541) (xy 423.025289 -157.235078) (xy 422.982421 -157.270753)
			(xy 422.934815 -157.299807) (xy 422.883486 -157.321619) (xy 422.829529 -157.335725) (xy 422.774092 -157.341825)
			(xy 422.718358 -157.339788) (xy 422.663515 -157.329658) (xy 422.610731 -157.311651) (xy 422.561131 -157.28615)
			(xy 422.515773 -157.253699) (xy 422.475624 -157.21499) (xy 422.441538 -157.170847) (xy 422.414242 -157.122212)
			(xy 422.394319 -157.070121) (xy 422.382193 -157.015684) (xy 422.378122 -156.960062) (xy 421.109534 -156.960062)
			(xy 420.266876 -157.80258) (xy 420.263066 -157.810708) (xy 420.251122 -157.834896) (xy 420.221486 -157.879967)
			(xy 420.185798 -157.920417) (xy 420.14477 -157.955438) (xy 420.09922 -157.984334) (xy 420.050055 -158.006528)
			(xy 419.998254 -158.021578) (xy 419.944851 -158.029185) (xy 419.91788 -158.029656) (xy 419.89063 -158.029141)
			(xy 419.836686 -158.021383) (xy 419.784395 -158.006028) (xy 419.734821 -157.983388) (xy 419.688973 -157.953924)
			(xy 419.647784 -157.918236) (xy 419.612093 -157.87705) (xy 419.582626 -157.831204) (xy 419.559982 -157.781631)
			(xy 419.544623 -157.729341) (xy 419.536861 -157.675398) (xy 419.536372 -157.648148) (xy 410.131006 -157.648148)
			(xy 410.131006 -161.520378) (xy 417.4998 -161.520378) (xy 417.500317 -161.493048) (xy 417.50828 -161.438971)
			(xy 417.524061 -161.386638) (xy 417.547322 -161.337175) (xy 417.577563 -161.291642) (xy 417.614133 -161.251018)
			(xy 417.656249 -161.216176) (xy 417.679378 -161.201608) (xy 417.691578 -161.19365) (xy 417.711251 -161.172189)
			(xy 417.724061 -161.146045) (xy 417.728962 -161.117347) (xy 417.725556 -161.088434) (xy 417.720272 -161.074862)
			(xy 417.710777 -161.051654) (xy 417.697428 -161.00332) (xy 417.690702 -160.95363) (xy 417.6903 -160.928558)
			(xy 417.690724 -160.903489) (xy 417.697474 -160.853806) (xy 417.710806 -160.805471) (xy 417.720272 -160.782254)
			(xy 417.725563 -160.768687) (xy 417.728937 -160.739773) (xy 417.724027 -160.711079) (xy 417.711231 -160.68493)
			(xy 417.691587 -160.663447) (xy 417.679378 -160.655508) (xy 417.656281 -160.640887) (xy 417.61416 -160.60605)
			(xy 417.57758 -160.565433) (xy 417.547327 -160.519907) (xy 417.52405 -160.470451) (xy 417.508247 -160.418124)
			(xy 417.500259 -160.36405) (xy 417.500256 -160.309389) (xy 417.508238 -160.255314) (xy 417.524036 -160.202986)
			(xy 417.547308 -160.153527) (xy 417.577556 -160.107998) (xy 417.614131 -160.067377) (xy 417.656249 -160.032536)
			(xy 417.679378 -160.017968) (xy 417.691605 -160.010048) (xy 417.711279 -159.988577) (xy 417.724084 -159.962423)
			(xy 417.728979 -159.933716) (xy 417.725563 -159.904796) (xy 417.720272 -159.891222) (xy 417.710796 -159.868007)
			(xy 417.69744 -159.819677) (xy 417.690706 -159.769989) (xy 417.6903 -159.744918) (xy 417.690766 -159.718075)
			(xy 417.698468 -159.664945) (xy 417.713716 -159.61347) (xy 417.736193 -159.564717) (xy 417.765435 -159.519694)
			(xy 417.800836 -159.479334) (xy 417.841662 -159.444472) (xy 417.887069 -159.415831) (xy 417.936117 -159.394002)
			(xy 417.961826 -159.38627) (xy 417.976329 -159.38162) (xy 418.0019 -159.365103) (xy 418.021469 -159.341785)
			(xy 418.033299 -159.313737) (xy 418.03634 -159.283448) (xy 418.030322 -159.253608) (xy 418.023548 -159.239966)
			(xy 418.00892 -159.211818) (xy 417.988191 -159.151868) (xy 417.977691 -159.08931) (xy 417.977066 -159.057594)
			(xy 417.977291 -159.039575) (xy 417.980722 -159.0037) (xy 417.983924 -158.985966) (xy 417.986322 -158.970764)
			(xy 417.982784 -158.940201) (xy 417.97031 -158.912077) (xy 417.95003 -158.888941) (xy 417.923782 -158.872889)
			(xy 417.908994 -158.868618) (xy 417.881967 -158.861164) (xy 417.830242 -158.839542) (xy 417.782237 -158.810585)
			(xy 417.738984 -158.774917) (xy 417.701416 -158.733305) (xy 417.670339 -158.686645) (xy 417.646423 -158.63594)
			(xy 417.630183 -158.582282) (xy 417.621967 -158.526825) (xy 417.621466 -158.498794) (xy 417.621972 -158.471544)
			(xy 417.629729 -158.417598) (xy 417.645083 -158.365305) (xy 417.667723 -158.31573) (xy 417.697188 -158.269881)
			(xy 417.732877 -158.228691) (xy 417.774065 -158.193) (xy 417.819912 -158.163533) (xy 417.869487 -158.14089)
			(xy 417.921779 -158.125533) (xy 417.975724 -158.117774) (xy 418.002974 -158.117286) (xy 418.030548 -158.117774)
			(xy 418.085119 -158.125723) (xy 418.137979 -158.141444) (xy 418.188024 -158.16461) (xy 418.234215 -158.194738)
			(xy 418.275587 -158.231201) (xy 418.293804 -158.251906) (xy 418.303702 -158.262804) (xy 418.328352 -158.278879)
			(xy 418.35656 -158.287263) (xy 418.385988 -158.287263) (xy 418.414196 -158.278879) (xy 418.438846 -158.262804)
			(xy 418.448744 -158.251906) (xy 418.466959 -158.2312) (xy 418.50833 -158.194735) (xy 418.55452 -158.164608)
			(xy 418.604567 -158.141445) (xy 418.657428 -158.125729) (xy 418.712 -158.117789) (xy 418.767148 -158.117789)
			(xy 418.82172 -158.125729) (xy 418.874581 -158.141445) (xy 418.924628 -158.164608) (xy 418.970818 -158.194735)
			(xy 419.012189 -158.2312) (xy 419.030404 -158.251906) (xy 419.040302 -158.262804) (xy 419.064952 -158.278879)
			(xy 419.09316 -158.287263) (xy 419.122588 -158.287263) (xy 419.150796 -158.278879) (xy 419.175446 -158.262804)
			(xy 419.185344 -158.251906) (xy 419.203582 -158.23122) (xy 419.244945 -158.194747) (xy 419.291129 -158.164612)
			(xy 419.341172 -158.141442) (xy 419.39403 -158.12572) (xy 419.448601 -158.117775) (xy 419.476174 -158.117286)
			(xy 419.503426 -158.117779) (xy 419.557375 -158.125533) (xy 419.609672 -158.140885) (xy 419.659252 -158.163524)
			(xy 419.705105 -158.192989) (xy 419.746298 -158.22868) (xy 419.781992 -158.269869) (xy 419.81146 -158.31572)
			(xy 419.834104 -158.365298) (xy 419.84946 -158.417593) (xy 419.857218 -158.471542) (xy 419.857682 -158.498794)
			(xy 419.857167 -158.52665) (xy 419.849043 -158.581766) (xy 419.832998 -158.635117) (xy 419.80937 -158.685571)
			(xy 419.778663 -158.732056) (xy 419.741526 -158.773585) (xy 419.69875 -158.809278) (xy 419.651241 -158.838376)
			(xy 419.600008 -158.860262) (xy 419.573202 -158.867856) (xy 419.559077 -158.872105) (xy 419.53393 -158.887501)
			(xy 419.514215 -158.909425) (xy 419.501566 -158.93606) (xy 419.497034 -158.965195) (xy 419.498526 -158.97987)
			(xy 419.5002 -158.992886) (xy 419.501977 -159.019071) (xy 419.502082 -159.032194) (xy 419.501988 -159.046343)
			(xy 419.499954 -159.074566) (xy 419.498018 -159.088582) (xy 419.496394 -159.101927) (xy 419.4995 -159.128623)
			(xy 419.509476 -159.153579) (xy 419.525629 -159.17506) (xy 419.546835 -159.191572) (xy 419.57162 -159.201966)
			(xy 419.584886 -159.204152) (xy 419.612039 -159.208237) (xy 419.664868 -159.223214) (xy 419.715004 -159.245609)
			(xy 419.761412 -159.274958) (xy 419.803135 -159.310656) (xy 419.839311 -159.351965) (xy 419.869192 -159.398033)
			(xy 419.892162 -159.447908) (xy 419.907746 -159.500561) (xy 419.915622 -159.554903) (xy 419.916102 -159.582358)
			(xy 419.915606 -159.60961) (xy 419.907854 -159.66356) (xy 419.892503 -159.715858) (xy 419.869865 -159.765438)
			(xy 419.840401 -159.811292) (xy 419.804711 -159.852485) (xy 419.763521 -159.888179) (xy 419.71767 -159.917648)
			(xy 419.668092 -159.940291) (xy 419.615795 -159.955647) (xy 419.561846 -159.963403) (xy 419.534594 -159.963866)
			(xy 419.507019 -159.963416) (xy 419.452445 -159.955462) (xy 419.399584 -159.939735) (xy 419.349538 -159.916562)
			(xy 419.303349 -159.886426) (xy 419.261979 -159.849955) (xy 419.243764 -159.829246) (xy 419.233866 -159.818348)
			(xy 419.209216 -159.802273) (xy 419.181008 -159.793889) (xy 419.15158 -159.793889) (xy 419.123372 -159.802273)
			(xy 419.098722 -159.818348) (xy 419.088824 -159.829246) (xy 419.070614 -159.849958) (xy 419.029244 -159.886426)
			(xy 418.983053 -159.916557) (xy 418.933005 -159.939722) (xy 418.880143 -159.955439) (xy 418.825569 -159.96338)
			(xy 418.797994 -159.963866) (xy 418.771493 -159.963405) (xy 418.719002 -159.956063) (xy 418.668034 -159.941521)
			(xy 418.619572 -159.920059) (xy 418.574549 -159.892091) (xy 418.5539 -159.875474) (xy 418.541717 -159.866082)
			(xy 418.51333 -159.854285) (xy 418.482719 -159.851451) (xy 418.452648 -159.857838) (xy 418.425831 -159.872868)
			(xy 418.404689 -159.895186) (xy 418.397436 -159.908748) (xy 418.385321 -159.93243) (xy 418.355402 -159.976413)
			(xy 418.319535 -160.015696) (xy 418.278448 -160.049482) (xy 418.255958 -160.063688) (xy 418.243751 -160.071635)
			(xy 418.224085 -160.093102) (xy 418.211281 -160.119249) (xy 418.206381 -160.147947) (xy 418.209783 -160.176861)
			(xy 418.215064 -160.190434) (xy 418.22456 -160.213641) (xy 418.237908 -160.261976) (xy 418.244633 -160.311666)
			(xy 418.245036 -160.336738) (xy 418.244615 -160.361807) (xy 418.237865 -160.411491) (xy 418.224531 -160.459825)
			(xy 418.215064 -160.483042) (xy 418.209854 -160.496631) (xy 418.206485 -160.525525) (xy 418.211389 -160.554198)
			(xy 418.224168 -160.58033) (xy 418.243789 -160.601805) (xy 418.255958 -160.609788) (xy 418.27905 -160.624416)
			(xy 418.321167 -160.659255) (xy 418.357742 -160.699872) (xy 418.387993 -160.745397) (xy 418.411268 -160.794852)
			(xy 418.427069 -160.847177) (xy 418.435057 -160.901249) (xy 418.43506 -160.955908) (xy 418.427078 -161.00998)
			(xy 418.411283 -161.062307) (xy 418.388014 -161.111765) (xy 418.357769 -161.157294) (xy 418.321198 -161.197915)
			(xy 418.279085 -161.232759) (xy 418.255958 -161.247328) (xy 418.243724 -161.255237) (xy 418.224058 -161.276714)
			(xy 418.211257 -161.302871) (xy 418.206364 -161.331578) (xy 418.209777 -161.360499) (xy 418.215064 -161.374074)
			(xy 418.224541 -161.397289) (xy 418.237896 -161.445619) (xy 418.244629 -161.495307) (xy 418.245036 -161.520378)
			(xy 418.244515 -161.548263) (xy 418.236203 -161.60341) (xy 418.219765 -161.656702) (xy 418.195567 -161.706948)
			(xy 418.164151 -161.753027) (xy 418.126218 -161.793909) (xy 418.082616 -161.828681) (xy 418.034318 -161.856566)
			(xy 417.982403 -161.876941) (xy 417.928032 -161.889351) (xy 417.872418 -161.893519) (xy 417.816804 -161.889351)
			(xy 417.762433 -161.876941) (xy 417.710518 -161.856566) (xy 417.66222 -161.828681) (xy 417.618618 -161.793909)
			(xy 417.580685 -161.753027) (xy 417.549269 -161.706948) (xy 417.525071 -161.656702) (xy 417.508633 -161.60341)
			(xy 417.500321 -161.548263) (xy 417.4998 -161.520378) (xy 410.131006 -161.520378) (xy 410.131006 -163.719764)
			(xy 412.827724 -163.719764) (xy 412.852676 -163.720247) (xy 412.901967 -163.728042) (xy 412.949432 -163.743452)
			(xy 412.993902 -163.766096) (xy 413.034282 -163.795419) (xy 413.05226 -163.812728) (xy 413.429782 -164.19025)
			(xy 419.374572 -164.19025) (xy 419.374572 -164.13575) (xy 419.382328 -164.081803) (xy 419.397682 -164.02951)
			(xy 419.420321 -163.979933) (xy 419.449786 -163.934084) (xy 419.485475 -163.892893) (xy 419.526663 -163.857201)
			(xy 419.572511 -163.827734) (xy 419.622085 -163.805091) (xy 419.674378 -163.789733) (xy 419.728324 -163.781974)
			(xy 419.755574 -163.781486) (xy 419.785261 -163.782065) (xy 419.843919 -163.79126) (xy 419.900444 -163.809431)
			(xy 419.953471 -163.836139) (xy 420.001721 -163.870741) (xy 420.044027 -163.912399) (xy 420.062152 -163.935918)
			(xy 420.070578 -163.946525) (xy 420.091891 -163.963232) (xy 420.116845 -163.973751) (xy 420.143686 -163.977341)
			(xy 420.170527 -163.973751) (xy 420.195481 -163.963232) (xy 420.216794 -163.946525) (xy 420.22522 -163.935918)
			(xy 420.243349 -163.912402) (xy 420.285654 -163.870741) (xy 420.333902 -163.836136) (xy 420.386928 -163.809424)
			(xy 420.443453 -163.79125) (xy 420.502111 -163.782051) (xy 420.531798 -163.781486) (xy 420.559051 -163.781961)
			(xy 420.613001 -163.789718) (xy 420.665298 -163.805073) (xy 420.714878 -163.827715) (xy 420.76073 -163.857183)
			(xy 420.801923 -163.892876) (xy 420.837616 -163.934068) (xy 420.867084 -163.979921) (xy 420.889726 -164.0295)
			(xy 420.905082 -164.081797) (xy 420.912839 -164.135747) (xy 420.912839 -164.190253) (xy 420.905082 -164.244203)
			(xy 420.889726 -164.2965) (xy 420.867084 -164.346079) (xy 420.837616 -164.391932) (xy 420.801923 -164.433124)
			(xy 420.76073 -164.468817) (xy 420.714878 -164.498285) (xy 420.665298 -164.520927) (xy 420.613001 -164.536282)
			(xy 420.559051 -164.544039) (xy 420.531798 -164.544502) (xy 420.50211 -164.543948) (xy 420.443451 -164.534749)
			(xy 420.386925 -164.516573) (xy 420.333898 -164.48986) (xy 420.285649 -164.455254) (xy 420.243344 -164.413591)
			(xy 420.22522 -164.39007) (xy 420.216794 -164.379463) (xy 420.195481 -164.362756) (xy 420.170527 -164.352237)
			(xy 420.143686 -164.348647) (xy 420.116845 -164.352237) (xy 420.091891 -164.362756) (xy 420.070578 -164.379463)
			(xy 420.062152 -164.39007) (xy 420.044036 -164.413597) (xy 420.001729 -164.455258) (xy 419.953478 -164.489861)
			(xy 419.900449 -164.516572) (xy 419.843922 -164.534744) (xy 419.785262 -164.543939) (xy 419.755574 -164.544502)
			(xy 419.728324 -164.544026) (xy 419.674378 -164.536267) (xy 419.622085 -164.520909) (xy 419.572511 -164.498266)
			(xy 419.526663 -164.468799) (xy 419.485475 -164.433107) (xy 419.449786 -164.391916) (xy 419.420321 -164.346067)
			(xy 419.397682 -164.29649) (xy 419.382328 -164.244197) (xy 419.374572 -164.19025) (xy 413.429782 -164.19025)
			(xy 413.879792 -164.64026) (xy 417.911534 -164.64026) (xy 417.936516 -164.640774) (xy 417.985861 -164.648629)
			(xy 418.033373 -164.664095) (xy 418.077886 -164.686792) (xy 418.118308 -164.716163) (xy 418.136324 -164.733478)
			(xy 418.215064 -164.812472) (xy 418.390578 -164.987986) (xy 418.401234 -164.996912) (xy 418.426153 -165.009201)
			(xy 418.453463 -165.014311) (xy 418.48114 -165.011865) (xy 418.50713 -165.002042) (xy 418.529506 -164.985572)
			(xy 418.54661 -164.963676) (xy 418.557173 -164.937978) (xy 418.559234 -164.924232) (xy 418.563013 -164.896761)
			(xy 418.577481 -164.843232) (xy 418.599539 -164.792357) (xy 418.628724 -164.745208) (xy 418.66442 -164.702777)
			(xy 418.705879 -164.665954) (xy 418.752228 -164.635515) (xy 418.802492 -164.612099) (xy 418.855614 -164.5962)
			(xy 418.910477 -164.588152) (xy 418.938202 -164.587682) (xy 418.965315 -164.588158) (xy 419.018995 -164.595836)
			(xy 419.071046 -164.611038) (xy 419.120421 -164.633457) (xy 419.166124 -164.662641) (xy 419.207235 -164.698002)
			(xy 419.242924 -164.738827) (xy 419.272473 -164.784295) (xy 419.295286 -164.833489) (xy 419.310904 -164.885417)
			(xy 419.319013 -164.939034) (xy 419.31971 -164.966142) (xy 419.31971 -164.96919) (xy 419.319311 -164.995436)
			(xy 419.312178 -165.04744) (xy 419.305486 -165.072822) (xy 419.302585 -165.087166) (xy 419.304197 -165.116375)
			(xy 419.314025 -165.143928) (xy 419.331261 -165.167564) (xy 419.354491 -165.185344) (xy 419.381809 -165.195808)
			(xy 419.410972 -165.198097) (xy 419.425374 -165.195504) (xy 419.44745 -165.190498) (xy 419.492402 -165.185151)
			(xy 419.515036 -165.184836) (xy 419.520624 -165.184836) (xy 419.547626 -165.185682) (xy 419.600996 -165.194048)
			(xy 419.652653 -165.20986) (xy 419.701562 -165.232801) (xy 419.746746 -165.262411) (xy 419.7873 -165.2981)
			(xy 419.822415 -165.339153) (xy 419.851387 -165.384749) (xy 419.873638 -165.433976) (xy 419.888721 -165.48585)
			(xy 419.896336 -165.539333) (xy 419.896798 -165.566344) (xy 419.896323 -165.593397) (xy 419.888672 -165.646959)
			(xy 419.873531 -165.698902) (xy 419.851202 -165.748186) (xy 419.822134 -165.79382) (xy 419.78691 -165.83489)
			(xy 419.746237 -165.87057) (xy 419.700931 -165.900147) (xy 419.651901 -165.923025) (xy 419.600129 -165.938747)
			(xy 419.573456 -165.94328) (xy 419.564883 -165.948269) (xy 419.547217 -165.957292) (xy 419.53815 -165.961314)
			(xy 419.524434 -165.966902) (xy 419.52164 -165.967918) (xy 419.509643 -165.972214) (xy 419.485102 -165.979082)
			(xy 419.472618 -165.981634) (xy 419.455854 -165.984936) (xy 419.437566 -165.98646) (xy 419.41242 -165.987476)
			(xy 418.622226 -165.987476) (xy 418.597245 -165.986959) (xy 418.547903 -165.979099) (xy 418.500394 -165.96363)
			(xy 418.455883 -165.940931) (xy 418.415463 -165.91156) (xy 418.397436 -165.894258) (xy 417.779708 -165.276276)
			(xy 413.747966 -165.276276) (xy 413.722983 -165.275762) (xy 413.673638 -165.267907) (xy 413.626125 -165.252443)
			(xy 413.58161 -165.229748) (xy 413.541186 -165.200379) (xy 413.523176 -165.183058) (xy 413.262318 -164.921946)
			(xy 413.00908 -164.668708) (xy 412.695898 -164.355272) (xy 410.131006 -164.355272) (xy 410.131006 -165.787957)
			(xy 416.453709 -165.787957) (xy 416.453709 -165.733443) (xy 416.461468 -165.679483) (xy 416.476827 -165.627176)
			(xy 416.499474 -165.577588) (xy 416.528948 -165.531728) (xy 416.56465 -165.49053) (xy 416.605851 -165.454832)
			(xy 416.651713 -165.425361) (xy 416.701302 -165.402717) (xy 416.75361 -165.387362) (xy 416.807571 -165.379607)
			(xy 416.834828 -165.379146) (xy 416.862199 -165.379584) (xy 416.91638 -165.387407) (xy 416.968884 -165.402902)
			(xy 417.01863 -165.42575) (xy 417.064596 -165.455481) (xy 417.085526 -165.473126) (xy 417.096854 -165.482362)
			(xy 417.123411 -165.494538) (xy 417.152328 -165.498711) (xy 417.181245 -165.494538) (xy 417.207802 -165.482362)
			(xy 417.21913 -165.473126) (xy 417.240081 -165.45551) (xy 417.286048 -165.425794) (xy 417.335791 -165.402953)
			(xy 417.388287 -165.387457) (xy 417.44246 -165.379623) (xy 417.469828 -165.379146) (xy 417.497075 -165.379726)
			(xy 417.551013 -165.387485) (xy 417.603298 -165.402841) (xy 417.652865 -165.425481) (xy 417.698707 -165.454944)
			(xy 417.739889 -165.490631) (xy 417.775573 -165.531816) (xy 417.805033 -165.577659) (xy 417.827669 -165.627228)
			(xy 417.843021 -165.679515) (xy 417.850776 -165.733453) (xy 417.850776 -165.787947) (xy 417.843021 -165.841885)
			(xy 417.827669 -165.894172) (xy 417.805033 -165.943741) (xy 417.775573 -165.989584) (xy 417.739889 -166.030769)
			(xy 417.698707 -166.066456) (xy 417.652865 -166.095919) (xy 417.603298 -166.118559) (xy 417.551013 -166.133915)
			(xy 417.497075 -166.141674) (xy 417.469828 -166.142162) (xy 417.442458 -166.141689) (xy 417.388279 -166.133874)
			(xy 417.335775 -166.118387) (xy 417.286028 -166.095547) (xy 417.240062 -166.065823) (xy 417.21913 -166.048182)
			(xy 417.207802 -166.038946) (xy 417.181245 -166.02677) (xy 417.152328 -166.022597) (xy 417.123411 -166.02677)
			(xy 417.096854 -166.038946) (xy 417.085526 -166.048182) (xy 417.064593 -166.06582) (xy 417.01862 -166.095532)
			(xy 416.968873 -166.118369) (xy 416.916373 -166.13386) (xy 416.862197 -166.141688) (xy 416.834828 -166.142162)
			(xy 416.807571 -166.141793) (xy 416.75361 -166.134038) (xy 416.701302 -166.118683) (xy 416.651713 -166.096039)
			(xy 416.605851 -166.066568) (xy 416.56465 -166.03087) (xy 416.528948 -165.989672) (xy 416.499474 -165.943812)
			(xy 416.476827 -165.894224) (xy 416.461468 -165.841917) (xy 416.453709 -165.787957) (xy 410.131006 -165.787957)
			(xy 410.131006 -170.156378) (xy 417.4998 -170.156378) (xy 417.500317 -170.129048) (xy 417.50828 -170.074971)
			(xy 417.524061 -170.022638) (xy 417.547322 -169.973175) (xy 417.577563 -169.927642) (xy 417.614133 -169.887018)
			(xy 417.656249 -169.852176) (xy 417.679378 -169.837608) (xy 417.691578 -169.82965) (xy 417.711251 -169.808189)
			(xy 417.724061 -169.782045) (xy 417.728962 -169.753347) (xy 417.725556 -169.724434) (xy 417.720272 -169.710862)
			(xy 417.710777 -169.687654) (xy 417.697428 -169.63932) (xy 417.690702 -169.58963) (xy 417.6903 -169.564558)
			(xy 417.690724 -169.539489) (xy 417.697474 -169.489806) (xy 417.710806 -169.441471) (xy 417.720272 -169.418254)
			(xy 417.725563 -169.404687) (xy 417.728937 -169.375773) (xy 417.724027 -169.347079) (xy 417.711231 -169.32093)
			(xy 417.691587 -169.299447) (xy 417.679378 -169.291508) (xy 417.656281 -169.276887) (xy 417.61416 -169.24205)
			(xy 417.57758 -169.201433) (xy 417.547327 -169.155907) (xy 417.52405 -169.106451) (xy 417.508247 -169.054124)
			(xy 417.500259 -169.00005) (xy 417.500256 -168.945389) (xy 417.508238 -168.891314) (xy 417.524036 -168.838986)
			(xy 417.547308 -168.789527) (xy 417.577556 -168.743998) (xy 417.614131 -168.703377) (xy 417.656249 -168.668536)
			(xy 417.679378 -168.653968) (xy 417.691605 -168.646048) (xy 417.711279 -168.624577) (xy 417.724084 -168.598423)
			(xy 417.728979 -168.569716) (xy 417.725563 -168.540796) (xy 417.720272 -168.527222) (xy 417.710796 -168.504007)
			(xy 417.69744 -168.455677) (xy 417.690706 -168.405989) (xy 417.6903 -168.380918) (xy 417.690766 -168.354075)
			(xy 417.698468 -168.300945) (xy 417.713716 -168.24947) (xy 417.736193 -168.200717) (xy 417.765435 -168.155694)
			(xy 417.800836 -168.115334) (xy 417.841662 -168.080472) (xy 417.887069 -168.051831) (xy 417.936117 -168.030002)
			(xy 417.961826 -168.02227) (xy 417.976329 -168.01762) (xy 418.0019 -168.001103) (xy 418.021469 -167.977785)
			(xy 418.033299 -167.949737) (xy 418.03634 -167.919448) (xy 418.030322 -167.889608) (xy 418.023548 -167.875966)
			(xy 418.00892 -167.847818) (xy 417.988191 -167.787868) (xy 417.977691 -167.72531) (xy 417.977066 -167.693594)
			(xy 417.977291 -167.675575) (xy 417.980722 -167.6397) (xy 417.983924 -167.621966) (xy 417.986322 -167.606764)
			(xy 417.982784 -167.576201) (xy 417.97031 -167.548077) (xy 417.95003 -167.524941) (xy 417.923782 -167.508889)
			(xy 417.908994 -167.504618) (xy 417.881967 -167.497164) (xy 417.830242 -167.475542) (xy 417.782237 -167.446585)
			(xy 417.738984 -167.410917) (xy 417.701416 -167.369305) (xy 417.670339 -167.322645) (xy 417.646423 -167.27194)
			(xy 417.630183 -167.218282) (xy 417.621967 -167.162825) (xy 417.621466 -167.134794) (xy 417.621972 -167.107544)
			(xy 417.629729 -167.053598) (xy 417.645083 -167.001305) (xy 417.667723 -166.95173) (xy 417.697188 -166.905881)
			(xy 417.732877 -166.864691) (xy 417.774065 -166.829) (xy 417.819912 -166.799533) (xy 417.869487 -166.77689)
			(xy 417.921779 -166.761533) (xy 417.975724 -166.753774) (xy 418.002974 -166.753286) (xy 418.030548 -166.753774)
			(xy 418.085119 -166.761723) (xy 418.137979 -166.777444) (xy 418.188024 -166.80061) (xy 418.234215 -166.830738)
			(xy 418.275587 -166.867201) (xy 418.293804 -166.887906) (xy 418.303702 -166.898804) (xy 418.328352 -166.914879)
			(xy 418.35656 -166.923263) (xy 418.385988 -166.923263) (xy 418.414196 -166.914879) (xy 418.438846 -166.898804)
			(xy 418.448744 -166.887906) (xy 418.466959 -166.8672) (xy 418.50833 -166.830735) (xy 418.55452 -166.800608)
			(xy 418.604567 -166.777445) (xy 418.657428 -166.761729) (xy 418.712 -166.753789) (xy 418.767148 -166.753789)
			(xy 418.82172 -166.761729) (xy 418.874581 -166.777445) (xy 418.924628 -166.800608) (xy 418.970818 -166.830735)
			(xy 419.012189 -166.8672) (xy 419.030404 -166.887906) (xy 419.040302 -166.898804) (xy 419.064952 -166.914879)
			(xy 419.09316 -166.923263) (xy 419.122588 -166.923263) (xy 419.150796 -166.914879) (xy 419.175446 -166.898804)
			(xy 419.185344 -166.887906) (xy 419.203582 -166.86722) (xy 419.244945 -166.830747) (xy 419.291129 -166.800612)
			(xy 419.341172 -166.777442) (xy 419.39403 -166.76172) (xy 419.448601 -166.753775) (xy 419.476174 -166.753286)
			(xy 419.503426 -166.753779) (xy 419.557375 -166.761533) (xy 419.609672 -166.776885) (xy 419.659252 -166.799524)
			(xy 419.705105 -166.828989) (xy 419.746298 -166.86468) (xy 419.781992 -166.905869) (xy 419.81146 -166.95172)
			(xy 419.834104 -167.001298) (xy 419.84946 -167.053593) (xy 419.857218 -167.107542) (xy 419.857682 -167.134794)
			(xy 419.857167 -167.16265) (xy 419.849043 -167.217766) (xy 419.832998 -167.271117) (xy 419.80937 -167.321571)
			(xy 419.778663 -167.368056) (xy 419.741526 -167.409585) (xy 419.69875 -167.445278) (xy 419.651241 -167.474376)
			(xy 419.600008 -167.496262) (xy 419.573202 -167.503856) (xy 419.559077 -167.508105) (xy 419.53393 -167.523501)
			(xy 419.514215 -167.545425) (xy 419.501566 -167.57206) (xy 419.497034 -167.601195) (xy 419.498526 -167.61587)
			(xy 419.5002 -167.628886) (xy 419.501977 -167.655071) (xy 419.502082 -167.668194) (xy 419.501988 -167.682343)
			(xy 419.499954 -167.710566) (xy 419.498018 -167.724582) (xy 419.496394 -167.737927) (xy 419.4995 -167.764623)
			(xy 419.509476 -167.789579) (xy 419.525629 -167.81106) (xy 419.546835 -167.827572) (xy 419.57162 -167.837966)
			(xy 419.584886 -167.840152) (xy 419.612039 -167.844237) (xy 419.664868 -167.859214) (xy 419.715004 -167.881609)
			(xy 419.761412 -167.910958) (xy 419.803135 -167.946656) (xy 419.839311 -167.987965) (xy 419.869192 -168.034033)
			(xy 419.892162 -168.083908) (xy 419.907746 -168.136561) (xy 419.915622 -168.190903) (xy 419.916102 -168.218358)
			(xy 419.915606 -168.24561) (xy 419.907854 -168.29956) (xy 419.892503 -168.351858) (xy 419.869865 -168.401438)
			(xy 419.840401 -168.447292) (xy 419.804711 -168.488485) (xy 419.763521 -168.524179) (xy 419.71767 -168.553648)
			(xy 419.668092 -168.576291) (xy 419.615795 -168.591647) (xy 419.561846 -168.599403) (xy 419.534594 -168.599866)
			(xy 419.507019 -168.599416) (xy 419.452445 -168.591462) (xy 419.399584 -168.575735) (xy 419.349538 -168.552562)
			(xy 419.303349 -168.522426) (xy 419.261979 -168.485955) (xy 419.243764 -168.465246) (xy 419.233866 -168.454348)
			(xy 419.209216 -168.438273) (xy 419.181008 -168.429889) (xy 419.15158 -168.429889) (xy 419.123372 -168.438273)
			(xy 419.098722 -168.454348) (xy 419.088824 -168.465246) (xy 419.070614 -168.485958) (xy 419.029244 -168.522426)
			(xy 418.983053 -168.552557) (xy 418.933005 -168.575722) (xy 418.880143 -168.591439) (xy 418.825569 -168.59938)
			(xy 418.797994 -168.599866) (xy 418.771493 -168.599405) (xy 418.719002 -168.592063) (xy 418.668034 -168.577521)
			(xy 418.619572 -168.556059) (xy 418.574549 -168.528091) (xy 418.5539 -168.511474) (xy 418.541717 -168.502082)
			(xy 418.51333 -168.490285) (xy 418.482719 -168.487451) (xy 418.452648 -168.493838) (xy 418.425831 -168.508868)
			(xy 418.404689 -168.531186) (xy 418.397436 -168.544748) (xy 418.385321 -168.56843) (xy 418.355402 -168.612413)
			(xy 418.319535 -168.651696) (xy 418.278448 -168.685482) (xy 418.255958 -168.699688) (xy 418.243751 -168.707635)
			(xy 418.224085 -168.729102) (xy 418.211281 -168.755249) (xy 418.206381 -168.783947) (xy 418.209783 -168.812861)
			(xy 418.215064 -168.826434) (xy 418.22456 -168.849641) (xy 418.237908 -168.897976) (xy 418.244633 -168.947666)
			(xy 418.245036 -168.972738) (xy 418.244615 -168.997807) (xy 418.237865 -169.047491) (xy 418.224531 -169.095825)
			(xy 418.215064 -169.119042) (xy 418.209854 -169.132631) (xy 418.206485 -169.161525) (xy 418.211389 -169.190198)
			(xy 418.224168 -169.21633) (xy 418.243789 -169.237805) (xy 418.255958 -169.245788) (xy 418.27905 -169.260416)
			(xy 418.321167 -169.295255) (xy 418.357742 -169.335872) (xy 418.387993 -169.381397) (xy 418.411268 -169.430852)
			(xy 418.427069 -169.483177) (xy 418.435057 -169.537249) (xy 418.43506 -169.591908) (xy 418.427078 -169.64598)
			(xy 418.411283 -169.698307) (xy 418.388014 -169.747765) (xy 418.357769 -169.793294) (xy 418.321198 -169.833915)
			(xy 418.279085 -169.868759) (xy 418.255958 -169.883328) (xy 418.243724 -169.891237) (xy 418.224058 -169.912714)
			(xy 418.211257 -169.938871) (xy 418.206364 -169.967578) (xy 418.209777 -169.996499) (xy 418.215064 -170.010074)
			(xy 418.224541 -170.033289) (xy 418.237896 -170.081619) (xy 418.244629 -170.131307) (xy 418.245036 -170.156378)
			(xy 418.244515 -170.184263) (xy 418.236203 -170.23941) (xy 418.219765 -170.292702) (xy 418.195567 -170.342948)
			(xy 418.164151 -170.389027) (xy 418.126218 -170.429909) (xy 418.082616 -170.464681) (xy 418.034318 -170.492566)
			(xy 417.982403 -170.512941) (xy 417.928032 -170.525351) (xy 417.872418 -170.529519) (xy 417.816804 -170.525351)
			(xy 417.762433 -170.512941) (xy 417.710518 -170.492566) (xy 417.66222 -170.464681) (xy 417.618618 -170.429909)
			(xy 417.580685 -170.389027) (xy 417.549269 -170.342948) (xy 417.525071 -170.292702) (xy 417.508633 -170.23941)
			(xy 417.500321 -170.184263) (xy 417.4998 -170.156378) (xy 410.131006 -170.156378) (xy 410.131006 -171.087542)
			(xy 419.315646 -171.087542) (xy 419.316217 -171.060294) (xy 419.323967 -171.006352) (xy 419.339314 -170.954061)
			(xy 419.361947 -170.904487) (xy 419.391405 -170.858639) (xy 419.427087 -170.81745) (xy 419.468269 -170.781757)
			(xy 419.51411 -170.752289) (xy 419.563679 -170.729645) (xy 419.615966 -170.714285) (xy 419.669906 -170.706523)
			(xy 419.697154 -170.706034) (xy 419.697408 -170.706034) (xy 419.727247 -170.706617) (xy 419.786193 -170.715927)
			(xy 419.814756 -170.724576) (xy 419.82866 -170.72863) (xy 419.857597 -170.72954) (xy 419.885621 -170.722274)
			(xy 419.910469 -170.707418) (xy 419.930134 -170.686171) (xy 419.943028 -170.660251) (xy 419.946074 -170.64609)
			(xy 419.951209 -170.619983) (xy 419.967804 -170.56943) (xy 419.991265 -170.521674) (xy 420.021136 -170.477644)
			(xy 420.056839 -170.438193) (xy 420.097679 -170.404089) (xy 420.142863 -170.375993) (xy 420.191514 -170.354451)
			(xy 420.242688 -170.339881) (xy 420.29539 -170.332567) (xy 420.321994 -170.332146) (xy 420.34333 -170.332146)
			(xy 420.557452 -170.118024) (xy 420.557706 -170.097196) (xy 420.558467 -170.072467) (xy 420.568381 -170.024002)
			(xy 420.587482 -169.978371) (xy 420.615049 -169.937297) (xy 420.632128 -169.919396) (xy 420.886128 -169.665396)
			(xy 420.904217 -169.648133) (xy 420.945765 -169.620324) (xy 420.991938 -169.601153) (xy 421.040963 -169.591356)
			(xy 421.06596 -169.59072) (xy 422.862502 -169.59072) (xy 423.121582 -169.331894) (xy 423.122344 -169.330878)
			(xy 423.13098 -169.321988) (xy 423.257472 -169.195242) (xy 423.257472 -159.857948) (xy 423.258124 -159.832953)
			(xy 423.267921 -159.78393) (xy 423.28709 -159.737759) (xy 423.314894 -159.696212) (xy 423.332148 -159.678116)
			(xy 425.416472 -157.593538) (xy 425.416472 -154.683968) (xy 425.417074 -154.65897) (xy 425.426887 -154.609945)
			(xy 425.44607 -154.563774) (xy 425.473888 -154.52223) (xy 425.491148 -154.504136) (xy 430.491392 -149.503638)
			(xy 430.491392 -147.542758) (xy 429.77689 -146.828256) (xy 422.4274 -146.828256) (xy 422.402404 -146.827626)
			(xy 422.35338 -146.817821) (xy 422.30721 -146.798645) (xy 422.265664 -146.770836) (xy 422.247568 -146.75358)
			(xy 420.660068 -145.16608) (xy 420.642821 -145.147976) (xy 420.615006 -145.106435) (xy 420.59583 -145.060267)
			(xy 420.586029 -145.011244) (xy 420.585392 -144.986248) (xy 420.585392 -138.401298) (xy 420.477188 -138.29284)
			(xy 420.459909 -138.274765) (xy 420.432103 -138.233213) (xy 420.412937 -138.187035) (xy 420.403145 -138.138006)
			(xy 420.402512 -138.113008) (xy 420.402512 -134.569708) (xy 420.403156 -134.544712) (xy 420.412958 -134.49569)
			(xy 420.43213 -134.44952) (xy 420.459934 -134.407973) (xy 420.477188 -134.389876) (xy 421.035988 -133.831076)
			(xy 421.054091 -133.813829) (xy 421.095634 -133.786018) (xy 421.141803 -133.766843) (xy 421.190825 -133.75704)
			(xy 421.21582 -133.7564) (xy 424.11523 -133.7564) (xy 424.679872 -133.191758) (xy 424.679872 -132.705348)
			(xy 424.680524 -132.680353) (xy 424.690321 -132.63133) (xy 424.70949 -132.585159) (xy 424.737294 -132.543612)
			(xy 424.754548 -132.525516) (xy 425.287948 -131.992116) (xy 425.306032 -131.974847) (xy 425.347581 -131.947038)
			(xy 425.393755 -131.927869) (xy 425.442783 -131.918074) (xy 425.46778 -131.91744) (xy 426.95495 -131.91744)
			(xy 427.4058 -131.46659) (xy 427.4058 -131.014724) (xy 427.386174 -130.996565) (xy 427.351717 -130.955679)
			(xy 427.323305 -130.910383) (xy 427.301495 -130.861564) (xy 427.286713 -130.810179) (xy 427.279249 -130.757233)
			(xy 427.2788 -130.730498) (xy 427.279286 -130.703247) (xy 427.287042 -130.649299) (xy 427.302397 -130.597004)
			(xy 427.325039 -130.547427) (xy 427.354505 -130.501577) (xy 427.390196 -130.460386) (xy 427.431387 -130.424695)
			(xy 427.477237 -130.395229) (xy 427.526814 -130.372587) (xy 427.579109 -130.357232) (xy 427.633057 -130.349476)
			(xy 427.687559 -130.349476) (xy 427.741507 -130.357232) (xy 427.793802 -130.372587) (xy 427.843379 -130.395229)
			(xy 427.889229 -130.424695) (xy 427.93042 -130.460386) (xy 427.966111 -130.501577) (xy 427.995577 -130.547427)
			(xy 428.018219 -130.597004) (xy 428.033574 -130.649299) (xy 428.04133 -130.703247) (xy 428.041816 -130.730498)
			(xy 428.041409 -130.757234) (xy 428.033942 -130.810183) (xy 428.019153 -130.861569) (xy 427.997332 -130.910387)
			(xy 427.968908 -130.955679) (xy 427.934437 -130.996557) (xy 427.914816 -131.014724) (xy 427.914816 -131.572)
			(xy 427.914198 -131.596997) (xy 427.913762 -131.599178) (xy 428.565054 -131.599178) (xy 428.569125 -131.543556)
			(xy 428.581251 -131.489119) (xy 428.601174 -131.437028) (xy 428.62847 -131.388393) (xy 428.662556 -131.34425)
			(xy 428.702705 -131.305541) (xy 428.748063 -131.27309) (xy 428.797663 -131.247589) (xy 428.850447 -131.229582)
			(xy 428.90529 -131.219452) (xy 428.961024 -131.217415) (xy 429.016461 -131.223515) (xy 429.070418 -131.237621)
			(xy 429.121747 -131.259433) (xy 429.169353 -131.288487) (xy 429.212221 -131.324162) (xy 429.249438 -131.365699)
			(xy 429.280211 -131.412212) (xy 429.303883 -131.462709) (xy 429.319951 -131.516116) (xy 429.328071 -131.571292)
			(xy 429.32858 -131.599178) (xy 429.328071 -131.627064) (xy 429.319951 -131.68224) (xy 429.303883 -131.735647)
			(xy 429.280211 -131.786144) (xy 429.249438 -131.832657) (xy 429.212221 -131.874194) (xy 429.169353 -131.909869)
			(xy 429.121747 -131.938923) (xy 429.070418 -131.960735) (xy 429.016461 -131.974841) (xy 428.961024 -131.980941)
			(xy 428.90529 -131.978904) (xy 428.850447 -131.968774) (xy 428.797663 -131.950767) (xy 428.748063 -131.925266)
			(xy 428.702705 -131.892815) (xy 428.662556 -131.854106) (xy 428.62847 -131.809963) (xy 428.601174 -131.761328)
			(xy 428.581251 -131.709237) (xy 428.569125 -131.6548) (xy 428.565054 -131.599178) (xy 427.913762 -131.599178)
			(xy 427.904391 -131.646022) (xy 427.885212 -131.692193) (xy 427.857398 -131.733737) (xy 427.84014 -131.751832)
			(xy 427.240192 -132.35178) (xy 427.22209 -132.36903) (xy 427.180548 -132.396842) (xy 427.134379 -132.416017)
			(xy 427.085356 -132.425818) (xy 427.06036 -132.426456) (xy 425.57319 -132.426456) (xy 425.536868 -132.462778)
			(xy 431.231292 -132.462778) (xy 431.235363 -132.407156) (xy 431.247489 -132.352719) (xy 431.267412 -132.300628)
			(xy 431.294708 -132.251993) (xy 431.328794 -132.20785) (xy 431.368943 -132.169141) (xy 431.414301 -132.13669)
			(xy 431.463901 -132.111189) (xy 431.516685 -132.093182) (xy 431.571528 -132.083052) (xy 431.627262 -132.081015)
			(xy 431.682699 -132.087115) (xy 431.736656 -132.101221) (xy 431.787985 -132.123033) (xy 431.835591 -132.152087)
			(xy 431.878459 -132.187762) (xy 431.915676 -132.229299) (xy 431.946449 -132.275812) (xy 431.970121 -132.326309)
			(xy 431.986189 -132.379716) (xy 431.994309 -132.434892) (xy 431.994818 -132.462778) (xy 431.994309 -132.490664)
			(xy 431.986189 -132.54584) (xy 431.970121 -132.599247) (xy 431.946449 -132.649744) (xy 431.915676 -132.696257)
			(xy 431.878459 -132.737794) (xy 431.835591 -132.773469) (xy 431.787985 -132.802523) (xy 431.736656 -132.824335)
			(xy 431.682699 -132.838441) (xy 431.627262 -132.844541) (xy 431.571528 -132.842504) (xy 431.516685 -132.832374)
			(xy 431.463901 -132.814367) (xy 431.414301 -132.788866) (xy 431.368943 -132.756415) (xy 431.328794 -132.717706)
			(xy 431.294708 -132.673563) (xy 431.267412 -132.624928) (xy 431.247489 -132.572837) (xy 431.235363 -132.5184)
			(xy 431.231292 -132.462778) (xy 425.536868 -132.462778) (xy 425.188888 -132.810758) (xy 425.188888 -133.297168)
			(xy 425.188229 -133.322163) (xy 425.178432 -133.371184) (xy 425.159264 -133.417355) (xy 425.131464 -133.458902)
			(xy 425.114212 -133.477) (xy 424.400472 -134.19074) (xy 424.382373 -134.207992) (xy 424.34083 -134.235806)
			(xy 424.29466 -134.254981) (xy 424.245636 -134.26478) (xy 424.22064 -134.265416) (xy 421.32123 -134.265416)
			(xy 420.911528 -134.675118) (xy 420.911528 -135.146034) (xy 421.320214 -135.146034) (xy 421.3207 -135.118783)
			(xy 421.328456 -135.064835) (xy 421.343811 -135.01254) (xy 421.366453 -134.962963) (xy 421.395919 -134.917113)
			(xy 421.43161 -134.875922) (xy 421.472801 -134.840231) (xy 421.518651 -134.810765) (xy 421.568228 -134.788123)
			(xy 421.620523 -134.772768) (xy 421.674471 -134.765012) (xy 421.728973 -134.765012) (xy 421.782921 -134.772768)
			(xy 421.835216 -134.788123) (xy 421.884793 -134.810765) (xy 421.930643 -134.840231) (xy 421.971834 -134.875922)
			(xy 422.007525 -134.917113) (xy 422.036991 -134.962963) (xy 422.059633 -135.01254) (xy 422.074988 -135.064835)
			(xy 422.082744 -135.118783) (xy 422.08323 -135.146034) (xy 422.08323 -135.146542) (xy 422.082832 -135.171672)
			(xy 422.076206 -135.221494) (xy 422.063087 -135.270013) (xy 422.053766 -135.293354) (xy 422.048903 -135.306273)
			(xy 422.045481 -135.333649) (xy 422.049519 -135.360942) (xy 422.060722 -135.386154) (xy 422.07827 -135.407444)
			(xy 422.100882 -135.423252) (xy 422.126902 -135.432425) (xy 422.140634 -135.433816) (xy 422.169256 -135.436256)
			(xy 422.225356 -135.448603) (xy 422.278972 -135.469218) (xy 422.328892 -135.497637) (xy 422.373988 -135.533217)
			(xy 422.413242 -135.575154) (xy 422.445767 -135.622501) (xy 422.470828 -135.674189) (xy 422.487858 -135.729048)
			(xy 422.496474 -135.785841) (xy 422.496996 -135.814562) (xy 422.496421 -135.844475) (xy 422.487063 -135.903565)
			(xy 422.468587 -135.960466) (xy 422.441447 -136.013782) (xy 422.424352 -136.038336) (xy 422.417 -136.049244)
			(xy 422.407492 -136.073757) (xy 422.404562 -136.099886) (xy 422.408405 -136.125896) (xy 422.418765 -136.150062)
			(xy 422.434956 -136.170778) (xy 422.44518 -136.179052) (xy 422.468223 -136.197173) (xy 422.508955 -136.239328)
			(xy 422.542755 -136.287221) (xy 422.568827 -136.339723) (xy 422.586555 -136.395597) (xy 422.595522 -136.453526)
			(xy 422.596056 -136.482836) (xy 422.59557 -136.510087) (xy 422.587814 -136.564035) (xy 422.572459 -136.61633)
			(xy 422.549817 -136.665907) (xy 422.520351 -136.711757) (xy 422.48466 -136.752948) (xy 422.443469 -136.788639)
			(xy 422.397619 -136.818105) (xy 422.348042 -136.840747) (xy 422.295747 -136.856102) (xy 422.241799 -136.863858)
			(xy 422.187297 -136.863858) (xy 422.133349 -136.856102) (xy 422.081054 -136.840747) (xy 422.031477 -136.818105)
			(xy 421.985627 -136.788639) (xy 421.944436 -136.752948) (xy 421.908745 -136.711757) (xy 421.879279 -136.665907)
			(xy 421.856637 -136.61633) (xy 421.841282 -136.564035) (xy 421.833526 -136.510087) (xy 421.83304 -136.482836)
			(xy 421.833608 -136.452923) (xy 421.842966 -136.393832) (xy 421.861444 -136.33693) (xy 421.888587 -136.283615)
			(xy 421.905684 -136.259062) (xy 421.913053 -136.248163) (xy 421.922569 -136.223647) (xy 421.925501 -136.197514)
			(xy 421.921655 -136.171499) (xy 421.911287 -136.147331) (xy 421.895086 -136.126617) (xy 421.884856 -136.118346)
			(xy 421.861799 -136.100243) (xy 421.82107 -136.058082) (xy 421.787274 -136.010185) (xy 421.761205 -135.95768)
			(xy 421.74348 -135.901803) (xy 421.734514 -135.843872) (xy 421.73398 -135.814562) (xy 421.73398 -135.814054)
			(xy 421.734376 -135.788924) (xy 421.741003 -135.739102) (xy 421.754123 -135.690583) (xy 421.763444 -135.667242)
			(xy 421.768303 -135.654323) (xy 421.771724 -135.626947) (xy 421.767685 -135.599656) (xy 421.756483 -135.574444)
			(xy 421.738935 -135.553155) (xy 421.716326 -135.537346) (xy 421.690307 -135.528172) (xy 421.676576 -135.52678)
			(xy 421.647954 -135.524335) (xy 421.591854 -135.51199) (xy 421.538238 -135.491375) (xy 421.488318 -135.462958)
			(xy 421.443221 -135.427378) (xy 421.403967 -135.385441) (xy 421.371442 -135.338094) (xy 421.346381 -135.286407)
			(xy 421.329351 -135.231548) (xy 421.320736 -135.174755) (xy 421.320214 -135.146034) (xy 420.911528 -135.146034)
			(xy 420.911528 -137.724388) (xy 421.191942 -137.724388) (xy 421.196013 -137.668766) (xy 421.208139 -137.614329)
			(xy 421.228062 -137.562238) (xy 421.255358 -137.513603) (xy 421.289444 -137.46946) (xy 421.329593 -137.430751)
			(xy 421.374951 -137.3983) (xy 421.424551 -137.372799) (xy 421.477335 -137.354792) (xy 421.532178 -137.344662)
			(xy 421.587912 -137.342625) (xy 421.643349 -137.348725) (xy 421.697306 -137.362831) (xy 421.748635 -137.384643)
			(xy 421.796241 -137.413697) (xy 421.839109 -137.449372) (xy 421.876326 -137.490909) (xy 421.907099 -137.537422)
			(xy 421.930771 -137.587919) (xy 421.946839 -137.641326) (xy 421.954959 -137.696502) (xy 421.955468 -137.724388)
			(xy 421.954959 -137.752274) (xy 421.946839 -137.80745) (xy 421.930771 -137.860857) (xy 421.907099 -137.911354)
			(xy 421.876326 -137.957867) (xy 421.839109 -137.999404) (xy 421.796241 -138.035079) (xy 421.748635 -138.064133)
			(xy 421.697306 -138.085945) (xy 421.643349 -138.100051) (xy 421.587912 -138.106151) (xy 421.532178 -138.104114)
			(xy 421.477335 -138.093984) (xy 421.424551 -138.075977) (xy 421.374951 -138.050476) (xy 421.329593 -138.018025)
			(xy 421.289444 -137.979316) (xy 421.255358 -137.935173) (xy 421.228062 -137.886538) (xy 421.208139 -137.834447)
			(xy 421.196013 -137.78001) (xy 421.191942 -137.724388) (xy 420.911528 -137.724388) (xy 420.911528 -138.007598)
			(xy 421.019732 -138.116056) (xy 421.037027 -138.134119) (xy 421.064844 -138.175671) (xy 421.084018 -138.221852)
			(xy 421.093815 -138.270887) (xy 421.094408 -138.295888) (xy 421.094408 -144.880838) (xy 422.53281 -146.31924)
			(xy 429.8823 -146.31924) (xy 429.907296 -146.319871) (xy 429.956319 -146.329676) (xy 430.00249 -146.348851)
			(xy 430.044036 -146.37666) (xy 430.062132 -146.393916) (xy 430.925732 -147.257516) (xy 430.942977 -147.275622)
			(xy 430.970792 -147.317162) (xy 430.989969 -147.36333) (xy 430.999771 -147.412352) (xy 431.000408 -147.437348)
			(xy 431.000408 -149.609048) (xy 430.99976 -149.634044) (xy 430.989962 -149.683067) (xy 430.970793 -149.729238)
			(xy 430.942987 -149.770784) (xy 430.925732 -149.78888) (xy 425.925488 -154.789378) (xy 425.925488 -157.698948)
			(xy 425.924817 -157.723942) (xy 425.915023 -157.772963) (xy 425.89586 -157.819134) (xy 425.868062 -157.860682)
			(xy 425.850812 -157.87878) (xy 423.766488 -159.963358) (xy 423.766488 -169.300652) (xy 423.76582 -169.325646)
			(xy 423.756025 -169.374667) (xy 423.736861 -169.420838) (xy 423.709063 -169.462386) (xy 423.691812 -169.480484)
			(xy 423.500042 -169.672254) (xy 423.49928 -169.67327) (xy 423.490644 -169.68216) (xy 423.147744 -170.02506)
			(xy 423.12966 -170.042329) (xy 423.088112 -170.070138) (xy 423.041937 -170.089309) (xy 422.99291 -170.099103)
			(xy 422.967912 -170.099736) (xy 421.17137 -170.099736) (xy 421.066468 -170.204384) (xy 421.066214 -170.225212)
			(xy 421.065452 -170.249941) (xy 421.055538 -170.298405) (xy 421.036437 -170.344036) (xy 421.00887 -170.385111)
			(xy 420.991792 -170.403012) (xy 420.702994 -170.69181) (xy 420.702994 -170.713146) (xy 420.702536 -170.740422)
			(xy 420.694844 -170.794428) (xy 420.679537 -170.846787) (xy 420.656928 -170.896432) (xy 420.627477 -170.942349)
			(xy 420.591786 -170.983604) (xy 420.550582 -171.019353) (xy 420.504706 -171.048869) (xy 420.455093 -171.071548)
			(xy 420.402756 -171.086929) (xy 420.348761 -171.094698) (xy 420.321486 -171.095162) (xy 420.321232 -171.095162)
			(xy 420.291393 -171.094593) (xy 420.232447 -171.085273) (xy 420.203884 -171.07662) (xy 420.189967 -171.072614)
			(xy 420.161038 -171.071695) (xy 420.133019 -171.078952) (xy 420.108173 -171.093799) (xy 420.088508 -171.115036)
			(xy 420.075613 -171.140949) (xy 420.072566 -171.155106) (xy 420.06599 -171.187947) (xy 420.042863 -171.250798)
			(xy 420.026592 -171.280074) (xy 420.019587 -171.293057) (xy 420.012541 -171.321688) (xy 420.013975 -171.351137)
			(xy 420.023771 -171.378948) (xy 420.04111 -171.402795) (xy 420.064544 -171.42069) (xy 420.078154 -171.426378)
			(xy 420.104942 -171.437047) (xy 420.155182 -171.465341) (xy 420.20059 -171.500876) (xy 420.240131 -171.542842)
			(xy 420.272903 -171.590283) (xy 420.298159 -171.642117) (xy 420.315323 -171.697162) (xy 420.324005 -171.754164)
			(xy 420.324534 -171.782994) (xy 420.324048 -171.810245) (xy 420.316292 -171.864193) (xy 420.300937 -171.916488)
			(xy 420.278295 -171.966065) (xy 420.248829 -172.011915) (xy 420.213138 -172.053106) (xy 420.171947 -172.088797)
			(xy 420.126097 -172.118263) (xy 420.07652 -172.140905) (xy 420.024225 -172.15626) (xy 419.970277 -172.164016)
			(xy 419.915775 -172.164016) (xy 419.861827 -172.15626) (xy 419.809532 -172.140905) (xy 419.759955 -172.118263)
			(xy 419.714105 -172.088797) (xy 419.672914 -172.053106) (xy 419.637223 -172.011915) (xy 419.607757 -171.966065)
			(xy 419.585115 -171.916488) (xy 419.56976 -171.864193) (xy 419.562004 -171.810245) (xy 419.561518 -171.782994)
			(xy 419.561518 -171.78274) (xy 419.561938 -171.757537) (xy 419.568572 -171.70757) (xy 419.581743 -171.658915)
			(xy 419.601219 -171.612425) (xy 419.613588 -171.590462) (xy 419.620627 -171.577499) (xy 419.627653 -171.548862)
			(xy 419.626205 -171.519412) (xy 419.616403 -171.491603) (xy 419.599064 -171.467754) (xy 419.575634 -171.449852)
			(xy 419.562026 -171.444158) (xy 419.535269 -171.433416) (xy 419.485027 -171.405136) (xy 419.439617 -171.369613)
			(xy 419.400072 -171.327658) (xy 419.367296 -171.280228) (xy 419.342035 -171.228402) (xy 419.324865 -171.173365)
			(xy 419.316178 -171.116369) (xy 419.315646 -171.087542) (xy 410.131006 -171.087542) (xy 410.131006 -172.353224)
			(xy 412.850584 -172.353224) (xy 412.875534 -172.353712) (xy 412.924821 -172.361514) (xy 412.972281 -172.376929)
			(xy 413.016747 -172.399577) (xy 413.057122 -172.428901) (xy 413.07512 -172.446188) (xy 413.455182 -172.82625)
			(xy 419.374572 -172.82625) (xy 419.374572 -172.77175) (xy 419.382328 -172.717803) (xy 419.397682 -172.66551)
			(xy 419.420321 -172.615933) (xy 419.449786 -172.570084) (xy 419.485475 -172.528893) (xy 419.526663 -172.493201)
			(xy 419.572511 -172.463734) (xy 419.622085 -172.441091) (xy 419.674378 -172.425733) (xy 419.728324 -172.417974)
			(xy 419.755574 -172.417486) (xy 419.78151 -172.417935) (xy 419.832905 -172.42496) (xy 419.882874 -172.438884)
			(xy 419.930495 -172.459451) (xy 419.97489 -172.48628) (xy 420.015241 -172.518878) (xy 420.050803 -172.556642)
			(xy 420.066216 -172.577506) (xy 420.075441 -172.589618) (xy 420.099609 -172.608114) (xy 420.128159 -172.618654)
			(xy 420.158548 -172.620298) (xy 420.188068 -172.6129) (xy 420.201344 -172.605446) (xy 420.223766 -172.592408)
			(xy 420.271398 -172.571875) (xy 420.321372 -172.557986) (xy 420.372767 -172.550998) (xy 420.398702 -172.550582)
			(xy 420.425952 -172.551088) (xy 420.479898 -172.558845) (xy 420.532192 -172.5742) (xy 420.581767 -172.59684)
			(xy 420.627616 -172.626306) (xy 420.668805 -172.661997) (xy 420.704495 -172.703186) (xy 420.733961 -172.749035)
			(xy 420.756601 -172.79861) (xy 420.771956 -172.850904) (xy 420.779712 -172.90485) (xy 420.779712 -172.95935)
			(xy 420.771956 -173.013296) (xy 420.756601 -173.06559) (xy 420.733961 -173.115165) (xy 420.704495 -173.161014)
			(xy 420.668805 -173.202203) (xy 420.627616 -173.237894) (xy 420.581767 -173.26736) (xy 420.532192 -173.29)
			(xy 420.479898 -173.305355) (xy 420.425952 -173.313112) (xy 420.398702 -173.313598) (xy 420.372765 -173.313174)
			(xy 420.321369 -173.306145) (xy 420.271399 -173.292217) (xy 420.223778 -173.271647) (xy 420.179382 -173.244813)
			(xy 420.139033 -173.212212) (xy 420.103472 -173.174444) (xy 420.08806 -173.153578) (xy 420.07886 -173.141445)
			(xy 420.054684 -173.122952) (xy 420.026127 -173.112417) (xy 419.995733 -173.110778) (xy 419.966209 -173.118181)
			(xy 419.952932 -173.125638) (xy 419.930497 -173.138654) (xy 419.88287 -173.15919) (xy 419.8329 -173.173085)
			(xy 419.781507 -173.180081) (xy 419.755574 -173.180502) (xy 419.728324 -173.180026) (xy 419.674378 -173.172267)
			(xy 419.622085 -173.156909) (xy 419.572511 -173.134266) (xy 419.526663 -173.104799) (xy 419.485475 -173.069107)
			(xy 419.449786 -173.027916) (xy 419.420321 -172.982067) (xy 419.397682 -172.93249) (xy 419.382328 -172.880197)
			(xy 419.374572 -172.82625) (xy 413.455182 -172.82625) (xy 413.905192 -173.27626) (xy 417.967414 -173.27626)
			(xy 417.992397 -173.276772) (xy 418.041743 -173.284625) (xy 418.089257 -173.300089) (xy 418.133772 -173.322784)
			(xy 418.174197 -173.352153) (xy 418.192204 -173.369478) (xy 418.255958 -173.433486) (xy 418.398706 -173.576234)
			(xy 418.410195 -173.585824) (xy 418.437296 -173.59848) (xy 418.466901 -173.602743) (xy 418.496473 -173.598247)
			(xy 418.523474 -173.585378) (xy 418.545589 -173.565239) (xy 418.560923 -173.539558) (xy 418.565076 -173.52518)
			(xy 418.571636 -173.497095) (xy 418.592073 -173.443167) (xy 418.620397 -173.39293) (xy 418.655962 -173.34753)
			(xy 418.697957 -173.308003) (xy 418.745424 -173.275248) (xy 418.797282 -173.250014) (xy 418.852347 -173.232875)
			(xy 418.909366 -173.224222) (xy 418.938202 -173.223682) (xy 418.965315 -173.224158) (xy 419.018995 -173.231836)
			(xy 419.071046 -173.247038) (xy 419.120421 -173.269457) (xy 419.166124 -173.298641) (xy 419.207235 -173.334002)
			(xy 419.242924 -173.374827) (xy 419.272473 -173.420295) (xy 419.295286 -173.469489) (xy 419.310904 -173.521417)
			(xy 419.319013 -173.575034) (xy 419.31971 -173.602142) (xy 419.31971 -173.60519) (xy 419.319311 -173.631436)
			(xy 419.312178 -173.68344) (xy 419.305486 -173.708822) (xy 419.302585 -173.723166) (xy 419.304197 -173.752375)
			(xy 419.314025 -173.779928) (xy 419.331261 -173.803564) (xy 419.354491 -173.821344) (xy 419.381809 -173.831808)
			(xy 419.410972 -173.834097) (xy 419.425374 -173.831504) (xy 419.44745 -173.826498) (xy 419.492402 -173.821151)
			(xy 419.515036 -173.820836) (xy 419.520624 -173.820836) (xy 419.548089 -173.821698) (xy 419.602355 -173.830337)
			(xy 419.65482 -173.84667) (xy 419.7044 -173.87036) (xy 419.75007 -173.900916) (xy 419.790884 -173.937707)
			(xy 419.826 -173.979971) (xy 419.854691 -174.026835) (xy 419.876363 -174.077329) (xy 419.890569 -174.13041)
			(xy 419.894258 -174.15764) (xy 419.89502 -174.165006) (xy 419.896798 -174.20209) (xy 419.896798 -174.209202)
			(xy 419.895757 -174.237928) (xy 419.886109 -174.294593) (xy 419.86807 -174.349169) (xy 419.842049 -174.400423)
			(xy 419.808634 -174.447193) (xy 419.768582 -174.488422) (xy 419.722798 -174.523176) (xy 419.67232 -174.55067)
			(xy 419.618288 -174.570282) (xy 419.59022 -174.576486) (xy 419.572586 -174.591933) (xy 419.533628 -174.618007)
			(xy 419.491264 -174.638078) (xy 419.446412 -174.65171) (xy 419.400045 -174.658609) (xy 419.376606 -174.659036)
			(xy 418.713666 -174.659036) (xy 418.688683 -174.658523) (xy 418.639337 -174.650669) (xy 418.591822 -174.635206)
			(xy 418.547304 -174.612514) (xy 418.506876 -174.58315) (xy 418.488876 -174.565818) (xy 417.835588 -173.912276)
			(xy 413.773366 -173.912276) (xy 413.748383 -173.911762) (xy 413.699038 -173.903907) (xy 413.651525 -173.888443)
			(xy 413.60701 -173.865748) (xy 413.566586 -173.836379) (xy 413.548576 -173.819058) (xy 413.286956 -173.557184)
			(xy 413.032956 -173.303184) (xy 412.718758 -172.988732) (xy 410.131006 -172.988732) (xy 410.131006 -174.423957)
			(xy 416.453709 -174.423957) (xy 416.453709 -174.369443) (xy 416.461468 -174.315483) (xy 416.476827 -174.263176)
			(xy 416.499474 -174.213588) (xy 416.528948 -174.167728) (xy 416.56465 -174.12653) (xy 416.605851 -174.090832)
			(xy 416.651713 -174.061361) (xy 416.701302 -174.038717) (xy 416.75361 -174.023362) (xy 416.807571 -174.015607)
			(xy 416.834828 -174.015146) (xy 416.862199 -174.015584) (xy 416.91638 -174.023407) (xy 416.968884 -174.038902)
			(xy 417.01863 -174.06175) (xy 417.064596 -174.091481) (xy 417.085526 -174.109126) (xy 417.096854 -174.118362)
			(xy 417.123411 -174.130538) (xy 417.152328 -174.134711) (xy 417.181245 -174.130538) (xy 417.207802 -174.118362)
			(xy 417.21913 -174.109126) (xy 417.240081 -174.09151) (xy 417.286048 -174.061794) (xy 417.335791 -174.038953)
			(xy 417.388287 -174.023457) (xy 417.44246 -174.015623) (xy 417.469828 -174.015146) (xy 417.497075 -174.015726)
			(xy 417.551013 -174.023485) (xy 417.603298 -174.038841) (xy 417.652865 -174.061481) (xy 417.698707 -174.090944)
			(xy 417.739889 -174.126631) (xy 417.775573 -174.167816) (xy 417.805033 -174.213659) (xy 417.827669 -174.263228)
			(xy 417.843021 -174.315515) (xy 417.850776 -174.369453) (xy 417.850776 -174.423947) (xy 417.843021 -174.477885)
			(xy 417.827669 -174.530172) (xy 417.805033 -174.579741) (xy 417.775573 -174.625584) (xy 417.739889 -174.666769)
			(xy 417.698707 -174.702456) (xy 417.652865 -174.731919) (xy 417.603298 -174.754559) (xy 417.551013 -174.769915)
			(xy 417.497075 -174.777674) (xy 417.469828 -174.778162) (xy 417.442458 -174.777689) (xy 417.388279 -174.769874)
			(xy 417.335775 -174.754387) (xy 417.286028 -174.731547) (xy 417.240062 -174.701823) (xy 417.21913 -174.684182)
			(xy 417.207802 -174.674946) (xy 417.181245 -174.66277) (xy 417.152328 -174.658597) (xy 417.123411 -174.66277)
			(xy 417.096854 -174.674946) (xy 417.085526 -174.684182) (xy 417.064593 -174.70182) (xy 417.01862 -174.731532)
			(xy 416.968873 -174.754369) (xy 416.916373 -174.76986) (xy 416.862197 -174.777688) (xy 416.834828 -174.778162)
			(xy 416.807571 -174.777793) (xy 416.75361 -174.770038) (xy 416.701302 -174.754683) (xy 416.651713 -174.732039)
			(xy 416.605851 -174.702568) (xy 416.56465 -174.66687) (xy 416.528948 -174.625672) (xy 416.499474 -174.579812)
			(xy 416.476827 -174.530224) (xy 416.461468 -174.477917) (xy 416.453709 -174.423957) (xy 410.131006 -174.423957)
			(xy 410.131006 -178.792378) (xy 417.4998 -178.792378) (xy 417.500317 -178.765048) (xy 417.50828 -178.710971)
			(xy 417.524061 -178.658638) (xy 417.547322 -178.609175) (xy 417.577563 -178.563642) (xy 417.614133 -178.523018)
			(xy 417.656249 -178.488176) (xy 417.679378 -178.473608) (xy 417.691578 -178.46565) (xy 417.711251 -178.444189)
			(xy 417.724061 -178.418045) (xy 417.728962 -178.389347) (xy 417.725556 -178.360434) (xy 417.720272 -178.346862)
			(xy 417.710777 -178.323654) (xy 417.697428 -178.27532) (xy 417.690702 -178.22563) (xy 417.6903 -178.200558)
			(xy 417.690724 -178.175489) (xy 417.697474 -178.125806) (xy 417.710806 -178.077471) (xy 417.720272 -178.054254)
			(xy 417.725563 -178.040687) (xy 417.728937 -178.011773) (xy 417.724027 -177.983079) (xy 417.711231 -177.95693)
			(xy 417.691587 -177.935447) (xy 417.679378 -177.927508) (xy 417.656281 -177.912887) (xy 417.61416 -177.87805)
			(xy 417.57758 -177.837433) (xy 417.547327 -177.791907) (xy 417.52405 -177.742451) (xy 417.508247 -177.690124)
			(xy 417.500259 -177.63605) (xy 417.500256 -177.581389) (xy 417.508238 -177.527314) (xy 417.524036 -177.474986)
			(xy 417.547308 -177.425527) (xy 417.577556 -177.379998) (xy 417.614131 -177.339377) (xy 417.656249 -177.304536)
			(xy 417.679378 -177.289968) (xy 417.691605 -177.282048) (xy 417.711279 -177.260577) (xy 417.724084 -177.234423)
			(xy 417.728979 -177.205716) (xy 417.725563 -177.176796) (xy 417.720272 -177.163222) (xy 417.710796 -177.140007)
			(xy 417.69744 -177.091677) (xy 417.690706 -177.041989) (xy 417.6903 -177.016918) (xy 417.690766 -176.990075)
			(xy 417.698468 -176.936945) (xy 417.713716 -176.88547) (xy 417.736193 -176.836717) (xy 417.765435 -176.791694)
			(xy 417.800836 -176.751334) (xy 417.841662 -176.716472) (xy 417.887069 -176.687831) (xy 417.936117 -176.666002)
			(xy 417.961826 -176.65827) (xy 417.976329 -176.65362) (xy 418.0019 -176.637103) (xy 418.021469 -176.613785)
			(xy 418.033299 -176.585737) (xy 418.03634 -176.555448) (xy 418.030322 -176.525608) (xy 418.023548 -176.511966)
			(xy 418.00892 -176.483818) (xy 417.988191 -176.423868) (xy 417.977691 -176.36131) (xy 417.977066 -176.329594)
			(xy 417.977291 -176.311575) (xy 417.980722 -176.2757) (xy 417.983924 -176.257966) (xy 417.986322 -176.242764)
			(xy 417.982784 -176.212201) (xy 417.97031 -176.184077) (xy 417.95003 -176.160941) (xy 417.923782 -176.144889)
			(xy 417.908994 -176.140618) (xy 417.881967 -176.133164) (xy 417.830242 -176.111542) (xy 417.782237 -176.082585)
			(xy 417.738984 -176.046917) (xy 417.701416 -176.005305) (xy 417.670339 -175.958645) (xy 417.646423 -175.90794)
			(xy 417.630183 -175.854282) (xy 417.621967 -175.798825) (xy 417.621466 -175.770794) (xy 417.621972 -175.743544)
			(xy 417.629729 -175.689598) (xy 417.645083 -175.637305) (xy 417.667723 -175.58773) (xy 417.697188 -175.541881)
			(xy 417.732877 -175.500691) (xy 417.774065 -175.465) (xy 417.819912 -175.435533) (xy 417.869487 -175.41289)
			(xy 417.921779 -175.397533) (xy 417.975724 -175.389774) (xy 418.002974 -175.389286) (xy 418.030548 -175.389774)
			(xy 418.085119 -175.397723) (xy 418.137979 -175.413444) (xy 418.188024 -175.43661) (xy 418.234215 -175.466738)
			(xy 418.275587 -175.503201) (xy 418.293804 -175.523906) (xy 418.303702 -175.534804) (xy 418.328352 -175.550879)
			(xy 418.35656 -175.559263) (xy 418.385988 -175.559263) (xy 418.414196 -175.550879) (xy 418.438846 -175.534804)
			(xy 418.448744 -175.523906) (xy 418.466959 -175.5032) (xy 418.50833 -175.466735) (xy 418.55452 -175.436608)
			(xy 418.604567 -175.413445) (xy 418.657428 -175.397729) (xy 418.712 -175.389789) (xy 418.767148 -175.389789)
			(xy 418.82172 -175.397729) (xy 418.874581 -175.413445) (xy 418.924628 -175.436608) (xy 418.970818 -175.466735)
			(xy 419.012189 -175.5032) (xy 419.030404 -175.523906) (xy 419.040302 -175.534804) (xy 419.064952 -175.550879)
			(xy 419.09316 -175.559263) (xy 419.122588 -175.559263) (xy 419.150796 -175.550879) (xy 419.175446 -175.534804)
			(xy 419.185344 -175.523906) (xy 419.203582 -175.50322) (xy 419.244945 -175.466747) (xy 419.291129 -175.436612)
			(xy 419.341172 -175.413442) (xy 419.39403 -175.39772) (xy 419.448601 -175.389775) (xy 419.476174 -175.389286)
			(xy 419.503426 -175.389779) (xy 419.557375 -175.397533) (xy 419.609672 -175.412885) (xy 419.659252 -175.435524)
			(xy 419.705105 -175.464989) (xy 419.746298 -175.50068) (xy 419.781992 -175.541869) (xy 419.81146 -175.58772)
			(xy 419.834104 -175.637298) (xy 419.84946 -175.689593) (xy 419.857218 -175.743542) (xy 419.857682 -175.770794)
			(xy 419.857167 -175.79865) (xy 419.849043 -175.853766) (xy 419.832998 -175.907117) (xy 419.80937 -175.957571)
			(xy 419.778663 -176.004056) (xy 419.741526 -176.045585) (xy 419.69875 -176.081278) (xy 419.651241 -176.110376)
			(xy 419.600008 -176.132262) (xy 419.573202 -176.139856) (xy 419.559077 -176.144105) (xy 419.53393 -176.159501)
			(xy 419.514215 -176.181425) (xy 419.501566 -176.20806) (xy 419.497034 -176.237195) (xy 419.498526 -176.25187)
			(xy 419.5002 -176.264886) (xy 419.501977 -176.291071) (xy 419.502082 -176.304194) (xy 419.501988 -176.318343)
			(xy 419.499954 -176.346566) (xy 419.498018 -176.360582) (xy 419.496394 -176.373927) (xy 419.4995 -176.400623)
			(xy 419.509476 -176.425579) (xy 419.525629 -176.44706) (xy 419.546835 -176.463572) (xy 419.57162 -176.473966)
			(xy 419.584886 -176.476152) (xy 419.612039 -176.480237) (xy 419.664868 -176.495214) (xy 419.715004 -176.517609)
			(xy 419.761412 -176.546958) (xy 419.803135 -176.582656) (xy 419.839311 -176.623965) (xy 419.869192 -176.670033)
			(xy 419.892162 -176.719908) (xy 419.907746 -176.772561) (xy 419.915622 -176.826903) (xy 419.916102 -176.854358)
			(xy 419.915606 -176.88161) (xy 419.907854 -176.93556) (xy 419.892503 -176.987858) (xy 419.869865 -177.037438)
			(xy 419.840401 -177.083292) (xy 419.804711 -177.124485) (xy 419.763521 -177.160179) (xy 419.71767 -177.189648)
			(xy 419.668092 -177.212291) (xy 419.615795 -177.227647) (xy 419.561846 -177.235403) (xy 419.534594 -177.235866)
			(xy 419.507019 -177.235416) (xy 419.452445 -177.227462) (xy 419.399584 -177.211735) (xy 419.349538 -177.188562)
			(xy 419.303349 -177.158426) (xy 419.261979 -177.121955) (xy 419.243764 -177.101246) (xy 419.233866 -177.090348)
			(xy 419.209216 -177.074273) (xy 419.181008 -177.065889) (xy 419.15158 -177.065889) (xy 419.123372 -177.074273)
			(xy 419.098722 -177.090348) (xy 419.088824 -177.101246) (xy 419.070614 -177.121958) (xy 419.029244 -177.158426)
			(xy 418.983053 -177.188557) (xy 418.933005 -177.211722) (xy 418.880143 -177.227439) (xy 418.825569 -177.23538)
			(xy 418.797994 -177.235866) (xy 418.771493 -177.235405) (xy 418.719002 -177.228063) (xy 418.668034 -177.213521)
			(xy 418.619572 -177.192059) (xy 418.574549 -177.164091) (xy 418.5539 -177.147474) (xy 418.541717 -177.138082)
			(xy 418.51333 -177.126285) (xy 418.482719 -177.123451) (xy 418.452648 -177.129838) (xy 418.425831 -177.144868)
			(xy 418.404689 -177.167186) (xy 418.397436 -177.180748) (xy 418.385321 -177.20443) (xy 418.355402 -177.248413)
			(xy 418.319535 -177.287696) (xy 418.278448 -177.321482) (xy 418.255958 -177.335688) (xy 418.243751 -177.343635)
			(xy 418.224085 -177.365102) (xy 418.211281 -177.391249) (xy 418.206381 -177.419947) (xy 418.209783 -177.448861)
			(xy 418.215064 -177.462434) (xy 418.22456 -177.485641) (xy 418.237908 -177.533976) (xy 418.244633 -177.583666)
			(xy 418.245036 -177.608738) (xy 418.244615 -177.633807) (xy 418.237865 -177.683491) (xy 418.224531 -177.731825)
			(xy 418.215064 -177.755042) (xy 418.209854 -177.768631) (xy 418.206485 -177.797525) (xy 418.211389 -177.826198)
			(xy 418.224168 -177.85233) (xy 418.243789 -177.873805) (xy 418.255958 -177.881788) (xy 418.27905 -177.896416)
			(xy 418.321167 -177.931255) (xy 418.357742 -177.971872) (xy 418.387993 -178.017397) (xy 418.411268 -178.066852)
			(xy 418.427069 -178.119177) (xy 418.435057 -178.173249) (xy 418.43506 -178.227908) (xy 418.427078 -178.28198)
			(xy 418.411283 -178.334307) (xy 418.388014 -178.383765) (xy 418.357769 -178.429294) (xy 418.321198 -178.469915)
			(xy 418.279085 -178.504759) (xy 418.255958 -178.519328) (xy 418.243724 -178.527237) (xy 418.224058 -178.548714)
			(xy 418.211257 -178.574871) (xy 418.206364 -178.603578) (xy 418.209777 -178.632499) (xy 418.215064 -178.646074)
			(xy 418.224541 -178.669289) (xy 418.237896 -178.717619) (xy 418.244629 -178.767307) (xy 418.245036 -178.792378)
			(xy 418.244515 -178.820263) (xy 418.236203 -178.87541) (xy 418.219765 -178.928702) (xy 418.195567 -178.978948)
			(xy 418.164151 -179.025027) (xy 418.126218 -179.065909) (xy 418.082616 -179.100681) (xy 418.034318 -179.128566)
			(xy 417.982403 -179.148941) (xy 417.928032 -179.161351) (xy 417.872418 -179.165519) (xy 417.816804 -179.161351)
			(xy 417.762433 -179.148941) (xy 417.710518 -179.128566) (xy 417.66222 -179.100681) (xy 417.618618 -179.065909)
			(xy 417.580685 -179.025027) (xy 417.549269 -178.978948) (xy 417.525071 -178.928702) (xy 417.508633 -178.87541)
			(xy 417.500321 -178.820263) (xy 417.4998 -178.792378) (xy 410.131006 -178.792378) (xy 410.131006 -179.723542)
			(xy 419.315646 -179.723542) (xy 419.316217 -179.696294) (xy 419.323967 -179.642352) (xy 419.339314 -179.590061)
			(xy 419.361947 -179.540487) (xy 419.391405 -179.494639) (xy 419.427087 -179.45345) (xy 419.468269 -179.417757)
			(xy 419.51411 -179.388289) (xy 419.563679 -179.365645) (xy 419.615966 -179.350285) (xy 419.669906 -179.342523)
			(xy 419.697154 -179.342034) (xy 419.697408 -179.342034) (xy 419.727247 -179.342617) (xy 419.786193 -179.351927)
			(xy 419.814756 -179.360576) (xy 419.82866 -179.36463) (xy 419.857597 -179.36554) (xy 419.885621 -179.358274)
			(xy 419.910469 -179.343418) (xy 419.930134 -179.322171) (xy 419.943028 -179.296251) (xy 419.946074 -179.28209)
			(xy 419.951209 -179.255983) (xy 419.967804 -179.20543) (xy 419.991265 -179.157674) (xy 420.021136 -179.113644)
			(xy 420.056839 -179.074193) (xy 420.097679 -179.040089) (xy 420.142863 -179.011993) (xy 420.191514 -178.990451)
			(xy 420.242688 -178.975881) (xy 420.29539 -178.968567) (xy 420.321994 -178.968146) (xy 420.34333 -178.968146)
			(xy 421.08628 -178.225196) (xy 421.10439 -178.207956) (xy 421.14593 -178.180143) (xy 421.192097 -178.160966)
			(xy 421.241117 -178.15116) (xy 421.266112 -178.15052) (xy 422.938702 -178.15052) (xy 424.204892 -176.88433)
			(xy 424.204892 -160.020508) (xy 424.205513 -159.995511) (xy 424.215319 -159.946486) (xy 424.234496 -159.900315)
			(xy 424.26231 -159.858771) (xy 424.279568 -159.840676) (xy 426.178472 -157.941518) (xy 426.178472 -155.064968)
			(xy 426.179074 -155.03997) (xy 426.188887 -154.990945) (xy 426.20807 -154.944774) (xy 426.235888 -154.90323)
			(xy 426.253148 -154.885136) (xy 431.276252 -149.861778) (xy 431.276252 -147.217638) (xy 430.10201 -146.043396)
			(xy 422.75252 -146.043396) (xy 422.727525 -146.042742) (xy 422.678504 -146.032943) (xy 422.632333 -146.013774)
			(xy 422.590786 -145.985972) (xy 422.572688 -145.96872) (xy 421.444928 -144.84096) (xy 421.427665 -144.822871)
			(xy 421.399855 -144.781324) (xy 421.380683 -144.735151) (xy 421.370887 -144.686125) (xy 421.370252 -144.661128)
			(xy 421.370252 -140.646404) (xy 421.370882 -140.621408) (xy 421.380687 -140.572384) (xy 421.399862 -140.526213)
			(xy 421.427672 -140.484668) (xy 421.444928 -140.466572) (xy 423.325544 -138.585956) (xy 423.343636 -138.568695)
			(xy 423.385181 -138.540884) (xy 423.431353 -138.521711) (xy 423.480379 -138.511915) (xy 423.505376 -138.51128)
			(xy 427.671738 -138.51128) (xy 427.707552 -138.475466) (xy 427.707552 -134.286498) (xy 427.25213 -133.831076)
			(xy 426.36186 -133.831076) (xy 426.336866 -133.830404) (xy 426.287845 -133.820611) (xy 426.241674 -133.801448)
			(xy 426.200126 -133.77365) (xy 426.182028 -133.7564) (xy 425.878244 -133.452616) (xy 425.856908 -133.452616)
			(xy 425.829632 -133.452179) (xy 425.775627 -133.444481) (xy 425.723268 -133.429169) (xy 425.673625 -133.406556)
			(xy 425.627708 -133.377103) (xy 425.586455 -133.34141) (xy 425.550706 -133.300205) (xy 425.521191 -133.254329)
			(xy 425.498511 -133.204716) (xy 425.483129 -133.152378) (xy 425.475358 -133.098384) (xy 425.474892 -133.071108)
			(xy 425.475355 -133.043843) (xy 425.483118 -132.989869) (xy 425.498486 -132.93755) (xy 425.521147 -132.887952)
			(xy 425.550638 -132.842085) (xy 425.586359 -132.800885) (xy 425.627583 -132.76519) (xy 425.673468 -132.735729)
			(xy 425.723081 -132.7131) (xy 425.77541 -132.697766) (xy 425.829389 -132.690038) (xy 425.883918 -132.690074)
			(xy 425.937887 -132.697874) (xy 425.990196 -132.713278) (xy 426.039778 -132.735973) (xy 426.085624 -132.765495)
			(xy 426.1268 -132.801245) (xy 426.162467 -132.842493) (xy 426.191897 -132.888398) (xy 426.214491 -132.938027)
			(xy 426.22979 -132.990366) (xy 426.237481 -133.044351) (xy 426.237908 -133.071616) (xy 426.237908 -133.092952)
			(xy 426.46727 -133.32206) (xy 427.35754 -133.32206) (xy 427.382535 -133.322722) (xy 427.431557 -133.332517)
			(xy 427.477728 -133.351683) (xy 427.519275 -133.379484) (xy 427.537372 -133.396736) (xy 427.619414 -133.478778)
			(xy 429.131728 -133.478778) (xy 429.135799 -133.423156) (xy 429.147925 -133.368719) (xy 429.167848 -133.316628)
			(xy 429.195144 -133.267993) (xy 429.22923 -133.22385) (xy 429.269379 -133.185141) (xy 429.314737 -133.15269)
			(xy 429.364337 -133.127189) (xy 429.417121 -133.109182) (xy 429.471964 -133.099052) (xy 429.527698 -133.097015)
			(xy 429.583135 -133.103115) (xy 429.637092 -133.117221) (xy 429.688421 -133.139033) (xy 429.736027 -133.168087)
			(xy 429.778895 -133.203762) (xy 429.816112 -133.245299) (xy 429.846885 -133.291812) (xy 429.870557 -133.342309)
			(xy 429.886625 -133.395716) (xy 429.894745 -133.450892) (xy 429.895254 -133.478778) (xy 429.894745 -133.506664)
			(xy 429.886625 -133.56184) (xy 429.870557 -133.615247) (xy 429.863684 -133.629908) (xy 432.162202 -133.629908)
			(xy 432.166273 -133.574286) (xy 432.178399 -133.519849) (xy 432.198322 -133.467758) (xy 432.225618 -133.419123)
			(xy 432.259704 -133.37498) (xy 432.299853 -133.336271) (xy 432.345211 -133.30382) (xy 432.394811 -133.278319)
			(xy 432.447595 -133.260312) (xy 432.502438 -133.250182) (xy 432.558172 -133.248145) (xy 432.613609 -133.254245)
			(xy 432.667566 -133.268351) (xy 432.718895 -133.290163) (xy 432.766501 -133.319217) (xy 432.809369 -133.354892)
			(xy 432.846586 -133.396429) (xy 432.877359 -133.442942) (xy 432.901031 -133.493439) (xy 432.917099 -133.546846)
			(xy 432.925219 -133.602022) (xy 432.925728 -133.629908) (xy 432.925219 -133.657794) (xy 432.917099 -133.71297)
			(xy 432.901031 -133.766377) (xy 432.877359 -133.816874) (xy 432.846586 -133.863387) (xy 432.809369 -133.904924)
			(xy 432.766501 -133.940599) (xy 432.718895 -133.969653) (xy 432.667566 -133.991465) (xy 432.613609 -134.005571)
			(xy 432.558172 -134.011671) (xy 432.502438 -134.009634) (xy 432.447595 -133.999504) (xy 432.394811 -133.981497)
			(xy 432.345211 -133.955996) (xy 432.299853 -133.923545) (xy 432.259704 -133.884836) (xy 432.225618 -133.840693)
			(xy 432.198322 -133.792058) (xy 432.178399 -133.739967) (xy 432.166273 -133.68553) (xy 432.162202 -133.629908)
			(xy 429.863684 -133.629908) (xy 429.846885 -133.665744) (xy 429.816112 -133.712257) (xy 429.778895 -133.753794)
			(xy 429.736027 -133.789469) (xy 429.688421 -133.818523) (xy 429.637092 -133.840335) (xy 429.583135 -133.854441)
			(xy 429.527698 -133.860541) (xy 429.471964 -133.858504) (xy 429.417121 -133.848374) (xy 429.364337 -133.830367)
			(xy 429.314737 -133.804866) (xy 429.269379 -133.772415) (xy 429.22923 -133.733706) (xy 429.195144 -133.689563)
			(xy 429.167848 -133.640928) (xy 429.147925 -133.588837) (xy 429.135799 -133.5344) (xy 429.131728 -133.478778)
			(xy 427.619414 -133.478778) (xy 428.141892 -134.001256) (xy 428.159166 -134.019335) (xy 428.186973 -134.060886)
			(xy 428.206142 -134.107062) (xy 428.215935 -134.15609) (xy 428.216568 -134.181088) (xy 428.216568 -134.747762)
			(xy 429.158398 -134.747762) (xy 429.162469 -134.69214) (xy 429.174595 -134.637703) (xy 429.194518 -134.585612)
			(xy 429.221814 -134.536977) (xy 429.2559 -134.492834) (xy 429.296049 -134.454125) (xy 429.341407 -134.421674)
			(xy 429.391007 -134.396173) (xy 429.443791 -134.378166) (xy 429.498634 -134.368036) (xy 429.554368 -134.365999)
			(xy 429.609805 -134.372099) (xy 429.663762 -134.386205) (xy 429.715091 -134.408017) (xy 429.762697 -134.437071)
			(xy 429.805565 -134.472746) (xy 429.842782 -134.514283) (xy 429.873555 -134.560796) (xy 429.897227 -134.611293)
			(xy 429.913295 -134.6647) (xy 429.921415 -134.719876) (xy 429.921924 -134.747762) (xy 429.921415 -134.775648)
			(xy 429.913295 -134.830824) (xy 429.897227 -134.884231) (xy 429.873555 -134.934728) (xy 429.842782 -134.981241)
			(xy 429.805565 -135.022778) (xy 429.762697 -135.058453) (xy 429.715091 -135.087507) (xy 429.663762 -135.109319)
			(xy 429.609805 -135.123425) (xy 429.554368 -135.129525) (xy 429.498634 -135.127488) (xy 429.443791 -135.117358)
			(xy 429.391007 -135.099351) (xy 429.341407 -135.07385) (xy 429.296049 -135.041399) (xy 429.2559 -135.00269)
			(xy 429.221814 -134.958547) (xy 429.194518 -134.909912) (xy 429.174595 -134.857821) (xy 429.162469 -134.803384)
			(xy 429.158398 -134.747762) (xy 428.216568 -134.747762) (xy 428.216568 -137.130028) (xy 428.753016 -137.130028)
			(xy 428.753463 -137.103293) (xy 428.760925 -137.050348) (xy 428.775708 -136.998963) (xy 428.797521 -136.950146)
			(xy 428.825937 -136.904853) (xy 428.860399 -136.863971) (xy 428.880016 -136.845802) (xy 428.890822 -136.835406)
			(xy 428.906368 -136.809781) (xy 428.913789 -136.780743) (xy 428.912443 -136.750802) (xy 428.902446 -136.722547)
			(xy 428.893986 -136.710166) (xy 428.876517 -136.68545) (xy 428.848814 -136.631639) (xy 428.829949 -136.574132)
			(xy 428.820397 -136.514367) (xy 428.819818 -136.484106) (xy 428.82029 -136.455888) (xy 428.828576 -136.400063)
			(xy 428.844998 -136.34607) (xy 428.869197 -136.295085) (xy 428.900645 -136.248223) (xy 428.938655 -136.206507)
			(xy 428.982397 -136.170847) (xy 429.030917 -136.142022) (xy 429.083154 -136.120661) (xy 429.137969 -136.107232)
			(xy 429.16602 -136.104122) (xy 429.180402 -136.102296) (xy 429.207356 -136.091662) (xy 429.230235 -136.073881)
			(xy 429.247195 -136.050386) (xy 429.256869 -136.023073) (xy 429.258478 -135.994141) (xy 429.255682 -135.979916)
			(xy 429.250944 -135.958447) (xy 429.245847 -135.914777) (xy 429.245522 -135.892794) (xy 429.246008 -135.865543)
			(xy 429.253764 -135.811595) (xy 429.269119 -135.7593) (xy 429.291761 -135.709723) (xy 429.321227 -135.663873)
			(xy 429.356918 -135.622682) (xy 429.398109 -135.586991) (xy 429.443959 -135.557525) (xy 429.493536 -135.534883)
			(xy 429.545831 -135.519528) (xy 429.599779 -135.511772) (xy 429.654281 -135.511772) (xy 429.708229 -135.519528)
			(xy 429.760524 -135.534883) (xy 429.782825 -135.545068) (xy 431.227736 -135.545068) (xy 431.231807 -135.489446)
			(xy 431.243933 -135.435009) (xy 431.263856 -135.382918) (xy 431.291152 -135.334283) (xy 431.325238 -135.29014)
			(xy 431.365387 -135.251431) (xy 431.410745 -135.21898) (xy 431.460345 -135.193479) (xy 431.513129 -135.175472)
			(xy 431.567972 -135.165342) (xy 431.623706 -135.163305) (xy 431.679143 -135.169405) (xy 431.7331 -135.183511)
			(xy 431.784429 -135.205323) (xy 431.832035 -135.234377) (xy 431.874903 -135.270052) (xy 431.91212 -135.311589)
			(xy 431.942893 -135.358102) (xy 431.966565 -135.408599) (xy 431.982633 -135.462006) (xy 431.990753 -135.517182)
			(xy 431.991262 -135.545068) (xy 431.990753 -135.572954) (xy 431.982633 -135.62813) (xy 431.966565 -135.681537)
			(xy 431.942893 -135.732034) (xy 431.91212 -135.778547) (xy 431.887022 -135.806558) (xy 432.659911 -135.806558)
			(xy 432.659911 -135.752042) (xy 432.66767 -135.698081) (xy 432.68303 -135.645773) (xy 432.705678 -135.596185)
			(xy 432.735154 -135.550324) (xy 432.770857 -135.509125) (xy 432.812059 -135.473428) (xy 432.857923 -135.443957)
			(xy 432.907515 -135.421315) (xy 432.959824 -135.405961) (xy 433.013786 -135.398208) (xy 433.041044 -135.397748)
			(xy 433.071983 -135.398373) (xy 433.133051 -135.408358) (xy 433.191705 -135.428075) (xy 433.246404 -135.457005)
			(xy 433.271422 -135.475218) (xy 433.282668 -135.48321) (xy 433.308295 -135.493405) (xy 433.335716 -135.496354)
			(xy 433.362924 -135.491841) (xy 433.387925 -135.480197) (xy 433.408887 -135.462274) (xy 433.416964 -135.451088)
			(xy 433.432273 -135.429314) (xy 433.467904 -135.389775) (xy 433.508688 -135.355577) (xy 433.553832 -135.327383)
			(xy 433.602458 -135.305741) (xy 433.653621 -135.291072) (xy 433.706328 -135.283661) (xy 433.73294 -135.283194)
			(xy 433.76019 -135.283679) (xy 433.793893 -135.288528) (xy 435.509922 -135.288528) (xy 435.513993 -135.232906)
			(xy 435.526119 -135.178469) (xy 435.546042 -135.126378) (xy 435.573338 -135.077743) (xy 435.607424 -135.0336)
			(xy 435.647573 -134.994891) (xy 435.692931 -134.96244) (xy 435.742531 -134.936939) (xy 435.795315 -134.918932)
			(xy 435.850158 -134.908802) (xy 435.905892 -134.906765) (xy 435.961329 -134.912865) (xy 436.015286 -134.926971)
			(xy 436.066615 -134.948783) (xy 436.114221 -134.977837) (xy 436.157089 -135.013512) (xy 436.194306 -135.055049)
			(xy 436.225079 -135.101562) (xy 436.248751 -135.152059) (xy 436.264819 -135.205466) (xy 436.272939 -135.260642)
			(xy 436.273448 -135.288528) (xy 436.272939 -135.316414) (xy 436.264819 -135.37159) (xy 436.248751 -135.424997)
			(xy 436.225079 -135.475494) (xy 436.194306 -135.522007) (xy 436.157089 -135.563544) (xy 436.114221 -135.599219)
			(xy 436.066615 -135.628273) (xy 436.015286 -135.650085) (xy 435.961329 -135.664191) (xy 435.905892 -135.670291)
			(xy 435.850158 -135.668254) (xy 435.795315 -135.658124) (xy 435.742531 -135.640117) (xy 435.692931 -135.614616)
			(xy 435.647573 -135.582165) (xy 435.607424 -135.543456) (xy 435.573338 -135.499313) (xy 435.546042 -135.450678)
			(xy 435.526119 -135.398587) (xy 435.513993 -135.34415) (xy 435.509922 -135.288528) (xy 433.793893 -135.288528)
			(xy 433.814133 -135.29144) (xy 433.866423 -135.306798) (xy 433.915996 -135.329442) (xy 433.961842 -135.358909)
			(xy 434.003027 -135.394601) (xy 434.038715 -135.435791) (xy 434.068177 -135.481639) (xy 434.090816 -135.531214)
			(xy 434.106169 -135.583506) (xy 434.113924 -135.63745) (xy 434.113924 -135.69195) (xy 434.106169 -135.745894)
			(xy 434.090816 -135.798186) (xy 434.068177 -135.847761) (xy 434.038715 -135.893609) (xy 434.003027 -135.934799)
			(xy 433.961842 -135.970491) (xy 433.915996 -135.999958) (xy 433.866423 -136.022602) (xy 433.814133 -136.03796)
			(xy 433.76019 -136.045721) (xy 433.73294 -136.04621) (xy 433.702 -136.045601) (xy 433.640931 -136.035612)
			(xy 433.582277 -136.015891) (xy 433.527579 -135.986955) (xy 433.502562 -135.96874) (xy 433.491321 -135.960741)
			(xy 433.465693 -135.950554) (xy 433.438271 -135.94761) (xy 433.411064 -135.952124) (xy 433.386063 -135.963767)
			(xy 433.365099 -135.981685) (xy 433.35702 -135.99287) (xy 433.341708 -136.014642) (xy 433.306079 -136.054183)
			(xy 433.265296 -136.088383) (xy 433.220153 -136.116578) (xy 433.171527 -136.13822) (xy 433.120363 -136.152888)
			(xy 433.067656 -136.160298) (xy 433.041044 -136.160764) (xy 433.013786 -136.160392) (xy 432.959824 -136.152639)
			(xy 432.907515 -136.137285) (xy 432.857923 -136.114643) (xy 432.812059 -136.085172) (xy 432.770857 -136.049475)
			(xy 432.735154 -136.008276) (xy 432.705678 -135.962415) (xy 432.68303 -135.912827) (xy 432.66767 -135.860519)
			(xy 432.659911 -135.806558) (xy 431.887022 -135.806558) (xy 431.874903 -135.820084) (xy 431.832035 -135.855759)
			(xy 431.784429 -135.884813) (xy 431.7331 -135.906625) (xy 431.679143 -135.920731) (xy 431.623706 -135.926831)
			(xy 431.567972 -135.924794) (xy 431.513129 -135.914664) (xy 431.460345 -135.896657) (xy 431.410745 -135.871156)
			(xy 431.365387 -135.838705) (xy 431.325238 -135.799996) (xy 431.291152 -135.755853) (xy 431.263856 -135.707218)
			(xy 431.243933 -135.655127) (xy 431.231807 -135.60069) (xy 431.227736 -135.545068) (xy 429.782825 -135.545068)
			(xy 429.810101 -135.557525) (xy 429.855951 -135.586991) (xy 429.897142 -135.622682) (xy 429.932833 -135.663873)
			(xy 429.962299 -135.709723) (xy 429.984941 -135.7593) (xy 430.000296 -135.811595) (xy 430.008052 -135.865543)
			(xy 430.008538 -135.892794) (xy 430.008015 -135.92101) (xy 429.999731 -135.97683) (xy 429.983312 -136.030819)
			(xy 429.959117 -136.081801) (xy 429.927675 -136.128661) (xy 429.889671 -136.170376) (xy 429.845935 -136.206037)
			(xy 429.797423 -136.234864) (xy 429.745192 -136.256229) (xy 429.690384 -136.269664) (xy 429.662336 -136.272778)
			(xy 429.64796 -136.274645) (xy 429.621005 -136.285266) (xy 429.598123 -136.303038) (xy 429.58116 -136.326525)
			(xy 429.571485 -136.353834) (xy 429.569877 -136.382761) (xy 429.572674 -136.396984) (xy 429.577413 -136.418453)
			(xy 429.582509 -136.462123) (xy 429.582834 -136.484106) (xy 429.582359 -136.51084) (xy 429.574905 -136.563785)
			(xy 429.560129 -136.61517) (xy 429.538321 -136.663988) (xy 429.509909 -136.709281) (xy 429.47545 -136.750163)
			(xy 429.455834 -136.768332) (xy 429.444998 -136.778702) (xy 429.429448 -136.804333) (xy 429.422029 -136.83338)
			(xy 429.423384 -136.863329) (xy 429.433395 -136.891588) (xy 429.441864 -136.903968) (xy 429.459298 -136.928708)
			(xy 429.487011 -136.982509) (xy 429.505885 -137.04001) (xy 429.515448 -137.099769) (xy 429.516032 -137.130028)
			(xy 429.515546 -137.157279) (xy 429.50779 -137.211227) (xy 429.492435 -137.263522) (xy 429.469793 -137.313099)
			(xy 429.440327 -137.358949) (xy 429.404636 -137.40014) (xy 429.363445 -137.435831) (xy 429.317595 -137.465297)
			(xy 429.268018 -137.487939) (xy 429.215723 -137.503294) (xy 429.161775 -137.51105) (xy 429.107273 -137.51105)
			(xy 429.053325 -137.503294) (xy 429.00103 -137.487939) (xy 428.951453 -137.465297) (xy 428.905603 -137.435831)
			(xy 428.864412 -137.40014) (xy 428.828721 -137.358949) (xy 428.799255 -137.313099) (xy 428.776613 -137.263522)
			(xy 428.761258 -137.211227) (xy 428.753502 -137.157279) (xy 428.753016 -137.130028) (xy 428.216568 -137.130028)
			(xy 428.216568 -137.542778) (xy 431.333146 -137.542778) (xy 431.337217 -137.487156) (xy 431.349343 -137.432719)
			(xy 431.369266 -137.380628) (xy 431.396562 -137.331993) (xy 431.430648 -137.28785) (xy 431.470797 -137.249141)
			(xy 431.516155 -137.21669) (xy 431.565755 -137.191189) (xy 431.618539 -137.173182) (xy 431.673382 -137.163052)
			(xy 431.729116 -137.161015) (xy 431.784553 -137.167115) (xy 431.83851 -137.181221) (xy 431.889839 -137.203033)
			(xy 431.937445 -137.232087) (xy 431.980313 -137.267762) (xy 432.01753 -137.309299) (xy 432.048303 -137.355812)
			(xy 432.071975 -137.406309) (xy 432.085293 -137.450576) (xy 433.794406 -137.450576) (xy 433.798477 -137.394954)
			(xy 433.810603 -137.340517) (xy 433.830526 -137.288426) (xy 433.857822 -137.239791) (xy 433.891908 -137.195648)
			(xy 433.932057 -137.156939) (xy 433.977415 -137.124488) (xy 434.027015 -137.098987) (xy 434.079799 -137.08098)
			(xy 434.134642 -137.07085) (xy 434.190376 -137.068813) (xy 434.245813 -137.074913) (xy 434.29977 -137.089019)
			(xy 434.351099 -137.110831) (xy 434.398705 -137.139885) (xy 434.441573 -137.17556) (xy 434.47879 -137.217097)
			(xy 434.509563 -137.26361) (xy 434.533235 -137.314107) (xy 434.549303 -137.367514) (xy 434.557423 -137.42269)
			(xy 434.557932 -137.450576) (xy 434.557423 -137.478462) (xy 434.549303 -137.533638) (xy 434.533235 -137.587045)
			(xy 434.509563 -137.637542) (xy 434.47879 -137.684055) (xy 434.441573 -137.725592) (xy 434.398705 -137.761267)
			(xy 434.351099 -137.790321) (xy 434.29977 -137.812133) (xy 434.245813 -137.826239) (xy 434.190376 -137.832339)
			(xy 434.134642 -137.830302) (xy 434.079799 -137.820172) (xy 434.027015 -137.802165) (xy 433.977415 -137.776664)
			(xy 433.932057 -137.744213) (xy 433.891908 -137.705504) (xy 433.857822 -137.661361) (xy 433.830526 -137.612726)
			(xy 433.810603 -137.560635) (xy 433.798477 -137.506198) (xy 433.794406 -137.450576) (xy 432.085293 -137.450576)
			(xy 432.088043 -137.459716) (xy 432.096163 -137.514892) (xy 432.096672 -137.542778) (xy 432.096163 -137.570664)
			(xy 432.088043 -137.62584) (xy 432.071975 -137.679247) (xy 432.048303 -137.729744) (xy 432.01753 -137.776257)
			(xy 431.980313 -137.817794) (xy 431.937445 -137.853469) (xy 431.889839 -137.882523) (xy 431.83851 -137.904335)
			(xy 431.784553 -137.918441) (xy 431.729116 -137.924541) (xy 431.673382 -137.922504) (xy 431.618539 -137.912374)
			(xy 431.565755 -137.894367) (xy 431.516155 -137.868866) (xy 431.470797 -137.836415) (xy 431.430648 -137.797706)
			(xy 431.396562 -137.753563) (xy 431.369266 -137.704928) (xy 431.349343 -137.652837) (xy 431.337217 -137.5984)
			(xy 431.333146 -137.542778) (xy 428.216568 -137.542778) (xy 428.216568 -138.143996) (xy 428.762158 -138.143996)
			(xy 428.766229 -138.088374) (xy 428.778355 -138.033937) (xy 428.798278 -137.981846) (xy 428.825574 -137.933211)
			(xy 428.85966 -137.889068) (xy 428.899809 -137.850359) (xy 428.945167 -137.817908) (xy 428.994767 -137.792407)
			(xy 429.047551 -137.7744) (xy 429.102394 -137.76427) (xy 429.158128 -137.762233) (xy 429.213565 -137.768333)
			(xy 429.267522 -137.782439) (xy 429.318851 -137.804251) (xy 429.366457 -137.833305) (xy 429.409325 -137.86898)
			(xy 429.446542 -137.910517) (xy 429.477315 -137.95703) (xy 429.500987 -138.007527) (xy 429.517055 -138.060934)
			(xy 429.525175 -138.11611) (xy 429.525684 -138.143996) (xy 429.525175 -138.171882) (xy 429.517055 -138.227058)
			(xy 429.500987 -138.280465) (xy 429.477315 -138.330962) (xy 429.446542 -138.377475) (xy 429.409325 -138.419012)
			(xy 429.366457 -138.454687) (xy 429.318851 -138.483741) (xy 429.267522 -138.505553) (xy 429.213565 -138.519659)
			(xy 429.158128 -138.525759) (xy 429.102394 -138.523722) (xy 429.047551 -138.513592) (xy 428.994767 -138.495585)
			(xy 428.945167 -138.470084) (xy 428.899809 -138.437633) (xy 428.85966 -138.398924) (xy 428.825574 -138.354781)
			(xy 428.798278 -138.306146) (xy 428.778355 -138.254055) (xy 428.766229 -138.199618) (xy 428.762158 -138.143996)
			(xy 428.216568 -138.143996) (xy 428.216568 -138.580876) (xy 428.21592 -138.605871) (xy 428.20612 -138.654894)
			(xy 428.18695 -138.701064) (xy 428.159146 -138.742611) (xy 428.141892 -138.760708) (xy 427.95698 -138.94562)
			(xy 427.93889 -138.962882) (xy 427.897343 -138.99069) (xy 427.85117 -139.009861) (xy 427.802145 -139.019659)
			(xy 427.777148 -139.020296) (xy 423.610786 -139.020296) (xy 422.933114 -139.697968) (xy 423.5229 -139.697968)
			(xy 423.526971 -139.642346) (xy 423.539097 -139.587909) (xy 423.55902 -139.535818) (xy 423.586316 -139.487183)
			(xy 423.620402 -139.44304) (xy 423.660551 -139.404331) (xy 423.705909 -139.37188) (xy 423.755509 -139.346379)
			(xy 423.808293 -139.328372) (xy 423.863136 -139.318242) (xy 423.91887 -139.316205) (xy 423.974307 -139.322305)
			(xy 424.028264 -139.336411) (xy 424.079593 -139.358223) (xy 424.127199 -139.387277) (xy 424.170067 -139.422952)
			(xy 424.207284 -139.464489) (xy 424.238057 -139.511002) (xy 424.261729 -139.561499) (xy 424.277797 -139.614906)
			(xy 424.285917 -139.670082) (xy 424.286426 -139.697968) (xy 424.286092 -139.716256) (xy 432.257706 -139.716256)
			(xy 432.261777 -139.660634) (xy 432.273903 -139.606197) (xy 432.293826 -139.554106) (xy 432.321122 -139.505471)
			(xy 432.355208 -139.461328) (xy 432.395357 -139.422619) (xy 432.440715 -139.390168) (xy 432.490315 -139.364667)
			(xy 432.543099 -139.34666) (xy 432.597942 -139.33653) (xy 432.653676 -139.334493) (xy 432.709113 -139.340593)
			(xy 432.76307 -139.354699) (xy 432.814399 -139.376511) (xy 432.862005 -139.405565) (xy 432.904873 -139.44124)
			(xy 432.94209 -139.482777) (xy 432.972863 -139.52929) (xy 432.996535 -139.579787) (xy 433.012603 -139.633194)
			(xy 433.020723 -139.68837) (xy 433.021232 -139.716256) (xy 433.020723 -139.744142) (xy 433.012603 -139.799318)
			(xy 432.996535 -139.852725) (xy 432.972863 -139.903222) (xy 432.94209 -139.949735) (xy 432.904873 -139.991272)
			(xy 432.862005 -140.026947) (xy 432.814399 -140.056001) (xy 432.76307 -140.077813) (xy 432.709113 -140.091919)
			(xy 432.653676 -140.098019) (xy 432.597942 -140.095982) (xy 432.543099 -140.085852) (xy 432.490315 -140.067845)
			(xy 432.440715 -140.042344) (xy 432.395357 -140.009893) (xy 432.355208 -139.971184) (xy 432.321122 -139.927041)
			(xy 432.293826 -139.878406) (xy 432.273903 -139.826315) (xy 432.261777 -139.771878) (xy 432.257706 -139.716256)
			(xy 424.286092 -139.716256) (xy 424.285917 -139.725854) (xy 424.277797 -139.78103) (xy 424.261729 -139.834437)
			(xy 424.238057 -139.884934) (xy 424.207284 -139.931447) (xy 424.170067 -139.972984) (xy 424.127199 -140.008659)
			(xy 424.079593 -140.037713) (xy 424.028264 -140.059525) (xy 423.974307 -140.073631) (xy 423.91887 -140.079731)
			(xy 423.863136 -140.077694) (xy 423.808293 -140.067564) (xy 423.755509 -140.049557) (xy 423.705909 -140.024056)
			(xy 423.660551 -139.991605) (xy 423.620402 -139.952896) (xy 423.586316 -139.908753) (xy 423.55902 -139.860118)
			(xy 423.539097 -139.808027) (xy 423.526971 -139.75359) (xy 423.5229 -139.697968) (xy 422.933114 -139.697968)
			(xy 422.366694 -140.264388) (xy 426.322996 -140.264388) (xy 426.327067 -140.208766) (xy 426.339193 -140.154329)
			(xy 426.359116 -140.102238) (xy 426.386412 -140.053603) (xy 426.420498 -140.00946) (xy 426.460647 -139.970751)
			(xy 426.506005 -139.9383) (xy 426.555605 -139.912799) (xy 426.608389 -139.894792) (xy 426.663232 -139.884662)
			(xy 426.718966 -139.882625) (xy 426.774403 -139.888725) (xy 426.82836 -139.902831) (xy 426.879689 -139.924643)
			(xy 426.927295 -139.953697) (xy 426.970163 -139.989372) (xy 427.00738 -140.030909) (xy 427.038153 -140.077422)
			(xy 427.061825 -140.127919) (xy 427.077893 -140.181326) (xy 427.086013 -140.236502) (xy 427.086522 -140.264388)
			(xy 427.086013 -140.292274) (xy 427.077893 -140.34745) (xy 427.061825 -140.400857) (xy 427.038153 -140.451354)
			(xy 427.00738 -140.497867) (xy 426.970163 -140.539404) (xy 426.927295 -140.575079) (xy 426.879689 -140.604133)
			(xy 426.82836 -140.625945) (xy 426.774403 -140.640051) (xy 426.718966 -140.646151) (xy 426.663232 -140.644114)
			(xy 426.608389 -140.633984) (xy 426.555605 -140.615977) (xy 426.506005 -140.590476) (xy 426.460647 -140.558025)
			(xy 426.420498 -140.519316) (xy 426.386412 -140.475173) (xy 426.359116 -140.426538) (xy 426.339193 -140.374447)
			(xy 426.327067 -140.32001) (xy 426.322996 -140.264388) (xy 422.366694 -140.264388) (xy 421.879268 -140.751814)
			(xy 421.879268 -141.026453) (xy 422.148465 -141.026453) (xy 422.148465 -140.971947) (xy 422.156222 -140.917997)
			(xy 422.171578 -140.8657) (xy 422.194221 -140.816121) (xy 422.223689 -140.770269) (xy 422.259382 -140.729077)
			(xy 422.300575 -140.693384) (xy 422.346428 -140.663917) (xy 422.396008 -140.641276) (xy 422.448305 -140.625921)
			(xy 422.502255 -140.618165) (xy 422.529508 -140.617702) (xy 422.555887 -140.618166) (xy 422.608144 -140.625419)
			(xy 422.658903 -140.639801) (xy 422.707198 -140.661037) (xy 422.752108 -140.688722) (xy 422.792777 -140.722329)
			(xy 422.82843 -140.761217) (xy 422.858387 -140.804644) (xy 422.87063 -140.828014) (xy 422.877332 -140.840373)
			(xy 422.896307 -140.861101) (xy 422.920221 -140.875863) (xy 422.947257 -140.883535) (xy 422.975359 -140.883535)
			(xy 423.002395 -140.875863) (xy 423.026309 -140.861101) (xy 423.045284 -140.840373) (xy 423.051986 -140.828014)
			(xy 423.064228 -140.804644) (xy 423.094189 -140.761219) (xy 423.129844 -140.722332) (xy 423.170513 -140.688725)
			(xy 423.215422 -140.661038) (xy 423.263715 -140.639798) (xy 423.314473 -140.62541) (xy 423.366729 -140.618147)
			(xy 423.393108 -140.617702) (xy 423.42036 -140.618168) (xy 423.474308 -140.625926) (xy 423.526603 -140.641282)
			(xy 423.576181 -140.663924) (xy 423.622031 -140.693392) (xy 423.663222 -140.729084) (xy 423.698913 -140.770275)
			(xy 423.728379 -140.816126) (xy 423.751021 -140.865704) (xy 423.766376 -140.918) (xy 423.774132 -140.971948)
			(xy 423.774132 -141.026452) (xy 423.766376 -141.0804) (xy 423.751021 -141.132696) (xy 423.728379 -141.182274)
			(xy 423.698913 -141.228125) (xy 423.663222 -141.269316) (xy 423.622031 -141.305008) (xy 423.576181 -141.334476)
			(xy 423.526603 -141.357118) (xy 423.474308 -141.372474) (xy 423.42036 -141.380232) (xy 423.393108 -141.380718)
			(xy 423.36673 -141.38023) (xy 423.314475 -141.372979) (xy 423.263716 -141.3586) (xy 423.215422 -141.337367)
			(xy 423.170512 -141.309686) (xy 423.129843 -141.276083) (xy 423.094189 -141.237198) (xy 423.06423 -141.193774)
			(xy 423.051986 -141.170406) (xy 423.045284 -141.158047) (xy 423.026309 -141.137319) (xy 423.002395 -141.122557)
			(xy 422.975359 -141.114885) (xy 422.947257 -141.114885) (xy 422.920221 -141.122557) (xy 422.896307 -141.137319)
			(xy 422.877332 -141.158047) (xy 422.87063 -141.170406) (xy 422.858385 -141.193774) (xy 422.828423 -141.237198)
			(xy 422.792768 -141.276084) (xy 422.752099 -141.30969) (xy 422.707191 -141.337377) (xy 422.658899 -141.358618)
			(xy 422.608141 -141.373008) (xy 422.555887 -141.380272) (xy 422.529508 -141.380718) (xy 422.502255 -141.380235)
			(xy 422.448305 -141.372479) (xy 422.396008 -141.357124) (xy 422.346428 -141.334483) (xy 422.300575 -141.305016)
			(xy 422.259382 -141.269323) (xy 422.223689 -141.228131) (xy 422.194221 -141.182279) (xy 422.171578 -141.1327)
			(xy 422.156222 -141.080403) (xy 422.148465 -141.026453) (xy 421.879268 -141.026453) (xy 421.879268 -141.415008)
			(xy 426.048422 -141.415008) (xy 426.052493 -141.359386) (xy 426.064619 -141.304949) (xy 426.084542 -141.252858)
			(xy 426.111838 -141.204223) (xy 426.145924 -141.16008) (xy 426.186073 -141.121371) (xy 426.231431 -141.08892)
			(xy 426.281031 -141.063419) (xy 426.333815 -141.045412) (xy 426.388658 -141.035282) (xy 426.444392 -141.033245)
			(xy 426.499829 -141.039345) (xy 426.553786 -141.053451) (xy 426.605115 -141.075263) (xy 426.652721 -141.104317)
			(xy 426.695589 -141.139992) (xy 426.721474 -141.168882) (xy 431.19116 -141.168882) (xy 431.195231 -141.11326)
			(xy 431.207357 -141.058823) (xy 431.22728 -141.006732) (xy 431.254576 -140.958097) (xy 431.288662 -140.913954)
			(xy 431.328811 -140.875245) (xy 431.374169 -140.842794) (xy 431.423769 -140.817293) (xy 431.476553 -140.799286)
			(xy 431.531396 -140.789156) (xy 431.58713 -140.787119) (xy 431.642567 -140.793219) (xy 431.696524 -140.807325)
			(xy 431.747853 -140.829137) (xy 431.795459 -140.858191) (xy 431.838327 -140.893866) (xy 431.875544 -140.935403)
			(xy 431.906317 -140.981916) (xy 431.929989 -141.032413) (xy 431.946057 -141.08582) (xy 431.954177 -141.140996)
			(xy 431.954686 -141.168882) (xy 431.954177 -141.196768) (xy 431.946057 -141.251944) (xy 431.929989 -141.305351)
			(xy 431.906317 -141.355848) (xy 431.875544 -141.402361) (xy 431.838327 -141.443898) (xy 431.795459 -141.479573)
			(xy 431.747853 -141.508627) (xy 431.696524 -141.530439) (xy 431.642567 -141.544545) (xy 431.58713 -141.550645)
			(xy 431.531396 -141.548608) (xy 431.476553 -141.538478) (xy 431.423769 -141.520471) (xy 431.374169 -141.49497)
			(xy 431.328811 -141.462519) (xy 431.288662 -141.42381) (xy 431.254576 -141.379667) (xy 431.22728 -141.331032)
			(xy 431.207357 -141.278941) (xy 431.195231 -141.224504) (xy 431.19116 -141.168882) (xy 426.721474 -141.168882)
			(xy 426.732806 -141.181529) (xy 426.763579 -141.228042) (xy 426.787251 -141.278539) (xy 426.803319 -141.331946)
			(xy 426.811439 -141.387122) (xy 426.811948 -141.415008) (xy 426.811439 -141.442894) (xy 426.803319 -141.49807)
			(xy 426.787251 -141.551477) (xy 426.763579 -141.601974) (xy 426.732806 -141.648487) (xy 426.695589 -141.690024)
			(xy 426.652721 -141.725699) (xy 426.605115 -141.754753) (xy 426.553786 -141.776565) (xy 426.499829 -141.790671)
			(xy 426.444392 -141.796771) (xy 426.388658 -141.794734) (xy 426.333815 -141.784604) (xy 426.281031 -141.766597)
			(xy 426.231431 -141.741096) (xy 426.186073 -141.708645) (xy 426.145924 -141.669936) (xy 426.111838 -141.625793)
			(xy 426.084542 -141.577158) (xy 426.064619 -141.525067) (xy 426.052493 -141.47063) (xy 426.048422 -141.415008)
			(xy 421.879268 -141.415008) (xy 421.879268 -144.555718) (xy 422.85793 -145.53438) (xy 430.20742 -145.53438)
			(xy 430.232418 -145.534987) (xy 430.281443 -145.544798) (xy 430.327613 -145.56398) (xy 430.369158 -145.591796)
			(xy 430.387252 -145.609056) (xy 431.710592 -146.932396) (xy 431.727838 -146.950501) (xy 431.75565 -146.992042)
			(xy 431.774826 -147.038211) (xy 431.784629 -147.087233) (xy 431.785268 -147.112228) (xy 431.785268 -149.967188)
			(xy 431.784627 -149.992184) (xy 431.774825 -150.041206) (xy 431.755653 -150.087377) (xy 431.727846 -150.128924)
			(xy 431.710592 -150.14702) (xy 426.687488 -155.170378) (xy 426.687488 -156.31414) (xy 426.688065 -156.328929)
			(xy 426.696553 -156.357263) (xy 426.712806 -156.381976) (xy 426.735459 -156.400994) (xy 426.762612 -156.412722)
			(xy 426.791988 -156.416176) (xy 426.821122 -156.411067) (xy 426.847568 -156.397822) (xy 426.858684 -156.388054)
			(xy 426.88874 -156.360332) (xy 426.95322 -156.310045) (xy 427.022162 -156.266074) (xy 427.094949 -156.228812)
			(xy 427.170931 -156.198593) (xy 427.249428 -156.175688) (xy 427.329738 -156.1603) (xy 427.411143 -156.152569)
			(xy 427.452028 -156.152088) (xy 427.493166 -156.152587) (xy 427.57507 -156.16041) (xy 427.655859 -156.175983)
			(xy 427.734802 -156.199165) (xy 427.811184 -156.229746) (xy 427.884313 -156.267449) (xy 427.953528 -156.311932)
			(xy 428.0182 -156.362793) (xy 428.077745 -156.419572) (xy 428.131624 -156.481753) (xy 428.179348 -156.548774)
			(xy 428.220486 -156.620028) (xy 428.254664 -156.694869) (xy 428.281573 -156.772621) (xy 428.30097 -156.852578)
			(xy 428.312679 -156.934017) (xy 428.316594 -157.0162) (xy 428.312679 -157.098383) (xy 428.30097 -157.179822)
			(xy 428.281573 -157.259779) (xy 428.254664 -157.337531) (xy 428.220486 -157.412372) (xy 428.179348 -157.483626)
			(xy 428.131624 -157.550647) (xy 428.077745 -157.612828) (xy 428.0182 -157.669607) (xy 427.953528 -157.720468)
			(xy 427.884313 -157.764951) (xy 427.811184 -157.802654) (xy 427.734802 -157.833235) (xy 427.655859 -157.856417)
			(xy 427.57507 -157.87199) (xy 427.493166 -157.879813) (xy 427.452028 -157.880304) (xy 427.411141 -157.879845)
			(xy 427.329731 -157.872127) (xy 427.249416 -157.856748) (xy 427.170915 -157.833846) (xy 427.094929 -157.803626)
			(xy 427.022141 -157.766358) (xy 426.953201 -157.722377) (xy 426.888728 -157.672076) (xy 426.858684 -157.644338)
			(xy 426.84755 -157.634574) (xy 426.8211 -157.621293) (xy 426.791952 -157.616157) (xy 426.762556 -157.619599)
			(xy 426.735382 -157.631329) (xy 426.712715 -157.650361) (xy 426.696461 -157.675095) (xy 426.687985 -157.703453)
			(xy 426.687488 -157.718252) (xy 426.687488 -158.046928) (xy 426.686866 -158.071925) (xy 426.677057 -158.120948)
			(xy 426.657879 -158.167118) (xy 426.630068 -158.208664) (xy 426.612812 -158.22676) (xy 425.281084 -159.558666)
			(xy 426.563024 -159.558666) (xy 426.563024 -159.47397) (xy 426.571075 -159.389656) (xy 426.587104 -159.30649)
			(xy 426.610965 -159.225223) (xy 426.642444 -159.146593) (xy 426.681255 -159.071312) (xy 426.727045 -159.00006)
			(xy 426.779401 -158.933484) (xy 426.837849 -158.872186) (xy 426.901859 -158.816721) (xy 426.970851 -158.767592)
			(xy 427.044201 -158.725243) (xy 427.121244 -158.690059) (xy 427.201283 -158.662357) (xy 427.283592 -158.642389)
			(xy 427.367427 -158.630336) (xy 427.452028 -158.626306) (xy 427.536629 -158.630336) (xy 427.620464 -158.642389)
			(xy 427.702773 -158.662357) (xy 427.782812 -158.690059) (xy 427.859855 -158.725243) (xy 427.933205 -158.767592)
			(xy 428.002197 -158.816721) (xy 428.066207 -158.872186) (xy 428.124655 -158.933484) (xy 428.177011 -159.00006)
			(xy 428.222801 -159.071312) (xy 428.261612 -159.146593) (xy 428.293091 -159.225223) (xy 428.316952 -159.30649)
			(xy 428.332981 -159.389656) (xy 428.341032 -159.47397) (xy 428.341536 -159.516318) (xy 428.341032 -159.558666)
			(xy 428.332981 -159.64298) (xy 428.316952 -159.726146) (xy 428.293091 -159.807413) (xy 428.261612 -159.886043)
			(xy 428.222801 -159.961324) (xy 428.177011 -160.032576) (xy 428.124655 -160.099152) (xy 428.066207 -160.16045)
			(xy 428.002197 -160.215915) (xy 427.933205 -160.265044) (xy 427.859855 -160.307393) (xy 427.782812 -160.342577)
			(xy 427.702773 -160.370279) (xy 427.620464 -160.390247) (xy 427.536629 -160.4023) (xy 427.452028 -160.406331)
			(xy 427.367427 -160.4023) (xy 427.283592 -160.390247) (xy 427.201283 -160.370279) (xy 427.121244 -160.342577)
			(xy 427.044201 -160.307393) (xy 426.970851 -160.265044) (xy 426.901859 -160.215915) (xy 426.837849 -160.16045)
			(xy 426.779401 -160.099152) (xy 426.727045 -160.032576) (xy 426.681255 -159.961324) (xy 426.642444 -159.886043)
			(xy 426.610965 -159.807413) (xy 426.587104 -159.726146) (xy 426.571075 -159.64298) (xy 426.563024 -159.558666)
			(xy 425.281084 -159.558666) (xy 424.713908 -160.125918) (xy 424.713908 -163.170616) (xy 425.480988 -163.170616)
			(xy 425.48147 -163.143364) (xy 425.489225 -163.089414) (xy 425.504579 -163.037116) (xy 425.527219 -162.987537)
			(xy 425.556685 -162.941684) (xy 425.592377 -162.900491) (xy 425.633568 -162.864797) (xy 425.679419 -162.835329)
			(xy 425.728998 -162.812686) (xy 425.781294 -162.797329) (xy 425.835244 -162.789572) (xy 425.862496 -162.789108)
			(xy 425.890642 -162.789598) (xy 425.946324 -162.797875) (xy 426.000186 -162.814237) (xy 426.051064 -162.838327)
			(xy 426.097854 -162.869626) (xy 426.119036 -162.888168) (xy 426.130841 -162.8982) (xy 426.15893 -162.911235)
			(xy 426.189633 -162.915257) (xy 426.220131 -162.909897) (xy 426.247624 -162.895647) (xy 426.25899 -162.88512)
			(xy 426.280551 -162.864437) (xy 426.328964 -162.829427) (xy 426.382244 -162.802395) (xy 426.439087 -162.784001)
			(xy 426.498103 -162.774696) (xy 426.527976 -162.774122) (xy 426.556122 -162.77462) (xy 426.611803 -162.782895)
			(xy 426.665666 -162.799254) (xy 426.716544 -162.823343) (xy 426.763334 -162.85464) (xy 426.784516 -162.873182)
			(xy 426.796337 -162.883193) (xy 426.82442 -162.896228) (xy 426.855118 -162.900253) (xy 426.885612 -162.894899)
			(xy 426.913103 -162.880657) (xy 426.92447 -162.870134) (xy 426.946042 -162.849463) (xy 426.994452 -162.814451)
			(xy 427.047729 -162.787416) (xy 427.10457 -162.76902) (xy 427.163584 -162.759712) (xy 427.193456 -162.759136)
			(xy 427.22071 -162.759596) (xy 427.274663 -162.767348) (xy 427.326964 -162.782701) (xy 427.376547 -162.805342)
			(xy 427.422402 -162.834809) (xy 427.463596 -162.870504) (xy 427.499291 -162.911698) (xy 427.528758 -162.957553)
			(xy 427.551399 -163.007136) (xy 427.566752 -163.059437) (xy 427.574504 -163.11339) (xy 427.574964 -163.140644)
			(xy 427.57445 -163.169383) (xy 427.565822 -163.22621) (xy 427.548769 -163.2811) (xy 427.523676 -163.332812)
			(xy 427.49111 -163.380175) (xy 427.47184 -163.401502) (xy 427.461724 -163.413001) (xy 427.448385 -163.44056)
			(xy 427.443809 -163.470832) (xy 427.448405 -163.501102) (xy 427.461761 -163.528652) (xy 427.47184 -163.540186)
			(xy 427.491156 -163.561474) (xy 427.523723 -163.608842) (xy 427.548814 -163.66056) (xy 427.565863 -163.715457)
			(xy 427.574482 -163.77229) (xy 427.574477 -163.829774) (xy 427.565849 -163.886606) (xy 427.548791 -163.9415)
			(xy 427.52369 -163.993213) (xy 427.491116 -164.040576) (xy 427.47184 -164.061902) (xy 427.461724 -164.073401)
			(xy 427.448385 -164.10096) (xy 427.443809 -164.131232) (xy 427.448405 -164.161502) (xy 427.461761 -164.189052)
			(xy 427.47184 -164.200586) (xy 427.491156 -164.221874) (xy 427.523723 -164.269242) (xy 427.548814 -164.32096)
			(xy 427.565863 -164.375857) (xy 427.574482 -164.43269) (xy 427.574477 -164.490174) (xy 427.565849 -164.547006)
			(xy 427.548791 -164.6019) (xy 427.52369 -164.653613) (xy 427.491116 -164.700976) (xy 427.47184 -164.722302)
			(xy 427.461724 -164.733801) (xy 427.448385 -164.76136) (xy 427.443809 -164.791632) (xy 427.448405 -164.821902)
			(xy 427.461761 -164.849452) (xy 427.47184 -164.860986) (xy 427.491156 -164.882274) (xy 427.523723 -164.929642)
			(xy 427.548814 -164.98136) (xy 427.565863 -165.036257) (xy 427.574482 -165.09309) (xy 427.574477 -165.150574)
			(xy 427.565849 -165.207406) (xy 427.548791 -165.2623) (xy 427.52369 -165.314013) (xy 427.491116 -165.361376)
			(xy 427.47184 -165.382702) (xy 427.461724 -165.394201) (xy 427.448385 -165.42176) (xy 427.443809 -165.452032)
			(xy 427.448405 -165.482302) (xy 427.461761 -165.509852) (xy 427.47184 -165.521386) (xy 427.491156 -165.542674)
			(xy 427.523723 -165.590042) (xy 427.548814 -165.64176) (xy 427.565863 -165.696657) (xy 427.574482 -165.75349)
			(xy 427.574477 -165.810974) (xy 427.565849 -165.867806) (xy 427.548791 -165.9227) (xy 427.52369 -165.974413)
			(xy 427.491116 -166.021776) (xy 427.47184 -166.043102) (xy 427.461724 -166.054601) (xy 427.448385 -166.08216)
			(xy 427.443809 -166.112432) (xy 427.448405 -166.142702) (xy 427.461761 -166.170252) (xy 427.47184 -166.181786)
			(xy 427.491128 -166.203098) (xy 427.523693 -166.250464) (xy 427.548782 -166.302179) (xy 427.565829 -166.357073)
			(xy 427.574446 -166.413904) (xy 427.57457 -166.4208) (xy 430.96942 -166.4208) (xy 430.969965 -166.392062)
			(xy 430.978586 -166.335237) (xy 430.995632 -166.280347) (xy 431.020718 -166.228635) (xy 431.053277 -166.181271)
			(xy 431.072544 -166.159942) (xy 431.082618 -166.148409) (xy 431.095963 -166.120863) (xy 431.100549 -166.0906)
			(xy 431.095963 -166.060337) (xy 431.082618 -166.032791) (xy 431.072544 -166.021258) (xy 431.053272 -165.999932)
			(xy 431.020705 -165.95257) (xy 430.995612 -165.900858) (xy 430.978561 -165.845967) (xy 430.969938 -165.789139)
			(xy 430.969938 -165.731661) (xy 430.978561 -165.674833) (xy 430.995612 -165.619942) (xy 431.020705 -165.56823)
			(xy 431.053272 -165.520868) (xy 431.072544 -165.499542) (xy 431.082618 -165.488009) (xy 431.095963 -165.460463)
			(xy 431.100549 -165.4302) (xy 431.095963 -165.399937) (xy 431.082618 -165.372391) (xy 431.072544 -165.360858)
			(xy 431.053272 -165.339532) (xy 431.020705 -165.29217) (xy 430.995612 -165.240458) (xy 430.978561 -165.185567)
			(xy 430.969938 -165.128739) (xy 430.969938 -165.071261) (xy 430.978561 -165.014433) (xy 430.995612 -164.959542)
			(xy 431.020705 -164.90783) (xy 431.053272 -164.860468) (xy 431.072544 -164.839142) (xy 431.082618 -164.827609)
			(xy 431.095963 -164.800063) (xy 431.100549 -164.7698) (xy 431.095963 -164.739537) (xy 431.082618 -164.711991)
			(xy 431.072544 -164.700458) (xy 431.053272 -164.679132) (xy 431.020705 -164.63177) (xy 430.995612 -164.580058)
			(xy 430.978561 -164.525167) (xy 430.969938 -164.468339) (xy 430.969938 -164.410861) (xy 430.978561 -164.354033)
			(xy 430.995612 -164.299142) (xy 431.020705 -164.24743) (xy 431.053272 -164.200068) (xy 431.072544 -164.178742)
			(xy 431.082618 -164.167209) (xy 431.095963 -164.139663) (xy 431.100549 -164.1094) (xy 431.095963 -164.079137)
			(xy 431.082618 -164.051591) (xy 431.072544 -164.040058) (xy 431.053274 -164.01873) (xy 431.020708 -163.971368)
			(xy 430.995615 -163.919657) (xy 430.978564 -163.864766) (xy 430.969941 -163.807939) (xy 430.96942 -163.7792)
			(xy 430.96983 -163.753378) (xy 430.976782 -163.702204) (xy 430.990572 -163.652435) (xy 431.010949 -163.604981)
			(xy 431.037539 -163.560709) (xy 431.069858 -163.520427) (xy 431.088292 -163.50234) (xy 431.09798 -163.492559)
			(xy 431.112152 -163.468967) (xy 431.119503 -163.442447) (xy 431.1195 -163.414926) (xy 431.112141 -163.388407)
			(xy 431.097962 -163.36482) (xy 431.088292 -163.35502) (xy 431.069869 -163.336925) (xy 431.037565 -163.296636)
			(xy 431.010985 -163.252362) (xy 430.990611 -163.204911) (xy 430.976815 -163.155148) (xy 430.96985 -163.10398)
			(xy 430.96942 -163.07816) (xy 430.969941 -163.049421) (xy 430.978567 -162.992595) (xy 430.995619 -162.937705)
			(xy 431.020711 -162.885993) (xy 431.053274 -162.83863) (xy 431.072544 -162.817302) (xy 431.082657 -162.8058)
			(xy 431.095999 -162.778243) (xy 431.100577 -162.747971) (xy 431.095981 -162.717701) (xy 431.082624 -162.690151)
			(xy 431.072544 -162.678618) (xy 431.053255 -162.657306) (xy 431.020691 -162.60994) (xy 430.995602 -162.558225)
			(xy 430.978556 -162.503331) (xy 430.969938 -162.4465) (xy 430.96942 -162.41776) (xy 430.969841 -162.390506)
			(xy 430.977603 -162.336555) (xy 430.992965 -162.284257) (xy 431.015613 -162.234678) (xy 431.045086 -162.188827)
			(xy 431.080784 -162.147636) (xy 431.121981 -162.111945) (xy 431.167838 -162.08248) (xy 431.217421 -162.059841)
			(xy 431.269722 -162.044489) (xy 431.323674 -162.036736) (xy 431.350928 -162.036252) (xy 431.379073 -162.036771)
			(xy 431.434754 -162.04504) (xy 431.488617 -162.061394) (xy 431.539495 -162.085478) (xy 431.586286 -162.116772)
			(xy 431.607468 -162.135312) (xy 431.619251 -162.145371) (xy 431.647348 -162.158396) (xy 431.678057 -162.16241)
			(xy 431.708558 -162.157044) (xy 431.736054 -162.142792) (xy 431.747422 -162.132264) (xy 431.76902 -162.111621)
			(xy 431.817422 -162.076604) (xy 431.870692 -162.049563) (xy 431.927528 -162.031161) (xy 431.986538 -162.021846)
			(xy 432.016408 -162.021266) (xy 432.045147 -162.021794) (xy 432.101973 -162.030417) (xy 432.156864 -162.047466)
			(xy 432.208576 -162.072557) (xy 432.255939 -162.10512) (xy 432.277266 -162.12439) (xy 432.2888 -162.134462)
			(xy 432.316346 -162.147804) (xy 432.346608 -162.152389) (xy 432.37687 -162.147804) (xy 432.404416 -162.134462)
			(xy 432.41595 -162.12439) (xy 432.437282 -162.105124) (xy 432.484642 -162.072556) (xy 432.536352 -162.047461)
			(xy 432.591242 -162.03041) (xy 432.648069 -162.021787) (xy 432.676808 -162.021266) (xy 432.704058 -162.02177)
			(xy 432.758004 -162.029527) (xy 432.810297 -162.044882) (xy 432.859872 -162.067522) (xy 432.905721 -162.096987)
			(xy 432.946911 -162.132676) (xy 432.982602 -162.173864) (xy 433.012069 -162.219712) (xy 433.034712 -162.269286)
			(xy 433.050069 -162.321578) (xy 433.057828 -162.375524) (xy 433.058316 -162.402774) (xy 433.057772 -162.431512)
			(xy 433.049154 -162.488338) (xy 433.032108 -162.543229) (xy 433.007021 -162.594941) (xy 432.974461 -162.642304)
			(xy 432.955192 -162.663632) (xy 432.945149 -162.675188) (xy 432.931809 -162.702727) (xy 432.927221 -162.732981)
			(xy 432.931798 -162.763237) (xy 432.945127 -162.790781) (xy 432.955192 -162.802316) (xy 432.974455 -162.823649)
			(xy 433.007022 -162.87101) (xy 433.032115 -162.92272) (xy 433.049167 -162.977609) (xy 433.057793 -163.034436)
			(xy 433.058316 -163.063174) (xy 433.057878 -163.088995) (xy 433.05093 -163.140167) (xy 433.037145 -163.189935)
			(xy 433.016773 -163.237389) (xy 432.990188 -163.281662) (xy 432.957875 -163.321945) (xy 432.939444 -163.340034)
			(xy 432.92978 -163.349838) (xy 432.915601 -163.373422) (xy 432.908243 -163.399937) (xy 432.908242 -163.427455)
			(xy 432.915598 -163.453971) (xy 432.929774 -163.477556) (xy 432.939444 -163.487354) (xy 432.957891 -163.505427)
			(xy 432.990194 -163.545719) (xy 433.016773 -163.589997) (xy 433.037143 -163.637453) (xy 433.050933 -163.68722)
			(xy 433.05789 -163.738393) (xy 433.058316 -163.764214) (xy 433.057796 -163.792953) (xy 433.049172 -163.84978)
			(xy 433.032121 -163.904671) (xy 433.007029 -163.956383) (xy 432.974463 -164.003745) (xy 432.955192 -164.025072)
			(xy 432.94511 -164.036597) (xy 432.931774 -164.064147) (xy 432.927194 -164.09441) (xy 432.93178 -164.124673)
			(xy 432.945121 -164.15222) (xy 432.955192 -164.163756) (xy 432.974476 -164.185071) (xy 433.007039 -164.232436)
			(xy 433.032129 -164.28415) (xy 433.049177 -164.339042) (xy 433.057798 -164.395871) (xy 433.057797 -164.45335)
			(xy 433.049173 -164.510178) (xy 433.032122 -164.565069) (xy 433.007029 -164.616782) (xy 432.974463 -164.664145)
			(xy 432.955192 -164.685472) (xy 432.94511 -164.696997) (xy 432.931774 -164.724547) (xy 432.927194 -164.75481)
			(xy 432.93178 -164.785073) (xy 432.945121 -164.81262) (xy 432.955192 -164.824156) (xy 432.974476 -164.845471)
			(xy 433.007039 -164.892836) (xy 433.032129 -164.94455) (xy 433.049177 -164.999442) (xy 433.057798 -165.056271)
			(xy 433.057797 -165.11375) (xy 433.049173 -165.170578) (xy 433.032122 -165.225469) (xy 433.007029 -165.277182)
			(xy 432.974463 -165.324545) (xy 432.955192 -165.345872) (xy 432.94511 -165.357397) (xy 432.931774 -165.384947)
			(xy 432.927194 -165.41521) (xy 432.93178 -165.445473) (xy 432.945121 -165.47302) (xy 432.955192 -165.484556)
			(xy 432.974474 -165.505873) (xy 433.007038 -165.553238) (xy 433.032128 -165.604952) (xy 433.049176 -165.659845)
			(xy 433.057796 -165.716674) (xy 433.058316 -165.745414) (xy 433.057835 -165.772665) (xy 433.050077 -165.826613)
			(xy 433.034721 -165.878907) (xy 433.012078 -165.928484) (xy 432.982611 -165.974334) (xy 432.946919 -166.015524)
			(xy 432.905729 -166.051215) (xy 432.859879 -166.080681) (xy 432.810301 -166.103323) (xy 432.758007 -166.118678)
			(xy 432.704059 -166.126436) (xy 432.676808 -166.126922) (xy 432.649163 -166.126403) (xy 432.594453 -166.118406)
			(xy 432.541471 -166.102593) (xy 432.491328 -166.079296) (xy 432.445074 -166.049002) (xy 432.40368 -166.012347)
			(xy 432.38547 -165.99154) (xy 432.377861 -165.983437) (xy 432.35771 -165.974116) (xy 432.335506 -165.974116)
			(xy 432.315355 -165.983437) (xy 432.307746 -165.99154) (xy 432.294792 -166.006272) (xy 432.28471 -166.017797)
			(xy 432.271374 -166.045347) (xy 432.266794 -166.07561) (xy 432.27138 -166.105873) (xy 432.284721 -166.13342)
			(xy 432.294792 -166.144956) (xy 432.314074 -166.166273) (xy 432.346638 -166.213638) (xy 432.371728 -166.265352)
			(xy 432.388776 -166.320245) (xy 432.397396 -166.377074) (xy 432.397916 -166.405814) (xy 432.397371 -166.4341)
			(xy 432.389016 -166.490053) (xy 432.372492 -166.544159) (xy 432.34816 -166.595232) (xy 432.316555 -166.642153)
			(xy 432.29784 -166.66337) (xy 432.28775 -166.675307) (xy 432.274637 -166.703659) (xy 432.270696 -166.734646)
			(xy 432.276295 -166.765378) (xy 432.290912 -166.792984) (xy 432.30165 -166.80434) (xy 432.322827 -166.826023)
			(xy 432.358792 -166.874803) (xy 432.386591 -166.928657) (xy 432.405522 -166.98623) (xy 432.415111 -167.046071)
			(xy 432.415696 -167.076374) (xy 432.41522 -167.103627) (xy 432.407467 -167.157578) (xy 432.392113 -167.209876)
			(xy 432.369473 -167.259457) (xy 432.340007 -167.305311) (xy 432.304314 -167.346504) (xy 432.263122 -167.382198)
			(xy 432.217269 -167.411666) (xy 432.167689 -167.434308) (xy 432.115392 -167.449664) (xy 432.061441 -167.457419)
			(xy 432.034188 -167.457882) (xy 432.006043 -167.457345) (xy 431.950364 -167.449079) (xy 431.896502 -167.432729)
			(xy 431.845623 -167.408649) (xy 431.798831 -167.37736) (xy 431.777648 -167.358822) (xy 431.765855 -167.348775)
			(xy 431.737762 -167.335744) (xy 431.707055 -167.331725) (xy 431.676555 -167.337089) (xy 431.649061 -167.351341)
			(xy 431.637694 -167.36187) (xy 431.616095 -167.382511) (xy 431.567692 -167.417527) (xy 431.514422 -167.444567)
			(xy 431.457587 -167.462971) (xy 431.398578 -167.472287) (xy 431.368708 -167.472868) (xy 431.341454 -167.472437)
			(xy 431.287499 -167.46468) (xy 431.235198 -167.449323) (xy 431.185616 -167.426679) (xy 431.139761 -167.397208)
			(xy 431.098567 -167.361511) (xy 431.062873 -167.320314) (xy 431.033406 -167.274456) (xy 431.010766 -167.224872)
			(xy 430.995413 -167.172569) (xy 430.987661 -167.118615) (xy 430.9872 -167.09136) (xy 430.987726 -167.063073)
			(xy 430.996085 -167.007119) (xy 431.012613 -166.953013) (xy 431.036949 -166.90194) (xy 431.068559 -166.85502)
			(xy 431.087276 -166.833804) (xy 431.09739 -166.821886) (xy 431.110498 -166.793527) (xy 431.114434 -166.762534)
			(xy 431.108828 -166.7318) (xy 431.094206 -166.704191) (xy 431.083466 -166.692834) (xy 431.062279 -166.67116)
			(xy 431.026315 -166.622378) (xy 430.998518 -166.568521) (xy 430.979589 -166.510947) (xy 430.970003 -166.451103)
			(xy 430.96942 -166.4208) (xy 427.57457 -166.4208) (xy 427.574964 -166.442644) (xy 427.574563 -166.469898)
			(xy 427.566799 -166.523851) (xy 427.551436 -166.57615) (xy 427.528787 -166.625731) (xy 427.499312 -166.671583)
			(xy 427.463612 -166.712774) (xy 427.422412 -166.748465) (xy 427.376553 -166.777929) (xy 427.326968 -166.800567)
			(xy 427.274665 -166.815918) (xy 427.22071 -166.823669) (xy 427.193456 -166.824152) (xy 427.16531 -166.823641)
			(xy 427.10963 -166.815371) (xy 427.055766 -166.799015) (xy 427.004888 -166.774928) (xy 426.958098 -166.743633)
			(xy 426.936916 -166.725092) (xy 426.925069 -166.715116) (xy 426.896995 -166.702081) (xy 426.866306 -166.698051)
			(xy 426.835818 -166.703395) (xy 426.80833 -166.717624) (xy 426.796962 -166.72814) (xy 426.775372 -166.748791)
			(xy 426.726968 -166.783807) (xy 426.673695 -166.810846) (xy 426.616858 -166.829247) (xy 426.557847 -166.838559)
			(xy 426.527976 -166.839138) (xy 426.499237 -166.838619) (xy 426.44241 -166.829993) (xy 426.38752 -166.812942)
			(xy 426.335808 -166.78785) (xy 426.288445 -166.755284) (xy 426.267118 -166.736014) (xy 426.255584 -166.725942)
			(xy 426.228038 -166.7126) (xy 426.197776 -166.708015) (xy 426.167514 -166.7126) (xy 426.139968 -166.725942)
			(xy 426.128434 -166.736014) (xy 426.10711 -166.755288) (xy 426.059748 -166.787856) (xy 426.008036 -166.812948)
			(xy 425.953144 -166.829998) (xy 425.896315 -166.838619) (xy 425.867576 -166.839138) (xy 425.840326 -166.838645)
			(xy 425.78638 -166.830886) (xy 425.734087 -166.815529) (xy 425.684512 -166.792887) (xy 425.638663 -166.763421)
			(xy 425.597474 -166.727731) (xy 425.561782 -166.686542) (xy 425.532316 -166.640694) (xy 425.509673 -166.591119)
			(xy 425.494316 -166.538826) (xy 425.486556 -166.48488) (xy 425.486068 -166.45763) (xy 425.486619 -166.428892)
			(xy 425.495236 -166.372066) (xy 425.51228 -166.317176) (xy 425.537366 -166.265464) (xy 425.569924 -166.2181)
			(xy 425.589192 -166.196772) (xy 425.599232 -166.185214) (xy 425.612575 -166.157676) (xy 425.617164 -166.127422)
			(xy 425.612588 -166.097166) (xy 425.599257 -166.069623) (xy 425.589192 -166.058088) (xy 425.569952 -166.036735)
			(xy 425.537389 -165.989376) (xy 425.512298 -165.937668) (xy 425.495247 -165.882782) (xy 425.486622 -165.825959)
			(xy 425.486619 -165.768485) (xy 425.495237 -165.711661) (xy 425.512282 -165.656773) (xy 425.537367 -165.605062)
			(xy 425.569925 -165.557699) (xy 425.589192 -165.536372) (xy 425.599232 -165.524814) (xy 425.612575 -165.497276)
			(xy 425.617164 -165.467022) (xy 425.612588 -165.436766) (xy 425.599257 -165.409223) (xy 425.589192 -165.397688)
			(xy 425.569952 -165.376335) (xy 425.537389 -165.328976) (xy 425.512298 -165.277268) (xy 425.495247 -165.222382)
			(xy 425.486622 -165.165559) (xy 425.486619 -165.108085) (xy 425.495237 -165.051261) (xy 425.512282 -164.996373)
			(xy 425.537367 -164.944662) (xy 425.569925 -164.897299) (xy 425.589192 -164.875972) (xy 425.599232 -164.864414)
			(xy 425.612575 -164.836876) (xy 425.617164 -164.806622) (xy 425.612588 -164.776366) (xy 425.599257 -164.748823)
			(xy 425.589192 -164.737288) (xy 425.569952 -164.715935) (xy 425.537389 -164.668576) (xy 425.512298 -164.616868)
			(xy 425.495247 -164.561982) (xy 425.486622 -164.505159) (xy 425.486619 -164.447685) (xy 425.495237 -164.390861)
			(xy 425.512282 -164.335973) (xy 425.537367 -164.284262) (xy 425.569925 -164.236899) (xy 425.589192 -164.215572)
			(xy 425.599232 -164.204014) (xy 425.612575 -164.176476) (xy 425.617164 -164.146222) (xy 425.612588 -164.115966)
			(xy 425.599257 -164.088423) (xy 425.589192 -164.076888) (xy 425.569945 -164.05554) (xy 425.537373 -164.008185)
			(xy 425.512276 -163.956479) (xy 425.49522 -163.901592) (xy 425.486592 -163.844768) (xy 425.486068 -163.81603)
			(xy 425.486539 -163.788401) (xy 425.494478 -163.733716) (xy 425.510222 -163.680748) (xy 425.533443 -163.630605)
			(xy 425.563654 -163.584337) (xy 425.581572 -163.5633) (xy 425.590996 -163.551771) (xy 425.603448 -163.524742)
			(xy 425.607576 -163.495271) (xy 425.603028 -163.465862) (xy 425.590191 -163.439014) (xy 425.580556 -163.427664)
			(xy 425.561911 -163.406478) (xy 425.530459 -163.35962) (xy 425.506249 -163.308641) (xy 425.489809 -163.254654)
			(xy 425.481497 -163.198834) (xy 425.480988 -163.170616) (xy 424.713908 -163.170616) (xy 424.713908 -169.953686)
			(xy 426.587415 -169.953686) (xy 426.591451 -169.870239) (xy 426.603523 -169.787571) (xy 426.623516 -169.706454)
			(xy 426.651245 -169.627645) (xy 426.686451 -169.55188) (xy 426.728805 -169.479867) (xy 426.777911 -169.412278)
			(xy 426.833312 -169.349744) (xy 426.894489 -169.292849) (xy 426.960872 -169.242123) (xy 427.03184 -169.198042)
			(xy 427.106732 -169.161016) (xy 427.184848 -169.13139) (xy 427.265458 -169.109442) (xy 427.34781 -169.095377)
			(xy 427.431136 -169.089325) (xy 427.514656 -169.091344) (xy 427.597592 -169.101414) (xy 427.679168 -169.119442)
			(xy 427.758624 -169.145259) (xy 427.835217 -169.178624) (xy 427.908233 -169.219225) (xy 427.976989 -169.266684)
			(xy 428.040843 -169.320557) (xy 428.0992 -169.380342) (xy 428.151515 -169.445479) (xy 428.197298 -169.515362)
			(xy 428.236123 -169.589337) (xy 428.267628 -169.666714) (xy 428.291517 -169.746771) (xy 428.307568 -169.828759)
			(xy 428.315631 -169.911914) (xy 428.316136 -169.953686) (xy 428.315631 -169.995458) (xy 428.307568 -170.078613)
			(xy 428.291517 -170.160601) (xy 428.267628 -170.240658) (xy 428.236123 -170.318035) (xy 428.197298 -170.39201)
			(xy 428.151515 -170.461893) (xy 428.0992 -170.52703) (xy 428.040843 -170.586815) (xy 427.976989 -170.640688)
			(xy 427.908233 -170.688147) (xy 427.835217 -170.728748) (xy 427.758624 -170.762113) (xy 427.679168 -170.78793)
			(xy 427.597592 -170.805958) (xy 427.514656 -170.816028) (xy 427.431136 -170.818047) (xy 427.34781 -170.811995)
			(xy 427.265458 -170.79793) (xy 427.184848 -170.775982) (xy 427.106732 -170.746356) (xy 427.03184 -170.70933)
			(xy 426.960872 -170.665249) (xy 426.894489 -170.614523) (xy 426.833312 -170.557628) (xy 426.777911 -170.495094)
			(xy 426.728805 -170.427505) (xy 426.686451 -170.355492) (xy 426.651245 -170.279727) (xy 426.623516 -170.200918)
			(xy 426.603523 -170.119801) (xy 426.591451 -170.037133) (xy 426.587415 -169.953686) (xy 424.713908 -169.953686)
			(xy 424.713908 -172.496156) (xy 426.563024 -172.496156) (xy 426.563024 -172.41146) (xy 426.571075 -172.327146)
			(xy 426.587104 -172.24398) (xy 426.610965 -172.162713) (xy 426.642444 -172.084083) (xy 426.681255 -172.008802)
			(xy 426.727045 -171.93755) (xy 426.779401 -171.870974) (xy 426.837849 -171.809676) (xy 426.901859 -171.754211)
			(xy 426.970851 -171.705082) (xy 427.044201 -171.662733) (xy 427.121244 -171.627549) (xy 427.201283 -171.599847)
			(xy 427.283592 -171.579879) (xy 427.367427 -171.567826) (xy 427.452028 -171.563796) (xy 427.536629 -171.567826)
			(xy 427.620464 -171.579879) (xy 427.702773 -171.599847) (xy 427.782812 -171.627549) (xy 427.859855 -171.662733)
			(xy 427.933205 -171.705082) (xy 428.002197 -171.754211) (xy 428.066207 -171.809676) (xy 428.124655 -171.870974)
			(xy 428.177011 -171.93755) (xy 428.222801 -172.008802) (xy 428.261612 -172.084083) (xy 428.293091 -172.162713)
			(xy 428.316952 -172.24398) (xy 428.332981 -172.327146) (xy 428.341032 -172.41146) (xy 428.341536 -172.453808)
			(xy 428.341032 -172.496156) (xy 428.332981 -172.58047) (xy 428.316952 -172.663636) (xy 428.293091 -172.744903)
			(xy 428.261612 -172.823533) (xy 428.222801 -172.898814) (xy 428.177011 -172.970066) (xy 428.124655 -173.036642)
			(xy 428.066207 -173.09794) (xy 428.002197 -173.153405) (xy 427.933205 -173.202534) (xy 427.859855 -173.244883)
			(xy 427.782812 -173.280067) (xy 427.702773 -173.307769) (xy 427.620464 -173.327737) (xy 427.536629 -173.33979)
			(xy 427.452028 -173.343821) (xy 427.367427 -173.33979) (xy 427.283592 -173.327737) (xy 427.201283 -173.307769)
			(xy 427.121244 -173.280067) (xy 427.044201 -173.244883) (xy 426.970851 -173.202534) (xy 426.901859 -173.153405)
			(xy 426.837849 -173.09794) (xy 426.779401 -173.036642) (xy 426.727045 -172.970066) (xy 426.681255 -172.898814)
			(xy 426.642444 -172.823533) (xy 426.610965 -172.744903) (xy 426.587104 -172.663636) (xy 426.571075 -172.58047)
			(xy 426.563024 -172.496156) (xy 424.713908 -172.496156) (xy 424.713908 -175.597058) (xy 434.095902 -175.597058)
			(xy 434.099991 -175.541176) (xy 434.112174 -175.486486) (xy 434.13219 -175.434152) (xy 434.159613 -175.38529)
			(xy 434.193858 -175.340942) (xy 434.234194 -175.302052) (xy 434.279764 -175.26945) (xy 434.329595 -175.243831)
			(xy 434.382625 -175.225739) (xy 434.437723 -175.215562) (xy 434.493717 -175.213516) (xy 434.549412 -175.219644)
			(xy 434.603621 -175.233816) (xy 434.655189 -175.25573) (xy 434.703017 -175.284919) (xy 434.746085 -175.32076)
			(xy 434.783475 -175.36249) (xy 434.814391 -175.40922) (xy 434.838174 -175.459953) (xy 434.854316 -175.513609)
			(xy 434.862475 -175.569043) (xy 434.862986 -175.597058) (xy 434.862601 -175.61814) (xy 435.603902 -175.61814)
			(xy 435.607973 -175.562518) (xy 435.620099 -175.508081) (xy 435.640022 -175.45599) (xy 435.667318 -175.407355)
			(xy 435.701404 -175.363212) (xy 435.741553 -175.324503) (xy 435.786911 -175.292052) (xy 435.836511 -175.266551)
			(xy 435.889295 -175.248544) (xy 435.944138 -175.238414) (xy 435.999872 -175.236377) (xy 436.055309 -175.242477)
			(xy 436.109266 -175.256583) (xy 436.160595 -175.278395) (xy 436.208201 -175.307449) (xy 436.251069 -175.343124)
			(xy 436.288286 -175.384661) (xy 436.319059 -175.431174) (xy 436.342731 -175.481671) (xy 436.358799 -175.535078)
			(xy 436.366919 -175.590254) (xy 436.367428 -175.61814) (xy 436.366919 -175.646026) (xy 436.358799 -175.701202)
			(xy 436.342731 -175.754609) (xy 436.319059 -175.805106) (xy 436.288286 -175.851619) (xy 436.251069 -175.893156)
			(xy 436.208201 -175.928831) (xy 436.160595 -175.957885) (xy 436.109266 -175.979697) (xy 436.055309 -175.993803)
			(xy 435.999872 -175.999903) (xy 435.944138 -175.997866) (xy 435.889295 -175.987736) (xy 435.836511 -175.969729)
			(xy 435.786911 -175.944228) (xy 435.741553 -175.911777) (xy 435.701404 -175.873068) (xy 435.667318 -175.828925)
			(xy 435.640022 -175.78029) (xy 435.620099 -175.728199) (xy 435.607973 -175.673762) (xy 435.603902 -175.61814)
			(xy 434.862601 -175.61814) (xy 434.862475 -175.625073) (xy 434.854316 -175.680507) (xy 434.838174 -175.734163)
			(xy 434.814391 -175.784896) (xy 434.783475 -175.831626) (xy 434.746085 -175.873356) (xy 434.703017 -175.909197)
			(xy 434.655189 -175.938386) (xy 434.603621 -175.9603) (xy 434.549412 -175.974472) (xy 434.493717 -175.9806)
			(xy 434.437723 -175.978554) (xy 434.382625 -175.968377) (xy 434.329595 -175.950285) (xy 434.279764 -175.924666)
			(xy 434.234194 -175.892064) (xy 434.193858 -175.853174) (xy 434.159613 -175.808826) (xy 434.13219 -175.759964)
			(xy 434.112174 -175.70763) (xy 434.099991 -175.65294) (xy 434.095902 -175.597058) (xy 424.713908 -175.597058)
			(xy 424.713908 -176.018952) (xy 444.68161 -176.018952) (xy 444.682033 -175.991699) (xy 444.689797 -175.937748)
			(xy 444.705159 -175.885451) (xy 444.727807 -175.835872) (xy 444.75728 -175.790021) (xy 444.792978 -175.748831)
			(xy 444.834174 -175.71314) (xy 444.88003 -175.683675) (xy 444.929613 -175.661036) (xy 444.981912 -175.645683)
			(xy 445.035865 -175.637929) (xy 445.063118 -175.637444) (xy 445.08913 -175.637893) (xy 445.140672 -175.644964)
			(xy 445.190775 -175.658973) (xy 445.238509 -175.67966) (xy 445.28299 -175.706641) (xy 445.323393 -175.739415)
			(xy 445.341502 -175.758094) (xy 445.351381 -175.768042) (xy 445.37536 -175.78255) (xy 445.402382 -175.789987)
			(xy 445.430407 -175.789795) (xy 445.457324 -175.781987) (xy 445.481102 -175.767151) (xy 445.490854 -175.757078)
			(xy 445.509036 -175.737781) (xy 445.549776 -175.703855) (xy 445.594821 -175.675895) (xy 445.643302 -175.65444)
			(xy 445.694287 -175.639904) (xy 445.746794 -175.632565) (xy 445.773302 -175.63211) (xy 445.800556 -175.632554)
			(xy 445.854508 -175.640311) (xy 445.906808 -175.655668) (xy 445.956389 -175.678312) (xy 446.002243 -175.707782)
			(xy 446.043436 -175.743478) (xy 446.07913 -175.784673) (xy 446.108597 -175.830529) (xy 446.131239 -175.880111)
			(xy 446.146593 -175.932411) (xy 446.154348 -175.986364) (xy 446.15481 -176.013618) (xy 446.15429 -176.041314)
			(xy 446.146295 -176.096126) (xy 446.130461 -176.149206) (xy 446.10712 -176.19944) (xy 446.076763 -176.245773)
			(xy 446.040027 -176.28723) (xy 446.019174 -176.305464) (xy 446.012336 -176.311719) (xy 446.003266 -176.32786)
			(xy 446.000545 -176.346174) (xy 446.004531 -176.364255) (xy 446.014699 -176.379727) (xy 446.021968 -176.385474)
			(xy 446.049146 -176.407064) (xy 446.060474 -176.4163) (xy 446.087031 -176.428476) (xy 446.115948 -176.432649)
			(xy 446.144865 -176.428476) (xy 446.171422 -176.4163) (xy 446.18275 -176.407064) (xy 446.203685 -176.389429)
			(xy 446.249658 -176.359718) (xy 446.299405 -176.336882) (xy 446.351904 -176.32139) (xy 446.406079 -176.313559)
			(xy 446.433448 -176.313084) (xy 446.460696 -176.313589) (xy 446.514638 -176.321351) (xy 446.566926 -176.33671)
			(xy 446.616496 -176.359353) (xy 446.662339 -176.38882) (xy 446.703523 -176.424511) (xy 446.739209 -176.465699)
			(xy 446.76867 -176.511546) (xy 446.791307 -176.561119) (xy 446.806659 -176.613409) (xy 446.814414 -176.667352)
			(xy 446.814414 -176.721848) (xy 446.806659 -176.775791) (xy 446.791307 -176.828081) (xy 446.76867 -176.877654)
			(xy 446.739209 -176.923501) (xy 446.703523 -176.964689) (xy 446.662339 -177.00038) (xy 446.616496 -177.029847)
			(xy 446.566926 -177.05249) (xy 446.514638 -177.067849) (xy 446.460696 -177.075611) (xy 446.433448 -177.0761)
			(xy 446.406079 -177.075606) (xy 446.351901 -177.067795) (xy 446.299398 -177.052312) (xy 446.249651 -177.029477)
			(xy 446.203683 -176.999758) (xy 446.18275 -176.98212) (xy 446.171422 -176.972884) (xy 446.144865 -176.960708)
			(xy 446.115948 -176.956535) (xy 446.087031 -176.960708) (xy 446.060474 -176.972884) (xy 446.049146 -176.98212)
			(xy 446.02821 -176.999754) (xy 445.982238 -177.029466) (xy 445.932491 -177.052303) (xy 445.879992 -177.067795)
			(xy 445.825817 -177.075625) (xy 445.798448 -177.0761) (xy 445.772434 -177.075691) (xy 445.72089 -177.068614)
			(xy 445.670786 -177.054599) (xy 445.623051 -177.033904) (xy 445.578571 -177.006916) (xy 445.538171 -176.974133)
			(xy 445.520064 -176.95545) (xy 445.510219 -176.945464) (xy 445.486231 -176.930952) (xy 445.4592 -176.923515)
			(xy 445.431165 -176.923714) (xy 445.404242 -176.931534) (xy 445.380462 -176.946385) (xy 445.370712 -176.956466)
			(xy 445.352556 -176.975788) (xy 445.311809 -177.00971) (xy 445.266759 -177.037665) (xy 445.218272 -177.059116)
			(xy 445.167283 -177.073648) (xy 445.114774 -177.080982) (xy 445.088264 -177.081434) (xy 445.061013 -177.080956)
			(xy 445.007066 -177.073195) (xy 444.954773 -177.057837) (xy 444.905197 -177.035193) (xy 444.859349 -177.005726)
			(xy 444.818159 -176.970034) (xy 444.782468 -176.928843) (xy 444.753002 -176.882994) (xy 444.73036 -176.833417)
			(xy 444.715003 -176.781124) (xy 444.707244 -176.727177) (xy 444.706756 -176.699926) (xy 444.707283 -176.671461)
			(xy 444.715757 -176.615165) (xy 444.732506 -176.560755) (xy 444.757158 -176.509439) (xy 444.789165 -176.462358)
			(xy 444.808102 -176.4411) (xy 444.816772 -176.431026) (xy 444.829184 -176.407541) (xy 444.835101 -176.381646)
			(xy 444.834121 -176.3551) (xy 444.826309 -176.329712) (xy 444.812199 -176.307206) (xy 444.802768 -176.297844)
			(xy 444.784021 -176.279718) (xy 444.751106 -176.239272) (xy 444.724005 -176.194722) (xy 444.703222 -176.146895)
			(xy 444.689146 -176.096685) (xy 444.682038 -176.045025) (xy 444.68161 -176.018952) (xy 424.713908 -176.018952)
			(xy 424.713908 -176.904904) (xy 434.675278 -176.904904) (xy 434.679349 -176.849282) (xy 434.691475 -176.794845)
			(xy 434.711398 -176.742754) (xy 434.738694 -176.694119) (xy 434.77278 -176.649976) (xy 434.812929 -176.611267)
			(xy 434.858287 -176.578816) (xy 434.907887 -176.553315) (xy 434.960671 -176.535308) (xy 435.015514 -176.525178)
			(xy 435.071248 -176.523141) (xy 435.126685 -176.529241) (xy 435.180642 -176.543347) (xy 435.231971 -176.565159)
			(xy 435.279577 -176.594213) (xy 435.322445 -176.629888) (xy 435.359662 -176.671425) (xy 435.390435 -176.717938)
			(xy 435.414107 -176.768435) (xy 435.430175 -176.821842) (xy 435.438295 -176.877018) (xy 435.438804 -176.904904)
			(xy 435.438295 -176.93279) (xy 435.430175 -176.987966) (xy 435.414107 -177.041373) (xy 435.390435 -177.09187)
			(xy 435.359662 -177.138383) (xy 435.322445 -177.17992) (xy 435.279577 -177.215595) (xy 435.231971 -177.244649)
			(xy 435.180642 -177.266461) (xy 435.126685 -177.280567) (xy 435.071248 -177.286667) (xy 435.015514 -177.28463)
			(xy 434.960671 -177.2745) (xy 434.907887 -177.256493) (xy 434.858287 -177.230992) (xy 434.812929 -177.198541)
			(xy 434.77278 -177.159832) (xy 434.738694 -177.115689) (xy 434.711398 -177.067054) (xy 434.691475 -177.014963)
			(xy 434.679349 -176.960526) (xy 434.675278 -176.904904) (xy 424.713908 -176.904904) (xy 424.713908 -176.98974)
			(xy 424.713255 -177.014735) (xy 424.703459 -177.063758) (xy 424.684291 -177.109929) (xy 424.656486 -177.151476)
			(xy 424.639232 -177.169572) (xy 423.764456 -178.044348) (xy 434.953662 -178.044348) (xy 434.957733 -177.988726)
			(xy 434.969859 -177.934289) (xy 434.989782 -177.882198) (xy 435.017078 -177.833563) (xy 435.051164 -177.78942)
			(xy 435.091313 -177.750711) (xy 435.136671 -177.71826) (xy 435.186271 -177.692759) (xy 435.239055 -177.674752)
			(xy 435.293898 -177.664622) (xy 435.349632 -177.662585) (xy 435.405069 -177.668685) (xy 435.459026 -177.682791)
			(xy 435.510355 -177.704603) (xy 435.557961 -177.733657) (xy 435.600829 -177.769332) (xy 435.638046 -177.810869)
			(xy 435.668819 -177.857382) (xy 435.692491 -177.907879) (xy 435.708559 -177.961286) (xy 435.716679 -178.016462)
			(xy 435.717188 -178.044348) (xy 435.716679 -178.072234) (xy 435.708559 -178.12741) (xy 435.692491 -178.180817)
			(xy 435.668819 -178.231314) (xy 435.638046 -178.277827) (xy 435.600829 -178.319364) (xy 435.557961 -178.355039)
			(xy 435.510355 -178.384093) (xy 435.459026 -178.405905) (xy 435.405069 -178.420011) (xy 435.349632 -178.426111)
			(xy 435.293898 -178.424074) (xy 435.239055 -178.413944) (xy 435.186271 -178.395937) (xy 435.136671 -178.370436)
			(xy 435.091313 -178.337985) (xy 435.051164 -178.299276) (xy 435.017078 -178.255133) (xy 434.989782 -178.206498)
			(xy 434.969859 -178.154407) (xy 434.957733 -178.09997) (xy 434.953662 -178.044348) (xy 423.764456 -178.044348)
			(xy 423.256456 -178.552348) (xy 430.915572 -178.552348) (xy 430.916058 -178.525097) (xy 430.923814 -178.471149)
			(xy 430.939169 -178.418854) (xy 430.961811 -178.369277) (xy 430.991277 -178.323427) (xy 431.026968 -178.282236)
			(xy 431.068159 -178.246545) (xy 431.114009 -178.217079) (xy 431.163586 -178.194437) (xy 431.215881 -178.179082)
			(xy 431.269829 -178.171326) (xy 431.324331 -178.171326) (xy 431.378279 -178.179082) (xy 431.430574 -178.194437)
			(xy 431.480151 -178.217079) (xy 431.526001 -178.246545) (xy 431.567192 -178.282236) (xy 431.602883 -178.323427)
			(xy 431.632349 -178.369277) (xy 431.654991 -178.418854) (xy 431.670346 -178.471149) (xy 431.678102 -178.525097)
			(xy 431.678588 -178.552348) (xy 431.678009 -178.582075) (xy 431.66878 -178.640807) (xy 431.652522 -178.691286)
			(xy 433.98897 -178.691286) (xy 433.993041 -178.635664) (xy 434.005167 -178.581227) (xy 434.02509 -178.529136)
			(xy 434.052386 -178.480501) (xy 434.086472 -178.436358) (xy 434.126621 -178.397649) (xy 434.171979 -178.365198)
			(xy 434.221579 -178.339697) (xy 434.274363 -178.32169) (xy 434.329206 -178.31156) (xy 434.38494 -178.309523)
			(xy 434.440377 -178.315623) (xy 434.494334 -178.329729) (xy 434.545663 -178.351541) (xy 434.593269 -178.380595)
			(xy 434.636137 -178.41627) (xy 434.673354 -178.457807) (xy 434.704127 -178.50432) (xy 434.727799 -178.554817)
			(xy 434.743867 -178.608224) (xy 434.751987 -178.6634) (xy 434.752496 -178.691286) (xy 434.751987 -178.719172)
			(xy 434.743867 -178.774348) (xy 434.727799 -178.827755) (xy 434.72424 -178.835348) (xy 444.707304 -178.835348)
			(xy 444.707304 -178.780852) (xy 444.715059 -178.726911) (xy 444.730411 -178.674623) (xy 444.753048 -178.625052)
			(xy 444.782509 -178.579206) (xy 444.818194 -178.53802) (xy 444.859377 -178.502331) (xy 444.90522 -178.472866)
			(xy 444.954789 -178.450224) (xy 445.007076 -178.434867) (xy 445.061016 -178.427107) (xy 445.088264 -178.426618)
			(xy 445.114278 -178.427013) (xy 445.165823 -178.434092) (xy 445.215928 -178.44811) (xy 445.263663 -178.468807)
			(xy 445.308143 -178.495798) (xy 445.348542 -178.528584) (xy 445.366648 -178.547268) (xy 445.376576 -178.557164)
			(xy 445.40054 -178.571678) (xy 445.42755 -178.579125) (xy 445.455566 -178.578943) (xy 445.482476 -178.571145)
			(xy 445.506249 -178.55632) (xy 445.516 -178.546252) (xy 445.534154 -178.526928) (xy 445.574901 -178.493005)
			(xy 445.619952 -178.46505) (xy 445.668438 -178.4436) (xy 445.719428 -178.429068) (xy 445.771938 -178.421735)
			(xy 445.798448 -178.421284) (xy 445.825818 -178.42176) (xy 445.879998 -178.429572) (xy 445.932501 -178.445058)
			(xy 445.982249 -178.467898) (xy 446.028215 -178.497622) (xy 446.049146 -178.515264) (xy 446.060474 -178.5245)
			(xy 446.087031 -178.536676) (xy 446.115948 -178.540849) (xy 446.144865 -178.536676) (xy 446.171422 -178.5245)
			(xy 446.18275 -178.515264) (xy 446.203685 -178.497629) (xy 446.249658 -178.467918) (xy 446.299405 -178.445082)
			(xy 446.351904 -178.42959) (xy 446.406079 -178.421759) (xy 446.433448 -178.421284) (xy 446.460696 -178.421789)
			(xy 446.514638 -178.429551) (xy 446.566926 -178.44491) (xy 446.616496 -178.467553) (xy 446.662339 -178.49702)
			(xy 446.703523 -178.532711) (xy 446.739209 -178.573899) (xy 446.76867 -178.619746) (xy 446.791307 -178.669319)
			(xy 446.806659 -178.721609) (xy 446.814414 -178.775552) (xy 446.814414 -178.830048) (xy 446.806659 -178.883991)
			(xy 446.791307 -178.936281) (xy 446.76867 -178.985854) (xy 446.739209 -179.031701) (xy 446.703523 -179.072889)
			(xy 446.662339 -179.10858) (xy 446.616496 -179.138047) (xy 446.566926 -179.16069) (xy 446.514638 -179.176049)
			(xy 446.460696 -179.183811) (xy 446.433448 -179.1843) (xy 446.406079 -179.183806) (xy 446.351901 -179.175995)
			(xy 446.299398 -179.160512) (xy 446.249651 -179.137677) (xy 446.203683 -179.107958) (xy 446.18275 -179.09032)
			(xy 446.171422 -179.081084) (xy 446.144865 -179.068908) (xy 446.115948 -179.064735) (xy 446.087031 -179.068908)
			(xy 446.060474 -179.081084) (xy 446.049146 -179.09032) (xy 446.02821 -179.107954) (xy 445.982238 -179.137666)
			(xy 445.932491 -179.160503) (xy 445.879992 -179.175995) (xy 445.825817 -179.183825) (xy 445.798448 -179.1843)
			(xy 445.772434 -179.183891) (xy 445.72089 -179.176814) (xy 445.670786 -179.162799) (xy 445.623051 -179.142104)
			(xy 445.578571 -179.115116) (xy 445.538171 -179.082333) (xy 445.520064 -179.06365) (xy 445.510219 -179.053664)
			(xy 445.486231 -179.039152) (xy 445.4592 -179.031715) (xy 445.431165 -179.031914) (xy 445.404242 -179.039734)
			(xy 445.380462 -179.054585) (xy 445.370712 -179.064666) (xy 445.352556 -179.083988) (xy 445.311809 -179.11791)
			(xy 445.266759 -179.145865) (xy 445.218272 -179.167316) (xy 445.167283 -179.181848) (xy 445.114774 -179.189182)
			(xy 445.088264 -179.189634) (xy 445.061016 -179.189093) (xy 445.007076 -179.181333) (xy 444.954789 -179.165976)
			(xy 444.90522 -179.143334) (xy 444.859377 -179.113869) (xy 444.818194 -179.07818) (xy 444.782509 -179.036994)
			(xy 444.753048 -178.991148) (xy 444.730411 -178.941577) (xy 444.715059 -178.889289) (xy 444.707304 -178.835348)
			(xy 434.72424 -178.835348) (xy 434.704127 -178.878252) (xy 434.673354 -178.924765) (xy 434.636137 -178.966302)
			(xy 434.593269 -179.001977) (xy 434.545663 -179.031031) (xy 434.494334 -179.052843) (xy 434.440377 -179.066949)
			(xy 434.38494 -179.073049) (xy 434.329206 -179.071012) (xy 434.274363 -179.060882) (xy 434.221579 -179.042875)
			(xy 434.171979 -179.017374) (xy 434.126621 -178.984923) (xy 434.086472 -178.946214) (xy 434.052386 -178.902071)
			(xy 434.02509 -178.853436) (xy 434.005167 -178.801345) (xy 433.993041 -178.746908) (xy 433.98897 -178.691286)
			(xy 431.652522 -178.691286) (xy 431.650554 -178.697398) (xy 431.623772 -178.750477) (xy 431.589081 -178.79876)
			(xy 431.568606 -178.820318) (xy 431.559494 -178.83014) (xy 431.546293 -178.853443) (xy 431.539604 -178.879377)
			(xy 431.539887 -178.906158) (xy 431.547121 -178.931945) (xy 431.56081 -178.954965) (xy 431.57013 -178.96459)
			(xy 431.58827 -178.982779) (xy 431.620002 -179.023176) (xy 431.633376 -179.045108) (xy 431.641506 -179.057796)
			(xy 431.663615 -179.07824) (xy 431.690727 -179.091344) (xy 431.720482 -179.095966) (xy 431.750292 -179.091704)
			(xy 431.77756 -179.07893) (xy 431.799915 -179.058754) (xy 431.808128 -179.046124) (xy 431.822982 -179.022263)
			(xy 431.858628 -178.978807) (xy 431.900265 -178.941053) (xy 431.946992 -178.909818) (xy 431.997798 -178.88578)
			(xy 432.051581 -178.869458) (xy 432.107177 -178.861206) (xy 432.13528 -178.860704) (xy 432.162535 -178.861142)
			(xy 432.21649 -178.868896) (xy 432.268791 -178.884251) (xy 432.318376 -178.906893) (xy 432.364233 -178.936362)
			(xy 432.405429 -178.972057) (xy 432.441126 -179.013251) (xy 432.470597 -179.059107) (xy 432.493242 -179.10869)
			(xy 432.508599 -179.160991) (xy 432.516357 -179.214945) (xy 432.516357 -179.269455) (xy 432.508599 -179.323409)
			(xy 432.493242 -179.37571) (xy 432.470597 -179.425293) (xy 432.441126 -179.471149) (xy 432.405429 -179.512343)
			(xy 432.364233 -179.548038) (xy 432.318376 -179.577507) (xy 432.268791 -179.600149) (xy 432.21649 -179.615504)
			(xy 432.162535 -179.623258) (xy 432.13528 -179.62372) (xy 432.106914 -179.623166) (xy 432.050806 -179.614767)
			(xy 431.996558 -179.598159) (xy 431.945366 -179.573705) (xy 431.898356 -179.541945) (xy 431.856564 -179.503578)
			(xy 431.820909 -179.459449) (xy 431.806096 -179.435252) (xy 431.798001 -179.422542) (xy 431.775882 -179.402103)
			(xy 431.748764 -179.389006) (xy 431.719003 -179.384389) (xy 431.689191 -179.388654) (xy 431.661919 -179.40143)
			(xy 431.63956 -179.421605) (xy 431.631344 -179.434236) (xy 431.616495 -179.458101) (xy 431.58085 -179.501559)
			(xy 431.539213 -179.539314) (xy 431.492484 -179.570549) (xy 431.441678 -179.594587) (xy 431.387893 -179.610907)
			(xy 431.332295 -179.619156) (xy 431.304192 -179.619656) (xy 431.276943 -179.61913) (xy 431.222999 -179.611373)
			(xy 431.170708 -179.59602) (xy 431.121134 -179.573381) (xy 431.075286 -179.543919) (xy 431.034097 -179.508231)
			(xy 430.998405 -179.467046) (xy 430.968938 -179.421201) (xy 430.946294 -179.37163) (xy 430.930935 -179.31934)
			(xy 430.923173 -179.265397) (xy 430.922684 -179.238148) (xy 430.923269 -179.208422) (xy 430.932497 -179.14969)
			(xy 430.950722 -179.093099) (xy 430.977503 -179.04002) (xy 431.012192 -178.991737) (xy 431.032666 -178.970178)
			(xy 431.041785 -178.960361) (xy 431.054989 -178.937057) (xy 431.061679 -178.911121) (xy 431.061396 -178.884338)
			(xy 431.054158 -178.858549) (xy 431.040465 -178.835529) (xy 431.031142 -178.825906) (xy 431.01323 -178.807853)
			(xy 430.981796 -178.767877) (xy 430.955952 -178.724079) (xy 430.936156 -178.677236) (xy 430.922758 -178.628178)
			(xy 430.915995 -178.577775) (xy 430.915572 -178.552348) (xy 423.256456 -178.552348) (xy 423.223944 -178.58486)
			(xy 423.20586 -178.602129) (xy 423.164312 -178.629938) (xy 423.118137 -178.649109) (xy 423.06911 -178.658903)
			(xy 423.044112 -178.659536) (xy 421.371522 -178.659536) (xy 420.702994 -179.32781) (xy 420.702994 -179.349146)
			(xy 420.702536 -179.376422) (xy 420.694844 -179.430428) (xy 420.679537 -179.482787) (xy 420.656928 -179.532432)
			(xy 420.627477 -179.578349) (xy 420.591786 -179.619604) (xy 420.550582 -179.655353) (xy 420.504706 -179.684869)
			(xy 420.455093 -179.707548) (xy 420.402756 -179.722929) (xy 420.348761 -179.730698) (xy 420.321486 -179.731162)
			(xy 420.321232 -179.731162) (xy 420.291393 -179.730593) (xy 420.232447 -179.721273) (xy 420.203884 -179.71262)
			(xy 420.189967 -179.708614) (xy 420.161038 -179.707695) (xy 420.133019 -179.714952) (xy 420.108173 -179.729799)
			(xy 420.088508 -179.751036) (xy 420.075613 -179.776949) (xy 420.072566 -179.791106) (xy 420.06599 -179.823947)
			(xy 420.042863 -179.886798) (xy 420.026592 -179.916074) (xy 420.019587 -179.929057) (xy 420.012541 -179.957688)
			(xy 420.013975 -179.987137) (xy 420.023771 -180.014948) (xy 420.04111 -180.038795) (xy 420.064544 -180.05669)
			(xy 420.078154 -180.062378) (xy 420.104942 -180.073047) (xy 420.155182 -180.101341) (xy 420.20059 -180.136876)
			(xy 420.240131 -180.178842) (xy 420.269517 -180.221382) (xy 430.50409 -180.221382) (xy 430.508161 -180.16576)
			(xy 430.520287 -180.111323) (xy 430.54021 -180.059232) (xy 430.567506 -180.010597) (xy 430.601592 -179.966454)
			(xy 430.641741 -179.927745) (xy 430.687099 -179.895294) (xy 430.736699 -179.869793) (xy 430.789483 -179.851786)
			(xy 430.844326 -179.841656) (xy 430.90006 -179.839619) (xy 430.955497 -179.845719) (xy 431.009454 -179.859825)
			(xy 431.060783 -179.881637) (xy 431.108389 -179.910691) (xy 431.151257 -179.946366) (xy 431.188474 -179.987903)
			(xy 431.219247 -180.034416) (xy 431.242919 -180.084913) (xy 431.258987 -180.13832) (xy 431.267107 -180.193496)
			(xy 431.267616 -180.221382) (xy 431.267107 -180.249268) (xy 431.258987 -180.304444) (xy 431.242919 -180.357851)
			(xy 431.219247 -180.408348) (xy 431.188474 -180.454861) (xy 431.151257 -180.496398) (xy 431.108389 -180.532073)
			(xy 431.060783 -180.561127) (xy 431.009454 -180.582939) (xy 430.955497 -180.597045) (xy 430.90006 -180.603145)
			(xy 430.844326 -180.601108) (xy 430.789483 -180.590978) (xy 430.736699 -180.572971) (xy 430.687099 -180.54747)
			(xy 430.641741 -180.515019) (xy 430.601592 -180.47631) (xy 430.567506 -180.432167) (xy 430.54021 -180.383532)
			(xy 430.520287 -180.331441) (xy 430.508161 -180.277004) (xy 430.50409 -180.221382) (xy 420.269517 -180.221382)
			(xy 420.272903 -180.226283) (xy 420.298159 -180.278117) (xy 420.315323 -180.333162) (xy 420.324005 -180.390164)
			(xy 420.324534 -180.418994) (xy 420.324048 -180.446245) (xy 420.316292 -180.500193) (xy 420.300937 -180.552488)
			(xy 420.278295 -180.602065) (xy 420.248829 -180.647915) (xy 420.213138 -180.689106) (xy 420.171947 -180.724797)
			(xy 420.126097 -180.754263) (xy 420.07652 -180.776905) (xy 420.024225 -180.79226) (xy 419.970277 -180.800016)
			(xy 419.915775 -180.800016) (xy 419.861827 -180.79226) (xy 419.809532 -180.776905) (xy 419.759955 -180.754263)
			(xy 419.714105 -180.724797) (xy 419.672914 -180.689106) (xy 419.637223 -180.647915) (xy 419.607757 -180.602065)
			(xy 419.585115 -180.552488) (xy 419.56976 -180.500193) (xy 419.562004 -180.446245) (xy 419.561518 -180.418994)
			(xy 419.561518 -180.41874) (xy 419.561938 -180.393537) (xy 419.568572 -180.34357) (xy 419.581743 -180.294915)
			(xy 419.601219 -180.248425) (xy 419.613588 -180.226462) (xy 419.620627 -180.213499) (xy 419.627653 -180.184862)
			(xy 419.626205 -180.155412) (xy 419.616403 -180.127603) (xy 419.599064 -180.103754) (xy 419.575634 -180.085852)
			(xy 419.562026 -180.080158) (xy 419.535269 -180.069416) (xy 419.485027 -180.041136) (xy 419.439617 -180.005613)
			(xy 419.400072 -179.963658) (xy 419.367296 -179.916228) (xy 419.342035 -179.864402) (xy 419.324865 -179.809365)
			(xy 419.316178 -179.752369) (xy 419.315646 -179.723542) (xy 410.131006 -179.723542) (xy 410.131006 -180.943548)
			(xy 444.707304 -180.943548) (xy 444.707304 -180.889052) (xy 444.715059 -180.835111) (xy 444.730411 -180.782823)
			(xy 444.753048 -180.733252) (xy 444.782509 -180.687406) (xy 444.818194 -180.64622) (xy 444.859377 -180.610531)
			(xy 444.90522 -180.581066) (xy 444.954789 -180.558424) (xy 445.007076 -180.543067) (xy 445.061016 -180.535307)
			(xy 445.088264 -180.534818) (xy 445.114278 -180.535213) (xy 445.165823 -180.542292) (xy 445.215928 -180.55631)
			(xy 445.263663 -180.577007) (xy 445.308143 -180.603998) (xy 445.348542 -180.636784) (xy 445.366648 -180.655468)
			(xy 445.376576 -180.665364) (xy 445.40054 -180.679878) (xy 445.42755 -180.687325) (xy 445.455566 -180.687143)
			(xy 445.482476 -180.679345) (xy 445.506249 -180.66452) (xy 445.516 -180.654452) (xy 445.534154 -180.635128)
			(xy 445.574901 -180.601205) (xy 445.619952 -180.57325) (xy 445.668438 -180.5518) (xy 445.719428 -180.537268)
			(xy 445.771938 -180.529935) (xy 445.798448 -180.529484) (xy 445.825818 -180.52996) (xy 445.879998 -180.537772)
			(xy 445.932501 -180.553258) (xy 445.982249 -180.576098) (xy 446.028215 -180.605822) (xy 446.049146 -180.623464)
			(xy 446.060474 -180.6327) (xy 446.087031 -180.644876) (xy 446.115948 -180.649049) (xy 446.144865 -180.644876)
			(xy 446.171422 -180.6327) (xy 446.18275 -180.623464) (xy 446.203685 -180.605829) (xy 446.249658 -180.576118)
			(xy 446.299405 -180.553282) (xy 446.351904 -180.53779) (xy 446.406079 -180.529959) (xy 446.433448 -180.529484)
			(xy 446.460696 -180.529989) (xy 446.514638 -180.537751) (xy 446.566926 -180.55311) (xy 446.616496 -180.575753)
			(xy 446.662339 -180.60522) (xy 446.703523 -180.640911) (xy 446.739209 -180.682099) (xy 446.76867 -180.727946)
			(xy 446.791307 -180.777519) (xy 446.806659 -180.829809) (xy 446.814414 -180.883752) (xy 446.814414 -180.938248)
			(xy 446.806659 -180.992191) (xy 446.791307 -181.044481) (xy 446.76867 -181.094054) (xy 446.739209 -181.139901)
			(xy 446.703523 -181.181089) (xy 446.662339 -181.21678) (xy 446.616496 -181.246247) (xy 446.566926 -181.26889)
			(xy 446.514638 -181.284249) (xy 446.460696 -181.292011) (xy 446.433448 -181.2925) (xy 446.406079 -181.292006)
			(xy 446.351901 -181.284195) (xy 446.299398 -181.268712) (xy 446.249651 -181.245877) (xy 446.203683 -181.216158)
			(xy 446.18275 -181.19852) (xy 446.171422 -181.189284) (xy 446.144865 -181.177108) (xy 446.115948 -181.172935)
			(xy 446.087031 -181.177108) (xy 446.060474 -181.189284) (xy 446.049146 -181.19852) (xy 446.02821 -181.216154)
			(xy 445.982238 -181.245866) (xy 445.932491 -181.268703) (xy 445.879992 -181.284195) (xy 445.825817 -181.292025)
			(xy 445.798448 -181.2925) (xy 445.772434 -181.292091) (xy 445.72089 -181.285014) (xy 445.670786 -181.270999)
			(xy 445.623051 -181.250304) (xy 445.578571 -181.223316) (xy 445.538171 -181.190533) (xy 445.520064 -181.17185)
			(xy 445.510219 -181.161864) (xy 445.486231 -181.147352) (xy 445.4592 -181.139915) (xy 445.431165 -181.140114)
			(xy 445.404242 -181.147934) (xy 445.380462 -181.162785) (xy 445.370712 -181.172866) (xy 445.352556 -181.192188)
			(xy 445.311809 -181.22611) (xy 445.266759 -181.254065) (xy 445.218272 -181.275516) (xy 445.167283 -181.290048)
			(xy 445.114774 -181.297382) (xy 445.088264 -181.297834) (xy 445.061016 -181.297293) (xy 445.007076 -181.289533)
			(xy 444.954789 -181.274176) (xy 444.90522 -181.251534) (xy 444.859377 -181.222069) (xy 444.818194 -181.18638)
			(xy 444.782509 -181.145194) (xy 444.753048 -181.099348) (xy 444.730411 -181.049777) (xy 444.715059 -180.997489)
			(xy 444.707304 -180.943548) (xy 410.131006 -180.943548) (xy 410.131006 -180.981604) (xy 412.837884 -180.981604)
			(xy 412.862836 -180.982067) (xy 412.912125 -180.989871) (xy 412.959587 -181.00529) (xy 413.004052 -181.027944)
			(xy 413.044426 -181.057275) (xy 413.06242 -181.074568) (xy 413.450102 -181.46225) (xy 419.374572 -181.46225)
			(xy 419.374572 -181.40775) (xy 419.382328 -181.353803) (xy 419.397682 -181.30151) (xy 419.420321 -181.251933)
			(xy 419.449786 -181.206084) (xy 419.485475 -181.164893) (xy 419.526663 -181.129201) (xy 419.572511 -181.099734)
			(xy 419.622085 -181.077091) (xy 419.674378 -181.061733) (xy 419.728324 -181.053974) (xy 419.755574 -181.053486)
			(xy 419.785261 -181.054065) (xy 419.843919 -181.06326) (xy 419.900444 -181.081431) (xy 419.953471 -181.108139)
			(xy 420.001721 -181.142741) (xy 420.044027 -181.184399) (xy 420.062152 -181.207918) (xy 420.070578 -181.218525)
			(xy 420.091891 -181.235232) (xy 420.116845 -181.245751) (xy 420.143686 -181.249341) (xy 420.170527 -181.245751)
			(xy 420.195481 -181.235232) (xy 420.216794 -181.218525) (xy 420.22522 -181.207918) (xy 420.243349 -181.184402)
			(xy 420.285654 -181.142741) (xy 420.333902 -181.108136) (xy 420.386928 -181.081424) (xy 420.443453 -181.06325)
			(xy 420.502111 -181.054051) (xy 420.531798 -181.053486) (xy 420.559051 -181.053961) (xy 420.613001 -181.061718)
			(xy 420.665298 -181.077073) (xy 420.714878 -181.099715) (xy 420.76073 -181.129183) (xy 420.801923 -181.164876)
			(xy 420.837616 -181.206068) (xy 420.867084 -181.251921) (xy 420.889726 -181.3015) (xy 420.905082 -181.353797)
			(xy 420.912839 -181.407747) (xy 420.912839 -181.462253) (xy 420.905082 -181.516203) (xy 420.889726 -181.5685)
			(xy 420.867084 -181.618079) (xy 420.837616 -181.663932) (xy 420.801923 -181.705124) (xy 420.76073 -181.740817)
			(xy 420.714878 -181.770285) (xy 420.665298 -181.792927) (xy 420.613001 -181.808282) (xy 420.559051 -181.816039)
			(xy 420.531798 -181.816502) (xy 420.50211 -181.815948) (xy 420.443451 -181.806749) (xy 420.386925 -181.788573)
			(xy 420.333898 -181.76186) (xy 420.285649 -181.727254) (xy 420.243344 -181.685591) (xy 420.22522 -181.66207)
			(xy 420.216794 -181.651463) (xy 420.195481 -181.634756) (xy 420.170527 -181.624237) (xy 420.143686 -181.620647)
			(xy 420.116845 -181.624237) (xy 420.091891 -181.634756) (xy 420.070578 -181.651463) (xy 420.062152 -181.66207)
			(xy 420.044036 -181.685597) (xy 420.001729 -181.727258) (xy 419.953478 -181.761861) (xy 419.900449 -181.788572)
			(xy 419.843922 -181.806744) (xy 419.785262 -181.815939) (xy 419.755574 -181.816502) (xy 419.728324 -181.816026)
			(xy 419.674378 -181.808267) (xy 419.622085 -181.792909) (xy 419.572511 -181.770266) (xy 419.526663 -181.740799)
			(xy 419.485475 -181.705107) (xy 419.449786 -181.663916) (xy 419.420321 -181.618067) (xy 419.397682 -181.56849)
			(xy 419.382328 -181.516197) (xy 419.374572 -181.46225) (xy 413.450102 -181.46225) (xy 413.900112 -181.91226)
			(xy 417.964874 -181.91226) (xy 417.989855 -181.912777) (xy 418.039196 -181.920638) (xy 418.086704 -181.936108)
			(xy 418.131213 -181.958809) (xy 418.171631 -181.988182) (xy 418.189664 -182.005478) (xy 418.394388 -182.210456)
			(xy 418.404338 -182.219748) (xy 418.428011 -182.23317) (xy 418.454389 -182.239864) (xy 418.481598 -182.239355)
			(xy 418.507707 -182.231679) (xy 418.530862 -182.217381) (xy 418.549419 -182.197476) (xy 418.562062 -182.173378)
			(xy 418.56533 -182.160164) (xy 418.571948 -182.132152) (xy 418.592472 -182.07838) (xy 418.620841 -182.028301)
			(xy 418.656412 -181.983052) (xy 418.698377 -181.943661) (xy 418.745784 -181.911022) (xy 418.797556 -181.885876)
			(xy 418.852519 -181.868793) (xy 418.909424 -181.860161) (xy 418.938202 -181.859682) (xy 418.965315 -181.860158)
			(xy 419.018995 -181.867836) (xy 419.071046 -181.883038) (xy 419.120421 -181.905457) (xy 419.166124 -181.934641)
			(xy 419.207235 -181.970002) (xy 419.242924 -182.010827) (xy 419.272473 -182.056295) (xy 419.295286 -182.105489)
			(xy 419.310904 -182.157417) (xy 419.319013 -182.211034) (xy 419.31971 -182.238142) (xy 419.31971 -182.24119)
			(xy 419.319311 -182.267436) (xy 419.312178 -182.31944) (xy 419.305486 -182.344822) (xy 419.302675 -182.358723)
			(xy 419.30399 -182.387042) (xy 419.313051 -182.413904) (xy 419.329158 -182.437234) (xy 419.351065 -182.455227)
			(xy 419.37708 -182.466493) (xy 419.405191 -182.470161) (xy 419.419278 -182.46852) (xy 419.442743 -182.462825)
			(xy 419.490639 -182.456709) (xy 419.514782 -182.456328) (xy 419.51529 -182.456328) (xy 419.542576 -182.456791)
			(xy 419.596594 -182.464556) (xy 419.648957 -182.47993) (xy 419.698599 -182.502599) (xy 419.744509 -182.532103)
			(xy 419.785753 -182.56784) (xy 419.821491 -182.609083) (xy 419.850996 -182.654993) (xy 419.870583 -182.697882)
			(xy 433.914294 -182.697882) (xy 433.918365 -182.64226) (xy 433.930491 -182.587823) (xy 433.950414 -182.535732)
			(xy 433.97771 -182.487097) (xy 434.011796 -182.442954) (xy 434.051945 -182.404245) (xy 434.097303 -182.371794)
			(xy 434.146903 -182.346293) (xy 434.199687 -182.328286) (xy 434.25453 -182.318156) (xy 434.310264 -182.316119)
			(xy 434.365701 -182.322219) (xy 434.419658 -182.336325) (xy 434.470987 -182.358137) (xy 434.518593 -182.387191)
			(xy 434.561461 -182.422866) (xy 434.598678 -182.464403) (xy 434.629451 -182.510916) (xy 434.653123 -182.561413)
			(xy 434.669191 -182.61482) (xy 434.677311 -182.669996) (xy 434.67782 -182.697882) (xy 434.677311 -182.725768)
			(xy 434.669191 -182.780944) (xy 434.653123 -182.834351) (xy 434.629451 -182.884848) (xy 434.598678 -182.931361)
			(xy 434.561461 -182.972898) (xy 434.518593 -183.008573) (xy 434.470987 -183.037627) (xy 434.461508 -183.041655)
			(xy 444.697021 -183.041655) (xy 444.697021 -182.987145) (xy 444.704779 -182.933188) (xy 444.720136 -182.880885)
			(xy 444.742781 -182.831301) (xy 444.772252 -182.785443) (xy 444.80795 -182.744247) (xy 444.849146 -182.70855)
			(xy 444.895004 -182.679079) (xy 444.944589 -182.656435) (xy 444.996892 -182.641078) (xy 445.050849 -182.633321)
			(xy 445.078104 -182.632858) (xy 445.104116 -182.633312) (xy 445.155658 -182.640381) (xy 445.205761 -182.654389)
			(xy 445.253495 -182.675075) (xy 445.297977 -182.702055) (xy 445.338379 -182.734829) (xy 445.356488 -182.753508)
			(xy 445.366376 -182.76345) (xy 445.39035 -182.77797) (xy 445.417371 -182.785417) (xy 445.445399 -182.785227)
			(xy 445.472317 -182.777415) (xy 445.496092 -182.76257) (xy 445.50584 -182.752492) (xy 445.524031 -182.733205)
			(xy 445.564769 -182.699277) (xy 445.609812 -182.671316) (xy 445.658292 -182.649859) (xy 445.709275 -182.63532)
			(xy 445.76178 -182.62798) (xy 445.788288 -182.627524) (xy 445.815658 -182.627991) (xy 445.869838 -182.635808)
			(xy 445.922341 -182.651296) (xy 445.972088 -182.674138) (xy 446.018054 -182.703863) (xy 446.038986 -182.721504)
			(xy 446.050314 -182.73074) (xy 446.076871 -182.742916) (xy 446.105788 -182.747089) (xy 446.134705 -182.742916)
			(xy 446.161262 -182.73074) (xy 446.17259 -182.721504) (xy 446.193516 -182.703857) (xy 446.23949 -182.674146)
			(xy 446.289239 -182.651312) (xy 446.341741 -182.635822) (xy 446.395918 -182.627997) (xy 446.423288 -182.627524)
			(xy 446.450544 -182.627922) (xy 446.504501 -182.635678) (xy 446.556804 -182.651035) (xy 446.60639 -182.673678)
			(xy 446.652249 -182.703149) (xy 446.693446 -182.738845) (xy 446.729144 -182.780042) (xy 446.758616 -182.825899)
			(xy 446.781261 -182.875484) (xy 446.796619 -182.927788) (xy 446.804377 -182.981744) (xy 446.804377 -183.036256)
			(xy 446.796619 -183.090212) (xy 446.781261 -183.142516) (xy 446.758616 -183.192101) (xy 446.729144 -183.237958)
			(xy 446.693446 -183.279155) (xy 446.652249 -183.314851) (xy 446.60639 -183.344322) (xy 446.556804 -183.366965)
			(xy 446.504501 -183.382322) (xy 446.450544 -183.390078) (xy 446.423288 -183.39054) (xy 446.395917 -183.390096)
			(xy 446.341736 -183.382275) (xy 446.289232 -183.366781) (xy 446.239486 -183.343935) (xy 446.19352 -183.314204)
			(xy 446.17259 -183.29656) (xy 446.161262 -183.287324) (xy 446.134705 -183.275148) (xy 446.105788 -183.270975)
			(xy 446.076871 -183.275148) (xy 446.050314 -183.287324) (xy 446.038986 -183.29656) (xy 446.018027 -183.314166)
			(xy 445.972062 -183.343884) (xy 445.922322 -183.366727) (xy 445.869827 -183.382226) (xy 445.815655 -183.390062)
			(xy 445.788288 -183.39054) (xy 445.762276 -183.390092) (xy 445.710734 -183.383021) (xy 445.660631 -183.369013)
			(xy 445.612896 -183.348326) (xy 445.568415 -183.321344) (xy 445.528013 -183.288569) (xy 445.509904 -183.26989)
			(xy 445.500024 -183.25994) (xy 445.476048 -183.24542) (xy 445.449024 -183.237975) (xy 445.420995 -183.238166)
			(xy 445.394076 -183.24598) (xy 445.3703 -183.260827) (xy 445.360552 -183.270906) (xy 445.342364 -183.290197)
			(xy 445.301626 -183.324124) (xy 445.256582 -183.352085) (xy 445.208102 -183.373541) (xy 445.157118 -183.388079)
			(xy 445.104612 -183.395419) (xy 445.078104 -183.395874) (xy 445.050849 -183.395479) (xy 444.996892 -183.387722)
			(xy 444.944589 -183.372365) (xy 444.895004 -183.349721) (xy 444.849146 -183.32025) (xy 444.80795 -183.284553)
			(xy 444.772252 -183.243357) (xy 444.742781 -183.197499) (xy 444.720136 -183.147915) (xy 444.704779 -183.095612)
			(xy 444.697021 -183.041655) (xy 434.461508 -183.041655) (xy 434.419658 -183.059439) (xy 434.365701 -183.073545)
			(xy 434.310264 -183.079645) (xy 434.25453 -183.077608) (xy 434.199687 -183.067478) (xy 434.146903 -183.049471)
			(xy 434.097303 -183.02397) (xy 434.051945 -182.991519) (xy 434.011796 -182.95281) (xy 433.97771 -182.908667)
			(xy 433.950414 -182.860032) (xy 433.930491 -182.807941) (xy 433.918365 -182.753504) (xy 433.914294 -182.697882)
			(xy 419.870583 -182.697882) (xy 419.873667 -182.704634) (xy 419.889042 -182.756996) (xy 419.896808 -182.811014)
			(xy 419.896808 -182.865586) (xy 419.889042 -182.919604) (xy 419.873667 -182.971966) (xy 419.850996 -183.021607)
			(xy 419.821491 -183.067517) (xy 419.785753 -183.10876) (xy 419.744509 -183.144497) (xy 419.698599 -183.174001)
			(xy 419.648957 -183.19667) (xy 419.596594 -183.212044) (xy 419.542576 -183.219809) (xy 419.51529 -183.22036)
			(xy 419.514782 -183.22036) (xy 419.485649 -183.219795) (xy 419.428063 -183.210914) (xy 419.372493 -183.193393)
			(xy 419.346126 -183.18099) (xy 419.335458 -183.175656) (xy 418.591746 -183.175656) (xy 418.566764 -183.175141)
			(xy 418.517421 -183.167283) (xy 418.469911 -183.151815) (xy 418.425399 -183.129117) (xy 418.384978 -183.099746)
			(xy 418.366956 -183.082438) (xy 417.833048 -182.548276) (xy 413.768286 -182.548276) (xy 413.743303 -182.547764)
			(xy 413.693956 -182.539912) (xy 413.646441 -182.524449) (xy 413.601924 -182.501756) (xy 413.561497 -182.472389)
			(xy 413.543496 -182.455058) (xy 413.27959 -182.190898) (xy 413.023304 -181.934612) (xy 412.706058 -181.617112)
			(xy 410.131006 -181.617112) (xy 410.131006 -183.059957) (xy 416.453709 -183.059957) (xy 416.453709 -183.005443)
			(xy 416.461468 -182.951483) (xy 416.476827 -182.899176) (xy 416.499474 -182.849588) (xy 416.528948 -182.803728)
			(xy 416.56465 -182.76253) (xy 416.605851 -182.726832) (xy 416.651713 -182.697361) (xy 416.701302 -182.674717)
			(xy 416.75361 -182.659362) (xy 416.807571 -182.651607) (xy 416.834828 -182.651146) (xy 416.862199 -182.651584)
			(xy 416.91638 -182.659407) (xy 416.968884 -182.674902) (xy 417.01863 -182.69775) (xy 417.064596 -182.727481)
			(xy 417.085526 -182.745126) (xy 417.096854 -182.754362) (xy 417.123411 -182.766538) (xy 417.152328 -182.770711)
			(xy 417.181245 -182.766538) (xy 417.207802 -182.754362) (xy 417.21913 -182.745126) (xy 417.240081 -182.72751)
			(xy 417.286048 -182.697794) (xy 417.335791 -182.674953) (xy 417.388287 -182.659457) (xy 417.44246 -182.651623)
			(xy 417.469828 -182.651146) (xy 417.497075 -182.651726) (xy 417.551013 -182.659485) (xy 417.603298 -182.674841)
			(xy 417.652865 -182.697481) (xy 417.698707 -182.726944) (xy 417.739889 -182.762631) (xy 417.775573 -182.803816)
			(xy 417.805033 -182.849659) (xy 417.827669 -182.899228) (xy 417.843021 -182.951515) (xy 417.850776 -183.005453)
			(xy 417.850776 -183.059947) (xy 417.843021 -183.113885) (xy 417.827669 -183.166172) (xy 417.805033 -183.215741)
			(xy 417.775573 -183.261584) (xy 417.739889 -183.302769) (xy 417.698707 -183.338456) (xy 417.652865 -183.367919)
			(xy 417.603298 -183.390559) (xy 417.551013 -183.405915) (xy 417.497075 -183.413674) (xy 417.469828 -183.414162)
			(xy 417.442458 -183.413689) (xy 417.388279 -183.405874) (xy 417.335775 -183.390387) (xy 417.286028 -183.367547)
			(xy 417.240062 -183.337823) (xy 417.21913 -183.320182) (xy 417.207802 -183.310946) (xy 417.181245 -183.29877)
			(xy 417.152328 -183.294597) (xy 417.123411 -183.29877) (xy 417.096854 -183.310946) (xy 417.085526 -183.320182)
			(xy 417.064593 -183.33782) (xy 417.01862 -183.367532) (xy 416.968873 -183.390369) (xy 416.916373 -183.40586)
			(xy 416.862197 -183.413688) (xy 416.834828 -183.414162) (xy 416.807571 -183.413793) (xy 416.75361 -183.406038)
			(xy 416.701302 -183.390683) (xy 416.651713 -183.368039) (xy 416.605851 -183.338568) (xy 416.56465 -183.30287)
			(xy 416.528948 -183.261672) (xy 416.499474 -183.215812) (xy 416.476827 -183.166224) (xy 416.461468 -183.113917)
			(xy 416.453709 -183.059957) (xy 410.131006 -183.059957) (xy 410.131006 -184.536588) (xy 424.778422 -184.536588)
			(xy 424.782493 -184.480966) (xy 424.794619 -184.426529) (xy 424.814542 -184.374438) (xy 424.841838 -184.325803)
			(xy 424.875924 -184.28166) (xy 424.916073 -184.242951) (xy 424.961431 -184.2105) (xy 425.011031 -184.184999)
			(xy 425.063815 -184.166992) (xy 425.118658 -184.156862) (xy 425.174392 -184.154825) (xy 425.229829 -184.160925)
			(xy 425.283786 -184.175031) (xy 425.335115 -184.196843) (xy 425.382721 -184.225897) (xy 425.425589 -184.261572)
			(xy 425.462806 -184.303109) (xy 425.493579 -184.349622) (xy 425.517251 -184.400119) (xy 425.533319 -184.453526)
			(xy 425.541439 -184.508702) (xy 425.541948 -184.536588) (xy 425.541439 -184.564474) (xy 425.533319 -184.61965)
			(xy 425.517251 -184.673057) (xy 425.493579 -184.723554) (xy 425.462806 -184.770067) (xy 425.46035 -184.772808)
			(xy 431.191922 -184.772808) (xy 431.195993 -184.717186) (xy 431.208119 -184.662749) (xy 431.228042 -184.610658)
			(xy 431.255338 -184.562023) (xy 431.289424 -184.51788) (xy 431.329573 -184.479171) (xy 431.374931 -184.44672)
			(xy 431.424531 -184.421219) (xy 431.477315 -184.403212) (xy 431.532158 -184.393082) (xy 431.587892 -184.391045)
			(xy 431.643329 -184.397145) (xy 431.697286 -184.411251) (xy 431.748615 -184.433063) (xy 431.796221 -184.462117)
			(xy 431.839089 -184.497792) (xy 431.876306 -184.539329) (xy 431.907079 -184.585842) (xy 431.930751 -184.636339)
			(xy 431.946819 -184.689746) (xy 431.954939 -184.744922) (xy 431.955448 -184.772808) (xy 431.954939 -184.800694)
			(xy 431.946819 -184.85587) (xy 431.930751 -184.909277) (xy 431.907079 -184.959774) (xy 431.876306 -185.006287)
			(xy 431.839089 -185.047824) (xy 431.796221 -185.083499) (xy 431.748615 -185.112553) (xy 431.697286 -185.134365)
			(xy 431.643329 -185.148471) (xy 431.587892 -185.154571) (xy 431.532158 -185.152534) (xy 431.477315 -185.142404)
			(xy 431.424531 -185.124397) (xy 431.374931 -185.098896) (xy 431.329573 -185.066445) (xy 431.289424 -185.027736)
			(xy 431.255338 -184.983593) (xy 431.228042 -184.934958) (xy 431.208119 -184.882867) (xy 431.195993 -184.82843)
			(xy 431.191922 -184.772808) (xy 425.46035 -184.772808) (xy 425.425589 -184.811604) (xy 425.382721 -184.847279)
			(xy 425.335115 -184.876333) (xy 425.283786 -184.898145) (xy 425.229829 -184.912251) (xy 425.174392 -184.918351)
			(xy 425.118658 -184.916314) (xy 425.063815 -184.906184) (xy 425.011031 -184.888177) (xy 424.961431 -184.862676)
			(xy 424.916073 -184.830225) (xy 424.875924 -184.791516) (xy 424.841838 -184.747373) (xy 424.814542 -184.698738)
			(xy 424.794619 -184.646647) (xy 424.782493 -184.59221) (xy 424.778422 -184.536588) (xy 410.131006 -184.536588)
			(xy 410.131006 -184.868566) (xy 410.533088 -185.270648)
		)
		(stroke
			(width 0)
			(type solid)
		)
		(fill yes)
		(layer "In2.Cu")
		(net "GND")
	)
	(gr_poly
		(pts
			(xy 140.52677 -373.829834) (xy 140.563092 -373.814594) (xy 144.283176 -370.09451) (xy 145.039842 -368.508534)
			(xy 145.789396 -366.937544) (xy 146.082004 -364.427008) (xy 146.359626 -362.045758) (xy 146.309842 -362.039154)
			(xy 146.281464 -362.034883) (xy 146.226339 -362.018929) (xy 146.174226 -361.994897) (xy 146.126302 -361.96333)
			(xy 146.083647 -361.92494) (xy 146.047224 -361.880593) (xy 146.017855 -361.83129) (xy 145.996204 -361.778144)
			(xy 145.98904 -361.750356) (xy 145.985738 -361.736386) (xy 145.864326 -361.614974) (xy 145.809208 -361.670092)
			(xy 145.814542 -361.696762) (xy 145.820337 -361.727487) (xy 145.826571 -361.789704) (xy 145.826988 -361.820968)
			(xy 145.826508 -361.856631) (xy 145.818525 -361.927509) (xy 145.802656 -361.997047) (xy 145.779101 -362.064372)
			(xy 145.748156 -362.128635) (xy 145.710209 -362.18903) (xy 145.665739 -362.244795) (xy 145.615304 -362.295231)
			(xy 145.559539 -362.339702) (xy 145.499146 -362.37765) (xy 145.434883 -362.408597) (xy 145.367559 -362.432153)
			(xy 145.298021 -362.448023) (xy 145.227143 -362.456007) (xy 145.19148 -362.456476) (xy 144.40408 -362.456476)
			(xy 144.368419 -362.455993) (xy 144.297547 -362.448003) (xy 144.228016 -362.432125) (xy 144.1607 -362.40856)
			(xy 144.096447 -362.377604) (xy 144.036066 -362.339646) (xy 143.980316 -362.295164) (xy 143.954754 -362.270294)
			(xy 143.383254 -361.698794) (xy 143.358372 -361.673244) (xy 143.31389 -361.617492) (xy 143.275933 -361.557109)
			(xy 143.244979 -361.492854) (xy 143.221417 -361.425536) (xy 143.205543 -361.356003) (xy 143.197558 -361.285129)
			(xy 143.197072 -361.249468) (xy 143.197072 -345.343734) (xy 143.197552 -345.308072) (xy 143.205536 -345.237196)
			(xy 143.221408 -345.167661) (xy 143.244967 -345.10034) (xy 143.275918 -345.036081) (xy 143.313871 -344.975693)
			(xy 143.358348 -344.919936) (xy 143.383254 -344.894408) (xy 144.260824 -344.016838) (xy 144.270292 -344.006725)
			(xy 144.283903 -343.982609) (xy 144.290526 -343.95572) (xy 144.289671 -343.928042) (xy 144.281402 -343.901613)
			(xy 144.266329 -343.878383) (xy 144.245562 -343.860064) (xy 144.220633 -343.848006) (xy 144.193379 -343.843099)
			(xy 144.179544 -343.843864) (xy 144.14373 -343.845642) (xy 144.111414 -343.844973) (xy 144.047698 -343.834125)
			(xy 144.016984 -343.824052) (xy 143.987027 -343.833641) (xy 143.924988 -343.843979) (xy 143.89354 -343.844626)
			(xy 143.866284 -343.844166) (xy 143.812326 -343.836413) (xy 143.760021 -343.82106) (xy 143.710433 -343.798418)
			(xy 143.664573 -343.76895) (xy 143.623374 -343.733255) (xy 143.587674 -343.692059) (xy 143.558201 -343.646202)
			(xy 143.535554 -343.596617) (xy 143.520195 -343.544313) (xy 143.512437 -343.490356) (xy 143.512437 -343.435844)
			(xy 143.520195 -343.381887) (xy 143.535554 -343.329583) (xy 143.558201 -343.279998) (xy 143.587674 -343.234141)
			(xy 143.623374 -343.192945) (xy 143.664573 -343.15725) (xy 143.710433 -343.127782) (xy 143.760021 -343.10514)
			(xy 143.812326 -343.089787) (xy 143.866284 -343.082034) (xy 143.89354 -343.08161) (xy 143.924986 -343.082274)
			(xy 143.987024 -343.09261) (xy 144.016984 -343.102184) (xy 144.0477 -343.092118) (xy 144.111414 -343.081267)
			(xy 144.14373 -343.080594) (xy 144.17152 -343.081093) (xy 144.226515 -343.089133) (xy 144.27977 -343.105039)
			(xy 144.330166 -343.128478) (xy 144.376644 -343.158957) (xy 144.418226 -343.195835) (xy 144.454041 -343.238338)
			(xy 144.469104 -343.261696) (xy 144.481804 -343.28227) (xy 144.50822 -343.285826) (xy 144.58696 -343.28862)
			(xy 144.601438 -343.258394) (xy 144.617268 -343.2263) (xy 144.655111 -343.165559) (xy 144.699542 -343.109457)
			(xy 144.749999 -343.058706) (xy 144.805841 -343.013949) (xy 144.866361 -342.975753) (xy 144.93079 -342.944602)
			(xy 144.998313 -342.920892) (xy 145.068074 -342.904923) (xy 145.139187 -342.896897) (xy 145.17497 -342.896444)
			(xy 145.210619 -342.896924) (xy 145.28147 -342.904903) (xy 145.350981 -342.920766) (xy 145.418279 -342.944312)
			(xy 145.482518 -342.975245) (xy 145.542889 -343.013176) (xy 145.598634 -343.057628) (xy 145.649051 -343.108042)
			(xy 145.693506 -343.163785) (xy 145.73144 -343.224154) (xy 145.762376 -343.288391) (xy 145.785925 -343.355688)
			(xy 145.801791 -343.425199) (xy 145.809775 -343.496049) (xy 145.810224 -343.531698) (xy 145.810224 -344.001852)
			(xy 145.809712 -344.037468) (xy 145.801716 -344.108251) (xy 145.785853 -344.177695) (xy 145.762321 -344.244929)
			(xy 145.731417 -344.309109) (xy 145.693527 -344.36943) (xy 145.649128 -344.425133) (xy 145.624296 -344.45067)
			(xy 145.255742 -344.819224) (xy 145.25244 -344.83294) (xy 145.244925 -344.860757) (xy 145.221266 -344.913291)
			(xy 145.18854 -344.96071) (xy 145.16862 -344.98153) (xy 144.895062 -345.255088) (xy 144.948148 -345.402154)
			(xy 144.980152 -345.405202) (xy 145.008132 -345.408386) (xy 145.06279 -345.421932) (xy 145.114863 -345.443366)
			(xy 145.16322 -345.47222) (xy 145.206811 -345.507868) (xy 145.244688 -345.549537) (xy 145.27603 -345.59632)
			(xy 145.300154 -345.647203) (xy 145.316538 -345.701078) (xy 145.324825 -345.756776) (xy 145.325338 -345.784932)
			(xy 145.325338 -345.78544) (xy 145.324921 -345.810828) (xy 145.318179 -345.861153) (xy 145.304805 -345.910135)
			(xy 145.285038 -345.956905) (xy 145.272506 -345.978988) (xy 145.269204 -345.984576) (xy 145.261584 -346.010484)
			(xy 145.261584 -360.113072) (xy 146.298158 -361.149646) (xy 146.30856 -361.159387) (xy 146.333477 -361.173195)
			(xy 146.36124 -361.179577) (xy 146.389685 -361.178038) (xy 146.416597 -361.168695) (xy 146.439878 -361.152278)
			(xy 146.457714 -361.130066) (xy 146.468716 -361.10379) (xy 146.470878 -361.089702) (xy 148.080476 -347.276928)
			(xy 148.080476 -336.009996) (xy 148.068792 -335.944464) (xy 147.995132 -335.52638) (xy 144.174464 -331.705712)
			(xy 134.816088 -331.705712) (xy 134.816088 -335.49844) (xy 135.415528 -336.09788) (xy 135.432812 -336.115878)
			(xy 135.462122 -336.156261) (xy 135.484761 -336.200727) (xy 135.500175 -336.248184) (xy 135.507984 -336.297467)
			(xy 135.508492 -336.322416) (xy 135.508492 -344.593164) (xy 135.508031 -344.618116) (xy 135.500229 -344.667407)
			(xy 135.484812 -344.714871) (xy 135.46216 -344.759338) (xy 135.447223 -344.7799) (xy 138.092587 -344.7799)
			(xy 138.096756 -344.724274) (xy 138.109169 -344.669891) (xy 138.129549 -344.617966) (xy 138.15744 -344.569658)
			(xy 138.19222 -344.526046) (xy 138.233112 -344.488106) (xy 138.279202 -344.456684) (xy 138.32946 -344.432482)
			(xy 138.382764 -344.416042) (xy 138.437923 -344.40773) (xy 138.465814 -344.407236) (xy 138.493148 -344.407663)
			(xy 138.547229 -344.41564) (xy 138.599565 -344.431436) (xy 138.649029 -344.454711) (xy 138.694561 -344.484966)
			(xy 138.735182 -344.52155) (xy 138.77002 -344.563679) (xy 138.784584 -344.586814) (xy 138.792541 -344.599014)
			(xy 138.814004 -344.618683) (xy 138.840148 -344.63149) (xy 138.868845 -344.636392) (xy 138.897758 -344.63299)
			(xy 138.91133 -344.627708) (xy 138.934539 -344.618217) (xy 138.982873 -344.604867) (xy 139.032562 -344.598139)
			(xy 139.057634 -344.597736) (xy 139.082703 -344.59816) (xy 139.132386 -344.604909) (xy 139.180721 -344.618242)
			(xy 139.203938 -344.627708) (xy 139.217525 -344.632926) (xy 139.246421 -344.636297) (xy 139.275096 -344.631393)
			(xy 139.301229 -344.618611) (xy 139.322703 -344.598986) (xy 139.330684 -344.586814) (xy 139.345253 -344.563683)
			(xy 139.380096 -344.521562) (xy 139.420719 -344.484983) (xy 139.46625 -344.454732) (xy 139.515712 -344.431456)
			(xy 139.568043 -344.415656) (xy 139.622122 -344.40767) (xy 139.676786 -344.40767) (xy 139.730865 -344.415656)
			(xy 139.783196 -344.431456) (xy 139.832658 -344.454732) (xy 139.878189 -344.484983) (xy 139.918812 -344.521562)
			(xy 139.953655 -344.563683) (xy 139.968224 -344.586814) (xy 139.976143 -344.599041) (xy 139.997616 -344.61871)
			(xy 140.023771 -344.631514) (xy 140.052476 -344.636408) (xy 140.081396 -344.632996) (xy 140.09497 -344.627708)
			(xy 140.118187 -344.618236) (xy 140.166516 -344.604878) (xy 140.216203 -344.598143) (xy 140.241274 -344.597736)
			(xy 140.268118 -344.598183) (xy 140.32125 -344.605885) (xy 140.372727 -344.621134) (xy 140.421482 -344.643612)
			(xy 140.466505 -344.672856) (xy 140.506866 -344.70826) (xy 140.541726 -344.74909) (xy 140.570366 -344.7945)
			(xy 140.592192 -344.843551) (xy 140.599922 -344.869262) (xy 140.604566 -344.883766) (xy 140.621088 -344.909332)
			(xy 140.644408 -344.928897) (xy 140.672456 -344.940726) (xy 140.702743 -344.943768) (xy 140.732583 -344.937755)
			(xy 140.746226 -344.930984) (xy 140.774377 -344.916361) (xy 140.834326 -344.89563) (xy 140.896882 -344.885128)
			(xy 140.928598 -344.884502) (xy 140.946617 -344.884727) (xy 140.982492 -344.888158) (xy 141.000226 -344.89136)
			(xy 141.015432 -344.893723) (xy 141.045988 -344.890188) (xy 141.074107 -344.877721) (xy 141.097243 -344.85745)
			(xy 141.113299 -344.831213) (xy 141.117574 -344.81643) (xy 141.124994 -344.789393) (xy 141.146623 -344.737669)
			(xy 141.175586 -344.689666) (xy 141.21126 -344.646416) (xy 141.252876 -344.608849) (xy 141.29954 -344.577774)
			(xy 141.350247 -344.55386) (xy 141.403907 -344.53762) (xy 141.459366 -344.529404) (xy 141.487398 -344.528902)
			(xy 141.514651 -344.529357) (xy 141.568603 -344.537114) (xy 141.620902 -344.55247) (xy 141.670482 -344.575113)
			(xy 141.716336 -344.604582) (xy 141.757529 -344.640277) (xy 141.793223 -344.68147) (xy 141.82269 -344.727325)
			(xy 141.845332 -344.776906) (xy 141.860688 -344.829205) (xy 141.868443 -344.883157) (xy 141.868906 -344.91041)
			(xy 141.868376 -344.937982) (xy 141.860437 -344.992552) (xy 141.844724 -345.045411) (xy 141.821566 -345.095457)
			(xy 141.791445 -345.141648) (xy 141.754988 -345.183022) (xy 141.734286 -345.20124) (xy 141.72338 -345.211129)
			(xy 141.707311 -345.235783) (xy 141.69893 -345.263992) (xy 141.698932 -345.293421) (xy 141.707317 -345.321629)
			(xy 141.723389 -345.34628) (xy 141.734286 -345.35618) (xy 141.755002 -345.374385) (xy 141.791467 -345.415757)
			(xy 141.821594 -345.461948) (xy 141.844757 -345.511997) (xy 141.860472 -345.564859) (xy 141.868412 -345.619432)
			(xy 141.868411 -345.674581) (xy 141.860469 -345.729154) (xy 141.844752 -345.782016) (xy 141.821588 -345.832063)
			(xy 141.791459 -345.878254) (xy 141.754993 -345.919625) (xy 141.734286 -345.93784) (xy 141.72338 -345.947729)
			(xy 141.707311 -345.972383) (xy 141.69893 -346.000592) (xy 141.698932 -346.030021) (xy 141.707317 -346.058229)
			(xy 141.723389 -346.08288) (xy 141.734286 -346.09278) (xy 141.754988 -346.111001) (xy 141.791459 -346.152368)
			(xy 141.821593 -346.198555) (xy 141.844761 -346.248601) (xy 141.860479 -346.301462) (xy 141.86842 -346.356036)
			(xy 141.868906 -346.38361) (xy 141.868432 -346.410862) (xy 141.860674 -346.46481) (xy 141.845317 -346.517105)
			(xy 141.822675 -346.566682) (xy 141.793207 -346.612533) (xy 141.757514 -346.653723) (xy 141.716323 -346.689414)
			(xy 141.670472 -346.71888) (xy 141.620894 -346.741521) (xy 141.568598 -346.756876) (xy 141.51465 -346.764632)
			(xy 141.487398 -346.765118) (xy 141.459543 -346.764584) (xy 141.404429 -346.75646) (xy 141.35108 -346.740415)
			(xy 141.300628 -346.716789) (xy 141.254143 -346.686084) (xy 141.212614 -346.64895) (xy 141.17692 -346.606177)
			(xy 141.14782 -346.558672) (xy 141.125931 -346.507442) (xy 141.118336 -346.480638) (xy 141.114074 -346.466517)
			(xy 141.098685 -346.441368) (xy 141.076764 -346.42165) (xy 141.050131 -346.409) (xy 141.020997 -346.404469)
			(xy 141.006322 -346.405962) (xy 140.993305 -346.407627) (xy 140.967121 -346.40941) (xy 140.953998 -346.409518)
			(xy 140.939849 -346.409424) (xy 140.911626 -346.40739) (xy 140.89761 -346.405454) (xy 140.884268 -346.403791)
			(xy 140.857565 -346.406899) (xy 140.832604 -346.416882) (xy 140.811121 -346.433043) (xy 140.794611 -346.454258)
			(xy 140.784222 -346.479052) (xy 140.78204 -346.492322) (xy 140.777912 -346.519469) (xy 140.762943 -346.572297)
			(xy 140.740556 -346.622434) (xy 140.711213 -346.668844) (xy 140.67552 -346.710569) (xy 140.634215 -346.746746)
			(xy 140.588151 -346.776628) (xy 140.538278 -346.799598) (xy 140.485628 -346.815183) (xy 140.431288 -346.823058)
			(xy 140.403834 -346.823538) (xy 140.376583 -346.823013) (xy 140.322636 -346.815262) (xy 140.270341 -346.799911)
			(xy 140.220763 -346.777275) (xy 140.174911 -346.747813) (xy 140.133719 -346.712126) (xy 140.098025 -346.67094)
			(xy 140.068556 -346.625093) (xy 140.045911 -346.575519) (xy 140.030552 -346.523226) (xy 140.022791 -346.469281)
			(xy 140.022326 -346.44203) (xy 140.022803 -346.414456) (xy 140.030752 -346.359883) (xy 140.046474 -346.307023)
			(xy 140.069642 -346.256977) (xy 140.099773 -346.210787) (xy 140.136239 -346.169416) (xy 140.156946 -346.1512)
			(xy 140.167817 -346.141273) (xy 140.183899 -346.116633) (xy 140.192291 -346.088431) (xy 140.192296 -346.059007)
			(xy 140.183915 -346.030802) (xy 140.167843 -346.006156) (xy 140.156946 -345.99626) (xy 140.13627 -345.978011)
			(xy 140.099795 -345.936651) (xy 140.069657 -345.89047) (xy 140.046485 -345.840429) (xy 140.030762 -345.787573)
			(xy 140.022815 -345.733003) (xy 140.022326 -345.70543) (xy 140.022752 -345.678928) (xy 140.030103 -345.626435)
			(xy 140.044654 -345.575467) (xy 140.066123 -345.527005) (xy 140.094098 -345.481984) (xy 140.110718 -345.461336)
			(xy 140.120186 -345.449208) (xy 140.131978 -345.420802) (xy 140.1348 -345.390175) (xy 140.128399 -345.360092)
			(xy 140.113351 -345.333268) (xy 140.091015 -345.312124) (xy 140.077444 -345.304872) (xy 140.05375 -345.292778)
			(xy 140.009769 -345.262853) (xy 139.970489 -345.22698) (xy 139.936707 -345.185888) (xy 139.922504 -345.163394)
			(xy 139.914556 -345.151187) (xy 139.893091 -345.131517) (xy 139.866945 -345.11871) (xy 139.838245 -345.11381)
			(xy 139.809331 -345.117216) (xy 139.795758 -345.1225) (xy 139.77255 -345.131995) (xy 139.724216 -345.145344)
			(xy 139.674526 -345.15207) (xy 139.649454 -345.152472) (xy 139.624385 -345.152051) (xy 139.574701 -345.1453)
			(xy 139.526367 -345.131967) (xy 139.50315 -345.1225) (xy 139.489568 -345.117266) (xy 139.46067 -345.113897)
			(xy 139.431992 -345.118804) (xy 139.405858 -345.13159) (xy 139.384384 -345.15122) (xy 139.376404 -345.163394)
			(xy 139.361835 -345.186525) (xy 139.326992 -345.228646) (xy 139.286369 -345.265225) (xy 139.240838 -345.295476)
			(xy 139.191376 -345.318752) (xy 139.139045 -345.334552) (xy 139.084966 -345.342538) (xy 139.030302 -345.342538)
			(xy 138.976223 -345.334552) (xy 138.923892 -345.318752) (xy 138.87443 -345.295476) (xy 138.828899 -345.265225)
			(xy 138.788276 -345.228646) (xy 138.753433 -345.186525) (xy 138.738864 -345.163394) (xy 138.730954 -345.15116)
			(xy 138.709479 -345.13149) (xy 138.683322 -345.118687) (xy 138.654614 -345.113794) (xy 138.625692 -345.11721)
			(xy 138.612118 -345.1225) (xy 138.588903 -345.131976) (xy 138.540573 -345.145332) (xy 138.490885 -345.152066)
			(xy 138.465814 -345.152472) (xy 138.437923 -345.15207) (xy 138.382764 -345.143758) (xy 138.32946 -345.127318)
			(xy 138.279202 -345.103116) (xy 138.233112 -345.071694) (xy 138.19222 -345.033754) (xy 138.15744 -344.990143)
			(xy 138.129549 -344.941834) (xy 138.109169 -344.889909) (xy 138.096756 -344.835526) (xy 138.092587 -344.7799)
			(xy 135.447223 -344.7799) (xy 135.432829 -344.799714) (xy 135.415528 -344.8177) (xy 134.94258 -345.290648)
			(xy 134.932331 -345.301652) (xy 134.918177 -345.328165) (xy 134.91235 -345.35765) (xy 134.915354 -345.387555)
			(xy 134.926931 -345.415291) (xy 134.946077 -345.438459) (xy 134.971136 -345.455053) (xy 134.999939 -345.463637)
			(xy 135.01497 -345.46413) (xy 135.017002 -345.46413) (xy 135.04425 -345.464616) (xy 135.098191 -345.472372)
			(xy 135.150479 -345.487725) (xy 135.200051 -345.510363) (xy 135.245896 -345.539826) (xy 135.287081 -345.575512)
			(xy 135.322769 -345.616697) (xy 135.352232 -345.662541) (xy 135.374872 -345.712112) (xy 135.390226 -345.7644)
			(xy 135.397983 -345.818341) (xy 135.397985 -345.872837) (xy 135.390231 -345.926778) (xy 135.37488 -345.979067)
			(xy 135.352243 -346.028639) (xy 135.322782 -346.074485) (xy 135.287097 -346.115672) (xy 135.245914 -346.151361)
			(xy 135.20007 -346.180826) (xy 135.150501 -346.203467) (xy 135.098213 -346.218823) (xy 135.044273 -346.226582)
			(xy 134.989777 -346.226586) (xy 134.935835 -346.218834) (xy 134.883546 -346.203484) (xy 134.833973 -346.18085)
			(xy 134.788126 -346.15139) (xy 134.746938 -346.115707) (xy 134.711247 -346.074524) (xy 134.681781 -346.028682)
			(xy 134.659138 -345.979113) (xy 134.64378 -345.926826) (xy 134.636019 -345.872886) (xy 134.635494 -345.845638)
			(xy 134.635494 -345.843606) (xy 134.635032 -345.82857) (xy 134.626432 -345.79976) (xy 134.609826 -345.774695)
			(xy 134.586648 -345.755543) (xy 134.558903 -345.743959) (xy 134.528988 -345.740944) (xy 134.499489 -345.746758)
			(xy 134.472955 -345.760899) (xy 134.462012 -345.771216) (xy 134.447026 -345.786202) (xy 134.327392 -345.905582)
			(xy 134.327392 -346.039948) (xy 134.412482 -346.124784) (xy 134.42315 -346.135452) (xy 134.43712 -346.139008)
			(xy 134.464527 -346.146106) (xy 134.517025 -346.167295) (xy 134.565811 -346.196015) (xy 134.609813 -346.231635)
			(xy 134.648063 -346.273371) (xy 134.67972 -346.320306) (xy 134.704087 -346.371406) (xy 134.720628 -346.425548)
			(xy 134.728979 -346.481542) (xy 134.729474 -346.509848) (xy 134.728984 -346.537096) (xy 134.721222 -346.591037)
			(xy 134.705863 -346.643324) (xy 134.683218 -346.692893) (xy 134.65375 -346.738735) (xy 134.618058 -346.779916)
			(xy 134.576869 -346.815599) (xy 134.531021 -346.845058) (xy 134.481447 -346.867691) (xy 134.429157 -346.88304)
			(xy 134.375214 -346.89079) (xy 134.347966 -346.891356) (xy 134.319672 -346.890847) (xy 134.263703 -346.882496)
			(xy 134.209582 -346.865969) (xy 134.158497 -346.841628) (xy 134.111568 -346.810007) (xy 134.069826 -346.7718)
			(xy 134.034186 -346.727846) (xy 134.00543 -346.679108) (xy 133.98419 -346.626658) (xy 133.977126 -346.599256)
			(xy 133.973824 -346.585286) (xy 133.784848 -346.39631) (xy 133.767565 -346.378311) (xy 133.73826 -346.337927)
			(xy 133.715623 -346.293461) (xy 133.700212 -346.246004) (xy 133.692405 -346.196722) (xy 133.691884 -346.171774)
			(xy 133.691884 -345.773756) (xy 133.692344 -345.748803) (xy 133.700142 -345.69951) (xy 133.715556 -345.652044)
			(xy 133.738205 -345.607573) (xy 133.767533 -345.567194) (xy 133.784848 -345.54922) (xy 134.872984 -344.461338)
			(xy 134.872984 -336.454242) (xy 134.46252 -336.044032) (xy 134.27329 -335.855056) (xy 134.255937 -335.837071)
			(xy 134.226538 -335.796657) (xy 134.203831 -335.752139) (xy 134.188376 -335.704613) (xy 134.180555 -335.655254)
			(xy 134.180072 -335.630266) (xy 134.180072 -331.705712) (xy 133.510528 -331.705712) (xy 131.76758 -329.962764)
			(xy 131.62534 -329.962764) (xy 131.620006 -329.968098) (xy 127.494792 -329.968098) (xy 127.494792 -334.087978)
			(xy 127.495046 -334.088486) (xy 127.495046 -334.095598) (xy 127.4953 -334.09763) (xy 127.4953 -334.102456)
			(xy 127.494586 -334.128092) (xy 127.485906 -334.178634) (xy 127.478028 -334.20304) (xy 127.469806 -334.225802)
			(xy 127.447453 -334.268724) (xy 127.418845 -334.307757) (xy 127.402082 -334.325214) (xy 127.370332 -334.35671)
			(xy 127.301752 -334.425036) (xy 127.301752 -336.830416) (xy 127.332486 -336.860896) (xy 127.34671 -336.874866)
			(xy 127.364062 -336.892852) (xy 127.393458 -336.933266) (xy 127.416162 -336.977785) (xy 127.431613 -337.02531)
			(xy 127.439431 -337.074669) (xy 127.439928 -337.099656) (xy 127.439928 -338.55025) (xy 127.439413 -338.575233)
			(xy 127.431557 -338.624577) (xy 127.416093 -338.67209) (xy 127.393399 -338.716606) (xy 127.364033 -338.757032)
			(xy 127.34671 -338.77504) (xy 127.13232 -338.9892) (xy 129.932095 -338.9892) (xy 129.936264 -338.933577)
			(xy 129.948676 -338.879196) (xy 129.969055 -338.827272) (xy 129.996944 -338.778966) (xy 130.031722 -338.735356)
			(xy 130.072612 -338.697416) (xy 130.118699 -338.665995) (xy 130.168955 -338.641793) (xy 130.222256 -338.625352)
			(xy 130.277412 -338.617039) (xy 130.305302 -338.616544) (xy 130.332635 -338.616977) (xy 130.386717 -338.624953)
			(xy 130.439052 -338.640747) (xy 130.488517 -338.664021) (xy 130.534049 -338.694275) (xy 130.57467 -338.730859)
			(xy 130.609508 -338.772987) (xy 130.624072 -338.796122) (xy 130.631944 -338.808383) (xy 130.65343 -338.828052)
			(xy 130.679597 -338.84085) (xy 130.708314 -338.845736) (xy 130.737242 -338.842311) (xy 130.750818 -338.837016)
			(xy 130.774029 -338.827529) (xy 130.822361 -338.814177) (xy 130.87205 -338.807448) (xy 130.897122 -338.807044)
			(xy 130.922191 -338.807471) (xy 130.971874 -338.814219) (xy 131.020209 -338.82755) (xy 131.043426 -338.837016)
			(xy 131.057019 -338.842218) (xy 131.085911 -338.845591) (xy 131.114584 -338.840691) (xy 131.140716 -338.827912)
			(xy 131.16219 -338.808292) (xy 131.170172 -338.796122) (xy 131.184741 -338.772991) (xy 131.219584 -338.73087)
			(xy 131.260207 -338.694291) (xy 131.305738 -338.66404) (xy 131.3552 -338.640764) (xy 131.407531 -338.624964)
			(xy 131.46161 -338.616978) (xy 131.516274 -338.616978) (xy 131.570353 -338.624964) (xy 131.622684 -338.640764)
			(xy 131.672146 -338.66404) (xy 131.717677 -338.694291) (xy 131.7583 -338.73087) (xy 131.793143 -338.772991)
			(xy 131.807712 -338.796122) (xy 131.815641 -338.808342) (xy 131.837112 -338.82801) (xy 131.863263 -338.840814)
			(xy 131.891967 -338.845711) (xy 131.920884 -338.842302) (xy 131.934458 -338.837016) (xy 131.957664 -338.827517)
			(xy 132.005999 -338.814169) (xy 132.05569 -338.807445) (xy 132.080762 -338.807044) (xy 132.105703 -338.807423)
			(xy 132.15514 -338.81407) (xy 132.203249 -338.827251) (xy 132.249171 -338.84673) (xy 132.292085 -338.872159)
			(xy 132.311902 -338.887308) (xy 132.3234 -338.89589) (xy 132.34993 -338.906786) (xy 132.378445 -338.909859)
			(xy 132.406688 -338.904866) (xy 132.432421 -338.892202) (xy 132.453607 -338.87287) (xy 132.461508 -338.860892)
			(xy 132.476508 -338.837421) (xy 132.512171 -338.794638) (xy 132.553678 -338.757497) (xy 132.600146 -338.726789)
			(xy 132.650587 -338.703166) (xy 132.703928 -338.687133) (xy 132.759033 -338.679028) (xy 132.786882 -338.67852)
			(xy 132.815037 -338.678965) (xy 132.870737 -338.687226) (xy 132.924618 -338.703587) (xy 132.975508 -338.727691)
			(xy 133.0223 -338.759016) (xy 133.06398 -338.796879) (xy 133.099639 -338.840459) (xy 133.128504 -338.888807)
			(xy 133.149947 -338.940874) (xy 133.157214 -338.96808) (xy 133.161562 -338.983021) (xy 133.177813 -339.009536)
			(xy 133.201287 -339.029935) (xy 133.229809 -339.042329) (xy 133.260739 -339.04557) (xy 133.276086 -339.04301)
			(xy 133.294808 -339.039458) (xy 133.332724 -339.035641) (xy 133.351778 -339.03539) (xy 133.352032 -339.03539)
			(xy 133.379282 -339.035882) (xy 133.433226 -339.043642) (xy 133.485516 -339.059) (xy 133.535089 -339.081643)
			(xy 133.580935 -339.11111) (xy 133.622122 -339.146801) (xy 133.657809 -339.18799) (xy 133.687273 -339.233839)
			(xy 133.709911 -339.283414) (xy 133.725265 -339.335706) (xy 133.73302 -339.38965) (xy 133.73302 -339.44415)
			(xy 133.725265 -339.498094) (xy 133.709911 -339.550386) (xy 133.687273 -339.599961) (xy 133.657809 -339.64581)
			(xy 133.622122 -339.686999) (xy 133.580935 -339.72269) (xy 133.535089 -339.752157) (xy 133.485516 -339.7748)
			(xy 133.433226 -339.790158) (xy 133.379282 -339.797918) (xy 133.352032 -339.798406) (xy 133.323878 -339.797929)
			(xy 133.26818 -339.78967) (xy 133.214302 -339.773313) (xy 133.163413 -339.749212) (xy 133.116621 -339.717892)
			(xy 133.074942 -339.680033) (xy 133.039281 -339.636457) (xy 133.010414 -339.588113) (xy 132.988968 -339.53605)
			(xy 132.9817 -339.508846) (xy 132.977428 -339.493877) (xy 132.961165 -339.467351) (xy 132.937673 -339.446949)
			(xy 132.909129 -339.434563) (xy 132.878181 -339.431342) (xy 132.862828 -339.433916) (xy 132.844045 -339.437484)
			(xy 132.806 -339.441301) (xy 132.786882 -339.441536) (xy 132.786628 -339.441536) (xy 132.760488 -339.441082)
			(xy 132.708697 -339.433949) (xy 132.658368 -339.419801) (xy 132.610447 -339.398902) (xy 132.565834 -339.371646)
			(xy 132.545328 -339.35543) (xy 132.533921 -339.346707) (xy 132.507553 -339.33537) (xy 132.47907 -339.331838)
			(xy 132.450732 -339.336391) (xy 132.424788 -339.348667) (xy 132.403298 -339.367692) (xy 132.395214 -339.37956)
			(xy 132.389483 -339.388432) (xy 132.377156 -339.405587) (xy 132.370576 -339.41385) (xy 132.361312 -339.426139)
			(xy 132.349909 -339.454705) (xy 132.347517 -339.485371) (xy 132.354353 -339.515361) (xy 132.369797 -339.541961)
			(xy 132.392453 -339.562764) (xy 132.406136 -339.569806) (xy 132.429267 -339.581168) (xy 132.472506 -339.609205)
			(xy 132.51157 -339.642817) (xy 132.545746 -339.681389) (xy 132.574408 -339.724217) (xy 132.597033 -339.770519)
			(xy 132.605526 -339.79485) (xy 132.610638 -339.808596) (xy 132.627402 -339.832642) (xy 132.650295 -339.850949)
			(xy 132.67744 -339.862015) (xy 132.706607 -339.864932) (xy 132.721096 -339.862668) (xy 132.738833 -339.859485)
			(xy 132.774706 -339.856046) (xy 132.792724 -339.85581) (xy 132.793486 -339.85581) (xy 132.820739 -339.856268)
			(xy 132.874691 -339.864024) (xy 132.92699 -339.879379) (xy 132.976572 -339.902021) (xy 133.022426 -339.931489)
			(xy 133.063619 -339.967184) (xy 133.099313 -340.008377) (xy 133.128781 -340.054232) (xy 133.151422 -340.103813)
			(xy 133.166777 -340.156113) (xy 133.174532 -340.210065) (xy 133.174994 -340.237318) (xy 133.17474 -340.247732)
			(xy 133.174877 -340.262098) (xy 133.18214 -340.28988) (xy 133.196844 -340.314545) (xy 133.21783 -340.334145)
			(xy 133.24344 -340.347133) (xy 133.271652 -340.352484) (xy 133.285992 -340.351618) (xy 133.322568 -340.34984)
			(xy 133.349826 -340.350205) (xy 133.403787 -340.357959) (xy 133.456095 -340.373314) (xy 133.505686 -340.395958)
			(xy 133.551549 -340.425429) (xy 133.59275 -340.461127) (xy 133.628452 -340.502326) (xy 133.657927 -340.548186)
			(xy 133.680575 -340.597775) (xy 133.695934 -340.650082) (xy 133.703693 -340.704042) (xy 133.703693 -340.758558)
			(xy 133.695934 -340.812518) (xy 133.680575 -340.864825) (xy 133.657927 -340.914414) (xy 133.628452 -340.960274)
			(xy 133.59275 -341.001473) (xy 133.551549 -341.037171) (xy 133.505686 -341.066642) (xy 133.456095 -341.089286)
			(xy 133.403787 -341.104641) (xy 133.349826 -341.112395) (xy 133.322568 -341.112856) (xy 133.311557 -341.112774)
			(xy 133.289572 -341.111506) (xy 133.278626 -341.110316) (xy 133.263768 -341.109077) (xy 133.234433 -341.114331)
			(xy 133.207865 -341.127834) (xy 133.18633 -341.148435) (xy 133.171663 -341.174379) (xy 133.167882 -341.188802)
			(xy 133.161046 -341.216549) (xy 133.140188 -341.269751) (xy 133.111632 -341.31925) (xy 133.076016 -341.363938)
			(xy 133.034138 -341.402819) (xy 132.986931 -341.435023) (xy 132.935451 -341.45983) (xy 132.880849 -341.476686)
			(xy 132.824344 -341.485215) (xy 132.795772 -341.485728) (xy 132.766784 -341.485202) (xy 132.709477 -341.476427)
			(xy 132.654157 -341.459083) (xy 132.602097 -341.433569) (xy 132.554497 -341.400472) (xy 132.512452 -341.360556)
			(xy 132.476929 -341.314737) (xy 132.448748 -341.264073) (xy 132.428556 -341.209727) (xy 132.416818 -341.152952)
			(xy 132.414772 -341.124032) (xy 132.413612 -341.109956) (xy 132.40452 -341.083227) (xy 132.388444 -341.060018)
			(xy 132.366618 -341.042109) (xy 132.340716 -341.030875) (xy 132.312727 -341.027177) (xy 132.298694 -341.028782)
			(xy 132.28493 -341.030679) (xy 132.257216 -341.032711) (xy 132.243322 -341.032846) (xy 132.216073 -341.032301)
			(xy 132.162129 -341.024549) (xy 132.109838 -341.009198) (xy 132.060264 -340.986563) (xy 132.014415 -340.957102)
			(xy 131.973226 -340.921417) (xy 131.937534 -340.880233) (xy 131.908066 -340.834389) (xy 131.885423 -340.784818)
			(xy 131.870064 -340.732529) (xy 131.862303 -340.678587) (xy 131.861814 -340.651338) (xy 131.862301 -340.623764)
			(xy 131.870248 -340.569192) (xy 131.885969 -340.516332) (xy 131.909135 -340.466286) (xy 131.939264 -340.420096)
			(xy 131.975728 -340.378724) (xy 131.996434 -340.360508) (xy 132.00729 -340.350569) (xy 132.023358 -340.325929)
			(xy 132.031742 -340.297733) (xy 132.03175 -340.268316) (xy 132.023378 -340.240116) (xy 132.007322 -340.215468)
			(xy 131.996434 -340.205568) (xy 131.975711 -340.18737) (xy 131.93924 -340.145999) (xy 131.909109 -340.099807)
			(xy 131.885945 -340.049756) (xy 131.870231 -339.996891) (xy 131.862296 -339.942314) (xy 131.861814 -339.914738)
			(xy 131.862248 -339.888236) (xy 131.869597 -339.835744) (xy 131.884146 -339.784776) (xy 131.905614 -339.736314)
			(xy 131.933586 -339.691292) (xy 131.950206 -339.670644) (xy 131.959669 -339.658512) (xy 131.971464 -339.630107)
			(xy 131.974288 -339.599481) (xy 131.967888 -339.569398) (xy 131.95284 -339.542574) (xy 131.930504 -339.521431)
			(xy 131.916932 -339.51418) (xy 131.893237 -339.502088) (xy 131.849257 -339.472162) (xy 131.809977 -339.436289)
			(xy 131.776195 -339.395196) (xy 131.761992 -339.372702) (xy 131.754054 -339.360488) (xy 131.732587 -339.340817)
			(xy 131.706437 -339.328011) (xy 131.677736 -339.323113) (xy 131.648819 -339.326522) (xy 131.635246 -339.331808)
			(xy 131.61204 -339.341307) (xy 131.563705 -339.354654) (xy 131.514014 -339.361379) (xy 131.488942 -339.36178)
			(xy 131.463872 -339.361362) (xy 131.414189 -339.35461) (xy 131.365855 -339.341275) (xy 131.342638 -339.331808)
			(xy 131.329062 -339.326558) (xy 131.30016 -339.323191) (xy 131.27148 -339.328102) (xy 131.245345 -339.340892)
			(xy 131.223871 -339.360526) (xy 131.215892 -339.372702) (xy 131.201323 -339.395833) (xy 131.16648 -339.437954)
			(xy 131.125857 -339.474533) (xy 131.080326 -339.504784) (xy 131.030864 -339.52806) (xy 130.978533 -339.54386)
			(xy 130.924454 -339.551846) (xy 130.86979 -339.551846) (xy 130.815711 -339.54386) (xy 130.76338 -339.52806)
			(xy 130.713918 -339.504784) (xy 130.668387 -339.474533) (xy 130.627764 -339.437954) (xy 130.592921 -339.395833)
			(xy 130.578352 -339.372702) (xy 130.570452 -339.360461) (xy 130.548974 -339.34079) (xy 130.522815 -339.327987)
			(xy 130.494104 -339.323096) (xy 130.465181 -339.326516) (xy 130.451606 -339.331808) (xy 130.428393 -339.341288)
			(xy 130.380061 -339.354643) (xy 130.330373 -339.361375) (xy 130.305302 -339.36178) (xy 130.277412 -339.361361)
			(xy 130.222256 -339.353048) (xy 130.168955 -339.336607) (xy 130.118699 -339.312405) (xy 130.072612 -339.280984)
			(xy 130.031722 -339.243044) (xy 129.996944 -339.199434) (xy 129.969055 -339.151128) (xy 129.948676 -339.099204)
			(xy 129.936264 -339.044823) (xy 129.932095 -338.9892) (xy 127.13232 -338.9892) (xy 127.109982 -339.011514)
			(xy 126.082552 -340.03869) (xy 126.082552 -340.054946) (xy 126.474472 -340.054946) (xy 126.478543 -339.999324)
			(xy 126.490669 -339.944887) (xy 126.510592 -339.892796) (xy 126.537888 -339.844161) (xy 126.571974 -339.800018)
			(xy 126.612123 -339.761309) (xy 126.657481 -339.728858) (xy 126.707081 -339.703357) (xy 126.759865 -339.68535)
			(xy 126.814708 -339.67522) (xy 126.870442 -339.673183) (xy 126.925879 -339.679283) (xy 126.979836 -339.693389)
			(xy 127.031165 -339.715201) (xy 127.078771 -339.744255) (xy 127.121639 -339.77993) (xy 127.158856 -339.821467)
			(xy 127.189629 -339.86798) (xy 127.213301 -339.918477) (xy 127.229369 -339.971884) (xy 127.237489 -340.02706)
			(xy 127.237998 -340.054946) (xy 127.237489 -340.082832) (xy 127.229369 -340.138008) (xy 127.213301 -340.191415)
			(xy 127.189629 -340.241912) (xy 127.158856 -340.288425) (xy 127.121639 -340.329962) (xy 127.078771 -340.365637)
			(xy 127.031165 -340.394691) (xy 126.979836 -340.416503) (xy 126.925879 -340.430609) (xy 126.870442 -340.436709)
			(xy 126.814708 -340.434672) (xy 126.759865 -340.424542) (xy 126.707081 -340.406535) (xy 126.657481 -340.381034)
			(xy 126.612123 -340.348583) (xy 126.571974 -340.309874) (xy 126.537888 -340.265731) (xy 126.510592 -340.217096)
			(xy 126.490669 -340.165005) (xy 126.478543 -340.110568) (xy 126.474472 -340.054946) (xy 126.082552 -340.054946)
			(xy 126.082552 -340.249256) (xy 126.14021 -340.30666) (xy 126.15418 -340.310216) (xy 126.181589 -340.317312)
			(xy 126.23409 -340.338497) (xy 126.282881 -340.367215) (xy 126.326887 -340.402834) (xy 126.365141 -340.44457)
			(xy 126.3968 -340.491506) (xy 126.421169 -340.542608) (xy 126.437711 -340.596753) (xy 126.446062 -340.652748)
			(xy 126.446534 -340.681056) (xy 126.446074 -340.708312) (xy 126.438322 -340.762269) (xy 126.42297 -340.814573)
			(xy 126.400331 -340.864161) (xy 126.370864 -340.910021) (xy 126.335171 -340.951221) (xy 126.293977 -340.986922)
			(xy 126.248122 -341.016397) (xy 126.198539 -341.039046) (xy 126.146237 -341.054408) (xy 126.092282 -341.062169)
			(xy 126.065026 -341.062564) (xy 126.036736 -341.062051) (xy 125.980775 -341.053695) (xy 125.926663 -341.037163)
			(xy 125.875588 -341.012817) (xy 125.828671 -340.981192) (xy 125.786941 -340.942981) (xy 125.751314 -340.899025)
			(xy 125.722574 -340.850287) (xy 125.701349 -340.797838) (xy 125.694186 -340.770464) (xy 125.690884 -340.756494)
			(xy 125.540008 -340.605618) (xy 125.522727 -340.587618) (xy 125.493424 -340.547234) (xy 125.470789 -340.502767)
			(xy 125.455379 -340.455311) (xy 125.447571 -340.40603) (xy 125.447044 -340.381082) (xy 125.447044 -339.906864)
			(xy 125.447528 -339.881912) (xy 125.455324 -339.832622) (xy 125.470734 -339.785158) (xy 125.493379 -339.740688)
			(xy 125.522701 -339.700308) (xy 125.540008 -339.682328) (xy 126.07798 -339.144356) (xy 126.087748 -339.133932)
			(xy 126.101582 -339.108953) (xy 126.107953 -339.081118) (xy 126.106359 -339.052608) (xy 126.096927 -339.025656)
			(xy 126.080394 -339.002375) (xy 126.058057 -338.984587) (xy 126.031665 -338.973686) (xy 126.017528 -338.971636)
			(xy 125.990205 -338.9677) (xy 125.937001 -338.952978) (xy 125.886472 -338.930749) (xy 125.839671 -338.901475)
			(xy 125.797573 -338.865767) (xy 125.761056 -338.824369) (xy 125.73088 -338.778144) (xy 125.707676 -338.728056)
			(xy 125.691926 -338.675148) (xy 125.68396 -338.620523) (xy 125.683518 -338.592922) (xy 125.683518 -338.592668)
			(xy 125.683992 -338.565534) (xy 125.691679 -338.511812) (xy 125.706908 -338.459724) (xy 125.72937 -338.410322)
			(xy 125.758612 -338.364606) (xy 125.775974 -338.343748) (xy 125.777752 -338.34197) (xy 125.779022 -338.340192)
			(xy 125.781816 -338.337144) (xy 125.791551 -338.325588) (xy 125.804389 -338.298254) (xy 125.808648 -338.268357)
			(xy 125.803953 -338.238526) (xy 125.790718 -338.211382) (xy 125.7808 -338.199984) (xy 125.76258 -338.178881)
			(xy 125.731824 -338.132381) (xy 125.708165 -338.081898) (xy 125.692108 -338.028509) (xy 125.683995 -337.973352)
			(xy 125.683518 -337.945476) (xy 125.683518 -337.94065) (xy 125.684313 -337.913612) (xy 125.692594 -337.860158)
			(xy 125.708341 -337.80841) (xy 125.73124 -337.759405) (xy 125.76083 -337.714124) (xy 125.796518 -337.673477)
			(xy 125.83759 -337.638278) (xy 125.883222 -337.609233) (xy 125.932498 -337.586923) (xy 125.984431 -337.571797)
			(xy 126.03798 -337.564158) (xy 126.092072 -337.564158) (xy 126.145621 -337.571797) (xy 126.197554 -337.586923)
			(xy 126.24683 -337.609233) (xy 126.292462 -337.638278) (xy 126.333534 -337.673477) (xy 126.369222 -337.714124)
			(xy 126.398812 -337.759405) (xy 126.421711 -337.80841) (xy 126.437458 -337.860158) (xy 126.445739 -337.913612)
			(xy 126.446534 -337.94065) (xy 126.446534 -337.945476) (xy 126.446057 -337.972609) (xy 126.438363 -338.026327)
			(xy 126.423128 -338.07841) (xy 126.40066 -338.127806) (xy 126.371412 -338.173516) (xy 126.354078 -338.194396)
			(xy 126.3523 -338.196174) (xy 126.35103 -338.197952) (xy 126.348236 -338.201) (xy 126.339203 -338.211623)
			(xy 126.326793 -338.236583) (xy 126.321618 -338.263973) (xy 126.324066 -338.29174) (xy 126.333953 -338.317802)
			(xy 126.341886 -338.32927) (xy 126.35357 -338.343494) (xy 126.354586 -338.345018) (xy 126.356618 -338.347304)
			(xy 126.374037 -338.368673) (xy 126.403182 -338.415471) (xy 126.42528 -338.465979) (xy 126.43987 -338.519143)
			(xy 126.44374 -338.54644) (xy 126.445914 -338.560509) (xy 126.456989 -338.586722) (xy 126.474875 -338.608856)
			(xy 126.498179 -338.625187) (xy 126.525087 -338.634446) (xy 126.553506 -338.635912) (xy 126.581224 -338.629471)
			(xy 126.606084 -338.615624) (xy 126.61646 -338.605876) (xy 126.803912 -338.418424) (xy 126.803912 -337.231482)
			(xy 126.759208 -337.186778) (xy 126.741923 -337.168779) (xy 126.712612 -337.128397) (xy 126.689969 -337.083931)
			(xy 126.67455 -337.036474) (xy 126.666734 -336.987191) (xy 126.666244 -336.962242) (xy 126.666244 -334.29321)
			(xy 126.666732 -334.26826) (xy 126.674536 -334.218974) (xy 126.689952 -334.171515) (xy 126.712602 -334.127051)
			(xy 126.741927 -334.086678) (xy 126.759208 -334.068674) (xy 126.859284 -333.968852) (xy 126.859284 -329.74788)
			(xy 123.436634 -326.32523) (xy 118.67642 -326.32523) (xy 118.67642 -327.009506) (xy 119.093996 -327.426828)
			(xy 119.11128 -327.444827) (xy 119.14059 -327.48521) (xy 119.163232 -327.529676) (xy 119.17865 -327.577132)
			(xy 119.186465 -327.626415) (xy 119.18696 -327.651364) (xy 119.18696 -328.152252) (xy 119.187468 -331.84973)
			(xy 119.187468 -335.213198) (xy 119.186949 -335.238179) (xy 119.179086 -335.287518) (xy 119.163613 -335.335025)
			(xy 119.140912 -335.379532) (xy 119.111539 -335.419949) (xy 119.09425 -335.437988) (xy 118.953108 -335.579)
			(xy 121.771617 -335.579) (xy 121.775785 -335.523381) (xy 121.788196 -335.469004) (xy 121.808573 -335.417085)
			(xy 121.83646 -335.368782) (xy 121.871235 -335.325175) (xy 121.91212 -335.287238) (xy 121.958203 -335.255818)
			(xy 122.008454 -335.231617) (xy 122.061751 -335.215176) (xy 122.116903 -335.206862) (xy 122.14479 -335.20634)
			(xy 122.172123 -335.206784) (xy 122.226204 -335.214758) (xy 122.278539 -335.230551) (xy 122.328004 -335.253823)
			(xy 122.373536 -335.284075) (xy 122.414157 -335.320657) (xy 122.448995 -335.362784) (xy 122.46356 -335.385918)
			(xy 122.471444 -335.39817) (xy 122.492927 -335.417839) (xy 122.519091 -335.430639) (xy 122.547805 -335.435527)
			(xy 122.57673 -335.432105) (xy 122.590306 -335.426812) (xy 122.613518 -335.417329) (xy 122.66185 -335.403975)
			(xy 122.711539 -335.397245) (xy 122.73661 -335.39684) (xy 122.761679 -335.397272) (xy 122.811362 -335.404018)
			(xy 122.859696 -335.417347) (xy 122.882914 -335.426812) (xy 122.89651 -335.432003) (xy 122.925401 -335.435379)
			(xy 122.954073 -335.430481) (xy 122.980204 -335.417706) (xy 123.001678 -335.398087) (xy 123.00966 -335.385918)
			(xy 123.024229 -335.362787) (xy 123.059072 -335.320666) (xy 123.099695 -335.284087) (xy 123.145226 -335.253836)
			(xy 123.194688 -335.23056) (xy 123.247019 -335.21476) (xy 123.301098 -335.206774) (xy 123.355762 -335.206774)
			(xy 123.409841 -335.21476) (xy 123.462172 -335.23056) (xy 123.511634 -335.253836) (xy 123.557165 -335.284087)
			(xy 123.597788 -335.320666) (xy 123.632631 -335.362787) (xy 123.6472 -335.385918) (xy 123.655141 -335.398129)
			(xy 123.676608 -335.417798) (xy 123.702757 -335.430603) (xy 123.731457 -335.435502) (xy 123.760373 -335.432096)
			(xy 123.773946 -335.426812) (xy 123.797154 -335.417317) (xy 123.845488 -335.403968) (xy 123.895178 -335.397242)
			(xy 123.92025 -335.39684) (xy 123.948136 -335.397416) (xy 124.003286 -335.405721) (xy 124.056582 -335.422155)
			(xy 124.106833 -335.446348) (xy 124.152917 -335.477762) (xy 124.193803 -335.515694) (xy 124.228579 -335.559296)
			(xy 124.256467 -335.607595) (xy 124.276844 -335.659511) (xy 124.289256 -335.713884) (xy 124.293424 -335.7695)
			(xy 124.289256 -335.825116) (xy 124.276844 -335.879489) (xy 124.256467 -335.931405) (xy 124.228579 -335.979704)
			(xy 124.193803 -336.023306) (xy 124.152917 -336.061238) (xy 124.106833 -336.092652) (xy 124.056582 -336.116845)
			(xy 124.003286 -336.133279) (xy 123.948136 -336.141584) (xy 123.92025 -336.142076) (xy 123.892918 -336.141593)
			(xy 123.838839 -336.133625) (xy 123.786506 -336.117839) (xy 123.737042 -336.094572) (xy 123.691509 -336.064327)
			(xy 123.650887 -336.02775) (xy 123.616046 -335.985629) (xy 123.60148 -335.962498) (xy 123.593554 -335.950276)
			(xy 123.572084 -335.930605) (xy 123.545931 -335.9178) (xy 123.517226 -335.912904) (xy 123.488308 -335.916316)
			(xy 123.474734 -335.921604) (xy 123.451517 -335.931076) (xy 123.403188 -335.944433) (xy 123.353501 -335.951169)
			(xy 123.32843 -335.951576) (xy 123.30336 -335.951163) (xy 123.253677 -335.944409) (xy 123.205343 -335.931072)
			(xy 123.182126 -335.921604) (xy 123.168553 -335.916343) (xy 123.13965 -335.912979) (xy 123.110969 -335.917892)
			(xy 123.084834 -335.930685) (xy 123.063359 -335.950321) (xy 123.05538 -335.962498) (xy 123.040811 -335.985629)
			(xy 123.005968 -336.02775) (xy 122.965345 -336.064329) (xy 122.919814 -336.09458) (xy 122.870352 -336.117856)
			(xy 122.818021 -336.133656) (xy 122.763942 -336.141642) (xy 122.709278 -336.141642) (xy 122.655199 -336.133656)
			(xy 122.602868 -336.117856) (xy 122.553406 -336.09458) (xy 122.507875 -336.064329) (xy 122.467252 -336.02775)
			(xy 122.432409 -335.985629) (xy 122.41784 -335.962498) (xy 122.409952 -335.950248) (xy 122.388471 -335.930577)
			(xy 122.362308 -335.917776) (xy 122.333594 -335.912888) (xy 122.304669 -335.91631) (xy 122.291094 -335.921604)
			(xy 122.267882 -335.931088) (xy 122.21955 -335.944441) (xy 122.169861 -335.951171) (xy 122.14479 -335.951576)
			(xy 122.116903 -335.951138) (xy 122.061751 -335.942824) (xy 122.008454 -335.926383) (xy 121.958203 -335.902182)
			(xy 121.91212 -335.870762) (xy 121.871235 -335.832825) (xy 121.83646 -335.789218) (xy 121.808573 -335.740915)
			(xy 121.788196 -335.688996) (xy 121.775785 -335.634619) (xy 121.771617 -335.579) (xy 118.953108 -335.579)
			(xy 118.819168 -335.712816) (xy 118.222268 -336.309462) (xy 118.222268 -336.33664) (xy 118.222727 -336.350491)
			(xy 118.230164 -336.377174) (xy 118.244505 -336.400874) (xy 118.264694 -336.419841) (xy 118.289241 -336.432677)
			(xy 118.316336 -336.438436) (xy 118.343982 -336.436693) (xy 118.37014 -336.427577) (xy 118.39288 -336.411759)
			(xy 118.4021 -336.40141) (xy 118.420313 -336.380177) (xy 118.461893 -336.342758) (xy 118.508493 -336.311814)
			(xy 118.559114 -336.288009) (xy 118.612668 -336.271853) (xy 118.668009 -336.263693) (xy 118.695978 -336.263234)
			(xy 118.723229 -336.263696) (xy 118.777176 -336.271449) (xy 118.829471 -336.286802) (xy 118.879048 -336.30944)
			(xy 118.924899 -336.338905) (xy 118.96609 -336.374594) (xy 119.001782 -336.415783) (xy 119.031249 -336.461632)
			(xy 119.053891 -336.511208) (xy 119.069246 -336.563502) (xy 119.077003 -336.617449) (xy 119.077003 -336.671951)
			(xy 119.069246 -336.725898) (xy 119.053891 -336.778192) (xy 119.031249 -336.827768) (xy 119.001782 -336.873617)
			(xy 118.96609 -336.914806) (xy 118.924899 -336.950495) (xy 118.879048 -336.97996) (xy 118.829471 -337.002598)
			(xy 118.777176 -337.017951) (xy 118.723229 -337.025704) (xy 118.695978 -337.02625) (xy 118.668011 -337.025759)
			(xy 118.612677 -337.017591) (xy 118.559127 -337.001435) (xy 118.508509 -336.977635) (xy 118.461907 -336.946702)
			(xy 118.420319 -336.909298) (xy 118.4021 -336.888074) (xy 118.392908 -336.877715) (xy 118.370163 -336.861935)
			(xy 118.344014 -336.852848) (xy 118.316385 -336.851124) (xy 118.289309 -336.856888) (xy 118.264778 -336.869717)
			(xy 118.244597 -336.888666) (xy 118.230252 -336.912343) (xy 118.222797 -336.939003) (xy 118.222268 -336.952844)
			(xy 118.222268 -337.048094) (xy 118.229888 -337.060286) (xy 118.243203 -337.082857) (xy 118.264194 -337.130872)
			(xy 118.278412 -337.18131) (xy 118.285586 -337.23322) (xy 118.286022 -337.259422) (xy 118.285536 -337.286673)
			(xy 118.27778 -337.340621) (xy 118.262425 -337.392916) (xy 118.239783 -337.442493) (xy 118.210317 -337.488343)
			(xy 118.174626 -337.529534) (xy 118.133435 -337.565225) (xy 118.087585 -337.594691) (xy 118.038008 -337.617333)
			(xy 117.985713 -337.632688) (xy 117.931765 -337.640444) (xy 117.877263 -337.640444) (xy 117.823315 -337.632688)
			(xy 117.77102 -337.617333) (xy 117.721443 -337.594691) (xy 117.675593 -337.565225) (xy 117.634402 -337.529534)
			(xy 117.598711 -337.488343) (xy 117.569245 -337.442493) (xy 117.546603 -337.392916) (xy 117.531248 -337.340621)
			(xy 117.523492 -337.286673) (xy 117.523006 -337.259422) (xy 117.523496 -337.231447) (xy 117.53167 -337.176096)
			(xy 117.547844 -337.122534) (xy 117.571673 -337.071911) (xy 117.58676 -337.048348) (xy 117.58676 -336.177636)
			(xy 117.587246 -336.152685) (xy 117.595047 -336.103397) (xy 117.61046 -336.055936) (xy 117.633109 -336.011471)
			(xy 117.662434 -335.971095) (xy 117.679724 -335.9531) (xy 117.906546 -335.726278) (xy 117.916027 -335.716137)
			(xy 117.929647 -335.691959) (xy 117.936253 -335.665008) (xy 117.935359 -335.637272) (xy 117.92703 -335.610802)
			(xy 117.911881 -335.587552) (xy 117.891032 -335.569239) (xy 117.866022 -335.557217) (xy 117.852444 -335.55432)
			(xy 117.825399 -335.550119) (xy 117.772803 -335.534979) (xy 117.72291 -335.512477) (xy 117.676746 -335.483077)
			(xy 117.635257 -335.447381) (xy 117.599295 -335.406123) (xy 117.569598 -335.360148) (xy 117.546776 -335.310402)
			(xy 117.531298 -335.257904) (xy 117.523481 -335.203734) (xy 117.523006 -335.176368) (xy 117.523494 -335.1488)
			(xy 117.531433 -335.094239) (xy 117.547143 -335.041388) (xy 117.570295 -334.991349) (xy 117.600408 -334.945162)
			(xy 117.618256 -334.924146) (xy 117.62701 -334.912956) (xy 117.63854 -334.887001) (xy 117.64248 -334.858875)
			(xy 117.638526 -334.830752) (xy 117.626984 -334.804803) (xy 117.618256 -334.79359) (xy 117.600392 -334.772585)
			(xy 117.57027 -334.7264) (xy 117.547113 -334.676358) (xy 117.531403 -334.623504) (xy 117.523468 -334.568938)
			(xy 117.523006 -334.541368) (xy 117.523492 -334.514117) (xy 117.531248 -334.460169) (xy 117.546603 -334.407874)
			(xy 117.569245 -334.358297) (xy 117.598711 -334.312447) (xy 117.634402 -334.271256) (xy 117.675593 -334.235565)
			(xy 117.721443 -334.206099) (xy 117.77102 -334.183457) (xy 117.823315 -334.168102) (xy 117.877263 -334.160346)
			(xy 117.931765 -334.160346) (xy 117.985713 -334.168102) (xy 118.038008 -334.183457) (xy 118.087585 -334.206099)
			(xy 118.133435 -334.235565) (xy 118.174626 -334.271256) (xy 118.210317 -334.312447) (xy 118.239783 -334.358297)
			(xy 118.262425 -334.407874) (xy 118.27778 -334.460169) (xy 118.285536 -334.514117) (xy 118.286022 -334.541368)
			(xy 118.285532 -334.568935) (xy 118.277588 -334.623494) (xy 118.261876 -334.676343) (xy 118.238721 -334.72638)
			(xy 118.208608 -334.772564) (xy 118.190772 -334.79359) (xy 118.182006 -334.80478) (xy 118.170457 -334.830739)
			(xy 118.1665 -334.858875) (xy 118.170443 -334.887013) (xy 118.18198 -334.912979) (xy 118.190772 -334.924146)
			(xy 118.208872 -334.945424) (xy 118.239298 -334.992273) (xy 118.262567 -335.043058) (xy 118.278183 -335.096693)
			(xy 118.282466 -335.124298) (xy 118.285356 -335.137879) (xy 118.297388 -335.162891) (xy 118.315707 -335.183742)
			(xy 118.338962 -335.198895) (xy 118.365436 -335.20723) (xy 118.393177 -335.208133) (xy 118.420137 -335.201537)
			(xy 118.444328 -335.187929) (xy 118.454424 -335.1784) (xy 118.551452 -335.081372) (xy 118.551452 -327.78319)
			(xy 118.133876 -327.365868) (xy 118.116589 -327.347871) (xy 118.087273 -327.30749) (xy 118.064626 -327.263024)
			(xy 118.049205 -327.215566) (xy 118.041388 -327.166282) (xy 118.040912 -327.141332) (xy 118.040912 -326.32523)
			(xy 111.745268 -326.32523) (xy 111.745268 -327.84288) (xy 111.744751 -327.867861) (xy 111.736889 -327.917202)
			(xy 111.721419 -327.964711) (xy 111.69872 -328.00922) (xy 111.669348 -328.049639) (xy 111.65205 -328.06767)
			(xy 111.0615 -328.65822) (xy 111.0615 -335.32826) (xy 111.060984 -335.353242) (xy 111.053126 -335.402585)
			(xy 111.03766 -335.450097) (xy 111.014964 -335.49461) (xy 110.985595 -335.535033) (xy 110.968282 -335.55305)
			(xy 110.942332 -335.579) (xy 113.611117 -335.579) (xy 113.615285 -335.523382) (xy 113.627696 -335.469007)
			(xy 113.648071 -335.417088) (xy 113.675957 -335.368786) (xy 113.710731 -335.325179) (xy 113.751615 -335.287242)
			(xy 113.797696 -335.255822) (xy 113.847945 -335.23162) (xy 113.901241 -335.215178) (xy 113.956391 -335.206863)
			(xy 113.984278 -335.20634) (xy 114.011611 -335.206794) (xy 114.065691 -335.214766) (xy 114.118026 -335.230557)
			(xy 114.167491 -335.253828) (xy 114.213023 -335.284078) (xy 114.253644 -335.320659) (xy 114.288483 -335.362784)
			(xy 114.303048 -335.385918) (xy 114.310943 -335.398162) (xy 114.332423 -335.417831) (xy 114.358584 -335.430632)
			(xy 114.387295 -335.435522) (xy 114.416219 -335.432103) (xy 114.429794 -335.426812) (xy 114.453008 -335.417333)
			(xy 114.501339 -335.403978) (xy 114.551027 -335.397245) (xy 114.576098 -335.39684) (xy 114.601167 -335.397276)
			(xy 114.65085 -335.40402) (xy 114.699184 -335.417348) (xy 114.722402 -335.426812) (xy 114.736003 -335.43199)
			(xy 114.764891 -335.435369) (xy 114.793561 -335.430474) (xy 114.819692 -335.417701) (xy 114.841166 -335.398085)
			(xy 114.849148 -335.385918) (xy 114.863717 -335.362787) (xy 114.89856 -335.320666) (xy 114.939183 -335.284087)
			(xy 114.984714 -335.253836) (xy 115.034176 -335.23056) (xy 115.086507 -335.21476) (xy 115.140586 -335.206774)
			(xy 115.19525 -335.206774) (xy 115.249329 -335.21476) (xy 115.30166 -335.23056) (xy 115.351122 -335.253836)
			(xy 115.396653 -335.284087) (xy 115.437276 -335.320666) (xy 115.472119 -335.362787) (xy 115.486688 -335.385918)
			(xy 115.49464 -335.398121) (xy 115.516105 -335.41779) (xy 115.54225 -335.430596) (xy 115.570948 -335.435497)
			(xy 115.599861 -335.432094) (xy 115.613434 -335.426812) (xy 115.636643 -335.41732) (xy 115.684976 -335.40397)
			(xy 115.734666 -335.397243) (xy 115.759738 -335.39684) (xy 115.78658 -335.3973) (xy 115.839709 -335.405008)
			(xy 115.891181 -335.420261) (xy 115.939933 -335.442741) (xy 115.984954 -335.471983) (xy 116.025313 -335.507383)
			(xy 116.060175 -335.548208) (xy 116.088819 -335.593613) (xy 116.110651 -335.642658) (xy 116.118386 -335.668366)
			(xy 116.123076 -335.682853) (xy 116.13959 -335.708413) (xy 116.1629 -335.727976) (xy 116.190938 -335.739807)
			(xy 116.221216 -335.742856) (xy 116.251049 -335.736853) (xy 116.26469 -335.730088) (xy 116.29283 -335.715442)
			(xy 116.352784 -335.69472) (xy 116.415345 -335.684226) (xy 116.447062 -335.683606) (xy 116.465081 -335.683822)
			(xy 116.500956 -335.687259) (xy 116.51869 -335.690464) (xy 116.5339 -335.692788) (xy 116.564451 -335.689263)
			(xy 116.592569 -335.676805) (xy 116.615704 -335.656543) (xy 116.631761 -335.630314) (xy 116.636038 -335.615534)
			(xy 116.643402 -335.58848) (xy 116.665036 -335.536753) (xy 116.694005 -335.488747) (xy 116.729685 -335.445495)
			(xy 116.771308 -335.407929) (xy 116.81798 -335.376856) (xy 116.868695 -335.352946) (xy 116.922362 -335.336711)
			(xy 116.977827 -335.328503) (xy 117.005862 -335.328006) (xy 117.033115 -335.328491) (xy 117.087065 -335.336243)
			(xy 117.139364 -335.351595) (xy 117.188945 -335.374234) (xy 117.234799 -335.403699) (xy 117.275992 -335.439391)
			(xy 117.311686 -335.480582) (xy 117.341155 -335.526434) (xy 117.363797 -335.576014) (xy 117.379152 -335.628311)
			(xy 117.386908 -335.682261) (xy 117.38737 -335.709514) (xy 117.386856 -335.737087) (xy 117.378914 -335.791658)
			(xy 117.3632 -335.844517) (xy 117.340039 -335.894564) (xy 117.309915 -335.940755) (xy 117.273454 -335.982127)
			(xy 117.25275 -336.000344) (xy 117.241835 -336.010226) (xy 117.225755 -336.034879) (xy 117.217369 -336.063092)
			(xy 117.217371 -336.092526) (xy 117.225763 -336.120737) (xy 117.241847 -336.145388) (xy 117.25275 -336.155284)
			(xy 117.273472 -336.173483) (xy 117.30994 -336.214855) (xy 117.34007 -336.261046) (xy 117.363235 -336.311095)
			(xy 117.378951 -336.363959) (xy 117.386892 -336.418534) (xy 117.38689 -336.473684) (xy 117.378947 -336.528259)
			(xy 117.363229 -336.581121) (xy 117.340061 -336.631169) (xy 117.309929 -336.67736) (xy 117.273459 -336.71873)
			(xy 117.25275 -336.736944) (xy 117.241835 -336.746826) (xy 117.225755 -336.771479) (xy 117.217369 -336.799692)
			(xy 117.217371 -336.829126) (xy 117.225763 -336.857337) (xy 117.241847 -336.881988) (xy 117.25275 -336.891884)
			(xy 117.273467 -336.910089) (xy 117.309934 -336.95146) (xy 117.340065 -336.997652) (xy 117.363229 -337.047701)
			(xy 117.378945 -337.100564) (xy 117.386884 -337.155139) (xy 117.38737 -337.182714) (xy 117.386958 -337.209969)
			(xy 117.379198 -337.263924) (xy 117.363838 -337.316225) (xy 117.341192 -337.365808) (xy 117.311718 -337.411663)
			(xy 117.276019 -337.452856) (xy 117.234821 -337.48855) (xy 117.188962 -337.518016) (xy 117.139376 -337.540657)
			(xy 117.087073 -337.556009) (xy 117.033117 -337.563762) (xy 117.005862 -337.564222) (xy 116.978006 -337.563717)
			(xy 116.922891 -337.555588) (xy 116.869541 -337.539539) (xy 116.819089 -337.515909) (xy 116.772605 -337.4852)
			(xy 116.731076 -337.448063) (xy 116.695383 -337.405287) (xy 116.666284 -337.357779) (xy 116.644395 -337.306547)
			(xy 116.6368 -337.279742) (xy 116.632472 -337.265645) (xy 116.617096 -337.240501) (xy 116.595191 -337.220783)
			(xy 116.568575 -337.208127) (xy 116.539455 -337.203582) (xy 116.524786 -337.205066) (xy 116.511769 -337.206735)
			(xy 116.485585 -337.208515) (xy 116.472462 -337.208622) (xy 116.458313 -337.208532) (xy 116.43009 -337.206495)
			(xy 116.416074 -337.204558) (xy 116.402721 -337.203043) (xy 116.376039 -337.206134) (xy 116.351092 -337.216091)
			(xy 116.329615 -337.232222) (xy 116.313101 -337.253406) (xy 116.302698 -337.27817) (xy 116.300504 -337.291426)
			(xy 116.296414 -337.318579) (xy 116.281442 -337.37141) (xy 116.259052 -337.42155) (xy 116.229705 -337.467961)
			(xy 116.194009 -337.509686) (xy 116.152699 -337.545863) (xy 116.106629 -337.575744) (xy 116.056752 -337.598712)
			(xy 116.004098 -337.614293) (xy 115.949754 -337.622165) (xy 115.922298 -337.622642) (xy 115.895048 -337.622124)
			(xy 115.841103 -337.614368) (xy 115.788811 -337.599015) (xy 115.739236 -337.576376) (xy 115.693388 -337.546912)
			(xy 115.652198 -337.511224) (xy 115.616507 -337.470038) (xy 115.58704 -337.424192) (xy 115.564397 -337.374619)
			(xy 115.549039 -337.322328) (xy 115.541278 -337.268384) (xy 115.54079 -337.241134) (xy 115.541283 -337.21356)
			(xy 115.54923 -337.158989) (xy 115.56495 -337.10613) (xy 115.588115 -337.056084) (xy 115.618243 -337.009893)
			(xy 115.654705 -336.968521) (xy 115.67541 -336.950304) (xy 115.686272 -336.94037) (xy 115.702343 -336.915729)
			(xy 115.71073 -336.887531) (xy 115.710736 -336.858113) (xy 115.702362 -336.829911) (xy 115.686301 -336.805263)
			(xy 115.67541 -336.795364) (xy 115.65468 -336.777173) (xy 115.618211 -336.7358) (xy 115.588081 -336.689606)
			(xy 115.564918 -336.639554) (xy 115.549206 -336.586688) (xy 115.541272 -336.53211) (xy 115.54079 -336.504534)
			(xy 115.541227 -336.478032) (xy 115.548576 -336.425541) (xy 115.563125 -336.374573) (xy 115.584592 -336.326111)
			(xy 115.612563 -336.281089) (xy 115.629182 -336.26044) (xy 115.638623 -336.248295) (xy 115.650406 -336.219894)
			(xy 115.653226 -336.189276) (xy 115.646829 -336.159201) (xy 115.631793 -336.13238) (xy 115.609472 -336.111232)
			(xy 115.595908 -336.103976) (xy 115.572209 -336.091892) (xy 115.528229 -336.061964) (xy 115.48895 -336.026088)
			(xy 115.45517 -335.984993) (xy 115.440968 -335.962498) (xy 115.433053 -335.950267) (xy 115.41158 -335.930597)
			(xy 115.385424 -335.917793) (xy 115.356717 -335.912899) (xy 115.327796 -335.916314) (xy 115.314222 -335.921604)
			(xy 115.291007 -335.931079) (xy 115.242677 -335.944436) (xy 115.192989 -335.95117) (xy 115.167918 -335.951576)
			(xy 115.142849 -335.951134) (xy 115.093167 -335.944392) (xy 115.044832 -335.931067) (xy 115.021614 -335.921604)
			(xy 115.008009 -335.916436) (xy 114.979123 -335.913053) (xy 114.950453 -335.917945) (xy 114.924323 -335.930716)
			(xy 114.902849 -335.950331) (xy 114.894868 -335.962498) (xy 114.880299 -335.985629) (xy 114.845456 -336.02775)
			(xy 114.804833 -336.064329) (xy 114.759302 -336.09458) (xy 114.70984 -336.117856) (xy 114.657509 -336.133656)
			(xy 114.60343 -336.141642) (xy 114.548766 -336.141642) (xy 114.494687 -336.133656) (xy 114.442356 -336.117856)
			(xy 114.392894 -336.09458) (xy 114.347363 -336.064329) (xy 114.30674 -336.02775) (xy 114.271897 -335.985629)
			(xy 114.257328 -335.962498) (xy 114.249451 -335.95024) (xy 114.227967 -335.930569) (xy 114.201801 -335.917769)
			(xy 114.173085 -335.912883) (xy 114.144158 -335.916308) (xy 114.130582 -335.921604) (xy 114.107371 -335.931092)
			(xy 114.059039 -335.944443) (xy 114.00935 -335.951172) (xy 113.984278 -335.951576) (xy 113.956391 -335.951137)
			(xy 113.901241 -335.942822) (xy 113.847945 -335.92638) (xy 113.797696 -335.902178) (xy 113.751615 -335.870758)
			(xy 113.710731 -335.832821) (xy 113.675957 -335.789214) (xy 113.648071 -335.740912) (xy 113.627696 -335.688993)
			(xy 113.615285 -335.634618) (xy 113.611117 -335.579) (xy 110.942332 -335.579) (xy 110.43031 -336.091022)
			(xy 110.419976 -336.102147) (xy 110.405765 -336.12896) (xy 110.40005 -336.158764) (xy 110.403337 -336.188933)
			(xy 110.415334 -336.216807) (xy 110.434986 -336.239932) (xy 110.46056 -336.256269) (xy 110.489803 -336.264379)
			(xy 110.504986 -336.264504) (xy 110.535466 -336.263234) (xy 110.562717 -336.263695) (xy 110.616666 -336.271447)
			(xy 110.668962 -336.286798) (xy 110.718541 -336.309437) (xy 110.764394 -336.3389) (xy 110.805586 -336.37459)
			(xy 110.841279 -336.415779) (xy 110.870747 -336.461629) (xy 110.89339 -336.511206) (xy 110.908746 -336.563501)
			(xy 110.916503 -336.617449) (xy 110.916503 -336.671951) (xy 110.908746 -336.725899) (xy 110.89339 -336.778194)
			(xy 110.870747 -336.827771) (xy 110.841279 -336.873621) (xy 110.805586 -336.91481) (xy 110.764394 -336.9505)
			(xy 110.718541 -336.979963) (xy 110.668962 -337.002602) (xy 110.616666 -337.017953) (xy 110.562717 -337.025705)
			(xy 110.535466 -337.02625) (xy 110.509594 -337.025817) (xy 110.458325 -337.018823) (xy 110.408471 -337.004968)
			(xy 110.360945 -336.984507) (xy 110.316619 -336.957813) (xy 110.296198 -336.941922) (xy 110.289086 -336.936334)
			(xy 110.27283 -336.930746) (xy 110.263521 -336.927995) (xy 110.24415 -336.928944) (xy 110.226514 -336.937014)
			(xy 110.213133 -336.951053) (xy 110.205918 -336.969055) (xy 110.20552 -336.978752) (xy 110.20552 -337.059524)
			(xy 110.21314 -337.071716) (xy 110.226512 -337.094372) (xy 110.247597 -337.142569) (xy 110.261883 -337.1932)
			(xy 110.2691 -337.24531) (xy 110.269528 -337.271614) (xy 110.269528 -337.27263) (xy 110.269041 -337.299918)
			(xy 110.261275 -337.353937) (xy 110.245899 -337.406301) (xy 110.223228 -337.455945) (xy 110.193722 -337.501856)
			(xy 110.157983 -337.543101) (xy 110.116738 -337.57884) (xy 110.070827 -337.608346) (xy 110.021183 -337.631017)
			(xy 109.968819 -337.646393) (xy 109.9148 -337.654159) (xy 109.860224 -337.654159) (xy 109.806205 -337.646393)
			(xy 109.753841 -337.631017) (xy 109.704197 -337.608346) (xy 109.658286 -337.57884) (xy 109.617041 -337.543101)
			(xy 109.581302 -337.501856) (xy 109.551796 -337.455945) (xy 109.529125 -337.406301) (xy 109.513749 -337.353937)
			(xy 109.505983 -337.299918) (xy 109.505496 -337.27263) (xy 109.505989 -337.244583) (xy 109.514197 -337.189092)
			(xy 109.53044 -337.135401) (xy 109.554368 -337.084665) (xy 109.569504 -337.061048) (xy 109.569504 -336.18424)
			(xy 109.57002 -336.159258) (xy 109.577878 -336.109915) (xy 109.593345 -336.062404) (xy 109.616041 -336.017891)
			(xy 109.64541 -335.977468) (xy 109.662722 -335.95945) (xy 110.425484 -335.196688) (xy 110.425484 -328.526648)
			(xy 110.425999 -328.501666) (xy 110.433855 -328.452321) (xy 110.449321 -328.404809) (xy 110.472015 -328.360294)
			(xy 110.501382 -328.319869) (xy 110.518702 -328.301858) (xy 111.109252 -327.711308) (xy 111.109252 -326.32523)
			(xy 102.777544 -326.32523) (xy 102.777544 -335.176368) (xy 109.362494 -335.176368) (xy 109.362943 -335.148997)
			(xy 109.370765 -335.094817) (xy 109.386258 -335.042314) (xy 109.409104 -334.992568) (xy 109.438831 -334.946601)
			(xy 109.456474 -334.92567) (xy 109.465744 -334.914367) (xy 109.477921 -334.887801) (xy 109.482088 -334.858876)
			(xy 109.477907 -334.829953) (xy 109.465717 -334.803393) (xy 109.456474 -334.792066) (xy 109.438848 -334.771123)
			(xy 109.409135 -334.725153) (xy 109.386297 -334.675408) (xy 109.370803 -334.62291) (xy 109.362971 -334.568736)
			(xy 109.362494 -334.541368) (xy 109.36298 -334.514117) (xy 109.370736 -334.460169) (xy 109.386091 -334.407874)
			(xy 109.408733 -334.358297) (xy 109.438199 -334.312447) (xy 109.47389 -334.271256) (xy 109.515081 -334.235565)
			(xy 109.560931 -334.206099) (xy 109.610508 -334.183457) (xy 109.662803 -334.168102) (xy 109.716751 -334.160346)
			(xy 109.771253 -334.160346) (xy 109.825201 -334.168102) (xy 109.877496 -334.183457) (xy 109.927073 -334.206099)
			(xy 109.972923 -334.235565) (xy 110.014114 -334.271256) (xy 110.049805 -334.312447) (xy 110.079271 -334.358297)
			(xy 110.101913 -334.407874) (xy 110.117268 -334.460169) (xy 110.125024 -334.514117) (xy 110.12551 -334.541368)
			(xy 110.125023 -334.568737) (xy 110.11721 -334.622916) (xy 110.101725 -334.675418) (xy 110.078888 -334.725165)
			(xy 110.049169 -334.771133) (xy 110.03153 -334.792066) (xy 110.022322 -334.803415) (xy 110.010137 -334.829965)
			(xy 110.005957 -334.858876) (xy 110.010123 -334.887789) (xy 110.022296 -334.914344) (xy 110.03153 -334.92567)
			(xy 110.049173 -334.946599) (xy 110.078883 -334.992573) (xy 110.101718 -335.042321) (xy 110.117208 -335.094823)
			(xy 110.125036 -335.148999) (xy 110.12551 -335.176368) (xy 110.125024 -335.203619) (xy 110.117268 -335.257567)
			(xy 110.101913 -335.309862) (xy 110.079271 -335.359439) (xy 110.049805 -335.405289) (xy 110.014114 -335.44648)
			(xy 109.972923 -335.482171) (xy 109.927073 -335.511637) (xy 109.877496 -335.534279) (xy 109.825201 -335.549634)
			(xy 109.771253 -335.55739) (xy 109.716751 -335.55739) (xy 109.662803 -335.549634) (xy 109.610508 -335.534279)
			(xy 109.560931 -335.511637) (xy 109.515081 -335.482171) (xy 109.47389 -335.44648) (xy 109.438199 -335.405289)
			(xy 109.408733 -335.359439) (xy 109.386091 -335.309862) (xy 109.370736 -335.257567) (xy 109.36298 -335.203619)
			(xy 109.362494 -335.176368) (xy 102.777544 -335.176368) (xy 102.777544 -335.214976) (xy 102.777057 -335.239926)
			(xy 102.769255 -335.289213) (xy 102.75384 -335.336673) (xy 102.731191 -335.381138) (xy 102.701865 -335.421512)
			(xy 102.68458 -335.439512) (xy 102.545042 -335.579) (xy 105.450617 -335.579) (xy 105.454785 -335.523383)
			(xy 105.467195 -335.469009) (xy 105.48757 -335.417091) (xy 105.515455 -335.36879) (xy 105.550227 -335.325183)
			(xy 105.591109 -335.287246) (xy 105.637189 -335.255826) (xy 105.687437 -335.231624) (xy 105.740731 -335.21518)
			(xy 105.79588 -335.206863) (xy 105.823766 -335.20634) (xy 105.851098 -335.206803) (xy 105.905179 -335.214774)
			(xy 105.957513 -335.230563) (xy 106.006978 -335.253832) (xy 106.05251 -335.284081) (xy 106.093132 -335.320661)
			(xy 106.127971 -335.362785) (xy 106.142536 -335.385918) (xy 106.150443 -335.398154) (xy 106.17192 -335.417823)
			(xy 106.198077 -335.430625) (xy 106.226786 -335.435517) (xy 106.255707 -335.432101) (xy 106.269282 -335.426812)
			(xy 106.292497 -335.417336) (xy 106.340827 -335.40398) (xy 106.390515 -335.397246) (xy 106.415586 -335.39684)
			(xy 106.440655 -335.397279) (xy 106.490337 -335.404022) (xy 106.538672 -335.417349) (xy 106.56189 -335.426812)
			(xy 106.575495 -335.431977) (xy 106.604381 -335.435359) (xy 106.63305 -335.430467) (xy 106.65918 -335.417697)
			(xy 106.680654 -335.398084) (xy 106.688636 -335.385918) (xy 106.703205 -335.362787) (xy 106.738048 -335.320666)
			(xy 106.778671 -335.284087) (xy 106.824202 -335.253836) (xy 106.873664 -335.23056) (xy 106.925995 -335.21476)
			(xy 106.980074 -335.206774) (xy 107.034738 -335.206774) (xy 107.088817 -335.21476) (xy 107.141148 -335.23056)
			(xy 107.19061 -335.253836) (xy 107.236141 -335.284087) (xy 107.276764 -335.320666) (xy 107.311607 -335.362787)
			(xy 107.326176 -335.385918) (xy 107.33414 -335.398113) (xy 107.355601 -335.417782) (xy 107.381743 -335.430589)
			(xy 107.410438 -335.435492) (xy 107.43935 -335.432092) (xy 107.452922 -335.426812) (xy 107.476132 -335.417324)
			(xy 107.524465 -335.403972) (xy 107.574154 -335.397244) (xy 107.599226 -335.39684) (xy 107.626068 -335.39731)
			(xy 107.679196 -335.405017) (xy 107.730668 -335.420268) (xy 107.779419 -335.442746) (xy 107.824441 -335.471988)
			(xy 107.8648 -335.507387) (xy 107.899663 -335.548211) (xy 107.928307 -335.593614) (xy 107.950139 -335.642658)
			(xy 107.957874 -335.668366) (xy 107.962579 -335.682847) (xy 107.979091 -335.708406) (xy 108.002398 -335.727968)
			(xy 108.030432 -335.7398) (xy 108.060707 -335.742851) (xy 108.090538 -335.736851) (xy 108.104178 -335.730088)
			(xy 108.13232 -335.715447) (xy 108.192273 -335.694722) (xy 108.254833 -335.684227) (xy 108.28655 -335.683606)
			(xy 108.304569 -335.683824) (xy 108.340444 -335.68726) (xy 108.358178 -335.690464) (xy 108.37339 -335.692776)
			(xy 108.403939 -335.689254) (xy 108.432056 -335.676799) (xy 108.455192 -335.65654) (xy 108.471249 -335.630313)
			(xy 108.475526 -335.615534) (xy 108.482901 -335.588483) (xy 108.504534 -335.536757) (xy 108.533502 -335.488751)
			(xy 108.56918 -335.4455) (xy 108.610802 -335.407934) (xy 108.657472 -335.37686) (xy 108.708186 -335.352949)
			(xy 108.761852 -335.336714) (xy 108.817316 -335.328504) (xy 108.84535 -335.328006) (xy 108.872602 -335.328502)
			(xy 108.926553 -335.336252) (xy 108.978851 -335.351603) (xy 109.028432 -335.37424) (xy 109.074286 -335.403705)
			(xy 109.115479 -335.439395) (xy 109.151174 -335.480585) (xy 109.180642 -335.526437) (xy 109.203285 -335.576015)
			(xy 109.21864 -335.628312) (xy 109.226396 -335.682262) (xy 109.226858 -335.709514) (xy 109.226348 -335.737087)
			(xy 109.218406 -335.791659) (xy 109.202691 -335.844518) (xy 109.17953 -335.894565) (xy 109.149404 -335.940755)
			(xy 109.112943 -335.982128) (xy 109.092238 -336.000344) (xy 109.081324 -336.010227) (xy 109.065246 -336.03488)
			(xy 109.056861 -336.063093) (xy 109.056864 -336.092525) (xy 109.065254 -336.120737) (xy 109.081336 -336.145387)
			(xy 109.092238 -336.155284) (xy 109.11296 -336.173483) (xy 109.149429 -336.214854) (xy 109.179561 -336.261046)
			(xy 109.202726 -336.311095) (xy 109.218443 -336.363958) (xy 109.226384 -336.418534) (xy 109.226383 -336.473684)
			(xy 109.218439 -336.52826) (xy 109.20272 -336.581122) (xy 109.179552 -336.63117) (xy 109.149418 -336.677361)
			(xy 109.112947 -336.71873) (xy 109.092238 -336.736944) (xy 109.081324 -336.746827) (xy 109.065246 -336.77148)
			(xy 109.056861 -336.799693) (xy 109.056864 -336.829125) (xy 109.065254 -336.857337) (xy 109.081336 -336.881987)
			(xy 109.092238 -336.891884) (xy 109.112952 -336.910092) (xy 109.149421 -336.951462) (xy 109.179551 -336.997653)
			(xy 109.202716 -337.047702) (xy 109.218433 -337.100564) (xy 109.226372 -337.155139) (xy 109.226858 -337.182714)
			(xy 109.226458 -337.20997) (xy 109.218698 -337.263925) (xy 109.203337 -337.316227) (xy 109.18069 -337.365811)
			(xy 109.151216 -337.411667) (xy 109.115515 -337.45286) (xy 109.074315 -337.488554) (xy 109.028455 -337.51802)
			(xy 108.978867 -337.54066) (xy 108.926563 -337.556011) (xy 108.872606 -337.563763) (xy 108.84535 -337.564222)
			(xy 108.817494 -337.563728) (xy 108.762378 -337.555598) (xy 108.709028 -337.539546) (xy 108.658576 -337.515915)
			(xy 108.612092 -337.485204) (xy 108.570563 -337.448066) (xy 108.534871 -337.405289) (xy 108.505771 -337.35778)
			(xy 108.483883 -337.306548) (xy 108.476288 -337.279742) (xy 108.471972 -337.26564) (xy 108.456594 -337.240496)
			(xy 108.434686 -337.220778) (xy 108.408067 -337.208123) (xy 108.378944 -337.20358) (xy 108.364274 -337.205066)
			(xy 108.351258 -337.206736) (xy 108.325073 -337.208515) (xy 108.31195 -337.208622) (xy 108.297801 -337.208523)
			(xy 108.269578 -337.206492) (xy 108.255562 -337.204558) (xy 108.24221 -337.203031) (xy 108.215527 -337.206124)
			(xy 108.19058 -337.216084) (xy 108.169103 -337.232218) (xy 108.152589 -337.253404) (xy 108.142186 -337.278169)
			(xy 108.139992 -337.291426) (xy 108.135913 -337.318581) (xy 108.120941 -337.371413) (xy 108.09855 -337.421553)
			(xy 108.069202 -337.467965) (xy 108.033504 -337.509691) (xy 107.992193 -337.545867) (xy 107.946122 -337.575748)
			(xy 107.896244 -337.598716) (xy 107.843588 -337.614295) (xy 107.789242 -337.622166) (xy 107.761786 -337.622642)
			(xy 107.734536 -337.622135) (xy 107.680591 -337.614378) (xy 107.628298 -337.599023) (xy 107.578723 -337.576382)
			(xy 107.532875 -337.546918) (xy 107.491686 -337.511229) (xy 107.455994 -337.470041) (xy 107.426527 -337.424194)
			(xy 107.403884 -337.37462) (xy 107.388526 -337.322329) (xy 107.380766 -337.268384) (xy 107.380278 -337.241134)
			(xy 107.380775 -337.213561) (xy 107.388722 -337.15899) (xy 107.404441 -337.106131) (xy 107.427606 -337.056085)
			(xy 107.457732 -337.009894) (xy 107.494194 -336.968521) (xy 107.514898 -336.950304) (xy 107.525761 -336.940371)
			(xy 107.541834 -336.91573) (xy 107.550222 -336.887532) (xy 107.550228 -336.858112) (xy 107.541853 -336.82991)
			(xy 107.52579 -336.805262) (xy 107.514898 -336.795364) (xy 107.494166 -336.777176) (xy 107.457697 -336.735802)
			(xy 107.427568 -336.689607) (xy 107.404406 -336.639555) (xy 107.388694 -336.586688) (xy 107.38076 -336.53211)
			(xy 107.380278 -336.504534) (xy 107.380717 -336.478032) (xy 107.388067 -336.425541) (xy 107.402615 -336.374573)
			(xy 107.424081 -336.326111) (xy 107.452052 -336.281089) (xy 107.46867 -336.26044) (xy 107.478115 -336.248298)
			(xy 107.489899 -336.219896) (xy 107.49272 -336.189276) (xy 107.486322 -336.1592) (xy 107.471284 -336.132379)
			(xy 107.448961 -336.111232) (xy 107.435396 -336.103976) (xy 107.411695 -336.091896) (xy 107.367716 -336.061966)
			(xy 107.328437 -336.026089) (xy 107.294658 -335.984993) (xy 107.280456 -335.962498) (xy 107.272553 -335.950259)
			(xy 107.251076 -335.930588) (xy 107.224917 -335.917786) (xy 107.196207 -335.912894) (xy 107.167285 -335.916313)
			(xy 107.15371 -335.921604) (xy 107.130496 -335.931083) (xy 107.082165 -335.944438) (xy 107.032477 -335.95117)
			(xy 107.007406 -335.951576) (xy 106.982337 -335.951138) (xy 106.932655 -335.944394) (xy 106.88432 -335.931067)
			(xy 106.861102 -335.921604) (xy 106.847502 -335.916424) (xy 106.818613 -335.913043) (xy 106.789942 -335.917938)
			(xy 106.763811 -335.930712) (xy 106.742337 -335.95033) (xy 106.734356 -335.962498) (xy 106.719787 -335.985629)
			(xy 106.684944 -336.02775) (xy 106.644321 -336.064329) (xy 106.59879 -336.09458) (xy 106.549328 -336.117856)
			(xy 106.496997 -336.133656) (xy 106.442918 -336.141642) (xy 106.388254 -336.141642) (xy 106.334175 -336.133656)
			(xy 106.281844 -336.117856) (xy 106.232382 -336.09458) (xy 106.186851 -336.064329) (xy 106.146228 -336.02775)
			(xy 106.111385 -335.985629) (xy 106.096816 -335.962498) (xy 106.088856 -335.9503) (xy 106.067395 -335.930629)
			(xy 106.041251 -335.917821) (xy 106.012555 -335.912919) (xy 105.983642 -335.916322) (xy 105.97007 -335.921604)
			(xy 105.946861 -335.931095) (xy 105.898528 -335.944446) (xy 105.848838 -335.951173) (xy 105.823766 -335.951576)
			(xy 105.79588 -335.951137) (xy 105.740731 -335.94282) (xy 105.687437 -335.926376) (xy 105.637189 -335.902174)
			(xy 105.591109 -335.870754) (xy 105.550227 -335.832817) (xy 105.515455 -335.78921) (xy 105.48757 -335.740909)
			(xy 105.467195 -335.688991) (xy 105.454785 -335.634617) (xy 105.450617 -335.579) (xy 102.545042 -335.579)
			(xy 101.971348 -336.15249) (xy 101.971348 -336.267552) (xy 101.971825 -336.281843) (xy 101.979736 -336.309308)
			(xy 101.994952 -336.333503) (xy 102.016279 -336.35253) (xy 102.042046 -336.364899) (xy 102.070232 -336.369639)
			(xy 102.098627 -336.366379) (xy 102.125005 -336.355374) (xy 102.136448 -336.3468) (xy 102.136956 -336.346292)
			(xy 102.138988 -336.344768) (xy 102.139496 -336.344514) (xy 102.163436 -336.326441) (xy 102.215842 -336.297262)
			(xy 102.272171 -336.27665) (xy 102.331033 -336.265115) (xy 102.360984 -336.263488) (xy 102.372668 -336.263234)
			(xy 102.380034 -336.263234) (xy 102.407048 -336.264061) (xy 102.460445 -336.272393) (xy 102.512133 -336.288178)
			(xy 102.561076 -336.311099) (xy 102.606293 -336.340699) (xy 102.646881 -336.376383) (xy 102.682027 -336.417439)
			(xy 102.711027 -336.463043) (xy 102.733301 -336.512284) (xy 102.748402 -336.564175) (xy 102.756029 -336.617678)
			(xy 102.756029 -336.671723) (xy 102.748402 -336.725226) (xy 102.7333 -336.777117) (xy 102.711027 -336.826358)
			(xy 102.682027 -336.871962) (xy 102.646881 -336.913018) (xy 102.606293 -336.948702) (xy 102.561075 -336.978301)
			(xy 102.512132 -337.001222) (xy 102.460444 -337.017007) (xy 102.407046 -337.02534) (xy 102.380034 -337.02625)
			(xy 102.374446 -337.02625) (xy 102.349114 -337.0258) (xy 102.298903 -337.019027) (xy 102.250029 -337.005674)
			(xy 102.203351 -336.985974) (xy 102.159687 -336.960275) (xy 102.139496 -336.94497) (xy 102.138988 -336.944716)
			(xy 102.136956 -336.943192) (xy 102.136448 -336.942684) (xy 102.124994 -336.934125) (xy 102.098611 -336.923132)
			(xy 102.070216 -336.919879) (xy 102.042031 -336.92462) (xy 102.016262 -336.936983) (xy 101.994926 -336.956)
			(xy 101.979694 -336.980184) (xy 101.971758 -337.007642) (xy 101.971348 -337.021932) (xy 101.971348 -337.078574)
			(xy 101.974904 -337.087464) (xy 101.982863 -337.109269) (xy 101.994046 -337.154322) (xy 101.999691 -337.200398)
			(xy 102.00005 -337.223608) (xy 102.00005 -337.23326) (xy 101.998935 -337.260071) (xy 101.990114 -337.313002)
			(xy 101.973961 -337.364174) (xy 101.950797 -337.412577) (xy 101.921078 -337.457256) (xy 101.88539 -337.497329)
			(xy 101.844439 -337.532006) (xy 101.799032 -337.560601) (xy 101.750066 -337.582551) (xy 101.698507 -337.597421)
			(xy 101.645373 -337.604919) (xy 101.618542 -337.60537) (xy 101.591288 -337.604909) (xy 101.537335 -337.597157)
			(xy 101.485034 -337.581804) (xy 101.435451 -337.559164) (xy 101.389595 -337.529696) (xy 101.348401 -337.494002)
			(xy 101.312706 -337.452808) (xy 101.283238 -337.406953) (xy 101.260597 -337.35737) (xy 101.245244 -337.305069)
			(xy 101.237491 -337.251116) (xy 101.237034 -337.223862) (xy 101.237556 -337.195777) (xy 101.245829 -337.140219)
			(xy 101.262148 -337.086471) (xy 101.286161 -337.035692) (xy 101.31735 -336.988975) (xy 101.33584 -336.96783)
			(xy 101.33584 -336.020664) (xy 101.336324 -335.995712) (xy 101.34412 -335.946422) (xy 101.35953 -335.898957)
			(xy 101.382175 -335.854488) (xy 101.411497 -335.814107) (xy 101.428804 -335.796128) (xy 101.514656 -335.710276)
			(xy 101.524838 -335.699292) (xy 101.538895 -335.672861) (xy 101.544691 -335.64349) (xy 101.541729 -335.613701)
			(xy 101.530263 -335.586047) (xy 101.511276 -335.562902) (xy 101.486397 -335.546251) (xy 101.472238 -335.541366)
			(xy 101.446511 -335.533035) (xy 101.397527 -335.510127) (xy 101.352269 -335.48053) (xy 101.311645 -335.444838)
			(xy 101.27647 -335.403766) (xy 101.247448 -335.358137) (xy 101.225161 -335.308867) (xy 101.210057 -335.256943)
			(xy 101.202438 -335.203406) (xy 101.201982 -335.176368) (xy 101.20247 -335.1488) (xy 101.210409 -335.094238)
			(xy 101.226118 -335.041387) (xy 101.249269 -334.991347) (xy 101.27938 -334.945159) (xy 101.297232 -334.924146)
			(xy 101.305988 -334.912956) (xy 101.31752 -334.887002) (xy 101.321461 -334.858875) (xy 101.317507 -334.830751)
			(xy 101.305962 -334.804802) (xy 101.297232 -334.79359) (xy 101.279369 -334.772585) (xy 101.249249 -334.726399)
			(xy 101.226094 -334.676357) (xy 101.210385 -334.623503) (xy 101.20245 -334.568938) (xy 101.201982 -334.541368)
			(xy 101.202468 -334.514117) (xy 101.210224 -334.460169) (xy 101.225579 -334.407874) (xy 101.248221 -334.358297)
			(xy 101.277687 -334.312447) (xy 101.313378 -334.271256) (xy 101.354569 -334.235565) (xy 101.400419 -334.206099)
			(xy 101.449996 -334.183457) (xy 101.502291 -334.168102) (xy 101.556239 -334.160346) (xy 101.610741 -334.160346)
			(xy 101.664689 -334.168102) (xy 101.716984 -334.183457) (xy 101.766561 -334.206099) (xy 101.812411 -334.235565)
			(xy 101.853602 -334.271256) (xy 101.889293 -334.312447) (xy 101.918759 -334.358297) (xy 101.941401 -334.407874)
			(xy 101.956756 -334.460169) (xy 101.964512 -334.514117) (xy 101.964998 -334.541368) (xy 101.964508 -334.568935)
			(xy 101.956564 -334.623494) (xy 101.94085 -334.676341) (xy 101.917695 -334.726378) (xy 101.88758 -334.772561)
			(xy 101.869748 -334.79359) (xy 101.86101 -334.804753) (xy 101.849486 -334.83064) (xy 101.845505 -334.858695)
			(xy 101.849373 -334.886767) (xy 101.860795 -334.9127) (xy 101.869494 -334.923892) (xy 101.871018 -334.925416)
			(xy 101.87305 -334.92821) (xy 101.87432 -334.929734) (xy 101.89077 -334.949717) (xy 101.918693 -334.993298)
			(xy 101.940471 -335.040252) (xy 101.948488 -335.064862) (xy 101.948742 -335.066132) (xy 101.953725 -335.080188)
			(xy 101.970521 -335.104814) (xy 101.993705 -335.12355) (xy 102.021308 -335.134804) (xy 102.050983 -335.13762)
			(xy 102.080209 -335.131757) (xy 102.106503 -335.117715) (xy 102.117398 -335.107534) (xy 102.120192 -335.10474)
			(xy 102.142036 -335.08315) (xy 102.142036 -326.32523) (xy 95.400622 -326.32523) (xy 94.669102 -327.05675)
			(xy 94.681294 -327.087738) (xy 94.684673 -327.096471) (xy 94.690521 -327.114262) (xy 94.692978 -327.123298)
			(xy 94.697815 -327.142947) (xy 94.703037 -327.183075) (xy 94.703392 -327.203308) (xy 94.703392 -335.276444)
			(xy 94.702932 -335.301397) (xy 94.695133 -335.35069) (xy 94.679719 -335.398155) (xy 94.657068 -335.442624)
			(xy 94.627739 -335.483002) (xy 94.610428 -335.50098) (xy 94.532388 -335.579) (xy 97.290117 -335.579)
			(xy 97.294285 -335.523384) (xy 97.306694 -335.469011) (xy 97.327068 -335.417094) (xy 97.354952 -335.368793)
			(xy 97.389723 -335.325188) (xy 97.430604 -335.287251) (xy 97.476682 -335.25583) (xy 97.526928 -335.231627)
			(xy 97.580221 -335.215183) (xy 97.635368 -335.206864) (xy 97.663254 -335.20634) (xy 97.690586 -335.206812)
			(xy 97.744666 -335.214781) (xy 97.797 -335.230569) (xy 97.846465 -335.253837) (xy 97.891997 -335.284084)
			(xy 97.932619 -335.320663) (xy 97.967459 -335.362786) (xy 97.982024 -335.385918) (xy 97.989942 -335.398145)
			(xy 98.011416 -335.417814) (xy 98.03757 -335.430618) (xy 98.066276 -335.435512) (xy 98.095196 -335.4321)
			(xy 98.10877 -335.426812) (xy 98.131987 -335.41734) (xy 98.180316 -335.403982) (xy 98.230003 -335.397247)
			(xy 98.255074 -335.39684) (xy 98.280144 -335.397251) (xy 98.329827 -335.404006) (xy 98.378161 -335.417343)
			(xy 98.401378 -335.426812) (xy 98.414951 -335.43207) (xy 98.443854 -335.435432) (xy 98.472533 -335.430519)
			(xy 98.498669 -335.417728) (xy 98.520144 -335.398094) (xy 98.528124 -335.385918) (xy 98.542693 -335.362787)
			(xy 98.577536 -335.320666) (xy 98.618159 -335.284087) (xy 98.66369 -335.253836) (xy 98.713152 -335.23056)
			(xy 98.765483 -335.21476) (xy 98.819562 -335.206774) (xy 98.874226 -335.206774) (xy 98.928305 -335.21476)
			(xy 98.980636 -335.23056) (xy 99.030098 -335.253836) (xy 99.075629 -335.284087) (xy 99.116252 -335.320666)
			(xy 99.151095 -335.362787) (xy 99.165664 -335.385918) (xy 99.173544 -335.398173) (xy 99.195028 -335.417842)
			(xy 99.221193 -335.430641) (xy 99.249908 -335.435529) (xy 99.278834 -335.432106) (xy 99.29241 -335.426812)
			(xy 99.315622 -335.417328) (xy 99.363954 -335.403974) (xy 99.413643 -335.397244) (xy 99.438714 -335.39684)
			(xy 99.465556 -335.397321) (xy 99.518683 -335.405026) (xy 99.570155 -335.420275) (xy 99.618906 -335.442752)
			(xy 99.663928 -335.471992) (xy 99.704287 -335.50739) (xy 99.73915 -335.548213) (xy 99.767794 -335.593616)
			(xy 99.789627 -335.642659) (xy 99.797362 -335.668366) (xy 99.802083 -335.682841) (xy 99.818592 -335.708398)
			(xy 99.841895 -335.72796) (xy 99.869926 -335.739792) (xy 99.900198 -335.742845) (xy 99.930026 -335.736849)
			(xy 99.943666 -335.730088) (xy 99.97181 -335.715451) (xy 100.031762 -335.694725) (xy 100.094321 -335.684228)
			(xy 100.126038 -335.683606) (xy 100.144057 -335.683825) (xy 100.179932 -335.687261) (xy 100.197666 -335.690464)
			(xy 100.212879 -335.692764) (xy 100.243427 -335.689245) (xy 100.271544 -335.676793) (xy 100.294679 -335.656537)
			(xy 100.310737 -335.630312) (xy 100.315014 -335.615534) (xy 100.3224 -335.588487) (xy 100.344032 -335.536761)
			(xy 100.372998 -335.488756) (xy 100.408676 -335.445505) (xy 100.450296 -335.407938) (xy 100.496965 -335.376865)
			(xy 100.547677 -335.352952) (xy 100.601342 -335.336716) (xy 100.656805 -335.328505) (xy 100.684838 -335.328006)
			(xy 100.712091 -335.328443) (xy 100.766041 -335.336205) (xy 100.818338 -335.351565) (xy 100.867916 -335.374212)
			(xy 100.913767 -335.403683) (xy 100.954957 -335.43938) (xy 100.990648 -335.480575) (xy 101.020113 -335.52643)
			(xy 101.042753 -335.576011) (xy 101.058107 -335.62831) (xy 101.065861 -335.682261) (xy 101.066346 -335.709514)
			(xy 101.06584 -335.737087) (xy 101.057898 -335.791659) (xy 101.042183 -335.844519) (xy 101.01902 -335.894566)
			(xy 100.988894 -335.940756) (xy 100.952431 -335.982128) (xy 100.931726 -336.000344) (xy 100.920813 -336.010227)
			(xy 100.904737 -336.034881) (xy 100.896353 -336.063093) (xy 100.896356 -336.092525) (xy 100.904745 -336.120736)
			(xy 100.920825 -336.145386) (xy 100.931726 -336.155284) (xy 100.952444 -336.173485) (xy 100.988906 -336.214859)
			(xy 101.01903 -336.261052) (xy 101.04219 -336.311101) (xy 101.057903 -336.363962) (xy 101.065842 -336.418535)
			(xy 101.06584 -336.473683) (xy 101.057899 -336.528256) (xy 101.042184 -336.581116) (xy 101.019021 -336.631164)
			(xy 100.988895 -336.677355) (xy 100.952431 -336.718728) (xy 100.931726 -336.736944) (xy 100.920813 -336.746827)
			(xy 100.904737 -336.771481) (xy 100.896353 -336.799693) (xy 100.896356 -336.829125) (xy 100.904745 -336.857336)
			(xy 100.920825 -336.881986) (xy 100.931726 -336.891884) (xy 100.952438 -336.910094) (xy 100.988907 -336.951464)
			(xy 101.019038 -336.997654) (xy 101.042204 -337.047702) (xy 101.05792 -337.100565) (xy 101.06586 -337.155139)
			(xy 101.066346 -337.182714) (xy 101.065835 -337.209964) (xy 101.058078 -337.263909) (xy 101.042723 -337.316201)
			(xy 101.020083 -337.365775) (xy 100.990619 -337.411624) (xy 100.95493 -337.452813) (xy 100.913743 -337.488504)
			(xy 100.867897 -337.517971) (xy 100.818323 -337.540615) (xy 100.766032 -337.555973) (xy 100.712088 -337.563734)
			(xy 100.684838 -337.564222) (xy 100.656985 -337.563648) (xy 100.601872 -337.555531) (xy 100.548524 -337.539491)
			(xy 100.498072 -337.515871) (xy 100.451588 -337.48517) (xy 100.410058 -337.448041) (xy 100.374364 -337.405272)
			(xy 100.345263 -337.357771) (xy 100.323372 -337.306545) (xy 100.315776 -337.279742) (xy 100.311472 -337.265636)
			(xy 100.296091 -337.24049) (xy 100.274181 -337.220772) (xy 100.247558 -337.208119) (xy 100.218433 -337.203579)
			(xy 100.203762 -337.205066) (xy 100.190746 -337.206737) (xy 100.164561 -337.208516) (xy 100.151438 -337.208622)
			(xy 100.137289 -337.208524) (xy 100.109066 -337.206493) (xy 100.09505 -337.204558) (xy 100.081699 -337.203018)
			(xy 100.055015 -337.206115) (xy 100.030067 -337.216077) (xy 100.00859 -337.232213) (xy 99.992076 -337.253401)
			(xy 99.981673 -337.278168) (xy 99.97948 -337.291426) (xy 99.975413 -337.318584) (xy 99.96044 -337.371416)
			(xy 99.938048 -337.421557) (xy 99.908699 -337.46797) (xy 99.873 -337.509695) (xy 99.831687 -337.545872)
			(xy 99.785615 -337.575752) (xy 99.735735 -337.598719) (xy 99.683078 -337.614298) (xy 99.628731 -337.622166)
			(xy 99.601274 -337.622642) (xy 99.574024 -337.622146) (xy 99.520078 -337.614387) (xy 99.467786 -337.599031)
			(xy 99.418211 -337.576389) (xy 99.372362 -337.546923) (xy 99.331173 -337.511233) (xy 99.295482 -337.470045)
			(xy 99.266015 -337.424197) (xy 99.243372 -337.374622) (xy 99.228014 -337.32233) (xy 99.220254 -337.268384)
			(xy 99.219766 -337.241134) (xy 99.220232 -337.213559) (xy 99.228181 -337.158985) (xy 99.243905 -337.106124)
			(xy 99.267075 -337.056078) (xy 99.297208 -337.009889) (xy 99.333678 -336.968519) (xy 99.354386 -336.950304)
			(xy 99.36525 -336.940371) (xy 99.381326 -336.915731) (xy 99.389714 -336.887532) (xy 99.389721 -336.858112)
			(xy 99.381344 -336.829909) (xy 99.365279 -336.805262) (xy 99.354386 -336.795364) (xy 99.333651 -336.777178)
			(xy 99.297184 -336.735804) (xy 99.267055 -336.689609) (xy 99.243893 -336.639556) (xy 99.228182 -336.586689)
			(xy 99.220248 -336.53211) (xy 99.219766 -336.504534) (xy 99.220208 -336.478033) (xy 99.227557 -336.425541)
			(xy 99.242105 -336.374574) (xy 99.26357 -336.326112) (xy 99.29154 -336.281089) (xy 99.308158 -336.26044)
			(xy 99.317607 -336.2483) (xy 99.329393 -336.219898) (xy 99.332214 -336.189277) (xy 99.325816 -336.159199)
			(xy 99.310776 -336.132377) (xy 99.28845 -336.111231) (xy 99.274884 -336.103976) (xy 99.251197 -336.091869)
			(xy 99.207215 -336.061949) (xy 99.167932 -336.026079) (xy 99.134148 -335.98499) (xy 99.119944 -335.962498)
			(xy 99.112052 -335.950251) (xy 99.090572 -335.93058) (xy 99.06441 -335.917779) (xy 99.035698 -335.912889)
			(xy 99.006773 -335.916311) (xy 98.993198 -335.921604) (xy 98.969986 -335.931087) (xy 98.921654 -335.94444)
			(xy 98.871965 -335.951171) (xy 98.846894 -335.951576) (xy 98.821825 -335.951142) (xy 98.772142 -335.944396)
			(xy 98.723808 -335.931068) (xy 98.70059 -335.921604) (xy 98.686994 -335.916411) (xy 98.658103 -335.913032)
			(xy 98.62943 -335.91793) (xy 98.603298 -335.930707) (xy 98.581825 -335.950328) (xy 98.573844 -335.962498)
			(xy 98.559275 -335.985629) (xy 98.524432 -336.02775) (xy 98.483809 -336.064329) (xy 98.438278 -336.09458)
			(xy 98.388816 -336.117856) (xy 98.336485 -336.133656) (xy 98.282406 -336.141642) (xy 98.227742 -336.141642)
			(xy 98.173663 -336.133656) (xy 98.121332 -336.117856) (xy 98.07187 -336.09458) (xy 98.026339 -336.064329)
			(xy 97.985716 -336.02775) (xy 97.950873 -335.985629) (xy 97.936304 -335.962498) (xy 97.928355 -335.950292)
			(xy 97.906891 -335.930621) (xy 97.880744 -335.917814) (xy 97.852045 -335.912914) (xy 97.823131 -335.91632)
			(xy 97.809558 -335.921604) (xy 97.78635 -335.931099) (xy 97.738016 -335.944448) (xy 97.688326 -335.951174)
			(xy 97.663254 -335.951576) (xy 97.635368 -335.951136) (xy 97.580221 -335.942817) (xy 97.526928 -335.926373)
			(xy 97.476682 -335.90217) (xy 97.430604 -335.870749) (xy 97.389723 -335.832812) (xy 97.354952 -335.789207)
			(xy 97.327068 -335.740906) (xy 97.306694 -335.688989) (xy 97.294285 -335.634616) (xy 97.290117 -335.579)
			(xy 94.532388 -335.579) (xy 93.631512 -336.479642) (xy 93.631512 -336.644742) (xy 93.832424 -336.644742)
			(xy 93.836495 -336.58912) (xy 93.848621 -336.534683) (xy 93.868544 -336.482592) (xy 93.89584 -336.433957)
			(xy 93.929926 -336.389814) (xy 93.970075 -336.351105) (xy 94.015433 -336.318654) (xy 94.065033 -336.293153)
			(xy 94.117817 -336.275146) (xy 94.17266 -336.265016) (xy 94.228394 -336.262979) (xy 94.283831 -336.269079)
			(xy 94.337788 -336.283185) (xy 94.389117 -336.304997) (xy 94.436723 -336.334051) (xy 94.479591 -336.369726)
			(xy 94.516808 -336.411263) (xy 94.547581 -336.457776) (xy 94.571253 -336.508273) (xy 94.587321 -336.56168)
			(xy 94.595441 -336.616856) (xy 94.59595 -336.644742) (xy 94.595441 -336.672628) (xy 94.587321 -336.727804)
			(xy 94.571253 -336.781211) (xy 94.547581 -336.831708) (xy 94.516808 -336.878221) (xy 94.479591 -336.919758)
			(xy 94.436723 -336.955433) (xy 94.389117 -336.984487) (xy 94.337788 -337.006299) (xy 94.283831 -337.020405)
			(xy 94.228394 -337.026505) (xy 94.17266 -337.024468) (xy 94.117817 -337.014338) (xy 94.065033 -336.996331)
			(xy 94.015433 -336.97083) (xy 93.970075 -336.938379) (xy 93.929926 -336.89967) (xy 93.89584 -336.855527)
			(xy 93.868544 -336.806892) (xy 93.848621 -336.754801) (xy 93.836495 -336.700364) (xy 93.832424 -336.644742)
			(xy 93.631512 -336.644742) (xy 93.631512 -336.96275) (xy 93.646752 -336.97799) (xy 93.669358 -336.984086)
			(xy 93.696087 -336.991736) (xy 93.747158 -337.013705) (xy 93.794504 -337.042847) (xy 93.837125 -337.078545)
			(xy 93.874119 -337.120046) (xy 93.904705 -337.166472) (xy 93.928237 -337.216843) (xy 93.944217 -337.270092)
			(xy 93.952308 -337.325096) (xy 93.952822 -337.352894) (xy 93.952337 -337.380146) (xy 93.944581 -337.434095)
			(xy 93.929226 -337.486391) (xy 93.906586 -337.53597) (xy 93.87712 -337.581822) (xy 93.841429 -337.623014)
			(xy 93.800238 -337.658708) (xy 93.754388 -337.688176) (xy 93.70481 -337.710819) (xy 93.652515 -337.726177)
			(xy 93.598566 -337.733935) (xy 93.571314 -337.734402) (xy 93.54306 -337.733892) (xy 93.48717 -337.725561)
			(xy 93.43312 -337.709079) (xy 93.382091 -337.684807) (xy 93.3352 -337.653275) (xy 93.293471 -337.615173)
			(xy 93.257817 -337.571334) (xy 93.229018 -337.522716) (xy 93.207703 -337.470383) (xy 93.200474 -337.443064)
			(xy 93.197172 -337.429094) (xy 93.088714 -337.320382) (xy 93.077873 -337.309371) (xy 93.058152 -337.28558)
			(xy 93.049344 -337.272884) (xy 93.045788 -337.26755) (xy 93.040883 -337.259779) (xy 93.031862 -337.243766)
			(xy 93.027754 -337.235546) (xy 93.022311 -337.224198) (xy 93.013027 -337.200803) (xy 93.009212 -337.18881)
			(xy 93.007434 -337.183222) (xy 93.00591 -337.177634) (xy 93.000879 -337.157435) (xy 92.995531 -337.116152)
			(xy 92.995242 -337.095338) (xy 92.995242 -337.092036) (xy 92.995242 -337.090766) (xy 92.996004 -337.07451)
			(xy 92.996004 -336.347816) (xy 92.996467 -336.322864) (xy 93.004271 -336.273575) (xy 93.01969 -336.226113)
			(xy 93.042344 -336.181648) (xy 93.071675 -336.141274) (xy 93.088968 -336.12328) (xy 93.481144 -335.731104)
			(xy 93.491113 -335.720481) (xy 93.505073 -335.694924) (xy 93.511261 -335.666467) (xy 93.509172 -335.637421)
			(xy 93.498978 -335.610142) (xy 93.481505 -335.586845) (xy 93.458172 -335.569421) (xy 93.430872 -335.559283)
			(xy 93.416374 -335.557876) (xy 93.38943 -335.556949) (xy 93.336194 -335.548446) (xy 93.284686 -335.532532)
			(xy 93.235931 -335.509524) (xy 93.190902 -335.479879) (xy 93.150496 -335.44419) (xy 93.115517 -335.403167)
			(xy 93.086664 -335.357627) (xy 93.06451 -335.308479) (xy 93.049497 -335.2567) (xy 93.041924 -335.203324)
			(xy 93.04147 -335.176368) (xy 93.041889 -335.150694) (xy 93.048775 -335.099809) (xy 93.062418 -335.050307)
			(xy 93.082573 -335.003079) (xy 93.108875 -334.958979) (xy 93.124528 -334.938624) (xy 93.133046 -334.927239)
			(xy 93.144007 -334.901018) (xy 93.147302 -334.872788) (xy 93.142675 -334.844747) (xy 93.130486 -334.819073)
			(xy 93.12148 -334.808068) (xy 93.101223 -334.786551) (xy 93.066926 -334.738427) (xy 93.040461 -334.68559)
			(xy 93.022459 -334.629304) (xy 93.013351 -334.570915) (xy 93.012768 -334.541368) (xy 93.013254 -334.514117)
			(xy 93.02101 -334.460169) (xy 93.036365 -334.407874) (xy 93.059007 -334.358297) (xy 93.088473 -334.312447)
			(xy 93.124164 -334.271256) (xy 93.165355 -334.235565) (xy 93.211205 -334.206099) (xy 93.260782 -334.183457)
			(xy 93.313077 -334.168102) (xy 93.367025 -334.160346) (xy 93.421527 -334.160346) (xy 93.475475 -334.168102)
			(xy 93.52777 -334.183457) (xy 93.577347 -334.206099) (xy 93.623197 -334.235565) (xy 93.664388 -334.271256)
			(xy 93.700079 -334.312447) (xy 93.729545 -334.358297) (xy 93.752187 -334.407874) (xy 93.767542 -334.460169)
			(xy 93.775298 -334.514117) (xy 93.775784 -334.541368) (xy 93.775369 -334.567043) (xy 93.76849 -334.617931)
			(xy 93.754852 -334.667438) (xy 93.734702 -334.714669) (xy 93.708402 -334.758774) (xy 93.692726 -334.779112)
			(xy 93.684202 -334.790498) (xy 93.673229 -334.816726) (xy 93.66992 -334.844963) (xy 93.674533 -334.873017)
			(xy 93.68671 -334.898708) (xy 93.695774 -334.909668) (xy 93.715584 -334.9307) (xy 93.749277 -334.977632)
			(xy 93.775518 -335.029104) (xy 93.793707 -335.08394) (xy 93.80343 -335.140891) (xy 93.804486 -335.169764)
			(xy 93.805977 -335.184246) (xy 93.816123 -335.211521) (xy 93.833543 -335.234833) (xy 93.856824 -335.252292)
			(xy 93.884082 -335.262486) (xy 93.913107 -335.264586) (xy 93.941549 -335.258424) (xy 93.967102 -335.244499)
			(xy 93.977714 -335.234534) (xy 93.987874 -335.224374) (xy 94.067884 -335.144618) (xy 94.067884 -331.84973)
			(xy 94.067376 -328.152252) (xy 94.067376 -327.903586) (xy 94.066857 -327.888608) (xy 94.058184 -327.859937)
			(xy 94.04156 -327.835019) (xy 94.018417 -327.816002) (xy 93.99075 -327.804523) (xy 93.960941 -327.801572)
			(xy 93.93156 -327.807402) (xy 93.905137 -327.821513) (xy 93.894148 -327.831704) (xy 92.128848 -329.597004)
			(xy 86.53399 -329.597004) (xy 85.795104 -330.33589) (xy 86.466426 -331.006958) (xy 86.483777 -331.024944)
			(xy 86.513173 -331.065358) (xy 86.535877 -331.109877) (xy 86.551329 -331.157402) (xy 86.559147 -331.206761)
			(xy 86.559644 -331.231748) (xy 86.559644 -338.238338) (xy 94.63913 -338.238338) (xy 94.639701 -338.20865)
			(xy 94.648894 -338.149991) (xy 94.667066 -338.093465) (xy 94.693776 -338.040437) (xy 94.72838 -337.992188)
			(xy 94.770042 -337.949884) (xy 94.793562 -337.93176) (xy 94.804147 -337.923306) (xy 94.820861 -337.902002)
			(xy 94.831386 -337.877054) (xy 94.834982 -337.850216) (xy 94.831395 -337.823376) (xy 94.820877 -337.798425)
			(xy 94.80417 -337.777116) (xy 94.793562 -337.768692) (xy 94.77004 -337.750571) (xy 94.728382 -337.708263)
			(xy 94.69378 -337.660013) (xy 94.667069 -337.606985) (xy 94.648895 -337.55046) (xy 94.639696 -337.491801)
			(xy 94.63913 -337.462114) (xy 94.639616 -337.434863) (xy 94.647372 -337.380915) (xy 94.662727 -337.32862)
			(xy 94.685369 -337.279043) (xy 94.714835 -337.233193) (xy 94.750526 -337.192002) (xy 94.791717 -337.156311)
			(xy 94.837567 -337.126845) (xy 94.887144 -337.104203) (xy 94.939439 -337.088848) (xy 94.993387 -337.081092)
			(xy 95.047889 -337.081092) (xy 95.101837 -337.088848) (xy 95.154132 -337.104203) (xy 95.203709 -337.126845)
			(xy 95.249559 -337.156311) (xy 95.29075 -337.192002) (xy 95.326441 -337.233193) (xy 95.355907 -337.279043)
			(xy 95.378549 -337.32862) (xy 95.393904 -337.380915) (xy 95.40166 -337.434863) (xy 95.402146 -337.462114)
			(xy 95.401623 -337.491804) (xy 95.39242 -337.550465) (xy 95.37424 -337.606993) (xy 95.347521 -337.66002)
			(xy 95.335442 -337.676857) (xy 95.655521 -337.676857) (xy 95.655521 -337.622343) (xy 95.66328 -337.568384)
			(xy 95.678639 -337.516078) (xy 95.701286 -337.466491) (xy 95.730761 -337.420632) (xy 95.766462 -337.379435)
			(xy 95.807662 -337.343738) (xy 95.853524 -337.314268) (xy 95.903114 -337.291626) (xy 95.955421 -337.276272)
			(xy 96.009381 -337.268518) (xy 96.036638 -337.268058) (xy 96.036892 -337.268058) (xy 96.062096 -337.268459)
			(xy 96.112064 -337.275098) (xy 96.160718 -337.288274) (xy 96.207208 -337.307756) (xy 96.22917 -337.320128)
			(xy 96.24216 -337.327118) (xy 96.270787 -337.334163) (xy 96.300234 -337.332729) (xy 96.328041 -337.322936)
			(xy 96.351888 -337.305602) (xy 96.369784 -337.282173) (xy 96.375474 -337.268566) (xy 96.386157 -337.241784)
			(xy 96.414448 -337.191543) (xy 96.44998 -337.146135) (xy 96.491944 -337.106593) (xy 96.539383 -337.07382)
			(xy 96.591215 -337.048563) (xy 96.64626 -337.031398) (xy 96.703261 -337.022716) (xy 96.73209 -337.022186)
			(xy 96.759342 -337.022665) (xy 96.813292 -337.03042) (xy 96.86559 -337.045775) (xy 96.915169 -337.068415)
			(xy 96.961022 -337.097882) (xy 97.002215 -337.133574) (xy 97.037909 -337.174765) (xy 97.067377 -337.220617)
			(xy 97.09002 -337.270195) (xy 97.105377 -337.322492) (xy 97.113134 -337.376442) (xy 97.113598 -337.403694)
			(xy 97.113598 -337.403948) (xy 97.113027 -337.433787) (xy 97.103709 -337.492733) (xy 97.095056 -337.521296)
			(xy 97.091124 -337.53523) (xy 97.090201 -337.564145) (xy 97.097449 -337.592153) (xy 97.112281 -337.616992)
			(xy 97.1335 -337.636657) (xy 97.159394 -337.64956) (xy 97.173542 -337.652614) (xy 97.201577 -337.658203)
			(xy 97.255683 -337.676654) (xy 97.306435 -337.702961) (xy 97.352701 -337.736537) (xy 97.393447 -337.776633)
			(xy 97.411032 -337.799172) (xy 97.679256 -337.799172) (xy 97.70174 -337.799715) (xy 97.74584 -337.808509)
			(xy 97.787379 -337.825731) (xy 97.824766 -337.850719) (xy 97.841054 -337.866228) (xy 98.213164 -338.238338)
			(xy 102.799642 -338.238338) (xy 102.800208 -338.20865) (xy 102.809402 -338.149991) (xy 102.827574 -338.093464)
			(xy 102.854285 -338.040436) (xy 102.88889 -337.992187) (xy 102.930553 -337.949883) (xy 102.954074 -337.93176)
			(xy 102.964658 -337.923305) (xy 102.98137 -337.902001) (xy 102.991894 -337.877053) (xy 102.995489 -337.850216)
			(xy 102.991902 -337.823377) (xy 102.981386 -337.798426) (xy 102.964681 -337.777116) (xy 102.954074 -337.768692)
			(xy 102.930554 -337.750568) (xy 102.888895 -337.708261) (xy 102.854293 -337.660011) (xy 102.827582 -337.606984)
			(xy 102.809407 -337.550459) (xy 102.800208 -337.491801) (xy 102.799642 -337.462114) (xy 102.800128 -337.434863)
			(xy 102.807884 -337.380915) (xy 102.823239 -337.32862) (xy 102.845881 -337.279043) (xy 102.875347 -337.233193)
			(xy 102.911038 -337.192002) (xy 102.952229 -337.156311) (xy 102.998079 -337.126845) (xy 103.047656 -337.104203)
			(xy 103.099951 -337.088848) (xy 103.153899 -337.081092) (xy 103.208401 -337.081092) (xy 103.262349 -337.088848)
			(xy 103.314644 -337.104203) (xy 103.364221 -337.126845) (xy 103.410071 -337.156311) (xy 103.451262 -337.192002)
			(xy 103.486953 -337.233193) (xy 103.516419 -337.279043) (xy 103.539061 -337.32862) (xy 103.554416 -337.380915)
			(xy 103.562172 -337.434863) (xy 103.562658 -337.462114) (xy 103.56213 -337.491803) (xy 103.552928 -337.550464)
			(xy 103.534748 -337.606992) (xy 103.50803 -337.660019) (xy 103.473419 -337.708267) (xy 103.43175 -337.75057)
			(xy 103.408226 -337.768692) (xy 103.39759 -337.777086) (xy 103.380877 -337.798404) (xy 103.370357 -337.823366)
			(xy 103.366769 -337.850216) (xy 103.370365 -337.877064) (xy 103.380893 -337.902023) (xy 103.397612 -337.923336)
			(xy 103.408226 -337.93176) (xy 103.43177 -337.949853) (xy 103.473428 -337.992167) (xy 103.508028 -338.040423)
			(xy 103.534735 -338.093456) (xy 103.552903 -338.149986) (xy 103.562096 -338.208649) (xy 103.562658 -338.238338)
			(xy 103.562172 -338.265589) (xy 103.554416 -338.319537) (xy 103.539061 -338.371832) (xy 103.516419 -338.421409)
			(xy 103.486953 -338.467259) (xy 103.451262 -338.50845) (xy 103.410071 -338.544141) (xy 103.364221 -338.573607)
			(xy 103.314644 -338.596249) (xy 103.262349 -338.611604) (xy 103.208401 -338.61936) (xy 103.153899 -338.61936)
			(xy 103.099951 -338.611604) (xy 103.047656 -338.596249) (xy 102.998079 -338.573607) (xy 102.952229 -338.544141)
			(xy 102.911038 -338.50845) (xy 102.875347 -338.467259) (xy 102.845881 -338.421409) (xy 102.823239 -338.371832)
			(xy 102.807884 -338.319537) (xy 102.800128 -338.265589) (xy 102.799642 -338.238338) (xy 98.213164 -338.238338)
			(xy 101.778816 -341.80399) (xy 101.794375 -341.820237) (xy 101.819377 -341.857627) (xy 101.836595 -341.899181)
			(xy 101.845364 -341.943298) (xy 101.845872 -341.965788) (xy 101.845872 -347.615256) (xy 101.845317 -347.637739)
			(xy 101.836524 -347.681837) (xy 101.819306 -347.723377) (xy 101.794323 -347.760765) (xy 101.778816 -347.777054)
			(xy 100.939092 -348.616778) (xy 100.939092 -352.916998) (xy 101.903784 -352.916998) (xy 101.903784 -349.08617)
			(xy 101.904339 -349.063687) (xy 101.913129 -349.019587) (xy 101.930347 -348.978047) (xy 101.955332 -348.94066)
			(xy 101.97084 -348.924372) (xy 102.868984 -348.026228) (xy 102.868984 -342.92159) (xy 102.869551 -342.899107)
			(xy 102.878338 -342.855009) (xy 102.895552 -342.813468) (xy 102.920533 -342.776081) (xy 102.93604 -342.759792)
			(xy 105.980484 -339.715348) (xy 105.980484 -338.652612) (xy 105.651554 -338.323936) (xy 105.640441 -338.313599)
			(xy 105.613632 -338.299403) (xy 105.583838 -338.293695) (xy 105.55368 -338.296976) (xy 105.525811 -338.308958)
			(xy 105.513886 -338.318348) (xy 105.493089 -338.33547) (xy 105.447594 -338.364316) (xy 105.39849 -338.386469)
			(xy 105.346757 -338.401486) (xy 105.293425 -338.40907) (xy 105.26649 -338.409534) (xy 105.23924 -338.409032)
			(xy 105.185294 -338.401274) (xy 105.133001 -338.385919) (xy 105.083426 -338.363279) (xy 105.037576 -338.333814)
			(xy 104.996387 -338.298124) (xy 104.960696 -338.256936) (xy 104.931229 -338.211089) (xy 104.908586 -338.161514)
			(xy 104.893229 -338.109222) (xy 104.88547 -338.055276) (xy 104.884982 -338.028026) (xy 104.885513 -337.998121)
			(xy 104.894828 -337.939042) (xy 104.903524 -337.910424) (xy 104.907562 -337.896517) (xy 104.908467 -337.867586)
			(xy 104.901199 -337.839567) (xy 104.886347 -337.814723) (xy 104.865107 -337.795057) (xy 104.839195 -337.782157)
			(xy 104.825038 -337.779106) (xy 104.7922 -337.772515) (xy 104.729347 -337.749398) (xy 104.70007 -337.733132)
			(xy 104.687106 -337.726092) (xy 104.65847 -337.719062) (xy 104.629018 -337.720509) (xy 104.601208 -337.730311)
			(xy 104.577358 -337.747652) (xy 104.559459 -337.771085) (xy 104.553766 -337.784694) (xy 104.543028 -337.811453)
			(xy 104.514746 -337.861693) (xy 104.479223 -337.907103) (xy 104.437267 -337.946647) (xy 104.389836 -337.979422)
			(xy 104.33801 -338.004683) (xy 104.282973 -338.021854) (xy 104.225977 -338.030542) (xy 104.19715 -338.031074)
			(xy 104.169899 -338.030653) (xy 104.115952 -338.02289) (xy 104.063658 -338.007529) (xy 104.014083 -337.984883)
			(xy 103.968235 -337.955413) (xy 103.927047 -337.919718) (xy 103.891357 -337.878525) (xy 103.861893 -337.832673)
			(xy 103.839254 -337.783095) (xy 103.8239 -337.7308) (xy 103.816144 -337.676851) (xy 103.816144 -337.622349)
			(xy 103.8239 -337.5684) (xy 103.839254 -337.516105) (xy 103.861893 -337.466527) (xy 103.891357 -337.420675)
			(xy 103.927047 -337.379482) (xy 103.968235 -337.343787) (xy 104.014083 -337.314317) (xy 104.063658 -337.291671)
			(xy 104.115952 -337.27631) (xy 104.169899 -337.268547) (xy 104.19715 -337.268058) (xy 104.222386 -337.268439)
			(xy 104.27242 -337.275063) (xy 104.32114 -337.288241) (xy 104.367692 -337.307741) (xy 104.389682 -337.320128)
			(xy 104.402665 -337.327132) (xy 104.431295 -337.334175) (xy 104.460744 -337.332738) (xy 104.488552 -337.322943)
			(xy 104.5124 -337.305606) (xy 104.530296 -337.282174) (xy 104.535986 -337.268566) (xy 104.546659 -337.24178)
			(xy 104.574951 -337.191539) (xy 104.610485 -337.14613) (xy 104.65245 -337.106588) (xy 104.699891 -337.073816)
			(xy 104.751724 -337.04856) (xy 104.80677 -337.031396) (xy 104.863772 -337.022715) (xy 104.892602 -337.022186)
			(xy 104.919853 -337.022676) (xy 104.9738 -337.030433) (xy 105.026095 -337.045788) (xy 105.075671 -337.068429)
			(xy 105.121522 -337.097894) (xy 105.162712 -337.133586) (xy 105.198403 -337.174775) (xy 105.22787 -337.220625)
			(xy 105.250511 -337.270202) (xy 105.265867 -337.322496) (xy 105.273624 -337.376443) (xy 105.27411 -337.403694)
			(xy 105.273584 -337.433599) (xy 105.264265 -337.492678) (xy 105.255568 -337.521296) (xy 105.251626 -337.535228)
			(xy 105.250703 -337.564145) (xy 105.257952 -337.592155) (xy 105.272786 -337.616995) (xy 105.294008 -337.63666)
			(xy 105.319904 -337.649562) (xy 105.334054 -337.652614) (xy 105.362079 -337.65825) (xy 105.416185 -337.676689)
			(xy 105.466939 -337.702984) (xy 105.513208 -337.73655) (xy 105.553957 -337.776637) (xy 105.571544 -337.799172)
			(xy 105.679494 -337.799172) (xy 105.701976 -337.799752) (xy 105.746074 -337.808535) (xy 105.787614 -337.825746)
			(xy 105.825002 -337.850723) (xy 105.841292 -337.866228) (xy 106.213402 -338.238338) (xy 110.960154 -338.238338)
			(xy 110.960715 -338.20865) (xy 110.969909 -338.14999) (xy 110.988082 -338.093463) (xy 111.014794 -338.040435)
			(xy 111.0494 -337.992187) (xy 111.091064 -337.949883) (xy 111.114586 -337.93176) (xy 111.125169 -337.923305)
			(xy 111.141879 -337.902) (xy 111.152402 -337.877052) (xy 111.155996 -337.850216) (xy 111.15241 -337.823378)
			(xy 111.141895 -337.798427) (xy 111.125192 -337.777117) (xy 111.114586 -337.768692) (xy 111.091069 -337.750565)
			(xy 111.049409 -337.708259) (xy 111.014806 -337.66001) (xy 110.988095 -337.606983) (xy 110.96992 -337.550459)
			(xy 110.96072 -337.491801) (xy 110.960154 -337.462114) (xy 110.96064 -337.434863) (xy 110.968396 -337.380915)
			(xy 110.983751 -337.32862) (xy 111.006393 -337.279043) (xy 111.035859 -337.233193) (xy 111.07155 -337.192002)
			(xy 111.112741 -337.156311) (xy 111.158591 -337.126845) (xy 111.208168 -337.104203) (xy 111.260463 -337.088848)
			(xy 111.314411 -337.081092) (xy 111.368913 -337.081092) (xy 111.422861 -337.088848) (xy 111.475156 -337.104203)
			(xy 111.524733 -337.126845) (xy 111.570583 -337.156311) (xy 111.611774 -337.192002) (xy 111.647465 -337.233193)
			(xy 111.676931 -337.279043) (xy 111.699573 -337.32862) (xy 111.714928 -337.380915) (xy 111.722684 -337.434863)
			(xy 111.72317 -337.462114) (xy 111.722637 -337.491803) (xy 111.713435 -337.550464) (xy 111.695256 -337.606991)
			(xy 111.668539 -337.660018) (xy 111.633929 -337.708266) (xy 111.592261 -337.750569) (xy 111.568738 -337.768692)
			(xy 111.558101 -337.777085) (xy 111.541386 -337.798403) (xy 111.530865 -337.823365) (xy 111.527276 -337.850216)
			(xy 111.530873 -337.877065) (xy 111.541402 -337.902024) (xy 111.558123 -337.923336) (xy 111.568738 -337.93176)
			(xy 111.592285 -337.94985) (xy 111.633942 -337.992165) (xy 111.668541 -338.040422) (xy 111.695247 -338.093455)
			(xy 111.713416 -338.149986) (xy 111.722608 -338.208649) (xy 111.72317 -338.238338) (xy 111.722684 -338.265589)
			(xy 111.714928 -338.319537) (xy 111.699573 -338.371832) (xy 111.676931 -338.421409) (xy 111.647465 -338.467259)
			(xy 111.611774 -338.50845) (xy 111.570583 -338.544141) (xy 111.524733 -338.573607) (xy 111.475156 -338.596249)
			(xy 111.422861 -338.611604) (xy 111.368913 -338.61936) (xy 111.314411 -338.61936) (xy 111.260463 -338.611604)
			(xy 111.208168 -338.596249) (xy 111.158591 -338.573607) (xy 111.112741 -338.544141) (xy 111.07155 -338.50845)
			(xy 111.035859 -338.467259) (xy 111.006393 -338.421409) (xy 110.983751 -338.371832) (xy 110.968396 -338.319537)
			(xy 110.96064 -338.265589) (xy 110.960154 -338.238338) (xy 106.213402 -338.238338) (xy 106.371136 -338.396072)
			(xy 106.38669 -338.412324) (xy 106.411692 -338.449713) (xy 106.428911 -338.491265) (xy 106.437682 -338.53538)
			(xy 106.438192 -338.55787) (xy 106.438192 -339.81009) (xy 106.437652 -339.832574) (xy 106.428854 -339.876673)
			(xy 106.411631 -339.918212) (xy 106.386644 -339.955599) (xy 106.371136 -339.971888) (xy 103.326692 -343.016332)
			(xy 103.326692 -344.071632) (xy 104.010456 -344.071632) (xy 104.010456 -343.986936) (xy 104.018507 -343.902622)
			(xy 104.034536 -343.819456) (xy 104.058397 -343.738189) (xy 104.089876 -343.659559) (xy 104.128687 -343.584278)
			(xy 104.174477 -343.513026) (xy 104.226833 -343.44645) (xy 104.285281 -343.385152) (xy 104.349291 -343.329687)
			(xy 104.418283 -343.280558) (xy 104.491633 -343.238209) (xy 104.568676 -343.203025) (xy 104.648715 -343.175323)
			(xy 104.731024 -343.155355) (xy 104.814859 -343.143302) (xy 104.89946 -343.139272) (xy 104.984061 -343.143302)
			(xy 105.067896 -343.155355) (xy 105.150205 -343.175323) (xy 105.230244 -343.203025) (xy 105.307287 -343.238209)
			(xy 105.380637 -343.280558) (xy 105.449629 -343.329687) (xy 105.513639 -343.385152) (xy 105.572087 -343.44645)
			(xy 105.624443 -343.513026) (xy 105.670233 -343.584278) (xy 105.709044 -343.659559) (xy 105.740523 -343.738189)
			(xy 105.764384 -343.819456) (xy 105.780413 -343.902622) (xy 105.788464 -343.986936) (xy 105.788968 -344.029284)
			(xy 106.534969 -344.029284) (xy 106.539005 -343.945837) (xy 106.551077 -343.863169) (xy 106.57107 -343.782052)
			(xy 106.598799 -343.703243) (xy 106.634005 -343.627478) (xy 106.676359 -343.555465) (xy 106.725465 -343.487876)
			(xy 106.780866 -343.425342) (xy 106.842043 -343.368447) (xy 106.908426 -343.317721) (xy 106.979394 -343.27364)
			(xy 107.054286 -343.236614) (xy 107.132402 -343.206988) (xy 107.213012 -343.18504) (xy 107.295364 -343.170975)
			(xy 107.37869 -343.164923) (xy 107.46221 -343.166942) (xy 107.545146 -343.177012) (xy 107.626722 -343.19504)
			(xy 107.706178 -343.220857) (xy 107.782771 -343.254222) (xy 107.855787 -343.294823) (xy 107.924543 -343.342282)
			(xy 107.988397 -343.396155) (xy 108.046754 -343.45594) (xy 108.099069 -343.521077) (xy 108.144852 -343.59096)
			(xy 108.183677 -343.664935) (xy 108.215182 -343.742312) (xy 108.239071 -343.822369) (xy 108.255122 -343.904357)
			(xy 108.263185 -343.987512) (xy 108.26369 -344.029284) (xy 108.263185 -344.071056) (xy 108.255122 -344.154211)
			(xy 108.239071 -344.236199) (xy 108.215182 -344.316256) (xy 108.183677 -344.393633) (xy 108.144852 -344.467608)
			(xy 108.099069 -344.537491) (xy 108.046754 -344.602628) (xy 107.988397 -344.662413) (xy 107.924543 -344.716286)
			(xy 107.855787 -344.763745) (xy 107.782771 -344.804346) (xy 107.706178 -344.837711) (xy 107.626722 -344.863528)
			(xy 107.545146 -344.881556) (xy 107.46221 -344.891626) (xy 107.37869 -344.893645) (xy 107.295364 -344.887593)
			(xy 107.213012 -344.873528) (xy 107.132402 -344.85158) (xy 107.054286 -344.821954) (xy 106.979394 -344.784928)
			(xy 106.908426 -344.740847) (xy 106.842043 -344.690121) (xy 106.780866 -344.633226) (xy 106.725465 -344.570692)
			(xy 106.676359 -344.503103) (xy 106.634005 -344.43109) (xy 106.598799 -344.355325) (xy 106.57107 -344.276516)
			(xy 106.551077 -344.195399) (xy 106.539005 -344.112731) (xy 106.534969 -344.029284) (xy 105.788968 -344.029284)
			(xy 105.788464 -344.071632) (xy 105.780413 -344.155946) (xy 105.764384 -344.239112) (xy 105.740523 -344.320379)
			(xy 105.709044 -344.399009) (xy 105.670233 -344.47429) (xy 105.624443 -344.545542) (xy 105.572087 -344.612118)
			(xy 105.513639 -344.673416) (xy 105.449629 -344.728881) (xy 105.380637 -344.77801) (xy 105.307287 -344.820359)
			(xy 105.230244 -344.855543) (xy 105.150205 -344.883245) (xy 105.067896 -344.903213) (xy 104.984061 -344.915266)
			(xy 104.89946 -344.919297) (xy 104.814859 -344.915266) (xy 104.731024 -344.903213) (xy 104.648715 -344.883245)
			(xy 104.568676 -344.855543) (xy 104.491633 -344.820359) (xy 104.418283 -344.77801) (xy 104.349291 -344.728881)
			(xy 104.285281 -344.673416) (xy 104.226833 -344.612118) (xy 104.174477 -344.545542) (xy 104.128687 -344.47429)
			(xy 104.089876 -344.399009) (xy 104.058397 -344.320379) (xy 104.034536 -344.239112) (xy 104.018507 -344.155946)
			(xy 104.010456 -344.071632) (xy 103.326692 -344.071632) (xy 103.326692 -348.12097) (xy 103.32614 -348.143453)
			(xy 103.317345 -348.187551) (xy 103.300126 -348.229091) (xy 103.275143 -348.266479) (xy 103.259636 -348.282768)
			(xy 102.361492 -349.180912) (xy 102.361492 -352.160586) (xy 103.161084 -352.160586) (xy 103.161084 -350.23171)
			(xy 103.161602 -350.209225) (xy 103.170404 -350.165124) (xy 103.187633 -350.123584) (xy 103.212628 -350.086199)
			(xy 103.22814 -350.069912) (xy 113.888012 -339.409786) (xy 113.888012 -338.812886) (xy 113.481612 -338.406232)
			(xy 113.45799 -338.408264) (xy 113.427002 -338.409534) (xy 113.399752 -338.40902) (xy 113.345807 -338.401265)
			(xy 113.293514 -338.385911) (xy 113.243938 -338.363272) (xy 113.198089 -338.333809) (xy 113.1569 -338.29812)
			(xy 113.121208 -338.256933) (xy 113.091741 -338.211086) (xy 113.069098 -338.161512) (xy 113.053741 -338.109221)
			(xy 113.045982 -338.055276) (xy 113.045494 -338.028026) (xy 113.045494 -338.027772) (xy 113.04607 -337.997933)
			(xy 113.055385 -337.938987) (xy 113.064036 -337.910424) (xy 113.068065 -337.896515) (xy 113.068969 -337.867586)
			(xy 113.061702 -337.839569) (xy 113.046852 -337.814725) (xy 113.025615 -337.79506) (xy 112.999706 -337.782158)
			(xy 112.98555 -337.779106) (xy 112.952713 -337.772512) (xy 112.889859 -337.749397) (xy 112.860582 -337.733132)
			(xy 112.847611 -337.726106) (xy 112.818977 -337.719074) (xy 112.789528 -337.720518) (xy 112.761719 -337.730318)
			(xy 112.73787 -337.747656) (xy 112.719971 -337.771086) (xy 112.714278 -337.784694) (xy 112.70353 -337.811448)
			(xy 112.67525 -337.861689) (xy 112.639727 -337.907098) (xy 112.597773 -337.946642) (xy 112.550343 -337.979418)
			(xy 112.498519 -338.00468) (xy 112.443483 -338.021851) (xy 112.386488 -338.030541) (xy 112.357662 -338.031074)
			(xy 112.33041 -338.030654) (xy 112.276462 -338.022892) (xy 112.224167 -338.007532) (xy 112.17459 -337.984887)
			(xy 112.12874 -337.955417) (xy 112.087551 -337.919722) (xy 112.05186 -337.878529) (xy 112.022395 -337.832677)
			(xy 111.999755 -337.783098) (xy 111.9844 -337.730801) (xy 111.976644 -337.676852) (xy 111.976644 -337.622348)
			(xy 111.9844 -337.568399) (xy 111.999755 -337.516102) (xy 112.022395 -337.466523) (xy 112.05186 -337.420671)
			(xy 112.087551 -337.379478) (xy 112.12874 -337.343783) (xy 112.17459 -337.314313) (xy 112.224167 -337.291668)
			(xy 112.276462 -337.276308) (xy 112.33041 -337.268546) (xy 112.357662 -337.268058) (xy 112.357916 -337.268058)
			(xy 112.38312 -337.268448) (xy 112.433088 -337.27509) (xy 112.481743 -337.288269) (xy 112.528232 -337.307755)
			(xy 112.550194 -337.320128) (xy 112.56317 -337.327146) (xy 112.591803 -337.334187) (xy 112.621253 -337.332748)
			(xy 112.649064 -337.322949) (xy 112.672912 -337.30561) (xy 112.690808 -337.282176) (xy 112.696498 -337.268566)
			(xy 112.707161 -337.241776) (xy 112.735454 -337.191534) (xy 112.770989 -337.146125) (xy 112.812956 -337.106583)
			(xy 112.860398 -337.073812) (xy 112.912233 -337.048556) (xy 112.96728 -337.031393) (xy 113.024284 -337.022714)
			(xy 113.053114 -337.022186) (xy 113.080365 -337.022665) (xy 113.134313 -337.030423) (xy 113.186608 -337.04578)
			(xy 113.236184 -337.068422) (xy 113.282034 -337.097889) (xy 113.323224 -337.133581) (xy 113.358916 -337.174772)
			(xy 113.388382 -337.220623) (xy 113.411023 -337.2702) (xy 113.426379 -337.322495) (xy 113.434136 -337.376443)
			(xy 113.434622 -337.403694) (xy 113.434622 -337.403948) (xy 113.43405 -337.433787) (xy 113.424732 -337.492733)
			(xy 113.41608 -337.521296) (xy 113.412129 -337.535225) (xy 113.411206 -337.564145) (xy 113.418455 -337.592157)
			(xy 113.433291 -337.616998) (xy 113.454516 -337.636663) (xy 113.480415 -337.649563) (xy 113.494566 -337.652614)
			(xy 113.520644 -337.657759) (xy 113.571147 -337.674334) (xy 113.61886 -337.697762) (xy 113.662857 -337.727588)
			(xy 113.702286 -337.763233) (xy 113.736384 -337.804009) (xy 113.76449 -337.849124) (xy 113.78606 -337.897705)
			(xy 113.800674 -337.94881) (xy 113.808051 -338.001449) (xy 113.80851 -338.028026) (xy 113.80724 -338.059014)
			(xy 113.805208 -338.082636) (xy 113.96091 -338.238338) (xy 119.120666 -338.238338) (xy 119.121223 -338.20865)
			(xy 119.130417 -338.149989) (xy 119.148591 -338.093463) (xy 119.175304 -338.040434) (xy 119.209911 -337.992186)
			(xy 119.251576 -337.949883) (xy 119.275098 -337.93176) (xy 119.28568 -337.923304) (xy 119.302388 -337.901999)
			(xy 119.312909 -337.877051) (xy 119.316503 -337.850216) (xy 119.312918 -337.823379) (xy 119.302404 -337.798428)
			(xy 119.285703 -337.777118) (xy 119.275098 -337.768692) (xy 119.251583 -337.750562) (xy 119.209923 -337.708256)
			(xy 119.175319 -337.660008) (xy 119.148607 -337.606982) (xy 119.130432 -337.550458) (xy 119.121232 -337.491801)
			(xy 119.120666 -337.462114) (xy 119.121152 -337.434863) (xy 119.128908 -337.380915) (xy 119.144263 -337.32862)
			(xy 119.166905 -337.279043) (xy 119.196371 -337.233193) (xy 119.232062 -337.192002) (xy 119.273253 -337.156311)
			(xy 119.319103 -337.126845) (xy 119.36868 -337.104203) (xy 119.420975 -337.088848) (xy 119.474923 -337.081092)
			(xy 119.529425 -337.081092) (xy 119.583373 -337.088848) (xy 119.635668 -337.104203) (xy 119.685245 -337.126845)
			(xy 119.731095 -337.156311) (xy 119.772286 -337.192002) (xy 119.807977 -337.233193) (xy 119.837443 -337.279043)
			(xy 119.860085 -337.32862) (xy 119.87544 -337.380915) (xy 119.883196 -337.434863) (xy 119.883682 -337.462114)
			(xy 119.883144 -337.491803) (xy 119.873943 -337.550463) (xy 119.855765 -337.60699) (xy 119.829048 -337.660017)
			(xy 119.794439 -337.708265) (xy 119.752772 -337.750569) (xy 119.72925 -337.768692) (xy 119.718621 -337.77709)
			(xy 119.701921 -337.798411) (xy 119.691409 -337.823371) (xy 119.687823 -337.850216) (xy 119.691417 -337.877059)
			(xy 119.701936 -337.902015) (xy 119.718643 -337.923331) (xy 119.72925 -337.93176) (xy 119.7528 -337.949847)
			(xy 119.794456 -337.992163) (xy 119.829054 -338.04042) (xy 119.85576 -338.093455) (xy 119.873928 -338.149986)
			(xy 119.88312 -338.208649) (xy 119.883682 -338.238338) (xy 119.883196 -338.265589) (xy 119.87544 -338.319537)
			(xy 119.860085 -338.371832) (xy 119.837443 -338.421409) (xy 119.807977 -338.467259) (xy 119.772286 -338.50845)
			(xy 119.731095 -338.544141) (xy 119.685245 -338.573607) (xy 119.635668 -338.596249) (xy 119.583373 -338.611604)
			(xy 119.529425 -338.61936) (xy 119.474923 -338.61936) (xy 119.420975 -338.611604) (xy 119.36868 -338.596249)
			(xy 119.319103 -338.573607) (xy 119.273253 -338.544141) (xy 119.232062 -338.50845) (xy 119.196371 -338.467259)
			(xy 119.166905 -338.421409) (xy 119.144263 -338.371832) (xy 119.128908 -338.319537) (xy 119.121152 -338.265589)
			(xy 119.120666 -338.238338) (xy 113.96091 -338.238338) (xy 114.278918 -338.556346) (xy 114.294525 -338.572566)
			(xy 114.319591 -338.609947) (xy 114.33687 -338.651506) (xy 114.345695 -338.69564) (xy 114.346228 -338.718144)
			(xy 114.346228 -339.504528) (xy 114.34567 -339.527025) (xy 114.336813 -339.57114) (xy 114.319522 -339.612681)
			(xy 114.294462 -339.650052) (xy 114.278918 -339.666326) (xy 109.873612 -344.071632) (xy 111.7158 -344.071632)
			(xy 111.7158 -343.986936) (xy 111.723851 -343.902622) (xy 111.73988 -343.819456) (xy 111.763741 -343.738189)
			(xy 111.79522 -343.659559) (xy 111.834031 -343.584278) (xy 111.879821 -343.513026) (xy 111.932177 -343.44645)
			(xy 111.990625 -343.385152) (xy 112.054635 -343.329687) (xy 112.123627 -343.280558) (xy 112.196977 -343.238209)
			(xy 112.27402 -343.203025) (xy 112.354059 -343.175323) (xy 112.436368 -343.155355) (xy 112.520203 -343.143302)
			(xy 112.604804 -343.139272) (xy 112.689405 -343.143302) (xy 112.77324 -343.155355) (xy 112.855549 -343.175323)
			(xy 112.935588 -343.203025) (xy 113.012631 -343.238209) (xy 113.085981 -343.280558) (xy 113.154973 -343.329687)
			(xy 113.218983 -343.385152) (xy 113.277431 -343.44645) (xy 113.329787 -343.513026) (xy 113.375577 -343.584278)
			(xy 113.414388 -343.659559) (xy 113.445867 -343.738189) (xy 113.469728 -343.819456) (xy 113.485757 -343.902622)
			(xy 113.493808 -343.986936) (xy 113.494312 -344.029284) (xy 114.240313 -344.029284) (xy 114.244349 -343.945837)
			(xy 114.256421 -343.863169) (xy 114.276414 -343.782052) (xy 114.304143 -343.703243) (xy 114.339349 -343.627478)
			(xy 114.381703 -343.555465) (xy 114.430809 -343.487876) (xy 114.48621 -343.425342) (xy 114.547387 -343.368447)
			(xy 114.61377 -343.317721) (xy 114.684738 -343.27364) (xy 114.75963 -343.236614) (xy 114.837746 -343.206988)
			(xy 114.918356 -343.18504) (xy 115.000708 -343.170975) (xy 115.084034 -343.164923) (xy 115.167554 -343.166942)
			(xy 115.25049 -343.177012) (xy 115.332066 -343.19504) (xy 115.411522 -343.220857) (xy 115.488115 -343.254222)
			(xy 115.561131 -343.294823) (xy 115.629887 -343.342282) (xy 115.693741 -343.396155) (xy 115.752098 -343.45594)
			(xy 115.804413 -343.521077) (xy 115.850196 -343.59096) (xy 115.889021 -343.664935) (xy 115.920526 -343.742312)
			(xy 115.944415 -343.822369) (xy 115.960466 -343.904357) (xy 115.968529 -343.987512) (xy 115.969034 -344.029284)
			(xy 115.968529 -344.071056) (xy 115.960466 -344.154211) (xy 115.944415 -344.236199) (xy 115.920526 -344.316256)
			(xy 115.889021 -344.393633) (xy 115.850196 -344.467608) (xy 115.804413 -344.537491) (xy 115.752098 -344.602628)
			(xy 115.693741 -344.662413) (xy 115.629887 -344.716286) (xy 115.561131 -344.763745) (xy 115.488115 -344.804346)
			(xy 115.411522 -344.837711) (xy 115.332066 -344.863528) (xy 115.25049 -344.881556) (xy 115.167554 -344.891626)
			(xy 115.084034 -344.893645) (xy 115.000708 -344.887593) (xy 114.918356 -344.873528) (xy 114.837746 -344.85158)
			(xy 114.75963 -344.821954) (xy 114.684738 -344.784928) (xy 114.61377 -344.740847) (xy 114.547387 -344.690121)
			(xy 114.48621 -344.633226) (xy 114.430809 -344.570692) (xy 114.381703 -344.503103) (xy 114.339349 -344.43109)
			(xy 114.304143 -344.355325) (xy 114.276414 -344.276516) (xy 114.256421 -344.195399) (xy 114.244349 -344.112731)
			(xy 114.240313 -344.029284) (xy 113.494312 -344.029284) (xy 113.493808 -344.071632) (xy 113.485757 -344.155946)
			(xy 113.469728 -344.239112) (xy 113.445867 -344.320379) (xy 113.414388 -344.399009) (xy 113.375577 -344.47429)
			(xy 113.329787 -344.545542) (xy 113.277431 -344.612118) (xy 113.218983 -344.673416) (xy 113.154973 -344.728881)
			(xy 113.085981 -344.77801) (xy 113.012631 -344.820359) (xy 112.935588 -344.855543) (xy 112.855549 -344.883245)
			(xy 112.77324 -344.903213) (xy 112.689405 -344.915266) (xy 112.604804 -344.919297) (xy 112.520203 -344.915266)
			(xy 112.436368 -344.903213) (xy 112.354059 -344.883245) (xy 112.27402 -344.855543) (xy 112.196977 -344.820359)
			(xy 112.123627 -344.77801) (xy 112.054635 -344.728881) (xy 111.990625 -344.673416) (xy 111.932177 -344.612118)
			(xy 111.879821 -344.545542) (xy 111.834031 -344.47429) (xy 111.79522 -344.399009) (xy 111.763741 -344.320379)
			(xy 111.73988 -344.239112) (xy 111.723851 -344.155946) (xy 111.7158 -344.071632) (xy 109.873612 -344.071632)
			(xy 103.618792 -350.326452) (xy 103.618792 -351.700592) (xy 103.994964 -351.700592) (xy 103.999035 -351.64497)
			(xy 104.011161 -351.590533) (xy 104.031084 -351.538442) (xy 104.05838 -351.489807) (xy 104.092466 -351.445664)
			(xy 104.132615 -351.406955) (xy 104.177973 -351.374504) (xy 104.227573 -351.349003) (xy 104.280357 -351.330996)
			(xy 104.3352 -351.320866) (xy 104.390934 -351.318829) (xy 104.446371 -351.324929) (xy 104.500328 -351.339035)
			(xy 104.551657 -351.360847) (xy 104.599263 -351.389901) (xy 104.642131 -351.425576) (xy 104.679348 -351.467113)
			(xy 104.710121 -351.513626) (xy 104.733793 -351.564123) (xy 104.749861 -351.61753) (xy 104.757981 -351.672706)
			(xy 104.75849 -351.700592) (xy 104.757981 -351.728478) (xy 104.749861 -351.783654) (xy 104.733793 -351.837061)
			(xy 104.721086 -351.864168) (xy 104.858564 -351.864168) (xy 104.862635 -351.808546) (xy 104.874761 -351.754109)
			(xy 104.894684 -351.702018) (xy 104.92198 -351.653383) (xy 104.956066 -351.60924) (xy 104.996215 -351.570531)
			(xy 105.041573 -351.53808) (xy 105.091173 -351.512579) (xy 105.143957 -351.494572) (xy 105.1988 -351.484442)
			(xy 105.254534 -351.482405) (xy 105.309971 -351.488505) (xy 105.357567 -351.500948) (xy 105.871262 -351.500948)
			(xy 105.875333 -351.445326) (xy 105.887459 -351.390889) (xy 105.907382 -351.338798) (xy 105.934678 -351.290163)
			(xy 105.968764 -351.24602) (xy 106.008913 -351.207311) (xy 106.054271 -351.17486) (xy 106.103871 -351.149359)
			(xy 106.156655 -351.131352) (xy 106.211498 -351.121222) (xy 106.267232 -351.119185) (xy 106.322669 -351.125285)
			(xy 106.376626 -351.139391) (xy 106.427955 -351.161203) (xy 106.475561 -351.190257) (xy 106.518429 -351.225932)
			(xy 106.555646 -351.267469) (xy 106.586419 -351.313982) (xy 106.610091 -351.364479) (xy 106.626159 -351.417886)
			(xy 106.634279 -351.473062) (xy 106.634788 -351.500948) (xy 106.887262 -351.500948) (xy 106.891333 -351.445326)
			(xy 106.903459 -351.390889) (xy 106.923382 -351.338798) (xy 106.950678 -351.290163) (xy 106.984764 -351.24602)
			(xy 107.024913 -351.207311) (xy 107.070271 -351.17486) (xy 107.119871 -351.149359) (xy 107.172655 -351.131352)
			(xy 107.227498 -351.121222) (xy 107.283232 -351.119185) (xy 107.338669 -351.125285) (xy 107.392626 -351.139391)
			(xy 107.443955 -351.161203) (xy 107.491561 -351.190257) (xy 107.534429 -351.225932) (xy 107.571646 -351.267469)
			(xy 107.602419 -351.313982) (xy 107.626091 -351.364479) (xy 107.642159 -351.417886) (xy 107.650279 -351.473062)
			(xy 107.650788 -351.500948) (xy 107.903262 -351.500948) (xy 107.907333 -351.445326) (xy 107.919459 -351.390889)
			(xy 107.939382 -351.338798) (xy 107.966678 -351.290163) (xy 108.000764 -351.24602) (xy 108.040913 -351.207311)
			(xy 108.086271 -351.17486) (xy 108.135871 -351.149359) (xy 108.188655 -351.131352) (xy 108.243498 -351.121222)
			(xy 108.299232 -351.119185) (xy 108.354669 -351.125285) (xy 108.408626 -351.139391) (xy 108.459955 -351.161203)
			(xy 108.507561 -351.190257) (xy 108.550429 -351.225932) (xy 108.587646 -351.267469) (xy 108.618419 -351.313982)
			(xy 108.642091 -351.364479) (xy 108.658159 -351.417886) (xy 108.666279 -351.473062) (xy 108.666788 -351.500948)
			(xy 108.919262 -351.500948) (xy 108.923333 -351.445326) (xy 108.935459 -351.390889) (xy 108.955382 -351.338798)
			(xy 108.982678 -351.290163) (xy 109.016764 -351.24602) (xy 109.056913 -351.207311) (xy 109.102271 -351.17486)
			(xy 109.151871 -351.149359) (xy 109.204655 -351.131352) (xy 109.259498 -351.121222) (xy 109.315232 -351.119185)
			(xy 109.370669 -351.125285) (xy 109.424626 -351.139391) (xy 109.475955 -351.161203) (xy 109.523561 -351.190257)
			(xy 109.566429 -351.225932) (xy 109.603646 -351.267469) (xy 109.634419 -351.313982) (xy 109.658091 -351.364479)
			(xy 109.674159 -351.417886) (xy 109.682279 -351.473062) (xy 109.682788 -351.500948) (xy 109.682279 -351.528834)
			(xy 109.674159 -351.58401) (xy 109.658091 -351.637417) (xy 109.634419 -351.687914) (xy 109.603646 -351.734427)
			(xy 109.566429 -351.775964) (xy 109.523561 -351.811639) (xy 109.475955 -351.840693) (xy 109.424626 -351.862505)
			(xy 109.370669 -351.876611) (xy 109.315232 -351.882711) (xy 109.259498 -351.880674) (xy 109.204655 -351.870544)
			(xy 109.151871 -351.852537) (xy 109.102271 -351.827036) (xy 109.056913 -351.794585) (xy 109.016764 -351.755876)
			(xy 108.982678 -351.711733) (xy 108.955382 -351.663098) (xy 108.935459 -351.611007) (xy 108.923333 -351.55657)
			(xy 108.919262 -351.500948) (xy 108.666788 -351.500948) (xy 108.666279 -351.528834) (xy 108.658159 -351.58401)
			(xy 108.642091 -351.637417) (xy 108.618419 -351.687914) (xy 108.587646 -351.734427) (xy 108.550429 -351.775964)
			(xy 108.507561 -351.811639) (xy 108.459955 -351.840693) (xy 108.408626 -351.862505) (xy 108.354669 -351.876611)
			(xy 108.299232 -351.882711) (xy 108.243498 -351.880674) (xy 108.188655 -351.870544) (xy 108.135871 -351.852537)
			(xy 108.086271 -351.827036) (xy 108.040913 -351.794585) (xy 108.000764 -351.755876) (xy 107.966678 -351.711733)
			(xy 107.939382 -351.663098) (xy 107.919459 -351.611007) (xy 107.907333 -351.55657) (xy 107.903262 -351.500948)
			(xy 107.650788 -351.500948) (xy 107.650279 -351.528834) (xy 107.642159 -351.58401) (xy 107.626091 -351.637417)
			(xy 107.602419 -351.687914) (xy 107.571646 -351.734427) (xy 107.534429 -351.775964) (xy 107.491561 -351.811639)
			(xy 107.443955 -351.840693) (xy 107.392626 -351.862505) (xy 107.338669 -351.876611) (xy 107.283232 -351.882711)
			(xy 107.227498 -351.880674) (xy 107.172655 -351.870544) (xy 107.119871 -351.852537) (xy 107.070271 -351.827036)
			(xy 107.024913 -351.794585) (xy 106.984764 -351.755876) (xy 106.950678 -351.711733) (xy 106.923382 -351.663098)
			(xy 106.903459 -351.611007) (xy 106.891333 -351.55657) (xy 106.887262 -351.500948) (xy 106.634788 -351.500948)
			(xy 106.634279 -351.528834) (xy 106.626159 -351.58401) (xy 106.610091 -351.637417) (xy 106.586419 -351.687914)
			(xy 106.555646 -351.734427) (xy 106.518429 -351.775964) (xy 106.475561 -351.811639) (xy 106.427955 -351.840693)
			(xy 106.376626 -351.862505) (xy 106.322669 -351.876611) (xy 106.267232 -351.882711) (xy 106.211498 -351.880674)
			(xy 106.156655 -351.870544) (xy 106.103871 -351.852537) (xy 106.054271 -351.827036) (xy 106.008913 -351.794585)
			(xy 105.968764 -351.755876) (xy 105.934678 -351.711733) (xy 105.907382 -351.663098) (xy 105.887459 -351.611007)
			(xy 105.875333 -351.55657) (xy 105.871262 -351.500948) (xy 105.357567 -351.500948) (xy 105.363928 -351.502611)
			(xy 105.415257 -351.524423) (xy 105.462863 -351.553477) (xy 105.505731 -351.589152) (xy 105.542948 -351.630689)
			(xy 105.573721 -351.677202) (xy 105.597393 -351.727699) (xy 105.613461 -351.781106) (xy 105.621581 -351.836282)
			(xy 105.62209 -351.864168) (xy 105.621581 -351.892054) (xy 105.613461 -351.94723) (xy 105.597393 -352.000637)
			(xy 105.573721 -352.051134) (xy 105.542948 -352.097647) (xy 105.505731 -352.139184) (xy 105.462863 -352.174859)
			(xy 105.415257 -352.203913) (xy 105.363928 -352.225725) (xy 105.309971 -352.239831) (xy 105.254534 -352.245931)
			(xy 105.1988 -352.243894) (xy 105.143957 -352.233764) (xy 105.091173 -352.215757) (xy 105.041573 -352.190256)
			(xy 104.996215 -352.157805) (xy 104.956066 -352.119096) (xy 104.92198 -352.074953) (xy 104.894684 -352.026318)
			(xy 104.874761 -351.974227) (xy 104.862635 -351.91979) (xy 104.858564 -351.864168) (xy 104.721086 -351.864168)
			(xy 104.710121 -351.887558) (xy 104.679348 -351.934071) (xy 104.642131 -351.975608) (xy 104.599263 -352.011283)
			(xy 104.551657 -352.040337) (xy 104.500328 -352.062149) (xy 104.446371 -352.076255) (xy 104.390934 -352.082355)
			(xy 104.3352 -352.080318) (xy 104.280357 -352.070188) (xy 104.227573 -352.052181) (xy 104.177973 -352.02668)
			(xy 104.132615 -351.994229) (xy 104.092466 -351.95552) (xy 104.05838 -351.911377) (xy 104.031084 -351.862742)
			(xy 104.011161 -351.810651) (xy 103.999035 -351.756214) (xy 103.994964 -351.700592) (xy 103.618792 -351.700592)
			(xy 103.618792 -352.065844) (xy 104.694482 -353.14128) (xy 105.54208 -353.14128) (xy 105.564575 -353.141865)
			(xy 105.60869 -353.150713) (xy 105.650231 -353.167996) (xy 105.687604 -353.193049) (xy 105.703878 -353.20859)
			(xy 107.646724 -355.151436) (xy 107.662259 -355.167705) (xy 107.687265 -355.205088) (xy 107.704489 -355.246635)
			(xy 107.713267 -355.290746) (xy 107.71378 -355.313234) (xy 107.71378 -361.963716) (xy 107.713198 -361.986198)
			(xy 107.704413 -362.030295) (xy 107.687203 -362.071834) (xy 107.662227 -362.109223) (xy 107.646724 -362.125514)
			(xy 106.90606 -362.866432) (xy 106.936032 -362.902246) (xy 106.952965 -362.922983) (xy 106.981464 -362.968305)
			(xy 107.003354 -363.017162) (xy 107.018206 -363.068598) (xy 107.025729 -363.121604) (xy 107.026202 -363.148372)
			(xy 107.025716 -363.175623) (xy 107.01796 -363.229571) (xy 107.002605 -363.281866) (xy 106.979963 -363.331443)
			(xy 106.950497 -363.377293) (xy 106.914806 -363.418484) (xy 106.873615 -363.454175) (xy 106.827765 -363.483641)
			(xy 106.778188 -363.506283) (xy 106.725893 -363.521638) (xy 106.671945 -363.529394) (xy 106.617443 -363.529394)
			(xy 106.563495 -363.521638) (xy 106.5112 -363.506283) (xy 106.461623 -363.483641) (xy 106.415773 -363.454175)
			(xy 106.374582 -363.418484) (xy 106.338891 -363.377293) (xy 106.309425 -363.331443) (xy 106.286783 -363.281866)
			(xy 106.271428 -363.229571) (xy 106.263672 -363.175623) (xy 106.263186 -363.148372) (xy 106.263706 -363.120799)
			(xy 106.271648 -363.066229) (xy 106.287363 -363.013371) (xy 106.310523 -362.963325) (xy 106.340645 -362.917134)
			(xy 106.377103 -362.87576) (xy 106.397806 -362.857542) (xy 106.41584 -362.842302) (xy 106.41584 -362.803948)
			(xy 106.416394 -362.781465) (xy 106.425187 -362.737366) (xy 106.442405 -362.695827) (xy 106.467389 -362.658439)
			(xy 106.482896 -362.64215) (xy 107.256072 -361.868974) (xy 107.256072 -355.407976) (xy 105.447338 -353.599496)
			(xy 104.59974 -353.599496) (xy 104.577247 -353.598877) (xy 104.533135 -353.590036) (xy 104.491595 -353.572763)
			(xy 104.454219 -353.547721) (xy 104.437942 -353.532186) (xy 103.22814 -352.322384) (xy 103.212609 -352.306112)
			(xy 103.187603 -352.26873) (xy 103.170379 -352.227183) (xy 103.161599 -352.183074) (xy 103.161084 -352.160586)
			(xy 102.361492 -352.160586) (xy 102.361492 -352.822256) (xy 104.036368 -354.497132) (xy 105.004868 -354.497132)
			(xy 105.008939 -354.44151) (xy 105.021065 -354.387073) (xy 105.040988 -354.334982) (xy 105.068284 -354.286347)
			(xy 105.10237 -354.242204) (xy 105.142519 -354.203495) (xy 105.187877 -354.171044) (xy 105.237477 -354.145543)
			(xy 105.290261 -354.127536) (xy 105.345104 -354.117406) (xy 105.400838 -354.115369) (xy 105.456275 -354.121469)
			(xy 105.510232 -354.135575) (xy 105.561561 -354.157387) (xy 105.609167 -354.186441) (xy 105.652035 -354.222116)
			(xy 105.689252 -354.263653) (xy 105.720025 -354.310166) (xy 105.743697 -354.360663) (xy 105.759765 -354.41407)
			(xy 105.767885 -354.469246) (xy 105.768394 -354.497132) (xy 105.767885 -354.525018) (xy 105.759765 -354.580194)
			(xy 105.743697 -354.633601) (xy 105.720025 -354.684098) (xy 105.689252 -354.730611) (xy 105.652035 -354.772148)
			(xy 105.609167 -354.807823) (xy 105.561561 -354.836877) (xy 105.510232 -354.858689) (xy 105.456275 -354.872795)
			(xy 105.400838 -354.878895) (xy 105.345104 -354.876858) (xy 105.290261 -354.866728) (xy 105.237477 -354.848721)
			(xy 105.187877 -354.82322) (xy 105.142519 -354.790769) (xy 105.10237 -354.75206) (xy 105.068284 -354.707917)
			(xy 105.040988 -354.659282) (xy 105.021065 -354.607191) (xy 105.008939 -354.552754) (xy 105.004868 -354.497132)
			(xy 104.036368 -354.497132) (xy 105.711498 -356.172262) (xy 105.727062 -356.188521) (xy 105.752137 -356.225888)
			(xy 105.769427 -356.267435) (xy 105.778267 -356.31156) (xy 105.778808 -356.33406) (xy 105.778808 -360.561382)
			(xy 105.778199 -360.583876) (xy 105.769354 -360.627987) (xy 105.752078 -360.669528) (xy 105.727034 -360.706903)
			(xy 105.711498 -360.72318) (xy 105.263188 -361.171744) (xy 105.263188 -363.357414) (xy 105.262604 -363.379909)
			(xy 105.253752 -363.424022) (xy 105.236469 -363.465563) (xy 105.211418 -363.502936) (xy 105.195878 -363.519212)
			(xy 105.13187 -363.58322) (xy 105.133902 -363.606842) (xy 105.135172 -363.63783) (xy 105.134712 -363.665087)
			(xy 105.126948 -363.719046) (xy 105.111582 -363.771351) (xy 105.088926 -363.820935) (xy 105.059443 -363.866789)
			(xy 105.023733 -363.90798) (xy 104.982523 -363.943668) (xy 104.936653 -363.973126) (xy 104.887056 -363.995754)
			(xy 104.834744 -364.011092) (xy 104.78078 -364.018827) (xy 104.726265 -364.018802) (xy 104.672309 -364.011017)
			(xy 104.620011 -363.99563) (xy 104.570435 -363.972955) (xy 104.524593 -363.943455) (xy 104.483416 -363.907729)
			(xy 104.447744 -363.866505) (xy 104.418304 -363.820623) (xy 104.395694 -363.771018) (xy 104.380377 -363.718699)
			(xy 104.372662 -363.664733) (xy 104.372709 -363.610218) (xy 104.380515 -363.556265) (xy 104.395922 -363.503973)
			(xy 104.418615 -363.454406) (xy 104.448134 -363.408574) (xy 104.483876 -363.367412) (xy 104.525113 -363.331756)
			(xy 104.571006 -363.302333) (xy 104.62062 -363.279743) (xy 104.672945 -363.264445) (xy 104.726914 -363.256752)
			(xy 104.754172 -363.256322) (xy 104.764189 -363.255858) (xy 104.782701 -363.248201) (xy 104.796873 -363.234043)
			(xy 104.804548 -363.215538) (xy 104.804972 -363.205522) (xy 104.804972 -361.077002) (xy 104.805548 -361.054506)
			(xy 104.8144 -361.010392) (xy 104.831685 -360.968851) (xy 104.85674 -360.931478) (xy 104.872282 -360.915204)
			(xy 105.320592 -360.46664) (xy 105.320592 -356.428802) (xy 101.97084 -353.078796) (xy 101.955314 -353.062519)
			(xy 101.930308 -353.025138) (xy 101.913082 -352.983594) (xy 101.9043 -352.939485) (xy 101.903784 -352.916998)
			(xy 100.939092 -352.916998) (xy 100.939092 -354.459032) (xy 101.443534 -354.459032) (xy 101.447605 -354.40341)
			(xy 101.459731 -354.348973) (xy 101.479654 -354.296882) (xy 101.50695 -354.248247) (xy 101.541036 -354.204104)
			(xy 101.581185 -354.165395) (xy 101.626543 -354.132944) (xy 101.676143 -354.107443) (xy 101.728927 -354.089436)
			(xy 101.78377 -354.079306) (xy 101.839504 -354.077269) (xy 101.894941 -354.083369) (xy 101.948898 -354.097475)
			(xy 102.000227 -354.119287) (xy 102.047833 -354.148341) (xy 102.090701 -354.184016) (xy 102.127918 -354.225553)
			(xy 102.158691 -354.272066) (xy 102.182363 -354.322563) (xy 102.198431 -354.37597) (xy 102.206551 -354.431146)
			(xy 102.20706 -354.459032) (xy 102.206551 -354.486918) (xy 102.198431 -354.542094) (xy 102.182363 -354.595501)
			(xy 102.158691 -354.645998) (xy 102.127918 -354.692511) (xy 102.090701 -354.734048) (xy 102.047833 -354.769723)
			(xy 102.000227 -354.798777) (xy 101.948898 -354.820589) (xy 101.894941 -354.834695) (xy 101.839504 -354.840795)
			(xy 101.78377 -354.838758) (xy 101.728927 -354.828628) (xy 101.676143 -354.810621) (xy 101.626543 -354.78512)
			(xy 101.581185 -354.752669) (xy 101.541036 -354.71396) (xy 101.50695 -354.669817) (xy 101.479654 -354.621182)
			(xy 101.459731 -354.569091) (xy 101.447605 -354.514654) (xy 101.443534 -354.459032) (xy 100.939092 -354.459032)
			(xy 100.939092 -355.398832) (xy 101.492048 -355.398832) (xy 101.496119 -355.34321) (xy 101.508245 -355.288773)
			(xy 101.528168 -355.236682) (xy 101.555464 -355.188047) (xy 101.58955 -355.143904) (xy 101.629699 -355.105195)
			(xy 101.675057 -355.072744) (xy 101.724657 -355.047243) (xy 101.777441 -355.029236) (xy 101.832284 -355.019106)
			(xy 101.888018 -355.017069) (xy 101.943455 -355.023169) (xy 101.997412 -355.037275) (xy 102.048741 -355.059087)
			(xy 102.096347 -355.088141) (xy 102.139215 -355.123816) (xy 102.176432 -355.165353) (xy 102.207205 -355.211866)
			(xy 102.230877 -355.262363) (xy 102.246945 -355.31577) (xy 102.255065 -355.370946) (xy 102.255574 -355.398832)
			(xy 102.255065 -355.426718) (xy 102.246945 -355.481894) (xy 102.230877 -355.535301) (xy 102.207205 -355.585798)
			(xy 102.176432 -355.632311) (xy 102.139215 -355.673848) (xy 102.096347 -355.709523) (xy 102.048741 -355.738577)
			(xy 101.997412 -355.760389) (xy 101.943455 -355.774495) (xy 101.888018 -355.780595) (xy 101.832284 -355.778558)
			(xy 101.777441 -355.768428) (xy 101.724657 -355.750421) (xy 101.675057 -355.72492) (xy 101.629699 -355.692469)
			(xy 101.58955 -355.65376) (xy 101.555464 -355.609617) (xy 101.528168 -355.560982) (xy 101.508245 -355.508891)
			(xy 101.496119 -355.454454) (xy 101.492048 -355.398832) (xy 100.939092 -355.398832) (xy 100.939092 -356.261924)
			(xy 103.482392 -356.261924) (xy 103.486463 -356.206302) (xy 103.498589 -356.151865) (xy 103.518512 -356.099774)
			(xy 103.545808 -356.051139) (xy 103.579894 -356.006996) (xy 103.620043 -355.968287) (xy 103.665401 -355.935836)
			(xy 103.715001 -355.910335) (xy 103.767785 -355.892328) (xy 103.822628 -355.882198) (xy 103.878362 -355.880161)
			(xy 103.933799 -355.886261) (xy 103.987756 -355.900367) (xy 104.039085 -355.922179) (xy 104.086691 -355.951233)
			(xy 104.129559 -355.986908) (xy 104.166776 -356.028445) (xy 104.197549 -356.074958) (xy 104.221221 -356.125455)
			(xy 104.237289 -356.178862) (xy 104.245409 -356.234038) (xy 104.245918 -356.261924) (xy 104.245409 -356.28981)
			(xy 104.237289 -356.344986) (xy 104.221221 -356.398393) (xy 104.197549 -356.44889) (xy 104.166776 -356.495403)
			(xy 104.129559 -356.53694) (xy 104.086691 -356.572615) (xy 104.039085 -356.601669) (xy 103.987756 -356.623481)
			(xy 103.933799 -356.637587) (xy 103.878362 -356.643687) (xy 103.822628 -356.64165) (xy 103.767785 -356.63152)
			(xy 103.715001 -356.613513) (xy 103.665401 -356.588012) (xy 103.620043 -356.555561) (xy 103.579894 -356.516852)
			(xy 103.545808 -356.472709) (xy 103.518512 -356.424074) (xy 103.498589 -356.371983) (xy 103.486463 -356.317546)
			(xy 103.482392 -356.261924) (xy 100.939092 -356.261924) (xy 100.939092 -356.795578) (xy 101.453186 -356.795578)
			(xy 101.457257 -356.739956) (xy 101.469383 -356.685519) (xy 101.489306 -356.633428) (xy 101.516602 -356.584793)
			(xy 101.550688 -356.54065) (xy 101.590837 -356.501941) (xy 101.636195 -356.46949) (xy 101.685795 -356.443989)
			(xy 101.738579 -356.425982) (xy 101.793422 -356.415852) (xy 101.849156 -356.413815) (xy 101.904593 -356.419915)
			(xy 101.95855 -356.434021) (xy 102.009879 -356.455833) (xy 102.057485 -356.484887) (xy 102.100353 -356.520562)
			(xy 102.13757 -356.562099) (xy 102.168343 -356.608612) (xy 102.192015 -356.659109) (xy 102.208083 -356.712516)
			(xy 102.216203 -356.767692) (xy 102.216712 -356.795578) (xy 102.216203 -356.823464) (xy 102.208083 -356.87864)
			(xy 102.192015 -356.932047) (xy 102.168343 -356.982544) (xy 102.13757 -357.029057) (xy 102.100353 -357.070594)
			(xy 102.057485 -357.106269) (xy 102.009879 -357.135323) (xy 101.95855 -357.157135) (xy 101.904593 -357.171241)
			(xy 101.849156 -357.177341) (xy 101.793422 -357.175304) (xy 101.738579 -357.165174) (xy 101.685795 -357.147167)
			(xy 101.636195 -357.121666) (xy 101.590837 -357.089215) (xy 101.550688 -357.050506) (xy 101.516602 -357.006363)
			(xy 101.489306 -356.957728) (xy 101.469383 -356.905637) (xy 101.457257 -356.8512) (xy 101.453186 -356.795578)
			(xy 100.939092 -356.795578) (xy 100.939092 -357.689658) (xy 101.452678 -357.689658) (xy 101.456749 -357.634036)
			(xy 101.468875 -357.579599) (xy 101.488798 -357.527508) (xy 101.516094 -357.478873) (xy 101.55018 -357.43473)
			(xy 101.590329 -357.396021) (xy 101.635687 -357.36357) (xy 101.685287 -357.338069) (xy 101.738071 -357.320062)
			(xy 101.792914 -357.309932) (xy 101.848648 -357.307895) (xy 101.904085 -357.313995) (xy 101.958042 -357.328101)
			(xy 102.009371 -357.349913) (xy 102.056977 -357.378967) (xy 102.099845 -357.414642) (xy 102.137062 -357.456179)
			(xy 102.167835 -357.502692) (xy 102.191507 -357.553189) (xy 102.207575 -357.606596) (xy 102.215695 -357.661772)
			(xy 102.216204 -357.689658) (xy 102.215695 -357.717544) (xy 102.207575 -357.77272) (xy 102.191507 -357.826127)
			(xy 102.167835 -357.876624) (xy 102.137062 -357.923137) (xy 102.099845 -357.964674) (xy 102.056977 -358.000349)
			(xy 102.009371 -358.029403) (xy 101.958042 -358.051215) (xy 101.904085 -358.065321) (xy 101.848648 -358.071421)
			(xy 101.792914 -358.069384) (xy 101.738071 -358.059254) (xy 101.685287 -358.041247) (xy 101.635687 -358.015746)
			(xy 101.590329 -357.983295) (xy 101.55018 -357.944586) (xy 101.516094 -357.900443) (xy 101.488798 -357.851808)
			(xy 101.468875 -357.799717) (xy 101.456749 -357.74528) (xy 101.452678 -357.689658) (xy 100.939092 -357.689658)
			(xy 100.939092 -358.221277) (xy 103.496811 -358.221277) (xy 103.504564 -358.167319) (xy 103.519917 -358.115013)
			(xy 103.542559 -358.065425) (xy 103.572026 -358.019564) (xy 103.607721 -357.978364) (xy 103.648916 -357.942663)
			(xy 103.694772 -357.913188) (xy 103.744356 -357.890539) (xy 103.796659 -357.875177) (xy 103.850616 -357.867415)
			(xy 103.877872 -357.86695) (xy 103.894015 -357.867093) (xy 103.926189 -357.869764) (xy 103.942134 -357.872284)
			(xy 103.955936 -357.874165) (xy 103.983631 -357.871332) (xy 104.00953 -357.861119) (xy 104.031703 -357.844285)
			(xy 104.048501 -357.822083) (xy 104.058672 -357.796168) (xy 104.061459 -357.768468) (xy 104.059482 -357.754682)
			(xy 104.055342 -357.734617) (xy 104.050887 -357.693888) (xy 104.050592 -357.673402) (xy 104.051053 -357.646149)
			(xy 104.05881 -357.592198) (xy 104.074166 -357.539899) (xy 104.096808 -357.490319) (xy 104.126276 -357.444465)
			(xy 104.16197 -357.403272) (xy 104.203163 -357.367578) (xy 104.249016 -357.33811) (xy 104.298596 -357.315467)
			(xy 104.350894 -357.300111) (xy 104.404846 -357.292353) (xy 104.459352 -357.292353) (xy 104.513303 -357.30011)
			(xy 104.565601 -357.315466) (xy 104.615182 -357.338109) (xy 104.661035 -357.367577) (xy 104.702228 -357.40327)
			(xy 104.737922 -357.444463) (xy 104.767391 -357.490317) (xy 104.790033 -357.539897) (xy 104.805389 -357.592195)
			(xy 104.813147 -357.646146) (xy 104.813147 -357.700652) (xy 104.80539 -357.754604) (xy 104.790034 -357.806902)
			(xy 104.767391 -357.856482) (xy 104.737923 -357.902336) (xy 104.702229 -357.943529) (xy 104.661036 -357.979223)
			(xy 104.615183 -358.008691) (xy 104.565602 -358.031333) (xy 104.513304 -358.04669) (xy 104.459353 -358.054447)
			(xy 104.4321 -358.05491) (xy 104.415957 -358.054772) (xy 104.383783 -358.052097) (xy 104.367838 -358.049576)
			(xy 104.353814 -358.047629) (xy 104.325679 -358.050694) (xy 104.299465 -358.061365) (xy 104.277187 -358.07882)
			(xy 104.260555 -358.10172) (xy 104.250848 -358.128305) (xy 104.248811 -358.156533) (xy 104.251252 -358.17048)
			(xy 104.255053 -358.18975) (xy 104.259125 -358.228818) (xy 104.25938 -358.248458) (xy 104.25899 -358.275714)
			(xy 104.251238 -358.329672) (xy 104.235886 -358.381978) (xy 104.213246 -358.431566) (xy 104.183779 -358.477428)
			(xy 104.148086 -358.518629) (xy 104.106892 -358.554332) (xy 104.061036 -358.583808) (xy 104.011452 -358.606458)
			(xy 103.95915 -358.621821) (xy 103.905193 -358.629584) (xy 103.850681 -358.62959) (xy 103.796723 -358.621837)
			(xy 103.744418 -358.606484) (xy 103.694829 -358.583844) (xy 103.648968 -358.554376) (xy 103.607767 -358.518682)
			(xy 103.572066 -358.477488) (xy 103.54259 -358.431632) (xy 103.51994 -358.382048) (xy 103.504578 -358.329745)
			(xy 103.496815 -358.275789) (xy 103.496811 -358.221277) (xy 100.939092 -358.221277) (xy 100.939092 -359.188004)
			(xy 104.05313 -359.188004) (xy 104.057201 -359.132382) (xy 104.069327 -359.077945) (xy 104.08925 -359.025854)
			(xy 104.116546 -358.977219) (xy 104.150632 -358.933076) (xy 104.190781 -358.894367) (xy 104.236139 -358.861916)
			(xy 104.285739 -358.836415) (xy 104.338523 -358.818408) (xy 104.393366 -358.808278) (xy 104.4491 -358.806241)
			(xy 104.504537 -358.812341) (xy 104.558494 -358.826447) (xy 104.609823 -358.848259) (xy 104.657429 -358.877313)
			(xy 104.700297 -358.912988) (xy 104.737514 -358.954525) (xy 104.768287 -359.001038) (xy 104.791959 -359.051535)
			(xy 104.808027 -359.104942) (xy 104.816147 -359.160118) (xy 104.816656 -359.188004) (xy 104.816147 -359.21589)
			(xy 104.808027 -359.271066) (xy 104.791959 -359.324473) (xy 104.768287 -359.37497) (xy 104.737514 -359.421483)
			(xy 104.700297 -359.46302) (xy 104.657429 -359.498695) (xy 104.609823 -359.527749) (xy 104.558494 -359.549561)
			(xy 104.504537 -359.563667) (xy 104.4491 -359.569767) (xy 104.393366 -359.56773) (xy 104.338523 -359.5576)
			(xy 104.285739 -359.539593) (xy 104.236139 -359.514092) (xy 104.190781 -359.481641) (xy 104.150632 -359.442932)
			(xy 104.116546 -359.398789) (xy 104.08925 -359.350154) (xy 104.069327 -359.298063) (xy 104.057201 -359.243626)
			(xy 104.05313 -359.188004) (xy 100.939092 -359.188004) (xy 100.939092 -359.985056) (xy 101.469696 -359.985056)
			(xy 101.473767 -359.929434) (xy 101.485893 -359.874997) (xy 101.505816 -359.822906) (xy 101.533112 -359.774271)
			(xy 101.567198 -359.730128) (xy 101.607347 -359.691419) (xy 101.652705 -359.658968) (xy 101.702305 -359.633467)
			(xy 101.755089 -359.61546) (xy 101.809932 -359.60533) (xy 101.865666 -359.603293) (xy 101.921103 -359.609393)
			(xy 101.97506 -359.623499) (xy 102.026389 -359.645311) (xy 102.073995 -359.674365) (xy 102.116863 -359.71004)
			(xy 102.15408 -359.751577) (xy 102.184853 -359.79809) (xy 102.208525 -359.848587) (xy 102.224593 -359.901994)
			(xy 102.232713 -359.95717) (xy 102.233222 -359.985056) (xy 102.232713 -360.012942) (xy 102.224593 -360.068118)
			(xy 102.208525 -360.121525) (xy 102.184853 -360.172022) (xy 102.155123 -360.216958) (xy 103.98963 -360.216958)
			(xy 103.993701 -360.161336) (xy 104.005827 -360.106899) (xy 104.02575 -360.054808) (xy 104.053046 -360.006173)
			(xy 104.087132 -359.96203) (xy 104.127281 -359.923321) (xy 104.172639 -359.89087) (xy 104.222239 -359.865369)
			(xy 104.275023 -359.847362) (xy 104.329866 -359.837232) (xy 104.3856 -359.835195) (xy 104.441037 -359.841295)
			(xy 104.494994 -359.855401) (xy 104.546323 -359.877213) (xy 104.593929 -359.906267) (xy 104.636797 -359.941942)
			(xy 104.674014 -359.983479) (xy 104.704787 -360.029992) (xy 104.728459 -360.080489) (xy 104.744527 -360.133896)
			(xy 104.752647 -360.189072) (xy 104.753156 -360.216958) (xy 104.752647 -360.244844) (xy 104.744527 -360.30002)
			(xy 104.728459 -360.353427) (xy 104.704787 -360.403924) (xy 104.674014 -360.450437) (xy 104.636797 -360.491974)
			(xy 104.593929 -360.527649) (xy 104.546323 -360.556703) (xy 104.494994 -360.578515) (xy 104.441037 -360.592621)
			(xy 104.3856 -360.598721) (xy 104.329866 -360.596684) (xy 104.275023 -360.586554) (xy 104.222239 -360.568547)
			(xy 104.172639 -360.543046) (xy 104.127281 -360.510595) (xy 104.087132 -360.471886) (xy 104.053046 -360.427743)
			(xy 104.02575 -360.379108) (xy 104.005827 -360.327017) (xy 103.993701 -360.27258) (xy 103.98963 -360.216958)
			(xy 102.155123 -360.216958) (xy 102.15408 -360.218535) (xy 102.116863 -360.260072) (xy 102.073995 -360.295747)
			(xy 102.026389 -360.324801) (xy 101.97506 -360.346613) (xy 101.921103 -360.360719) (xy 101.865666 -360.366819)
			(xy 101.809932 -360.364782) (xy 101.755089 -360.354652) (xy 101.702305 -360.336645) (xy 101.652705 -360.311144)
			(xy 101.607347 -360.278693) (xy 101.567198 -360.239984) (xy 101.533112 -360.195841) (xy 101.505816 -360.147206)
			(xy 101.485893 -360.095115) (xy 101.473767 -360.040678) (xy 101.469696 -359.985056) (xy 100.939092 -359.985056)
			(xy 100.939092 -360.35361) (xy 101.406198 -360.820716) (xy 101.421787 -360.836952) (xy 101.446858 -360.874327)
			(xy 101.464141 -360.915881) (xy 101.472972 -360.960012) (xy 101.473508 -360.982514) (xy 101.473508 -361.952032)
			(xy 102.011732 -361.952032) (xy 102.015803 -361.89641) (xy 102.027929 -361.841973) (xy 102.047852 -361.789882)
			(xy 102.075148 -361.741247) (xy 102.109234 -361.697104) (xy 102.149383 -361.658395) (xy 102.194741 -361.625944)
			(xy 102.244341 -361.600443) (xy 102.297125 -361.582436) (xy 102.351968 -361.572306) (xy 102.407702 -361.570269)
			(xy 102.463139 -361.576369) (xy 102.517096 -361.590475) (xy 102.568425 -361.612287) (xy 102.616031 -361.641341)
			(xy 102.658899 -361.677016) (xy 102.696116 -361.718553) (xy 102.726889 -361.765066) (xy 102.750561 -361.815563)
			(xy 102.766629 -361.86897) (xy 102.774749 -361.924146) (xy 102.775188 -361.948222) (xy 103.776778 -361.948222)
			(xy 103.780849 -361.8926) (xy 103.792975 -361.838163) (xy 103.812898 -361.786072) (xy 103.840194 -361.737437)
			(xy 103.87428 -361.693294) (xy 103.914429 -361.654585) (xy 103.959787 -361.622134) (xy 104.009387 -361.596633)
			(xy 104.062171 -361.578626) (xy 104.117014 -361.568496) (xy 104.172748 -361.566459) (xy 104.228185 -361.572559)
			(xy 104.282142 -361.586665) (xy 104.333471 -361.608477) (xy 104.381077 -361.637531) (xy 104.423945 -361.673206)
			(xy 104.461162 -361.714743) (xy 104.491935 -361.761256) (xy 104.515607 -361.811753) (xy 104.531675 -361.86516)
			(xy 104.539795 -361.920336) (xy 104.540304 -361.948222) (xy 104.539795 -361.976108) (xy 104.531675 -362.031284)
			(xy 104.515607 -362.084691) (xy 104.491935 -362.135188) (xy 104.461162 -362.181701) (xy 104.423945 -362.223238)
			(xy 104.381077 -362.258913) (xy 104.333471 -362.287967) (xy 104.282142 -362.309779) (xy 104.228185 -362.323885)
			(xy 104.172748 -362.329985) (xy 104.117014 -362.327948) (xy 104.062171 -362.317818) (xy 104.009387 -362.299811)
			(xy 103.959787 -362.27431) (xy 103.914429 -362.241859) (xy 103.87428 -362.20315) (xy 103.840194 -362.159007)
			(xy 103.812898 -362.110372) (xy 103.792975 -362.058281) (xy 103.780849 -362.003844) (xy 103.776778 -361.948222)
			(xy 102.775188 -361.948222) (xy 102.775258 -361.952032) (xy 102.774749 -361.979918) (xy 102.766629 -362.035094)
			(xy 102.750561 -362.088501) (xy 102.726889 -362.138998) (xy 102.696116 -362.185511) (xy 102.658899 -362.227048)
			(xy 102.616031 -362.262723) (xy 102.568425 -362.291777) (xy 102.517096 -362.313589) (xy 102.463139 -362.327695)
			(xy 102.407702 -362.333795) (xy 102.351968 -362.331758) (xy 102.297125 -362.321628) (xy 102.244341 -362.303621)
			(xy 102.194741 -362.27812) (xy 102.149383 -362.245669) (xy 102.109234 -362.20696) (xy 102.075148 -362.162817)
			(xy 102.047852 -362.114182) (xy 102.027929 -362.062091) (xy 102.015803 -362.007654) (xy 102.011732 -361.952032)
			(xy 101.473508 -361.952032) (xy 101.473508 -362.0389) (xy 102.650036 -363.215428) (xy 103.338884 -363.215428)
			(xy 103.361379 -363.216025) (xy 103.405491 -363.224873) (xy 103.447032 -363.242152) (xy 103.484406 -363.267199)
			(xy 103.500682 -363.282738) (xy 104.52354 -364.305596) (xy 105.017316 -364.305596) (xy 105.521252 -363.801406)
			(xy 105.521252 -362.472478) (xy 105.521532 -362.457894) (xy 105.525356 -362.428976) (xy 105.528872 -362.41482)
			(xy 105.523677 -362.392381) (xy 105.518074 -362.346663) (xy 105.517696 -362.323634) (xy 105.518182 -362.296383)
			(xy 105.525938 -362.242435) (xy 105.541293 -362.19014) (xy 105.563935 -362.140563) (xy 105.593401 -362.094713)
			(xy 105.629092 -362.053522) (xy 105.670283 -362.017831) (xy 105.716133 -361.988365) (xy 105.76571 -361.965723)
			(xy 105.818005 -361.950368) (xy 105.871953 -361.942612) (xy 105.926455 -361.942612) (xy 105.980403 -361.950368)
			(xy 106.032698 -361.965723) (xy 106.082275 -361.988365) (xy 106.128125 -362.017831) (xy 106.169316 -362.053522)
			(xy 106.205007 -362.094713) (xy 106.234473 -362.140563) (xy 106.257115 -362.19014) (xy 106.27247 -362.242435)
			(xy 106.280226 -362.296383) (xy 106.280712 -362.323634) (xy 106.28022 -362.352444) (xy 106.271524 -362.409403)
			(xy 106.254364 -362.464409) (xy 106.229131 -362.51621) (xy 106.196398 -362.563629) (xy 106.156909 -362.605589)
			(xy 106.111561 -362.641136) (xy 106.061385 -362.669463) (xy 106.007521 -362.689925) (xy 105.979468 -362.696506)
			(xy 105.979468 -363.896148) (xy 105.97885 -363.918642) (xy 105.970009 -363.962753) (xy 105.952736 -364.004294)
			(xy 105.927694 -364.041669) (xy 105.912158 -364.057946) (xy 105.529051 -364.441053) (xy 106.121655 -364.441053)
			(xy 106.121655 -364.386547) (xy 106.129413 -364.332595) (xy 106.144769 -364.280297) (xy 106.167412 -364.230716)
			(xy 106.196881 -364.184863) (xy 106.232575 -364.14367) (xy 106.273769 -364.107976) (xy 106.319623 -364.078508)
			(xy 106.369204 -364.055866) (xy 106.421503 -364.040511) (xy 106.475455 -364.032755) (xy 106.502708 -364.032292)
			(xy 106.503216 -364.032292) (xy 106.529533 -364.032752) (xy 106.581663 -364.040013) (xy 106.607102 -364.04677)
			(xy 106.635804 -364.054898) (xy 107.286552 -363.40415) (xy 107.286552 -362.986828) (xy 107.28715 -362.964333)
			(xy 107.295996 -362.92022) (xy 107.313274 -362.878679) (xy 107.338323 -362.841306) (xy 107.353862 -362.82503)
			(xy 109.254544 -360.924094) (xy 109.254544 -352.631502) (xy 109.255128 -352.609007) (xy 109.263979 -352.564893)
			(xy 109.281262 -352.523352) (xy 109.306313 -352.485979) (xy 109.321854 -352.469704) (xy 109.938312 -351.852992)
			(xy 109.938312 -350.959928) (xy 109.938921 -350.937434) (xy 109.947765 -350.893322) (xy 109.965041 -350.851782)
			(xy 109.990085 -350.814407) (xy 110.005622 -350.79813) (xy 110.658402 -350.14535) (xy 110.674636 -350.129759)
			(xy 110.712013 -350.104691) (xy 110.753568 -350.087408) (xy 110.797698 -350.078577) (xy 110.8202 -350.07804)
			(xy 111.865664 -350.07804) (xy 117.444012 -344.499692) (xy 117.444012 -342.499442) (xy 117.44463 -342.476949)
			(xy 117.453471 -342.432837) (xy 117.470745 -342.391296) (xy 117.495786 -342.353921) (xy 117.511322 -342.337644)
			(xy 119.635524 -340.213442) (xy 119.651763 -340.197856) (xy 119.689136 -340.172783) (xy 119.73069 -340.155498)
			(xy 119.77482 -340.146668) (xy 119.797322 -340.146132) (xy 121.536206 -340.146132) (xy 122.117104 -339.565488)
			(xy 122.117104 -338.881212) (xy 121.642124 -338.406232) (xy 121.618502 -338.408264) (xy 121.587514 -338.409534)
			(xy 121.560264 -338.409009) (xy 121.506319 -338.401255) (xy 121.454027 -338.385903) (xy 121.404452 -338.363265)
			(xy 121.358602 -338.333803) (xy 121.317413 -338.298116) (xy 121.281721 -338.25693) (xy 121.252254 -338.211084)
			(xy 121.229611 -338.161511) (xy 121.214254 -338.10922) (xy 121.206494 -338.055276) (xy 121.206006 -338.028026)
			(xy 121.206006 -338.027772) (xy 121.206581 -337.997933) (xy 121.215897 -337.938987) (xy 121.224548 -337.910424)
			(xy 121.228568 -337.896513) (xy 121.229471 -337.867586) (xy 121.222206 -337.83957) (xy 121.207357 -337.814728)
			(xy 121.186123 -337.795062) (xy 121.160217 -337.782159) (xy 121.146062 -337.779106) (xy 121.113226 -337.77251)
			(xy 121.050372 -337.749396) (xy 121.021094 -337.733132) (xy 121.008116 -337.72612) (xy 120.979485 -337.719086)
			(xy 120.950038 -337.720528) (xy 120.92223 -337.730325) (xy 120.898382 -337.74766) (xy 120.880483 -337.771087)
			(xy 120.87479 -337.784694) (xy 120.864116 -337.81148) (xy 120.835826 -337.861723) (xy 120.800294 -337.907134)
			(xy 120.758329 -337.946677) (xy 120.710889 -337.97945) (xy 120.659054 -338.004706) (xy 120.604007 -338.021869)
			(xy 120.547004 -338.030547) (xy 120.518174 -338.031074) (xy 120.490922 -338.030654) (xy 120.436972 -338.022894)
			(xy 120.384676 -338.007535) (xy 120.335097 -337.984891) (xy 120.289246 -337.955421) (xy 120.248055 -337.919726)
			(xy 120.212363 -337.878533) (xy 120.182897 -337.83268) (xy 120.160255 -337.7831) (xy 120.1449 -337.730803)
			(xy 120.137144 -337.676852) (xy 120.137144 -337.622348) (xy 120.1449 -337.568397) (xy 120.160255 -337.5161)
			(xy 120.182897 -337.46652) (xy 120.212363 -337.420667) (xy 120.248055 -337.379474) (xy 120.289246 -337.343779)
			(xy 120.335097 -337.314309) (xy 120.384676 -337.291665) (xy 120.436972 -337.276306) (xy 120.490922 -337.268546)
			(xy 120.518174 -337.268058) (xy 120.518428 -337.268058) (xy 120.543632 -337.268443) (xy 120.593601 -337.275086)
			(xy 120.642255 -337.288267) (xy 120.688745 -337.307754) (xy 120.710706 -337.320128) (xy 120.723675 -337.32716)
			(xy 120.75231 -337.334199) (xy 120.781763 -337.332757) (xy 120.809575 -337.322956) (xy 120.833424 -337.305614)
			(xy 120.85132 -337.282177) (xy 120.85701 -337.268566) (xy 120.867663 -337.241771) (xy 120.895957 -337.191529)
			(xy 120.931494 -337.14612) (xy 120.973462 -337.106579) (xy 121.020905 -337.073807) (xy 121.072742 -337.048553)
			(xy 121.127791 -337.031391) (xy 121.184795 -337.022713) (xy 121.213626 -337.022186) (xy 121.240878 -337.022654)
			(xy 121.294826 -337.030413) (xy 121.34712 -337.045772) (xy 121.396697 -337.068415) (xy 121.442547 -337.097884)
			(xy 121.483737 -337.133577) (xy 121.519428 -337.174769) (xy 121.548894 -337.22062) (xy 121.571535 -337.270198)
			(xy 121.586891 -337.322494) (xy 121.594648 -337.376442) (xy 121.595134 -337.403694) (xy 121.595134 -337.403948)
			(xy 121.594561 -337.433787) (xy 121.586832 -337.482688) (xy 123.707398 -337.482688) (xy 123.707925 -337.455116)
			(xy 123.715865 -337.400546) (xy 123.731578 -337.347687) (xy 123.754737 -337.297641) (xy 123.784858 -337.251449)
			(xy 123.821316 -337.210076) (xy 123.842018 -337.191858) (xy 123.852925 -337.18197) (xy 123.868994 -337.157316)
			(xy 123.877374 -337.129106) (xy 123.877372 -337.099678) (xy 123.868987 -337.071469) (xy 123.852915 -337.046818)
			(xy 123.842018 -337.036918) (xy 123.821316 -337.018697) (xy 123.784844 -336.977331) (xy 123.75471 -336.931143)
			(xy 123.731543 -336.881097) (xy 123.715825 -336.828236) (xy 123.707884 -336.773662) (xy 123.707398 -336.746088)
			(xy 123.707867 -336.718836) (xy 123.715625 -336.664888) (xy 123.730982 -336.612592) (xy 123.753625 -336.563014)
			(xy 123.783093 -336.517164) (xy 123.818786 -336.475974) (xy 123.859978 -336.440282) (xy 123.90583 -336.410816)
			(xy 123.955409 -336.388176) (xy 124.007705 -336.372821) (xy 124.061654 -336.365065) (xy 124.088906 -336.36458)
			(xy 124.089668 -336.36458) (xy 124.101639 -336.364688) (xy 124.125532 -336.366216) (xy 124.13742 -336.367628)
			(xy 124.151183 -336.36885) (xy 124.178509 -336.364881) (xy 124.203774 -336.353739) (xy 124.225132 -336.336237)
			(xy 124.241022 -336.313655) (xy 124.250284 -336.287641) (xy 124.25172 -336.273902) (xy 124.254288 -336.245371)
			(xy 124.26677 -336.189468) (xy 124.287472 -336.136059) (xy 124.315929 -336.086348) (xy 124.351502 -336.041452)
			(xy 124.393389 -336.002382) (xy 124.440649 -335.970016) (xy 124.492218 -335.945083) (xy 124.546936 -335.928143)
			(xy 124.603572 -335.919578) (xy 124.632212 -335.919064) (xy 124.650231 -335.919288) (xy 124.686106 -335.92272)
			(xy 124.70384 -335.925922) (xy 124.719042 -335.928328) (xy 124.749605 -335.924788) (xy 124.77773 -335.912312)
			(xy 124.800866 -335.89203) (xy 124.816917 -335.865781) (xy 124.821188 -335.850992) (xy 124.828636 -335.823962)
			(xy 124.850258 -335.772237) (xy 124.879215 -335.724232) (xy 124.914884 -335.68098) (xy 124.956497 -335.643411)
			(xy 125.003158 -335.612335) (xy 125.053864 -335.588419) (xy 125.107523 -335.57218) (xy 125.162981 -335.563965)
			(xy 125.191012 -335.563464) (xy 125.218262 -335.563967) (xy 125.272208 -335.571724) (xy 125.324501 -335.587079)
			(xy 125.374076 -335.60972) (xy 125.419925 -335.639185) (xy 125.461114 -335.674874) (xy 125.496806 -335.716062)
			(xy 125.526273 -335.76191) (xy 125.548915 -335.811484) (xy 125.564273 -335.863776) (xy 125.572032 -335.917722)
			(xy 125.57252 -335.944972) (xy 125.572028 -335.972546) (xy 125.56408 -336.027117) (xy 125.54836 -336.079976)
			(xy 125.525194 -336.130022) (xy 125.495067 -336.176212) (xy 125.458605 -336.217585) (xy 125.4379 -336.235802)
			(xy 125.427031 -336.245729) (xy 125.410958 -336.270371) (xy 125.402572 -336.298572) (xy 125.402566 -336.327992)
			(xy 125.410943 -336.356195) (xy 125.427007 -336.380843) (xy 125.4379 -336.390742) (xy 125.458577 -336.408988)
			(xy 125.495041 -336.450356) (xy 125.525168 -336.496542) (xy 125.548331 -336.546585) (xy 125.564048 -336.599441)
			(xy 125.57199 -336.65401) (xy 125.571993 -336.709154) (xy 125.564056 -336.763723) (xy 125.548344 -336.816581)
			(xy 125.525186 -336.866626) (xy 125.495063 -336.912816) (xy 125.458603 -336.954186) (xy 125.4379 -336.972402)
			(xy 125.427031 -336.982329) (xy 125.410958 -337.006971) (xy 125.402572 -337.035172) (xy 125.402566 -337.064592)
			(xy 125.410943 -337.092795) (xy 125.427007 -337.117443) (xy 125.4379 -337.127342) (xy 125.458586 -337.14558)
			(xy 125.495059 -337.186943) (xy 125.525194 -337.233127) (xy 125.548364 -337.28317) (xy 125.564086 -337.336028)
			(xy 125.572031 -337.390599) (xy 125.57252 -337.418172) (xy 125.572019 -337.445424) (xy 125.564266 -337.499373)
			(xy 125.548914 -337.551669) (xy 125.526276 -337.601248) (xy 125.496812 -337.647101) (xy 125.461122 -337.688294)
			(xy 125.419933 -337.723988) (xy 125.374083 -337.753456) (xy 125.324506 -337.7761) (xy 125.272212 -337.791457)
			(xy 125.218264 -337.799216) (xy 125.191012 -337.79968) (xy 125.163156 -337.799161) (xy 125.10804 -337.791038)
			(xy 125.054689 -337.774993) (xy 125.004235 -337.751367) (xy 124.95775 -337.720659) (xy 124.916221 -337.683523)
			(xy 124.880528 -337.640747) (xy 124.85143 -337.593238) (xy 124.829543 -337.542006) (xy 124.82195 -337.5152)
			(xy 124.817696 -337.501077) (xy 124.802301 -337.475931) (xy 124.780378 -337.456216) (xy 124.753745 -337.443567)
			(xy 124.724611 -337.439033) (xy 124.709936 -337.440524) (xy 124.697109 -337.442177) (xy 124.671306 -337.443953)
			(xy 124.658374 -337.44408) (xy 124.657612 -337.44408) (xy 124.639981 -337.443844) (xy 124.604873 -337.440538)
			(xy 124.587508 -337.437476) (xy 124.573734 -337.435253) (xy 124.545948 -337.437699) (xy 124.519864 -337.447584)
			(xy 124.497434 -337.464166) (xy 124.480337 -337.486207) (xy 124.469852 -337.512055) (xy 124.467874 -337.525868)
			(xy 124.464232 -337.553444) (xy 124.450001 -337.607215) (xy 124.428107 -337.658348) (xy 124.399017 -337.705757)
			(xy 124.363347 -337.748436) (xy 124.321855 -337.78548) (xy 124.27542 -337.816102) (xy 124.225029 -337.839652)
			(xy 124.171752 -337.85563) (xy 124.116717 -337.863699) (xy 124.088906 -337.864196) (xy 124.061653 -337.863739)
			(xy 124.007701 -337.855983) (xy 123.955402 -337.840627) (xy 123.905821 -337.817984) (xy 123.859968 -337.788516)
			(xy 123.818775 -337.752821) (xy 123.783081 -337.711628) (xy 123.753613 -337.665773) (xy 123.730971 -337.616192)
			(xy 123.715616 -337.563893) (xy 123.707861 -337.509941) (xy 123.707398 -337.482688) (xy 121.586832 -337.482688)
			(xy 121.585244 -337.492733) (xy 121.576592 -337.521296) (xy 121.572631 -337.535223) (xy 121.571708 -337.564145)
			(xy 121.578958 -337.592158) (xy 121.593796 -337.617001) (xy 121.615023 -337.636665) (xy 121.640926 -337.649564)
			(xy 121.655078 -337.652614) (xy 121.681143 -337.657824) (xy 121.731646 -337.674388) (xy 121.779359 -337.697805)
			(xy 121.823358 -337.727622) (xy 121.86279 -337.76326) (xy 121.89689 -337.804029) (xy 121.924998 -337.849138)
			(xy 121.94657 -337.897714) (xy 121.961186 -337.948815) (xy 121.968563 -338.001451) (xy 121.969022 -338.028026)
			(xy 121.967752 -338.059014) (xy 121.96572 -338.082636) (xy 122.507756 -338.624672) (xy 122.523313 -338.64092)
			(xy 122.548314 -338.678311) (xy 122.565532 -338.719865) (xy 122.574302 -338.76398) (xy 122.574812 -338.78647)
			(xy 122.574812 -339.66023) (xy 122.574229 -339.682711) (xy 122.565443 -339.726808) (xy 122.548233 -339.768347)
			(xy 122.523258 -339.805737) (xy 122.507756 -339.822028) (xy 121.792746 -340.537038) (xy 121.77649 -340.552604)
			(xy 121.739121 -340.577677) (xy 121.697573 -340.594967) (xy 121.653448 -340.603806) (xy 121.630948 -340.604348)
			(xy 119.892064 -340.604348) (xy 118.84787 -341.648542) (xy 127.281178 -341.648542) (xy 127.281772 -341.618856)
			(xy 127.290964 -341.560199) (xy 127.309132 -341.503674) (xy 127.335838 -341.450647) (xy 127.370437 -341.402397)
			(xy 127.412093 -341.360089) (xy 127.43561 -341.341964) (xy 127.446187 -341.333503) (xy 127.462893 -341.312198)
			(xy 127.473413 -341.287252) (xy 127.477007 -341.260418) (xy 127.473423 -341.233583) (xy 127.462912 -341.208633)
			(xy 127.446213 -341.187322) (xy 127.43561 -341.178896) (xy 127.4121 -341.16076) (xy 127.370439 -341.118456)
			(xy 127.335834 -341.07021) (xy 127.309121 -341.017184) (xy 127.290945 -340.960661) (xy 127.281744 -340.902005)
			(xy 127.281178 -340.872318) (xy 127.281664 -340.845067) (xy 127.28942 -340.791119) (xy 127.304775 -340.738824)
			(xy 127.327417 -340.689247) (xy 127.356883 -340.643397) (xy 127.392574 -340.602206) (xy 127.433765 -340.566515)
			(xy 127.479615 -340.537049) (xy 127.529192 -340.514407) (xy 127.581487 -340.499052) (xy 127.635435 -340.491296)
			(xy 127.689937 -340.491296) (xy 127.743885 -340.499052) (xy 127.79618 -340.514407) (xy 127.845757 -340.537049)
			(xy 127.891607 -340.566515) (xy 127.932798 -340.602206) (xy 127.968489 -340.643397) (xy 127.997955 -340.689247)
			(xy 128.020597 -340.738824) (xy 128.035952 -340.791119) (xy 128.043708 -340.845067) (xy 128.044194 -340.872318)
			(xy 128.043654 -340.902007) (xy 128.034453 -340.960667) (xy 128.016274 -341.017193) (xy 127.989558 -341.07022)
			(xy 127.95495 -341.118469) (xy 127.913284 -341.160773) (xy 127.889762 -341.178896) (xy 127.879128 -341.187289)
			(xy 127.862426 -341.208611) (xy 127.851913 -341.233572) (xy 127.848327 -341.260418) (xy 127.851922 -341.287263)
			(xy 127.862444 -341.31222) (xy 127.879153 -341.333536) (xy 127.889762 -341.341964) (xy 127.913247 -341.360131)
			(xy 127.954911 -341.402427) (xy 127.989519 -341.450668) (xy 128.016237 -341.503687) (xy 128.034418 -341.560205)
			(xy 128.043625 -341.618857) (xy 128.044194 -341.648542) (xy 128.043708 -341.675793) (xy 128.035952 -341.729741)
			(xy 128.020597 -341.782036) (xy 127.997955 -341.831613) (xy 127.968489 -341.877463) (xy 127.932798 -341.918654)
			(xy 127.891607 -341.954345) (xy 127.845757 -341.983811) (xy 127.79618 -342.006453) (xy 127.743885 -342.021808)
			(xy 127.689937 -342.029564) (xy 127.635435 -342.029564) (xy 127.581487 -342.021808) (xy 127.529192 -342.006453)
			(xy 127.479615 -341.983811) (xy 127.433765 -341.954345) (xy 127.392574 -341.918654) (xy 127.356883 -341.877463)
			(xy 127.327417 -341.831613) (xy 127.304775 -341.782036) (xy 127.28942 -341.729741) (xy 127.281664 -341.675793)
			(xy 127.281178 -341.648542) (xy 118.84787 -341.648542) (xy 117.902228 -342.594184) (xy 117.902228 -343.948696)
			(xy 119.176796 -343.948696) (xy 119.176796 -343.864) (xy 119.184847 -343.779686) (xy 119.200876 -343.69652)
			(xy 119.224737 -343.615253) (xy 119.256216 -343.536623) (xy 119.295027 -343.461342) (xy 119.340817 -343.39009)
			(xy 119.393173 -343.323514) (xy 119.451621 -343.262216) (xy 119.515631 -343.206751) (xy 119.584623 -343.157622)
			(xy 119.657973 -343.115273) (xy 119.735016 -343.080089) (xy 119.815055 -343.052387) (xy 119.897364 -343.032419)
			(xy 119.981199 -343.020366) (xy 120.0658 -343.016336) (xy 120.150401 -343.020366) (xy 120.234236 -343.032419)
			(xy 120.316545 -343.052387) (xy 120.396584 -343.080089) (xy 120.473627 -343.115273) (xy 120.546977 -343.157622)
			(xy 120.615969 -343.206751) (xy 120.679979 -343.262216) (xy 120.738427 -343.323514) (xy 120.790783 -343.39009)
			(xy 120.836573 -343.461342) (xy 120.875384 -343.536623) (xy 120.906863 -343.615253) (xy 120.930724 -343.69652)
			(xy 120.946753 -343.779686) (xy 120.954804 -343.864) (xy 120.955308 -343.906348) (xy 121.701309 -343.906348)
			(xy 121.705345 -343.822901) (xy 121.717417 -343.740233) (xy 121.73741 -343.659116) (xy 121.765139 -343.580307)
			(xy 121.800345 -343.504542) (xy 121.842699 -343.432529) (xy 121.891805 -343.36494) (xy 121.947206 -343.302406)
			(xy 122.008383 -343.245511) (xy 122.074766 -343.194785) (xy 122.145734 -343.150704) (xy 122.220626 -343.113678)
			(xy 122.298742 -343.084052) (xy 122.379352 -343.062104) (xy 122.461704 -343.048039) (xy 122.54503 -343.041987)
			(xy 122.62855 -343.044006) (xy 122.711486 -343.054076) (xy 122.793062 -343.072104) (xy 122.872518 -343.097921)
			(xy 122.949111 -343.131286) (xy 123.022127 -343.171887) (xy 123.090883 -343.219346) (xy 123.154737 -343.273219)
			(xy 123.213094 -343.333004) (xy 123.265409 -343.398141) (xy 123.311192 -343.468024) (xy 123.350017 -343.541999)
			(xy 123.381522 -343.619376) (xy 123.405411 -343.699433) (xy 123.421462 -343.781421) (xy 123.429525 -343.864576)
			(xy 123.43003 -343.906348) (xy 123.429525 -343.94812) (xy 123.421462 -344.031275) (xy 123.405411 -344.113263)
			(xy 123.381522 -344.19332) (xy 123.350017 -344.270697) (xy 123.311192 -344.344672) (xy 123.265409 -344.414555)
			(xy 123.213094 -344.479692) (xy 123.154737 -344.539477) (xy 123.090883 -344.59335) (xy 123.022127 -344.640809)
			(xy 122.949111 -344.68141) (xy 122.872518 -344.714775) (xy 122.793062 -344.740592) (xy 122.711486 -344.75862)
			(xy 122.62855 -344.76869) (xy 122.54503 -344.770709) (xy 122.461704 -344.764657) (xy 122.379352 -344.750592)
			(xy 122.298742 -344.728644) (xy 122.220626 -344.699018) (xy 122.145734 -344.661992) (xy 122.074766 -344.617911)
			(xy 122.008383 -344.567185) (xy 121.947206 -344.51029) (xy 121.891805 -344.447756) (xy 121.842699 -344.380167)
			(xy 121.800345 -344.308154) (xy 121.765139 -344.232389) (xy 121.73741 -344.15358) (xy 121.717417 -344.072463)
			(xy 121.705345 -343.989795) (xy 121.701309 -343.906348) (xy 120.955308 -343.906348) (xy 120.954804 -343.948696)
			(xy 120.946753 -344.03301) (xy 120.930724 -344.116176) (xy 120.906863 -344.197443) (xy 120.875384 -344.276073)
			(xy 120.836573 -344.351354) (xy 120.790783 -344.422606) (xy 120.738427 -344.489182) (xy 120.679979 -344.55048)
			(xy 120.615969 -344.605945) (xy 120.546977 -344.655074) (xy 120.473627 -344.697423) (xy 120.396584 -344.732607)
			(xy 120.316545 -344.760309) (xy 120.234236 -344.780277) (xy 120.150401 -344.79233) (xy 120.0658 -344.796361)
			(xy 119.981199 -344.79233) (xy 119.897364 -344.780277) (xy 119.815055 -344.760309) (xy 119.735016 -344.732607)
			(xy 119.657973 -344.697423) (xy 119.584623 -344.655074) (xy 119.515631 -344.605945) (xy 119.451621 -344.55048)
			(xy 119.393173 -344.489182) (xy 119.340817 -344.422606) (xy 119.295027 -344.351354) (xy 119.256216 -344.276073)
			(xy 119.224737 -344.197443) (xy 119.200876 -344.116176) (xy 119.184847 -344.03301) (xy 119.176796 -343.948696)
			(xy 117.902228 -343.948696) (xy 117.902228 -344.594434) (xy 117.901674 -344.616931) (xy 117.892815 -344.661046)
			(xy 117.875524 -344.702587) (xy 117.850463 -344.739959) (xy 117.834918 -344.756232) (xy 112.122204 -350.468946)
			(xy 112.105967 -350.484534) (xy 112.068591 -350.509602) (xy 112.027037 -350.526886) (xy 111.982908 -350.535718)
			(xy 111.960406 -350.536256) (xy 110.914942 -350.536256) (xy 110.396528 -351.05467) (xy 110.396528 -351.457768)
			(xy 111.131602 -351.457768) (xy 111.135673 -351.402146) (xy 111.147799 -351.347709) (xy 111.167722 -351.295618)
			(xy 111.195018 -351.246983) (xy 111.229104 -351.20284) (xy 111.269253 -351.164131) (xy 111.314611 -351.13168)
			(xy 111.364211 -351.106179) (xy 111.416995 -351.088172) (xy 111.471838 -351.078042) (xy 111.527572 -351.076005)
			(xy 111.583009 -351.082105) (xy 111.636966 -351.096211) (xy 111.688295 -351.118023) (xy 111.735901 -351.147077)
			(xy 111.778769 -351.182752) (xy 111.815986 -351.224289) (xy 111.846759 -351.270802) (xy 111.870431 -351.321299)
			(xy 111.886499 -351.374706) (xy 111.894619 -351.429882) (xy 111.895128 -351.457768) (xy 111.894619 -351.485654)
			(xy 111.886499 -351.54083) (xy 111.870431 -351.594237) (xy 111.846759 -351.644734) (xy 111.815986 -351.691247)
			(xy 111.778769 -351.732784) (xy 111.735901 -351.768459) (xy 111.688295 -351.797513) (xy 111.636966 -351.819325)
			(xy 111.583009 -351.833431) (xy 111.527572 -351.839531) (xy 111.471838 -351.837494) (xy 111.416995 -351.827364)
			(xy 111.364211 -351.809357) (xy 111.314611 -351.783856) (xy 111.269253 -351.751405) (xy 111.229104 -351.712696)
			(xy 111.195018 -351.668553) (xy 111.167722 -351.619918) (xy 111.147799 -351.567827) (xy 111.135673 -351.51339)
			(xy 111.131602 -351.457768) (xy 110.396528 -351.457768) (xy 110.396528 -351.947734) (xy 110.395974 -351.970231)
			(xy 110.387115 -352.014346) (xy 110.369824 -352.055887) (xy 110.344763 -352.093259) (xy 110.329218 -352.109532)
			(xy 110.04257 -352.396298) (xy 110.560102 -352.396298) (xy 110.564173 -352.340676) (xy 110.576299 -352.286239)
			(xy 110.596222 -352.234148) (xy 110.623518 -352.185513) (xy 110.657604 -352.14137) (xy 110.697753 -352.102661)
			(xy 110.743111 -352.07021) (xy 110.792711 -352.044709) (xy 110.845495 -352.026702) (xy 110.900338 -352.016572)
			(xy 110.956072 -352.014535) (xy 111.011509 -352.020635) (xy 111.065466 -352.034741) (xy 111.116795 -352.056553)
			(xy 111.164401 -352.085607) (xy 111.207269 -352.121282) (xy 111.244486 -352.162819) (xy 111.275259 -352.209332)
			(xy 111.298931 -352.259829) (xy 111.314999 -352.313236) (xy 111.323119 -352.368412) (xy 111.323628 -352.396298)
			(xy 111.323119 -352.424184) (xy 111.314999 -352.47936) (xy 111.298931 -352.532767) (xy 111.275259 -352.583264)
			(xy 111.244486 -352.629777) (xy 111.207269 -352.671314) (xy 111.164401 -352.706989) (xy 111.116795 -352.736043)
			(xy 111.065466 -352.757855) (xy 111.011509 -352.771961) (xy 110.956072 -352.778061) (xy 110.900338 -352.776024)
			(xy 110.845495 -352.765894) (xy 110.792711 -352.747887) (xy 110.743111 -352.722386) (xy 110.697753 -352.689935)
			(xy 110.657604 -352.651226) (xy 110.623518 -352.607083) (xy 110.596222 -352.558448) (xy 110.576299 -352.506357)
			(xy 110.564173 -352.45192) (xy 110.560102 -352.396298) (xy 110.04257 -352.396298) (xy 109.71276 -352.726244)
			(xy 109.71276 -352.832924) (xy 112.35385 -352.832924) (xy 112.357921 -352.777302) (xy 112.370047 -352.722865)
			(xy 112.38997 -352.670774) (xy 112.417266 -352.622139) (xy 112.451352 -352.577996) (xy 112.491501 -352.539287)
			(xy 112.536859 -352.506836) (xy 112.586459 -352.481335) (xy 112.639243 -352.463328) (xy 112.694086 -352.453198)
			(xy 112.74982 -352.451161) (xy 112.805257 -352.457261) (xy 112.859214 -352.471367) (xy 112.910543 -352.493179)
			(xy 112.958149 -352.522233) (xy 113.001017 -352.557908) (xy 113.038234 -352.599445) (xy 113.069007 -352.645958)
			(xy 113.092679 -352.696455) (xy 113.108747 -352.749862) (xy 113.116867 -352.805038) (xy 113.117376 -352.832924)
			(xy 113.116867 -352.86081) (xy 113.108747 -352.915986) (xy 113.092679 -352.969393) (xy 113.069007 -353.01989)
			(xy 113.038234 -353.066403) (xy 113.001017 -353.10794) (xy 112.958149 -353.143615) (xy 112.910543 -353.172669)
			(xy 112.859214 -353.194481) (xy 112.805257 -353.208587) (xy 112.74982 -353.214687) (xy 112.694086 -353.21265)
			(xy 112.639243 -353.20252) (xy 112.586459 -353.184513) (xy 112.536859 -353.159012) (xy 112.491501 -353.126561)
			(xy 112.451352 -353.087852) (xy 112.417266 -353.043709) (xy 112.38997 -352.995074) (xy 112.370047 -352.942983)
			(xy 112.357921 -352.888546) (xy 112.35385 -352.832924) (xy 109.71276 -352.832924) (xy 109.71276 -353.488498)
			(xy 110.4806 -353.488498) (xy 110.484671 -353.432876) (xy 110.496797 -353.378439) (xy 110.51672 -353.326348)
			(xy 110.544016 -353.277713) (xy 110.578102 -353.23357) (xy 110.618251 -353.194861) (xy 110.663609 -353.16241)
			(xy 110.713209 -353.136909) (xy 110.765993 -353.118902) (xy 110.820836 -353.108772) (xy 110.87657 -353.106735)
			(xy 110.932007 -353.112835) (xy 110.985964 -353.126941) (xy 111.037293 -353.148753) (xy 111.084899 -353.177807)
			(xy 111.127767 -353.213482) (xy 111.164984 -353.255019) (xy 111.195757 -353.301532) (xy 111.219429 -353.352029)
			(xy 111.235497 -353.405436) (xy 111.243617 -353.460612) (xy 111.244126 -353.488498) (xy 111.243617 -353.516384)
			(xy 111.241179 -353.532948) (xy 113.415062 -353.532948) (xy 113.419133 -353.477326) (xy 113.431259 -353.422889)
			(xy 113.451182 -353.370798) (xy 113.478478 -353.322163) (xy 113.512564 -353.27802) (xy 113.552713 -353.239311)
			(xy 113.598071 -353.20686) (xy 113.647671 -353.181359) (xy 113.700455 -353.163352) (xy 113.755298 -353.153222)
			(xy 113.811032 -353.151185) (xy 113.866469 -353.157285) (xy 113.920426 -353.171391) (xy 113.971755 -353.193203)
			(xy 114.019361 -353.222257) (xy 114.062229 -353.257932) (xy 114.099446 -353.299469) (xy 114.130219 -353.345982)
			(xy 114.153891 -353.396479) (xy 114.169959 -353.449886) (xy 114.178079 -353.505062) (xy 114.178588 -353.532948)
			(xy 114.178079 -353.560834) (xy 114.169959 -353.61601) (xy 114.153891 -353.669417) (xy 114.130219 -353.719914)
			(xy 114.099446 -353.766427) (xy 114.062229 -353.807964) (xy 114.019361 -353.843639) (xy 113.971755 -353.872693)
			(xy 113.920426 -353.894505) (xy 113.866469 -353.908611) (xy 113.811032 -353.914711) (xy 113.755298 -353.912674)
			(xy 113.700455 -353.902544) (xy 113.647671 -353.884537) (xy 113.598071 -353.859036) (xy 113.552713 -353.826585)
			(xy 113.512564 -353.787876) (xy 113.478478 -353.743733) (xy 113.451182 -353.695098) (xy 113.431259 -353.643007)
			(xy 113.419133 -353.58857) (xy 113.415062 -353.532948) (xy 111.241179 -353.532948) (xy 111.235497 -353.57156)
			(xy 111.219429 -353.624967) (xy 111.195757 -353.675464) (xy 111.164984 -353.721977) (xy 111.127767 -353.763514)
			(xy 111.084899 -353.799189) (xy 111.037293 -353.828243) (xy 110.985964 -353.850055) (xy 110.932007 -353.864161)
			(xy 110.87657 -353.870261) (xy 110.820836 -353.868224) (xy 110.765993 -353.858094) (xy 110.713209 -353.840087)
			(xy 110.663609 -353.814586) (xy 110.618251 -353.782135) (xy 110.578102 -353.743426) (xy 110.544016 -353.699283)
			(xy 110.51672 -353.650648) (xy 110.496797 -353.598557) (xy 110.484671 -353.54412) (xy 110.4806 -353.488498)
			(xy 109.71276 -353.488498) (xy 109.71276 -354.14204) (xy 111.725708 -354.14204) (xy 111.729779 -354.086418)
			(xy 111.741905 -354.031981) (xy 111.761828 -353.97989) (xy 111.789124 -353.931255) (xy 111.82321 -353.887112)
			(xy 111.863359 -353.848403) (xy 111.908717 -353.815952) (xy 111.958317 -353.790451) (xy 112.011101 -353.772444)
			(xy 112.065944 -353.762314) (xy 112.121678 -353.760277) (xy 112.177115 -353.766377) (xy 112.231072 -353.780483)
			(xy 112.282401 -353.802295) (xy 112.330007 -353.831349) (xy 112.372875 -353.867024) (xy 112.410092 -353.908561)
			(xy 112.440865 -353.955074) (xy 112.464537 -354.005571) (xy 112.480605 -354.058978) (xy 112.488725 -354.114154)
			(xy 112.489234 -354.14204) (xy 112.488725 -354.169926) (xy 112.480605 -354.225102) (xy 112.464537 -354.278509)
			(xy 112.440865 -354.329006) (xy 112.410092 -354.375519) (xy 112.372875 -354.417056) (xy 112.330007 -354.452731)
			(xy 112.282401 -354.481785) (xy 112.231072 -354.503597) (xy 112.177115 -354.517703) (xy 112.121678 -354.523803)
			(xy 112.065944 -354.521766) (xy 112.011101 -354.511636) (xy 111.958317 -354.493629) (xy 111.908717 -354.468128)
			(xy 111.863359 -354.435677) (xy 111.82321 -354.396968) (xy 111.789124 -354.352825) (xy 111.761828 -354.30419)
			(xy 111.741905 -354.252099) (xy 111.729779 -354.197662) (xy 111.725708 -354.14204) (xy 109.71276 -354.14204)
			(xy 109.71276 -355.159564) (xy 111.223296 -355.159564) (xy 111.227367 -355.103942) (xy 111.239493 -355.049505)
			(xy 111.259416 -354.997414) (xy 111.286712 -354.948779) (xy 111.320798 -354.904636) (xy 111.360947 -354.865927)
			(xy 111.406305 -354.833476) (xy 111.455905 -354.807975) (xy 111.508689 -354.789968) (xy 111.563532 -354.779838)
			(xy 111.619266 -354.777801) (xy 111.674703 -354.783901) (xy 111.72866 -354.798007) (xy 111.779989 -354.819819)
			(xy 111.827595 -354.848873) (xy 111.870463 -354.884548) (xy 111.90768 -354.926085) (xy 111.938453 -354.972598)
			(xy 111.962125 -355.023095) (xy 111.972845 -355.058726) (xy 112.247678 -355.058726) (xy 112.251749 -355.003104)
			(xy 112.263875 -354.948667) (xy 112.283798 -354.896576) (xy 112.311094 -354.847941) (xy 112.34518 -354.803798)
			(xy 112.385329 -354.765089) (xy 112.430687 -354.732638) (xy 112.480287 -354.707137) (xy 112.533071 -354.68913)
			(xy 112.587914 -354.679) (xy 112.643648 -354.676963) (xy 112.699085 -354.683063) (xy 112.753042 -354.697169)
			(xy 112.804371 -354.718981) (xy 112.851977 -354.748035) (xy 112.894845 -354.78371) (xy 112.900703 -354.790248)
			(xy 113.438938 -354.790248) (xy 113.443009 -354.734626) (xy 113.455135 -354.680189) (xy 113.475058 -354.628098)
			(xy 113.502354 -354.579463) (xy 113.53644 -354.53532) (xy 113.576589 -354.496611) (xy 113.621947 -354.46416)
			(xy 113.671547 -354.438659) (xy 113.724331 -354.420652) (xy 113.779174 -354.410522) (xy 113.834908 -354.408485)
			(xy 113.890345 -354.414585) (xy 113.944302 -354.428691) (xy 113.995631 -354.450503) (xy 114.043237 -354.479557)
			(xy 114.086105 -354.515232) (xy 114.123322 -354.556769) (xy 114.154095 -354.603282) (xy 114.177767 -354.653779)
			(xy 114.193835 -354.707186) (xy 114.201955 -354.762362) (xy 114.202464 -354.790248) (xy 114.201955 -354.818134)
			(xy 114.193835 -354.87331) (xy 114.177767 -354.926717) (xy 114.154095 -354.977214) (xy 114.123322 -355.023727)
			(xy 114.086105 -355.065264) (xy 114.043237 -355.100939) (xy 113.995631 -355.129993) (xy 113.944302 -355.151805)
			(xy 113.890345 -355.165911) (xy 113.834908 -355.172011) (xy 113.779174 -355.169974) (xy 113.724331 -355.159844)
			(xy 113.671547 -355.141837) (xy 113.621947 -355.116336) (xy 113.576589 -355.083885) (xy 113.53644 -355.045176)
			(xy 113.502354 -355.001033) (xy 113.475058 -354.952398) (xy 113.455135 -354.900307) (xy 113.443009 -354.84587)
			(xy 113.438938 -354.790248) (xy 112.900703 -354.790248) (xy 112.932062 -354.825247) (xy 112.962835 -354.87176)
			(xy 112.986507 -354.922257) (xy 113.002575 -354.975664) (xy 113.010695 -355.03084) (xy 113.011204 -355.058726)
			(xy 113.010695 -355.086612) (xy 113.002575 -355.141788) (xy 112.986507 -355.195195) (xy 112.962835 -355.245692)
			(xy 112.932062 -355.292205) (xy 112.894845 -355.333742) (xy 112.851977 -355.369417) (xy 112.804371 -355.398471)
			(xy 112.753042 -355.420283) (xy 112.699085 -355.434389) (xy 112.643648 -355.440489) (xy 112.587914 -355.438452)
			(xy 112.533071 -355.428322) (xy 112.480287 -355.410315) (xy 112.430687 -355.384814) (xy 112.385329 -355.352363)
			(xy 112.34518 -355.313654) (xy 112.311094 -355.269511) (xy 112.283798 -355.220876) (xy 112.263875 -355.168785)
			(xy 112.251749 -355.114348) (xy 112.247678 -355.058726) (xy 111.972845 -355.058726) (xy 111.978193 -355.076502)
			(xy 111.986313 -355.131678) (xy 111.986822 -355.159564) (xy 111.986313 -355.18745) (xy 111.978193 -355.242626)
			(xy 111.962125 -355.296033) (xy 111.938453 -355.34653) (xy 111.90768 -355.393043) (xy 111.870463 -355.43458)
			(xy 111.827595 -355.470255) (xy 111.779989 -355.499309) (xy 111.72866 -355.521121) (xy 111.674703 -355.535227)
			(xy 111.619266 -355.541327) (xy 111.563532 -355.53929) (xy 111.508689 -355.52916) (xy 111.455905 -355.511153)
			(xy 111.406305 -355.485652) (xy 111.360947 -355.453201) (xy 111.320798 -355.414492) (xy 111.286712 -355.370349)
			(xy 111.259416 -355.321714) (xy 111.239493 -355.269623) (xy 111.227367 -355.215186) (xy 111.223296 -355.159564)
			(xy 109.71276 -355.159564) (xy 109.71276 -356.150926) (xy 110.986314 -356.150926) (xy 110.990385 -356.095304)
			(xy 111.002511 -356.040867) (xy 111.022434 -355.988776) (xy 111.04973 -355.940141) (xy 111.083816 -355.895998)
			(xy 111.123965 -355.857289) (xy 111.169323 -355.824838) (xy 111.218923 -355.799337) (xy 111.271707 -355.78133)
			(xy 111.32655 -355.7712) (xy 111.382284 -355.769163) (xy 111.437721 -355.775263) (xy 111.491678 -355.789369)
			(xy 111.543007 -355.811181) (xy 111.590613 -355.840235) (xy 111.633481 -355.87591) (xy 111.670698 -355.917447)
			(xy 111.701471 -355.96396) (xy 111.725143 -356.014457) (xy 111.741211 -356.067864) (xy 111.749331 -356.12304)
			(xy 111.74984 -356.150926) (xy 111.749331 -356.178812) (xy 111.741211 -356.233988) (xy 111.725143 -356.287395)
			(xy 111.701471 -356.337892) (xy 111.670698 -356.384405) (xy 111.633481 -356.425942) (xy 111.590613 -356.461617)
			(xy 111.543007 -356.490671) (xy 111.491678 -356.512483) (xy 111.437721 -356.526589) (xy 111.382284 -356.532689)
			(xy 111.32655 -356.530652) (xy 111.271707 -356.520522) (xy 111.218923 -356.502515) (xy 111.169323 -356.477014)
			(xy 111.123965 -356.444563) (xy 111.083816 -356.405854) (xy 111.04973 -356.361711) (xy 111.022434 -356.313076)
			(xy 111.002511 -356.260985) (xy 110.990385 -356.206548) (xy 110.986314 -356.150926) (xy 109.71276 -356.150926)
			(xy 109.71276 -361.018836) (xy 109.712198 -361.041332) (xy 109.70334 -361.085447) (xy 109.686051 -361.126988)
			(xy 109.660993 -361.16436) (xy 109.64545 -361.180634) (xy 107.744768 -363.08157) (xy 107.744768 -363.498892)
			(xy 107.744177 -363.521387) (xy 107.735328 -363.5655) (xy 107.718047 -363.607041) (xy 107.692997 -363.644414)
			(xy 107.677458 -363.66069) (xy 107.000911 -364.337453) (xy 107.576523 -364.337453) (xy 107.576523 -364.282941)
			(xy 107.584282 -364.228984) (xy 107.59964 -364.176681) (xy 107.622286 -364.127095) (xy 107.651759 -364.081238)
			(xy 107.687458 -364.040041) (xy 107.728656 -364.004345) (xy 107.774515 -363.974875) (xy 107.824102 -363.952232)
			(xy 107.876407 -363.936877) (xy 107.930364 -363.929122) (xy 107.95762 -363.92866) (xy 107.988608 -363.92993)
			(xy 108.01223 -363.931962) (xy 111.22152 -360.722672) (xy 111.22152 -357.462074) (xy 111.222096 -357.439592)
			(xy 111.230883 -357.395495) (xy 111.248095 -357.353955) (xy 111.273072 -357.316566) (xy 111.288576 -357.300276)
			(xy 113.046002 -355.54285) (xy 113.062236 -355.527259) (xy 113.099613 -355.502191) (xy 113.141168 -355.484908)
			(xy 113.185298 -355.476077) (xy 113.2078 -355.47554) (xy 114.119152 -355.47554) (xy 114.464592 -355.1301)
			(xy 114.464592 -349.836994) (xy 114.465186 -349.814499) (xy 114.474036 -349.770387) (xy 114.491316 -349.728847)
			(xy 114.516364 -349.691472) (xy 114.531902 -349.675196) (xy 116.94922 -347.257878) (xy 116.96545 -347.242283)
			(xy 117.002828 -347.217215) (xy 117.044384 -347.199933) (xy 117.088515 -347.191104) (xy 117.111018 -347.190568)
			(xy 123.369324 -347.190568) (xy 126.990094 -343.570052) (xy 127.006334 -343.554486) (xy 127.043728 -343.529486)
			(xy 127.085284 -343.512271) (xy 127.129401 -343.503504) (xy 127.151892 -343.502996) (xy 129.972816 -343.502996)
			(xy 130.410204 -343.065608) (xy 130.410204 -342.424004) (xy 129.802636 -341.816436) (xy 129.779014 -341.818468)
			(xy 129.748026 -341.819738) (xy 129.720777 -341.819198) (xy 129.666833 -341.811445) (xy 129.614541 -341.796095)
			(xy 129.564966 -341.773459) (xy 129.519117 -341.743999) (xy 129.477927 -341.708313) (xy 129.442235 -341.667128)
			(xy 129.412768 -341.621284) (xy 129.390124 -341.571712) (xy 129.374766 -341.519422) (xy 129.367006 -341.465479)
			(xy 129.366518 -341.43823) (xy 129.366518 -341.437976) (xy 129.367094 -341.408137) (xy 129.376409 -341.349191)
			(xy 129.38506 -341.320628) (xy 129.389144 -341.306731) (xy 129.390052 -341.27779) (xy 129.382781 -341.249762)
			(xy 129.367918 -341.224911) (xy 129.346665 -341.205246) (xy 129.320738 -341.192354) (xy 129.306574 -341.18931)
			(xy 129.273733 -341.182734) (xy 129.210882 -341.159606) (xy 129.181606 -341.143336) (xy 129.168622 -341.136337)
			(xy 129.139993 -341.1293) (xy 129.110547 -341.130739) (xy 129.082741 -341.140534) (xy 129.058894 -341.157867)
			(xy 129.040995 -341.181292) (xy 129.035302 -341.194898) (xy 129.02462 -341.22168) (xy 128.996331 -341.271923)
			(xy 128.9608 -341.317334) (xy 128.918836 -341.356877) (xy 128.871397 -341.38965) (xy 128.819563 -341.414906)
			(xy 128.764518 -341.43207) (xy 128.707516 -341.44075) (xy 128.678686 -341.441278) (xy 128.651433 -341.440851)
			(xy 128.597483 -341.433092) (xy 128.545186 -341.417735) (xy 128.495606 -341.395091) (xy 128.449754 -341.365622)
			(xy 128.408562 -341.329928) (xy 128.372869 -341.288735) (xy 128.343402 -341.242881) (xy 128.32076 -341.193301)
			(xy 128.305405 -341.141003) (xy 128.297648 -341.087053) (xy 128.297648 -341.032547) (xy 128.305405 -340.978597)
			(xy 128.32076 -340.926299) (xy 128.343402 -340.876719) (xy 128.372869 -340.830865) (xy 128.408562 -340.789672)
			(xy 128.449754 -340.753978) (xy 128.495606 -340.724509) (xy 128.545186 -340.701865) (xy 128.597483 -340.686508)
			(xy 128.651433 -340.678749) (xy 128.678686 -340.678262) (xy 128.67894 -340.678262) (xy 128.704144 -340.678641)
			(xy 128.754113 -340.685286) (xy 128.802768 -340.698469) (xy 128.849257 -340.717957) (xy 128.871218 -340.730332)
			(xy 128.88418 -340.737377) (xy 128.912819 -340.744413) (xy 128.942273 -340.742969) (xy 128.970086 -340.733165)
			(xy 128.993936 -340.715821) (xy 129.011832 -340.692382) (xy 129.017522 -340.67877) (xy 129.02825 -340.652008)
			(xy 129.056536 -340.601769) (xy 129.092062 -340.556361) (xy 129.134019 -340.516818) (xy 129.181451 -340.484043)
			(xy 129.233277 -340.458783) (xy 129.288315 -340.441612) (xy 129.345311 -340.432923) (xy 129.374138 -340.43239)
			(xy 129.40139 -340.432842) (xy 129.455339 -340.440604) (xy 129.507634 -340.455964) (xy 129.557211 -340.478609)
			(xy 129.603061 -340.508079) (xy 129.644251 -340.543774) (xy 129.679942 -340.584967) (xy 129.709408 -340.63082)
			(xy 129.732049 -340.6804) (xy 129.747404 -340.732696) (xy 129.75516 -340.786646) (xy 129.755646 -340.813898)
			(xy 129.755646 -340.814152) (xy 129.755074 -340.843991) (xy 129.745756 -340.902937) (xy 129.737104 -340.9315)
			(xy 129.733129 -340.945424) (xy 129.732206 -340.974348) (xy 129.739458 -341.002364) (xy 129.754299 -341.027207)
			(xy 129.77553 -341.046872) (xy 129.801436 -341.05977) (xy 129.81559 -341.062818) (xy 129.841657 -341.068015)
			(xy 129.892161 -341.084581) (xy 129.939874 -341.108) (xy 129.983873 -341.137818) (xy 130.023305 -341.173458)
			(xy 130.057405 -341.214228) (xy 130.085512 -341.259339) (xy 130.107083 -341.307916) (xy 130.121698 -341.359018)
			(xy 130.129076 -341.411654) (xy 130.129534 -341.43823) (xy 130.128264 -341.469218) (xy 130.126232 -341.49284)
			(xy 130.800856 -342.167464) (xy 130.816409 -342.183716) (xy 130.841411 -342.221105) (xy 130.85863 -342.262658)
			(xy 130.867402 -342.306773) (xy 130.867912 -342.329262) (xy 130.867912 -343.16035) (xy 130.867342 -343.182832)
			(xy 130.858552 -343.226929) (xy 130.841338 -343.268468) (xy 130.81636 -343.305857) (xy 130.800856 -343.322148)
			(xy 130.229356 -343.893648) (xy 130.213094 -343.90919) (xy 130.175708 -343.934195) (xy 130.134159 -343.951416)
			(xy 130.090047 -343.960192) (xy 130.067558 -343.960704) (xy 127.246634 -343.960704) (xy 126.830074 -344.377264)
			(xy 133.84403 -344.377264) (xy 133.844468 -344.349893) (xy 133.852291 -344.295712) (xy 133.867787 -344.243208)
			(xy 133.890635 -344.193462) (xy 133.920366 -344.147497) (xy 133.93801 -344.126566) (xy 133.947281 -344.115264)
			(xy 133.959453 -344.088697) (xy 133.963618 -344.059773) (xy 133.959437 -344.030851) (xy 133.947251 -344.00429)
			(xy 133.93801 -343.992962) (xy 133.920388 -343.972016) (xy 133.890673 -343.926047) (xy 133.867834 -343.876303)
			(xy 133.852339 -343.823806) (xy 133.844506 -343.769632) (xy 133.84403 -343.742264) (xy 133.844516 -343.715013)
			(xy 133.852272 -343.661065) (xy 133.867627 -343.60877) (xy 133.890269 -343.559193) (xy 133.919735 -343.513343)
			(xy 133.955426 -343.472152) (xy 133.996617 -343.436461) (xy 134.042467 -343.406995) (xy 134.092044 -343.384353)
			(xy 134.144339 -343.368998) (xy 134.198287 -343.361242) (xy 134.252789 -343.361242) (xy 134.306737 -343.368998)
			(xy 134.359032 -343.384353) (xy 134.408609 -343.406995) (xy 134.454459 -343.436461) (xy 134.49565 -343.472152)
			(xy 134.531341 -343.513343) (xy 134.560807 -343.559193) (xy 134.583449 -343.60877) (xy 134.598804 -343.661065)
			(xy 134.60656 -343.715013) (xy 134.607046 -343.742264) (xy 134.606572 -343.769634) (xy 134.598758 -343.823813)
			(xy 134.583272 -343.876317) (xy 134.560431 -343.926064) (xy 134.530707 -343.972031) (xy 134.513066 -343.992962)
			(xy 134.503867 -344.004316) (xy 134.491689 -344.030865) (xy 134.487511 -344.059773) (xy 134.491674 -344.088683)
			(xy 134.503837 -344.115238) (xy 134.513066 -344.126566) (xy 134.530697 -344.147504) (xy 134.560411 -344.193475)
			(xy 134.583249 -344.243221) (xy 134.598742 -344.29572) (xy 134.606572 -344.349895) (xy 134.607046 -344.377264)
			(xy 134.60656 -344.404515) (xy 134.598804 -344.458463) (xy 134.583449 -344.510758) (xy 134.560807 -344.560335)
			(xy 134.531341 -344.606185) (xy 134.49565 -344.647376) (xy 134.454459 -344.683067) (xy 134.408609 -344.712533)
			(xy 134.359032 -344.735175) (xy 134.306737 -344.75053) (xy 134.252789 -344.758286) (xy 134.198287 -344.758286)
			(xy 134.144339 -344.75053) (xy 134.092044 -344.735175) (xy 134.042467 -344.712533) (xy 133.996617 -344.683067)
			(xy 133.955426 -344.647376) (xy 133.919735 -344.606185) (xy 133.890269 -344.560335) (xy 133.867627 -344.510758)
			(xy 133.852272 -344.458463) (xy 133.844516 -344.404515) (xy 133.84403 -344.377264) (xy 126.830074 -344.377264)
			(xy 123.768104 -347.439234) (xy 135.44169 -347.439234) (xy 135.442274 -347.409547) (xy 135.451467 -347.35089)
			(xy 135.469637 -347.294364) (xy 135.496345 -347.241337) (xy 135.530946 -347.193087) (xy 135.572604 -347.150781)
			(xy 135.596122 -347.132656) (xy 135.606706 -347.124204) (xy 135.623411 -347.102896) (xy 135.633929 -347.077948)
			(xy 135.637521 -347.051113) (xy 135.633936 -347.024277) (xy 135.623424 -346.999326) (xy 135.606725 -346.978015)
			(xy 135.596122 -346.969588) (xy 135.572611 -346.951453) (xy 135.530949 -346.90915) (xy 135.496344 -346.860903)
			(xy 135.469631 -346.807878) (xy 135.451455 -346.751354) (xy 135.442256 -346.692697) (xy 135.44169 -346.66301)
			(xy 135.442176 -346.635759) (xy 135.449932 -346.581811) (xy 135.465287 -346.529516) (xy 135.487929 -346.479939)
			(xy 135.517395 -346.434089) (xy 135.553086 -346.392898) (xy 135.594277 -346.357207) (xy 135.640127 -346.327741)
			(xy 135.689704 -346.305099) (xy 135.741999 -346.289744) (xy 135.795947 -346.281988) (xy 135.850449 -346.281988)
			(xy 135.904397 -346.289744) (xy 135.956692 -346.305099) (xy 136.006269 -346.327741) (xy 136.052119 -346.357207)
			(xy 136.09331 -346.392898) (xy 136.129001 -346.434089) (xy 136.158467 -346.479939) (xy 136.181109 -346.529516)
			(xy 136.196464 -346.581811) (xy 136.20422 -346.635759) (xy 136.204706 -346.66301) (xy 136.204156 -346.692698)
			(xy 136.194956 -346.751357) (xy 136.176779 -346.807883) (xy 136.150065 -346.860911) (xy 136.115458 -346.909159)
			(xy 136.073795 -346.951464) (xy 136.050274 -346.969588) (xy 136.039646 -346.97799) (xy 136.022942 -346.999309)
			(xy 136.012428 -347.024268) (xy 136.008841 -347.051113) (xy 136.012435 -347.077957) (xy 136.022956 -347.102914)
			(xy 136.039665 -347.124229) (xy 136.050274 -347.132656) (xy 136.073806 -347.150766) (xy 136.115466 -347.193074)
			(xy 136.150069 -347.241326) (xy 136.176779 -347.294357) (xy 136.19495 -347.350885) (xy 136.204144 -347.409546)
			(xy 136.204706 -347.439234) (xy 136.20422 -347.466485) (xy 136.196464 -347.520433) (xy 136.181109 -347.572728)
			(xy 136.158467 -347.622305) (xy 136.129001 -347.668155) (xy 136.09331 -347.709346) (xy 136.052119 -347.745037)
			(xy 136.006269 -347.774503) (xy 135.956692 -347.797145) (xy 135.904397 -347.8125) (xy 135.850449 -347.820256)
			(xy 135.795947 -347.820256) (xy 135.741999 -347.8125) (xy 135.689704 -347.797145) (xy 135.640127 -347.774503)
			(xy 135.594277 -347.745037) (xy 135.553086 -347.709346) (xy 135.517395 -347.668155) (xy 135.487929 -347.622305)
			(xy 135.465287 -347.572728) (xy 135.449932 -347.520433) (xy 135.442176 -347.466485) (xy 135.44169 -347.439234)
			(xy 123.768104 -347.439234) (xy 123.625864 -347.581474) (xy 123.609633 -347.597068) (xy 123.572256 -347.622139)
			(xy 123.530701 -347.639422) (xy 123.486569 -347.64825) (xy 123.464066 -347.648784) (xy 117.20576 -347.648784)
			(xy 114.922808 -349.931736) (xy 114.922808 -350.476496) (xy 115.595396 -350.476496) (xy 115.595396 -350.3918)
			(xy 115.603447 -350.307486) (xy 115.619476 -350.22432) (xy 115.643337 -350.143053) (xy 115.674816 -350.064423)
			(xy 115.713627 -349.989142) (xy 115.759417 -349.91789) (xy 115.811773 -349.851314) (xy 115.870221 -349.790016)
			(xy 115.934231 -349.734551) (xy 116.003223 -349.685422) (xy 116.076573 -349.643073) (xy 116.153616 -349.607889)
			(xy 116.233655 -349.580187) (xy 116.315964 -349.560219) (xy 116.399799 -349.548166) (xy 116.4844 -349.544136)
			(xy 116.569001 -349.548166) (xy 116.652836 -349.560219) (xy 116.735145 -349.580187) (xy 116.815184 -349.607889)
			(xy 116.892227 -349.643073) (xy 116.965577 -349.685422) (xy 117.034569 -349.734551) (xy 117.098579 -349.790016)
			(xy 117.157027 -349.851314) (xy 117.209383 -349.91789) (xy 117.255173 -349.989142) (xy 117.293984 -350.064423)
			(xy 117.325463 -350.143053) (xy 117.349324 -350.22432) (xy 117.365353 -350.307486) (xy 117.373404 -350.3918)
			(xy 117.373908 -350.434148) (xy 118.119909 -350.434148) (xy 118.123945 -350.350701) (xy 118.136017 -350.268033)
			(xy 118.15601 -350.186916) (xy 118.183739 -350.108107) (xy 118.218945 -350.032342) (xy 118.261299 -349.960329)
			(xy 118.310405 -349.89274) (xy 118.365806 -349.830206) (xy 118.426983 -349.773311) (xy 118.493366 -349.722585)
			(xy 118.564334 -349.678504) (xy 118.639226 -349.641478) (xy 118.717342 -349.611852) (xy 118.797952 -349.589904)
			(xy 118.880304 -349.575839) (xy 118.96363 -349.569787) (xy 119.04715 -349.571806) (xy 119.130086 -349.581876)
			(xy 119.211662 -349.599904) (xy 119.291118 -349.625721) (xy 119.367711 -349.659086) (xy 119.440727 -349.699687)
			(xy 119.509483 -349.747146) (xy 119.573337 -349.801019) (xy 119.631694 -349.860804) (xy 119.684009 -349.925941)
			(xy 119.729792 -349.995824) (xy 119.768617 -350.069799) (xy 119.800122 -350.147176) (xy 119.824011 -350.227233)
			(xy 119.840062 -350.309221) (xy 119.848125 -350.392376) (xy 119.84863 -350.434148) (xy 119.848125 -350.47592)
			(xy 119.840062 -350.559075) (xy 119.824011 -350.641063) (xy 119.800122 -350.72112) (xy 119.768617 -350.798497)
			(xy 119.729792 -350.872472) (xy 119.684009 -350.942355) (xy 119.631694 -351.007492) (xy 119.573337 -351.067277)
			(xy 119.509483 -351.12115) (xy 119.440727 -351.168609) (xy 119.367711 -351.20921) (xy 119.291118 -351.242575)
			(xy 119.211662 -351.268392) (xy 119.130086 -351.28642) (xy 119.04715 -351.29649) (xy 118.96363 -351.298509)
			(xy 118.880304 -351.292457) (xy 118.797952 -351.278392) (xy 118.717342 -351.256444) (xy 118.639226 -351.226818)
			(xy 118.564334 -351.189792) (xy 118.493366 -351.145711) (xy 118.426983 -351.094985) (xy 118.365806 -351.03809)
			(xy 118.310405 -350.975556) (xy 118.261299 -350.907967) (xy 118.218945 -350.835954) (xy 118.183739 -350.760189)
			(xy 118.15601 -350.68138) (xy 118.136017 -350.600263) (xy 118.123945 -350.517595) (xy 118.119909 -350.434148)
			(xy 117.373908 -350.434148) (xy 117.373404 -350.476496) (xy 117.365353 -350.56081) (xy 117.349324 -350.643976)
			(xy 117.325463 -350.725243) (xy 117.293984 -350.803873) (xy 117.255173 -350.879154) (xy 117.209383 -350.950406)
			(xy 117.157027 -351.016982) (xy 117.098579 -351.07828) (xy 117.034569 -351.133745) (xy 116.965577 -351.182874)
			(xy 116.892227 -351.225223) (xy 116.815184 -351.260407) (xy 116.735145 -351.288109) (xy 116.652836 -351.308077)
			(xy 116.569001 -351.32013) (xy 116.4844 -351.324161) (xy 116.399799 -351.32013) (xy 116.315964 -351.308077)
			(xy 116.233655 -351.288109) (xy 116.153616 -351.260407) (xy 116.076573 -351.225223) (xy 116.003223 -351.182874)
			(xy 115.934231 -351.133745) (xy 115.870221 -351.07828) (xy 115.811773 -351.016982) (xy 115.759417 -350.950406)
			(xy 115.713627 -350.879154) (xy 115.674816 -350.803873) (xy 115.643337 -350.725243) (xy 115.619476 -350.643976)
			(xy 115.603447 -350.56081) (xy 115.595396 -350.476496) (xy 114.922808 -350.476496) (xy 114.922808 -355.224842)
			(xy 114.922175 -355.247335) (xy 114.913337 -355.291445) (xy 114.896068 -355.332986) (xy 114.871031 -355.370362)
			(xy 114.855498 -355.38664) (xy 114.375692 -355.866446) (xy 114.35946 -355.882039) (xy 114.322082 -355.907107)
			(xy 114.280527 -355.924389) (xy 114.236396 -355.933219) (xy 114.213894 -355.933756) (xy 113.302542 -355.933756)
			(xy 112.667951 -356.568248) (xy 113.183922 -356.568248) (xy 113.187993 -356.512626) (xy 113.200119 -356.458189)
			(xy 113.220042 -356.406098) (xy 113.247338 -356.357463) (xy 113.281424 -356.31332) (xy 113.321573 -356.274611)
			(xy 113.366931 -356.24216) (xy 113.416531 -356.216659) (xy 113.469315 -356.198652) (xy 113.524158 -356.188522)
			(xy 113.579892 -356.186485) (xy 113.635329 -356.192585) (xy 113.689286 -356.206691) (xy 113.740615 -356.228503)
			(xy 113.788221 -356.257557) (xy 113.831089 -356.293232) (xy 113.868306 -356.334769) (xy 113.899079 -356.381282)
			(xy 113.922751 -356.431779) (xy 113.938819 -356.485186) (xy 113.946939 -356.540362) (xy 113.947448 -356.568248)
			(xy 113.946939 -356.596134) (xy 113.938819 -356.65131) (xy 113.922751 -356.704717) (xy 113.899079 -356.755214)
			(xy 113.868306 -356.801727) (xy 113.831089 -356.843264) (xy 113.825211 -356.848156) (xy 114.184174 -356.848156)
			(xy 114.188245 -356.792534) (xy 114.200371 -356.738097) (xy 114.220294 -356.686006) (xy 114.24759 -356.637371)
			(xy 114.281676 -356.593228) (xy 114.321825 -356.554519) (xy 114.367183 -356.522068) (xy 114.416783 -356.496567)
			(xy 114.469567 -356.47856) (xy 114.52441 -356.46843) (xy 114.580144 -356.466393) (xy 114.635581 -356.472493)
			(xy 114.689538 -356.486599) (xy 114.740867 -356.508411) (xy 114.788473 -356.537465) (xy 114.831341 -356.57314)
			(xy 114.868558 -356.614677) (xy 114.899331 -356.66119) (xy 114.923003 -356.711687) (xy 114.939071 -356.765094)
			(xy 114.947191 -356.82027) (xy 114.9477 -356.848156) (xy 114.947191 -356.876042) (xy 114.939071 -356.931218)
			(xy 114.923003 -356.984625) (xy 114.899331 -357.035122) (xy 114.868558 -357.081635) (xy 114.831341 -357.123172)
			(xy 114.788473 -357.158847) (xy 114.740867 -357.187901) (xy 114.689538 -357.209713) (xy 114.635581 -357.223819)
			(xy 114.580144 -357.229919) (xy 114.52441 -357.227882) (xy 114.469567 -357.217752) (xy 114.416783 -357.199745)
			(xy 114.367183 -357.174244) (xy 114.321825 -357.141793) (xy 114.281676 -357.103084) (xy 114.24759 -357.058941)
			(xy 114.220294 -357.010306) (xy 114.200371 -356.958215) (xy 114.188245 -356.903778) (xy 114.184174 -356.848156)
			(xy 113.825211 -356.848156) (xy 113.788221 -356.878939) (xy 113.740615 -356.907993) (xy 113.689286 -356.929805)
			(xy 113.635329 -356.943911) (xy 113.579892 -356.950011) (xy 113.524158 -356.947974) (xy 113.469315 -356.937844)
			(xy 113.416531 -356.919837) (xy 113.366931 -356.894336) (xy 113.321573 -356.861885) (xy 113.281424 -356.823176)
			(xy 113.247338 -356.779033) (xy 113.220042 -356.730398) (xy 113.200119 -356.678307) (xy 113.187993 -356.62387)
			(xy 113.183922 -356.568248) (xy 112.667951 -356.568248) (xy 111.679228 -357.556816) (xy 111.679228 -357.561388)
			(xy 112.960402 -357.561388) (xy 112.964473 -357.505766) (xy 112.976599 -357.451329) (xy 112.996522 -357.399238)
			(xy 113.023818 -357.350603) (xy 113.057904 -357.30646) (xy 113.098053 -357.267751) (xy 113.143411 -357.2353)
			(xy 113.193011 -357.209799) (xy 113.245795 -357.191792) (xy 113.300638 -357.181662) (xy 113.356372 -357.179625)
			(xy 113.411809 -357.185725) (xy 113.465766 -357.199831) (xy 113.517095 -357.221643) (xy 113.564701 -357.250697)
			(xy 113.607569 -357.286372) (xy 113.644786 -357.327909) (xy 113.675559 -357.374422) (xy 113.699231 -357.424919)
			(xy 113.715299 -357.478326) (xy 113.723419 -357.533502) (xy 113.723928 -357.561388) (xy 113.723419 -357.589274)
			(xy 113.715299 -357.64445) (xy 113.699231 -357.697857) (xy 113.675559 -357.748354) (xy 113.644786 -357.794867)
			(xy 113.607569 -357.836404) (xy 113.564701 -357.872079) (xy 113.517095 -357.901133) (xy 113.465766 -357.922945)
			(xy 113.411809 -357.937051) (xy 113.356372 -357.943151) (xy 113.300638 -357.941114) (xy 113.245795 -357.930984)
			(xy 113.193011 -357.912977) (xy 113.143411 -357.887476) (xy 113.098053 -357.855025) (xy 113.057904 -357.816316)
			(xy 113.023818 -357.772173) (xy 112.996522 -357.723538) (xy 112.976599 -357.671447) (xy 112.964473 -357.61701)
			(xy 112.960402 -357.561388) (xy 111.679228 -357.561388) (xy 111.679228 -358.576626) (xy 112.706402 -358.576626)
			(xy 112.710473 -358.521004) (xy 112.722599 -358.466567) (xy 112.742522 -358.414476) (xy 112.769818 -358.365841)
			(xy 112.803904 -358.321698) (xy 112.844053 -358.282989) (xy 112.889411 -358.250538) (xy 112.939011 -358.225037)
			(xy 112.991795 -358.20703) (xy 113.046638 -358.1969) (xy 113.102372 -358.194863) (xy 113.157809 -358.200963)
			(xy 113.211766 -358.215069) (xy 113.263095 -358.236881) (xy 113.310701 -358.265935) (xy 113.353569 -358.30161)
			(xy 113.390786 -358.343147) (xy 113.421559 -358.38966) (xy 113.445231 -358.440157) (xy 113.461299 -358.493564)
			(xy 113.469419 -358.54874) (xy 113.469928 -358.576626) (xy 113.469419 -358.604512) (xy 113.461299 -358.659688)
			(xy 113.445231 -358.713095) (xy 113.421559 -358.763592) (xy 113.390786 -358.810105) (xy 113.353569 -358.851642)
			(xy 113.310701 -358.887317) (xy 113.263095 -358.916371) (xy 113.211766 -358.938183) (xy 113.157809 -358.952289)
			(xy 113.102372 -358.958389) (xy 113.046638 -358.956352) (xy 112.991795 -358.946222) (xy 112.939011 -358.928215)
			(xy 112.889411 -358.902714) (xy 112.844053 -358.870263) (xy 112.803904 -358.831554) (xy 112.769818 -358.787411)
			(xy 112.742522 -358.738776) (xy 112.722599 -358.686685) (xy 112.710473 -358.632248) (xy 112.706402 -358.576626)
			(xy 111.679228 -358.576626) (xy 111.679228 -359.595674) (xy 112.734088 -359.595674) (xy 112.738159 -359.540052)
			(xy 112.750285 -359.485615) (xy 112.770208 -359.433524) (xy 112.797504 -359.384889) (xy 112.83159 -359.340746)
			(xy 112.871739 -359.302037) (xy 112.917097 -359.269586) (xy 112.966697 -359.244085) (xy 113.019481 -359.226078)
			(xy 113.074324 -359.215948) (xy 113.130058 -359.213911) (xy 113.185495 -359.220011) (xy 113.239452 -359.234117)
			(xy 113.290781 -359.255929) (xy 113.338387 -359.284983) (xy 113.381255 -359.320658) (xy 113.418472 -359.362195)
			(xy 113.449245 -359.408708) (xy 113.472917 -359.459205) (xy 113.488985 -359.512612) (xy 113.497105 -359.567788)
			(xy 113.497614 -359.595674) (xy 113.497105 -359.62356) (xy 113.488985 -359.678736) (xy 113.472917 -359.732143)
			(xy 113.449245 -359.78264) (xy 113.418472 -359.829153) (xy 113.381255 -359.87069) (xy 113.338387 -359.906365)
			(xy 113.290781 -359.935419) (xy 113.239452 -359.957231) (xy 113.185495 -359.971337) (xy 113.130058 -359.977437)
			(xy 113.074324 -359.9754) (xy 113.019481 -359.96527) (xy 112.966697 -359.947263) (xy 112.917097 -359.921762)
			(xy 112.871739 -359.889311) (xy 112.83159 -359.850602) (xy 112.797504 -359.806459) (xy 112.770208 -359.757824)
			(xy 112.750285 -359.705733) (xy 112.738159 -359.651296) (xy 112.734088 -359.595674) (xy 111.679228 -359.595674)
			(xy 111.679228 -360.61142) (xy 112.831624 -360.61142) (xy 112.835695 -360.555798) (xy 112.847821 -360.501361)
			(xy 112.867744 -360.44927) (xy 112.89504 -360.400635) (xy 112.929126 -360.356492) (xy 112.969275 -360.317783)
			(xy 113.014633 -360.285332) (xy 113.064233 -360.259831) (xy 113.117017 -360.241824) (xy 113.17186 -360.231694)
			(xy 113.227594 -360.229657) (xy 113.283031 -360.235757) (xy 113.336988 -360.249863) (xy 113.388317 -360.271675)
			(xy 113.435923 -360.300729) (xy 113.478791 -360.336404) (xy 113.516008 -360.377941) (xy 113.546781 -360.424454)
			(xy 113.570453 -360.474951) (xy 113.586521 -360.528358) (xy 113.594641 -360.583534) (xy 113.59515 -360.61142)
			(xy 113.594641 -360.639306) (xy 113.586521 -360.694482) (xy 113.570453 -360.747889) (xy 113.546781 -360.798386)
			(xy 113.516008 -360.844899) (xy 113.478791 -360.886436) (xy 113.435923 -360.922111) (xy 113.388317 -360.951165)
			(xy 113.336988 -360.972977) (xy 113.283031 -360.987083) (xy 113.227594 -360.993183) (xy 113.17186 -360.991146)
			(xy 113.117017 -360.981016) (xy 113.064233 -360.963009) (xy 113.014633 -360.937508) (xy 112.969275 -360.905057)
			(xy 112.929126 -360.866348) (xy 112.89504 -360.822205) (xy 112.867744 -360.77357) (xy 112.847821 -360.721479)
			(xy 112.835695 -360.667042) (xy 112.831624 -360.61142) (xy 111.679228 -360.61142) (xy 111.679228 -360.817414)
			(xy 111.67866 -360.839896) (xy 111.669873 -360.883995) (xy 111.652659 -360.925535) (xy 111.627678 -360.962923)
			(xy 111.612172 -360.979212) (xy 111.046768 -361.544616) (xy 112.355882 -361.544616) (xy 112.359953 -361.488994)
			(xy 112.372079 -361.434557) (xy 112.392002 -361.382466) (xy 112.419298 -361.333831) (xy 112.453384 -361.289688)
			(xy 112.493533 -361.250979) (xy 112.538891 -361.218528) (xy 112.588491 -361.193027) (xy 112.641275 -361.17502)
			(xy 112.696118 -361.16489) (xy 112.751852 -361.162853) (xy 112.807289 -361.168953) (xy 112.861246 -361.183059)
			(xy 112.912575 -361.204871) (xy 112.960181 -361.233925) (xy 113.003049 -361.2696) (xy 113.040266 -361.311137)
			(xy 113.071039 -361.35765) (xy 113.094711 -361.408147) (xy 113.110779 -361.461554) (xy 113.118899 -361.51673)
			(xy 113.119408 -361.544616) (xy 113.118899 -361.572502) (xy 113.110779 -361.627678) (xy 113.094711 -361.681085)
			(xy 113.071039 -361.731582) (xy 113.040266 -361.778095) (xy 113.003049 -361.819632) (xy 112.960181 -361.855307)
			(xy 112.912575 -361.884361) (xy 112.861246 -361.906173) (xy 112.807289 -361.920279) (xy 112.751852 -361.926379)
			(xy 112.696118 -361.924342) (xy 112.641275 -361.914212) (xy 112.588491 -361.896205) (xy 112.538891 -361.870704)
			(xy 112.493533 -361.838253) (xy 112.453384 -361.799544) (xy 112.419298 -361.755401) (xy 112.392002 -361.706766)
			(xy 112.372079 -361.654675) (xy 112.359953 -361.600238) (xy 112.355882 -361.544616) (xy 111.046768 -361.544616)
			(xy 110.161324 -362.43006) (xy 111.033812 -362.43006) (xy 111.037883 -362.374438) (xy 111.050009 -362.320001)
			(xy 111.069932 -362.26791) (xy 111.097228 -362.219275) (xy 111.131314 -362.175132) (xy 111.171463 -362.136423)
			(xy 111.216821 -362.103972) (xy 111.266421 -362.078471) (xy 111.319205 -362.060464) (xy 111.374048 -362.050334)
			(xy 111.429782 -362.048297) (xy 111.485219 -362.054397) (xy 111.539176 -362.068503) (xy 111.590505 -362.090315)
			(xy 111.638111 -362.119369) (xy 111.680979 -362.155044) (xy 111.718196 -362.196581) (xy 111.748969 -362.243094)
			(xy 111.772641 -362.293591) (xy 111.788709 -362.346998) (xy 111.796829 -362.402174) (xy 111.797338 -362.43006)
			(xy 111.796829 -362.457946) (xy 111.788709 -362.513122) (xy 111.772641 -362.566529) (xy 111.748969 -362.617026)
			(xy 111.718196 -362.663539) (xy 111.680979 -362.705076) (xy 111.638111 -362.740751) (xy 111.590505 -362.769805)
			(xy 111.539176 -362.791617) (xy 111.485219 -362.805723) (xy 111.429782 -362.811823) (xy 111.374048 -362.809786)
			(xy 111.319205 -362.799656) (xy 111.266421 -362.781649) (xy 111.216821 -362.756148) (xy 111.171463 -362.723697)
			(xy 111.131314 -362.684988) (xy 111.097228 -362.640845) (xy 111.069932 -362.59221) (xy 111.050009 -362.540119)
			(xy 111.037883 -362.485682) (xy 111.033812 -362.43006) (xy 110.161324 -362.43006) (xy 109.215682 -363.375702)
			(xy 109.736888 -363.375702) (xy 109.740959 -363.32008) (xy 109.753085 -363.265643) (xy 109.773008 -363.213552)
			(xy 109.800304 -363.164917) (xy 109.83439 -363.120774) (xy 109.874539 -363.082065) (xy 109.919897 -363.049614)
			(xy 109.969497 -363.024113) (xy 110.022281 -363.006106) (xy 110.077124 -362.995976) (xy 110.132858 -362.993939)
			(xy 110.188295 -363.000039) (xy 110.242252 -363.014145) (xy 110.293581 -363.035957) (xy 110.341187 -363.065011)
			(xy 110.384055 -363.100686) (xy 110.421272 -363.142223) (xy 110.452045 -363.188736) (xy 110.475717 -363.239233)
			(xy 110.491785 -363.29264) (xy 110.499905 -363.347816) (xy 110.500414 -363.375702) (xy 110.499905 -363.403588)
			(xy 110.491785 -363.458764) (xy 110.475717 -363.512171) (xy 110.452045 -363.562668) (xy 110.421272 -363.609181)
			(xy 110.384055 -363.650718) (xy 110.341187 -363.686393) (xy 110.293581 -363.715447) (xy 110.242252 -363.737259)
			(xy 110.188295 -363.751365) (xy 110.132858 -363.757465) (xy 110.077124 -363.755428) (xy 110.022281 -363.745298)
			(xy 109.969497 -363.727291) (xy 109.919897 -363.70179) (xy 109.874539 -363.669339) (xy 109.83439 -363.63063)
			(xy 109.800304 -363.586487) (xy 109.773008 -363.537852) (xy 109.753085 -363.485761) (xy 109.740959 -363.431324)
			(xy 109.736888 -363.375702) (xy 109.215682 -363.375702) (xy 108.335826 -364.255558) (xy 108.337858 -364.27918)
			(xy 108.339128 -364.310168) (xy 108.338679 -364.337424) (xy 108.330926 -364.391382) (xy 108.318575 -364.433456)
			(xy 109.828735 -364.433456) (xy 109.828735 -364.378944) (xy 109.836493 -364.324987) (xy 109.851852 -364.272683)
			(xy 109.874499 -364.223098) (xy 109.903972 -364.17724) (xy 109.939671 -364.136045) (xy 109.980871 -364.100349)
			(xy 110.026731 -364.07088) (xy 110.076319 -364.048239) (xy 110.128624 -364.032885) (xy 110.182582 -364.025132)
			(xy 110.209838 -364.024672) (xy 110.236618 -364.025135) (xy 110.289649 -364.032657) (xy 110.315502 -364.039658)
			(xy 110.344458 -364.04804) (xy 111.191548 -363.20095) (xy 111.207805 -363.185384) (xy 111.245174 -363.160312)
			(xy 111.286722 -363.143022) (xy 111.330846 -363.134182) (xy 111.353346 -363.13364) (xy 111.622078 -363.13364)
			(xy 112.48644 -362.269532) (xy 112.5027 -362.253988) (xy 112.540087 -362.228985) (xy 112.581637 -362.211764)
			(xy 112.625749 -362.202989) (xy 112.648238 -362.202476) (xy 113.770156 -362.202476) (xy 115.000532 -360.971846)
			(xy 115.000532 -357.708962) (xy 115.001095 -357.686466) (xy 115.009953 -357.642351) (xy 115.027242 -357.60081)
			(xy 115.052299 -357.563438) (xy 115.067842 -357.547164) (xy 115.274852 -357.3399) (xy 115.274852 -353.725734)
			(xy 115.275453 -353.703239) (xy 115.284298 -353.659127) (xy 115.301576 -353.617586) (xy 115.326623 -353.580212)
			(xy 115.342162 -353.563936) (xy 116.601748 -352.30435) (xy 116.618005 -352.288784) (xy 116.655374 -352.263712)
			(xy 116.696922 -352.246422) (xy 116.741046 -352.237582) (xy 116.763546 -352.23704) (xy 120.521476 -352.23704)
			(xy 123.257056 -349.501714) (xy 123.273319 -349.486155) (xy 123.310685 -349.461079) (xy 123.352231 -349.443787)
			(xy 123.396354 -349.434946) (xy 123.418854 -349.434404) (xy 134.99338 -349.434404) (xy 137.360914 -347.067124)
			(xy 137.367798 -347.060293) (xy 137.382551 -347.047704) (xy 137.390378 -347.041978) (xy 137.39887 -347.035321)
			(xy 137.409848 -347.016775) (xy 137.412239 -346.995356) (xy 137.405622 -346.974845) (xy 137.391164 -346.958863)
			(xy 137.381488 -346.954094) (xy 137.371401 -346.949571) (xy 137.351704 -346.939533) (xy 137.342118 -346.934028)
			(xy 137.329125 -346.927047) (xy 137.3005 -346.920009) (xy 137.271058 -346.921446) (xy 137.243253 -346.931237)
			(xy 137.219407 -346.948565) (xy 137.201508 -346.971986) (xy 137.195814 -346.98559) (xy 137.185117 -347.012366)
			(xy 137.156831 -347.062609) (xy 137.121302 -347.10802) (xy 137.07934 -347.147563) (xy 137.031903 -347.180337)
			(xy 136.980071 -347.205595) (xy 136.925028 -347.22276) (xy 136.868027 -347.231441) (xy 136.839198 -347.23197)
			(xy 136.811944 -347.23156) (xy 136.757991 -347.223802) (xy 136.705692 -347.208446) (xy 136.65611 -347.185802)
			(xy 136.610255 -347.156333) (xy 136.569061 -347.120638) (xy 136.533366 -347.079443) (xy 136.503897 -347.033589)
			(xy 136.481254 -346.984007) (xy 136.465897 -346.931707) (xy 136.45814 -346.877754) (xy 136.45814 -346.823246)
			(xy 136.465897 -346.769293) (xy 136.481254 -346.716993) (xy 136.503897 -346.667411) (xy 136.533366 -346.621557)
			(xy 136.569061 -346.580362) (xy 136.610255 -346.544667) (xy 136.65611 -346.515198) (xy 136.705692 -346.492554)
			(xy 136.757991 -346.477198) (xy 136.811944 -346.46944) (xy 136.839198 -346.468954) (xy 136.839452 -346.468954)
			(xy 136.864655 -346.469373) (xy 136.914622 -346.476006) (xy 136.963277 -346.489177) (xy 137.009767 -346.508655)
			(xy 137.03173 -346.521024) (xy 137.044684 -346.528087) (xy 137.073326 -346.535122) (xy 137.102783 -346.533675)
			(xy 137.130598 -346.523868) (xy 137.154449 -346.506519) (xy 137.172345 -346.483076) (xy 137.178034 -346.469462)
			(xy 137.188748 -346.442694) (xy 137.217036 -346.392454) (xy 137.252564 -346.347046) (xy 137.294524 -346.307505)
			(xy 137.341958 -346.27473) (xy 137.393785 -346.249471) (xy 137.448825 -346.232302) (xy 137.505822 -346.223614)
			(xy 137.53465 -346.223082) (xy 137.561901 -346.223602) (xy 137.61585 -346.231352) (xy 137.668146 -346.246701)
			(xy 137.717725 -346.269337) (xy 137.763578 -346.298799) (xy 137.804771 -346.334487) (xy 137.840465 -346.375674)
			(xy 137.869934 -346.421522) (xy 137.892578 -346.471098) (xy 137.907936 -346.523392) (xy 137.915694 -346.577339)
			(xy 137.916158 -346.60459) (xy 137.916158 -346.604844) (xy 137.915584 -346.634683) (xy 137.906268 -346.693629)
			(xy 137.897616 -346.722192) (xy 137.893528 -346.736087) (xy 137.892626 -346.765028) (xy 137.8999 -346.793054)
			(xy 137.914763 -346.817903) (xy 137.936014 -346.837569) (xy 137.961939 -346.850464) (xy 137.976102 -346.85351)
			(xy 138.002169 -346.858706) (xy 138.052672 -346.875273) (xy 138.100385 -346.898693) (xy 138.144384 -346.928511)
			(xy 138.183815 -346.964151) (xy 138.217914 -347.004921) (xy 138.246022 -347.050032) (xy 138.267593 -347.098609)
			(xy 138.282209 -347.14971) (xy 138.289587 -347.202347) (xy 138.290046 -347.228922) (xy 138.289543 -347.256172)
			(xy 138.281784 -347.310117) (xy 138.266428 -347.362409) (xy 138.243787 -347.411984) (xy 138.214322 -347.457833)
			(xy 138.178633 -347.499022) (xy 138.137445 -347.534713) (xy 138.091598 -347.56418) (xy 138.042024 -347.586823)
			(xy 137.989733 -347.602181) (xy 137.935788 -347.609942) (xy 137.908538 -347.61043) (xy 137.879165 -347.609937)
			(xy 137.821114 -347.600935) (xy 137.76513 -347.583137) (xy 137.712537 -347.556966) (xy 137.664579 -347.523039)
			(xy 137.643108 -347.502988) (xy 137.607294 -347.46819) (xy 135.24992 -349.82531) (xy 135.233671 -349.840884)
			(xy 135.1963 -349.865957) (xy 135.15475 -349.883245) (xy 135.110623 -349.892081) (xy 135.088122 -349.89262)
			(xy 123.513596 -349.89262) (xy 120.778016 -352.627946) (xy 120.761774 -352.643528) (xy 120.7244 -352.668598)
			(xy 120.682848 -352.685883) (xy 120.638719 -352.694717) (xy 120.616218 -352.695256) (xy 116.858288 -352.695256)
			(xy 115.733068 -353.820476) (xy 115.733068 -354.687886) (xy 116.286026 -354.687886) (xy 116.286472 -354.661506)
			(xy 116.293727 -354.609248) (xy 116.30811 -354.558488) (xy 116.329348 -354.510192) (xy 116.357036 -354.465282)
			(xy 116.390646 -354.424613) (xy 116.429536 -354.388961) (xy 116.472967 -354.359006) (xy 116.496338 -354.346764)
			(xy 116.508712 -354.340085) (xy 116.529447 -354.321108) (xy 116.544213 -354.29719) (xy 116.551887 -354.270148)
			(xy 116.551885 -354.242039) (xy 116.544208 -354.214999) (xy 116.529439 -354.191082) (xy 116.508701 -354.172108)
			(xy 116.496338 -354.165408) (xy 116.472948 -354.153203) (xy 116.429525 -354.123234) (xy 116.390642 -354.087572)
			(xy 116.357039 -354.046897) (xy 116.329355 -354.001983) (xy 116.308118 -353.953686) (xy 116.293731 -353.902924)
			(xy 116.28647 -353.850666) (xy 116.286026 -353.824286) (xy 116.286512 -353.797035) (xy 116.294268 -353.743087)
			(xy 116.309623 -353.690792) (xy 116.332265 -353.641215) (xy 116.361731 -353.595365) (xy 116.397422 -353.554174)
			(xy 116.438613 -353.518483) (xy 116.484463 -353.489017) (xy 116.53404 -353.466375) (xy 116.586335 -353.45102)
			(xy 116.640283 -353.443264) (xy 116.694785 -353.443264) (xy 116.748733 -353.45102) (xy 116.801028 -353.466375)
			(xy 116.850605 -353.489017) (xy 116.896455 -353.518483) (xy 116.937646 -353.554174) (xy 116.973337 -353.595365)
			(xy 117.002803 -353.641215) (xy 117.025445 -353.690792) (xy 117.0408 -353.743087) (xy 117.048556 -353.797035)
			(xy 117.049042 -353.824286) (xy 117.048618 -353.850666) (xy 117.041355 -353.902923) (xy 117.026965 -353.953683)
			(xy 117.005723 -354.001977) (xy 116.978032 -354.046886) (xy 116.944421 -354.087554) (xy 116.90553 -354.123207)
			(xy 116.862101 -354.153164) (xy 116.83873 -354.165408) (xy 116.826384 -354.172131) (xy 116.805657 -354.191103)
			(xy 116.790897 -354.215013) (xy 116.783225 -354.242044) (xy 116.783223 -354.270143) (xy 116.790892 -354.297175)
			(xy 116.805649 -354.321087) (xy 116.826374 -354.340062) (xy 116.83873 -354.346764) (xy 116.862101 -354.359004)
			(xy 116.905524 -354.388967) (xy 116.944409 -354.424623) (xy 116.978014 -354.465293) (xy 117.005701 -354.510202)
			(xy 117.026941 -354.558495) (xy 117.041331 -354.609252) (xy 117.048596 -354.661507) (xy 117.049042 -354.687886)
			(xy 117.048556 -354.715137) (xy 117.0408 -354.769085) (xy 117.025445 -354.82138) (xy 117.002803 -354.870957)
			(xy 116.973337 -354.916807) (xy 116.937646 -354.957998) (xy 116.896455 -354.993689) (xy 116.850605 -355.023155)
			(xy 116.801028 -355.045797) (xy 116.748733 -355.061152) (xy 116.694785 -355.068908) (xy 116.640283 -355.068908)
			(xy 116.586335 -355.061152) (xy 116.53404 -355.045797) (xy 116.484463 -355.023155) (xy 116.438613 -354.993689)
			(xy 116.397422 -354.957998) (xy 116.361731 -354.916807) (xy 116.332265 -354.870957) (xy 116.309623 -354.82138)
			(xy 116.294268 -354.769085) (xy 116.286512 -354.715137) (xy 116.286026 -354.687886) (xy 115.733068 -354.687886)
			(xy 115.733068 -355.18217) (xy 117.96852 -355.18217) (xy 117.972591 -355.126548) (xy 117.984717 -355.072111)
			(xy 118.00464 -355.02002) (xy 118.031936 -354.971385) (xy 118.066022 -354.927242) (xy 118.106171 -354.888533)
			(xy 118.151529 -354.856082) (xy 118.201129 -354.830581) (xy 118.253913 -354.812574) (xy 118.308756 -354.802444)
			(xy 118.36449 -354.800407) (xy 118.419927 -354.806507) (xy 118.473884 -354.820613) (xy 118.525213 -354.842425)
			(xy 118.572819 -354.871479) (xy 118.615687 -354.907154) (xy 118.652904 -354.948691) (xy 118.683677 -354.995204)
			(xy 118.707349 -355.045701) (xy 118.723417 -355.099108) (xy 118.731537 -355.154284) (xy 118.732046 -355.18217)
			(xy 118.731537 -355.210056) (xy 118.723417 -355.265232) (xy 118.707349 -355.318639) (xy 118.683677 -355.369136)
			(xy 118.652904 -355.415649) (xy 118.615687 -355.457186) (xy 118.572819 -355.492861) (xy 118.525213 -355.521915)
			(xy 118.473884 -355.543727) (xy 118.419927 -355.557833) (xy 118.36449 -355.563933) (xy 118.308756 -355.561896)
			(xy 118.253913 -355.551766) (xy 118.201129 -355.533759) (xy 118.151529 -355.508258) (xy 118.106171 -355.475807)
			(xy 118.066022 -355.437098) (xy 118.031936 -355.392955) (xy 118.00464 -355.34432) (xy 117.984717 -355.292229)
			(xy 117.972591 -355.237792) (xy 117.96852 -355.18217) (xy 115.733068 -355.18217) (xy 115.733068 -357.434642)
			(xy 115.732446 -357.457135) (xy 115.723607 -357.501247) (xy 115.706335 -357.542788) (xy 115.681294 -357.580163)
			(xy 115.665758 -357.59644) (xy 115.458748 -357.803704) (xy 115.458748 -361.066588) (xy 115.45816 -361.089083)
			(xy 115.449311 -361.133197) (xy 115.432029 -361.174738) (xy 115.406978 -361.212111) (xy 115.391438 -361.228386)
			(xy 114.026696 -362.593128) (xy 114.010414 -362.608648) (xy 113.973036 -362.633657) (xy 113.931493 -362.650885)
			(xy 113.887385 -362.659668) (xy 113.864898 -362.660184) (xy 112.74298 -362.660184) (xy 112.077754 -363.32541)
			(xy 112.722658 -363.32541) (xy 112.726729 -363.269788) (xy 112.738855 -363.215351) (xy 112.758778 -363.16326)
			(xy 112.786074 -363.114625) (xy 112.82016 -363.070482) (xy 112.860309 -363.031773) (xy 112.905667 -362.999322)
			(xy 112.955267 -362.973821) (xy 113.008051 -362.955814) (xy 113.062894 -362.945684) (xy 113.118628 -362.943647)
			(xy 113.174065 -362.949747) (xy 113.228022 -362.963853) (xy 113.279351 -362.985665) (xy 113.326957 -363.014719)
			(xy 113.369825 -363.050394) (xy 113.407042 -363.091931) (xy 113.437815 -363.138444) (xy 113.461487 -363.188941)
			(xy 113.477555 -363.242348) (xy 113.485675 -363.297524) (xy 113.486184 -363.32541) (xy 113.485675 -363.353296)
			(xy 113.477555 -363.408472) (xy 113.461487 -363.461879) (xy 113.437815 -363.512376) (xy 113.431444 -363.522006)
			(xy 115.599718 -363.522006) (xy 115.600195 -363.493698) (xy 115.60854 -363.4377) (xy 115.625078 -363.383554)
			(xy 115.649445 -363.33245) (xy 115.681103 -363.285512) (xy 115.719357 -363.243775) (xy 115.763365 -363.208157)
			(xy 115.812158 -363.179441) (xy 115.864662 -363.158259) (xy 115.892072 -363.151166) (xy 115.906042 -363.14761)
			(xy 116.12626 -362.927646) (xy 116.12626 -359.593896) (xy 116.111191 -359.570322) (xy 116.087358 -359.519703)
			(xy 116.071179 -359.466144) (xy 116.062999 -359.410796) (xy 116.062506 -359.382822) (xy 116.062992 -359.355571)
			(xy 116.070748 -359.301623) (xy 116.086103 -359.249328) (xy 116.108745 -359.199751) (xy 116.138211 -359.153901)
			(xy 116.173902 -359.11271) (xy 116.215093 -359.077019) (xy 116.260943 -359.047553) (xy 116.31052 -359.024911)
			(xy 116.362815 -359.009556) (xy 116.416763 -359.0018) (xy 116.471265 -359.0018) (xy 116.525213 -359.009556)
			(xy 116.577508 -359.024911) (xy 116.627085 -359.047553) (xy 116.672935 -359.077019) (xy 116.714126 -359.11271)
			(xy 116.749817 -359.153901) (xy 116.779283 -359.199751) (xy 116.801925 -359.249328) (xy 116.81728 -359.301623)
			(xy 116.825036 -359.355571) (xy 116.825522 -359.382822) (xy 116.825051 -359.410798) (xy 116.81687 -359.466148)
			(xy 116.800687 -359.519708) (xy 116.776849 -359.570328) (xy 116.761768 -359.593896) (xy 116.761768 -363.059472)
			(xy 116.761231 -363.084419) (xy 116.753425 -363.1337) (xy 116.738017 -363.181156) (xy 116.715385 -363.225623)
			(xy 116.686084 -363.266008) (xy 116.668804 -363.284008) (xy 116.355622 -363.59719) (xy 116.352066 -363.61116)
			(xy 116.345028 -363.638579) (xy 116.323807 -363.691062) (xy 116.295064 -363.739832) (xy 116.25943 -363.783819)
			(xy 116.217687 -363.822059) (xy 116.170752 -363.85371) (xy 116.119656 -363.878078) (xy 116.065519 -363.894628)
			(xy 116.009531 -363.902997) (xy 115.981226 -363.903514) (xy 115.953974 -363.903021) (xy 115.900025 -363.895267)
			(xy 115.847728 -363.879915) (xy 115.798148 -363.857276) (xy 115.752295 -363.827811) (xy 115.711102 -363.79212)
			(xy 115.675408 -363.750931) (xy 115.64594 -363.70508) (xy 115.623296 -363.655502) (xy 115.60794 -363.603207)
			(xy 115.600182 -363.549258) (xy 115.599718 -363.522006) (xy 113.431444 -363.522006) (xy 113.407042 -363.558889)
			(xy 113.369825 -363.600426) (xy 113.326957 -363.636101) (xy 113.279351 -363.665155) (xy 113.228022 -363.686967)
			(xy 113.174065 -363.701073) (xy 113.118628 -363.707173) (xy 113.062894 -363.705136) (xy 113.008051 -363.695006)
			(xy 112.955267 -363.676999) (xy 112.905667 -363.651498) (xy 112.860309 -363.619047) (xy 112.82016 -363.580338)
			(xy 112.786074 -363.536195) (xy 112.758778 -363.48756) (xy 112.738855 -363.435469) (xy 112.726729 -363.381032)
			(xy 112.722658 -363.32541) (xy 112.077754 -363.32541) (xy 111.878618 -363.524546) (xy 111.862375 -363.540127)
			(xy 111.825001 -363.565197) (xy 111.783449 -363.582482) (xy 111.739321 -363.591317) (xy 111.71682 -363.591856)
			(xy 111.448088 -363.591856) (xy 110.808516 -364.231428) (xy 111.419638 -364.231428) (xy 111.423709 -364.175806)
			(xy 111.435835 -364.121369) (xy 111.455758 -364.069278) (xy 111.483054 -364.020643) (xy 111.51714 -363.9765)
			(xy 111.557289 -363.937791) (xy 111.602647 -363.90534) (xy 111.652247 -363.879839) (xy 111.705031 -363.861832)
			(xy 111.759874 -363.851702) (xy 111.815608 -363.849665) (xy 111.871045 -363.855765) (xy 111.925002 -363.869871)
			(xy 111.976331 -363.891683) (xy 112.023937 -363.920737) (xy 112.066805 -363.956412) (xy 112.104022 -363.997949)
			(xy 112.134795 -364.044462) (xy 112.158467 -364.094959) (xy 112.174535 -364.148366) (xy 112.182655 -364.203542)
			(xy 112.183164 -364.231428) (xy 112.182655 -364.259314) (xy 112.174535 -364.31449) (xy 112.158467 -364.367897)
			(xy 112.134795 -364.418394) (xy 112.104022 -364.464907) (xy 112.066805 -364.506444) (xy 112.023937 -364.542119)
			(xy 111.976331 -364.571173) (xy 111.925002 -364.592985) (xy 111.871045 -364.607091) (xy 111.815608 -364.613191)
			(xy 111.759874 -364.611154) (xy 111.705031 -364.601024) (xy 111.652247 -364.583017) (xy 111.602647 -364.557516)
			(xy 111.557289 -364.525065) (xy 111.51714 -364.486356) (xy 111.483054 -364.442213) (xy 111.455758 -364.393578)
			(xy 111.435835 -364.341487) (xy 111.423709 -364.28705) (xy 111.419638 -364.231428) (xy 110.808516 -364.231428)
			(xy 110.58906 -364.450884) (xy 110.58652 -364.46714) (xy 110.581791 -364.493642) (xy 110.565785 -364.545042)
			(xy 110.542716 -364.593684) (xy 110.513041 -364.638601) (xy 110.477349 -364.678903) (xy 110.436348 -364.713789)
			(xy 110.390851 -364.742569) (xy 110.341762 -364.76467) (xy 110.290055 -364.779654) (xy 110.236755 -364.787224)
			(xy 110.209838 -364.787688) (xy 110.182582 -364.787268) (xy 110.128624 -364.779515) (xy 110.076319 -364.764161)
			(xy 110.026731 -364.74152) (xy 109.980871 -364.712051) (xy 109.939671 -364.676355) (xy 109.903972 -364.63516)
			(xy 109.874499 -364.589302) (xy 109.851852 -364.539717) (xy 109.836493 -364.487413) (xy 109.828735 -364.433456)
			(xy 108.318575 -364.433456) (xy 108.315572 -364.443687) (xy 108.29293 -364.493274) (xy 108.263462 -364.539134)
			(xy 108.227767 -364.580334) (xy 108.186572 -364.616034) (xy 108.140715 -364.645508) (xy 108.09113 -364.668156)
			(xy 108.038827 -364.683516) (xy 107.984871 -364.691276) (xy 107.930359 -364.691278) (xy 107.876401 -364.683522)
			(xy 107.824097 -364.668166) (xy 107.774511 -364.645522) (xy 107.728652 -364.616052) (xy 107.687454 -364.580355)
			(xy 107.651755 -364.539158) (xy 107.622284 -364.4933) (xy 107.599638 -364.443714) (xy 107.58428 -364.39141)
			(xy 107.576523 -364.337453) (xy 107.000911 -364.337453) (xy 106.882184 -364.456218) (xy 106.879644 -364.472474)
			(xy 106.87497 -364.499099) (xy 106.859212 -364.550806) (xy 106.836311 -364.59977) (xy 106.806726 -364.64501)
			(xy 106.771051 -364.68562) (xy 106.729999 -364.720786) (xy 106.684393 -364.749804) (xy 106.635148 -364.772092)
			(xy 106.583248 -364.787204) (xy 106.529735 -364.794837) (xy 106.502708 -364.795308) (xy 106.475455 -364.794845)
			(xy 106.421503 -364.787089) (xy 106.369204 -364.771734) (xy 106.319623 -364.749092) (xy 106.273769 -364.719624)
			(xy 106.232575 -364.68393) (xy 106.196881 -364.642737) (xy 106.167412 -364.596884) (xy 106.144769 -364.547303)
			(xy 106.129413 -364.495005) (xy 106.121655 -364.441053) (xy 105.529051 -364.441053) (xy 105.273856 -364.696248)
			(xy 105.257594 -364.71179) (xy 105.220208 -364.736795) (xy 105.178659 -364.754016) (xy 105.134547 -364.762792)
			(xy 105.112058 -364.763304) (xy 104.428798 -364.763304) (xy 104.406317 -364.762707) (xy 104.362221 -364.753925)
			(xy 104.320682 -364.736719) (xy 104.283292 -364.711749) (xy 104.267 -364.696248) (xy 103.244142 -363.673644)
			(xy 102.555294 -363.673644) (xy 102.532798 -363.673068) (xy 102.488684 -363.664216) (xy 102.447143 -363.64693)
			(xy 102.409771 -363.621876) (xy 102.393496 -363.606334) (xy 101.082602 -362.29544) (xy 101.067039 -362.27918)
			(xy 101.041964 -362.241813) (xy 101.024673 -362.200266) (xy 101.015833 -362.156142) (xy 101.015292 -362.133642)
			(xy 101.015292 -361.077256) (xy 100.54844 -360.61015) (xy 100.532893 -360.593893) (xy 100.50789 -360.556505)
			(xy 100.49067 -360.514954) (xy 100.481896 -360.470841) (xy 100.481384 -360.448352) (xy 100.481384 -348.522036)
			(xy 100.481918 -348.499552) (xy 100.490715 -348.455451) (xy 100.507939 -348.413911) (xy 100.53293 -348.376526)
			(xy 100.54844 -348.360238) (xy 101.388164 -347.520514) (xy 101.388164 -342.06053) (xy 97.584514 -338.25688)
			(xy 97.411032 -338.25688) (xy 97.392914 -338.280149) (xy 97.350689 -338.321317) (xy 97.302636 -338.355501)
			(xy 97.249897 -338.381889) (xy 97.193728 -338.399852) (xy 97.135464 -338.408964) (xy 97.105978 -338.409534)
			(xy 97.078727 -338.409043) (xy 97.024781 -338.401284) (xy 96.972488 -338.385927) (xy 96.922913 -338.363286)
			(xy 96.877064 -338.333819) (xy 96.835874 -338.298129) (xy 96.800183 -338.25694) (xy 96.770716 -338.211091)
			(xy 96.748074 -338.161516) (xy 96.732717 -338.109223) (xy 96.724958 -338.055277) (xy 96.72447 -338.028026)
			(xy 96.72447 -338.027772) (xy 96.725047 -337.997933) (xy 96.734361 -337.938987) (xy 96.743012 -337.910424)
			(xy 96.74706 -337.896519) (xy 96.747965 -337.867586) (xy 96.740696 -337.839565) (xy 96.725842 -337.81472)
			(xy 96.704599 -337.795054) (xy 96.678684 -337.782155) (xy 96.664526 -337.779106) (xy 96.631688 -337.772518)
			(xy 96.568835 -337.749399) (xy 96.539558 -337.733132) (xy 96.526602 -337.726078) (xy 96.497962 -337.71905)
			(xy 96.468508 -337.720499) (xy 96.440696 -337.730304) (xy 96.416846 -337.747648) (xy 96.398947 -337.771083)
			(xy 96.393254 -337.784694) (xy 96.382526 -337.811457) (xy 96.354243 -337.861698) (xy 96.318718 -337.907108)
			(xy 96.276761 -337.946651) (xy 96.229328 -337.979427) (xy 96.177501 -338.004687) (xy 96.122462 -338.021856)
			(xy 96.065465 -338.030542) (xy 96.036638 -338.031074) (xy 96.009381 -338.030682) (xy 95.955421 -338.022928)
			(xy 95.903114 -338.007574) (xy 95.853525 -337.984932) (xy 95.807662 -337.955462) (xy 95.766462 -337.919765)
			(xy 95.730761 -337.878568) (xy 95.701286 -337.832709) (xy 95.678639 -337.783122) (xy 95.66328 -337.730816)
			(xy 95.655521 -337.676857) (xy 95.335442 -337.676857) (xy 95.312908 -337.708268) (xy 95.271238 -337.75057)
			(xy 95.247714 -337.768692) (xy 95.237079 -337.777087) (xy 95.220368 -337.798405) (xy 95.209849 -337.823367)
			(xy 95.206262 -337.850216) (xy 95.209858 -337.877063) (xy 95.220384 -337.902021) (xy 95.237101 -337.923335)
			(xy 95.247714 -337.93176) (xy 95.271256 -337.949857) (xy 95.312914 -337.992169) (xy 95.347515 -338.040424)
			(xy 95.374222 -338.093457) (xy 95.392391 -338.149987) (xy 95.401584 -338.208649) (xy 95.402146 -338.238338)
			(xy 95.40166 -338.265589) (xy 95.393904 -338.319537) (xy 95.378549 -338.371832) (xy 95.355907 -338.421409)
			(xy 95.326441 -338.467259) (xy 95.29075 -338.50845) (xy 95.249559 -338.544141) (xy 95.203709 -338.573607)
			(xy 95.154132 -338.596249) (xy 95.101837 -338.611604) (xy 95.047889 -338.61936) (xy 94.993387 -338.61936)
			(xy 94.939439 -338.611604) (xy 94.887144 -338.596249) (xy 94.837567 -338.573607) (xy 94.791717 -338.544141)
			(xy 94.750526 -338.50845) (xy 94.714835 -338.467259) (xy 94.685369 -338.421409) (xy 94.662727 -338.371832)
			(xy 94.647372 -338.319537) (xy 94.639616 -338.265589) (xy 94.63913 -338.238338) (xy 86.559644 -338.238338)
			(xy 86.559644 -338.793328) (xy 86.559131 -338.818311) (xy 86.551276 -338.867656) (xy 86.535811 -338.915168)
			(xy 86.513115 -338.959682) (xy 86.491668 -338.9892) (xy 89.129495 -338.9892) (xy 89.133664 -338.933573)
			(xy 89.146078 -338.879188) (xy 89.16646 -338.827262) (xy 89.194353 -338.778953) (xy 89.229135 -338.735342)
			(xy 89.27003 -338.697402) (xy 89.316122 -338.665981) (xy 89.366383 -338.641782) (xy 89.419689 -338.625344)
			(xy 89.47485 -338.617036) (xy 89.502742 -338.616544) (xy 89.530074 -338.617024) (xy 89.584153 -338.624991)
			(xy 89.636488 -338.640777) (xy 89.685952 -338.664044) (xy 89.731485 -338.69429) (xy 89.772107 -338.730868)
			(xy 89.806946 -338.77299) (xy 89.821512 -338.796122) (xy 89.829441 -338.808342) (xy 89.850912 -338.82801)
			(xy 89.877063 -338.840814) (xy 89.905767 -338.845711) (xy 89.934684 -338.842302) (xy 89.948258 -338.837016)
			(xy 89.971464 -338.827517) (xy 90.019799 -338.814169) (xy 90.06949 -338.807445) (xy 90.094562 -338.807044)
			(xy 90.119632 -338.807458) (xy 90.169315 -338.814212) (xy 90.217649 -338.827548) (xy 90.240866 -338.837016)
			(xy 90.254444 -338.84226) (xy 90.283344 -338.845625) (xy 90.312022 -338.840714) (xy 90.338156 -338.827926)
			(xy 90.359631 -338.808296) (xy 90.367612 -338.796122) (xy 90.382181 -338.772991) (xy 90.417024 -338.73087)
			(xy 90.457647 -338.694291) (xy 90.503178 -338.66404) (xy 90.55264 -338.640764) (xy 90.604971 -338.624964)
			(xy 90.65905 -338.616978) (xy 90.713714 -338.616978) (xy 90.767793 -338.624964) (xy 90.820124 -338.640764)
			(xy 90.869586 -338.66404) (xy 90.915117 -338.694291) (xy 90.95574 -338.73087) (xy 90.990583 -338.772991)
			(xy 91.005152 -338.796122) (xy 91.013043 -338.808369) (xy 91.034524 -338.828038) (xy 91.060686 -338.840838)
			(xy 91.089398 -338.845727) (xy 91.118322 -338.842308) (xy 91.131898 -338.837016) (xy 91.155111 -338.827536)
			(xy 91.203442 -338.814181) (xy 91.253131 -338.807449) (xy 91.278202 -338.807044) (xy 91.30584 -338.807554)
			(xy 91.360507 -338.815747) (xy 91.413365 -338.831923) (xy 91.463254 -338.855727) (xy 91.509081 -338.886638)
			(xy 91.549841 -338.923978) (xy 91.584639 -338.966928) (xy 91.612713 -339.014545) (xy 91.633448 -339.065787)
			(xy 91.640406 -339.09254) (xy 91.644031 -339.105642) (xy 91.657168 -339.129428) (xy 91.676113 -339.148908)
			(xy 91.699525 -339.162702) (xy 91.725746 -339.169834) (xy 91.752919 -339.169798) (xy 91.779121 -339.162598)
			(xy 91.791028 -339.15604) (xy 91.813174 -339.143407) (xy 91.860126 -339.123531) (xy 91.909309 -339.110095)
			(xy 91.959845 -339.103339) (xy 91.985338 -339.102954) (xy 91.993466 -339.102954) (xy 92.008325 -339.102719)
			(xy 92.036942 -339.094758) (xy 92.062067 -339.078913) (xy 92.081582 -339.056521) (xy 92.093844 -339.029466)
			(xy 92.096336 -339.014816) (xy 92.100451 -338.987679) (xy 92.115458 -338.934885) (xy 92.137872 -338.884785)
			(xy 92.167232 -338.838412) (xy 92.202933 -338.796724) (xy 92.244237 -338.76058) (xy 92.290293 -338.730725)
			(xy 92.34015 -338.707776) (xy 92.392781 -338.692205) (xy 92.447099 -338.684334) (xy 92.474542 -338.683854)
			(xy 92.501793 -338.684339) (xy 92.555738 -338.6921) (xy 92.608031 -338.707458) (xy 92.657606 -338.730102)
			(xy 92.703454 -338.759569) (xy 92.744643 -338.79526) (xy 92.780334 -338.836449) (xy 92.8098 -338.882298)
			(xy 92.832443 -338.931873) (xy 92.847801 -338.984166) (xy 92.855562 -339.038111) (xy 92.85605 -339.065362)
			(xy 92.855523 -339.093963) (xy 92.846994 -339.150525) (xy 92.83012 -339.205182) (xy 92.80528 -339.256709)
			(xy 92.77303 -339.303952) (xy 92.734092 -339.345855) (xy 92.712032 -339.364066) (xy 92.701416 -339.373139)
			(xy 92.685125 -339.395806) (xy 92.675581 -339.422039) (xy 92.6735 -339.449875) (xy 92.679035 -339.477235)
			(xy 92.691773 -339.502074) (xy 92.710763 -339.522534) (xy 92.722446 -339.530182) (xy 92.746065 -339.545126)
			(xy 92.789079 -339.580814) (xy 92.826427 -339.622394) (xy 92.857311 -339.668977) (xy 92.881071 -339.719566)
			(xy 92.897198 -339.773079) (xy 92.905347 -339.828373) (xy 92.905834 -339.856318) (xy 92.905414 -339.882211)
			(xy 92.898413 -339.933522) (xy 92.884529 -339.983413) (xy 92.864018 -340.030964) (xy 92.837257 -340.075301)
			(xy 92.80474 -340.115605) (xy 92.7862 -340.133686) (xy 92.776099 -340.143826) (xy 92.761486 -340.16842)
			(xy 92.754279 -340.196106) (xy 92.755045 -340.224704) (xy 92.763725 -340.251964) (xy 92.779634 -340.27574)
			(xy 92.790264 -340.285324) (xy 92.811084 -340.303523) (xy 92.847757 -340.344909) (xy 92.878062 -340.391161)
			(xy 92.901364 -340.441308) (xy 92.917173 -340.494297) (xy 92.925157 -340.549014) (xy 92.925646 -340.576662)
			(xy 92.925087 -340.603911) (xy 92.917336 -340.657854) (xy 92.901988 -340.710145) (xy 92.879354 -340.759719)
			(xy 92.849895 -340.805568) (xy 92.814211 -340.846757) (xy 92.773029 -340.88245) (xy 92.727186 -340.911917)
			(xy 92.677616 -340.934561) (xy 92.625328 -340.94992) (xy 92.571386 -340.957681) (xy 92.544138 -340.95817)
			(xy 92.515061 -340.957651) (xy 92.45758 -340.948831) (xy 92.402103 -340.931388) (xy 92.349916 -340.905728)
			(xy 92.302229 -340.872445) (xy 92.260145 -340.83231) (xy 92.22464 -340.786252) (xy 92.196536 -340.73534)
			(xy 92.185998 -340.708234) (xy 92.180456 -340.694696) (xy 92.162994 -340.671244) (xy 92.1396 -340.653705)
			(xy 92.112194 -340.643518) (xy 92.083024 -340.641518) (xy 92.06865 -340.644226) (xy 92.048216 -340.648497)
			(xy 92.00672 -340.653077) (xy 91.985846 -340.65337) (xy 91.985338 -340.65337) (xy 91.971122 -340.65321)
			(xy 91.942772 -340.65105) (xy 91.928696 -340.649052) (xy 91.913365 -340.647367) (xy 91.882917 -340.652173)
			(xy 91.855285 -340.665837) (xy 91.832982 -340.687116) (xy 91.818036 -340.714076) (xy 91.814396 -340.729062)
			(xy 91.807912 -340.757296) (xy 91.787671 -340.811571) (xy 91.759458 -340.862163) (xy 91.723922 -340.907908)
			(xy 91.68188 -340.947757) (xy 91.634297 -340.980792) (xy 91.582268 -341.006255) (xy 91.526987 -341.023561)
			(xy 91.469725 -341.032311) (xy 91.440762 -341.032846) (xy 91.413512 -341.032358) (xy 91.359566 -341.024597)
			(xy 91.307274 -341.009239) (xy 91.257699 -340.986596) (xy 91.21185 -340.957129) (xy 91.170662 -340.921438)
			(xy 91.134971 -340.88025) (xy 91.105504 -340.834401) (xy 91.082861 -340.784826) (xy 91.067503 -340.732534)
			(xy 91.059742 -340.678588) (xy 91.059254 -340.651338) (xy 91.059727 -340.623764) (xy 91.067675 -340.56919)
			(xy 91.083398 -340.51633) (xy 91.106566 -340.466283) (xy 91.136698 -340.420094) (xy 91.173166 -340.378723)
			(xy 91.193874 -340.360508) (xy 91.204735 -340.350572) (xy 91.220813 -340.325933) (xy 91.229203 -340.297735)
			(xy 91.22921 -340.268314) (xy 91.220833 -340.240112) (xy 91.204768 -340.215465) (xy 91.193874 -340.205568)
			(xy 91.173139 -340.187383) (xy 91.136672 -340.146008) (xy 91.106543 -340.099812) (xy 91.083382 -340.049759)
			(xy 91.06767 -339.996893) (xy 91.059736 -339.942314) (xy 91.059254 -339.914738) (xy 91.059701 -339.888237)
			(xy 91.06705 -339.835746) (xy 91.081596 -339.784778) (xy 91.10306 -339.736316) (xy 91.131029 -339.691293)
			(xy 91.147646 -339.670644) (xy 91.157095 -339.658503) (xy 91.168883 -339.630101) (xy 91.171706 -339.59948)
			(xy 91.165308 -339.569401) (xy 91.150267 -339.542579) (xy 91.127939 -339.521434) (xy 91.114372 -339.51418)
			(xy 91.090684 -339.502075) (xy 91.046702 -339.472154) (xy 91.00742 -339.436284) (xy 90.973636 -339.395194)
			(xy 90.959432 -339.372702) (xy 90.951551 -339.360448) (xy 90.930068 -339.340776) (xy 90.903903 -339.327975)
			(xy 90.875188 -339.323088) (xy 90.846262 -339.326513) (xy 90.832686 -339.331808) (xy 90.809475 -339.341295)
			(xy 90.761143 -339.354647) (xy 90.711454 -339.361376) (xy 90.686382 -339.36178) (xy 90.661313 -339.361349)
			(xy 90.61163 -339.354603) (xy 90.563296 -339.341273) (xy 90.540078 -339.331808) (xy 90.526487 -339.3266)
			(xy 90.497593 -339.323225) (xy 90.468919 -339.328125) (xy 90.442786 -339.340906) (xy 90.421312 -339.36053)
			(xy 90.413332 -339.372702) (xy 90.398763 -339.395833) (xy 90.36392 -339.437954) (xy 90.323297 -339.474533)
			(xy 90.277766 -339.504784) (xy 90.228304 -339.52806) (xy 90.175973 -339.54386) (xy 90.121894 -339.551846)
			(xy 90.06723 -339.551846) (xy 90.013151 -339.54386) (xy 89.96082 -339.52806) (xy 89.911358 -339.504784)
			(xy 89.865827 -339.474533) (xy 89.825204 -339.437954) (xy 89.790361 -339.395833) (xy 89.775792 -339.372702)
			(xy 89.767854 -339.360488) (xy 89.746387 -339.340817) (xy 89.720237 -339.328011) (xy 89.691536 -339.323113)
			(xy 89.662619 -339.326522) (xy 89.649046 -339.331808) (xy 89.62584 -339.341307) (xy 89.577505 -339.354654)
			(xy 89.527814 -339.361379) (xy 89.502742 -339.36178) (xy 89.47485 -339.361364) (xy 89.419689 -339.353056)
			(xy 89.366383 -339.336618) (xy 89.316122 -339.312419) (xy 89.27003 -339.280998) (xy 89.229135 -339.243058)
			(xy 89.194353 -339.199447) (xy 89.16646 -339.151138) (xy 89.146078 -339.099212) (xy 89.133664 -339.044827)
			(xy 89.129495 -338.9892) (xy 86.491668 -338.9892) (xy 86.483745 -339.000105) (xy 86.466426 -339.018118)
			(xy 85.984334 -339.499956) (xy 85.974128 -339.510911) (xy 85.960008 -339.537297) (xy 85.954138 -339.566642)
			(xy 85.95702 -339.596429) (xy 85.968408 -339.624104) (xy 85.987324 -339.647294) (xy 86.012147 -339.664009)
			(xy 86.040748 -339.672817) (xy 86.055708 -339.673438) (xy 86.082874 -339.674047) (xy 86.136623 -339.682012)
			(xy 86.188699 -339.697524) (xy 86.238046 -339.720268) (xy 86.283667 -339.749784) (xy 86.324637 -339.785475)
			(xy 86.360129 -339.826619) (xy 86.389423 -339.872383) (xy 86.411927 -339.92184) (xy 86.427185 -339.97399)
			(xy 86.434889 -340.027778) (xy 86.435438 -340.054946) (xy 86.434949 -340.082196) (xy 86.427187 -340.13614)
			(xy 86.411829 -340.188431) (xy 86.389185 -340.238005) (xy 86.359718 -340.283851) (xy 86.324027 -340.325038)
			(xy 86.282838 -340.360728) (xy 86.23699 -340.390193) (xy 86.187416 -340.412834) (xy 86.135125 -340.428191)
			(xy 86.08118 -340.43595) (xy 86.05393 -340.436454) (xy 86.026757 -340.435976) (xy 85.97296 -340.428269)
			(xy 85.920801 -340.413007) (xy 85.871335 -340.390498) (xy 85.825564 -340.361198) (xy 85.784413 -340.3257)
			(xy 85.748715 -340.284722) (xy 85.719193 -340.239094) (xy 85.696444 -340.189738) (xy 85.680929 -340.137654)
			(xy 85.67296 -340.083895) (xy 85.672422 -340.056724) (xy 85.671811 -340.041771) (xy 85.662989 -340.013191)
			(xy 85.646269 -339.988388) (xy 85.623084 -339.969489) (xy 85.595421 -339.958112) (xy 85.565649 -339.955232)
			(xy 85.536317 -339.961096) (xy 85.50994 -339.9752) (xy 85.49894 -339.98535) (xy 85.485224 -339.999066)
			(xy 85.375496 -340.10854) (xy 85.375496 -340.595966) (xy 85.46465 -340.684866) (xy 85.47862 -340.688422)
			(xy 85.506026 -340.69552) (xy 85.558523 -340.716709) (xy 85.607308 -340.74543) (xy 85.651309 -340.78105)
			(xy 85.689558 -340.822787) (xy 85.721213 -340.869721) (xy 85.745578 -340.920821) (xy 85.762117 -340.974963)
			(xy 85.770466 -341.030956) (xy 85.770974 -341.059262) (xy 85.770513 -341.086516) (xy 85.76276 -341.140469)
			(xy 85.747407 -341.192769) (xy 85.724767 -341.242352) (xy 85.695299 -341.288208) (xy 85.659605 -341.329402)
			(xy 85.618411 -341.365097) (xy 85.572556 -341.394565) (xy 85.522973 -341.417206) (xy 85.470673 -341.43256)
			(xy 85.41672 -341.440313) (xy 85.389466 -341.44077) (xy 85.361174 -341.44026) (xy 85.305209 -341.431909)
			(xy 85.251092 -341.41538) (xy 85.200012 -341.391037) (xy 85.153089 -341.359413) (xy 85.111353 -341.321204)
			(xy 85.075722 -341.277247) (xy 85.046977 -341.228508) (xy 85.025748 -341.176056) (xy 85.018626 -341.14867)
			(xy 85.015324 -341.1347) (xy 84.832952 -340.952328) (xy 84.815668 -340.93433) (xy 84.78636 -340.893947)
			(xy 84.76372 -340.84948) (xy 84.748307 -340.802023) (xy 84.740496 -340.752741) (xy 84.739988 -340.727792)
			(xy 84.739988 -339.976714) (xy 84.740476 -339.951764) (xy 84.74828 -339.902479) (xy 84.763697 -339.855021)
			(xy 84.786349 -339.810558) (xy 84.815677 -339.770187) (xy 84.832952 -339.752178) (xy 85.923628 -338.661502)
			(xy 85.923628 -331.363574) (xy 85.345524 -330.78547) (xy 85.084412 -331.046582) (xy 85.102192 -331.064362)
			(xy 85.102192 -332.459838) (xy 84.349082 -333.212948) (xy 78.308962 -333.212948) (xy 78.292452 -333.229458)
			(xy 78.161896 -333.35976) (xy 78.161896 -338.671662) (xy 84.701634 -338.671662) (xy 84.70209 -338.644953)
			(xy 84.709554 -338.592057) (xy 84.724317 -338.540718) (xy 84.746092 -338.491938) (xy 84.774452 -338.446669)
			(xy 84.808845 -338.405794) (xy 84.848599 -338.370111) (xy 84.892938 -338.340318) (xy 84.916772 -338.328254)
			(xy 84.929938 -338.321345) (xy 84.951847 -338.301262) (xy 84.967048 -338.275722) (xy 84.974254 -338.246888)
			(xy 84.972856 -338.2172) (xy 84.962971 -338.189171) (xy 84.954618 -338.17687) (xy 84.937282 -338.152202)
			(xy 84.909765 -338.098558) (xy 84.891027 -338.041254) (xy 84.881534 -337.981717) (xy 84.880958 -337.951572)
			(xy 84.881444 -337.924321) (xy 84.8892 -337.870373) (xy 84.904555 -337.818078) (xy 84.927197 -337.768501)
			(xy 84.956663 -337.722651) (xy 84.992354 -337.68146) (xy 85.033545 -337.645769) (xy 85.079395 -337.616303)
			(xy 85.128972 -337.593661) (xy 85.181267 -337.578306) (xy 85.235215 -337.57055) (xy 85.289717 -337.57055)
			(xy 85.343665 -337.578306) (xy 85.39596 -337.593661) (xy 85.445537 -337.616303) (xy 85.491387 -337.645769)
			(xy 85.532578 -337.68146) (xy 85.568269 -337.722651) (xy 85.597735 -337.768501) (xy 85.620377 -337.818078)
			(xy 85.635732 -337.870373) (xy 85.643488 -337.924321) (xy 85.643974 -337.951572) (xy 85.643543 -337.978282)
			(xy 85.636074 -338.031178) (xy 85.621306 -338.082518) (xy 85.599528 -338.131298) (xy 85.571165 -338.176567)
			(xy 85.536769 -338.217441) (xy 85.497013 -338.253124) (xy 85.452672 -338.282917) (xy 85.428836 -338.29498)
			(xy 85.415646 -338.301849) (xy 85.393733 -338.32194) (xy 85.378532 -338.347489) (xy 85.371329 -338.376332)
			(xy 85.372735 -338.406028) (xy 85.382631 -338.434062) (xy 85.39099 -338.446364) (xy 85.408342 -338.471021)
			(xy 85.435855 -338.524669) (xy 85.454589 -338.581976) (xy 85.464077 -338.641516) (xy 85.46465 -338.671662)
			(xy 85.464164 -338.698913) (xy 85.456408 -338.752861) (xy 85.441053 -338.805156) (xy 85.418411 -338.854733)
			(xy 85.388945 -338.900583) (xy 85.353254 -338.941774) (xy 85.312063 -338.977465) (xy 85.266213 -339.006931)
			(xy 85.216636 -339.029573) (xy 85.164341 -339.044928) (xy 85.110393 -339.052684) (xy 85.055891 -339.052684)
			(xy 85.001943 -339.044928) (xy 84.949648 -339.029573) (xy 84.900071 -339.006931) (xy 84.854221 -338.977465)
			(xy 84.81303 -338.941774) (xy 84.777339 -338.900583) (xy 84.747873 -338.854733) (xy 84.725231 -338.805156)
			(xy 84.709876 -338.752861) (xy 84.70212 -338.698913) (xy 84.701634 -338.671662) (xy 78.161896 -338.671662)
			(xy 78.161896 -341.648542) (xy 86.478618 -341.648542) (xy 86.479196 -341.618855) (xy 86.488389 -341.560196)
			(xy 86.506559 -341.503671) (xy 86.533268 -341.450643) (xy 86.56787 -341.402394) (xy 86.609531 -341.360088)
			(xy 86.63305 -341.341964) (xy 86.643624 -341.333501) (xy 86.660324 -341.312195) (xy 86.670839 -341.28725)
			(xy 86.674432 -341.260418) (xy 86.670849 -341.233585) (xy 86.660342 -341.208636) (xy 86.64365 -341.187324)
			(xy 86.63305 -341.178896) (xy 86.609527 -341.160776) (xy 86.56787 -341.118467) (xy 86.533268 -341.070217)
			(xy 86.506558 -341.017189) (xy 86.488384 -340.960663) (xy 86.479184 -340.902005) (xy 86.478618 -340.872318)
			(xy 86.479104 -340.845067) (xy 86.48686 -340.791119) (xy 86.502215 -340.738824) (xy 86.524857 -340.689247)
			(xy 86.554323 -340.643397) (xy 86.590014 -340.602206) (xy 86.631205 -340.566515) (xy 86.677055 -340.537049)
			(xy 86.726632 -340.514407) (xy 86.778927 -340.499052) (xy 86.832875 -340.491296) (xy 86.887377 -340.491296)
			(xy 86.941325 -340.499052) (xy 86.99362 -340.514407) (xy 87.043197 -340.537049) (xy 87.089047 -340.566515)
			(xy 87.130238 -340.602206) (xy 87.165929 -340.643397) (xy 87.195395 -340.689247) (xy 87.218037 -340.738824)
			(xy 87.233392 -340.791119) (xy 87.241148 -340.845067) (xy 87.241634 -340.872318) (xy 87.241119 -340.902008)
			(xy 87.231915 -340.96067) (xy 87.213734 -341.017198) (xy 87.187013 -341.070226) (xy 87.174939 -341.087056)
			(xy 87.495025 -341.087056) (xy 87.495025 -341.032544) (xy 87.502783 -340.978586) (xy 87.518142 -340.926282)
			(xy 87.540788 -340.876696) (xy 87.570261 -340.830838) (xy 87.60596 -340.789642) (xy 87.647159 -340.753945)
			(xy 87.693019 -340.724476) (xy 87.742607 -340.701833) (xy 87.794912 -340.686478) (xy 87.84887 -340.678723)
			(xy 87.876126 -340.678262) (xy 87.87638 -340.678262) (xy 87.901584 -340.678667) (xy 87.951551 -340.685305)
			(xy 88.000206 -340.698479) (xy 88.046696 -340.717961) (xy 88.068658 -340.730332) (xy 88.081597 -340.737424)
			(xy 88.110245 -340.744453) (xy 88.139706 -340.743) (xy 88.167523 -340.733188) (xy 88.191376 -340.715834)
			(xy 88.209273 -340.692386) (xy 88.214962 -340.67877) (xy 88.225657 -340.651993) (xy 88.253946 -340.601753)
			(xy 88.289477 -340.556344) (xy 88.331439 -340.516802) (xy 88.378876 -340.484029) (xy 88.430707 -340.458771)
			(xy 88.48575 -340.441604) (xy 88.542749 -340.43292) (xy 88.571578 -340.43239) (xy 88.59883 -340.432876)
			(xy 88.65278 -340.44063) (xy 88.705078 -340.455983) (xy 88.754657 -340.478623) (xy 88.800511 -340.508088)
			(xy 88.841703 -340.54378) (xy 88.877397 -340.58497) (xy 88.906866 -340.630821) (xy 88.929509 -340.6804)
			(xy 88.944865 -340.732696) (xy 88.952623 -340.786646) (xy 88.953086 -340.813898) (xy 88.953086 -340.814152)
			(xy 88.952517 -340.843991) (xy 88.943197 -340.902937) (xy 88.934544 -340.9315) (xy 88.930537 -340.945417)
			(xy 88.929613 -340.974348) (xy 88.936868 -341.00237) (xy 88.951716 -341.027217) (xy 88.972956 -341.046881)
			(xy 88.998872 -341.059774) (xy 89.01303 -341.062818) (xy 89.039103 -341.067986) (xy 89.089607 -341.084557)
			(xy 89.13732 -341.107981) (xy 89.181318 -341.137803) (xy 89.220748 -341.173446) (xy 89.254847 -341.214219)
			(xy 89.282954 -341.259332) (xy 89.304524 -341.307912) (xy 89.319139 -341.359015) (xy 89.326516 -341.411654)
			(xy 89.326974 -341.43823) (xy 89.325704 -341.469218) (xy 89.323672 -341.49284) (xy 90.71991 -342.888824)
			(xy 94.007432 -342.888824) (xy 94.029928 -342.889393) (xy 94.074042 -342.898249) (xy 94.115583 -342.915537)
			(xy 94.152955 -342.940592) (xy 94.16923 -342.956134) (xy 95.284728 -344.071632) (xy 96.449892 -344.071632)
			(xy 96.449892 -343.986936) (xy 96.457943 -343.902622) (xy 96.473972 -343.819456) (xy 96.497833 -343.738189)
			(xy 96.529312 -343.659559) (xy 96.568123 -343.584278) (xy 96.613913 -343.513026) (xy 96.666269 -343.44645)
			(xy 96.724717 -343.385152) (xy 96.788727 -343.329687) (xy 96.857719 -343.280558) (xy 96.931069 -343.238209)
			(xy 97.008112 -343.203025) (xy 97.088151 -343.175323) (xy 97.17046 -343.155355) (xy 97.254295 -343.143302)
			(xy 97.338896 -343.139272) (xy 97.423497 -343.143302) (xy 97.507332 -343.155355) (xy 97.589641 -343.175323)
			(xy 97.66968 -343.203025) (xy 97.746723 -343.238209) (xy 97.820073 -343.280558) (xy 97.889065 -343.329687)
			(xy 97.953075 -343.385152) (xy 98.011523 -343.44645) (xy 98.063879 -343.513026) (xy 98.109669 -343.584278)
			(xy 98.14848 -343.659559) (xy 98.179959 -343.738189) (xy 98.20382 -343.819456) (xy 98.219849 -343.902622)
			(xy 98.2279 -343.986936) (xy 98.228404 -344.029284) (xy 98.974405 -344.029284) (xy 98.978441 -343.945837)
			(xy 98.990513 -343.863169) (xy 99.010506 -343.782052) (xy 99.038235 -343.703243) (xy 99.073441 -343.627478)
			(xy 99.115795 -343.555465) (xy 99.164901 -343.487876) (xy 99.220302 -343.425342) (xy 99.281479 -343.368447)
			(xy 99.347862 -343.317721) (xy 99.41883 -343.27364) (xy 99.493722 -343.236614) (xy 99.571838 -343.206988)
			(xy 99.652448 -343.18504) (xy 99.7348 -343.170975) (xy 99.818126 -343.164923) (xy 99.901646 -343.166942)
			(xy 99.984582 -343.177012) (xy 100.066158 -343.19504) (xy 100.145614 -343.220857) (xy 100.222207 -343.254222)
			(xy 100.295223 -343.294823) (xy 100.363979 -343.342282) (xy 100.427833 -343.396155) (xy 100.48619 -343.45594)
			(xy 100.538505 -343.521077) (xy 100.584288 -343.59096) (xy 100.623113 -343.664935) (xy 100.654618 -343.742312)
			(xy 100.678507 -343.822369) (xy 100.694558 -343.904357) (xy 100.702621 -343.987512) (xy 100.703126 -344.029284)
			(xy 100.702621 -344.071056) (xy 100.694558 -344.154211) (xy 100.678507 -344.236199) (xy 100.654618 -344.316256)
			(xy 100.623113 -344.393633) (xy 100.584288 -344.467608) (xy 100.538505 -344.537491) (xy 100.48619 -344.602628)
			(xy 100.427833 -344.662413) (xy 100.363979 -344.716286) (xy 100.295223 -344.763745) (xy 100.222207 -344.804346)
			(xy 100.145614 -344.837711) (xy 100.066158 -344.863528) (xy 99.984582 -344.881556) (xy 99.901646 -344.891626)
			(xy 99.818126 -344.893645) (xy 99.7348 -344.887593) (xy 99.652448 -344.873528) (xy 99.571838 -344.85158)
			(xy 99.493722 -344.821954) (xy 99.41883 -344.784928) (xy 99.347862 -344.740847) (xy 99.281479 -344.690121)
			(xy 99.220302 -344.633226) (xy 99.164901 -344.570692) (xy 99.115795 -344.503103) (xy 99.073441 -344.43109)
			(xy 99.038235 -344.355325) (xy 99.010506 -344.276516) (xy 98.990513 -344.195399) (xy 98.978441 -344.112731)
			(xy 98.974405 -344.029284) (xy 98.228404 -344.029284) (xy 98.2279 -344.071632) (xy 98.219849 -344.155946)
			(xy 98.20382 -344.239112) (xy 98.179959 -344.320379) (xy 98.14848 -344.399009) (xy 98.109669 -344.47429)
			(xy 98.063879 -344.545542) (xy 98.011523 -344.612118) (xy 97.953075 -344.673416) (xy 97.889065 -344.728881)
			(xy 97.820073 -344.77801) (xy 97.746723 -344.820359) (xy 97.66968 -344.855543) (xy 97.589641 -344.883245)
			(xy 97.507332 -344.903213) (xy 97.423497 -344.915266) (xy 97.338896 -344.919297) (xy 97.254295 -344.915266)
			(xy 97.17046 -344.903213) (xy 97.088151 -344.883245) (xy 97.008112 -344.855543) (xy 96.931069 -344.820359)
			(xy 96.857719 -344.77801) (xy 96.788727 -344.728881) (xy 96.724717 -344.673416) (xy 96.666269 -344.612118)
			(xy 96.613913 -344.545542) (xy 96.568123 -344.47429) (xy 96.529312 -344.399009) (xy 96.497833 -344.320379)
			(xy 96.473972 -344.239112) (xy 96.457943 -344.155946) (xy 96.449892 -344.071632) (xy 95.284728 -344.071632)
			(xy 99.539044 -348.325948) (xy 99.554588 -348.342208) (xy 99.579592 -348.379595) (xy 99.596813 -348.421144)
			(xy 99.605588 -348.465257) (xy 99.6061 -348.487746) (xy 99.6061 -354.257864) (xy 99.605542 -354.280347)
			(xy 99.596749 -354.324445) (xy 99.579531 -354.365984) (xy 99.55455 -354.403372) (xy 99.539044 -354.419662)
			(xy 98.910797 -355.048058) (xy 99.42652 -355.048058) (xy 99.430591 -354.992436) (xy 99.442717 -354.937999)
			(xy 99.46264 -354.885908) (xy 99.489936 -354.837273) (xy 99.524022 -354.79313) (xy 99.564171 -354.754421)
			(xy 99.609529 -354.72197) (xy 99.659129 -354.696469) (xy 99.711913 -354.678462) (xy 99.766756 -354.668332)
			(xy 99.82249 -354.666295) (xy 99.877927 -354.672395) (xy 99.931884 -354.686501) (xy 99.983213 -354.708313)
			(xy 100.030819 -354.737367) (xy 100.073687 -354.773042) (xy 100.110904 -354.814579) (xy 100.141677 -354.861092)
			(xy 100.165349 -354.911589) (xy 100.181417 -354.964996) (xy 100.189537 -355.020172) (xy 100.190046 -355.048058)
			(xy 100.189537 -355.075944) (xy 100.181417 -355.13112) (xy 100.165349 -355.184527) (xy 100.141677 -355.235024)
			(xy 100.110904 -355.281537) (xy 100.073687 -355.323074) (xy 100.030819 -355.358749) (xy 99.983213 -355.387803)
			(xy 99.931884 -355.409615) (xy 99.877927 -355.423721) (xy 99.82249 -355.429821) (xy 99.766756 -355.427784)
			(xy 99.711913 -355.417654) (xy 99.659129 -355.399647) (xy 99.609529 -355.374146) (xy 99.564171 -355.341695)
			(xy 99.524022 -355.302986) (xy 99.489936 -355.258843) (xy 99.46264 -355.210208) (xy 99.442717 -355.158117)
			(xy 99.430591 -355.10368) (xy 99.42652 -355.048058) (xy 98.910797 -355.048058) (xy 98.468688 -355.490272)
			(xy 98.468688 -356.63759) (xy 98.915218 -356.63759) (xy 98.919289 -356.581968) (xy 98.931415 -356.527531)
			(xy 98.951338 -356.47544) (xy 98.978634 -356.426805) (xy 99.01272 -356.382662) (xy 99.052869 -356.343953)
			(xy 99.098227 -356.311502) (xy 99.147827 -356.286001) (xy 99.200611 -356.267994) (xy 99.255454 -356.257864)
			(xy 99.311188 -356.255827) (xy 99.366625 -356.261927) (xy 99.420582 -356.276033) (xy 99.471911 -356.297845)
			(xy 99.519517 -356.326899) (xy 99.562385 -356.362574) (xy 99.599602 -356.404111) (xy 99.630375 -356.450624)
			(xy 99.654047 -356.501121) (xy 99.670115 -356.554528) (xy 99.678235 -356.609704) (xy 99.678744 -356.63759)
			(xy 99.678235 -356.665476) (xy 99.670115 -356.720652) (xy 99.654047 -356.774059) (xy 99.630375 -356.824556)
			(xy 99.599602 -356.871069) (xy 99.562385 -356.912606) (xy 99.519517 -356.948281) (xy 99.471911 -356.977335)
			(xy 99.420582 -356.999147) (xy 99.366625 -357.013253) (xy 99.311188 -357.019353) (xy 99.255454 -357.017316)
			(xy 99.200611 -357.007186) (xy 99.147827 -356.989179) (xy 99.098227 -356.963678) (xy 99.052869 -356.931227)
			(xy 99.01272 -356.892518) (xy 98.978634 -356.848375) (xy 98.951338 -356.79974) (xy 98.931415 -356.747649)
			(xy 98.919289 -356.693212) (xy 98.915218 -356.63759) (xy 98.468688 -356.63759) (xy 98.468688 -357.53167)
			(xy 98.915218 -357.53167) (xy 98.919289 -357.476048) (xy 98.931415 -357.421611) (xy 98.951338 -357.36952)
			(xy 98.978634 -357.320885) (xy 99.01272 -357.276742) (xy 99.052869 -357.238033) (xy 99.098227 -357.205582)
			(xy 99.147827 -357.180081) (xy 99.200611 -357.162074) (xy 99.255454 -357.151944) (xy 99.311188 -357.149907)
			(xy 99.366625 -357.156007) (xy 99.420582 -357.170113) (xy 99.471911 -357.191925) (xy 99.519517 -357.220979)
			(xy 99.562385 -357.256654) (xy 99.599602 -357.298191) (xy 99.630375 -357.344704) (xy 99.654047 -357.395201)
			(xy 99.670115 -357.448608) (xy 99.678235 -357.503784) (xy 99.678744 -357.53167) (xy 99.678235 -357.559556)
			(xy 99.670115 -357.614732) (xy 99.654047 -357.668139) (xy 99.630375 -357.718636) (xy 99.599602 -357.765149)
			(xy 99.562385 -357.806686) (xy 99.519517 -357.842361) (xy 99.471911 -357.871415) (xy 99.420582 -357.893227)
			(xy 99.366625 -357.907333) (xy 99.311188 -357.913433) (xy 99.255454 -357.911396) (xy 99.200611 -357.901266)
			(xy 99.147827 -357.883259) (xy 99.098227 -357.857758) (xy 99.052869 -357.825307) (xy 99.01272 -357.786598)
			(xy 98.978634 -357.742455) (xy 98.951338 -357.69382) (xy 98.931415 -357.641729) (xy 98.919289 -357.587292)
			(xy 98.915218 -357.53167) (xy 98.468688 -357.53167) (xy 98.468688 -358.899714) (xy 98.910138 -358.899714)
			(xy 98.914209 -358.844092) (xy 98.926335 -358.789655) (xy 98.946258 -358.737564) (xy 98.973554 -358.688929)
			(xy 99.00764 -358.644786) (xy 99.047789 -358.606077) (xy 99.093147 -358.573626) (xy 99.142747 -358.548125)
			(xy 99.195531 -358.530118) (xy 99.250374 -358.519988) (xy 99.306108 -358.517951) (xy 99.361545 -358.524051)
			(xy 99.415502 -358.538157) (xy 99.466831 -358.559969) (xy 99.514437 -358.589023) (xy 99.557305 -358.624698)
			(xy 99.594522 -358.666235) (xy 99.625295 -358.712748) (xy 99.648967 -358.763245) (xy 99.665035 -358.816652)
			(xy 99.673155 -358.871828) (xy 99.673664 -358.899714) (xy 99.673155 -358.9276) (xy 99.665035 -358.982776)
			(xy 99.648967 -359.036183) (xy 99.625295 -359.08668) (xy 99.594522 -359.133193) (xy 99.557305 -359.17473)
			(xy 99.514437 -359.210405) (xy 99.466831 -359.239459) (xy 99.415502 -359.261271) (xy 99.361545 -359.275377)
			(xy 99.306108 -359.281477) (xy 99.250374 -359.27944) (xy 99.195531 -359.26931) (xy 99.142747 -359.251303)
			(xy 99.093147 -359.225802) (xy 99.047789 -359.193351) (xy 99.00764 -359.154642) (xy 98.973554 -359.110499)
			(xy 98.946258 -359.061864) (xy 98.926335 -359.009773) (xy 98.914209 -358.955336) (xy 98.910138 -358.899714)
			(xy 98.468688 -358.899714) (xy 98.468688 -360.184446) (xy 98.714052 -360.42981) (xy 99.3173 -360.42981)
			(xy 99.321371 -360.374188) (xy 99.333497 -360.319751) (xy 99.35342 -360.26766) (xy 99.380716 -360.219025)
			(xy 99.414802 -360.174882) (xy 99.454951 -360.136173) (xy 99.500309 -360.103722) (xy 99.549909 -360.078221)
			(xy 99.602693 -360.060214) (xy 99.657536 -360.050084) (xy 99.71327 -360.048047) (xy 99.768707 -360.054147)
			(xy 99.822664 -360.068253) (xy 99.873993 -360.090065) (xy 99.921599 -360.119119) (xy 99.964467 -360.154794)
			(xy 100.001684 -360.196331) (xy 100.032457 -360.242844) (xy 100.056129 -360.293341) (xy 100.072197 -360.346748)
			(xy 100.080317 -360.401924) (xy 100.080826 -360.42981) (xy 100.080317 -360.457696) (xy 100.072197 -360.512872)
			(xy 100.056129 -360.566279) (xy 100.032457 -360.616776) (xy 100.001684 -360.663289) (xy 99.964467 -360.704826)
			(xy 99.921599 -360.740501) (xy 99.873993 -360.769555) (xy 99.822664 -360.791367) (xy 99.768707 -360.805473)
			(xy 99.71327 -360.811573) (xy 99.657536 -360.809536) (xy 99.602693 -360.799406) (xy 99.549909 -360.781399)
			(xy 99.500309 -360.755898) (xy 99.454951 -360.723447) (xy 99.414802 -360.684738) (xy 99.380716 -360.640595)
			(xy 99.35342 -360.59196) (xy 99.333497 -360.539869) (xy 99.321371 -360.485432) (xy 99.3173 -360.42981)
			(xy 98.714052 -360.42981) (xy 99.350322 -361.06608) (xy 99.83216 -361.06608) (xy 99.854655 -361.066677)
			(xy 99.898768 -361.075522) (xy 99.94031 -361.092801) (xy 99.977683 -361.11785) (xy 99.993958 -361.13339)
			(xy 100.373688 -361.51312) (xy 100.389226 -361.529386) (xy 100.414229 -361.566771) (xy 100.431451 -361.608319)
			(xy 100.44023 -361.65243) (xy 100.440744 -361.674918) (xy 100.440744 -362.212636) (xy 102.246684 -364.018576)
			(xy 103.105204 -364.018576) (xy 103.127686 -364.019149) (xy 103.171785 -364.027934) (xy 103.213325 -364.045147)
			(xy 103.250713 -364.070126) (xy 103.267002 -364.085632) (xy 104.259126 -365.077756) (xy 106.989372 -365.077756)
			(xy 106.999786 -365.040164) (xy 107.007517 -365.013586) (xy 107.029599 -364.962832) (xy 107.058784 -364.915802)
			(xy 107.09446 -364.873484) (xy 107.135877 -364.836765) (xy 107.182166 -364.806418) (xy 107.232355 -364.78308)
			(xy 107.28539 -364.76724) (xy 107.340157 -364.759231) (xy 107.367832 -364.758732) (xy 107.395085 -364.75914)
			(xy 107.449035 -364.766901) (xy 107.501331 -364.782261) (xy 107.550909 -364.804906) (xy 107.596761 -364.834376)
			(xy 107.637951 -364.870071) (xy 107.673643 -364.911265) (xy 107.692491 -364.940596) (xy 110.691928 -364.940596)
			(xy 110.695999 -364.884974) (xy 110.708125 -364.830537) (xy 110.728048 -364.778446) (xy 110.755344 -364.729811)
			(xy 110.78943 -364.685668) (xy 110.829579 -364.646959) (xy 110.874937 -364.614508) (xy 110.924537 -364.589007)
			(xy 110.977321 -364.571) (xy 111.032164 -364.56087) (xy 111.087898 -364.558833) (xy 111.143335 -364.564933)
			(xy 111.197292 -364.579039) (xy 111.248621 -364.600851) (xy 111.296227 -364.629905) (xy 111.339095 -364.66558)
			(xy 111.376312 -364.707117) (xy 111.407085 -364.75363) (xy 111.408762 -364.757208) (xy 112.321592 -364.757208)
			(xy 112.325663 -364.701586) (xy 112.337789 -364.647149) (xy 112.357712 -364.595058) (xy 112.385008 -364.546423)
			(xy 112.419094 -364.50228) (xy 112.459243 -364.463571) (xy 112.504601 -364.43112) (xy 112.554201 -364.405619)
			(xy 112.606985 -364.387612) (xy 112.661828 -364.377482) (xy 112.717562 -364.375445) (xy 112.772999 -364.381545)
			(xy 112.826956 -364.395651) (xy 112.878285 -364.417463) (xy 112.925891 -364.446517) (xy 112.968759 -364.482192)
			(xy 113.005976 -364.523729) (xy 113.036749 -364.570242) (xy 113.060421 -364.620739) (xy 113.076489 -364.674146)
			(xy 113.084609 -364.729322) (xy 113.085118 -364.757208) (xy 113.084609 -364.785094) (xy 113.076489 -364.84027)
			(xy 113.060421 -364.893677) (xy 113.036749 -364.944174) (xy 113.005976 -364.990687) (xy 112.968759 -365.032224)
			(xy 112.925891 -365.067899) (xy 112.878285 -365.096953) (xy 112.826956 -365.118765) (xy 112.772999 -365.132871)
			(xy 112.717562 -365.138971) (xy 112.661828 -365.136934) (xy 112.606985 -365.126804) (xy 112.554201 -365.108797)
			(xy 112.504601 -365.083296) (xy 112.459243 -365.050845) (xy 112.419094 -365.012136) (xy 112.385008 -364.967993)
			(xy 112.357712 -364.919358) (xy 112.337789 -364.867267) (xy 112.325663 -364.81283) (xy 112.321592 -364.757208)
			(xy 111.408762 -364.757208) (xy 111.430757 -364.804127) (xy 111.446825 -364.857534) (xy 111.454945 -364.91271)
			(xy 111.455454 -364.940596) (xy 111.454945 -364.968482) (xy 111.446825 -365.023658) (xy 111.430757 -365.077065)
			(xy 111.407085 -365.127562) (xy 111.376312 -365.174075) (xy 111.339095 -365.215612) (xy 111.296227 -365.251287)
			(xy 111.248621 -365.280341) (xy 111.197292 -365.302153) (xy 111.143335 -365.316259) (xy 111.087898 -365.322359)
			(xy 111.032164 -365.320322) (xy 110.977321 -365.310192) (xy 110.924537 -365.292185) (xy 110.874937 -365.266684)
			(xy 110.829579 -365.234233) (xy 110.78943 -365.195524) (xy 110.755344 -365.151381) (xy 110.728048 -365.102746)
			(xy 110.708125 -365.050655) (xy 110.695999 -364.996218) (xy 110.691928 -364.940596) (xy 107.692491 -364.940596)
			(xy 107.703109 -364.957119) (xy 107.725751 -365.006699) (xy 107.741106 -365.058997) (xy 107.748862 -365.112947)
			(xy 107.748862 -365.167453) (xy 107.741106 -365.221403) (xy 107.725751 -365.273701) (xy 107.703109 -365.323281)
			(xy 107.673643 -365.369135) (xy 107.637951 -365.410329) (xy 107.59676 -365.446024) (xy 107.550909 -365.475494)
			(xy 107.501331 -365.498139) (xy 107.449035 -365.513499) (xy 107.395085 -365.52126) (xy 107.367832 -365.521748)
			(xy 107.349876 -365.521515) (xy 107.314129 -365.518083) (xy 107.296458 -365.51489) (xy 107.27395 -365.524459)
			(xy 107.226165 -365.534835) (xy 107.201716 -365.535464) (xy 104.164384 -365.535464) (xy 104.141902 -365.534887)
			(xy 104.097805 -365.526101) (xy 104.056265 -365.508889) (xy 104.018876 -365.483912) (xy 104.002586 -365.468408)
			(xy 103.010462 -364.476284) (xy 102.151942 -364.476284) (xy 102.129459 -364.475726) (xy 102.085361 -364.466934)
			(xy 102.043822 -364.449716) (xy 102.006434 -364.424734) (xy 101.990144 -364.409228) (xy 100.050092 -362.469176)
			(xy 100.034566 -362.4529) (xy 100.009557 -362.41552) (xy 99.99233 -362.373975) (xy 99.98355 -362.329865)
			(xy 99.983036 -362.307378) (xy 99.983036 -361.76966) (xy 99.737418 -361.524296) (xy 99.25558 -361.524296)
			(xy 99.233085 -361.523714) (xy 99.188972 -361.514861) (xy 99.147431 -361.497577) (xy 99.110058 -361.472526)
			(xy 99.093782 -361.456986) (xy 98.077782 -360.440986) (xy 98.062191 -360.424752) (xy 98.037121 -360.387376)
			(xy 98.019838 -360.345821) (xy 98.011008 -360.30169) (xy 98.010472 -360.279188) (xy 98.010472 -355.39553)
			(xy 98.011065 -355.373035) (xy 98.019912 -355.328921) (xy 98.037192 -355.28738) (xy 98.062242 -355.250007)
			(xy 98.077782 -355.233732) (xy 99.148392 -354.163122) (xy 99.148392 -348.582488) (xy 93.91269 -343.34704)
			(xy 90.625168 -343.34704) (xy 90.602671 -343.346481) (xy 90.558556 -343.337623) (xy 90.517015 -343.320333)
			(xy 90.479644 -343.295274) (xy 90.46337 -343.27973) (xy 89.000076 -341.816436) (xy 88.976454 -341.818468)
			(xy 88.945466 -341.819738) (xy 88.918215 -341.819254) (xy 88.864269 -341.811494) (xy 88.811976 -341.796136)
			(xy 88.762401 -341.773493) (xy 88.716552 -341.744026) (xy 88.675363 -341.708334) (xy 88.639672 -341.667145)
			(xy 88.610205 -341.621296) (xy 88.587563 -341.57172) (xy 88.572206 -341.519427) (xy 88.564446 -341.465481)
			(xy 88.563958 -341.43823) (xy 88.563958 -341.437976) (xy 88.564536 -341.408137) (xy 88.57385 -341.349191)
			(xy 88.5825 -341.320628) (xy 88.586553 -341.306724) (xy 88.587459 -341.277789) (xy 88.580191 -341.249768)
			(xy 88.565335 -341.224921) (xy 88.544091 -341.205255) (xy 88.518173 -341.192358) (xy 88.504014 -341.18931)
			(xy 88.471175 -341.182725) (xy 88.408323 -341.159603) (xy 88.379046 -341.143336) (xy 88.366097 -341.136266)
			(xy 88.337454 -341.12924) (xy 88.307998 -341.130691) (xy 88.280185 -341.140499) (xy 88.256334 -341.157846)
			(xy 88.238434 -341.181286) (xy 88.232742 -341.194898) (xy 88.222026 -341.221666) (xy 88.193742 -341.271908)
			(xy 88.158215 -341.317317) (xy 88.116256 -341.356861) (xy 88.068821 -341.389635) (xy 88.016993 -341.414895)
			(xy 87.961952 -341.432062) (xy 87.904954 -341.440747) (xy 87.876126 -341.441278) (xy 87.84887 -341.440877)
			(xy 87.794912 -341.433122) (xy 87.742607 -341.417767) (xy 87.693019 -341.395124) (xy 87.647159 -341.365655)
			(xy 87.60596 -341.329958) (xy 87.570261 -341.288762) (xy 87.540788 -341.242904) (xy 87.518142 -341.193318)
			(xy 87.502783 -341.141014) (xy 87.495025 -341.087056) (xy 87.174939 -341.087056) (xy 87.152399 -341.118473)
			(xy 87.110727 -341.160775) (xy 87.087202 -341.178896) (xy 87.076564 -341.187287) (xy 87.059855 -341.208607)
			(xy 87.049338 -341.233569) (xy 87.045751 -341.260418) (xy 87.049347 -341.287266) (xy 87.059874 -341.312224)
			(xy 87.07659 -341.333538) (xy 87.087202 -341.341964) (xy 87.110696 -341.36012) (xy 87.152357 -341.40242)
			(xy 87.186963 -341.450663) (xy 87.213679 -341.503684) (xy 87.231859 -341.560203) (xy 87.241065 -341.618856)
			(xy 87.241634 -341.648542) (xy 87.241148 -341.675793) (xy 87.233392 -341.729741) (xy 87.218037 -341.782036)
			(xy 87.195395 -341.831613) (xy 87.165929 -341.877463) (xy 87.130238 -341.918654) (xy 87.089047 -341.954345)
			(xy 87.043197 -341.983811) (xy 86.99362 -342.006453) (xy 86.941325 -342.021808) (xy 86.887377 -342.029564)
			(xy 86.832875 -342.029564) (xy 86.778927 -342.021808) (xy 86.726632 -342.006453) (xy 86.677055 -341.983811)
			(xy 86.631205 -341.954345) (xy 86.590014 -341.918654) (xy 86.554323 -341.877463) (xy 86.524857 -341.831613)
			(xy 86.502215 -341.782036) (xy 86.48686 -341.729741) (xy 86.479104 -341.675793) (xy 86.478618 -341.648542)
			(xy 78.161896 -341.648542) (xy 78.161896 -341.79764) (xy 78.161437 -341.822593) (xy 78.153638 -341.871886)
			(xy 78.138224 -341.919352) (xy 78.115574 -341.963822) (xy 78.086246 -342.004201) (xy 78.068932 -342.022176)
			(xy 77.782674 -342.308434) (xy 77.390244 -342.701118) (xy 77.372258 -342.71847) (xy 77.331844 -342.747866)
			(xy 77.287325 -342.770571) (xy 77.2398 -342.786024) (xy 77.190441 -342.793843) (xy 77.165454 -342.794336)
			(xy 76.730352 -342.794336) (xy 76.340208 -343.18448) (xy 76.340208 -344.386662) (xy 76.764134 -344.386662)
			(xy 76.76463 -344.358787) (xy 76.772738 -344.30363) (xy 76.78879 -344.250241) (xy 76.812445 -344.199758)
			(xy 76.843197 -344.153257) (xy 76.861416 -344.132154) (xy 76.870999 -344.120785) (xy 76.883633 -344.093879)
			(xy 76.887962 -344.064472) (xy 76.883617 -344.035068) (xy 76.870968 -344.008169) (xy 76.861416 -343.996772)
			(xy 76.843231 -343.975642) (xy 76.812482 -343.929145) (xy 76.788826 -343.878668) (xy 76.772767 -343.825287)
			(xy 76.764646 -343.770136) (xy 76.764134 -343.742264) (xy 76.76462 -343.715013) (xy 76.772376 -343.661065)
			(xy 76.787731 -343.60877) (xy 76.810373 -343.559193) (xy 76.839839 -343.513343) (xy 76.87553 -343.472152)
			(xy 76.916721 -343.436461) (xy 76.962571 -343.406995) (xy 77.012148 -343.384353) (xy 77.064443 -343.368998)
			(xy 77.118391 -343.361242) (xy 77.172893 -343.361242) (xy 77.226841 -343.368998) (xy 77.279136 -343.384353)
			(xy 77.328713 -343.406995) (xy 77.374563 -343.436461) (xy 77.415754 -343.472152) (xy 77.451445 -343.513343)
			(xy 77.480911 -343.559193) (xy 77.503553 -343.60877) (xy 77.518908 -343.661065) (xy 77.526664 -343.715013)
			(xy 77.52715 -343.742264) (xy 77.526649 -343.770139) (xy 77.518539 -343.825295) (xy 77.502486 -343.878683)
			(xy 77.478834 -343.929165) (xy 77.448085 -343.975667) (xy 77.429868 -343.996772) (xy 77.420413 -344.008221)
			(xy 77.407861 -344.035111) (xy 77.403551 -344.064472) (xy 77.407845 -344.093836) (xy 77.420383 -344.120733)
			(xy 77.429868 -344.132154) (xy 77.448078 -344.153263) (xy 77.478821 -344.199767) (xy 77.50247 -344.250249)
			(xy 77.518524 -344.303635) (xy 77.52664 -344.358788) (xy 77.52715 -344.386662) (xy 77.526664 -344.413913)
			(xy 77.518908 -344.467861) (xy 77.503553 -344.520156) (xy 77.480911 -344.569733) (xy 77.451445 -344.615583)
			(xy 77.415754 -344.656774) (xy 77.374563 -344.692465) (xy 77.328713 -344.721931) (xy 77.279136 -344.744573)
			(xy 77.226841 -344.759928) (xy 77.172893 -344.767684) (xy 77.118391 -344.767684) (xy 77.064443 -344.759928)
			(xy 77.012148 -344.744573) (xy 76.962571 -344.721931) (xy 76.916721 -344.692465) (xy 76.87553 -344.656774)
			(xy 76.839839 -344.615583) (xy 76.810373 -344.569733) (xy 76.787731 -344.520156) (xy 76.772376 -344.467861)
			(xy 76.76462 -344.413913) (xy 76.764134 -344.386662) (xy 76.340208 -344.386662) (xy 76.340208 -344.7799)
			(xy 80.968987 -344.7799) (xy 80.973156 -344.724273) (xy 80.98557 -344.669888) (xy 81.005951 -344.617961)
			(xy 81.033844 -344.569652) (xy 81.068626 -344.526041) (xy 81.109519 -344.4881) (xy 81.155611 -344.456678)
			(xy 81.205871 -344.432478) (xy 81.259178 -344.416039) (xy 81.314338 -344.407729) (xy 81.34223 -344.407236)
			(xy 81.369561 -344.407729) (xy 81.42364 -344.415694) (xy 81.475974 -344.431479) (xy 81.525438 -344.454743)
			(xy 81.570971 -344.484988) (xy 81.611594 -344.521563) (xy 81.646434 -344.563683) (xy 81.661 -344.586814)
			(xy 81.668942 -344.599025) (xy 81.690409 -344.618694) (xy 81.716557 -344.631499) (xy 81.745257 -344.636399)
			(xy 81.774173 -344.632992) (xy 81.787746 -344.627708) (xy 81.810954 -344.618212) (xy 81.859288 -344.604863)
			(xy 81.908978 -344.598138) (xy 81.93405 -344.597736) (xy 81.95912 -344.598155) (xy 82.008803 -344.604906)
			(xy 82.057137 -344.618241) (xy 82.080354 -344.627708) (xy 82.093935 -344.632943) (xy 82.122834 -344.63631)
			(xy 82.151511 -344.631403) (xy 82.177645 -344.618617) (xy 82.199119 -344.598987) (xy 82.2071 -344.586814)
			(xy 82.221669 -344.563683) (xy 82.256512 -344.521562) (xy 82.297135 -344.484983) (xy 82.342666 -344.454732)
			(xy 82.392128 -344.431456) (xy 82.444459 -344.415656) (xy 82.498538 -344.40767) (xy 82.553202 -344.40767)
			(xy 82.607281 -344.415656) (xy 82.659612 -344.431456) (xy 82.709074 -344.454732) (xy 82.754605 -344.484983)
			(xy 82.795228 -344.521562) (xy 82.830071 -344.563683) (xy 82.84464 -344.586814) (xy 82.852544 -344.599052)
			(xy 82.874021 -344.618721) (xy 82.90018 -344.631523) (xy 82.928889 -344.636415) (xy 82.957811 -344.632998)
			(xy 82.971386 -344.627708) (xy 82.994601 -344.618231) (xy 83.042931 -344.604875) (xy 83.092619 -344.598142)
			(xy 83.11769 -344.597736) (xy 83.144534 -344.598169) (xy 83.197667 -344.605873) (xy 83.249144 -344.621124)
			(xy 83.297899 -344.643605) (xy 83.342923 -344.67285) (xy 83.383283 -344.708255) (xy 83.418143 -344.749087)
			(xy 83.446783 -344.794498) (xy 83.468608 -344.843551) (xy 83.476338 -344.869262) (xy 83.480962 -344.883774)
			(xy 83.497487 -344.909342) (xy 83.520811 -344.928908) (xy 83.548863 -344.940736) (xy 83.579155 -344.943775)
			(xy 83.608998 -344.937758) (xy 83.622642 -344.930984) (xy 83.65079 -344.916355) (xy 83.71074 -344.895627)
			(xy 83.773298 -344.885126) (xy 83.805014 -344.884502) (xy 83.805268 -344.884502) (xy 83.828344 -344.884849)
			(xy 83.874159 -344.890427) (xy 83.918962 -344.901503) (xy 83.94065 -344.909394) (xy 83.954434 -344.914181)
			(xy 83.983516 -344.916438) (xy 84.012051 -344.910385) (xy 84.037712 -344.896514) (xy 84.058407 -344.875956)
			(xy 84.072448 -344.850388) (xy 84.076032 -344.836242) (xy 84.082655 -344.808282) (xy 84.103249 -344.754639)
			(xy 84.131655 -344.704692) (xy 84.167231 -344.65957) (xy 84.209172 -344.620294) (xy 84.25653 -344.587753)
			(xy 84.308232 -344.562682) (xy 84.363109 -344.545649) (xy 84.41992 -344.537039) (xy 84.44865 -344.536522)
			(xy 84.475903 -344.537002) (xy 84.529855 -344.544753) (xy 84.582154 -344.560104) (xy 84.631736 -344.582743)
			(xy 84.677591 -344.612208) (xy 84.718785 -344.647901) (xy 84.75448 -344.689093) (xy 84.783947 -344.734946)
			(xy 84.806589 -344.784527) (xy 84.821943 -344.836826) (xy 84.829697 -344.890777) (xy 84.830158 -344.91803)
			(xy 84.82972 -344.945401) (xy 84.821897 -344.999582) (xy 84.806402 -345.052086) (xy 84.783554 -345.101832)
			(xy 84.753822 -345.147798) (xy 84.736178 -345.168728) (xy 84.726914 -345.180034) (xy 84.714743 -345.2066)
			(xy 84.710577 -345.235523) (xy 84.714756 -345.264444) (xy 84.726939 -345.291004) (xy 84.736178 -345.302332)
			(xy 84.753795 -345.323282) (xy 84.783511 -345.369249) (xy 84.806352 -345.418992) (xy 84.821848 -345.471489)
			(xy 84.829681 -345.525662) (xy 84.830158 -345.55303) (xy 84.829659 -345.580604) (xy 84.821715 -345.635176)
			(xy 84.805998 -345.688035) (xy 84.782834 -345.738082) (xy 84.752707 -345.784272) (xy 84.716243 -345.825644)
			(xy 84.695538 -345.84386) (xy 84.684608 -345.853726) (xy 84.668531 -345.878384) (xy 84.660147 -345.906601)
			(xy 84.660153 -345.936037) (xy 84.668547 -345.964251) (xy 84.684633 -345.988903) (xy 84.695538 -345.9988)
			(xy 84.71626 -346.016999) (xy 84.752728 -346.058371) (xy 84.782858 -346.104564) (xy 84.806021 -346.154614)
			(xy 84.821736 -346.207479) (xy 84.829674 -346.262055) (xy 84.830158 -346.28963) (xy 84.829773 -346.316886)
			(xy 84.822011 -346.370842) (xy 84.806648 -346.423145) (xy 84.783998 -346.472728) (xy 84.754523 -346.518584)
			(xy 84.718821 -346.559777) (xy 84.67762 -346.595471) (xy 84.631758 -346.624937) (xy 84.58217 -346.647576)
			(xy 84.529864 -346.662928) (xy 84.475906 -346.670679) (xy 84.44865 -346.671138) (xy 84.420776 -346.670626)
			(xy 84.365624 -346.662506) (xy 84.31224 -346.646446) (xy 84.261761 -346.622788) (xy 84.215263 -346.592036)
			(xy 84.173735 -346.554845) (xy 84.138062 -346.512006) (xy 84.109002 -346.464432) (xy 84.097622 -346.438982)
			(xy 84.090901 -346.424856) (xy 84.070496 -346.40117) (xy 84.043891 -346.384752) (xy 84.013571 -346.377136)
			(xy 83.982366 -346.379032) (xy 83.967574 -346.384118) (xy 83.945612 -346.392165) (xy 83.900228 -346.403485)
			(xy 83.853801 -346.409176) (xy 83.830414 -346.409518) (xy 83.816265 -346.409423) (xy 83.788042 -346.407389)
			(xy 83.774026 -346.405454) (xy 83.760682 -346.403807) (xy 83.733981 -346.406912) (xy 83.709021 -346.41689)
			(xy 83.687538 -346.433048) (xy 83.671028 -346.454261) (xy 83.660638 -346.479053) (xy 83.658456 -346.492322)
			(xy 83.654312 -346.519466) (xy 83.639344 -346.572293) (xy 83.616959 -346.622429) (xy 83.587617 -346.668838)
			(xy 83.551926 -346.710563) (xy 83.510623 -346.74674) (xy 83.464561 -346.776623) (xy 83.41469 -346.799594)
			(xy 83.362042 -346.81518) (xy 83.307703 -346.823057) (xy 83.28025 -346.823538) (xy 83.253 -346.822998)
			(xy 83.199053 -346.815249) (xy 83.146759 -346.799901) (xy 83.097181 -346.777266) (xy 83.051329 -346.747806)
			(xy 83.010136 -346.71212) (xy 82.974442 -346.670935) (xy 82.944972 -346.62509) (xy 82.922327 -346.575517)
			(xy 82.906968 -346.523225) (xy 82.899207 -346.46928) (xy 82.898742 -346.44203) (xy 82.899214 -346.414456)
			(xy 82.907163 -346.359882) (xy 82.922886 -346.307022) (xy 82.946055 -346.256976) (xy 82.976187 -346.210786)
			(xy 83.012655 -346.169415) (xy 83.033362 -346.1512) (xy 83.044232 -346.141273) (xy 83.060311 -346.116632)
			(xy 83.068702 -346.088431) (xy 83.068707 -346.059008) (xy 83.060328 -346.030803) (xy 83.044258 -346.006157)
			(xy 83.033362 -345.99626) (xy 83.012669 -345.978029) (xy 82.976199 -345.936664) (xy 82.946066 -345.890478)
			(xy 82.922897 -345.840434) (xy 82.907176 -345.787575) (xy 82.899231 -345.733003) (xy 82.898742 -345.70543)
			(xy 82.899165 -345.678928) (xy 82.906516 -345.626435) (xy 82.921067 -345.575466) (xy 82.942537 -345.527005)
			(xy 82.970513 -345.481984) (xy 82.987134 -345.461336) (xy 82.996597 -345.449205) (xy 83.008386 -345.420799)
			(xy 83.011207 -345.390174) (xy 83.004807 -345.360093) (xy 82.989762 -345.33327) (xy 82.96743 -345.312125)
			(xy 82.95386 -345.304872) (xy 82.930169 -345.292774) (xy 82.886187 -345.26285) (xy 82.846906 -345.226979)
			(xy 82.813123 -345.185887) (xy 82.79892 -345.163394) (xy 82.790957 -345.151198) (xy 82.769496 -345.131528)
			(xy 82.743354 -345.11872) (xy 82.714658 -345.113817) (xy 82.685746 -345.117219) (xy 82.672174 -345.1225)
			(xy 82.648964 -345.13199) (xy 82.600631 -345.145341) (xy 82.550942 -345.152069) (xy 82.52587 -345.152472)
			(xy 82.500801 -345.152046) (xy 82.451118 -345.145297) (xy 82.402783 -345.131966) (xy 82.379566 -345.1225)
			(xy 82.365978 -345.117283) (xy 82.337083 -345.11391) (xy 82.308408 -345.118814) (xy 82.282275 -345.131596)
			(xy 82.2608 -345.151222) (xy 82.25282 -345.163394) (xy 82.238251 -345.186525) (xy 82.203408 -345.228646)
			(xy 82.162785 -345.265225) (xy 82.117254 -345.295476) (xy 82.067792 -345.318752) (xy 82.015461 -345.334552)
			(xy 81.961382 -345.342538) (xy 81.906718 -345.342538) (xy 81.852639 -345.334552) (xy 81.800308 -345.318752)
			(xy 81.750846 -345.295476) (xy 81.705315 -345.265225) (xy 81.664692 -345.228646) (xy 81.629849 -345.186525)
			(xy 81.61528 -345.163394) (xy 81.607355 -345.151171) (xy 81.585884 -345.131501) (xy 81.559731 -345.118696)
			(xy 81.531026 -345.113801) (xy 81.502108 -345.117212) (xy 81.488534 -345.1225) (xy 81.465317 -345.131971)
			(xy 81.416988 -345.145329) (xy 81.367301 -345.152065) (xy 81.34223 -345.152472) (xy 81.314338 -345.152071)
			(xy 81.259178 -345.143761) (xy 81.205871 -345.127322) (xy 81.155611 -345.103122) (xy 81.109519 -345.0717)
			(xy 81.068626 -345.033759) (xy 81.033844 -344.990148) (xy 81.005951 -344.941839) (xy 80.98557 -344.889912)
			(xy 80.973156 -344.835527) (xy 80.968987 -344.7799) (xy 76.340208 -344.7799) (xy 76.340208 -345.486736)
			(xy 76.69911 -345.845638) (xy 77.5114 -345.845638) (xy 77.515471 -345.790016) (xy 77.527597 -345.735579)
			(xy 77.54752 -345.683488) (xy 77.574816 -345.634853) (xy 77.608902 -345.59071) (xy 77.649051 -345.552001)
			(xy 77.694409 -345.51955) (xy 77.744009 -345.494049) (xy 77.796793 -345.476042) (xy 77.851636 -345.465912)
			(xy 77.90737 -345.463875) (xy 77.962807 -345.469975) (xy 78.016764 -345.484081) (xy 78.068093 -345.505893)
			(xy 78.115699 -345.534947) (xy 78.158567 -345.570622) (xy 78.195784 -345.612159) (xy 78.226557 -345.658672)
			(xy 78.250229 -345.709169) (xy 78.266297 -345.762576) (xy 78.274417 -345.817752) (xy 78.274926 -345.845638)
			(xy 78.274417 -345.873524) (xy 78.266297 -345.9287) (xy 78.250229 -345.982107) (xy 78.226557 -346.032604)
			(xy 78.195784 -346.079117) (xy 78.158567 -346.120654) (xy 78.115699 -346.156329) (xy 78.068093 -346.185383)
			(xy 78.016764 -346.207195) (xy 77.962807 -346.221301) (xy 77.90737 -346.227401) (xy 77.851636 -346.225364)
			(xy 77.796793 -346.215234) (xy 77.744009 -346.197227) (xy 77.694409 -346.171726) (xy 77.649051 -346.139275)
			(xy 77.608902 -346.100566) (xy 77.574816 -346.056423) (xy 77.54752 -346.007788) (xy 77.527597 -345.955697)
			(xy 77.515471 -345.90126) (xy 77.5114 -345.845638) (xy 76.69911 -345.845638) (xy 77.304138 -346.450666)
			(xy 77.318108 -346.454222) (xy 77.345515 -346.461319) (xy 77.398013 -346.482507) (xy 77.4468 -346.511227)
			(xy 77.490802 -346.546847) (xy 77.529052 -346.588584) (xy 77.560708 -346.635519) (xy 77.585074 -346.686619)
			(xy 77.601614 -346.740762) (xy 77.609963 -346.796755) (xy 77.610462 -346.825062) (xy 77.610001 -346.852315)
			(xy 77.602248 -346.906268) (xy 77.586895 -346.958568) (xy 77.564254 -347.00815) (xy 77.534787 -347.054004)
			(xy 77.499092 -347.095198) (xy 77.457898 -347.130891) (xy 77.412043 -347.160358) (xy 77.36246 -347.182998)
			(xy 77.31016 -347.19835) (xy 77.256207 -347.206102) (xy 77.228954 -347.20657) (xy 77.200662 -347.206059)
			(xy 77.144699 -347.197707) (xy 77.090583 -347.181177) (xy 77.039504 -347.156833) (xy 76.992583 -347.125209)
			(xy 76.950849 -347.086999) (xy 76.915219 -347.043042) (xy 76.886475 -346.994304) (xy 76.865247 -346.941853)
			(xy 76.858114 -346.91447) (xy 76.854812 -346.9005) (xy 75.79741 -345.843352) (xy 75.780056 -345.825367)
			(xy 75.750656 -345.784954) (xy 75.727948 -345.740435) (xy 75.712493 -345.69291) (xy 75.704672 -345.64355)
			(xy 75.704192 -345.618562) (xy 75.704192 -343.052654) (xy 75.704706 -343.027671) (xy 75.712562 -342.978327)
			(xy 75.728027 -342.930814) (xy 75.750722 -342.886299) (xy 75.780089 -342.845874) (xy 75.79741 -342.827864)
			(xy 76.373736 -342.251538) (xy 76.39172 -342.234182) (xy 76.432132 -342.204778) (xy 76.47665 -342.182067)
			(xy 76.524176 -342.166608) (xy 76.573537 -342.158784) (xy 76.598526 -342.15832) (xy 77.033628 -342.15832)
			(xy 77.088746 -342.103202) (xy 77.526388 -341.665814) (xy 77.526388 -333.212948) (xy 77.0382 -333.212948)
			(xy 75.1332 -335.117948) (xy 75.1332 -346.264484) (xy 75.196992 -347.439234) (xy 78.318106 -347.439234)
			(xy 78.318683 -347.409547) (xy 78.327877 -347.350889) (xy 78.346048 -347.294363) (xy 78.372757 -347.241335)
			(xy 78.407359 -347.193086) (xy 78.449019 -347.15078) (xy 78.472538 -347.132656) (xy 78.483121 -347.124203)
			(xy 78.499823 -347.102895) (xy 78.510339 -347.077947) (xy 78.513931 -347.051113) (xy 78.510346 -347.024278)
			(xy 78.499836 -346.999328) (xy 78.48314 -346.978016) (xy 78.472538 -346.969588) (xy 78.44903 -346.951449)
			(xy 78.407367 -346.909147) (xy 78.372762 -346.860901) (xy 78.346048 -346.807876) (xy 78.327872 -346.751353)
			(xy 78.318672 -346.692697) (xy 78.318106 -346.66301) (xy 78.318592 -346.635759) (xy 78.326348 -346.581811)
			(xy 78.341703 -346.529516) (xy 78.364345 -346.479939) (xy 78.393811 -346.434089) (xy 78.429502 -346.392898)
			(xy 78.470693 -346.357207) (xy 78.516543 -346.327741) (xy 78.56612 -346.305099) (xy 78.618415 -346.289744)
			(xy 78.672363 -346.281988) (xy 78.726865 -346.281988) (xy 78.780813 -346.289744) (xy 78.833108 -346.305099)
			(xy 78.882685 -346.327741) (xy 78.928535 -346.357207) (xy 78.969726 -346.392898) (xy 79.005417 -346.434089)
			(xy 79.034883 -346.479939) (xy 79.057525 -346.529516) (xy 79.07288 -346.581811) (xy 79.080636 -346.635759)
			(xy 79.081122 -346.66301) (xy 79.080565 -346.692698) (xy 79.071366 -346.751356) (xy 79.05319 -346.807882)
			(xy 79.026477 -346.860909) (xy 79.014394 -346.877756) (xy 79.334517 -346.877756) (xy 79.334517 -346.823244)
			(xy 79.342275 -346.769286) (xy 79.357633 -346.716982) (xy 79.380279 -346.667396) (xy 79.409751 -346.621537)
			(xy 79.44545 -346.58034) (xy 79.486649 -346.544643) (xy 79.532508 -346.515172) (xy 79.582095 -346.492528)
			(xy 79.6344 -346.477172) (xy 79.688358 -346.469416) (xy 79.715614 -346.468954) (xy 79.715868 -346.468954)
			(xy 79.741071 -346.469366) (xy 79.791039 -346.476001) (xy 79.839693 -346.489174) (xy 79.886184 -346.508654)
			(xy 79.908146 -346.521024) (xy 79.92109 -346.528106) (xy 79.949736 -346.535138) (xy 79.979196 -346.533688)
			(xy 80.007013 -346.523877) (xy 80.030865 -346.506525) (xy 80.048761 -346.483078) (xy 80.05445 -346.469462)
			(xy 80.065151 -346.442688) (xy 80.09344 -346.392448) (xy 80.12897 -346.34704) (xy 80.170931 -346.307498)
			(xy 80.218368 -346.274725) (xy 80.270197 -346.249466) (xy 80.325239 -346.232299) (xy 80.382238 -346.223613)
			(xy 80.411066 -346.223082) (xy 80.438318 -346.223587) (xy 80.492266 -346.231339) (xy 80.544563 -346.24669)
			(xy 80.594142 -346.269328) (xy 80.639995 -346.298792) (xy 80.681188 -346.334481) (xy 80.716882 -346.37567)
			(xy 80.746351 -346.421519) (xy 80.768994 -346.471096) (xy 80.784352 -346.52339) (xy 80.79211 -346.577338)
			(xy 80.792574 -346.60459) (xy 80.792574 -346.604844) (xy 80.792003 -346.634683) (xy 80.782685 -346.693629)
			(xy 80.774032 -346.722192) (xy 80.769931 -346.736084) (xy 80.769028 -346.765028) (xy 80.776304 -346.793057)
			(xy 80.791169 -346.817907) (xy 80.812425 -346.837573) (xy 80.838354 -346.850466) (xy 80.852518 -346.85351)
			(xy 80.878588 -346.858694) (xy 80.929091 -346.875263) (xy 80.976803 -346.898685) (xy 81.020801 -346.928505)
			(xy 81.060232 -346.964146) (xy 81.094332 -347.004918) (xy 81.122439 -347.050029) (xy 81.144009 -347.098607)
			(xy 81.158625 -347.149709) (xy 81.166003 -347.202346) (xy 81.166462 -347.228922) (xy 81.165192 -347.25991)
			(xy 81.16316 -347.283532) (xy 81.294224 -347.414596) (xy 86.105746 -347.414596) (xy 86.40699 -347.113352)
			(xy 86.423232 -347.097788) (xy 86.460625 -347.072788) (xy 86.50218 -347.055572) (xy 86.546298 -347.046804)
			(xy 86.568788 -347.046296) (xy 97.158556 -347.046296) (xy 97.181038 -347.04686) (xy 97.225136 -347.055652)
			(xy 97.266675 -347.072867) (xy 97.304064 -347.097847) (xy 97.320354 -347.113352) (xy 98.827844 -348.620842)
			(xy 98.843385 -348.637105) (xy 98.868389 -348.67449) (xy 98.885611 -348.716039) (xy 98.894387 -348.760152)
			(xy 98.8949 -348.78264) (xy 98.8949 -353.927156) (xy 98.894337 -353.949638) (xy 98.885545 -353.993736)
			(xy 98.868329 -354.035275) (xy 98.843349 -354.072664) (xy 98.827844 -354.088954) (xy 97.684844 -355.232208)
			(xy 97.684844 -360.533696) (xy 101.90861 -364.757716) (xy 102.574598 -364.757716) (xy 102.597079 -364.75831)
			(xy 102.641175 -364.767091) (xy 102.682715 -364.784298) (xy 102.720105 -364.80927) (xy 102.736396 -364.824772)
			(xy 104.183477 -366.271853) (xy 104.673087 -366.271853) (xy 104.673087 -366.217347) (xy 104.680845 -366.163397)
			(xy 104.696202 -366.1111) (xy 104.718846 -366.061521) (xy 104.748316 -366.015669) (xy 104.784011 -365.974479)
			(xy 104.825206 -365.938788) (xy 104.871061 -365.909324) (xy 104.920643 -365.886686) (xy 104.972942 -365.871335)
			(xy 105.026893 -365.863584) (xy 105.054146 -365.863124) (xy 105.080526 -365.863544) (xy 105.132786 -365.870804)
			(xy 105.183547 -365.885191) (xy 105.231843 -365.906433) (xy 105.276753 -365.934124) (xy 105.317421 -365.967737)
			(xy 105.353072 -366.006631) (xy 105.383026 -366.050064) (xy 105.395268 -366.073436) (xy 105.40197 -366.085795)
			(xy 105.420945 -366.106523) (xy 105.444859 -366.121285) (xy 105.471895 -366.128957) (xy 105.499997 -366.128957)
			(xy 105.527033 -366.121285) (xy 105.550947 -366.106523) (xy 105.569922 -366.085795) (xy 105.576624 -366.073436)
			(xy 105.588879 -366.050073) (xy 105.618842 -366.006652) (xy 105.654497 -365.967769) (xy 105.695164 -365.934164)
			(xy 105.740071 -365.906477) (xy 105.788361 -365.885234) (xy 105.839116 -365.870842) (xy 105.891368 -365.863572)
			(xy 105.917746 -365.863124) (xy 105.944997 -365.863549) (xy 105.998945 -365.871311) (xy 106.051238 -365.886672)
			(xy 106.100814 -365.909318) (xy 106.146662 -365.938788) (xy 106.187851 -365.974482) (xy 106.22354 -366.015675)
			(xy 106.253005 -366.061527) (xy 106.275644 -366.111105) (xy 106.290998 -366.1634) (xy 106.298754 -366.217349)
			(xy 106.298754 -366.271851) (xy 106.290998 -366.3258) (xy 106.275644 -366.378095) (xy 106.253005 -366.427673)
			(xy 106.22354 -366.473525) (xy 106.187851 -366.514718) (xy 106.146662 -366.550412) (xy 106.100814 -366.579882)
			(xy 106.051238 -366.602528) (xy 105.998945 -366.617889) (xy 105.944997 -366.625651) (xy 105.917746 -366.62614)
			(xy 105.891367 -366.625691) (xy 105.839111 -366.618432) (xy 105.788352 -366.604046) (xy 105.740058 -366.582807)
			(xy 105.695148 -366.55512) (xy 105.65448 -366.521513) (xy 105.618826 -366.482625) (xy 105.588868 -366.439197)
			(xy 105.576624 -366.415828) (xy 105.569922 -366.403469) (xy 105.550947 -366.382741) (xy 105.527033 -366.367979)
			(xy 105.499997 -366.360307) (xy 105.471895 -366.360307) (xy 105.444859 -366.367979) (xy 105.420945 -366.382741)
			(xy 105.40197 -366.403469) (xy 105.395268 -366.415828) (xy 105.383003 -366.439186) (xy 105.353043 -366.482608)
			(xy 105.317391 -366.521493) (xy 105.276725 -366.555099) (xy 105.231819 -366.582787) (xy 105.18353 -366.60403)
			(xy 105.132776 -366.618423) (xy 105.080524 -366.625692) (xy 105.054146 -366.62614) (xy 105.026893 -366.625616)
			(xy 104.972942 -366.617865) (xy 104.920643 -366.602514) (xy 104.871061 -366.579876) (xy 104.825206 -366.550412)
			(xy 104.784011 -366.514721) (xy 104.748316 -366.473531) (xy 104.718846 -366.427679) (xy 104.696202 -366.3781)
			(xy 104.680845 -366.325803) (xy 104.673087 -366.271853) (xy 104.183477 -366.271853) (xy 104.565275 -366.653651)
			(xy 107.352072 -366.653651) (xy 107.352072 -366.599149) (xy 107.359828 -366.545202) (xy 107.375183 -366.492908)
			(xy 107.397823 -366.443331) (xy 107.427288 -366.39748) (xy 107.462978 -366.35629) (xy 107.504167 -366.320598)
			(xy 107.550017 -366.291131) (xy 107.599593 -366.268488) (xy 107.651886 -366.253131) (xy 107.705833 -366.245373)
			(xy 107.733084 -366.244886) (xy 107.759465 -366.245296) (xy 107.811723 -366.252559) (xy 107.862484 -366.26695)
			(xy 107.910779 -366.288195) (xy 107.955688 -366.315887) (xy 107.996356 -366.3495) (xy 108.032008 -366.388394)
			(xy 108.061963 -366.431826) (xy 108.074206 -366.455198) (xy 108.080908 -366.467557) (xy 108.099883 -366.488285)
			(xy 108.123797 -366.503047) (xy 108.150833 -366.510719) (xy 108.178935 -366.510719) (xy 108.205971 -366.503047)
			(xy 108.229885 -366.488285) (xy 108.24886 -366.467557) (xy 108.255562 -366.455198) (xy 108.267815 -366.431834)
			(xy 108.297776 -366.38841) (xy 108.333429 -366.349524) (xy 108.374097 -366.315917) (xy 108.419004 -366.28823)
			(xy 108.467296 -366.266988) (xy 108.518052 -366.252598) (xy 108.570306 -366.245332) (xy 108.596684 -366.244886)
			(xy 108.623937 -366.24536) (xy 108.677889 -366.253115) (xy 108.730188 -366.26847) (xy 108.779769 -366.291111)
			(xy 108.825624 -366.320578) (xy 108.866818 -366.356271) (xy 108.902512 -366.397463) (xy 108.931981 -366.443317)
			(xy 108.954625 -366.492897) (xy 108.969981 -366.545195) (xy 108.977739 -366.599147) (xy 108.977739 -366.653653)
			(xy 108.969981 -366.707605) (xy 108.954625 -366.759903) (xy 108.931981 -366.809483) (xy 108.902512 -366.855337)
			(xy 108.866818 -366.896529) (xy 108.825624 -366.932222) (xy 108.779769 -366.961689) (xy 108.730188 -366.98433)
			(xy 108.677889 -366.999685) (xy 108.623937 -367.00744) (xy 108.596684 -367.007902) (xy 108.570305 -367.007443)
			(xy 108.518048 -367.000188) (xy 108.467289 -366.985805) (xy 108.418994 -366.964569) (xy 108.374084 -366.936883)
			(xy 108.333415 -366.903276) (xy 108.297762 -366.864388) (xy 108.267805 -366.82096) (xy 108.255562 -366.79759)
			(xy 108.24886 -366.785231) (xy 108.229885 -366.764503) (xy 108.205971 -366.749741) (xy 108.178935 -366.742069)
			(xy 108.150833 -366.742069) (xy 108.123797 -366.749741) (xy 108.099883 -366.764503) (xy 108.080908 -366.785231)
			(xy 108.074206 -366.79759) (xy 108.061972 -366.820965) (xy 108.032009 -366.86439) (xy 107.996354 -366.903276)
			(xy 107.955683 -366.936882) (xy 107.910773 -366.964569) (xy 107.862479 -366.985808) (xy 107.81172 -367.000196)
			(xy 107.759463 -367.007458) (xy 107.733084 -367.007902) (xy 107.705833 -367.007427) (xy 107.651886 -366.999669)
			(xy 107.599593 -366.984312) (xy 107.550017 -366.961669) (xy 107.504167 -366.932202) (xy 107.462978 -366.89651)
			(xy 107.427288 -366.85532) (xy 107.397823 -366.809469) (xy 107.375183 -366.759892) (xy 107.359828 -366.707598)
			(xy 107.352072 -366.653651) (xy 104.565275 -366.653651) (xy 105.54716 -367.635536) (xy 109.066076 -367.635536)
			(xy 109.995208 -366.70615) (xy 109.995208 -365.81842) (xy 109.971956 -365.800295) (xy 109.930825 -365.758061)
			(xy 109.89668 -365.710001) (xy 109.870336 -365.657261) (xy 109.852418 -365.601096) (xy 109.843354 -365.542843)
			(xy 109.842808 -365.513366) (xy 109.843294 -365.486115) (xy 109.85105 -365.432167) (xy 109.866405 -365.379872)
			(xy 109.889047 -365.330295) (xy 109.918513 -365.284445) (xy 109.954204 -365.243254) (xy 109.995395 -365.207563)
			(xy 110.041245 -365.178097) (xy 110.090822 -365.155455) (xy 110.143117 -365.1401) (xy 110.197065 -365.132344)
			(xy 110.251567 -365.132344) (xy 110.305515 -365.1401) (xy 110.35781 -365.155455) (xy 110.407387 -365.178097)
			(xy 110.453237 -365.207563) (xy 110.494428 -365.243254) (xy 110.530119 -365.284445) (xy 110.559585 -365.330295)
			(xy 110.582227 -365.379872) (xy 110.597582 -365.432167) (xy 110.605338 -365.486115) (xy 110.605824 -365.513366)
			(xy 110.605245 -365.542841) (xy 110.596182 -365.601089) (xy 110.578267 -365.65725) (xy 110.551926 -365.709987)
			(xy 110.517787 -365.758045) (xy 110.476661 -365.800279) (xy 110.453424 -365.81842) (xy 110.453424 -366.800892)
			(xy 110.452845 -366.823388) (xy 110.443995 -366.867502) (xy 110.42671 -366.909043) (xy 110.401656 -366.946416)
			(xy 110.386114 -366.96269) (xy 109.322616 -368.026188) (xy 109.306378 -368.041756) (xy 109.268983 -368.066754)
			(xy 109.227426 -368.083968) (xy 109.183309 -368.092736) (xy 109.160818 -368.093244) (xy 105.452418 -368.093244)
			(xy 105.429934 -368.092713) (xy 105.385834 -368.083913) (xy 105.344294 -368.066688) (xy 105.306908 -368.041698)
			(xy 105.29062 -368.026188) (xy 102.479856 -365.215424) (xy 101.813868 -365.215424) (xy 101.791385 -365.214868)
			(xy 101.747286 -365.206078) (xy 101.705746 -365.18886) (xy 101.668359 -365.163876) (xy 101.65207 -365.148368)
			(xy 97.293938 -360.790236) (xy 97.27838 -360.773972) (xy 97.253302 -360.736607) (xy 97.236009 -360.695062)
			(xy 97.227169 -360.650938) (xy 97.226628 -360.628438) (xy 97.226628 -355.137466) (xy 97.227195 -355.11497)
			(xy 97.236051 -355.070856) (xy 97.253339 -355.029315) (xy 97.278395 -354.991942) (xy 97.293938 -354.975668)
			(xy 98.437192 -353.832414) (xy 98.437192 -348.877382) (xy 97.063814 -347.504004) (xy 86.66353 -347.504004)
			(xy 86.362286 -347.805248) (xy 86.346012 -347.820776) (xy 86.30863 -347.845783) (xy 86.267085 -347.863008)
			(xy 86.222975 -347.871789) (xy 86.200488 -347.872304) (xy 81.199482 -347.872304) (xy 81.177001 -347.871716)
			(xy 81.132904 -347.862932) (xy 81.091365 -347.845723) (xy 81.053975 -347.82075) (xy 81.037684 -347.805248)
			(xy 80.839564 -347.607128) (xy 80.815942 -347.60916) (xy 80.784954 -347.61043) (xy 80.757703 -347.609965)
			(xy 80.703755 -347.602203) (xy 80.651462 -347.586843) (xy 80.601886 -347.564198) (xy 80.556036 -347.534729)
			(xy 80.514847 -347.499036) (xy 80.479157 -347.457844) (xy 80.44969 -347.411993) (xy 80.427049 -347.362416)
			(xy 80.411692 -347.310121) (xy 80.403933 -347.256173) (xy 80.403446 -347.228922) (xy 80.403446 -347.228668)
			(xy 80.404023 -347.198829) (xy 80.413337 -347.139883) (xy 80.421988 -347.11132) (xy 80.426059 -347.097421)
			(xy 80.426964 -347.068483) (xy 80.419693 -347.040458) (xy 80.404833 -347.01561) (xy 80.383585 -346.995944)
			(xy 80.357663 -346.983049) (xy 80.343502 -346.980002) (xy 80.310662 -346.97342) (xy 80.24781 -346.950297)
			(xy 80.218534 -346.934028) (xy 80.205591 -346.926948) (xy 80.176946 -346.919925) (xy 80.147488 -346.921379)
			(xy 80.119674 -346.931189) (xy 80.095823 -346.948537) (xy 80.077923 -346.971977) (xy 80.07223 -346.98559)
			(xy 80.06152 -347.012361) (xy 80.033235 -347.062603) (xy 79.997708 -347.108013) (xy 79.955748 -347.147557)
			(xy 79.908313 -347.180331) (xy 79.856483 -347.20559) (xy 79.801441 -347.222757) (xy 79.744442 -347.23144)
			(xy 79.715614 -347.23197) (xy 79.688358 -347.231584) (xy 79.6344 -347.223828) (xy 79.582095 -347.208472)
			(xy 79.532508 -347.185828) (xy 79.486649 -347.156357) (xy 79.44545 -347.12066) (xy 79.409751 -347.079463)
			(xy 79.380279 -347.033604) (xy 79.357633 -346.984018) (xy 79.342275 -346.931714) (xy 79.334517 -346.877756)
			(xy 79.014394 -346.877756) (xy 78.991872 -346.909158) (xy 78.95021 -346.951464) (xy 78.92669 -346.969588)
			(xy 78.916061 -346.977989) (xy 78.899354 -346.999307) (xy 78.888838 -347.024267) (xy 78.885251 -347.051113)
			(xy 78.888845 -347.077958) (xy 78.899368 -347.102916) (xy 78.91608 -347.12423) (xy 78.92669 -347.132656)
			(xy 78.950225 -347.150762) (xy 78.991885 -347.193071) (xy 79.026487 -347.241324) (xy 79.053195 -347.294356)
			(xy 79.071366 -347.350884) (xy 79.08056 -347.409545) (xy 79.081122 -347.439234) (xy 79.080636 -347.466485)
			(xy 79.07288 -347.520433) (xy 79.057525 -347.572728) (xy 79.034883 -347.622305) (xy 79.005417 -347.668155)
			(xy 78.969726 -347.709346) (xy 78.928535 -347.745037) (xy 78.882685 -347.774503) (xy 78.833108 -347.797145)
			(xy 78.780813 -347.8125) (xy 78.726865 -347.820256) (xy 78.672363 -347.820256) (xy 78.618415 -347.8125)
			(xy 78.56612 -347.797145) (xy 78.516543 -347.774503) (xy 78.470693 -347.745037) (xy 78.429502 -347.709346)
			(xy 78.393811 -347.668155) (xy 78.364345 -347.622305) (xy 78.341703 -347.572728) (xy 78.326348 -347.520433)
			(xy 78.318592 -347.466485) (xy 78.318106 -347.439234) (xy 75.196992 -347.439234) (xy 75.325224 -349.800672)
			(xy 75.632222 -350.505014) (xy 76.530962 -350.505014) (xy 76.531383 -350.478634) (xy 76.538647 -350.426376)
			(xy 76.553037 -350.375617) (xy 76.57428 -350.327322) (xy 76.601971 -350.282413) (xy 76.635582 -350.241745)
			(xy 76.674473 -350.206093) (xy 76.717903 -350.176136) (xy 76.741274 -350.163892) (xy 76.75362 -350.157169)
			(xy 76.774345 -350.138196) (xy 76.789105 -350.114286) (xy 76.796777 -350.087256) (xy 76.796779 -350.059157)
			(xy 76.78911 -350.032125) (xy 76.774353 -350.008213) (xy 76.75363 -349.989238) (xy 76.741274 -349.982536)
			(xy 76.717904 -349.970295) (xy 76.67448 -349.940332) (xy 76.635596 -349.904676) (xy 76.60199 -349.864006)
			(xy 76.574303 -349.819098) (xy 76.553063 -349.770805) (xy 76.538673 -349.720048) (xy 76.531408 -349.667793)
			(xy 76.530962 -349.641414) (xy 76.531448 -349.614163) (xy 76.539204 -349.560215) (xy 76.554559 -349.50792)
			(xy 76.577201 -349.458343) (xy 76.606667 -349.412493) (xy 76.642358 -349.371302) (xy 76.683549 -349.335611)
			(xy 76.729399 -349.306145) (xy 76.778976 -349.283503) (xy 76.831271 -349.268148) (xy 76.885219 -349.260392)
			(xy 76.939721 -349.260392) (xy 76.993669 -349.268148) (xy 77.045964 -349.283503) (xy 77.095541 -349.306145)
			(xy 77.141391 -349.335611) (xy 77.182582 -349.371302) (xy 77.218273 -349.412493) (xy 77.247739 -349.458343)
			(xy 77.270381 -349.50792) (xy 77.285736 -349.560215) (xy 77.293492 -349.614163) (xy 77.293978 -349.641414)
			(xy 77.29353 -349.667794) (xy 77.286275 -349.720051) (xy 77.271892 -349.770812) (xy 77.250654 -349.819107)
			(xy 77.222967 -349.864018) (xy 77.189357 -349.904686) (xy 77.150467 -349.940338) (xy 77.107037 -349.970294)
			(xy 77.083666 -349.982536) (xy 77.071292 -349.989214) (xy 77.050555 -350.008192) (xy 77.035789 -350.03211)
			(xy 77.028115 -350.059152) (xy 77.028117 -350.087261) (xy 77.035794 -350.114302) (xy 77.050563 -350.138218)
			(xy 77.071302 -350.157193) (xy 77.083666 -350.163892) (xy 77.107058 -350.176095) (xy 77.15048 -350.206064)
			(xy 77.189363 -350.241727) (xy 77.222966 -350.282402) (xy 77.25065 -350.327316) (xy 77.271887 -350.375614)
			(xy 77.286273 -350.426375) (xy 77.293534 -350.478634) (xy 77.29388 -350.499172) (xy 88.330532 -350.499172)
			(xy 88.33109 -350.470256) (xy 88.339809 -350.413086) (xy 88.357058 -350.357888) (xy 88.382442 -350.305926)
			(xy 88.41538 -350.258391) (xy 88.455115 -350.216373) (xy 88.477598 -350.198182) (xy 88.48943 -350.188315)
			(xy 88.506945 -350.162982) (xy 88.516117 -350.133582) (xy 88.516112 -350.102784) (xy 88.50693 -350.073387)
			(xy 88.489406 -350.04806) (xy 88.477598 -350.038162) (xy 88.455096 -350.019993) (xy 88.415362 -349.977969)
			(xy 88.382425 -349.930429) (xy 88.35704 -349.878463) (xy 88.339788 -349.823262) (xy 88.331064 -349.766089)
			(xy 88.330532 -349.737172) (xy 88.330929 -349.709917) (xy 88.338691 -349.655961) (xy 88.354052 -349.60366)
			(xy 88.376701 -349.554077) (xy 88.406176 -349.508222) (xy 88.441876 -349.467028) (xy 88.483076 -349.431335)
			(xy 88.528936 -349.401868) (xy 88.578523 -349.379229) (xy 88.630828 -349.363876) (xy 88.684785 -349.356124)
			(xy 88.71204 -349.355664) (xy 88.712294 -349.355664) (xy 88.738495 -349.356104) (xy 88.790401 -349.363294)
			(xy 88.840836 -349.377513) (xy 88.888855 -349.398493) (xy 88.91143 -349.411798) (xy 88.921042 -349.417123)
			(xy 88.942853 -349.419676) (xy 88.963746 -349.412914) (xy 88.979926 -349.398067) (xy 88.988453 -349.377831)
			(xy 88.988646 -349.36684) (xy 88.988392 -349.353632) (xy 88.988456 -349.342494) (xy 88.989728 -349.320255)
			(xy 88.990932 -349.309182) (xy 88.992189 -349.294211) (xy 88.986907 -349.264651) (xy 88.973257 -349.237904)
			(xy 88.952417 -349.216283) (xy 88.926191 -349.201657) (xy 88.896845 -349.19529) (xy 88.866916 -349.197734)
			(xy 88.852756 -349.202756) (xy 88.830293 -349.2113) (xy 88.78375 -349.223283) (xy 88.73607 -349.229319)
			(xy 88.71204 -349.22968) (xy 88.684783 -349.229276) (xy 88.630824 -349.221523) (xy 88.578517 -349.206169)
			(xy 88.528929 -349.183527) (xy 88.483067 -349.154058) (xy 88.441866 -349.118362) (xy 88.406166 -349.077165)
			(xy 88.376692 -349.031307) (xy 88.354045 -348.98172) (xy 88.338686 -348.929415) (xy 88.330927 -348.875457)
			(xy 88.330927 -348.820943) (xy 88.338686 -348.766985) (xy 88.354045 -348.71468) (xy 88.376692 -348.665093)
			(xy 88.406166 -348.619235) (xy 88.441866 -348.578038) (xy 88.483067 -348.542342) (xy 88.528929 -348.512873)
			(xy 88.578517 -348.490231) (xy 88.630824 -348.474877) (xy 88.684783 -348.467124) (xy 88.71204 -348.466664)
			(xy 88.736204 -348.467041) (xy 88.784147 -348.473135) (xy 88.830936 -348.485233) (xy 88.853518 -348.493842)
			(xy 88.868007 -348.499123) (xy 88.89874 -348.501541) (xy 88.928796 -348.494686) (xy 88.955441 -348.479182)
			(xy 88.976252 -348.456438) (xy 88.989334 -348.428524) (xy 88.991948 -348.413324) (xy 88.996023 -348.386221)
			(xy 89.011078 -348.333521) (xy 89.033522 -348.283519) (xy 89.062893 -348.237245) (xy 89.098585 -348.195651)
			(xy 89.139864 -348.159596) (xy 89.18588 -348.129821) (xy 89.235683 -348.106939) (xy 89.28825 -348.091423)
			(xy 89.342496 -348.083591) (xy 89.3699 -348.083124) (xy 89.398817 -348.083633) (xy 89.455989 -348.092363)
			(xy 89.511189 -348.109622) (xy 89.563151 -348.135015) (xy 89.610684 -348.167961) (xy 89.6527 -348.207704)
			(xy 89.67089 -348.23019) (xy 89.680787 -348.241995) (xy 89.706111 -348.259514) (xy 89.735504 -348.26869)
			(xy 89.766296 -348.26869) (xy 89.795689 -348.259514) (xy 89.821013 -348.241995) (xy 89.83091 -348.23019)
			(xy 89.849093 -348.2077) (xy 89.891115 -348.167965) (xy 89.938651 -348.135027) (xy 89.990614 -348.10964)
			(xy 90.045813 -348.092385) (xy 90.102984 -348.083658) (xy 90.1319 -348.083124) (xy 90.159154 -348.083546)
			(xy 90.213106 -348.091303) (xy 90.265405 -348.106659) (xy 90.314986 -348.129302) (xy 90.360841 -348.158771)
			(xy 90.402034 -348.194466) (xy 90.437729 -348.235659) (xy 90.467198 -348.281514) (xy 90.489841 -348.331095)
			(xy 90.505197 -348.383394) (xy 90.512954 -348.437346) (xy 90.512954 -348.491854) (xy 90.509949 -348.512757)
			(xy 90.715215 -348.512757) (xy 90.715215 -348.458243) (xy 90.722974 -348.404283) (xy 90.738333 -348.351976)
			(xy 90.760981 -348.302388) (xy 90.790456 -348.256528) (xy 90.826157 -348.21533) (xy 90.867359 -348.179633)
			(xy 90.913222 -348.150163) (xy 90.962812 -348.12752) (xy 91.01512 -348.112166) (xy 91.06908 -348.104412)
			(xy 91.096338 -348.103952) (xy 91.125254 -348.104495) (xy 91.182425 -348.113217) (xy 91.237624 -348.130468)
			(xy 91.289586 -348.155855) (xy 91.337121 -348.188795) (xy 91.379138 -348.228534) (xy 91.397328 -348.251018)
			(xy 91.407225 -348.262823) (xy 91.432549 -348.280342) (xy 91.461942 -348.289518) (xy 91.492734 -348.289518)
			(xy 91.522127 -348.280342) (xy 91.547451 -348.262823) (xy 91.557348 -348.251018) (xy 91.574101 -348.230235)
			(xy 91.612455 -348.193105) (xy 91.655609 -348.161683) (xy 91.702723 -348.136584) (xy 91.752875 -348.118298)
			(xy 91.805086 -348.107181) (xy 91.858338 -348.103451) (xy 91.91159 -348.107181) (xy 91.963801 -348.118298)
			(xy 92.013953 -348.136584) (xy 92.061067 -348.161683) (xy 92.104221 -348.193105) (xy 92.142575 -348.230235)
			(xy 92.159328 -348.251018) (xy 92.169225 -348.262823) (xy 92.194549 -348.280342) (xy 92.223942 -348.289518)
			(xy 92.254734 -348.289518) (xy 92.284127 -348.280342) (xy 92.309451 -348.262823) (xy 92.319348 -348.251018)
			(xy 92.336101 -348.230235) (xy 92.374455 -348.193105) (xy 92.417609 -348.161683) (xy 92.464723 -348.136584)
			(xy 92.514875 -348.118298) (xy 92.567086 -348.107181) (xy 92.620338 -348.103451) (xy 92.67359 -348.107181)
			(xy 92.725801 -348.118298) (xy 92.775953 -348.136584) (xy 92.823067 -348.161683) (xy 92.866221 -348.193105)
			(xy 92.904575 -348.230235) (xy 92.921328 -348.251018) (xy 92.931225 -348.262823) (xy 92.956549 -348.280342)
			(xy 92.985942 -348.289518) (xy 93.016734 -348.289518) (xy 93.046127 -348.280342) (xy 93.071451 -348.262823)
			(xy 93.081348 -348.251018) (xy 93.099573 -348.228563) (xy 93.141585 -348.188825) (xy 93.189113 -348.155882)
			(xy 93.241067 -348.130489) (xy 93.296259 -348.113227) (xy 93.353424 -348.104491) (xy 93.382338 -348.103952)
			(xy 93.410905 -348.104492) (xy 93.467399 -348.113024) (xy 93.521992 -348.129875) (xy 93.573466 -348.15467)
			(xy 93.620672 -348.186857) (xy 93.662557 -348.225716) (xy 93.680788 -348.247716) (xy 93.690372 -348.258945)
			(xy 93.714608 -348.275783) (xy 93.742643 -348.284996) (xy 93.772143 -348.285814) (xy 93.800646 -348.278172)
			(xy 93.825779 -348.262704) (xy 93.835982 -348.252034) (xy 93.854145 -348.232411) (xy 93.895029 -348.197953)
			(xy 93.940324 -348.16954) (xy 93.989143 -348.147728) (xy 94.040528 -348.132946) (xy 94.093473 -348.125482)
			(xy 94.120208 -348.125034) (xy 94.149123 -348.125606) (xy 94.206292 -348.134322) (xy 94.261491 -348.151568)
			(xy 94.313453 -348.17695) (xy 94.360988 -348.209885) (xy 94.403007 -348.249618) (xy 94.421198 -348.2721)
			(xy 94.431095 -348.283905) (xy 94.456419 -348.301424) (xy 94.485812 -348.3106) (xy 94.516604 -348.3106)
			(xy 94.545997 -348.301424) (xy 94.571321 -348.283905) (xy 94.581218 -348.2721) (xy 94.599399 -348.249608)
			(xy 94.641421 -348.209873) (xy 94.688958 -348.176935) (xy 94.740921 -348.151548) (xy 94.79612 -348.134294)
			(xy 94.853291 -348.125568) (xy 94.882208 -348.125034) (xy 94.909462 -348.125436) (xy 94.963415 -348.133195)
			(xy 95.015714 -348.148552) (xy 95.065296 -348.171196) (xy 95.11115 -348.200666) (xy 95.152344 -348.236362)
			(xy 95.188039 -348.277556) (xy 95.217508 -348.323411) (xy 95.240151 -348.372993) (xy 95.255507 -348.425293)
			(xy 95.263264 -348.479246) (xy 95.263264 -348.512752) (xy 95.383338 -348.512752) (xy 95.383338 -348.458248)
			(xy 95.391094 -348.404299) (xy 95.406448 -348.352003) (xy 95.429088 -348.302424) (xy 95.458553 -348.256571)
			(xy 95.494242 -348.215378) (xy 95.535431 -348.179683) (xy 95.58128 -348.150212) (xy 95.630856 -348.127565)
			(xy 95.68315 -348.112204) (xy 95.737098 -348.104441) (xy 95.76435 -348.103952) (xy 95.793267 -348.104486)
			(xy 95.850438 -348.113209) (xy 95.905637 -348.130463) (xy 95.9576 -348.155851) (xy 96.005134 -348.188793)
			(xy 96.04715 -348.228533) (xy 96.06534 -348.251018) (xy 96.075237 -348.262823) (xy 96.100561 -348.280342)
			(xy 96.129954 -348.289518) (xy 96.160746 -348.289518) (xy 96.190139 -348.280342) (xy 96.215463 -348.262823)
			(xy 96.22536 -348.251018) (xy 96.243578 -348.228557) (xy 96.285592 -348.18882) (xy 96.333121 -348.155878)
			(xy 96.385077 -348.130485) (xy 96.44027 -348.113224) (xy 96.497436 -348.10449) (xy 96.52635 -348.103952)
			(xy 96.553602 -348.104492) (xy 96.607553 -348.112242) (xy 96.659851 -348.127592) (xy 96.709433 -348.15023)
			(xy 96.755287 -348.179693) (xy 96.796482 -348.215383) (xy 96.832177 -348.256573) (xy 96.861646 -348.302423)
			(xy 96.88429 -348.352002) (xy 96.899647 -348.404298) (xy 96.907405 -348.458248) (xy 96.907405 -348.512752)
			(xy 96.899647 -348.566702) (xy 96.88429 -348.618998) (xy 96.861646 -348.668577) (xy 96.832177 -348.714427)
			(xy 96.796482 -348.755617) (xy 96.755287 -348.791307) (xy 96.709433 -348.82077) (xy 96.659851 -348.843408)
			(xy 96.607553 -348.858758) (xy 96.553602 -348.866508) (xy 96.52635 -348.866968) (xy 96.497434 -348.866426)
			(xy 96.440263 -348.857704) (xy 96.385064 -348.840451) (xy 96.333102 -348.815064) (xy 96.285568 -348.782124)
			(xy 96.24355 -348.742386) (xy 96.22536 -348.719902) (xy 96.215463 -348.708097) (xy 96.190139 -348.690578)
			(xy 96.160746 -348.681402) (xy 96.129954 -348.681402) (xy 96.100561 -348.690578) (xy 96.075237 -348.708097)
			(xy 96.06534 -348.719902) (xy 96.047127 -348.742367) (xy 96.005112 -348.782103) (xy 95.957581 -348.815044)
			(xy 95.905624 -348.840436) (xy 95.850431 -348.857696) (xy 95.793265 -348.86643) (xy 95.76435 -348.866968)
			(xy 95.737098 -348.866559) (xy 95.68315 -348.858796) (xy 95.630856 -348.843435) (xy 95.58128 -348.820788)
			(xy 95.535431 -348.791317) (xy 95.494242 -348.755622) (xy 95.458553 -348.714429) (xy 95.429088 -348.668576)
			(xy 95.406448 -348.618997) (xy 95.391094 -348.566701) (xy 95.383338 -348.512752) (xy 95.263264 -348.512752)
			(xy 95.263264 -348.533754) (xy 95.255507 -348.587707) (xy 95.240151 -348.640007) (xy 95.217508 -348.689589)
			(xy 95.188039 -348.735444) (xy 95.152344 -348.776638) (xy 95.11115 -348.812334) (xy 95.065296 -348.841804)
			(xy 95.015714 -348.864448) (xy 94.963415 -348.879805) (xy 94.909462 -348.887564) (xy 94.882208 -348.88805)
			(xy 94.85329 -348.887545) (xy 94.796118 -348.878816) (xy 94.740918 -348.861556) (xy 94.688956 -348.836162)
			(xy 94.641422 -348.803216) (xy 94.599407 -348.763471) (xy 94.581218 -348.740984) (xy 94.571321 -348.729179)
			(xy 94.545997 -348.71166) (xy 94.516604 -348.702484) (xy 94.485812 -348.702484) (xy 94.456419 -348.71166)
			(xy 94.431095 -348.729179) (xy 94.421198 -348.740984) (xy 94.403004 -348.763465) (xy 94.360985 -348.803201)
			(xy 94.313451 -348.836141) (xy 94.26149 -348.86153) (xy 94.206293 -348.878786) (xy 94.149124 -348.887515)
			(xy 94.120208 -348.88805) (xy 94.091642 -348.887476) (xy 94.03515 -348.878952) (xy 93.980557 -348.862107)
			(xy 93.929083 -348.837318) (xy 93.881876 -348.805137) (xy 93.83999 -348.766284) (xy 93.821758 -348.744286)
			(xy 93.812126 -348.733102) (xy 93.787903 -348.716262) (xy 93.75988 -348.707045) (xy 93.730391 -348.706217)
			(xy 93.701895 -348.713849) (xy 93.676767 -348.729304) (xy 93.666564 -348.739968) (xy 93.648379 -348.759569)
			(xy 93.607499 -348.794029) (xy 93.562209 -348.822445) (xy 93.513395 -348.84426) (xy 93.462014 -348.859047)
			(xy 93.409071 -348.866516) (xy 93.382338 -348.866968) (xy 93.353422 -348.866435) (xy 93.29625 -348.85771)
			(xy 93.241051 -348.840456) (xy 93.189089 -348.815068) (xy 93.141555 -348.782126) (xy 93.099538 -348.742387)
			(xy 93.081348 -348.719902) (xy 93.071451 -348.708097) (xy 93.046127 -348.690578) (xy 93.016734 -348.681402)
			(xy 92.985942 -348.681402) (xy 92.956549 -348.690578) (xy 92.931225 -348.708097) (xy 92.921328 -348.719902)
			(xy 92.904575 -348.740685) (xy 92.866221 -348.777815) (xy 92.823067 -348.809237) (xy 92.775953 -348.834336)
			(xy 92.725801 -348.852622) (xy 92.67359 -348.863739) (xy 92.620338 -348.867469) (xy 92.567086 -348.863739)
			(xy 92.514875 -348.852622) (xy 92.464723 -348.834336) (xy 92.417609 -348.809237) (xy 92.374455 -348.777815)
			(xy 92.336101 -348.740685) (xy 92.319348 -348.719902) (xy 92.309451 -348.708097) (xy 92.284127 -348.690578)
			(xy 92.254734 -348.681402) (xy 92.223942 -348.681402) (xy 92.194549 -348.690578) (xy 92.169225 -348.708097)
			(xy 92.159328 -348.719902) (xy 92.142575 -348.740685) (xy 92.104221 -348.777815) (xy 92.061067 -348.809237)
			(xy 92.013953 -348.834336) (xy 91.963801 -348.852622) (xy 91.91159 -348.863739) (xy 91.858338 -348.867469)
			(xy 91.805086 -348.863739) (xy 91.752875 -348.852622) (xy 91.702723 -348.834336) (xy 91.655609 -348.809237)
			(xy 91.612455 -348.777815) (xy 91.574101 -348.740685) (xy 91.557348 -348.719902) (xy 91.547451 -348.708097)
			(xy 91.522127 -348.690578) (xy 91.492734 -348.681402) (xy 91.461942 -348.681402) (xy 91.432549 -348.690578)
			(xy 91.407225 -348.708097) (xy 91.397328 -348.719902) (xy 91.379122 -348.742372) (xy 91.337105 -348.782108)
			(xy 91.289573 -348.815049) (xy 91.237615 -348.840439) (xy 91.18242 -348.857699) (xy 91.125253 -348.866431)
			(xy 91.096338 -348.866968) (xy 91.06908 -348.866588) (xy 91.01512 -348.858834) (xy 90.962812 -348.84348)
			(xy 90.913222 -348.820837) (xy 90.867359 -348.791367) (xy 90.826157 -348.75567) (xy 90.790456 -348.714472)
			(xy 90.760981 -348.668612) (xy 90.738333 -348.619024) (xy 90.722974 -348.566717) (xy 90.715215 -348.512757)
			(xy 90.509949 -348.512757) (xy 90.505197 -348.545806) (xy 90.489841 -348.598105) (xy 90.467198 -348.647686)
			(xy 90.437729 -348.693541) (xy 90.402034 -348.734734) (xy 90.360841 -348.770429) (xy 90.314986 -348.799898)
			(xy 90.265405 -348.822541) (xy 90.213106 -348.837897) (xy 90.159154 -348.845654) (xy 90.1319 -348.84614)
			(xy 90.102982 -348.845644) (xy 90.045809 -348.836914) (xy 89.990608 -348.819653) (xy 89.938646 -348.794257)
			(xy 89.891113 -348.761308) (xy 89.849098 -348.721562) (xy 89.83091 -348.699074) (xy 89.821013 -348.687269)
			(xy 89.795689 -348.66975) (xy 89.766296 -348.660574) (xy 89.735504 -348.660574) (xy 89.706111 -348.66975)
			(xy 89.680787 -348.687269) (xy 89.67089 -348.699074) (xy 89.652698 -348.721557) (xy 89.610679 -348.761293)
			(xy 89.563145 -348.794233) (xy 89.511184 -348.819622) (xy 89.455986 -348.836878) (xy 89.398816 -348.845606)
			(xy 89.3699 -348.84614) (xy 89.369646 -348.84614) (xy 89.343446 -348.845681) (xy 89.291541 -348.838497)
			(xy 89.241105 -348.824284) (xy 89.193086 -348.803309) (xy 89.17051 -348.790006) (xy 89.160875 -348.784726)
			(xy 89.139075 -348.782162) (xy 89.118188 -348.788913) (xy 89.102011 -348.80375) (xy 89.093486 -348.823978)
			(xy 89.093294 -348.834964) (xy 89.093548 -348.848172) (xy 89.093485 -348.85931) (xy 89.092212 -348.881549)
			(xy 89.091008 -348.892622) (xy 89.089693 -348.907591) (xy 89.094978 -348.937162) (xy 89.108636 -348.963917)
			(xy 89.129485 -348.985543) (xy 89.155724 -349.000168) (xy 89.185082 -349.00653) (xy 89.215021 -349.004077)
			(xy 89.229184 -348.999048) (xy 89.251653 -348.990521) (xy 89.298193 -348.978532) (xy 89.34587 -348.972489)
			(xy 89.3699 -348.972124) (xy 89.398817 -348.972633) (xy 89.455989 -348.981363) (xy 89.511189 -348.998622)
			(xy 89.563151 -349.024015) (xy 89.610684 -349.056961) (xy 89.6527 -349.096704) (xy 89.67089 -349.11919)
			(xy 89.680787 -349.130995) (xy 89.706111 -349.148514) (xy 89.735504 -349.15769) (xy 89.766296 -349.15769)
			(xy 89.795689 -349.148514) (xy 89.821013 -349.130995) (xy 89.83091 -349.11919) (xy 89.849093 -349.0967)
			(xy 89.891115 -349.056965) (xy 89.938651 -349.024027) (xy 89.990614 -348.99864) (xy 90.045813 -348.981385)
			(xy 90.102984 -348.972658) (xy 90.1319 -348.972124) (xy 90.159154 -348.972555) (xy 90.213108 -348.980313)
			(xy 90.265408 -348.995671) (xy 90.314991 -349.018316) (xy 90.360845 -349.047787) (xy 90.402039 -349.083484)
			(xy 90.437733 -349.12468) (xy 90.4672 -349.170537) (xy 90.48984 -349.220122) (xy 90.505194 -349.272423)
			(xy 90.512947 -349.326378) (xy 90.513408 -349.353632) (xy 90.512876 -349.382549) (xy 90.504154 -349.439721)
			(xy 90.486902 -349.494921) (xy 90.461513 -349.546884) (xy 90.42857 -349.594417) (xy 90.388828 -349.636433)
			(xy 90.366342 -349.654622) (xy 90.354502 -349.664483) (xy 90.33698 -349.689815) (xy 90.327805 -349.719219)
			(xy 90.327811 -349.750021) (xy 90.336997 -349.779421) (xy 90.354529 -349.804746) (xy 90.366342 -349.814642)
			(xy 90.387156 -349.831358) (xy 90.424287 -349.869715) (xy 90.455708 -349.912875) (xy 90.480807 -349.959992)
			(xy 90.499092 -350.010149) (xy 90.510206 -350.062365) (xy 90.513933 -350.11562) (xy 90.512473 -350.13646)
			(xy 90.71483 -350.13646) (xy 90.71538 -350.107544) (xy 90.724101 -350.050374) (xy 90.741352 -349.995175)
			(xy 90.766737 -349.943213) (xy 90.799676 -349.895678) (xy 90.839412 -349.853661) (xy 90.861896 -349.83547)
			(xy 90.87374 -349.825616) (xy 90.891256 -349.80028) (xy 90.900426 -349.770876) (xy 90.900419 -349.740075)
			(xy 90.891234 -349.710676) (xy 90.873706 -349.685348) (xy 90.861896 -349.67545) (xy 90.839436 -349.657232)
			(xy 90.799699 -349.615218) (xy 90.766758 -349.567688) (xy 90.741365 -349.515732) (xy 90.724104 -349.46054)
			(xy 90.715369 -349.403374) (xy 90.71483 -349.37446) (xy 90.715241 -349.347206) (xy 90.723004 -349.293254)
			(xy 90.738366 -349.240955) (xy 90.761014 -349.191375) (xy 90.790488 -349.145523) (xy 90.826188 -349.104332)
			(xy 90.867386 -349.068642) (xy 90.913244 -349.039177) (xy 90.962828 -349.016538) (xy 91.01513 -349.001187)
			(xy 91.069084 -348.993435) (xy 91.096338 -348.992952) (xy 91.125254 -348.993495) (xy 91.182425 -349.002217)
			(xy 91.237624 -349.019468) (xy 91.289586 -349.044855) (xy 91.337121 -349.077795) (xy 91.379138 -349.117534)
			(xy 91.397328 -349.140018) (xy 91.407225 -349.151823) (xy 91.432549 -349.169342) (xy 91.461942 -349.178518)
			(xy 91.492734 -349.178518) (xy 91.522127 -349.169342) (xy 91.547451 -349.151823) (xy 91.557348 -349.140018)
			(xy 91.574101 -349.119235) (xy 91.612455 -349.082105) (xy 91.655609 -349.050683) (xy 91.702723 -349.025584)
			(xy 91.752875 -349.007298) (xy 91.805086 -348.996181) (xy 91.858338 -348.992451) (xy 91.91159 -348.996181)
			(xy 91.963801 -349.007298) (xy 92.013953 -349.025584) (xy 92.061067 -349.050683) (xy 92.104221 -349.082105)
			(xy 92.142575 -349.119235) (xy 92.159328 -349.140018) (xy 92.169225 -349.151823) (xy 92.194549 -349.169342)
			(xy 92.223942 -349.178518) (xy 92.254734 -349.178518) (xy 92.284127 -349.169342) (xy 92.309451 -349.151823)
			(xy 92.319348 -349.140018) (xy 92.336101 -349.119235) (xy 92.374455 -349.082105) (xy 92.417609 -349.050683)
			(xy 92.464723 -349.025584) (xy 92.514875 -349.007298) (xy 92.567086 -348.996181) (xy 92.620338 -348.992451)
			(xy 92.67359 -348.996181) (xy 92.725801 -349.007298) (xy 92.775953 -349.025584) (xy 92.823067 -349.050683)
			(xy 92.866221 -349.082105) (xy 92.904575 -349.119235) (xy 92.921328 -349.140018) (xy 92.931225 -349.151823)
			(xy 92.956549 -349.169342) (xy 92.985942 -349.178518) (xy 93.016734 -349.178518) (xy 93.046127 -349.169342)
			(xy 93.071451 -349.151823) (xy 93.081348 -349.140018) (xy 93.099573 -349.117563) (xy 93.141585 -349.077825)
			(xy 93.189113 -349.044882) (xy 93.241067 -349.019489) (xy 93.296259 -349.002227) (xy 93.353424 -348.993491)
			(xy 93.382338 -348.992952) (xy 93.410905 -348.993492) (xy 93.467399 -349.002024) (xy 93.521992 -349.018875)
			(xy 93.573466 -349.04367) (xy 93.620672 -349.075857) (xy 93.662557 -349.114716) (xy 93.680788 -349.136716)
			(xy 93.690372 -349.147945) (xy 93.714608 -349.164783) (xy 93.742643 -349.173996) (xy 93.772143 -349.174814)
			(xy 93.800646 -349.167172) (xy 93.825779 -349.151704) (xy 93.835982 -349.141034) (xy 93.854145 -349.121411)
			(xy 93.895029 -349.086953) (xy 93.940324 -349.05854) (xy 93.989143 -349.036728) (xy 94.040528 -349.021946)
			(xy 94.093473 -349.014482) (xy 94.120208 -349.014034) (xy 94.149123 -349.014606) (xy 94.206292 -349.023322)
			(xy 94.261491 -349.040568) (xy 94.313453 -349.06595) (xy 94.360988 -349.098885) (xy 94.403007 -349.138618)
			(xy 94.421198 -349.1611) (xy 94.431095 -349.172905) (xy 94.456419 -349.190424) (xy 94.485812 -349.1996)
			(xy 94.516604 -349.1996) (xy 94.545997 -349.190424) (xy 94.571321 -349.172905) (xy 94.581218 -349.1611)
			(xy 94.599399 -349.138608) (xy 94.641421 -349.098873) (xy 94.688958 -349.065935) (xy 94.740921 -349.040548)
			(xy 94.79612 -349.023294) (xy 94.853291 -349.014568) (xy 94.882208 -349.014034) (xy 94.909463 -349.014448)
			(xy 94.963418 -349.022207) (xy 95.015719 -349.037566) (xy 95.065302 -349.060213) (xy 95.111157 -349.089686)
			(xy 95.152351 -349.125385) (xy 95.188044 -349.166583) (xy 95.217511 -349.212442) (xy 95.240151 -349.262028)
			(xy 95.255503 -349.314331) (xy 95.263256 -349.368287) (xy 95.263716 -349.395542) (xy 95.26314 -349.424984)
			(xy 95.254075 -349.483167) (xy 95.236182 -349.539267) (xy 95.209886 -349.591954) (xy 95.17581 -349.639978)
			(xy 95.134764 -349.682198) (xy 95.11157 -349.700342) (xy 95.101069 -349.708669) (xy 95.084553 -349.729767)
			(xy 95.074096 -349.754435) (xy 95.070417 -349.780975) (xy 95.073771 -349.807558) (xy 95.083926 -349.832353)
			(xy 95.100182 -349.853651) (xy 95.110554 -349.86214) (xy 95.133163 -349.880342) (xy 95.173168 -349.922394)
			(xy 95.20634 -349.970022) (xy 95.231914 -350.022125) (xy 95.249298 -350.077501) (xy 95.258093 -350.134872)
			(xy 95.258123 -350.136475) (xy 95.382291 -350.136475) (xy 95.386025 -350.083218) (xy 95.397148 -350.031001)
			(xy 95.415441 -349.980845) (xy 95.440549 -349.933729) (xy 95.471979 -349.890574) (xy 95.50912 -349.852222)
			(xy 95.529908 -349.83547) (xy 95.541751 -349.825615) (xy 95.559264 -349.800279) (xy 95.568434 -349.770875)
			(xy 95.568426 -349.740076) (xy 95.559243 -349.710677) (xy 95.541717 -349.685349) (xy 95.529908 -349.67545)
			(xy 95.50745 -349.657229) (xy 95.467713 -349.615216) (xy 95.434771 -349.567687) (xy 95.409378 -349.515732)
			(xy 95.392116 -349.460539) (xy 95.383381 -349.403374) (xy 95.382842 -349.37446) (xy 95.383218 -349.347204)
			(xy 95.390982 -349.293247) (xy 95.406345 -349.240945) (xy 95.428996 -349.191361) (xy 95.458473 -349.145506)
			(xy 95.494176 -349.104312) (xy 95.535378 -349.068619) (xy 95.58124 -349.039153) (xy 95.630829 -349.016514)
			(xy 95.683135 -349.001162) (xy 95.737094 -348.993411) (xy 95.76435 -348.992952) (xy 95.793267 -348.993486)
			(xy 95.850438 -349.002209) (xy 95.905637 -349.019463) (xy 95.9576 -349.044851) (xy 96.005134 -349.077793)
			(xy 96.04715 -349.117533) (xy 96.06534 -349.140018) (xy 96.075237 -349.151823) (xy 96.100561 -349.169342)
			(xy 96.129954 -349.178518) (xy 96.160746 -349.178518) (xy 96.190139 -349.169342) (xy 96.215463 -349.151823)
			(xy 96.22536 -349.140018) (xy 96.243578 -349.117557) (xy 96.285592 -349.07782) (xy 96.333121 -349.044878)
			(xy 96.385077 -349.019485) (xy 96.44027 -349.002224) (xy 96.497436 -348.99349) (xy 96.52635 -348.992952)
			(xy 96.5536 -348.993502) (xy 96.607546 -349.001251) (xy 96.659839 -349.016598) (xy 96.709417 -349.039232)
			(xy 96.755268 -349.068691) (xy 96.79646 -349.104376) (xy 96.832155 -349.14556) (xy 96.861625 -349.191404)
			(xy 96.88427 -349.240976) (xy 96.89963 -349.293266) (xy 96.907392 -349.34721) (xy 96.907858 -349.37446)
			(xy 96.907327 -349.403377) (xy 96.898603 -349.460548) (xy 96.881348 -349.515747) (xy 96.855959 -349.567709)
			(xy 96.823017 -349.615243) (xy 96.783277 -349.65726) (xy 96.760792 -349.67545) (xy 96.749029 -349.685392)
			(xy 96.731514 -349.710704) (xy 96.722336 -349.740085) (xy 96.722329 -349.770866) (xy 96.731493 -349.800251)
			(xy 96.748995 -349.825572) (xy 96.760792 -349.83547) (xy 96.781538 -349.852269) (xy 96.818672 -349.890615)
			(xy 96.850097 -349.933763) (xy 96.875201 -349.980871) (xy 96.893491 -350.031019) (xy 96.904612 -350.083227)
			(xy 96.908345 -350.136475) (xy 96.904619 -350.189724) (xy 96.893505 -350.241934) (xy 96.875221 -350.292084)
			(xy 96.850124 -350.339195) (xy 96.818704 -350.382347) (xy 96.781574 -350.420698) (xy 96.760792 -350.43745)
			(xy 96.749029 -350.447392) (xy 96.731514 -350.472704) (xy 96.722336 -350.502085) (xy 96.722329 -350.532866)
			(xy 96.731493 -350.562251) (xy 96.748995 -350.587572) (xy 96.760792 -350.59747) (xy 96.783259 -350.61568)
			(xy 96.822996 -350.657696) (xy 96.855937 -350.705226) (xy 96.881328 -350.757184) (xy 96.898588 -350.812378)
			(xy 96.907321 -350.869545) (xy 96.907858 -350.89846) (xy 96.907407 -350.925714) (xy 96.899655 -350.979668)
			(xy 96.884301 -351.031969) (xy 96.86166 -351.081553) (xy 96.832191 -351.127408) (xy 96.796496 -351.168603)
			(xy 96.7553 -351.204297) (xy 96.709444 -351.233764) (xy 96.65986 -351.256405) (xy 96.607558 -351.271757)
			(xy 96.553604 -351.279508) (xy 96.52635 -351.279968) (xy 96.497434 -351.279426) (xy 96.440263 -351.270704)
			(xy 96.385064 -351.253451) (xy 96.333102 -351.228064) (xy 96.285568 -351.195124) (xy 96.24355 -351.155386)
			(xy 96.22536 -351.132902) (xy 96.215463 -351.121097) (xy 96.190139 -351.103578) (xy 96.160746 -351.094402)
			(xy 96.129954 -351.094402) (xy 96.100561 -351.103578) (xy 96.075237 -351.121097) (xy 96.06534 -351.132902)
			(xy 96.047127 -351.155367) (xy 96.005112 -351.195103) (xy 95.957581 -351.228044) (xy 95.905624 -351.253436)
			(xy 95.850431 -351.270696) (xy 95.793265 -351.27943) (xy 95.76435 -351.279968) (xy 95.737097 -351.279498)
			(xy 95.683144 -351.271747) (xy 95.630844 -351.256395) (xy 95.581261 -351.233756) (xy 95.535406 -351.204289)
			(xy 95.494211 -351.168596) (xy 95.458517 -351.127402) (xy 95.429049 -351.081548) (xy 95.406408 -351.031966)
			(xy 95.391055 -350.979666) (xy 95.383303 -350.925713) (xy 95.382842 -350.89846) (xy 95.383387 -350.869544)
			(xy 95.392108 -350.812373) (xy 95.40936 -350.757174) (xy 95.434746 -350.705212) (xy 95.467686 -350.657678)
			(xy 95.507424 -350.61566) (xy 95.529908 -350.59747) (xy 95.541751 -350.587615) (xy 95.559264 -350.562279)
			(xy 95.568434 -350.532875) (xy 95.568426 -350.502076) (xy 95.559243 -350.472677) (xy 95.541717 -350.447349)
			(xy 95.529908 -350.43745) (xy 95.509083 -350.420745) (xy 95.471948 -350.382388) (xy 95.440522 -350.339229)
			(xy 95.415421 -350.29211) (xy 95.397134 -350.241951) (xy 95.386018 -350.189733) (xy 95.382291 -350.136475)
			(xy 95.258123 -350.136475) (xy 95.258636 -350.163892) (xy 95.25815 -350.191143) (xy 95.250394 -350.245091)
			(xy 95.235039 -350.297386) (xy 95.212397 -350.346963) (xy 95.182931 -350.392813) (xy 95.14724 -350.434004)
			(xy 95.106049 -350.469695) (xy 95.060199 -350.499161) (xy 95.010622 -350.521803) (xy 94.958327 -350.537158)
			(xy 94.904379 -350.544914) (xy 94.849877 -350.544914) (xy 94.795929 -350.537158) (xy 94.743634 -350.521803)
			(xy 94.694057 -350.499161) (xy 94.648207 -350.469695) (xy 94.607016 -350.434004) (xy 94.571325 -350.392813)
			(xy 94.541859 -350.346963) (xy 94.519217 -350.297386) (xy 94.503862 -350.245091) (xy 94.496106 -350.191143)
			(xy 94.49562 -350.163892) (xy 94.496134 -350.134447) (xy 94.50521 -350.076261) (xy 94.523114 -350.020159)
			(xy 94.549422 -349.967472) (xy 94.583509 -349.91945) (xy 94.624567 -349.877233) (xy 94.647766 -349.859092)
			(xy 94.65823 -349.850724) (xy 94.67474 -349.829634) (xy 94.685196 -349.804975) (xy 94.688878 -349.778445)
			(xy 94.685532 -349.751871) (xy 94.675388 -349.727082) (xy 94.659146 -349.705784) (xy 94.648782 -349.697294)
			(xy 94.63008 -349.682385) (xy 94.596195 -349.648631) (xy 94.581218 -349.629984) (xy 94.571321 -349.618179)
			(xy 94.545997 -349.60066) (xy 94.516604 -349.591484) (xy 94.485812 -349.591484) (xy 94.456419 -349.60066)
			(xy 94.431095 -349.618179) (xy 94.421198 -349.629984) (xy 94.403004 -349.652465) (xy 94.360985 -349.692201)
			(xy 94.313451 -349.725141) (xy 94.26149 -349.75053) (xy 94.206293 -349.767786) (xy 94.149124 -349.776515)
			(xy 94.120208 -349.77705) (xy 94.091642 -349.776476) (xy 94.03515 -349.767952) (xy 93.980557 -349.751107)
			(xy 93.929083 -349.726318) (xy 93.881876 -349.694137) (xy 93.83999 -349.655284) (xy 93.821758 -349.633286)
			(xy 93.812126 -349.622102) (xy 93.787903 -349.605262) (xy 93.75988 -349.596045) (xy 93.730391 -349.595217)
			(xy 93.701895 -349.602849) (xy 93.676767 -349.618304) (xy 93.666564 -349.628968) (xy 93.648379 -349.648569)
			(xy 93.607499 -349.683029) (xy 93.562209 -349.711445) (xy 93.513395 -349.73326) (xy 93.462014 -349.748047)
			(xy 93.409071 -349.755516) (xy 93.382338 -349.755968) (xy 93.353422 -349.755435) (xy 93.29625 -349.74671)
			(xy 93.241051 -349.729456) (xy 93.189089 -349.704068) (xy 93.141555 -349.671126) (xy 93.099538 -349.631387)
			(xy 93.081348 -349.608902) (xy 93.071451 -349.597097) (xy 93.046127 -349.579578) (xy 93.016734 -349.570402)
			(xy 92.985942 -349.570402) (xy 92.956549 -349.579578) (xy 92.931225 -349.597097) (xy 92.921328 -349.608902)
			(xy 92.904575 -349.629685) (xy 92.866221 -349.666815) (xy 92.823067 -349.698237) (xy 92.775953 -349.723336)
			(xy 92.725801 -349.741622) (xy 92.67359 -349.752739) (xy 92.620338 -349.756469) (xy 92.567086 -349.752739)
			(xy 92.514875 -349.741622) (xy 92.464723 -349.723336) (xy 92.417609 -349.698237) (xy 92.374455 -349.666815)
			(xy 92.336101 -349.629685) (xy 92.319348 -349.608902) (xy 92.309451 -349.597097) (xy 92.284127 -349.579578)
			(xy 92.254734 -349.570402) (xy 92.223942 -349.570402) (xy 92.194549 -349.579578) (xy 92.169225 -349.597097)
			(xy 92.159328 -349.608902) (xy 92.142575 -349.629685) (xy 92.104221 -349.666815) (xy 92.061067 -349.698237)
			(xy 92.013953 -349.723336) (xy 91.963801 -349.741622) (xy 91.91159 -349.752739) (xy 91.858338 -349.756469)
			(xy 91.805086 -349.752739) (xy 91.752875 -349.741622) (xy 91.702723 -349.723336) (xy 91.655609 -349.698237)
			(xy 91.612455 -349.666815) (xy 91.574101 -349.629685) (xy 91.557348 -349.608902) (xy 91.547451 -349.597097)
			(xy 91.522127 -349.579578) (xy 91.492734 -349.570402) (xy 91.461942 -349.570402) (xy 91.432549 -349.579578)
			(xy 91.407225 -349.597097) (xy 91.397328 -349.608902) (xy 91.382552 -349.627303) (xy 91.34918 -349.660673)
			(xy 91.33078 -349.67545) (xy 91.319018 -349.685393) (xy 91.301506 -349.710705) (xy 91.292329 -349.740086)
			(xy 91.292321 -349.770865) (xy 91.301484 -349.80025) (xy 91.318984 -349.825571) (xy 91.33078 -349.83547)
			(xy 91.353245 -349.853683) (xy 91.392982 -349.895698) (xy 91.425924 -349.943228) (xy 91.451316 -349.995185)
			(xy 91.468576 -350.050379) (xy 91.477309 -350.107545) (xy 91.477846 -350.13646) (xy 91.47736 -350.163711)
			(xy 91.469604 -350.217659) (xy 91.454249 -350.269954) (xy 91.431607 -350.319531) (xy 91.402141 -350.365381)
			(xy 91.36645 -350.406572) (xy 91.325259 -350.442263) (xy 91.279409 -350.471729) (xy 91.229832 -350.494371)
			(xy 91.177537 -350.509726) (xy 91.123589 -350.517482) (xy 91.069087 -350.517482) (xy 91.015139 -350.509726)
			(xy 90.962844 -350.494371) (xy 90.913267 -350.471729) (xy 90.867417 -350.442263) (xy 90.826226 -350.406572)
			(xy 90.790535 -350.365381) (xy 90.761069 -350.319531) (xy 90.738427 -350.269954) (xy 90.723072 -350.217659)
			(xy 90.715316 -350.163711) (xy 90.71483 -350.13646) (xy 90.512473 -350.13646) (xy 90.510201 -350.168874)
			(xy 90.499081 -350.221089) (xy 90.480791 -350.271244) (xy 90.455688 -350.318359) (xy 90.424262 -350.361515)
			(xy 90.387127 -350.399869) (xy 90.366342 -350.416622) (xy 90.354502 -350.426483) (xy 90.33698 -350.451815)
			(xy 90.327805 -350.481219) (xy 90.327811 -350.512021) (xy 90.336997 -350.541421) (xy 90.354529 -350.566746)
			(xy 90.366342 -350.576642) (xy 90.388854 -350.594799) (xy 90.428586 -350.636827) (xy 90.46152 -350.684369)
			(xy 90.486903 -350.736337) (xy 90.504154 -350.79154) (xy 90.512876 -350.848714) (xy 90.513408 -350.877632)
			(xy 90.512952 -350.904884) (xy 90.505191 -350.958833) (xy 90.489832 -351.011128) (xy 90.467187 -351.060705)
			(xy 90.437717 -351.106556) (xy 90.402023 -351.147746) (xy 90.36083 -351.183437) (xy 90.314977 -351.212902)
			(xy 90.265398 -351.235543) (xy 90.213102 -351.250898) (xy 90.159152 -351.258654) (xy 90.1319 -351.25914)
			(xy 90.102982 -351.258644) (xy 90.045809 -351.249914) (xy 89.990608 -351.232653) (xy 89.938646 -351.207257)
			(xy 89.891113 -351.174308) (xy 89.849098 -351.134562) (xy 89.83091 -351.112074) (xy 89.821013 -351.100269)
			(xy 89.795689 -351.08275) (xy 89.766296 -351.073574) (xy 89.735504 -351.073574) (xy 89.706111 -351.08275)
			(xy 89.680787 -351.100269) (xy 89.67089 -351.112074) (xy 89.652698 -351.134557) (xy 89.610679 -351.174293)
			(xy 89.563145 -351.207233) (xy 89.511184 -351.232622) (xy 89.455986 -351.249878) (xy 89.398816 -351.258606)
			(xy 89.3699 -351.25914) (xy 89.342694 -351.258661) (xy 89.288835 -351.250917) (xy 89.236622 -351.235599)
			(xy 89.187116 -351.21302) (xy 89.141319 -351.183636) (xy 89.100161 -351.148044) (xy 89.064477 -351.106966)
			(xy 89.03499 -351.061235) (xy 89.0123 -351.011779) (xy 88.996866 -350.959601) (xy 88.992456 -350.93275)
			(xy 88.989721 -350.91765) (xy 88.976444 -350.889996) (xy 88.955567 -350.867522) (xy 88.928965 -350.852247)
			(xy 88.89903 -350.845546) (xy 88.868455 -350.84802) (xy 88.854026 -350.853248) (xy 88.831378 -350.861945)
			(xy 88.784423 -350.874154) (xy 88.736298 -350.880304) (xy 88.71204 -350.88068) (xy 88.684787 -350.880207)
			(xy 88.630835 -350.872455) (xy 88.578535 -350.857103) (xy 88.528954 -350.834463) (xy 88.483099 -350.804996)
			(xy 88.441905 -350.769303) (xy 88.406211 -350.728111) (xy 88.376743 -350.682257) (xy 88.354101 -350.632676)
			(xy 88.338747 -350.580377) (xy 88.330993 -350.526425) (xy 88.330532 -350.499172) (xy 77.29388 -350.499172)
			(xy 77.293978 -350.505014) (xy 77.293492 -350.532265) (xy 77.285736 -350.586213) (xy 77.270381 -350.638508)
			(xy 77.247739 -350.688085) (xy 77.218273 -350.733935) (xy 77.182582 -350.775126) (xy 77.141391 -350.810817)
			(xy 77.095541 -350.840283) (xy 77.045964 -350.862925) (xy 76.993669 -350.87828) (xy 76.939721 -350.886036)
			(xy 76.885219 -350.886036) (xy 76.831271 -350.87828) (xy 76.778976 -350.862925) (xy 76.729399 -350.840283)
			(xy 76.683549 -350.810817) (xy 76.642358 -350.775126) (xy 76.606667 -350.733935) (xy 76.577201 -350.688085)
			(xy 76.554559 -350.638508) (xy 76.539204 -350.586213) (xy 76.531448 -350.532265) (xy 76.530962 -350.505014)
			(xy 75.632222 -350.505014) (xy 75.858624 -351.024444) (xy 75.884786 -351.050606) (xy 75.884941 -351.05584)
			(xy 75.887113 -351.066083) (xy 75.889104 -351.070926) (xy 79.843965 -359.994454) (xy 87.567516 -359.994454)
			(xy 87.568039 -359.964944) (xy 87.577109 -359.906626) (xy 87.595057 -359.850402) (xy 87.621454 -359.797615)
			(xy 87.655669 -359.749525) (xy 87.696885 -359.707282) (xy 87.72017 -359.689146) (xy 87.731669 -359.679895)
			(xy 87.749252 -359.65621) (xy 87.759335 -359.628487) (xy 87.761075 -359.59904) (xy 87.754328 -359.570324)
			(xy 87.739657 -359.544732) (xy 87.729314 -359.534206) (xy 87.710907 -359.516162) (xy 87.678669 -359.475943)
			(xy 87.652144 -359.431746) (xy 87.631817 -359.384378) (xy 87.618058 -359.334703) (xy 87.611119 -359.283627)
			(xy 87.610696 -359.257854) (xy 87.611135 -359.230601) (xy 87.618898 -359.176652) (xy 87.634259 -359.124356)
			(xy 87.656906 -359.074778) (xy 87.686377 -359.028928) (xy 87.722074 -358.987738) (xy 87.763268 -358.952047)
			(xy 87.809122 -358.922582) (xy 87.858703 -358.899942) (xy 87.911001 -358.884587) (xy 87.964951 -358.876831)
			(xy 87.992204 -358.876346) (xy 88.020942 -358.876882) (xy 88.077768 -358.885504) (xy 88.132658 -358.902552)
			(xy 88.18437 -358.92764) (xy 88.231734 -358.960201) (xy 88.253062 -358.97947) (xy 88.264929 -358.989692)
			(xy 88.293199 -359.003124) (xy 88.324209 -359.007369) (xy 88.35505 -359.002028) (xy 88.382827 -358.987604)
			(xy 88.394286 -358.97693) (xy 88.403382 -358.96806) (xy 88.422574 -358.951408) (xy 88.43264 -358.943656)
			(xy 88.444447 -358.933923) (xy 88.462142 -358.908978) (xy 88.471662 -358.879914) (xy 88.472154 -358.849335)
			(xy 88.463574 -358.81998) (xy 88.44669 -358.794479) (xy 88.43518 -358.784398) (xy 88.413773 -358.766185)
			(xy 88.376036 -358.724534) (xy 88.344817 -358.677798) (xy 88.320791 -358.626987) (xy 88.30448 -358.573202)
			(xy 88.296234 -358.517606) (xy 88.295734 -358.489504) (xy 88.296173 -358.463163) (xy 88.303428 -358.410981)
			(xy 88.317788 -358.360293) (xy 88.338978 -358.31206) (xy 88.366598 -358.267197) (xy 88.400123 -358.226557)
			(xy 88.438915 -358.190911) (xy 88.460326 -358.17556) (xy 88.472459 -358.166357) (xy 88.491238 -358.142411)
			(xy 88.502137 -358.113999) (xy 88.504189 -358.083637) (xy 88.497214 -358.054017) (xy 88.481828 -358.027762)
			(xy 88.470994 -358.017064) (xy 88.451748 -357.998917) (xy 88.417965 -357.958213) (xy 88.390127 -357.913234)
			(xy 88.368767 -357.864841) (xy 88.354294 -357.813962) (xy 88.346986 -357.761573) (xy 88.346534 -357.735124)
			(xy 88.347047 -357.707644) (xy 88.354936 -357.653254) (xy 88.370553 -357.600559) (xy 88.393575 -357.550654)
			(xy 88.423525 -357.504572) (xy 88.459782 -357.463268) (xy 88.501594 -357.427598) (xy 88.524588 -357.412544)
			(xy 88.536216 -357.404727) (xy 88.554933 -357.383886) (xy 88.567286 -357.358745) (xy 88.572344 -357.331193)
			(xy 88.569727 -357.303304) (xy 88.559632 -357.277174) (xy 88.542819 -357.254769) (xy 88.531954 -357.24592)
			(xy 88.509103 -357.227703) (xy 88.468635 -357.185548) (xy 88.435063 -357.137719) (xy 88.409171 -357.085333)
			(xy 88.391564 -357.029614) (xy 88.382653 -356.971862) (xy 88.382094 -356.942644) (xy 88.382629 -356.913474)
			(xy 88.391536 -356.855819) (xy 88.409119 -356.800192) (xy 88.434968 -356.747892) (xy 88.468479 -356.700137)
			(xy 88.508871 -356.658042) (xy 88.5317 -356.639876) (xy 88.54349 -356.630122) (xy 88.561192 -356.605185)
			(xy 88.570719 -356.576125) (xy 88.571214 -356.545548) (xy 88.562635 -356.516195) (xy 88.54575 -356.490697)
			(xy 88.53424 -356.480618) (xy 88.512834 -356.462404) (xy 88.475099 -356.420752) (xy 88.443881 -356.374015)
			(xy 88.419855 -356.323205) (xy 88.403543 -356.269421) (xy 88.395295 -356.213826) (xy 88.394794 -356.185724)
			(xy 88.395234 -356.15908) (xy 88.40264 -356.106308) (xy 88.417325 -356.055083) (xy 88.439004 -356.006404)
			(xy 88.467252 -355.961219) (xy 88.50152 -355.920409) (xy 88.521032 -355.90226) (xy 88.530713 -355.892925)
			(xy 88.545327 -355.870366) (xy 88.553537 -355.844771) (xy 88.554773 -355.81792) (xy 88.548948 -355.791679)
			(xy 88.536467 -355.767873) (xy 88.527636 -355.757734) (xy 88.508665 -355.736462) (xy 88.476607 -355.689336)
			(xy 88.451906 -355.637971) (xy 88.435109 -355.583507) (xy 88.42659 -355.527151) (xy 88.426036 -355.498654)
			(xy 88.426435 -355.4714) (xy 88.434199 -355.417446) (xy 88.449562 -355.365147) (xy 88.472212 -355.315567)
			(xy 88.501687 -355.269715) (xy 88.537388 -355.228524) (xy 88.578587 -355.192833) (xy 88.624446 -355.163369)
			(xy 88.674032 -355.140731) (xy 88.726335 -355.12538) (xy 88.78029 -355.117629) (xy 88.807544 -355.117146)
			(xy 88.834954 -355.117634) (xy 88.889209 -355.125473) (xy 88.941784 -355.140999) (xy 88.991595 -355.163892)
			(xy 89.037615 -355.193679) (xy 89.078897 -355.229748) (xy 89.097104 -355.250242) (xy 89.106461 -355.260357)
			(xy 89.12933 -355.275699) (xy 89.155469 -355.284364) (xy 89.182974 -355.285721) (xy 89.20984 -355.279669)
			(xy 89.234107 -355.266652) (xy 89.254008 -355.247617) (xy 89.261442 -355.236018) (xy 89.276312 -355.212088)
			(xy 89.31195 -355.168457) (xy 89.353619 -355.130542) (xy 89.400412 -355.099171) (xy 89.451312 -355.075025)
			(xy 89.50521 -355.058629) (xy 89.560934 -355.050342) (xy 89.589102 -355.049836) (xy 89.61802 -355.050339)
			(xy 89.675192 -355.05907) (xy 89.730392 -355.07633) (xy 89.782354 -355.101724) (xy 89.829887 -355.134671)
			(xy 89.871903 -355.174415) (xy 89.890092 -355.196902) (xy 89.899989 -355.208707) (xy 89.925313 -355.226226)
			(xy 89.954706 -355.235402) (xy 89.985498 -355.235402) (xy 90.014891 -355.226226) (xy 90.040215 -355.208707)
			(xy 90.050112 -355.196902) (xy 90.066865 -355.176119) (xy 90.105219 -355.138989) (xy 90.148373 -355.107567)
			(xy 90.195487 -355.082468) (xy 90.245639 -355.064182) (xy 90.29785 -355.053065) (xy 90.351102 -355.049335)
			(xy 90.404354 -355.053065) (xy 90.456565 -355.064182) (xy 90.506717 -355.082468) (xy 90.553831 -355.107567)
			(xy 90.596985 -355.138989) (xy 90.635339 -355.176119) (xy 90.652092 -355.196902) (xy 90.661989 -355.208707)
			(xy 90.687313 -355.226226) (xy 90.716706 -355.235402) (xy 90.747498 -355.235402) (xy 90.776891 -355.226226)
			(xy 90.802215 -355.208707) (xy 90.812112 -355.196902) (xy 90.830297 -355.174413) (xy 90.872318 -355.134678)
			(xy 90.919854 -355.10174) (xy 90.971816 -355.076352) (xy 91.027015 -355.059097) (xy 91.084186 -355.05037)
			(xy 91.113102 -355.049836) (xy 91.142411 -355.05037) (xy 91.200337 -355.059342) (xy 91.256208 -355.077074)
			(xy 91.308707 -355.103148) (xy 91.356596 -355.13695) (xy 91.398748 -355.177684) (xy 91.416886 -355.200712)
			(xy 91.426627 -355.212609) (xy 91.451624 -355.230485) (xy 91.48081 -355.240107) (xy 91.511537 -355.240603)
			(xy 91.541018 -355.231927) (xy 91.566578 -355.214866) (xy 91.576652 -355.203252) (xy 91.594896 -355.181695)
			(xy 91.636601 -355.143621) (xy 91.683463 -355.112111) (xy 91.734459 -355.087854) (xy 91.788474 -355.07138)
			(xy 91.844327 -355.063049) (xy 91.872562 -355.062536) (xy 91.901479 -355.063068) (xy 91.95865 -355.071792)
			(xy 92.013849 -355.089047) (xy 92.065811 -355.114436) (xy 92.113345 -355.147377) (xy 92.155362 -355.187117)
			(xy 92.173552 -355.209602) (xy 92.183449 -355.221407) (xy 92.208773 -355.238926) (xy 92.238166 -355.248102)
			(xy 92.268958 -355.248102) (xy 92.298351 -355.238926) (xy 92.323675 -355.221407) (xy 92.333572 -355.209602)
			(xy 92.350325 -355.188819) (xy 92.388679 -355.151689) (xy 92.431833 -355.120267) (xy 92.478947 -355.095168)
			(xy 92.529099 -355.076882) (xy 92.58131 -355.065765) (xy 92.634562 -355.062035) (xy 92.687814 -355.065765)
			(xy 92.740025 -355.076882) (xy 92.790177 -355.095168) (xy 92.837291 -355.120267) (xy 92.880445 -355.151689)
			(xy 92.918799 -355.188819) (xy 92.935552 -355.209602) (xy 92.945449 -355.221407) (xy 92.970773 -355.238926)
			(xy 93.000166 -355.248102) (xy 93.030958 -355.248102) (xy 93.060351 -355.238926) (xy 93.085675 -355.221407)
			(xy 93.095572 -355.209602) (xy 93.112325 -355.188819) (xy 93.150679 -355.151689) (xy 93.193833 -355.120267)
			(xy 93.240947 -355.095168) (xy 93.291099 -355.076882) (xy 93.34331 -355.065765) (xy 93.396562 -355.062035)
			(xy 93.449814 -355.065765) (xy 93.502025 -355.076882) (xy 93.552177 -355.095168) (xy 93.599291 -355.120267)
			(xy 93.642445 -355.151689) (xy 93.680799 -355.188819) (xy 93.697552 -355.209602) (xy 93.707449 -355.221407)
			(xy 93.732773 -355.238926) (xy 93.762166 -355.248102) (xy 93.792958 -355.248102) (xy 93.822351 -355.238926)
			(xy 93.847675 -355.221407) (xy 93.857572 -355.209602) (xy 93.874325 -355.188819) (xy 93.912679 -355.151689)
			(xy 93.955833 -355.120267) (xy 94.002947 -355.095168) (xy 94.053099 -355.076882) (xy 94.10531 -355.065765)
			(xy 94.158562 -355.062035) (xy 94.211814 -355.065765) (xy 94.264025 -355.076882) (xy 94.314177 -355.095168)
			(xy 94.361291 -355.120267) (xy 94.404445 -355.151689) (xy 94.442799 -355.188819) (xy 94.459552 -355.209602)
			(xy 94.469449 -355.221407) (xy 94.494773 -355.238926) (xy 94.524166 -355.248102) (xy 94.554958 -355.248102)
			(xy 94.584351 -355.238926) (xy 94.609675 -355.221407) (xy 94.619572 -355.209602) (xy 94.637779 -355.187132)
			(xy 94.679796 -355.147396) (xy 94.727327 -355.114456) (xy 94.779285 -355.089065) (xy 94.83448 -355.071805)
			(xy 94.891647 -355.063073) (xy 94.920562 -355.062536) (xy 94.946814 -355.062978) (xy 94.998823 -355.070162)
			(xy 95.049354 -355.084412) (xy 95.097454 -355.10546) (xy 95.142211 -355.132907) (xy 95.182779 -355.166235)
			(xy 95.218392 -355.204813) (xy 95.233744 -355.226112) (xy 95.242108 -355.237325) (xy 95.263733 -355.255051)
			(xy 95.289357 -355.266248) (xy 95.317056 -355.270076) (xy 95.344755 -355.266248) (xy 95.370379 -355.255051)
			(xy 95.392004 -355.237325) (xy 95.400368 -355.226112) (xy 95.415735 -355.204826) (xy 95.451355 -355.166259)
			(xy 95.491925 -355.132939) (xy 95.536679 -355.105493) (xy 95.584773 -355.084441) (xy 95.635297 -355.070179)
			(xy 95.6873 -355.062976) (xy 95.71355 -355.062536) (xy 95.742466 -355.063076) (xy 95.799637 -355.071799)
			(xy 95.854836 -355.089052) (xy 95.906798 -355.114439) (xy 95.954333 -355.147379) (xy 95.99635 -355.187118)
			(xy 96.01454 -355.209602) (xy 96.024437 -355.221407) (xy 96.049761 -355.238926) (xy 96.079154 -355.248102)
			(xy 96.109946 -355.248102) (xy 96.139339 -355.238926) (xy 96.164663 -355.221407) (xy 96.17456 -355.209602)
			(xy 96.192774 -355.187138) (xy 96.234789 -355.147402) (xy 96.282319 -355.11446) (xy 96.334276 -355.089068)
			(xy 96.389469 -355.071808) (xy 96.446635 -355.063074) (xy 96.47555 -355.062536) (xy 96.502804 -355.063002)
			(xy 96.556757 -355.070753) (xy 96.609057 -355.086105) (xy 96.65864 -355.108745) (xy 96.704496 -355.138212)
			(xy 96.74569 -355.173906) (xy 96.781384 -355.2151) (xy 96.810852 -355.260955) (xy 96.833493 -355.310537)
			(xy 96.848845 -355.362837) (xy 96.856598 -355.41679) (xy 96.857058 -355.444044) (xy 96.856516 -355.47296)
			(xy 96.847794 -355.530131) (xy 96.830542 -355.58533) (xy 96.805155 -355.637292) (xy 96.772215 -355.684827)
			(xy 96.732476 -355.726844) (xy 96.709992 -355.745034) (xy 96.698145 -355.754885) (xy 96.680632 -355.780222)
			(xy 96.671463 -355.809627) (xy 96.671471 -355.840427) (xy 96.680655 -355.869827) (xy 96.698182 -355.895155)
			(xy 96.709992 -355.905054) (xy 96.730821 -355.921754) (xy 96.767956 -355.960111) (xy 96.799382 -356.003272)
			(xy 96.824483 -356.050391) (xy 96.84277 -356.10055) (xy 96.853885 -356.152769) (xy 96.857612 -356.206027)
			(xy 96.853878 -356.259285) (xy 96.842755 -356.311502) (xy 96.824461 -356.361658) (xy 96.799353 -356.408774)
			(xy 96.767921 -356.45193) (xy 96.73078 -356.490282) (xy 96.709992 -356.507034) (xy 96.698145 -356.516885)
			(xy 96.680632 -356.542222) (xy 96.671463 -356.571627) (xy 96.671471 -356.602427) (xy 96.680655 -356.631827)
			(xy 96.698182 -356.657155) (xy 96.709992 -356.667054) (xy 96.730821 -356.683754) (xy 96.767956 -356.722111)
			(xy 96.799382 -356.765272) (xy 96.824483 -356.812391) (xy 96.84277 -356.86255) (xy 96.853885 -356.914769)
			(xy 96.857612 -356.968027) (xy 96.853878 -357.021285) (xy 96.842755 -357.073502) (xy 96.824461 -357.123658)
			(xy 96.799353 -357.170774) (xy 96.767921 -357.21393) (xy 96.73078 -357.252282) (xy 96.709992 -357.269034)
			(xy 96.698145 -357.278885) (xy 96.680632 -357.304222) (xy 96.671463 -357.333627) (xy 96.671471 -357.364427)
			(xy 96.680655 -357.393827) (xy 96.698182 -357.419155) (xy 96.709992 -357.429054) (xy 96.730821 -357.445754)
			(xy 96.767956 -357.484111) (xy 96.799382 -357.527272) (xy 96.824483 -357.574391) (xy 96.84277 -357.62455)
			(xy 96.853885 -357.676769) (xy 96.857612 -357.730027) (xy 96.853878 -357.783285) (xy 96.842755 -357.835502)
			(xy 96.824461 -357.885658) (xy 96.799353 -357.932774) (xy 96.767921 -357.97593) (xy 96.73078 -358.014282)
			(xy 96.709992 -358.031034) (xy 96.698145 -358.040885) (xy 96.680632 -358.066222) (xy 96.671463 -358.095627)
			(xy 96.671471 -358.126427) (xy 96.680655 -358.155827) (xy 96.698182 -358.181155) (xy 96.709992 -358.191054)
			(xy 96.730821 -358.207754) (xy 96.767956 -358.246111) (xy 96.799382 -358.289272) (xy 96.824483 -358.336391)
			(xy 96.84277 -358.38655) (xy 96.853885 -358.438769) (xy 96.857612 -358.492027) (xy 96.853878 -358.545285)
			(xy 96.842755 -358.597502) (xy 96.824461 -358.647658) (xy 96.799353 -358.694774) (xy 96.767921 -358.73793)
			(xy 96.73078 -358.776282) (xy 96.709992 -358.793034) (xy 96.698145 -358.802885) (xy 96.680632 -358.828222)
			(xy 96.671463 -358.857627) (xy 96.671471 -358.888427) (xy 96.680655 -358.917827) (xy 96.698182 -358.943155)
			(xy 96.709992 -358.953054) (xy 96.732452 -358.971273) (xy 96.772189 -359.013287) (xy 96.805131 -359.060816)
			(xy 96.830523 -359.112772) (xy 96.847785 -359.167964) (xy 96.85652 -359.22513) (xy 96.857058 -359.254044)
			(xy 96.856686 -359.2813) (xy 96.848922 -359.335257) (xy 96.833557 -359.38756) (xy 96.810906 -359.437143)
			(xy 96.781429 -359.482999) (xy 96.745726 -359.524192) (xy 96.704523 -359.559885) (xy 96.658661 -359.589351)
			(xy 96.609072 -359.61199) (xy 96.556765 -359.627342) (xy 96.502806 -359.635093) (xy 96.47555 -359.635552)
			(xy 96.446634 -359.635016) (xy 96.389462 -359.626293) (xy 96.334263 -359.60904) (xy 96.282301 -359.583652)
			(xy 96.234767 -359.55071) (xy 96.19275 -359.510971) (xy 96.17456 -359.488486) (xy 96.164663 -359.476681)
			(xy 96.139339 -359.459162) (xy 96.109946 -359.449986) (xy 96.079154 -359.449986) (xy 96.049761 -359.459162)
			(xy 96.024437 -359.476681) (xy 96.01454 -359.488486) (xy 95.999762 -359.506885) (xy 95.966391 -359.540256)
			(xy 95.947992 -359.555034) (xy 95.936145 -359.564885) (xy 95.918632 -359.590222) (xy 95.909463 -359.619627)
			(xy 95.909471 -359.650427) (xy 95.918655 -359.679827) (xy 95.936182 -359.705155) (xy 95.947992 -359.715054)
			(xy 95.970452 -359.733273) (xy 96.010189 -359.775287) (xy 96.043131 -359.822816) (xy 96.068523 -359.874772)
			(xy 96.085785 -359.929964) (xy 96.09452 -359.98713) (xy 96.095058 -360.016044) (xy 96.094686 -360.0433)
			(xy 96.086922 -360.097257) (xy 96.071557 -360.14956) (xy 96.048906 -360.199143) (xy 96.019429 -360.244999)
			(xy 95.983726 -360.286192) (xy 95.942523 -360.321885) (xy 95.896661 -360.351351) (xy 95.847072 -360.37399)
			(xy 95.794765 -360.389342) (xy 95.740806 -360.397093) (xy 95.71355 -360.397552) (xy 95.687299 -360.397106)
			(xy 95.635289 -360.389924) (xy 95.584757 -360.375674) (xy 95.536658 -360.354627) (xy 95.491901 -360.32718)
			(xy 95.451332 -360.293853) (xy 95.415719 -360.255275) (xy 95.400368 -360.233976) (xy 95.392004 -360.222763)
			(xy 95.370379 -360.205037) (xy 95.344755 -360.19384) (xy 95.317056 -360.190012) (xy 95.289357 -360.19384)
			(xy 95.263733 -360.205037) (xy 95.242108 -360.222763) (xy 95.233744 -360.233976) (xy 95.218366 -360.255254)
			(xy 95.182748 -360.293821) (xy 95.14218 -360.327143) (xy 95.097428 -360.35459) (xy 95.049336 -360.375643)
			(xy 94.998813 -360.389907) (xy 94.946811 -360.397111) (xy 94.920562 -360.397552) (xy 94.892056 -360.397013)
			(xy 94.835678 -360.388524) (xy 94.781192 -360.37174) (xy 94.729809 -360.347035) (xy 94.682675 -360.31496)
			(xy 94.640838 -360.276228) (xy 94.62262 -360.254296) (xy 94.61269 -360.242603) (xy 94.587311 -360.225391)
			(xy 94.557967 -360.216484) (xy 94.527302 -360.216686) (xy 94.498078 -360.225979) (xy 94.472927 -360.243524)
			(xy 94.463108 -360.255312) (xy 94.444916 -360.277794) (xy 94.402896 -360.317529) (xy 94.355361 -360.350468)
			(xy 94.3034 -360.375856) (xy 94.248203 -360.393113) (xy 94.191034 -360.401843) (xy 94.162118 -360.402378)
			(xy 94.132824 -360.401817) (xy 94.074926 -360.392855) (xy 94.019076 -360.375156) (xy 93.966585 -360.349134)
			(xy 93.918685 -360.315399) (xy 93.876499 -360.274744) (xy 93.858334 -360.251756) (xy 93.849905 -360.241474)
			(xy 93.828885 -360.225217) (xy 93.804384 -360.214928) (xy 93.778059 -360.211303) (xy 93.751689 -360.214588)
			(xy 93.727058 -360.22456) (xy 93.70583 -360.240545) (xy 93.697298 -360.25074) (xy 93.679113 -360.27319)
			(xy 93.637118 -360.312862) (xy 93.589619 -360.345747) (xy 93.537703 -360.371091) (xy 93.482559 -360.388314)
			(xy 93.425448 -360.397022) (xy 93.396562 -360.397552) (xy 93.367646 -360.397008) (xy 93.310475 -360.388287)
			(xy 93.255276 -360.371035) (xy 93.203314 -360.345648) (xy 93.155779 -360.312709) (xy 93.113762 -360.27297)
			(xy 93.095572 -360.250486) (xy 93.085675 -360.238681) (xy 93.060351 -360.221162) (xy 93.030958 -360.211986)
			(xy 93.000166 -360.211986) (xy 92.970773 -360.221162) (xy 92.945449 -360.238681) (xy 92.935552 -360.250486)
			(xy 92.918799 -360.271269) (xy 92.880445 -360.308399) (xy 92.837291 -360.339821) (xy 92.790177 -360.36492)
			(xy 92.740025 -360.383206) (xy 92.687814 -360.394323) (xy 92.634562 -360.398053) (xy 92.58131 -360.394323)
			(xy 92.529099 -360.383206) (xy 92.478947 -360.36492) (xy 92.431833 -360.339821) (xy 92.388679 -360.308399)
			(xy 92.350325 -360.271269) (xy 92.333572 -360.250486) (xy 92.323675 -360.238681) (xy 92.298351 -360.221162)
			(xy 92.268958 -360.211986) (xy 92.238166 -360.211986) (xy 92.208773 -360.221162) (xy 92.183449 -360.238681)
			(xy 92.173552 -360.250486) (xy 92.156799 -360.271269) (xy 92.118445 -360.308399) (xy 92.075291 -360.339821)
			(xy 92.028177 -360.36492) (xy 91.978025 -360.383206) (xy 91.925814 -360.394323) (xy 91.872562 -360.398053)
			(xy 91.81931 -360.394323) (xy 91.767099 -360.383206) (xy 91.716947 -360.36492) (xy 91.669833 -360.339821)
			(xy 91.626679 -360.308399) (xy 91.588325 -360.271269) (xy 91.571572 -360.250486) (xy 91.561675 -360.238681)
			(xy 91.536351 -360.221162) (xy 91.506958 -360.211986) (xy 91.476166 -360.211986) (xy 91.446773 -360.221162)
			(xy 91.421449 -360.238681) (xy 91.411552 -360.250486) (xy 91.393328 -360.272942) (xy 91.351316 -360.312679)
			(xy 91.303788 -360.345622) (xy 91.251833 -360.371015) (xy 91.196641 -360.388277) (xy 91.139476 -360.397013)
			(xy 91.110562 -360.397552) (xy 91.084492 -360.397123) (xy 91.03284 -360.39001) (xy 90.982635 -360.375936)
			(xy 90.934812 -360.355161) (xy 90.890261 -360.328073) (xy 90.84981 -360.295175) (xy 90.81421 -360.25708)
			(xy 90.784126 -360.214495) (xy 90.771726 -360.191558) (xy 90.764913 -360.179441) (xy 90.745946 -360.159136)
			(xy 90.722205 -360.1447) (xy 90.695449 -360.137204) (xy 90.667663 -360.137204) (xy 90.640907 -360.1447)
			(xy 90.617166 -360.159136) (xy 90.598199 -360.179441) (xy 90.591386 -360.191558) (xy 90.578996 -360.214503)
			(xy 90.548924 -360.257102) (xy 90.51333 -360.295209) (xy 90.472879 -360.328114) (xy 90.428324 -360.355203)
			(xy 90.380494 -360.375973) (xy 90.330282 -360.390036) (xy 90.278622 -360.397131) (xy 90.25255 -360.397552)
			(xy 90.22617 -360.397098) (xy 90.173911 -360.389833) (xy 90.123153 -360.375435) (xy 90.074863 -360.354179)
			(xy 90.029964 -360.326471) (xy 89.989312 -360.292839) (xy 89.953683 -360.253925) (xy 89.938352 -360.232452)
			(xy 89.930165 -360.221296) (xy 89.908954 -360.203541) (xy 89.883751 -360.192138) (xy 89.856412 -360.187927)
			(xy 89.828946 -360.191218) (xy 89.803376 -360.201768) (xy 89.78158 -360.218802) (xy 89.772998 -360.229658)
			(xy 89.754877 -360.253141) (xy 89.712594 -360.294738) (xy 89.664381 -360.329286) (xy 89.6114 -360.355953)
			(xy 89.55493 -360.374095) (xy 89.496331 -360.383274) (xy 89.466674 -360.383836) (xy 89.440711 -360.38336)
			(xy 89.389265 -360.376319) (xy 89.339247 -360.36237) (xy 89.291582 -360.341771) (xy 89.247148 -360.314902)
			(xy 89.206765 -360.282259) (xy 89.17118 -360.244444) (xy 89.141048 -360.202155) (xy 89.1286 -360.179366)
			(xy 89.121978 -360.16751) (xy 89.103535 -360.147587) (xy 89.080488 -360.133238) (xy 89.054472 -360.12548)
			(xy 89.02733 -360.124862) (xy 89.000988 -360.131428) (xy 88.977312 -360.144712) (xy 88.95798 -360.163774)
			(xy 88.9508 -360.175302) (xy 88.936041 -360.199594) (xy 88.900425 -360.243892) (xy 88.858631 -360.282415)
			(xy 88.811584 -360.314311) (xy 88.760326 -360.338875) (xy 88.705991 -360.355562) (xy 88.649782 -360.364004)
			(xy 88.621362 -360.364532) (xy 88.592623 -360.364023) (xy 88.535795 -360.355395) (xy 88.480904 -360.338341)
			(xy 88.429193 -360.313247) (xy 88.381831 -360.28068) (xy 88.360504 -360.261408) (xy 88.348663 -360.251155)
			(xy 88.320383 -360.237729) (xy 88.289366 -360.233492) (xy 88.258521 -360.23884) (xy 88.23074 -360.253271)
			(xy 88.21928 -360.263948) (xy 88.197682 -360.284801) (xy 88.149147 -360.320133) (xy 88.095675 -360.347424)
			(xy 88.038588 -360.366001) (xy 87.979295 -360.375403) (xy 87.949278 -360.375962) (xy 87.949024 -360.375962)
			(xy 87.92177 -360.375522) (xy 87.867815 -360.367767) (xy 87.815514 -360.352412) (xy 87.765931 -360.329769)
			(xy 87.720076 -360.300299) (xy 87.678882 -360.264603) (xy 87.643188 -360.223407) (xy 87.613721 -360.177549)
			(xy 87.59108 -360.127965) (xy 87.575728 -360.075663) (xy 87.567976 -360.021708) (xy 87.567516 -359.994454)
			(xy 79.843965 -359.994454) (xy 81.102176 -362.833412) (xy 96.770188 -362.833412) (xy 96.774259 -362.77779)
			(xy 96.786385 -362.723353) (xy 96.806308 -362.671262) (xy 96.833604 -362.622627) (xy 96.86769 -362.578484)
			(xy 96.907839 -362.539775) (xy 96.953197 -362.507324) (xy 97.002797 -362.481823) (xy 97.055581 -362.463816)
			(xy 97.110424 -362.453686) (xy 97.166158 -362.451649) (xy 97.221595 -362.457749) (xy 97.275552 -362.471855)
			(xy 97.326881 -362.493667) (xy 97.374487 -362.522721) (xy 97.417355 -362.558396) (xy 97.454572 -362.599933)
			(xy 97.485345 -362.646446) (xy 97.509017 -362.696943) (xy 97.525085 -362.75035) (xy 97.533205 -362.805526)
			(xy 97.533714 -362.833412) (xy 97.533205 -362.861298) (xy 97.525085 -362.916474) (xy 97.509017 -362.969881)
			(xy 97.485345 -363.020378) (xy 97.454572 -363.066891) (xy 97.425489 -363.09935) (xy 97.87204 -363.09935)
			(xy 97.876111 -363.043728) (xy 97.888237 -362.989291) (xy 97.90816 -362.9372) (xy 97.935456 -362.888565)
			(xy 97.969542 -362.844422) (xy 98.009691 -362.805713) (xy 98.055049 -362.773262) (xy 98.104649 -362.747761)
			(xy 98.157433 -362.729754) (xy 98.212276 -362.719624) (xy 98.26801 -362.717587) (xy 98.323447 -362.723687)
			(xy 98.377404 -362.737793) (xy 98.428733 -362.759605) (xy 98.476339 -362.788659) (xy 98.519207 -362.824334)
			(xy 98.556424 -362.865871) (xy 98.587197 -362.912384) (xy 98.610869 -362.962881) (xy 98.626937 -363.016288)
			(xy 98.635057 -363.071464) (xy 98.635566 -363.09935) (xy 98.635057 -363.127236) (xy 98.626937 -363.182412)
			(xy 98.610869 -363.235819) (xy 98.587197 -363.286316) (xy 98.556424 -363.332829) (xy 98.519207 -363.374366)
			(xy 98.476339 -363.410041) (xy 98.428733 -363.439095) (xy 98.377404 -363.460907) (xy 98.323447 -363.475013)
			(xy 98.26801 -363.481113) (xy 98.212276 -363.479076) (xy 98.157433 -363.468946) (xy 98.104649 -363.450939)
			(xy 98.055049 -363.425438) (xy 98.009691 -363.392987) (xy 97.969542 -363.354278) (xy 97.935456 -363.310135)
			(xy 97.90816 -363.2615) (xy 97.888237 -363.209409) (xy 97.876111 -363.154972) (xy 97.87204 -363.09935)
			(xy 97.425489 -363.09935) (xy 97.417355 -363.108428) (xy 97.374487 -363.144103) (xy 97.326881 -363.173157)
			(xy 97.275552 -363.194969) (xy 97.221595 -363.209075) (xy 97.166158 -363.215175) (xy 97.110424 -363.213138)
			(xy 97.055581 -363.203008) (xy 97.002797 -363.185001) (xy 96.953197 -363.1595) (xy 96.907839 -363.127049)
			(xy 96.86769 -363.08834) (xy 96.833604 -363.044197) (xy 96.806308 -362.995562) (xy 96.786385 -362.943471)
			(xy 96.774259 -362.889034) (xy 96.770188 -362.833412) (xy 81.102176 -362.833412) (xy 81.466345 -363.655102)
			(xy 98.85248 -363.655102) (xy 98.856551 -363.59948) (xy 98.868677 -363.545043) (xy 98.8886 -363.492952)
			(xy 98.915896 -363.444317) (xy 98.949982 -363.400174) (xy 98.990131 -363.361465) (xy 99.035489 -363.329014)
			(xy 99.085089 -363.303513) (xy 99.137873 -363.285506) (xy 99.192716 -363.275376) (xy 99.24845 -363.273339)
			(xy 99.303887 -363.279439) (xy 99.357844 -363.293545) (xy 99.409173 -363.315357) (xy 99.456779 -363.344411)
			(xy 99.499647 -363.380086) (xy 99.536864 -363.421623) (xy 99.567637 -363.468136) (xy 99.591309 -363.518633)
			(xy 99.607377 -363.57204) (xy 99.615497 -363.627216) (xy 99.616006 -363.655102) (xy 99.615497 -363.682988)
			(xy 99.607377 -363.738164) (xy 99.591309 -363.791571) (xy 99.567637 -363.842068) (xy 99.536864 -363.888581)
			(xy 99.499647 -363.930118) (xy 99.456779 -363.965793) (xy 99.409173 -363.994847) (xy 99.357844 -364.016659)
			(xy 99.303887 -364.030765) (xy 99.24845 -364.036865) (xy 99.192716 -364.034828) (xy 99.137873 -364.024698)
			(xy 99.085089 -364.006691) (xy 99.035489 -363.98119) (xy 98.990131 -363.948739) (xy 98.949982 -363.91003)
			(xy 98.915896 -363.865887) (xy 98.8886 -363.817252) (xy 98.868677 -363.765161) (xy 98.856551 -363.710724)
			(xy 98.85248 -363.655102) (xy 81.466345 -363.655102) (xy 81.659067 -364.08995) (xy 97.5774 -364.08995)
			(xy 97.581471 -364.034328) (xy 97.593597 -363.979891) (xy 97.61352 -363.9278) (xy 97.640816 -363.879165)
			(xy 97.674902 -363.835022) (xy 97.715051 -363.796313) (xy 97.760409 -363.763862) (xy 97.810009 -363.738361)
			(xy 97.862793 -363.720354) (xy 97.917636 -363.710224) (xy 97.97337 -363.708187) (xy 98.028807 -363.714287)
			(xy 98.082764 -363.728393) (xy 98.134093 -363.750205) (xy 98.181699 -363.779259) (xy 98.224567 -363.814934)
			(xy 98.261784 -363.856471) (xy 98.292557 -363.902984) (xy 98.316229 -363.953481) (xy 98.332297 -364.006888)
			(xy 98.340417 -364.062064) (xy 98.340926 -364.08995) (xy 98.340417 -364.117836) (xy 98.332297 -364.173012)
			(xy 98.316229 -364.226419) (xy 98.292557 -364.276916) (xy 98.261784 -364.323429) (xy 98.224567 -364.364966)
			(xy 98.181699 -364.400641) (xy 98.134093 -364.429695) (xy 98.082764 -364.451507) (xy 98.028807 -364.465613)
			(xy 97.97337 -364.471713) (xy 97.917636 -364.469676) (xy 97.862793 -364.459546) (xy 97.810009 -364.441539)
			(xy 97.760409 -364.416038) (xy 97.715051 -364.383587) (xy 97.674902 -364.344878) (xy 97.640816 -364.300735)
			(xy 97.61352 -364.2521) (xy 97.593597 -364.200009) (xy 97.581471 -364.145572) (xy 97.5774 -364.08995)
			(xy 81.659067 -364.08995) (xy 81.865551 -364.555849) (xy 98.876386 -364.555849) (xy 98.876386 -364.501351)
			(xy 98.884141 -364.447408) (xy 98.899494 -364.395118) (xy 98.922131 -364.345545) (xy 98.951593 -364.299697)
			(xy 98.987279 -364.258509) (xy 99.028464 -364.222818) (xy 99.074308 -364.193351) (xy 99.123879 -364.170708)
			(xy 99.176167 -364.15535) (xy 99.230109 -364.147589) (xy 99.257358 -364.1471) (xy 99.283582 -364.147509)
			(xy 99.335533 -364.154713) (xy 99.386009 -364.168963) (xy 99.434058 -364.189991) (xy 99.478774 -364.2174)
			(xy 99.519316 -364.250675) (xy 99.554919 -364.289188) (xy 99.584913 -364.332214) (xy 99.59721 -364.35538)
			(xy 99.604539 -364.368759) (xy 99.625777 -364.390643) (xy 99.652525 -364.405289) (xy 99.682403 -364.411393)
			(xy 99.712753 -364.408413) (xy 99.740873 -364.396614) (xy 99.764262 -364.377045) (xy 99.772978 -364.364524)
			(xy 99.788181 -364.342039) (xy 99.823848 -364.301132) (xy 99.864955 -364.265695) (xy 99.91067 -364.236444)
			(xy 99.960071 -364.213969) (xy 100.012159 -364.198724) (xy 100.065882 -364.191018) (xy 100.093018 -364.190534)
			(xy 100.120271 -364.190937) (xy 100.174223 -364.198697) (xy 100.226521 -364.214055) (xy 100.276102 -364.2367)
			(xy 100.321955 -364.26617) (xy 100.363148 -364.301865) (xy 100.398841 -364.343059) (xy 100.428309 -364.388914)
			(xy 100.450951 -364.438495) (xy 100.466307 -364.490794) (xy 100.474064 -364.544747) (xy 100.474064 -364.599253)
			(xy 100.466307 -364.653206) (xy 100.450951 -364.705505) (xy 100.428309 -364.755086) (xy 100.398841 -364.800941)
			(xy 100.363148 -364.842135) (xy 100.321955 -364.87783) (xy 100.276102 -364.9073) (xy 100.226521 -364.929945)
			(xy 100.174223 -364.945303) (xy 100.120271 -364.953063) (xy 100.093018 -364.95355) (xy 100.066795 -364.953133)
			(xy 100.014845 -364.945928) (xy 99.964371 -364.931677) (xy 99.916323 -364.910649) (xy 99.871607 -364.883241)
			(xy 99.831065 -364.849968) (xy 99.795461 -364.811457) (xy 99.765465 -364.768435) (xy 99.753166 -364.74527)
			(xy 99.745729 -364.731955) (xy 99.724517 -364.710068) (xy 99.697791 -364.695415) (xy 99.667931 -364.6893)
			(xy 99.637597 -364.692269) (xy 99.609489 -364.704056) (xy 99.58611 -364.723612) (xy 99.577398 -364.736126)
			(xy 99.562228 -364.758633) (xy 99.526553 -364.799537) (xy 99.48544 -364.834971) (xy 99.439719 -364.864219)
			(xy 99.390314 -364.886691) (xy 99.338222 -364.901931) (xy 99.284496 -364.909633) (xy 99.257358 -364.910116)
			(xy 99.230109 -364.909611) (xy 99.176167 -364.90185) (xy 99.123879 -364.886492) (xy 99.074308 -364.863849)
			(xy 99.028464 -364.834382) (xy 98.987279 -364.798691) (xy 98.951593 -364.757503) (xy 98.922131 -364.711655)
			(xy 98.899494 -364.662082) (xy 98.884141 -364.609792) (xy 98.876386 -364.555849) (xy 81.865551 -364.555849)
			(xy 82.324927 -365.59236) (xy 100.41077 -365.59236) (xy 100.414841 -365.536738) (xy 100.426967 -365.482301)
			(xy 100.44689 -365.43021) (xy 100.474186 -365.381575) (xy 100.508272 -365.337432) (xy 100.548421 -365.298723)
			(xy 100.593779 -365.266272) (xy 100.643379 -365.240771) (xy 100.696163 -365.222764) (xy 100.751006 -365.212634)
			(xy 100.80674 -365.210597) (xy 100.862177 -365.216697) (xy 100.916134 -365.230803) (xy 100.967463 -365.252615)
			(xy 101.015069 -365.281669) (xy 101.057937 -365.317344) (xy 101.095154 -365.358881) (xy 101.125927 -365.405394)
			(xy 101.149599 -365.455891) (xy 101.165667 -365.509298) (xy 101.173787 -365.564474) (xy 101.174296 -365.59236)
			(xy 101.173787 -365.620246) (xy 101.165667 -365.675422) (xy 101.149599 -365.728829) (xy 101.125927 -365.779326)
			(xy 101.095154 -365.825839) (xy 101.057937 -365.867376) (xy 101.015069 -365.903051) (xy 100.967463 -365.932105)
			(xy 100.916134 -365.953917) (xy 100.906858 -365.956342) (xy 101.534468 -365.956342) (xy 101.534949 -365.929096)
			(xy 101.542702 -365.875158) (xy 101.558056 -365.822873) (xy 101.580699 -365.773308) (xy 101.610169 -365.727472)
			(xy 101.645865 -365.686299) (xy 101.687059 -365.650628) (xy 101.732914 -365.621187) (xy 101.782493 -365.598574)
			(xy 101.834787 -365.583252) (xy 101.888729 -365.575532) (xy 101.915976 -365.575088) (xy 101.945948 -365.575615)
			(xy 102.005163 -365.584936) (xy 102.062188 -365.603414) (xy 102.115616 -365.630593) (xy 102.164129 -365.665803)
			(xy 102.185724 -365.686594) (xy 105.584752 -369.085876) (xy 114.52225 -369.085876) (xy 115.236244 -368.371882)
			(xy 115.236244 -365.546132) (xy 115.207796 -365.532162) (xy 115.179829 -365.517789) (xy 115.128643 -365.481275)
			(xy 115.105942 -365.459518) (xy 114.304572 -364.658148) (xy 114.283786 -364.636536) (xy 114.248527 -364.588039)
			(xy 114.221293 -364.534622) (xy 114.202755 -364.4776) (xy 114.193371 -364.41838) (xy 114.192812 -364.3884)
			(xy 114.192812 -364.16996) (xy 114.193298 -364.142709) (xy 114.201054 -364.088761) (xy 114.216409 -364.036466)
			(xy 114.239051 -363.986889) (xy 114.268517 -363.941039) (xy 114.304208 -363.899848) (xy 114.345399 -363.864157)
			(xy 114.391249 -363.834691) (xy 114.440826 -363.812049) (xy 114.493121 -363.796694) (xy 114.547069 -363.788938)
			(xy 114.601571 -363.788938) (xy 114.655519 -363.796694) (xy 114.707814 -363.812049) (xy 114.757391 -363.834691)
			(xy 114.803241 -363.864157) (xy 114.844432 -363.899848) (xy 114.880123 -363.941039) (xy 114.909589 -363.986889)
			(xy 114.932231 -364.036466) (xy 114.947586 -364.088761) (xy 114.955342 -364.142709) (xy 114.955828 -364.16996)
			(xy 114.955828 -364.230412) (xy 115.496594 -364.771432) (xy 117.671088 -362.596684) (xy 117.671088 -357.849678)
			(xy 116.455952 -356.634542) (xy 116.43516 -356.612936) (xy 116.399902 -356.564437) (xy 116.37267 -356.511018)
			(xy 116.354133 -356.453995) (xy 116.34475 -356.394774) (xy 116.344192 -356.364794) (xy 116.344192 -355.942392)
			(xy 116.344678 -355.915141) (xy 116.352434 -355.861193) (xy 116.367789 -355.808898) (xy 116.390431 -355.759321)
			(xy 116.419897 -355.713471) (xy 116.455588 -355.67228) (xy 116.496779 -355.636589) (xy 116.542629 -355.607123)
			(xy 116.592206 -355.584481) (xy 116.644501 -355.569126) (xy 116.698449 -355.56137) (xy 116.752951 -355.56137)
			(xy 116.806899 -355.569126) (xy 116.859194 -355.584481) (xy 116.908771 -355.607123) (xy 116.954621 -355.636589)
			(xy 116.995812 -355.67228) (xy 117.031503 -355.713471) (xy 117.060969 -355.759321) (xy 117.083611 -355.808898)
			(xy 117.098966 -355.861193) (xy 117.106722 -355.915141) (xy 117.107208 -355.942392) (xy 117.107208 -356.206806)
			(xy 118.052596 -357.152448) (xy 119.776748 -355.428042) (xy 119.798332 -355.407319) (xy 119.846759 -355.372178)
			(xy 119.900077 -355.345027) (xy 119.95698 -355.326531) (xy 120.016072 -355.317143) (xy 120.045988 -355.316536)
			(xy 120.645682 -355.316536) (xy 120.672917 -355.317017) (xy 120.726832 -355.324767) (xy 120.779096 -355.340111)
			(xy 120.828644 -355.362737) (xy 120.874468 -355.392184) (xy 120.915634 -355.427853) (xy 120.951305 -355.469017)
			(xy 120.980755 -355.51484) (xy 121.003383 -355.564387) (xy 121.018729 -355.61665) (xy 121.026481 -355.670565)
			(xy 121.026481 -355.725035) (xy 121.018729 -355.77895) (xy 121.003383 -355.831213) (xy 120.980755 -355.88076)
			(xy 120.951305 -355.926583) (xy 120.915634 -355.967747) (xy 120.874468 -356.003416) (xy 120.828644 -356.032863)
			(xy 120.824297 -356.034848) (xy 122.442222 -356.034848) (xy 122.446293 -355.979226) (xy 122.458419 -355.924789)
			(xy 122.478342 -355.872698) (xy 122.505638 -355.824063) (xy 122.539724 -355.77992) (xy 122.579873 -355.741211)
			(xy 122.625231 -355.70876) (xy 122.674831 -355.683259) (xy 122.727615 -355.665252) (xy 122.782458 -355.655122)
			(xy 122.838192 -355.653085) (xy 122.893629 -355.659185) (xy 122.947586 -355.673291) (xy 122.998915 -355.695103)
			(xy 123.046521 -355.724157) (xy 123.089389 -355.759832) (xy 123.126606 -355.801369) (xy 123.157379 -355.847882)
			(xy 123.181051 -355.898379) (xy 123.197119 -355.951786) (xy 123.205239 -356.006962) (xy 123.205748 -356.034848)
			(xy 123.205239 -356.062734) (xy 123.197119 -356.11791) (xy 123.181051 -356.171317) (xy 123.157379 -356.221814)
			(xy 123.126606 -356.268327) (xy 123.089389 -356.309864) (xy 123.046521 -356.345539) (xy 122.998915 -356.374593)
			(xy 122.947586 -356.396405) (xy 122.893629 -356.410511) (xy 122.838192 -356.416611) (xy 122.782458 -356.414574)
			(xy 122.727615 -356.404444) (xy 122.674831 -356.386437) (xy 122.625231 -356.360936) (xy 122.579873 -356.328485)
			(xy 122.539724 -356.289776) (xy 122.505638 -356.245633) (xy 122.478342 -356.196998) (xy 122.458419 -356.144907)
			(xy 122.446293 -356.09047) (xy 122.442222 -356.034848) (xy 120.824297 -356.034848) (xy 120.779096 -356.055489)
			(xy 120.726832 -356.070833) (xy 120.672917 -356.078583) (xy 120.645682 -356.079044) (xy 120.204484 -356.079044)
			(xy 119.304437 -356.97922) (xy 122.843796 -356.97922) (xy 122.847867 -356.923598) (xy 122.859993 -356.869161)
			(xy 122.879916 -356.81707) (xy 122.907212 -356.768435) (xy 122.941298 -356.724292) (xy 122.981447 -356.685583)
			(xy 123.026805 -356.653132) (xy 123.076405 -356.627631) (xy 123.129189 -356.609624) (xy 123.184032 -356.599494)
			(xy 123.239766 -356.597457) (xy 123.295203 -356.603557) (xy 123.34916 -356.617663) (xy 123.400489 -356.639475)
			(xy 123.448095 -356.668529) (xy 123.490963 -356.704204) (xy 123.52818 -356.745741) (xy 123.558953 -356.792254)
			(xy 123.582625 -356.842751) (xy 123.598693 -356.896158) (xy 123.606813 -356.951334) (xy 123.607322 -356.97922)
			(xy 123.606813 -357.007106) (xy 123.598693 -357.062282) (xy 123.582625 -357.115689) (xy 123.558953 -357.166186)
			(xy 123.52818 -357.212699) (xy 123.490963 -357.254236) (xy 123.448095 -357.289911) (xy 123.400489 -357.318965)
			(xy 123.34916 -357.340777) (xy 123.295203 -357.354883) (xy 123.239766 -357.360983) (xy 123.184032 -357.358946)
			(xy 123.129189 -357.348816) (xy 123.076405 -357.330809) (xy 123.026805 -357.305308) (xy 122.981447 -357.272857)
			(xy 122.941298 -357.234148) (xy 122.907212 -357.190005) (xy 122.879916 -357.14137) (xy 122.859993 -357.089279)
			(xy 122.847867 -357.034842) (xy 122.843796 -356.97922) (xy 119.304437 -356.97922) (xy 118.434104 -357.849678)
			(xy 118.434104 -358.13111) (xy 119.248426 -358.13111) (xy 119.252499 -358.075451) (xy 119.264634 -358.020978)
			(xy 119.28457 -357.968852) (xy 119.311884 -357.920184) (xy 119.345992 -357.876012) (xy 119.386169 -357.837277)
			(xy 119.431557 -357.804805) (xy 119.481189 -357.779287) (xy 119.534009 -357.761268) (xy 119.588888 -357.751131)
			(xy 119.644659 -357.749093) (xy 119.700133 -357.755196) (xy 119.754126 -357.769312) (xy 119.805489 -357.791139)
			(xy 119.853127 -357.820212) (xy 119.896023 -357.855911) (xy 119.933265 -357.897475) (xy 119.964059 -357.944019)
			(xy 119.987747 -357.99455) (xy 120.003825 -358.047992) (xy 120.011951 -358.103206) (xy 120.012414 -358.12857)
			(xy 122.04522 -358.12857) (xy 122.049291 -358.072948) (xy 122.061417 -358.018511) (xy 122.08134 -357.96642)
			(xy 122.108636 -357.917785) (xy 122.142722 -357.873642) (xy 122.182871 -357.834933) (xy 122.228229 -357.802482)
			(xy 122.277829 -357.776981) (xy 122.330613 -357.758974) (xy 122.385456 -357.748844) (xy 122.44119 -357.746807)
			(xy 122.496627 -357.752907) (xy 122.550584 -357.767013) (xy 122.601913 -357.788825) (xy 122.649519 -357.817879)
			(xy 122.692387 -357.853554) (xy 122.729604 -357.895091) (xy 122.760377 -357.941604) (xy 122.784049 -357.992101)
			(xy 122.800117 -358.045508) (xy 122.808237 -358.100684) (xy 122.808746 -358.12857) (xy 122.808237 -358.156456)
			(xy 122.800117 -358.211632) (xy 122.784049 -358.265039) (xy 122.760377 -358.315536) (xy 122.729604 -358.362049)
			(xy 122.692387 -358.403586) (xy 122.649519 -358.439261) (xy 122.601913 -358.468315) (xy 122.550584 -358.490127)
			(xy 122.496627 -358.504233) (xy 122.44119 -358.510333) (xy 122.385456 -358.508296) (xy 122.330613 -358.498166)
			(xy 122.277829 -358.480159) (xy 122.228229 -358.454658) (xy 122.182871 -358.422207) (xy 122.142722 -358.383498)
			(xy 122.108636 -358.339355) (xy 122.08134 -358.29072) (xy 122.061417 -358.238629) (xy 122.049291 -358.184192)
			(xy 122.04522 -358.12857) (xy 120.012414 -358.12857) (xy 120.01246 -358.13111) (xy 120.011951 -358.159014)
			(xy 120.003825 -358.214228) (xy 119.987747 -358.26767) (xy 119.964059 -358.318201) (xy 119.933265 -358.364745)
			(xy 119.896023 -358.406309) (xy 119.853127 -358.442008) (xy 119.805489 -358.471081) (xy 119.754126 -358.492908)
			(xy 119.700133 -358.507024) (xy 119.644659 -358.513127) (xy 119.588888 -358.511089) (xy 119.534009 -358.500952)
			(xy 119.481189 -358.482933) (xy 119.431557 -358.457415) (xy 119.386169 -358.424943) (xy 119.345992 -358.386208)
			(xy 119.311884 -358.342036) (xy 119.28457 -358.293368) (xy 119.264634 -358.241242) (xy 119.252499 -358.186769)
			(xy 119.248426 -358.13111) (xy 118.434104 -358.13111) (xy 118.434104 -358.964484) (xy 122.787916 -358.964484)
			(xy 122.791987 -358.908862) (xy 122.804113 -358.854425) (xy 122.824036 -358.802334) (xy 122.851332 -358.753699)
			(xy 122.885418 -358.709556) (xy 122.925567 -358.670847) (xy 122.970925 -358.638396) (xy 123.020525 -358.612895)
			(xy 123.073309 -358.594888) (xy 123.128152 -358.584758) (xy 123.183886 -358.582721) (xy 123.239323 -358.588821)
			(xy 123.29328 -358.602927) (xy 123.344609 -358.624739) (xy 123.392215 -358.653793) (xy 123.435083 -358.689468)
			(xy 123.4723 -358.731005) (xy 123.503073 -358.777518) (xy 123.526745 -358.828015) (xy 123.542813 -358.881422)
			(xy 123.550933 -358.936598) (xy 123.551442 -358.964484) (xy 123.550933 -358.99237) (xy 123.542813 -359.047546)
			(xy 123.526745 -359.100953) (xy 123.503073 -359.15145) (xy 123.4723 -359.197963) (xy 123.435083 -359.2395)
			(xy 123.392215 -359.275175) (xy 123.344609 -359.304229) (xy 123.29328 -359.326041) (xy 123.239323 -359.340147)
			(xy 123.183886 -359.346247) (xy 123.128152 -359.34421) (xy 123.073309 -359.33408) (xy 123.020525 -359.316073)
			(xy 122.970925 -359.290572) (xy 122.925567 -359.258121) (xy 122.885418 -359.219412) (xy 122.851332 -359.175269)
			(xy 122.824036 -359.126634) (xy 122.804113 -359.074543) (xy 122.791987 -359.020106) (xy 122.787916 -358.964484)
			(xy 118.434104 -358.964484) (xy 118.434104 -360.2736) (xy 118.713248 -360.2736) (xy 118.717321 -360.217941)
			(xy 118.729456 -360.163468) (xy 118.749392 -360.111342) (xy 118.776706 -360.062674) (xy 118.810814 -360.018502)
			(xy 118.850991 -359.979767) (xy 118.896379 -359.947295) (xy 118.946011 -359.921777) (xy 118.998831 -359.903758)
			(xy 119.05371 -359.893621) (xy 119.109481 -359.891583) (xy 119.164955 -359.897686) (xy 119.218948 -359.911802)
			(xy 119.270311 -359.933629) (xy 119.317949 -359.962702) (xy 119.360845 -359.998401) (xy 119.398087 -360.039965)
			(xy 119.428881 -360.086509) (xy 119.452569 -360.13704) (xy 119.468647 -360.190482) (xy 119.476773 -360.245696)
			(xy 119.477282 -360.2736) (xy 119.476773 -360.301504) (xy 119.468647 -360.356718) (xy 119.452569 -360.41016)
			(xy 119.428881 -360.460691) (xy 119.398087 -360.507235) (xy 119.360845 -360.548799) (xy 119.317949 -360.584498)
			(xy 119.270311 -360.613571) (xy 119.218948 -360.635398) (xy 119.164955 -360.649514) (xy 119.109481 -360.655617)
			(xy 119.05371 -360.653579) (xy 118.998831 -360.643442) (xy 118.946011 -360.625423) (xy 118.896379 -360.599905)
			(xy 118.850991 -360.567433) (xy 118.810814 -360.528698) (xy 118.776706 -360.484526) (xy 118.749392 -360.435858)
			(xy 118.729456 -360.383732) (xy 118.717321 -360.329259) (xy 118.713248 -360.2736) (xy 118.434104 -360.2736)
			(xy 118.434104 -360.680508) (xy 128.966466 -360.680508) (xy 128.970537 -360.624886) (xy 128.982663 -360.570449)
			(xy 129.002586 -360.518358) (xy 129.029882 -360.469723) (xy 129.063968 -360.42558) (xy 129.104117 -360.386871)
			(xy 129.149475 -360.35442) (xy 129.199075 -360.328919) (xy 129.251859 -360.310912) (xy 129.306702 -360.300782)
			(xy 129.362436 -360.298745) (xy 129.417873 -360.304845) (xy 129.47183 -360.318951) (xy 129.523159 -360.340763)
			(xy 129.570765 -360.369817) (xy 129.613633 -360.405492) (xy 129.65085 -360.447029) (xy 129.681623 -360.493542)
			(xy 129.705295 -360.544039) (xy 129.721363 -360.597446) (xy 129.729483 -360.652622) (xy 129.729992 -360.680508)
			(xy 129.729483 -360.708394) (xy 129.721363 -360.76357) (xy 129.705295 -360.816977) (xy 129.681623 -360.867474)
			(xy 129.65085 -360.913987) (xy 129.613633 -360.955524) (xy 129.570765 -360.991199) (xy 129.523159 -361.020253)
			(xy 129.47183 -361.042065) (xy 129.417873 -361.056171) (xy 129.362436 -361.062271) (xy 129.306702 -361.060234)
			(xy 129.251859 -361.050104) (xy 129.199075 -361.032097) (xy 129.149475 -361.006596) (xy 129.104117 -360.974145)
			(xy 129.063968 -360.935436) (xy 129.029882 -360.891293) (xy 129.002586 -360.842658) (xy 128.982663 -360.790567)
			(xy 128.970537 -360.73613) (xy 128.966466 -360.680508) (xy 118.434104 -360.680508) (xy 118.434104 -361.133136)
			(xy 121.446286 -361.133136) (xy 121.450375 -361.077254) (xy 121.462558 -361.022564) (xy 121.482574 -360.97023)
			(xy 121.509997 -360.921368) (xy 121.544242 -360.87702) (xy 121.584578 -360.83813) (xy 121.630148 -360.805528)
			(xy 121.679979 -360.779909) (xy 121.733009 -360.761817) (xy 121.788107 -360.75164) (xy 121.844101 -360.749594)
			(xy 121.899796 -360.755722) (xy 121.954005 -360.769894) (xy 122.005573 -360.791808) (xy 122.053401 -360.820997)
			(xy 122.096469 -360.856838) (xy 122.133859 -360.898568) (xy 122.164775 -360.945298) (xy 122.188558 -360.996031)
			(xy 122.2047 -361.049687) (xy 122.212859 -361.105121) (xy 122.21337 -361.133136) (xy 122.212859 -361.161151)
			(xy 122.2047 -361.216585) (xy 122.188558 -361.270241) (xy 122.164775 -361.320974) (xy 122.133859 -361.367704)
			(xy 122.096469 -361.409434) (xy 122.053401 -361.445275) (xy 122.005573 -361.474464) (xy 121.954005 -361.496378)
			(xy 121.899796 -361.51055) (xy 121.844101 -361.516678) (xy 121.788107 -361.514632) (xy 121.733009 -361.504455)
			(xy 121.679979 -361.486363) (xy 121.630148 -361.460744) (xy 121.584578 -361.428142) (xy 121.544242 -361.389252)
			(xy 121.509997 -361.344904) (xy 121.482574 -361.296042) (xy 121.462558 -361.243708) (xy 121.450375 -361.189018)
			(xy 121.446286 -361.133136) (xy 118.434104 -361.133136) (xy 118.434104 -362.097066) (xy 128.08534 -362.097066)
			(xy 128.089411 -362.041444) (xy 128.101537 -361.987007) (xy 128.12146 -361.934916) (xy 128.148756 -361.886281)
			(xy 128.182842 -361.842138) (xy 128.222991 -361.803429) (xy 128.268349 -361.770978) (xy 128.317949 -361.745477)
			(xy 128.370733 -361.72747) (xy 128.425576 -361.71734) (xy 128.48131 -361.715303) (xy 128.536747 -361.721403)
			(xy 128.590704 -361.735509) (xy 128.642033 -361.757321) (xy 128.689639 -361.786375) (xy 128.732507 -361.82205)
			(xy 128.769724 -361.863587) (xy 128.800497 -361.9101) (xy 128.824169 -361.960597) (xy 128.840237 -362.014004)
			(xy 128.848357 -362.06918) (xy 128.848866 -362.097066) (xy 128.848357 -362.124952) (xy 128.840237 -362.180128)
			(xy 128.824169 -362.233535) (xy 128.800497 -362.284032) (xy 128.769724 -362.330545) (xy 128.732507 -362.372082)
			(xy 128.689639 -362.407757) (xy 128.642033 -362.436811) (xy 128.590704 -362.458623) (xy 128.536747 -362.472729)
			(xy 128.48131 -362.478829) (xy 128.425576 -362.476792) (xy 128.370733 -362.466662) (xy 128.317949 -362.448655)
			(xy 128.268349 -362.423154) (xy 128.222991 -362.390703) (xy 128.182842 -362.351994) (xy 128.148756 -362.307851)
			(xy 128.12146 -362.259216) (xy 128.101537 -362.207125) (xy 128.089411 -362.152688) (xy 128.08534 -362.097066)
			(xy 118.434104 -362.097066) (xy 118.434104 -362.754672) (xy 118.433507 -362.784649) (xy 118.42412 -362.843865)
			(xy 118.405587 -362.900883) (xy 118.378366 -362.954302) (xy 118.343125 -363.002806) (xy 118.322344 -363.02442)
			(xy 116.643729 -364.702852) (xy 119.224042 -364.702852) (xy 119.228113 -364.64723) (xy 119.240239 -364.592793)
			(xy 119.260162 -364.540702) (xy 119.287458 -364.492067) (xy 119.321544 -364.447924) (xy 119.361693 -364.409215)
			(xy 119.407051 -364.376764) (xy 119.456651 -364.351263) (xy 119.509435 -364.333256) (xy 119.564278 -364.323126)
			(xy 119.620012 -364.321089) (xy 119.675449 -364.327189) (xy 119.729406 -364.341295) (xy 119.780735 -364.363107)
			(xy 119.828341 -364.392161) (xy 119.871209 -364.427836) (xy 119.908426 -364.469373) (xy 119.939199 -364.515886)
			(xy 119.962871 -364.566383) (xy 119.978939 -364.61979) (xy 119.987059 -364.674966) (xy 119.987568 -364.702852)
			(xy 119.987059 -364.730738) (xy 119.978939 -364.785914) (xy 119.962871 -364.839321) (xy 119.939199 -364.889818)
			(xy 119.908426 -364.936331) (xy 119.871209 -364.977868) (xy 119.828341 -365.013543) (xy 119.780735 -365.042597)
			(xy 119.729406 -365.064409) (xy 119.675449 -365.078515) (xy 119.620012 -365.084615) (xy 119.564278 -365.082578)
			(xy 119.509435 -365.072448) (xy 119.456651 -365.054441) (xy 119.407051 -365.02894) (xy 119.361693 -364.996489)
			(xy 119.321544 -364.95778) (xy 119.287458 -364.913637) (xy 119.260162 -364.865002) (xy 119.240239 -364.812911)
			(xy 119.228113 -364.758474) (xy 119.224042 -364.702852) (xy 116.643729 -364.702852) (xy 115.998752 -365.347758)
			(xy 115.998752 -365.747808) (xy 132.860799 -365.747808) (xy 132.864835 -365.664361) (xy 132.876907 -365.581693)
			(xy 132.8969 -365.500576) (xy 132.924629 -365.421767) (xy 132.959835 -365.346002) (xy 133.002189 -365.273989)
			(xy 133.051295 -365.2064) (xy 133.106696 -365.143866) (xy 133.167873 -365.086971) (xy 133.234256 -365.036245)
			(xy 133.305224 -364.992164) (xy 133.380116 -364.955138) (xy 133.458232 -364.925512) (xy 133.538842 -364.903564)
			(xy 133.621194 -364.889499) (xy 133.70452 -364.883447) (xy 133.78804 -364.885466) (xy 133.870976 -364.895536)
			(xy 133.952552 -364.913564) (xy 134.032008 -364.939381) (xy 134.108601 -364.972746) (xy 134.181617 -365.013347)
			(xy 134.250373 -365.060806) (xy 134.314227 -365.114679) (xy 134.372584 -365.174464) (xy 134.424899 -365.239601)
			(xy 134.470682 -365.309484) (xy 134.509507 -365.383459) (xy 134.541012 -365.460836) (xy 134.564901 -365.540893)
			(xy 134.580952 -365.622881) (xy 134.589015 -365.706036) (xy 134.58952 -365.747808) (xy 134.589015 -365.78958)
			(xy 134.580952 -365.872735) (xy 134.564901 -365.954723) (xy 134.541012 -366.03478) (xy 134.528065 -366.066578)
			(xy 138.60324 -366.066578) (xy 138.607206 -365.982047) (xy 138.619071 -365.89826) (xy 138.638729 -365.815951)
			(xy 138.666009 -365.735845) (xy 138.70067 -365.658646) (xy 138.742408 -365.585031) (xy 138.790855 -365.515648)
			(xy 138.845587 -365.451107) (xy 138.906123 -365.391975) (xy 138.971929 -365.338771) (xy 139.042429 -365.291963)
			(xy 139.117001 -365.251962) (xy 139.194992 -365.21912) (xy 139.275716 -365.193726) (xy 139.358463 -365.176003)
			(xy 139.442505 -365.166105) (xy 139.527106 -365.164122) (xy 139.61152 -365.170069) (xy 139.695007 -365.183894)
			(xy 139.776832 -365.205477) (xy 139.856276 -365.234627) (xy 139.932642 -365.271088) (xy 140.005258 -365.31454)
			(xy 140.073486 -365.364601) (xy 140.136726 -365.420831) (xy 140.194423 -365.482736) (xy 140.24607 -365.549772)
			(xy 140.291212 -365.621349) (xy 140.329454 -365.696839) (xy 140.360458 -365.775578) (xy 140.383953 -365.856875)
			(xy 140.399732 -365.940014) (xy 140.407656 -366.024266) (xy 140.408152 -366.066578) (xy 143.68324 -366.066578)
			(xy 143.687206 -365.982047) (xy 143.699071 -365.89826) (xy 143.718729 -365.815951) (xy 143.746009 -365.735845)
			(xy 143.78067 -365.658646) (xy 143.822408 -365.585031) (xy 143.870855 -365.515648) (xy 143.925587 -365.451107)
			(xy 143.986123 -365.391975) (xy 144.051929 -365.338771) (xy 144.122429 -365.291963) (xy 144.197001 -365.251962)
			(xy 144.274992 -365.21912) (xy 144.355716 -365.193726) (xy 144.438463 -365.176003) (xy 144.522505 -365.166105)
			(xy 144.607106 -365.164122) (xy 144.69152 -365.170069) (xy 144.775007 -365.183894) (xy 144.856832 -365.205477)
			(xy 144.936276 -365.234627) (xy 145.012642 -365.271088) (xy 145.085258 -365.31454) (xy 145.153486 -365.364601)
			(xy 145.216726 -365.420831) (xy 145.274423 -365.482736) (xy 145.32607 -365.549772) (xy 145.371212 -365.621349)
			(xy 145.409454 -365.696839) (xy 145.440458 -365.775578) (xy 145.463953 -365.856875) (xy 145.479732 -365.940014)
			(xy 145.487656 -366.024266) (xy 145.488152 -366.066578) (xy 145.487656 -366.10889) (xy 145.479732 -366.193142)
			(xy 145.463953 -366.276281) (xy 145.440458 -366.357578) (xy 145.409454 -366.436317) (xy 145.371212 -366.511807)
			(xy 145.32607 -366.583384) (xy 145.274423 -366.65042) (xy 145.216726 -366.712325) (xy 145.153486 -366.768555)
			(xy 145.085258 -366.818616) (xy 145.012642 -366.862068) (xy 144.936276 -366.898529) (xy 144.856832 -366.927679)
			(xy 144.775007 -366.949262) (xy 144.69152 -366.963087) (xy 144.607106 -366.969034) (xy 144.522505 -366.967051)
			(xy 144.438463 -366.957153) (xy 144.355716 -366.93943) (xy 144.274992 -366.914036) (xy 144.197001 -366.881194)
			(xy 144.122429 -366.841193) (xy 144.051929 -366.794385) (xy 143.986123 -366.741181) (xy 143.925587 -366.682049)
			(xy 143.870855 -366.617508) (xy 143.822408 -366.548125) (xy 143.78067 -366.47451) (xy 143.746009 -366.397311)
			(xy 143.718729 -366.317205) (xy 143.699071 -366.234896) (xy 143.687206 -366.151109) (xy 143.68324 -366.066578)
			(xy 140.408152 -366.066578) (xy 140.407656 -366.10889) (xy 140.399732 -366.193142) (xy 140.383953 -366.276281)
			(xy 140.360458 -366.357578) (xy 140.329454 -366.436317) (xy 140.291212 -366.511807) (xy 140.24607 -366.583384)
			(xy 140.194423 -366.65042) (xy 140.136726 -366.712325) (xy 140.073486 -366.768555) (xy 140.005258 -366.818616)
			(xy 139.932642 -366.862068) (xy 139.856276 -366.898529) (xy 139.776832 -366.927679) (xy 139.695007 -366.949262)
			(xy 139.61152 -366.963087) (xy 139.527106 -366.969034) (xy 139.442505 -366.967051) (xy 139.358463 -366.957153)
			(xy 139.275716 -366.93943) (xy 139.194992 -366.914036) (xy 139.117001 -366.881194) (xy 139.042429 -366.841193)
			(xy 138.971929 -366.794385) (xy 138.906123 -366.741181) (xy 138.845587 -366.682049) (xy 138.790855 -366.617508)
			(xy 138.742408 -366.548125) (xy 138.70067 -366.47451) (xy 138.666009 -366.397311) (xy 138.638729 -366.317205)
			(xy 138.619071 -366.234896) (xy 138.607206 -366.151109) (xy 138.60324 -366.066578) (xy 134.528065 -366.066578)
			(xy 134.509507 -366.112157) (xy 134.470682 -366.186132) (xy 134.424899 -366.256015) (xy 134.372584 -366.321152)
			(xy 134.314227 -366.380937) (xy 134.250373 -366.43481) (xy 134.181617 -366.482269) (xy 134.108601 -366.52287)
			(xy 134.032008 -366.556235) (xy 133.952552 -366.582052) (xy 133.870976 -366.60008) (xy 133.78804 -366.61015)
			(xy 133.70452 -366.612169) (xy 133.621194 -366.606117) (xy 133.538842 -366.592052) (xy 133.458232 -366.570104)
			(xy 133.380116 -366.540478) (xy 133.305224 -366.503452) (xy 133.234256 -366.459371) (xy 133.167873 -366.408645)
			(xy 133.106696 -366.35175) (xy 133.051295 -366.289216) (xy 133.002189 -366.221627) (xy 132.959835 -366.149614)
			(xy 132.924629 -366.073849) (xy 132.8969 -365.99504) (xy 132.876907 -365.913923) (xy 132.864835 -365.831255)
			(xy 132.860799 -365.747808) (xy 115.998752 -365.747808) (xy 115.998752 -367.832132) (xy 121.144028 -367.832132)
			(xy 121.148099 -367.77651) (xy 121.160225 -367.722073) (xy 121.180148 -367.669982) (xy 121.207444 -367.621347)
			(xy 121.24153 -367.577204) (xy 121.281679 -367.538495) (xy 121.327037 -367.506044) (xy 121.376637 -367.480543)
			(xy 121.429421 -367.462536) (xy 121.484264 -367.452406) (xy 121.539998 -367.450369) (xy 121.595435 -367.456469)
			(xy 121.649392 -367.470575) (xy 121.700721 -367.492387) (xy 121.748327 -367.521441) (xy 121.791195 -367.557116)
			(xy 121.828412 -367.598653) (xy 121.859185 -367.645166) (xy 121.882857 -367.695663) (xy 121.898925 -367.74907)
			(xy 121.907045 -367.804246) (xy 121.907554 -367.832132) (xy 121.907045 -367.860018) (xy 121.898925 -367.915194)
			(xy 121.882857 -367.968601) (xy 121.859185 -368.019098) (xy 121.828412 -368.065611) (xy 121.825273 -368.069114)
			(xy 122.207274 -368.069114) (xy 122.207774 -368.040196) (xy 122.216503 -367.983023) (xy 122.233763 -367.927822)
			(xy 122.259158 -367.87586) (xy 122.292106 -367.828327) (xy 122.331852 -367.786312) (xy 122.35434 -367.768124)
			(xy 122.366136 -367.758214) (xy 122.383662 -367.732896) (xy 122.392843 -367.703505) (xy 122.392846 -367.672712)
			(xy 122.383669 -367.64332) (xy 122.366148 -367.617999) (xy 122.35434 -367.608104) (xy 122.331867 -367.589901)
			(xy 122.292129 -367.547885) (xy 122.259188 -367.500353) (xy 122.233797 -367.448394) (xy 122.216539 -367.393198)
			(xy 122.207809 -367.336029) (xy 122.207274 -367.307114) (xy 122.20776 -367.279863) (xy 122.215516 -367.225915)
			(xy 122.230871 -367.17362) (xy 122.253513 -367.124043) (xy 122.282979 -367.078193) (xy 122.31867 -367.037002)
			(xy 122.359861 -367.001311) (xy 122.405711 -366.971845) (xy 122.455288 -366.949203) (xy 122.507583 -366.933848)
			(xy 122.561531 -366.926092) (xy 122.616033 -366.926092) (xy 122.669981 -366.933848) (xy 122.722276 -366.949203)
			(xy 122.771853 -366.971845) (xy 122.817703 -367.001311) (xy 122.858894 -367.037002) (xy 122.894585 -367.078193)
			(xy 122.924051 -367.124043) (xy 122.946693 -367.17362) (xy 122.962048 -367.225915) (xy 122.969804 -367.279863)
			(xy 122.97029 -367.307114) (xy 122.969714 -367.336029) (xy 122.960997 -367.393198) (xy 122.943751 -367.448395)
			(xy 122.91837 -367.500357) (xy 122.885437 -367.547893) (xy 122.845705 -367.589912) (xy 122.823224 -367.608104)
			(xy 122.811404 -367.617986) (xy 122.793885 -367.643313) (xy 122.784709 -367.672711) (xy 122.784712 -367.703507)
			(xy 122.793892 -367.732903) (xy 122.811416 -367.758227) (xy 122.823224 -367.768124) (xy 122.845724 -367.786295)
			(xy 122.885457 -367.82832) (xy 122.918393 -367.875859) (xy 122.943779 -367.927824) (xy 122.961032 -367.983025)
			(xy 122.969757 -368.040197) (xy 122.97029 -368.069114) (xy 124.355098 -368.069114) (xy 124.355627 -368.040198)
			(xy 124.364354 -367.983027) (xy 124.38161 -367.927828) (xy 124.407 -367.875867) (xy 124.439941 -367.828332)
			(xy 124.47968 -367.786315) (xy 124.502164 -367.768124) (xy 124.513957 -367.758212) (xy 124.531479 -367.732894)
			(xy 124.540659 -367.703504) (xy 124.540661 -367.672713) (xy 124.531487 -367.643322) (xy 124.513969 -367.618)
			(xy 124.502164 -367.608104) (xy 124.479675 -367.58992) (xy 124.439942 -367.547898) (xy 124.407004 -367.500361)
			(xy 124.381617 -367.448398) (xy 124.364362 -367.3932) (xy 124.355633 -367.33603) (xy 124.355098 -367.307114)
			(xy 124.355584 -367.279863) (xy 124.36334 -367.225915) (xy 124.378695 -367.17362) (xy 124.401337 -367.124043)
			(xy 124.430803 -367.078193) (xy 124.466494 -367.037002) (xy 124.507685 -367.001311) (xy 124.553535 -366.971845)
			(xy 124.603112 -366.949203) (xy 124.655407 -366.933848) (xy 124.709355 -366.926092) (xy 124.763857 -366.926092)
			(xy 124.817805 -366.933848) (xy 124.8701 -366.949203) (xy 124.919677 -366.971845) (xy 124.965527 -367.001311)
			(xy 125.006718 -367.037002) (xy 125.042409 -367.078193) (xy 125.071875 -367.124043) (xy 125.094517 -367.17362)
			(xy 125.109872 -367.225915) (xy 125.117628 -367.279863) (xy 125.118114 -367.307114) (xy 125.117566 -367.33603)
			(xy 125.108848 -367.393202) (xy 125.091598 -367.448401) (xy 125.066212 -367.500364) (xy 125.033272 -367.547898)
			(xy 124.993533 -367.589914) (xy 124.971048 -367.608104) (xy 124.959226 -367.617984) (xy 124.941702 -367.643311)
			(xy 124.932525 -367.67271) (xy 124.932527 -367.703508) (xy 124.94171 -367.732905) (xy 124.959237 -367.758228)
			(xy 124.971048 -367.768124) (xy 124.993553 -367.786289) (xy 125.033285 -367.828316) (xy 125.06622 -367.875857)
			(xy 125.091604 -367.927823) (xy 125.108856 -367.983024) (xy 125.117581 -368.040197) (xy 125.118114 -368.069114)
			(xy 126.488698 -368.069114) (xy 126.489227 -368.040198) (xy 126.497954 -367.983027) (xy 126.51521 -367.927828)
			(xy 126.5406 -367.875867) (xy 126.573541 -367.828332) (xy 126.61328 -367.786315) (xy 126.635764 -367.768124)
			(xy 126.647557 -367.758212) (xy 126.665079 -367.732894) (xy 126.674259 -367.703504) (xy 126.674261 -367.672713)
			(xy 126.665087 -367.643322) (xy 126.647569 -367.618) (xy 126.635764 -367.608104) (xy 126.613275 -367.58992)
			(xy 126.573542 -367.547898) (xy 126.540604 -367.500361) (xy 126.515217 -367.448398) (xy 126.497962 -367.3932)
			(xy 126.489233 -367.33603) (xy 126.488698 -367.307114) (xy 126.489184 -367.279863) (xy 126.49694 -367.225915)
			(xy 126.512295 -367.17362) (xy 126.534937 -367.124043) (xy 126.564403 -367.078193) (xy 126.600094 -367.037002)
			(xy 126.641285 -367.001311) (xy 126.687135 -366.971845) (xy 126.736712 -366.949203) (xy 126.789007 -366.933848)
			(xy 126.842955 -366.926092) (xy 126.897457 -366.926092) (xy 126.951405 -366.933848) (xy 127.0037 -366.949203)
			(xy 127.053277 -366.971845) (xy 127.099127 -367.001311) (xy 127.140318 -367.037002) (xy 127.176009 -367.078193)
			(xy 127.205475 -367.124043) (xy 127.228117 -367.17362) (xy 127.243472 -367.225915) (xy 127.251228 -367.279863)
			(xy 127.251714 -367.307114) (xy 127.251166 -367.33603) (xy 127.242448 -367.393202) (xy 127.225198 -367.448401)
			(xy 127.199812 -367.500364) (xy 127.166872 -367.547898) (xy 127.127133 -367.589914) (xy 127.104648 -367.608104)
			(xy 127.092826 -367.617984) (xy 127.075302 -367.643311) (xy 127.066125 -367.67271) (xy 127.066127 -367.703508)
			(xy 127.07531 -367.732905) (xy 127.092837 -367.758228) (xy 127.104648 -367.768124) (xy 127.127153 -367.786289)
			(xy 127.166885 -367.828316) (xy 127.19982 -367.875857) (xy 127.225204 -367.927823) (xy 127.242456 -367.983024)
			(xy 127.251181 -368.040197) (xy 127.25119 -368.040666) (xy 128.641348 -368.040666) (xy 128.641896 -368.01175)
			(xy 128.650616 -367.954579) (xy 128.667867 -367.89938) (xy 128.693253 -367.847418) (xy 128.726193 -367.799884)
			(xy 128.76593 -367.757867) (xy 128.788414 -367.739676) (xy 128.800251 -367.729814) (xy 128.817763 -367.70448)
			(xy 128.826932 -367.675078) (xy 128.826926 -367.64428) (xy 128.817744 -367.614882) (xy 128.800222 -367.589555)
			(xy 128.788414 -367.579656) (xy 128.765912 -367.561486) (xy 128.726178 -367.519463) (xy 128.69324 -367.471923)
			(xy 128.667855 -367.419958) (xy 128.650603 -367.364756) (xy 128.64188 -367.307583) (xy 128.641348 -367.278666)
			(xy 128.641834 -367.251415) (xy 128.64959 -367.197467) (xy 128.664945 -367.145172) (xy 128.687587 -367.095595)
			(xy 128.717053 -367.049745) (xy 128.752744 -367.008554) (xy 128.793935 -366.972863) (xy 128.839785 -366.943397)
			(xy 128.889362 -366.920755) (xy 128.941657 -366.9054) (xy 128.995605 -366.897644) (xy 129.050107 -366.897644)
			(xy 129.104055 -366.9054) (xy 129.15635 -366.920755) (xy 129.205927 -366.943397) (xy 129.251777 -366.972863)
			(xy 129.292968 -367.008554) (xy 129.328659 -367.049745) (xy 129.358125 -367.095595) (xy 129.380767 -367.145172)
			(xy 129.396122 -367.197467) (xy 129.403878 -367.251415) (xy 129.404364 -367.278666) (xy 129.403835 -367.307583)
			(xy 129.39511 -367.364754) (xy 129.377855 -367.419953) (xy 129.352466 -367.471915) (xy 129.319523 -367.519449)
			(xy 129.279783 -367.561466) (xy 129.257298 -367.579656) (xy 129.245528 -367.589592) (xy 129.228013 -367.614905)
			(xy 129.218835 -367.644288) (xy 129.218829 -367.675071) (xy 129.227994 -367.704457) (xy 129.2455 -367.729778)
			(xy 129.257298 -367.739676) (xy 129.27977 -367.757881) (xy 129.319506 -367.799898) (xy 129.352446 -367.84743)
			(xy 129.377836 -367.899388) (xy 129.395095 -367.954583) (xy 129.403827 -368.011751) (xy 129.404364 -368.040666)
			(xy 129.403878 -368.067917) (xy 129.396122 -368.121865) (xy 129.380767 -368.17416) (xy 129.358125 -368.223737)
			(xy 129.328659 -368.269587) (xy 129.310731 -368.290278) (xy 132.836408 -368.290278) (xy 132.836408 -368.205582)
			(xy 132.844459 -368.121268) (xy 132.860488 -368.038102) (xy 132.884349 -367.956835) (xy 132.915828 -367.878205)
			(xy 132.954639 -367.802924) (xy 133.000429 -367.731672) (xy 133.052785 -367.665096) (xy 133.111233 -367.603798)
			(xy 133.175243 -367.548333) (xy 133.244235 -367.499204) (xy 133.317585 -367.456855) (xy 133.394628 -367.421671)
			(xy 133.474667 -367.393969) (xy 133.556976 -367.374001) (xy 133.640811 -367.361948) (xy 133.725412 -367.357918)
			(xy 133.810013 -367.361948) (xy 133.893848 -367.374001) (xy 133.976157 -367.393969) (xy 134.056196 -367.421671)
			(xy 134.133239 -367.456855) (xy 134.206589 -367.499204) (xy 134.275581 -367.548333) (xy 134.339591 -367.603798)
			(xy 134.398039 -367.665096) (xy 134.450395 -367.731672) (xy 134.496185 -367.802924) (xy 134.534996 -367.878205)
			(xy 134.566475 -367.956835) (xy 134.590336 -368.038102) (xy 134.606365 -368.121268) (xy 134.614416 -368.205582)
			(xy 134.61492 -368.24793) (xy 134.614416 -368.290278) (xy 134.606365 -368.374592) (xy 134.590336 -368.457758)
			(xy 134.566475 -368.539025) (xy 134.534996 -368.617655) (xy 134.496185 -368.692936) (xy 134.450395 -368.764188)
			(xy 134.398039 -368.830764) (xy 134.339591 -368.892062) (xy 134.275581 -368.947527) (xy 134.206589 -368.996656)
			(xy 134.133239 -369.039005) (xy 134.056196 -369.074189) (xy 133.976157 -369.101891) (xy 133.893848 -369.121859)
			(xy 133.810013 -369.133912) (xy 133.725412 -369.137943) (xy 133.640811 -369.133912) (xy 133.556976 -369.121859)
			(xy 133.474667 -369.101891) (xy 133.394628 -369.074189) (xy 133.317585 -369.039005) (xy 133.244235 -368.996656)
			(xy 133.175243 -368.947527) (xy 133.111233 -368.892062) (xy 133.052785 -368.830764) (xy 133.000429 -368.764188)
			(xy 132.954639 -368.692936) (xy 132.915828 -368.617655) (xy 132.884349 -368.539025) (xy 132.860488 -368.457758)
			(xy 132.844459 -368.374592) (xy 132.836408 -368.290278) (xy 129.310731 -368.290278) (xy 129.292968 -368.310778)
			(xy 129.251777 -368.346469) (xy 129.205927 -368.375935) (xy 129.15635 -368.398577) (xy 129.104055 -368.413932)
			(xy 129.050107 -368.421688) (xy 128.995605 -368.421688) (xy 128.941657 -368.413932) (xy 128.889362 -368.398577)
			(xy 128.839785 -368.375935) (xy 128.793935 -368.346469) (xy 128.752744 -368.310778) (xy 128.717053 -368.269587)
			(xy 128.687587 -368.223737) (xy 128.664945 -368.17416) (xy 128.64959 -368.121865) (xy 128.641834 -368.067917)
			(xy 128.641348 -368.040666) (xy 127.25119 -368.040666) (xy 127.251714 -368.069114) (xy 127.251228 -368.096365)
			(xy 127.243472 -368.150313) (xy 127.228117 -368.202608) (xy 127.205475 -368.252185) (xy 127.176009 -368.298035)
			(xy 127.140318 -368.339226) (xy 127.099127 -368.374917) (xy 127.053277 -368.404383) (xy 127.0037 -368.427025)
			(xy 126.951405 -368.44238) (xy 126.897457 -368.450136) (xy 126.842955 -368.450136) (xy 126.789007 -368.44238)
			(xy 126.736712 -368.427025) (xy 126.687135 -368.404383) (xy 126.641285 -368.374917) (xy 126.600094 -368.339226)
			(xy 126.564403 -368.298035) (xy 126.534937 -368.252185) (xy 126.512295 -368.202608) (xy 126.49694 -368.150313)
			(xy 126.489184 -368.096365) (xy 126.488698 -368.069114) (xy 125.118114 -368.069114) (xy 125.117628 -368.096365)
			(xy 125.109872 -368.150313) (xy 125.094517 -368.202608) (xy 125.071875 -368.252185) (xy 125.042409 -368.298035)
			(xy 125.006718 -368.339226) (xy 124.965527 -368.374917) (xy 124.919677 -368.404383) (xy 124.8701 -368.427025)
			(xy 124.817805 -368.44238) (xy 124.763857 -368.450136) (xy 124.709355 -368.450136) (xy 124.655407 -368.44238)
			(xy 124.603112 -368.427025) (xy 124.553535 -368.404383) (xy 124.507685 -368.374917) (xy 124.466494 -368.339226)
			(xy 124.430803 -368.298035) (xy 124.401337 -368.252185) (xy 124.378695 -368.202608) (xy 124.36334 -368.150313)
			(xy 124.355584 -368.096365) (xy 124.355098 -368.069114) (xy 122.97029 -368.069114) (xy 122.969804 -368.096365)
			(xy 122.962048 -368.150313) (xy 122.946693 -368.202608) (xy 122.924051 -368.252185) (xy 122.894585 -368.298035)
			(xy 122.858894 -368.339226) (xy 122.817703 -368.374917) (xy 122.771853 -368.404383) (xy 122.722276 -368.427025)
			(xy 122.669981 -368.44238) (xy 122.616033 -368.450136) (xy 122.561531 -368.450136) (xy 122.507583 -368.44238)
			(xy 122.455288 -368.427025) (xy 122.405711 -368.404383) (xy 122.359861 -368.374917) (xy 122.31867 -368.339226)
			(xy 122.282979 -368.298035) (xy 122.253513 -368.252185) (xy 122.230871 -368.202608) (xy 122.215516 -368.150313)
			(xy 122.20776 -368.096365) (xy 122.207274 -368.069114) (xy 121.825273 -368.069114) (xy 121.791195 -368.107148)
			(xy 121.748327 -368.142823) (xy 121.700721 -368.171877) (xy 121.649392 -368.193689) (xy 121.595435 -368.207795)
			(xy 121.539998 -368.213895) (xy 121.484264 -368.211858) (xy 121.429421 -368.201728) (xy 121.376637 -368.183721)
			(xy 121.327037 -368.15822) (xy 121.281679 -368.125769) (xy 121.24153 -368.08706) (xy 121.207444 -368.042917)
			(xy 121.180148 -367.994282) (xy 121.160225 -367.942191) (xy 121.148099 -367.887754) (xy 121.144028 -367.832132)
			(xy 115.998752 -367.832132) (xy 115.998752 -368.696748) (xy 117.255542 -368.696748) (xy 117.259613 -368.641126)
			(xy 117.271739 -368.586689) (xy 117.291662 -368.534598) (xy 117.318958 -368.485963) (xy 117.353044 -368.44182)
			(xy 117.393193 -368.403111) (xy 117.438551 -368.37066) (xy 117.488151 -368.345159) (xy 117.540935 -368.327152)
			(xy 117.595778 -368.317022) (xy 117.651512 -368.314985) (xy 117.706949 -368.321085) (xy 117.760906 -368.335191)
			(xy 117.812235 -368.357003) (xy 117.859841 -368.386057) (xy 117.902709 -368.421732) (xy 117.939926 -368.463269)
			(xy 117.970699 -368.509782) (xy 117.994371 -368.560279) (xy 118.010439 -368.613686) (xy 118.018559 -368.668862)
			(xy 118.019068 -368.696748) (xy 118.018559 -368.724634) (xy 118.010439 -368.77981) (xy 117.994371 -368.833217)
			(xy 117.970699 -368.883714) (xy 117.939926 -368.930227) (xy 117.902709 -368.971764) (xy 117.859841 -369.007439)
			(xy 117.812235 -369.036493) (xy 117.760906 -369.058305) (xy 117.706949 -369.072411) (xy 117.651512 -369.078511)
			(xy 117.595778 -369.076474) (xy 117.540935 -369.066344) (xy 117.488151 -369.048337) (xy 117.438551 -369.022836)
			(xy 117.393193 -368.990385) (xy 117.353044 -368.951676) (xy 117.318958 -368.907533) (xy 117.291662 -368.858898)
			(xy 117.271739 -368.806807) (xy 117.259613 -368.75237) (xy 117.255542 -368.696748) (xy 115.998752 -368.696748)
			(xy 115.998752 -369.089178) (xy 117.64391 -370.734336) (xy 137.85723 -370.734336) (xy 140.71473 -367.876582)
			(xy 140.736329 -367.855874) (xy 140.784751 -367.82073) (xy 140.838065 -367.793575) (xy 140.894965 -367.775076)
			(xy 140.954055 -367.765685) (xy 140.98397 -367.765076) (xy 140.984478 -367.765076) (xy 141.011714 -367.765529)
			(xy 141.065631 -367.773279) (xy 141.117896 -367.788623) (xy 141.167445 -367.81125) (xy 141.213269 -367.840699)
			(xy 141.254435 -367.87637) (xy 141.290105 -367.917538) (xy 141.319553 -367.963362) (xy 141.342179 -368.012912)
			(xy 141.357523 -368.065177) (xy 141.365271 -368.119094) (xy 141.365732 -368.14633) (xy 141.365732 -368.146838)
			(xy 141.365103 -368.176755) (xy 141.355744 -368.235853) (xy 141.337261 -368.292761) (xy 141.31011 -368.34608)
			(xy 141.274957 -368.3945) (xy 141.254226 -368.416078) (xy 138.284966 -371.385338) (xy 138.263372 -371.406051)
			(xy 138.214949 -371.441194) (xy 138.161633 -371.468347) (xy 138.104732 -371.486846) (xy 138.045642 -371.496236)
			(xy 138.015726 -371.496844) (xy 117.485414 -371.496844) (xy 117.455494 -371.496271) (xy 117.396393 -371.486902)
			(xy 117.339483 -371.468407) (xy 117.286165 -371.441243) (xy 117.237749 -371.406076) (xy 117.216174 -371.385338)
			(xy 115.34775 -369.516914) (xy 115.334542 -369.502944) (xy 115.324967 -369.493093) (xy 115.301761 -369.47841)
			(xy 115.275481 -369.470448) (xy 115.248029 -369.469781) (xy 115.221393 -369.476459) (xy 115.197502 -369.489997)
			(xy 115.187476 -369.499388) (xy 114.949986 -369.736878) (xy 114.92839 -369.757589) (xy 114.879966 -369.79273)
			(xy 114.826651 -369.819883) (xy 114.769751 -369.838382) (xy 114.710661 -369.847774) (xy 114.680746 -369.848384)
			(xy 105.426256 -369.848384) (xy 105.396338 -369.847773) (xy 105.337239 -369.838411) (xy 105.28033 -369.819925)
			(xy 105.227011 -369.792769) (xy 105.178593 -369.757611) (xy 105.157016 -369.736878) (xy 101.646228 -366.22609)
			(xy 101.625406 -366.204511) (xy 101.590153 -366.156005) (xy 101.562927 -366.102579) (xy 101.544397 -366.04555)
			(xy 101.535021 -365.986324) (xy 101.534468 -365.956342) (xy 100.906858 -365.956342) (xy 100.862177 -365.968023)
			(xy 100.80674 -365.974123) (xy 100.751006 -365.972086) (xy 100.696163 -365.961956) (xy 100.643379 -365.943949)
			(xy 100.593779 -365.918448) (xy 100.548421 -365.885997) (xy 100.508272 -365.847288) (xy 100.474186 -365.803145)
			(xy 100.44689 -365.75451) (xy 100.426967 -365.702419) (xy 100.414841 -365.647982) (xy 100.41077 -365.59236)
			(xy 82.324927 -365.59236) (xy 84.206334 -369.837462) (xy 88.183466 -373.814594) (xy 88.219534 -373.82958)
			(xy 98.402902 -384.012948) (xy 130.343656 -384.012948)
		)
		(stroke
			(width 0)
			(type solid)
		)
		(fill yes)
		(layer "In2.Cu")
		(net "GND")
	)
	(gr_poly
		(pts
			(xy 383.54889 -368.843814) (xy 385.217924 -364.278164) (xy 385.222081 -364.264832) (xy 385.223736 -364.236964)
			(xy 385.217784 -364.209689) (xy 385.20467 -364.185044) (xy 385.185373 -364.16487) (xy 385.161335 -364.150674)
			(xy 385.134351 -364.143517) (xy 385.120388 -364.14329) (xy 385.098798 -364.143798) (xy 385.071546 -364.143335)
			(xy 385.017595 -364.135577) (xy 384.965298 -364.120221) (xy 384.915719 -364.097578) (xy 384.869867 -364.06811)
			(xy 384.828675 -364.032416) (xy 384.792983 -363.991223) (xy 384.763516 -363.94537) (xy 384.740875 -363.89579)
			(xy 384.72552 -363.843493) (xy 384.717765 -363.789543) (xy 384.71729 -363.76229) (xy 384.717467 -363.744727)
			(xy 384.720646 -363.709746) (xy 384.72364 -363.69244) (xy 384.725857 -363.677471) (xy 384.72243 -363.64742)
			(xy 384.710359 -363.619688) (xy 384.690702 -363.596702) (xy 384.665179 -363.580475) (xy 384.636025 -363.572427)
			(xy 384.605791 -363.573262) (xy 384.591306 -363.577632) (xy 384.561761 -363.586979) (xy 384.500622 -363.597056)
			(xy 384.46964 -363.597698) (xy 384.468878 -363.597698) (xy 384.441628 -363.59721) (xy 384.387683 -363.589451)
			(xy 384.335392 -363.574094) (xy 384.285818 -363.551451) (xy 384.239971 -363.521984) (xy 384.198784 -363.486293)
			(xy 384.163096 -363.445103) (xy 384.133633 -363.399254) (xy 384.110995 -363.349678) (xy 384.095642 -363.297385)
			(xy 384.087888 -363.24344) (xy 384.08737 -363.21619) (xy 384.08737 -363.215682) (xy 384.087582 -363.198311)
			(xy 384.090766 -363.163714) (xy 384.09372 -363.146594) (xy 384.095315 -363.131381) (xy 384.090373 -363.101209)
			(xy 384.076713 -363.073856) (xy 384.055562 -363.051779) (xy 384.028819 -363.03696) (xy 384.013964 -363.03331)
			(xy 383.985815 -363.026788) (xy 383.93175 -363.006405) (xy 383.881373 -362.978109) (xy 383.835834 -362.942545)
			(xy 383.796174 -362.900527) (xy 383.763297 -362.853013) (xy 383.737953 -362.801088) (xy 383.720723 -362.745937)
			(xy 383.711998 -362.68882) (xy 383.71145 -362.65993) (xy 383.711704 -362.642912) (xy 383.711856 -362.62809)
			(xy 383.704617 -362.59936) (xy 383.689433 -362.573919) (xy 383.667582 -362.55391) (xy 383.640906 -362.541018)
			(xy 383.611651 -362.536331) (xy 383.596896 -362.537756) (xy 383.584444 -362.5393) (xy 383.559405 -362.540954)
			(xy 383.546858 -362.541058) (xy 383.519896 -362.54059) (xy 383.466509 -362.532992) (xy 383.414724 -362.517953)
			(xy 383.365572 -362.495772) (xy 383.320033 -362.466892) (xy 383.279013 -362.431888) (xy 383.24333 -362.391458)
			(xy 383.213696 -362.346406) (xy 383.190699 -362.29763) (xy 383.1748 -362.246103) (xy 383.166313 -362.19285)
			(xy 383.16535 -362.1659) (xy 383.163883 -362.152039) (xy 383.154479 -362.125814) (xy 383.138359 -362.10309)
			(xy 383.116715 -362.085546) (xy 383.104136 -362.07954) (xy 383.088457 -362.073554) (xy 383.055019 -362.070965)
			(xy 383.038604 -362.07446) (xy 383.013165 -362.081216) (xy 382.961035 -362.088477) (xy 382.934718 -362.088938)
			(xy 382.907462 -362.088476) (xy 382.853505 -362.080721) (xy 382.801201 -362.065365) (xy 382.751614 -362.042722)
			(xy 382.705755 -362.013252) (xy 382.664557 -361.977555) (xy 382.628859 -361.936359) (xy 382.599387 -361.890501)
			(xy 382.576741 -361.840916) (xy 382.561383 -361.788613) (xy 382.553625 -361.734656) (xy 382.553625 -361.680144)
			(xy 382.561383 -361.626187) (xy 382.576741 -361.573884) (xy 382.599387 -361.524299) (xy 382.628859 -361.478441)
			(xy 382.664557 -361.437245) (xy 382.705755 -361.401548) (xy 382.751614 -361.372078) (xy 382.801201 -361.349435)
			(xy 382.853505 -361.334079) (xy 382.907462 -361.326324) (xy 382.934718 -361.325922) (xy 382.961682 -361.326388)
			(xy 383.015072 -361.333984) (xy 383.066861 -361.349021) (xy 383.116017 -361.3712) (xy 383.161561 -361.400078)
			(xy 383.202585 -361.435082) (xy 383.238272 -361.475513) (xy 383.267911 -361.520566) (xy 383.290911 -361.569343)
			(xy 383.306815 -361.620872) (xy 383.315305 -361.674128) (xy 383.316226 -361.70108) (xy 383.317691 -361.714943)
			(xy 383.32709 -361.741175) (xy 383.343206 -361.763906) (xy 383.364848 -361.781458) (xy 383.37744 -361.78744)
			(xy 383.393118 -361.793431) (xy 383.426559 -361.796028) (xy 383.442972 -361.79252) (xy 383.468411 -361.785762)
			(xy 383.520541 -361.778499) (xy 383.546858 -361.778042) (xy 383.574112 -361.778503) (xy 383.628064 -361.786255)
			(xy 383.680364 -361.801608) (xy 383.729947 -361.824249) (xy 383.775801 -361.853716) (xy 383.816995 -361.889411)
			(xy 383.852689 -361.930605) (xy 383.882155 -361.97646) (xy 383.904795 -362.026043) (xy 383.920147 -362.078344)
			(xy 383.927898 -362.132296) (xy 383.928366 -362.15955) (xy 383.928112 -362.176568) (xy 383.927958 -362.191391)
			(xy 383.935193 -362.220124) (xy 383.950376 -362.245568) (xy 383.972228 -362.265579) (xy 383.998907 -362.278469)
			(xy 384.028164 -362.283154) (xy 384.04292 -362.281724) (xy 384.055372 -362.28018) (xy 384.080411 -362.278527)
			(xy 384.092958 -362.278422) (xy 384.120212 -362.278882) (xy 384.174166 -362.286635) (xy 384.226467 -362.301987)
			(xy 384.276051 -362.324628) (xy 384.321907 -362.354095) (xy 384.363102 -362.389789) (xy 384.398797 -362.430984)
			(xy 384.428266 -362.476839) (xy 384.450908 -362.526422) (xy 384.466263 -362.578722) (xy 384.474017 -362.632676)
			(xy 384.474466 -362.65993) (xy 384.474466 -362.660438) (xy 384.474258 -362.67781) (xy 384.471081 -362.712408)
			(xy 384.468116 -362.729526) (xy 384.466524 -362.744739) (xy 384.471469 -362.774912) (xy 384.485128 -362.802267)
			(xy 384.506275 -362.824349) (xy 384.533013 -362.83918) (xy 384.547872 -362.84281) (xy 384.576019 -362.849334)
			(xy 384.630078 -362.869721) (xy 384.680449 -362.89802) (xy 384.725981 -362.933585) (xy 384.765635 -362.975604)
			(xy 384.798507 -363.023117) (xy 384.823845 -363.07504) (xy 384.841071 -363.130188) (xy 384.849792 -363.187302)
			(xy 384.850386 -363.21619) (xy 384.85021 -363.233753) (xy 384.847033 -363.268734) (xy 384.844036 -363.28604)
			(xy 384.841816 -363.301006) (xy 384.845237 -363.331052) (xy 384.857305 -363.358779) (xy 384.876962 -363.381758)
			(xy 384.902485 -363.397975) (xy 384.931638 -363.406009) (xy 384.961866 -363.405155) (xy 384.97637 -363.400848)
			(xy 385.005915 -363.3915) (xy 385.067054 -363.38142) (xy 385.098036 -363.380782) (xy 385.098798 -363.380782)
			(xy 385.127395 -363.381292) (xy 385.183947 -363.389826) (xy 385.238593 -363.406705) (xy 385.290108 -363.431549)
			(xy 385.337339 -363.463803) (xy 385.35864 -363.48289) (xy 385.369261 -363.492125) (xy 385.394326 -363.504907)
			(xy 385.421925 -363.510373) (xy 385.449969 -363.50811) (xy 385.476335 -363.498288) (xy 385.499025 -363.481652)
			(xy 385.516321 -363.459461) (xy 385.521962 -363.446568) (xy 391.07364 -348.260416) (xy 391.07364 -336.076036)
			(xy 390.633458 -335.586832) (xy 388.210298 -333.163672) (xy 382.995424 -333.163672) (xy 382.987804 -333.156052)
			(xy 382.976822 -333.145882) (xy 382.950402 -333.131844) (xy 382.921048 -333.126064) (xy 382.891278 -333.129036)
			(xy 382.863646 -333.140505) (xy 382.840522 -333.159487) (xy 382.823889 -333.184356) (xy 382.815174 -333.212976)
			(xy 382.814576 -333.227934) (xy 382.814576 -335.551526) (xy 383.439416 -336.176366) (xy 383.460194 -336.197981)
			(xy 383.49543 -336.246487) (xy 383.522648 -336.299906) (xy 383.541179 -336.356924) (xy 383.550567 -336.416137)
			(xy 383.551176 -336.446114) (xy 383.551176 -342.395048) (xy 383.570988 -342.41486) (xy 383.588271 -342.432859)
			(xy 383.617577 -342.473243) (xy 383.640215 -342.517709) (xy 383.655629 -342.565166) (xy 383.66344 -342.614448)
			(xy 383.663952 -342.639396) (xy 383.663952 -344.091006) (xy 383.663462 -344.115956) (xy 383.655657 -344.16524)
			(xy 383.640239 -344.212698) (xy 383.617587 -344.257159) (xy 383.58826 -344.297531) (xy 383.570988 -344.315542)
			(xy 383.10663 -344.7799) (xy 386.032387 -344.7799) (xy 386.036556 -344.724273) (xy 386.04897 -344.669889)
			(xy 386.069351 -344.617962) (xy 386.097243 -344.569653) (xy 386.132025 -344.526041) (xy 386.172918 -344.488101)
			(xy 386.21901 -344.456679) (xy 386.26927 -344.432478) (xy 386.322576 -344.416039) (xy 386.377736 -344.407729)
			(xy 386.405628 -344.407236) (xy 386.432959 -344.407731) (xy 386.487038 -344.415696) (xy 386.539372 -344.43148)
			(xy 386.588836 -344.454744) (xy 386.634369 -344.484988) (xy 386.674992 -344.521563) (xy 386.709832 -344.563683)
			(xy 386.724398 -344.586814) (xy 386.732342 -344.599023) (xy 386.753808 -344.618693) (xy 386.779956 -344.631498)
			(xy 386.808656 -344.636398) (xy 386.837571 -344.632992) (xy 386.851144 -344.627708) (xy 386.874352 -344.618213)
			(xy 386.922686 -344.604864) (xy 386.972376 -344.598138) (xy 386.997448 -344.597736) (xy 387.022517 -344.598156)
			(xy 387.072201 -344.604907) (xy 387.120535 -344.618241) (xy 387.143752 -344.627708) (xy 387.157334 -344.63294)
			(xy 387.186232 -344.636309) (xy 387.214909 -344.631401) (xy 387.241043 -344.618616) (xy 387.262517 -344.598987)
			(xy 387.270498 -344.586814) (xy 387.285067 -344.563683) (xy 387.31991 -344.521562) (xy 387.360533 -344.484983)
			(xy 387.406064 -344.454732) (xy 387.455526 -344.431456) (xy 387.507857 -344.415656) (xy 387.561936 -344.40767)
			(xy 387.6166 -344.40767) (xy 387.670679 -344.415656) (xy 387.72301 -344.431456) (xy 387.772472 -344.454732)
			(xy 387.818003 -344.484983) (xy 387.858626 -344.521562) (xy 387.893469 -344.563683) (xy 387.908038 -344.586814)
			(xy 387.915944 -344.59905) (xy 387.937421 -344.61872) (xy 387.963579 -344.631522) (xy 387.992288 -344.636414)
			(xy 388.021209 -344.632998) (xy 388.034784 -344.627708) (xy 388.057999 -344.618232) (xy 388.106329 -344.604875)
			(xy 388.156017 -344.598142) (xy 388.181088 -344.597736) (xy 388.207932 -344.598171) (xy 388.261065 -344.605875)
			(xy 388.312542 -344.621125) (xy 388.361297 -344.643606) (xy 388.406321 -344.672851) (xy 388.446681 -344.708256)
			(xy 388.481541 -344.749087) (xy 388.510181 -344.794499) (xy 388.532006 -344.843551) (xy 388.539736 -344.869262)
			(xy 388.544362 -344.883773) (xy 388.560887 -344.909341) (xy 388.584211 -344.928907) (xy 388.612263 -344.940734)
			(xy 388.642554 -344.943775) (xy 388.672397 -344.937757) (xy 388.68604 -344.930984) (xy 388.714189 -344.916356)
			(xy 388.774138 -344.895627) (xy 388.836696 -344.885126) (xy 388.868412 -344.884502) (xy 388.886431 -344.884725)
			(xy 388.922306 -344.888158) (xy 388.94004 -344.89136) (xy 388.955244 -344.893737) (xy 388.985802 -344.890199)
			(xy 389.013922 -344.877728) (xy 389.037058 -344.857454) (xy 389.053113 -344.831214) (xy 389.057388 -344.81643)
			(xy 389.064795 -344.789389) (xy 389.086426 -344.737665) (xy 389.11539 -344.689661) (xy 389.151065 -344.64641)
			(xy 389.192683 -344.608844) (xy 389.239348 -344.577769) (xy 389.290058 -344.553856) (xy 389.343719 -344.537617)
			(xy 389.39918 -344.529403) (xy 389.427212 -344.528902) (xy 389.454464 -344.529367) (xy 389.508413 -344.537125)
			(xy 389.560709 -344.552482) (xy 389.610287 -344.575125) (xy 389.656138 -344.604594) (xy 389.697328 -344.640288)
			(xy 389.733019 -344.68148) (xy 389.762485 -344.727333) (xy 389.785125 -344.776912) (xy 389.80048 -344.829209)
			(xy 389.808235 -344.883158) (xy 389.80872 -344.91041) (xy 389.808185 -344.937982) (xy 389.800246 -344.992551)
			(xy 389.784534 -345.04541) (xy 389.761377 -345.095456) (xy 389.731257 -345.141647) (xy 389.694801 -345.183022)
			(xy 389.6741 -345.20124) (xy 389.663193 -345.211129) (xy 389.647122 -345.235782) (xy 389.638739 -345.263992)
			(xy 389.638741 -345.293421) (xy 389.647127 -345.32163) (xy 389.663202 -345.346281) (xy 389.6741 -345.35618)
			(xy 389.694815 -345.374385) (xy 389.731279 -345.415758) (xy 389.761405 -345.461949) (xy 389.784567 -345.511998)
			(xy 389.800281 -345.564859) (xy 389.808221 -345.619433) (xy 389.80822 -345.67458) (xy 389.800279 -345.729153)
			(xy 389.784563 -345.782015) (xy 389.761399 -345.832062) (xy 389.731271 -345.878253) (xy 389.694806 -345.919624)
			(xy 389.6741 -345.93784) (xy 389.663193 -345.947729) (xy 389.647122 -345.972382) (xy 389.638739 -346.000592)
			(xy 389.638741 -346.030021) (xy 389.647127 -346.05823) (xy 389.663202 -346.082881) (xy 389.6741 -346.09278)
			(xy 389.694805 -346.110998) (xy 389.731275 -346.152365) (xy 389.761408 -346.198554) (xy 389.784575 -346.2486)
			(xy 389.800293 -346.301462) (xy 389.808234 -346.356036) (xy 389.80872 -346.38361) (xy 389.808232 -346.410861)
			(xy 389.800474 -346.464808) (xy 389.785118 -346.517102) (xy 389.762477 -346.566678) (xy 389.733011 -346.612528)
			(xy 389.697319 -346.653718) (xy 389.65613 -346.689409) (xy 389.61028 -346.718876) (xy 389.560704 -346.741517)
			(xy 389.50841 -346.756874) (xy 389.454463 -346.764631) (xy 389.427212 -346.765118) (xy 389.399358 -346.764571)
			(xy 389.344244 -346.756449) (xy 389.290895 -346.740406) (xy 389.240443 -346.716782) (xy 389.193959 -346.686078)
			(xy 389.152429 -346.648946) (xy 389.116736 -346.606174) (xy 389.087635 -346.55867) (xy 389.065746 -346.507442)
			(xy 389.05815 -346.480638) (xy 389.053874 -346.466522) (xy 389.038487 -346.441374) (xy 389.01657 -346.421656)
			(xy 388.98994 -346.409005) (xy 388.96081 -346.404471) (xy 388.946136 -346.405962) (xy 388.93312 -346.407636)
			(xy 388.906935 -346.409413) (xy 388.893812 -346.409518) (xy 388.879663 -346.409423) (xy 388.85144 -346.40739)
			(xy 388.837424 -346.405454) (xy 388.82408 -346.403805) (xy 388.797379 -346.40691) (xy 388.772419 -346.416889)
			(xy 388.750936 -346.433048) (xy 388.734426 -346.454261) (xy 388.724036 -346.479053) (xy 388.721854 -346.492322)
			(xy 388.717712 -346.519466) (xy 388.702744 -346.572294) (xy 388.680358 -346.62243) (xy 388.651017 -346.668839)
			(xy 388.615326 -346.710563) (xy 388.574022 -346.74674) (xy 388.527959 -346.776623) (xy 388.478089 -346.799595)
			(xy 388.42544 -346.81518) (xy 388.371101 -346.823057) (xy 388.343648 -346.823538) (xy 388.316398 -346.823)
			(xy 388.262451 -346.81525) (xy 388.210156 -346.799902) (xy 388.160578 -346.777267) (xy 388.114726 -346.747807)
			(xy 388.073534 -346.712121) (xy 388.03784 -346.670936) (xy 388.00837 -346.62509) (xy 387.985725 -346.575517)
			(xy 387.970366 -346.523225) (xy 387.962605 -346.46928) (xy 387.96214 -346.44203) (xy 387.962612 -346.414456)
			(xy 387.970562 -346.359882) (xy 387.986284 -346.307022) (xy 388.009453 -346.256976) (xy 388.039585 -346.210786)
			(xy 388.076053 -346.169415) (xy 388.09676 -346.1512) (xy 388.10763 -346.141273) (xy 388.12371 -346.116632)
			(xy 388.1321 -346.088431) (xy 388.132106 -346.059008) (xy 388.123726 -346.030803) (xy 388.107656 -346.006157)
			(xy 388.09676 -345.99626) (xy 388.076067 -345.97803) (xy 388.039597 -345.936664) (xy 388.009463 -345.890478)
			(xy 387.986295 -345.840434) (xy 387.970574 -345.787575) (xy 387.962629 -345.733003) (xy 387.96214 -345.70543)
			(xy 387.962563 -345.678928) (xy 387.969914 -345.626435) (xy 387.984465 -345.575466) (xy 388.005935 -345.527005)
			(xy 388.033911 -345.481984) (xy 388.050532 -345.461336) (xy 388.059995 -345.449205) (xy 388.071785 -345.4208)
			(xy 388.074606 -345.390175) (xy 388.068206 -345.360093) (xy 388.05316 -345.33327) (xy 388.030828 -345.312125)
			(xy 388.017258 -345.304872) (xy 387.993566 -345.292774) (xy 387.949585 -345.262851) (xy 387.910304 -345.226979)
			(xy 387.876521 -345.185887) (xy 387.862318 -345.163394) (xy 387.854357 -345.151197) (xy 387.832896 -345.131527)
			(xy 387.806753 -345.118719) (xy 387.778056 -345.113816) (xy 387.749144 -345.117218) (xy 387.735572 -345.1225)
			(xy 387.712363 -345.13199) (xy 387.664029 -345.145341) (xy 387.61434 -345.152069) (xy 387.589268 -345.152472)
			(xy 387.564199 -345.152047) (xy 387.514516 -345.145298) (xy 387.466181 -345.131966) (xy 387.442964 -345.1225)
			(xy 387.429377 -345.117281) (xy 387.400481 -345.113909) (xy 387.371806 -345.118813) (xy 387.345673 -345.131595)
			(xy 387.324198 -345.151222) (xy 387.316218 -345.163394) (xy 387.301649 -345.186525) (xy 387.266806 -345.228646)
			(xy 387.226183 -345.265225) (xy 387.180652 -345.295476) (xy 387.13119 -345.318752) (xy 387.078859 -345.334552)
			(xy 387.02478 -345.342538) (xy 386.970116 -345.342538) (xy 386.916037 -345.334552) (xy 386.863706 -345.318752)
			(xy 386.814244 -345.295476) (xy 386.768713 -345.265225) (xy 386.72809 -345.228646) (xy 386.693247 -345.186525)
			(xy 386.678678 -345.163394) (xy 386.670755 -345.15117) (xy 386.649283 -345.131499) (xy 386.62313 -345.118695)
			(xy 386.594425 -345.1138) (xy 386.565506 -345.117212) (xy 386.551932 -345.1225) (xy 386.528715 -345.131972)
			(xy 386.480386 -345.14533) (xy 386.430699 -345.152065) (xy 386.405628 -345.152472) (xy 386.377736 -345.152071)
			(xy 386.322576 -345.143761) (xy 386.26927 -345.127322) (xy 386.21901 -345.103121) (xy 386.172918 -345.071699)
			(xy 386.132025 -345.033759) (xy 386.097243 -344.990147) (xy 386.069351 -344.941838) (xy 386.04897 -344.889911)
			(xy 386.036556 -344.835527) (xy 386.032387 -344.7799) (xy 383.10663 -344.7799) (xy 382.242568 -345.643962)
			(xy 382.242568 -346.015056) (xy 382.359154 -346.131642) (xy 382.382776 -346.12961) (xy 382.41478 -346.12834)
			(xy 382.434349 -346.128563) (xy 382.473288 -346.132506) (xy 382.492504 -346.136214) (xy 382.506114 -346.138605)
			(xy 382.533678 -346.136829) (xy 382.559755 -346.12772) (xy 382.582429 -346.111946) (xy 382.600038 -346.090666)
			(xy 382.61129 -346.06544) (xy 382.615358 -346.03812) (xy 382.611945 -346.01071) (xy 382.607058 -345.997784)
			(xy 382.597014 -345.973691) (xy 382.582873 -345.923445) (xy 382.575732 -345.871737) (xy 382.575308 -345.845638)
			(xy 382.575769 -345.818386) (xy 382.58352 -345.764436) (xy 382.598871 -345.712138) (xy 382.621508 -345.662557)
			(xy 382.650971 -345.616703) (xy 382.686659 -345.575508) (xy 382.727848 -345.539812) (xy 382.773697 -345.510341)
			(xy 382.823274 -345.487695) (xy 382.875569 -345.472335) (xy 382.929517 -345.464574) (xy 382.984021 -345.464569)
			(xy 383.037971 -345.472322) (xy 383.090269 -345.487673) (xy 383.139849 -345.510311) (xy 383.185703 -345.539775)
			(xy 383.226897 -345.575465) (xy 383.262593 -345.616654) (xy 383.292063 -345.662503) (xy 383.314708 -345.712081)
			(xy 383.330067 -345.764376) (xy 383.337827 -345.818325) (xy 383.33783 -345.872829) (xy 383.330077 -345.926779)
			(xy 383.314724 -345.979076) (xy 383.292085 -346.028656) (xy 383.262621 -346.074509) (xy 383.22693 -346.115702)
			(xy 383.18574 -346.151397) (xy 383.13989 -346.180866) (xy 383.090313 -346.20351) (xy 383.038017 -346.218868)
			(xy 382.984068 -346.226628) (xy 382.956816 -346.227146) (xy 382.937247 -346.226923) (xy 382.898308 -346.222979)
			(xy 382.879092 -346.219272) (xy 382.865481 -346.216882) (xy 382.837916 -346.218659) (xy 382.811839 -346.227769)
			(xy 382.789164 -346.243543) (xy 382.771553 -346.264823) (xy 382.7603 -346.290049) (xy 382.756229 -346.31737)
			(xy 382.75964 -346.344781) (xy 382.764538 -346.357702) (xy 382.774583 -346.381795) (xy 382.788726 -346.432041)
			(xy 382.795869 -346.483749) (xy 382.796288 -346.509848) (xy 382.795798 -346.537096) (xy 382.788036 -346.591038)
			(xy 382.772677 -346.643326) (xy 382.750033 -346.692895) (xy 382.720565 -346.738738) (xy 382.684873 -346.779921)
			(xy 382.643684 -346.815606) (xy 382.597836 -346.845065) (xy 382.548262 -346.867701) (xy 382.495971 -346.883051)
			(xy 382.442029 -346.890803) (xy 382.41478 -346.891356) (xy 382.414526 -346.891356) (xy 382.388746 -346.890937)
			(xy 382.337654 -346.884) (xy 382.287966 -346.870235) (xy 382.240587 -346.849894) (xy 382.196386 -346.823348)
			(xy 382.17602 -346.807536) (xy 382.154967 -346.799219) (xy 382.115262 -346.777485) (xy 382.079038 -346.750343)
			(xy 382.062736 -346.734638) (xy 381.69977 -346.371418) (xy 381.682423 -346.353428) (xy 381.653032 -346.31301)
			(xy 381.630326 -346.268492) (xy 381.614863 -346.220971) (xy 381.607026 -346.171615) (xy 381.606552 -346.146628)
			(xy 381.606552 -345.51239) (xy 381.607012 -345.4874) (xy 381.614827 -345.438034) (xy 381.63028 -345.390503)
			(xy 381.652987 -345.345978) (xy 381.682389 -345.305561) (xy 381.69977 -345.2876) (xy 382.081024 -344.906346)
			(xy 382.090919 -344.895747) (xy 382.104856 -344.870335) (xy 382.111098 -344.842033) (xy 382.109142 -344.813116)
			(xy 382.099146 -344.785912) (xy 382.081914 -344.762608) (xy 382.058833 -344.74508) (xy 382.045464 -344.739468)
			(xy 382.020419 -344.7307) (xy 381.972839 -344.707211) (xy 381.928974 -344.677354) (xy 381.88967 -344.641705)
			(xy 381.855686 -344.600954) (xy 381.827677 -344.555886) (xy 381.806185 -344.507371) (xy 381.791624 -344.456346)
			(xy 381.784275 -344.403795) (xy 381.783844 -344.377264) (xy 381.784332 -344.349696) (xy 381.792271 -344.295134)
			(xy 381.807979 -344.242282) (xy 381.831128 -344.192241) (xy 381.861238 -344.146052) (xy 381.879094 -344.125042)
			(xy 381.887845 -344.113851) (xy 381.899369 -344.087896) (xy 381.903307 -344.059772) (xy 381.899354 -344.031651)
			(xy 381.887816 -344.005702) (xy 381.879094 -343.994486) (xy 381.861228 -343.973482) (xy 381.831105 -343.927297)
			(xy 381.807946 -343.877256) (xy 381.792235 -343.824401) (xy 381.784299 -343.769834) (xy 381.783844 -343.742264)
			(xy 381.78433 -343.715013) (xy 381.792086 -343.661065) (xy 381.807441 -343.60877) (xy 381.830083 -343.559193)
			(xy 381.859549 -343.513343) (xy 381.89524 -343.472152) (xy 381.936431 -343.436461) (xy 381.982281 -343.406995)
			(xy 382.031858 -343.384353) (xy 382.084153 -343.368998) (xy 382.138101 -343.361242) (xy 382.192603 -343.361242)
			(xy 382.246551 -343.368998) (xy 382.298846 -343.384353) (xy 382.348423 -343.406995) (xy 382.394273 -343.436461)
			(xy 382.435464 -343.472152) (xy 382.471155 -343.513343) (xy 382.500621 -343.559193) (xy 382.523263 -343.60877)
			(xy 382.538618 -343.661065) (xy 382.546374 -343.715013) (xy 382.54686 -343.742264) (xy 382.54637 -343.769831)
			(xy 382.538428 -343.824392) (xy 382.522717 -343.877241) (xy 382.499565 -343.92728) (xy 382.469454 -343.973466)
			(xy 382.45161 -343.994486) (xy 382.442849 -344.005678) (xy 382.431305 -344.031638) (xy 382.42735 -344.059772)
			(xy 382.43129 -344.087909) (xy 382.442819 -344.113875) (xy 382.45161 -344.125042) (xy 382.468233 -344.144533)
			(xy 382.496654 -344.187152) (xy 382.51912 -344.233189) (xy 382.527556 -344.257376) (xy 382.533178 -344.270747)
			(xy 382.550673 -344.293863) (xy 382.573967 -344.311122) (xy 382.601177 -344.321126) (xy 382.630102 -344.323068)
			(xy 382.658405 -344.316791) (xy 382.683797 -344.302801) (xy 382.694434 -344.292936) (xy 382.731772 -344.255598)
			(xy 383.028444 -343.95918) (xy 383.028444 -342.771222) (xy 382.819148 -342.56218) (xy 382.801861 -342.544182)
			(xy 382.772546 -342.503801) (xy 382.7499 -342.459335) (xy 382.734479 -342.411878) (xy 382.726661 -342.362594)
			(xy 382.726184 -342.337644) (xy 382.726184 -336.542126) (xy 382.16332 -335.979262) (xy 382.142538 -335.957648)
			(xy 382.107296 -335.909144) (xy 382.080071 -335.855726) (xy 382.061534 -335.798707) (xy 382.052141 -335.739492)
			(xy 382.05156 -335.709514) (xy 382.05156 -332.220062) (xy 379.812804 -329.981052) (xy 375.548652 -329.981052)
			(xy 375.548652 -330.986384) (xy 375.548164 -331.011334) (xy 375.540361 -331.060621) (xy 375.524946 -331.10808)
			(xy 375.502296 -331.152544) (xy 375.472971 -331.192918) (xy 375.455688 -331.21092) (xy 375.390664 -331.275944)
			(xy 375.390664 -336.774536) (xy 375.392696 -336.776568) (xy 375.412226 -336.794844) (xy 375.445487 -336.836725)
			(xy 375.471285 -336.883575) (xy 375.488894 -336.934076) (xy 375.49782 -336.986808) (xy 375.49836 -337.01355)
			(xy 375.498106 -337.021678) (xy 375.498106 -337.022186) (xy 375.497852 -337.02498) (xy 375.497852 -338.764118)
			(xy 375.497369 -338.78907) (xy 375.489576 -338.838362) (xy 375.474167 -338.885828) (xy 375.451524 -338.930299)
			(xy 375.422203 -338.970681) (xy 375.404888 -338.988654) (xy 375.404342 -338.9892) (xy 377.871895 -338.9892)
			(xy 377.876064 -338.933575) (xy 377.888477 -338.879193) (xy 377.908856 -338.827269) (xy 377.936747 -338.778961)
			(xy 377.971527 -338.735351) (xy 378.012418 -338.697411) (xy 378.058507 -338.66599) (xy 378.108764 -338.641789)
			(xy 378.162068 -338.625349) (xy 378.217226 -338.617038) (xy 378.245116 -338.616544) (xy 378.27245 -338.616965)
			(xy 378.326532 -338.624943) (xy 378.378868 -338.64074) (xy 378.428332 -338.664016) (xy 378.473864 -338.694271)
			(xy 378.514485 -338.730857) (xy 378.549322 -338.772986) (xy 378.563886 -338.796122) (xy 378.571839 -338.808324)
			(xy 378.593304 -338.827993) (xy 378.619449 -338.840799) (xy 378.648146 -338.8457) (xy 378.677059 -338.842298)
			(xy 378.690632 -338.837016) (xy 378.713841 -338.827525) (xy 378.762174 -338.814174) (xy 378.811864 -338.807447)
			(xy 378.836936 -338.807044) (xy 378.862005 -338.807467) (xy 378.911688 -338.814217) (xy 378.960023 -338.82755)
			(xy 378.98324 -338.837016) (xy 378.996827 -338.842232) (xy 379.025723 -338.845603) (xy 379.054397 -338.840699)
			(xy 379.08053 -338.827917) (xy 379.102005 -338.808293) (xy 379.109986 -338.796122) (xy 379.124555 -338.772991)
			(xy 379.159398 -338.73087) (xy 379.200021 -338.694291) (xy 379.245552 -338.66404) (xy 379.295014 -338.640764)
			(xy 379.347345 -338.624964) (xy 379.401424 -338.616978) (xy 379.456088 -338.616978) (xy 379.510167 -338.624964)
			(xy 379.562498 -338.640764) (xy 379.61196 -338.66404) (xy 379.657491 -338.694291) (xy 379.698114 -338.73087)
			(xy 379.732957 -338.772991) (xy 379.747526 -338.796122) (xy 379.755441 -338.808351) (xy 379.776916 -338.82802)
			(xy 379.803071 -338.840823) (xy 379.831778 -338.845717) (xy 379.860698 -338.842304) (xy 379.874272 -338.837016)
			(xy 379.897488 -338.827544) (xy 379.945818 -338.814186) (xy 379.995505 -338.807451) (xy 380.020576 -338.807044)
			(xy 380.045517 -338.807416) (xy 380.094955 -338.814065) (xy 380.143064 -338.827247) (xy 380.188986 -338.846727)
			(xy 380.231899 -338.872158) (xy 380.251716 -338.887308) (xy 380.26328 -338.895793) (xy 380.289788 -338.906699)
			(xy 380.318285 -338.909788) (xy 380.346513 -338.904813) (xy 380.372238 -338.89217) (xy 380.393421 -338.872859)
			(xy 380.401322 -338.860892) (xy 380.416313 -338.837415) (xy 380.451977 -338.794632) (xy 380.493486 -338.757491)
			(xy 380.539956 -338.726784) (xy 380.590398 -338.703162) (xy 380.64374 -338.68713) (xy 380.698846 -338.679027)
			(xy 380.726696 -338.67852) (xy 380.754851 -338.678952) (xy 380.810552 -338.687216) (xy 380.864433 -338.703578)
			(xy 380.915323 -338.727684) (xy 380.962116 -338.75901) (xy 381.003795 -338.796875) (xy 381.039454 -338.840456)
			(xy 381.068319 -338.888806) (xy 381.089761 -338.940874) (xy 381.097028 -338.96808) (xy 381.101361 -338.983027)
			(xy 381.117615 -339.009543) (xy 381.141093 -339.029942) (xy 381.169619 -339.042335) (xy 381.200552 -339.045572)
			(xy 381.2159 -339.04301) (xy 381.234621 -339.039456) (xy 381.272538 -339.035641) (xy 381.291592 -339.03539)
			(xy 381.291846 -339.03539) (xy 381.319095 -339.035883) (xy 381.373037 -339.043645) (xy 381.425326 -339.059004)
			(xy 381.474898 -339.081647) (xy 381.520742 -339.111115) (xy 381.561926 -339.146806) (xy 381.597613 -339.187995)
			(xy 381.627075 -339.233843) (xy 381.649712 -339.283417) (xy 381.665065 -339.335708) (xy 381.67282 -339.389651)
			(xy 381.67282 -339.444149) (xy 381.665065 -339.498092) (xy 381.649712 -339.550383) (xy 381.627075 -339.599957)
			(xy 381.597613 -339.645805) (xy 381.561926 -339.686994) (xy 381.520742 -339.722685) (xy 381.474898 -339.752153)
			(xy 381.425326 -339.774796) (xy 381.373037 -339.790155) (xy 381.319095 -339.797917) (xy 381.291846 -339.798406)
			(xy 381.263693 -339.797916) (xy 381.207995 -339.789659) (xy 381.154117 -339.773304) (xy 381.103229 -339.749205)
			(xy 381.056436 -339.717886) (xy 381.014757 -339.680028) (xy 380.979096 -339.636454) (xy 380.950229 -339.588111)
			(xy 380.928783 -339.536049) (xy 380.921514 -339.508846) (xy 380.917228 -339.493882) (xy 380.900967 -339.467358)
			(xy 380.877478 -339.446956) (xy 380.848939 -339.434569) (xy 380.817994 -339.431344) (xy 380.802642 -339.433916)
			(xy 380.783858 -339.437482) (xy 380.745814 -339.4413) (xy 380.726696 -339.441536) (xy 380.726442 -339.441536)
			(xy 380.700302 -339.441074) (xy 380.648512 -339.433943) (xy 380.598183 -339.419797) (xy 380.550262 -339.3989)
			(xy 380.505649 -339.371646) (xy 380.485142 -339.35543) (xy 380.473724 -339.346722) (xy 380.44736 -339.335384)
			(xy 380.41888 -339.33185) (xy 380.390544 -339.3364) (xy 380.364601 -339.348673) (xy 380.343112 -339.367694)
			(xy 380.335028 -339.37956) (xy 380.3293 -339.388435) (xy 380.316971 -339.405588) (xy 380.31039 -339.41385)
			(xy 380.301159 -339.426158) (xy 380.289769 -339.454718) (xy 380.287381 -339.485373) (xy 380.29421 -339.515353)
			(xy 380.30964 -339.541948) (xy 380.332277 -339.562757) (xy 380.34595 -339.569806) (xy 380.369084 -339.581162)
			(xy 380.412323 -339.609201) (xy 380.451386 -339.642814) (xy 380.485561 -339.681387) (xy 380.514222 -339.724216)
			(xy 380.536847 -339.770519) (xy 380.54534 -339.79485) (xy 380.550438 -339.808602) (xy 380.567205 -339.832649)
			(xy 380.590102 -339.850956) (xy 380.61725 -339.862021) (xy 380.64642 -339.864934) (xy 380.66091 -339.862668)
			(xy 380.678646 -339.859483) (xy 380.71452 -339.856046) (xy 380.732538 -339.85581) (xy 380.7333 -339.85581)
			(xy 380.760554 -339.856255) (xy 380.814506 -339.864013) (xy 380.866805 -339.87937) (xy 380.916387 -339.902014)
			(xy 380.962241 -339.931483) (xy 381.003434 -339.967179) (xy 381.039128 -340.008374) (xy 381.068595 -340.054229)
			(xy 381.091237 -340.103811) (xy 381.106591 -340.156111) (xy 381.114346 -340.210064) (xy 381.114808 -340.237318)
			(xy 381.114554 -340.247732) (xy 381.114676 -340.262099) (xy 381.12194 -340.289884) (xy 381.136646 -340.31455)
			(xy 381.157635 -340.334151) (xy 381.183249 -340.347138) (xy 381.211465 -340.352486) (xy 381.225806 -340.351618)
			(xy 381.262382 -340.34984) (xy 381.289639 -340.350206) (xy 381.343599 -340.357962) (xy 381.395906 -340.373318)
			(xy 381.445494 -340.395962) (xy 381.491355 -340.425434) (xy 381.532555 -340.461132) (xy 381.568256 -340.50233)
			(xy 381.597729 -340.54819) (xy 381.620376 -340.597778) (xy 381.635735 -340.650084) (xy 381.643493 -340.704043)
			(xy 381.643493 -340.758557) (xy 381.635735 -340.812516) (xy 381.620376 -340.864822) (xy 381.597729 -340.91441)
			(xy 381.568256 -340.96027) (xy 381.532555 -341.001468) (xy 381.491355 -341.037166) (xy 381.445494 -341.066638)
			(xy 381.395906 -341.089282) (xy 381.343599 -341.104638) (xy 381.289639 -341.112394) (xy 381.262382 -341.112856)
			(xy 381.251371 -341.112781) (xy 381.229386 -341.111508) (xy 381.21844 -341.110316) (xy 381.203582 -341.109091)
			(xy 381.174247 -341.11434) (xy 381.14768 -341.12784) (xy 381.126144 -341.148439) (xy 381.111478 -341.17438)
			(xy 381.107696 -341.188802) (xy 381.100847 -341.216546) (xy 381.07999 -341.269747) (xy 381.051435 -341.319245)
			(xy 381.015821 -341.363933) (xy 380.973944 -341.402814) (xy 380.926739 -341.435018) (xy 380.875262 -341.459826)
			(xy 380.820661 -341.476683) (xy 380.764158 -341.485214) (xy 380.735586 -341.485728) (xy 380.706599 -341.485189)
			(xy 380.649292 -341.476416) (xy 380.593972 -341.459074) (xy 380.541912 -341.433561) (xy 380.494312 -341.400467)
			(xy 380.452267 -341.360551) (xy 380.416744 -341.314734) (xy 380.388562 -341.26407) (xy 380.36837 -341.209726)
			(xy 380.356632 -341.152952) (xy 380.354586 -341.124032) (xy 380.353411 -341.109958) (xy 380.34432 -341.083231)
			(xy 380.328247 -341.060024) (xy 380.306424 -341.042115) (xy 380.280526 -341.030879) (xy 380.252539 -341.027179)
			(xy 380.238508 -341.028782) (xy 380.224743 -341.030678) (xy 380.19703 -341.032711) (xy 380.183136 -341.032846)
			(xy 380.155887 -341.032288) (xy 380.101944 -341.024538) (xy 380.049653 -341.009189) (xy 380.000079 -340.986555)
			(xy 379.95423 -340.957096) (xy 379.91304 -340.921412) (xy 379.877348 -340.880229) (xy 379.847881 -340.834386)
			(xy 379.825237 -340.784816) (xy 379.809878 -340.732528) (xy 379.802117 -340.678587) (xy 379.801628 -340.651338)
			(xy 379.80211 -340.623764) (xy 379.810058 -340.569191) (xy 379.825779 -340.516331) (xy 379.848946 -340.466285)
			(xy 379.879076 -340.420095) (xy 379.915542 -340.378724) (xy 379.936248 -340.360508) (xy 379.947111 -340.350573)
			(xy 379.963193 -340.325935) (xy 379.971585 -340.297735) (xy 379.971592 -340.268314) (xy 379.963214 -340.24011)
			(xy 379.947144 -340.215464) (xy 379.936248 -340.205568) (xy 379.915528 -340.187366) (xy 379.879056 -340.145997)
			(xy 379.848924 -340.099805) (xy 379.825759 -340.049755) (xy 379.810046 -339.99689) (xy 379.80211 -339.942313)
			(xy 379.801628 -339.914738) (xy 379.802058 -339.888236) (xy 379.809408 -339.835744) (xy 379.823958 -339.784775)
			(xy 379.845426 -339.736313) (xy 379.8734 -339.691292) (xy 379.89002 -339.670644) (xy 379.899478 -339.658509)
			(xy 379.911271 -339.630105) (xy 379.914094 -339.59948) (xy 379.907695 -339.569399) (xy 379.892649 -339.542576)
			(xy 379.870316 -339.521432) (xy 379.856746 -339.51418) (xy 379.833054 -339.502083) (xy 379.789072 -339.472159)
			(xy 379.749792 -339.436287) (xy 379.716009 -339.395195) (xy 379.701806 -339.372702) (xy 379.693854 -339.360498)
			(xy 379.672391 -339.340827) (xy 379.646245 -339.328019) (xy 379.617547 -339.323119) (xy 379.588632 -339.326524)
			(xy 379.57506 -339.331808) (xy 379.551852 -339.341303) (xy 379.503518 -339.354652) (xy 379.453828 -339.361378)
			(xy 379.428756 -339.36178) (xy 379.403687 -339.361358) (xy 379.354004 -339.354608) (xy 379.305669 -339.341274)
			(xy 379.282452 -339.331808) (xy 379.26887 -339.326573) (xy 379.239972 -339.323203) (xy 379.211294 -339.32811)
			(xy 379.18516 -339.340897) (xy 379.163686 -339.360528) (xy 379.155706 -339.372702) (xy 379.141137 -339.395833)
			(xy 379.106294 -339.437954) (xy 379.065671 -339.474533) (xy 379.02014 -339.504784) (xy 378.970678 -339.52806)
			(xy 378.918347 -339.54386) (xy 378.864268 -339.551846) (xy 378.809604 -339.551846) (xy 378.755525 -339.54386)
			(xy 378.703194 -339.52806) (xy 378.653732 -339.504784) (xy 378.608201 -339.474533) (xy 378.567578 -339.437954)
			(xy 378.532735 -339.395833) (xy 378.518166 -339.372702) (xy 378.510252 -339.360471) (xy 378.488779 -339.340799)
			(xy 378.462623 -339.327995) (xy 378.433915 -339.323102) (xy 378.404994 -339.326518) (xy 378.39142 -339.331808)
			(xy 378.368205 -339.341284) (xy 378.319875 -339.35464) (xy 378.270187 -339.361374) (xy 378.245116 -339.36178)
			(xy 378.217226 -339.361362) (xy 378.162068 -339.353051) (xy 378.108764 -339.336611) (xy 378.058507 -339.31241)
			(xy 378.012418 -339.280989) (xy 377.971527 -339.243049) (xy 377.936747 -339.199439) (xy 377.908856 -339.151131)
			(xy 377.888477 -339.099207) (xy 377.876064 -339.044825) (xy 377.871895 -338.9892) (xy 375.404342 -338.9892)
			(xy 375.383298 -339.010244) (xy 375.379996 -339.024214) (xy 375.373449 -339.04952) (xy 375.354369 -339.098184)
			(xy 375.328826 -339.143788) (xy 375.297298 -339.18548) (xy 375.279158 -339.2043) (xy 374.934988 -339.548216)
			(xy 374.845326 -339.548216) (xy 374.768618 -339.624924) (xy 374.817386 -339.673692) (xy 374.835166 -339.67547)
			(xy 374.862999 -339.678817) (xy 374.917329 -339.692627) (xy 374.969053 -339.714238) (xy 375.017058 -339.743186)
			(xy 375.06031 -339.778847) (xy 375.097879 -339.820453) (xy 375.128954 -339.867109) (xy 375.152868 -339.91781)
			(xy 375.169105 -339.971464) (xy 375.177316 -340.026917) (xy 375.177812 -340.054946) (xy 375.177326 -340.08248)
			(xy 375.169406 -340.136977) (xy 375.153737 -340.18977) (xy 375.130644 -340.239763) (xy 375.100607 -340.285919)
			(xy 375.064248 -340.327279) (xy 375.022324 -340.362986) (xy 374.975704 -340.392297) (xy 374.925355 -340.414604)
			(xy 374.872324 -340.429445) (xy 374.845072 -340.433406) (xy 374.831282 -340.435614) (xy 374.805588 -340.44653)
			(xy 374.783809 -340.463995) (xy 374.767572 -340.486704) (xy 374.75809 -340.512961) (xy 374.756072 -340.540805)
			(xy 374.758458 -340.554564) (xy 374.762139 -340.573527) (xy 374.766086 -340.611956) (xy 374.766332 -340.631272)
			(xy 374.765871 -340.658527) (xy 374.758117 -340.712482) (xy 374.742764 -340.764785) (xy 374.720124 -340.81437)
			(xy 374.690657 -340.860228) (xy 374.654963 -340.901426) (xy 374.61377 -340.937125) (xy 374.567916 -340.966599)
			(xy 374.518334 -340.989246) (xy 374.466033 -341.004606) (xy 374.412079 -341.012367) (xy 374.384824 -341.01278)
			(xy 374.336056 -341.01278) (xy 374.306074 -341.012226) (xy 374.246847 -341.002851) (xy 374.189817 -340.984323)
			(xy 374.136389 -340.957099) (xy 374.08788 -340.921849) (xy 374.066308 -340.90102) (xy 373.878856 -340.713568)
			(xy 373.858072 -340.691955) (xy 373.822826 -340.643452) (xy 373.795597 -340.590034) (xy 373.777058 -340.533015)
			(xy 373.767663 -340.473798) (xy 373.767096 -340.44382) (xy 373.767096 -339.795358) (xy 373.76765 -339.765376)
			(xy 373.777026 -339.706151) (xy 373.795557 -339.649123) (xy 373.822785 -339.595698) (xy 373.858039 -339.547194)
			(xy 373.878856 -339.52561) (xy 374.628156 -338.776564) (xy 374.628156 -336.911442) (xy 374.60934 -336.893231)
			(xy 374.577337 -336.851789) (xy 374.552552 -336.805666) (xy 374.535656 -336.756107) (xy 374.527102 -336.70445)
			(xy 374.526556 -336.67827) (xy 374.52681 -336.670142) (xy 374.52681 -336.669634) (xy 374.527064 -336.66684)
			(xy 374.527064 -331.37221) (xy 374.527507 -331.348118) (xy 374.534772 -331.300485) (xy 374.549137 -331.254493)
			(xy 374.570273 -331.211192) (xy 374.597697 -331.171575) (xy 374.613932 -331.15377) (xy 374.627902 -331.139038)
			(xy 374.627902 -331.038708) (xy 374.627648 -331.038708) (xy 374.627648 -329.63231) (xy 371.283484 -326.287892)
			(xy 366.770412 -326.287892) (xy 366.770412 -327.19137) (xy 367.118392 -327.53935) (xy 367.139172 -327.560964)
			(xy 367.174413 -327.609469) (xy 367.201635 -327.662888) (xy 367.220169 -327.719906) (xy 367.22956 -327.779121)
			(xy 367.230152 -327.809098) (xy 367.230152 -335.56702) (xy 367.229909 -335.579) (xy 369.711391 -335.579)
			(xy 369.71556 -335.523376) (xy 369.727972 -335.468994) (xy 369.748351 -335.41707) (xy 369.776242 -335.368763)
			(xy 369.81102 -335.325152) (xy 369.85191 -335.287212) (xy 369.897998 -335.255791) (xy 369.948254 -335.231589)
			(xy 370.001557 -335.215148) (xy 370.056714 -335.206835) (xy 370.084604 -335.20634) (xy 370.111937 -335.206773)
			(xy 370.166019 -335.214749) (xy 370.218354 -335.230543) (xy 370.267819 -335.253818) (xy 370.313351 -335.284071)
			(xy 370.353972 -335.320655) (xy 370.38881 -335.362783) (xy 370.403374 -335.385918) (xy 370.41134 -335.398111)
			(xy 370.4328 -335.41778) (xy 370.458942 -335.430588) (xy 370.487637 -335.435491) (xy 370.516548 -335.432092)
			(xy 370.53012 -335.426812) (xy 370.553331 -335.417325) (xy 370.601663 -335.403973) (xy 370.651352 -335.397244)
			(xy 370.676424 -335.39684) (xy 370.701493 -335.397267) (xy 370.751176 -335.404015) (xy 370.799511 -335.417346)
			(xy 370.822728 -335.426812) (xy 370.836319 -335.432017) (xy 370.865212 -335.435391) (xy 370.893886 -335.430489)
			(xy 370.920018 -335.41771) (xy 370.941493 -335.398088) (xy 370.949474 -335.385918) (xy 370.964043 -335.362787)
			(xy 370.998886 -335.320666) (xy 371.039509 -335.284087) (xy 371.08504 -335.253836) (xy 371.134502 -335.23056)
			(xy 371.186833 -335.21476) (xy 371.240912 -335.206774) (xy 371.295576 -335.206774) (xy 371.349655 -335.21476)
			(xy 371.401986 -335.23056) (xy 371.451448 -335.253836) (xy 371.496979 -335.284087) (xy 371.537602 -335.320666)
			(xy 371.572445 -335.362787) (xy 371.587014 -335.385918) (xy 371.594942 -335.398139) (xy 371.616413 -335.417808)
			(xy 371.642565 -335.430612) (xy 371.671268 -335.435508) (xy 371.700186 -335.432098) (xy 371.71376 -335.426812)
			(xy 371.736966 -335.417312) (xy 371.785301 -335.403965) (xy 371.834992 -335.397241) (xy 371.860064 -335.39684)
			(xy 371.887949 -335.397417) (xy 371.943098 -335.405724) (xy 371.996392 -335.422159) (xy 372.046641 -335.446353)
			(xy 372.092723 -335.477767) (xy 372.133608 -335.515699) (xy 372.168382 -335.5593) (xy 372.196269 -335.607598)
			(xy 372.216645 -335.659513) (xy 372.229056 -335.713885) (xy 372.233224 -335.7695) (xy 372.229056 -335.825115)
			(xy 372.216645 -335.879487) (xy 372.196269 -335.931402) (xy 372.168382 -335.9797) (xy 372.133608 -336.023301)
			(xy 372.092723 -336.061233) (xy 372.046641 -336.092647) (xy 371.996392 -336.116841) (xy 371.943098 -336.133276)
			(xy 371.887949 -336.141583) (xy 371.860064 -336.142076) (xy 371.832733 -336.141582) (xy 371.778654 -336.133616)
			(xy 371.726321 -336.117831) (xy 371.676857 -336.094567) (xy 371.631324 -336.064323) (xy 371.590701 -336.027748)
			(xy 371.55586 -335.985629) (xy 371.541294 -335.962498) (xy 371.533355 -335.950285) (xy 371.511888 -335.930614)
			(xy 371.485739 -335.917808) (xy 371.457037 -335.91291) (xy 371.428121 -335.916318) (xy 371.414548 -335.921604)
			(xy 371.391341 -335.931102) (xy 371.343007 -335.94445) (xy 371.293316 -335.951174) (xy 371.268244 -335.951576)
			(xy 371.243174 -335.951158) (xy 371.193491 -335.944406) (xy 371.145157 -335.931071) (xy 371.12194 -335.921604)
			(xy 371.108362 -335.916358) (xy 371.079462 -335.912991) (xy 371.050783 -335.917901) (xy 371.024648 -335.93069)
			(xy 371.003174 -335.950323) (xy 370.995194 -335.962498) (xy 370.980625 -335.985629) (xy 370.945782 -336.02775)
			(xy 370.905159 -336.064329) (xy 370.859628 -336.09458) (xy 370.810166 -336.117856) (xy 370.757835 -336.133656)
			(xy 370.703756 -336.141642) (xy 370.649092 -336.141642) (xy 370.595013 -336.133656) (xy 370.542682 -336.117856)
			(xy 370.49322 -336.09458) (xy 370.447689 -336.064329) (xy 370.407066 -336.02775) (xy 370.372223 -335.985629)
			(xy 370.357654 -335.962498) (xy 370.349753 -335.950258) (xy 370.328276 -335.930587) (xy 370.302116 -335.917784)
			(xy 370.273406 -335.912893) (xy 370.244483 -335.916312) (xy 370.230908 -335.921604) (xy 370.207694 -335.931084)
			(xy 370.159363 -335.944438) (xy 370.109675 -335.95117) (xy 370.084604 -335.951576) (xy 370.056714 -335.951165)
			(xy 370.001557 -335.942852) (xy 369.948254 -335.926411) (xy 369.897998 -335.902209) (xy 369.85191 -335.870788)
			(xy 369.81102 -335.832848) (xy 369.776242 -335.789237) (xy 369.748351 -335.74093) (xy 369.727972 -335.689006)
			(xy 369.71556 -335.634624) (xy 369.711391 -335.579) (xy 367.229909 -335.579) (xy 367.229544 -335.596936)
			(xy 367.220155 -335.656027) (xy 367.201658 -335.712929) (xy 367.174505 -335.766245) (xy 367.139363 -335.81467)
			(xy 367.118646 -335.83626) (xy 366.802162 -336.15249) (xy 366.7125 -336.15249) (xy 366.644936 -336.220054)
			(xy 366.691926 -336.267044) (xy 366.70742 -336.270092) (xy 366.733234 -336.275484) (xy 366.783171 -336.292433)
			(xy 366.830298 -336.316096) (xy 366.873719 -336.346022) (xy 366.912605 -336.381643) (xy 366.946216 -336.422278)
			(xy 366.973912 -336.467154) (xy 366.995164 -336.515417) (xy 367.00957 -336.566146) (xy 367.016852 -336.618375)
			(xy 367.0173 -336.644742) (xy 367.016811 -336.671991) (xy 367.00905 -336.725934) (xy 366.993691 -336.778223)
			(xy 366.971047 -336.827795) (xy 366.94158 -336.873639) (xy 366.905888 -336.914824) (xy 366.864699 -336.95051)
			(xy 366.818851 -336.979971) (xy 366.769276 -337.002609) (xy 366.716985 -337.017961) (xy 366.663041 -337.025715)
			(xy 366.635792 -337.02625) (xy 366.620485 -337.02612) (xy 366.589968 -337.023707) (xy 366.574832 -337.021424)
			(xy 366.560508 -337.020057) (xy 366.532081 -337.024434) (xy 366.505997 -337.036554) (xy 366.484321 -337.05546)
			(xy 366.468768 -337.079653) (xy 366.460568 -337.107222) (xy 366.460369 -337.135983) (xy 366.463834 -337.149948)
			(xy 366.471289 -337.176636) (xy 366.479321 -337.231463) (xy 366.479836 -337.259168) (xy 366.479836 -337.259422)
			(xy 366.479349 -337.286673) (xy 366.47159 -337.34062) (xy 366.456233 -337.392914) (xy 366.433591 -337.44249)
			(xy 366.404125 -337.488339) (xy 366.368434 -337.529529) (xy 366.327244 -337.565221) (xy 366.281395 -337.594688)
			(xy 366.231819 -337.617331) (xy 366.179526 -337.632689) (xy 366.125579 -337.640448) (xy 366.098328 -337.64093)
			(xy 366.072909 -337.640512) (xy 366.022522 -337.633763) (xy 365.973478 -337.62038) (xy 365.926647 -337.600601)
			(xy 365.882857 -337.574776) (xy 365.862616 -337.559396) (xy 365.853716 -337.552291) (xy 365.836685 -337.53717)
			(xy 365.82858 -337.52917) (xy 365.705136 -337.405726) (xy 365.684356 -337.384112) (xy 365.649116 -337.335607)
			(xy 365.621895 -337.282188) (xy 365.603363 -337.22517) (xy 365.593975 -337.165955) (xy 365.593376 -337.135978)
			(xy 365.593376 -336.440526) (xy 365.593932 -336.410545) (xy 365.603312 -336.351322) (xy 365.621846 -336.294297)
			(xy 365.649076 -336.240874) (xy 365.684331 -336.192372) (xy 365.705136 -336.170778) (xy 366.467644 -335.408524)
			(xy 366.467644 -333.828136) (xy 366.410748 -333.77124) (xy 366.393464 -333.753242) (xy 366.364154 -333.712859)
			(xy 366.341513 -333.668393) (xy 366.326098 -333.620936) (xy 366.318286 -333.571653) (xy 366.317784 -333.546704)
			(xy 366.317784 -327.817734) (xy 366.070896 -327.570846) (xy 366.050117 -327.549231) (xy 366.014878 -327.500726)
			(xy 365.987657 -327.447307) (xy 365.969124 -327.39029) (xy 365.959734 -327.331075) (xy 365.959136 -327.301098)
			(xy 365.959136 -326.287892) (xy 357.382572 -326.287892) (xy 357.382572 -327.11009) (xy 358.95788 -328.685398)
			(xy 358.978654 -328.706974) (xy 359.01384 -328.755441) (xy 359.04101 -328.808817) (xy 359.059493 -328.865786)
			(xy 359.068834 -328.924945) (xy 359.069386 -328.954892) (xy 359.069386 -328.955146) (xy 359.06964 -334.887062)
			(xy 359.06964 -335.176368) (xy 365.46282 -335.176368) (xy 365.463262 -335.148997) (xy 365.471085 -335.094817)
			(xy 365.48658 -335.042313) (xy 365.509427 -334.992567) (xy 365.539156 -334.946601) (xy 365.5568 -334.92567)
			(xy 365.566068 -334.914366) (xy 365.578241 -334.8878) (xy 365.582408 -334.858876) (xy 365.578228 -334.829954)
			(xy 365.566041 -334.803393) (xy 365.5568 -334.792066) (xy 365.539178 -334.77112) (xy 365.509464 -334.725151)
			(xy 365.486625 -334.675407) (xy 365.471129 -334.622909) (xy 365.463297 -334.568736) (xy 365.46282 -334.541368)
			(xy 365.463306 -334.514117) (xy 365.471062 -334.460169) (xy 365.486417 -334.407874) (xy 365.509059 -334.358297)
			(xy 365.538525 -334.312447) (xy 365.574216 -334.271256) (xy 365.615407 -334.235565) (xy 365.661257 -334.206099)
			(xy 365.710834 -334.183457) (xy 365.763129 -334.168102) (xy 365.817077 -334.160346) (xy 365.871579 -334.160346)
			(xy 365.925527 -334.168102) (xy 365.977822 -334.183457) (xy 366.027399 -334.206099) (xy 366.073249 -334.235565)
			(xy 366.11444 -334.271256) (xy 366.150131 -334.312447) (xy 366.179597 -334.358297) (xy 366.202239 -334.407874)
			(xy 366.217594 -334.460169) (xy 366.22535 -334.514117) (xy 366.225836 -334.541368) (xy 366.225367 -334.568738)
			(xy 366.217552 -334.622918) (xy 366.202065 -334.675422) (xy 366.179223 -334.725169) (xy 366.149498 -334.771135)
			(xy 366.131856 -334.792066) (xy 366.122653 -334.803418) (xy 366.110478 -334.829967) (xy 366.106301 -334.858876)
			(xy 366.110464 -334.887786) (xy 366.122627 -334.914341) (xy 366.131856 -334.92567) (xy 366.149488 -334.946608)
			(xy 366.179202 -334.992579) (xy 366.20204 -335.042324) (xy 366.217533 -335.094824) (xy 366.225362 -335.148999)
			(xy 366.225836 -335.176368) (xy 366.22535 -335.203619) (xy 366.217594 -335.257567) (xy 366.202239 -335.309862)
			(xy 366.179597 -335.359439) (xy 366.150131 -335.405289) (xy 366.11444 -335.44648) (xy 366.073249 -335.482171)
			(xy 366.027399 -335.511637) (xy 365.977822 -335.534279) (xy 365.925527 -335.549634) (xy 365.871579 -335.55739)
			(xy 365.817077 -335.55739) (xy 365.763129 -335.549634) (xy 365.710834 -335.534279) (xy 365.661257 -335.511637)
			(xy 365.615407 -335.482171) (xy 365.574216 -335.44648) (xy 365.538525 -335.405289) (xy 365.509059 -335.359439)
			(xy 365.486417 -335.309862) (xy 365.471062 -335.257567) (xy 365.463306 -335.203619) (xy 365.46282 -335.176368)
			(xy 359.06964 -335.176368) (xy 359.06964 -335.42986) (xy 359.069029 -335.459774) (xy 359.059634 -335.518862)
			(xy 359.041132 -335.575759) (xy 359.039481 -335.579) (xy 361.550917 -335.579) (xy 361.555086 -335.523381)
			(xy 361.567497 -335.469004) (xy 361.587873 -335.417084) (xy 361.61576 -335.368781) (xy 361.650535 -335.325174)
			(xy 361.691421 -335.287237) (xy 361.737504 -335.255817) (xy 361.787755 -335.231616) (xy 361.841052 -335.215175)
			(xy 361.896204 -335.206862) (xy 361.924092 -335.20634) (xy 361.951425 -335.206783) (xy 362.005506 -335.214757)
			(xy 362.057841 -335.23055) (xy 362.107306 -335.253822) (xy 362.152838 -335.284075) (xy 362.193459 -335.320657)
			(xy 362.228297 -335.362784) (xy 362.242862 -335.385918) (xy 362.250744 -335.398171) (xy 362.272228 -335.417841)
			(xy 362.298392 -335.43064) (xy 362.327106 -335.435528) (xy 362.356032 -335.432105) (xy 362.369608 -335.426812)
			(xy 362.39282 -335.417328) (xy 362.441152 -335.403975) (xy 362.490841 -335.397244) (xy 362.515912 -335.39684)
			(xy 362.540981 -335.397271) (xy 362.590664 -335.404017) (xy 362.638998 -335.417347) (xy 362.662216 -335.426812)
			(xy 362.675812 -335.432005) (xy 362.704703 -335.435381) (xy 362.733375 -335.430482) (xy 362.759506 -335.417706)
			(xy 362.78098 -335.398087) (xy 362.788962 -335.385918) (xy 362.803531 -335.362787) (xy 362.838374 -335.320666)
			(xy 362.878997 -335.284087) (xy 362.924528 -335.253836) (xy 362.97399 -335.23056) (xy 363.026321 -335.21476)
			(xy 363.0804 -335.206774) (xy 363.135064 -335.206774) (xy 363.189143 -335.21476) (xy 363.241474 -335.23056)
			(xy 363.290936 -335.253836) (xy 363.336467 -335.284087) (xy 363.37709 -335.320666) (xy 363.411933 -335.362787)
			(xy 363.426502 -335.385918) (xy 363.434441 -335.39813) (xy 363.455909 -335.417799) (xy 363.482058 -335.430604)
			(xy 363.510759 -335.435503) (xy 363.539675 -335.432096) (xy 363.553248 -335.426812) (xy 363.576455 -335.417316)
			(xy 363.624789 -335.403967) (xy 363.67448 -335.397242) (xy 363.699552 -335.39684) (xy 363.726392 -335.397376)
			(xy 363.779517 -335.405073) (xy 363.830988 -335.420314) (xy 363.879739 -335.442783) (xy 363.92476 -335.472016)
			(xy 363.965121 -335.507407) (xy 363.999985 -335.548224) (xy 364.02863 -335.593622) (xy 364.050464 -335.642661)
			(xy 364.0582 -335.668366) (xy 364.062871 -335.68286) (xy 364.079389 -335.708422) (xy 364.102703 -335.727986)
			(xy 364.130744 -335.739816) (xy 364.161026 -335.742862) (xy 364.190862 -335.736855) (xy 364.204504 -335.730088)
			(xy 364.232659 -335.715474) (xy 364.292606 -335.69474) (xy 364.35516 -335.684233) (xy 364.386876 -335.683606)
			(xy 364.404896 -335.68382) (xy 364.44077 -335.687259) (xy 364.458504 -335.690464) (xy 364.473713 -335.692802)
			(xy 364.504265 -335.689273) (xy 364.532384 -335.676812) (xy 364.555519 -335.656547) (xy 364.571576 -335.630315)
			(xy 364.575852 -335.615534) (xy 364.583203 -335.588476) (xy 364.604838 -335.536748) (xy 364.633808 -335.488742)
			(xy 364.66949 -335.44549) (xy 364.711115 -335.407924) (xy 364.757788 -335.376851) (xy 364.808505 -335.352942)
			(xy 364.862174 -335.336709) (xy 364.917641 -335.328502) (xy 364.945676 -335.328006) (xy 364.972929 -335.328478)
			(xy 365.02688 -335.336232) (xy 365.079179 -335.351585) (xy 365.12876 -335.374226) (xy 365.174614 -335.403693)
			(xy 365.215807 -335.439386) (xy 365.251501 -335.480578) (xy 365.280969 -335.526431) (xy 365.303611 -335.576012)
			(xy 365.318966 -335.62831) (xy 365.326722 -335.682261) (xy 365.327184 -335.709514) (xy 365.326665 -335.737087)
			(xy 365.318724 -335.791657) (xy 365.30301 -335.844517) (xy 365.27985 -335.894563) (xy 365.249727 -335.940754)
			(xy 365.213267 -335.982127) (xy 365.192564 -336.000344) (xy 365.181647 -336.010225) (xy 365.165566 -336.034878)
			(xy 365.157178 -336.063092) (xy 365.157181 -336.092526) (xy 365.165573 -336.120739) (xy 365.181659 -336.145388)
			(xy 365.192564 -336.155284) (xy 365.213285 -336.173484) (xy 365.249752 -336.214856) (xy 365.279881 -336.261047)
			(xy 365.303045 -336.311096) (xy 365.318761 -336.363959) (xy 365.326701 -336.418534) (xy 365.326699 -336.473684)
			(xy 365.318757 -336.528258) (xy 365.303039 -336.581121) (xy 365.279872 -336.631168) (xy 365.249741 -336.677359)
			(xy 365.213272 -336.718729) (xy 365.192564 -336.736944) (xy 365.181647 -336.746825) (xy 365.165566 -336.771478)
			(xy 365.157178 -336.799692) (xy 365.157181 -336.829126) (xy 365.165573 -336.857339) (xy 365.181659 -336.881988)
			(xy 365.192564 -336.891884) (xy 365.213263 -336.910108) (xy 365.249736 -336.951473) (xy 365.279871 -336.99766)
			(xy 365.303039 -337.047706) (xy 365.318757 -337.100566) (xy 365.326698 -337.15514) (xy 365.327184 -337.182714)
			(xy 365.326758 -337.209968) (xy 365.318999 -337.263922) (xy 365.30364 -337.316222) (xy 365.280994 -337.365804)
			(xy 365.251522 -337.411658) (xy 365.215824 -337.452851) (xy 365.174628 -337.488545) (xy 365.12877 -337.518012)
			(xy 365.079186 -337.540653) (xy 365.026885 -337.556007) (xy 364.97293 -337.563761) (xy 364.945676 -337.564222)
			(xy 364.917821 -337.563704) (xy 364.862706 -337.555578) (xy 364.809356 -337.53953) (xy 364.758904 -337.515902)
			(xy 364.71242 -337.485194) (xy 364.670891 -337.448059) (xy 364.635198 -337.405284) (xy 364.606098 -337.357777)
			(xy 364.584209 -337.306547) (xy 364.576614 -337.279742) (xy 364.572272 -337.26565) (xy 364.556899 -337.240508)
			(xy 364.534998 -337.22079) (xy 364.508385 -337.208132) (xy 364.479268 -337.203584) (xy 364.4646 -337.205066)
			(xy 364.451583 -337.206734) (xy 364.425399 -337.208514) (xy 364.412276 -337.208622) (xy 364.398127 -337.208531)
			(xy 364.369904 -337.206495) (xy 364.355888 -337.204558) (xy 364.342533 -337.203057) (xy 364.315853 -337.206144)
			(xy 364.290907 -337.216099) (xy 364.26943 -337.232227) (xy 364.252916 -337.253409) (xy 364.242512 -337.278171)
			(xy 364.240318 -337.291426) (xy 364.236214 -337.318577) (xy 364.221244 -337.371407) (xy 364.198855 -337.421545)
			(xy 364.169509 -337.467956) (xy 364.133814 -337.509681) (xy 364.092506 -337.545858) (xy 364.046438 -337.57574)
			(xy 363.996563 -337.598709) (xy 363.94391 -337.614291) (xy 363.889567 -337.622164) (xy 363.862112 -337.622642)
			(xy 363.834863 -337.622111) (xy 363.780918 -337.614357) (xy 363.728627 -337.599005) (xy 363.679052 -337.576368)
			(xy 363.633203 -337.546906) (xy 363.592014 -337.511219) (xy 363.556322 -337.470034) (xy 363.526855 -337.424189)
			(xy 363.504211 -337.374617) (xy 363.488853 -337.322327) (xy 363.481093 -337.268383) (xy 363.480604 -337.241134)
			(xy 363.481092 -337.21356) (xy 363.48904 -337.158988) (xy 363.50476 -337.106129) (xy 363.527926 -337.056083)
			(xy 363.558055 -337.009893) (xy 363.594519 -336.96852) (xy 363.615224 -336.950304) (xy 363.626084 -336.940369)
			(xy 363.642154 -336.915728) (xy 363.650539 -336.887531) (xy 363.650546 -336.858113) (xy 363.642173 -336.829912)
			(xy 363.626114 -336.805264) (xy 363.615224 -336.795364) (xy 363.594497 -336.77717) (xy 363.558027 -336.735798)
			(xy 363.527896 -336.689605) (xy 363.504733 -336.639553) (xy 363.48902 -336.586688) (xy 363.481086 -336.53211)
			(xy 363.480604 -336.504534) (xy 363.481038 -336.478032) (xy 363.488387 -336.42554) (xy 363.502936 -336.374572)
			(xy 363.524404 -336.32611) (xy 363.552377 -336.281088) (xy 363.568996 -336.26044) (xy 363.578467 -336.248313)
			(xy 363.590263 -336.219907) (xy 363.593087 -336.189278) (xy 363.586685 -336.159193) (xy 363.571635 -336.132369)
			(xy 363.549295 -336.111226) (xy 363.535722 -336.103976) (xy 363.512025 -336.091888) (xy 363.468045 -336.061961)
			(xy 363.428765 -336.026086) (xy 363.394984 -335.984992) (xy 363.380782 -335.962498) (xy 363.372854 -335.950277)
			(xy 363.351384 -335.930606) (xy 363.325232 -335.917801) (xy 363.296528 -335.912905) (xy 363.26761 -335.916317)
			(xy 363.254036 -335.921604) (xy 363.230819 -335.931075) (xy 363.18249 -335.944433) (xy 363.132803 -335.951169)
			(xy 363.107732 -335.951576) (xy 363.082662 -335.951162) (xy 363.032979 -335.944408) (xy 362.984645 -335.931072)
			(xy 362.961428 -335.921604) (xy 362.947855 -335.916345) (xy 362.918952 -335.912981) (xy 362.890271 -335.917894)
			(xy 362.864136 -335.930686) (xy 362.842662 -335.950321) (xy 362.834682 -335.962498) (xy 362.820113 -335.985629)
			(xy 362.78527 -336.02775) (xy 362.744647 -336.064329) (xy 362.699116 -336.09458) (xy 362.649654 -336.117856)
			(xy 362.597323 -336.133656) (xy 362.543244 -336.141642) (xy 362.48858 -336.141642) (xy 362.434501 -336.133656)
			(xy 362.38217 -336.117856) (xy 362.332708 -336.09458) (xy 362.287177 -336.064329) (xy 362.246554 -336.02775)
			(xy 362.211711 -335.985629) (xy 362.197142 -335.962498) (xy 362.189252 -335.95025) (xy 362.167772 -335.930579)
			(xy 362.141609 -335.917777) (xy 362.112896 -335.912888) (xy 362.083971 -335.916311) (xy 362.070396 -335.921604)
			(xy 362.047184 -335.931087) (xy 361.998852 -335.944441) (xy 361.949163 -335.951171) (xy 361.924092 -335.951576)
			(xy 361.896204 -335.951138) (xy 361.841052 -335.942825) (xy 361.787755 -335.926384) (xy 361.737504 -335.902183)
			(xy 361.691421 -335.870763) (xy 361.650535 -335.832826) (xy 361.61576 -335.789219) (xy 361.587873 -335.740916)
			(xy 361.567497 -335.688996) (xy 361.555086 -335.634619) (xy 361.550917 -335.579) (xy 359.039481 -335.579)
			(xy 359.013975 -335.629071) (xy 358.97883 -335.677491) (xy 358.958134 -335.6991) (xy 358.624378 -336.03311)
			(xy 358.534208 -336.03311) (xy 358.472486 -336.094832) (xy 358.462889 -336.105113) (xy 358.449242 -336.129694)
			(xy 358.442816 -336.157065) (xy 358.444096 -336.18515) (xy 358.452987 -336.211822) (xy 358.468814 -336.235059)
			(xy 358.490378 -336.2531) (xy 358.516043 -336.264576) (xy 358.52989 -336.267044) (xy 358.55677 -336.271445)
			(xy 358.609009 -336.286869) (xy 358.658526 -336.30956) (xy 358.704315 -336.339057) (xy 358.745449 -336.374761)
			(xy 358.781091 -336.415949) (xy 358.810519 -336.461783) (xy 358.833134 -336.511334) (xy 358.848479 -336.563596)
			(xy 358.856241 -336.617508) (xy 358.856788 -336.644742) (xy 358.856299 -336.671991) (xy 358.848537 -336.725933)
			(xy 358.833178 -336.778221) (xy 358.810535 -336.827792) (xy 358.781067 -336.873636) (xy 358.745375 -336.914819)
			(xy 358.704186 -336.950504) (xy 358.658337 -336.979964) (xy 358.608763 -337.0026) (xy 358.556472 -337.017951)
			(xy 358.502529 -337.025703) (xy 358.47528 -337.02625) (xy 358.475026 -337.02625) (xy 358.449172 -337.025805)
			(xy 358.39794 -337.018801) (xy 358.372918 -337.01228) (xy 358.35835 -337.009173) (xy 358.32861 -337.010594)
			(xy 358.300543 -337.020532) (xy 358.276536 -337.038143) (xy 358.258629 -337.061931) (xy 358.248345 -337.089872)
			(xy 358.246556 -337.119592) (xy 358.249474 -337.1342) (xy 358.254215 -337.155732) (xy 358.259305 -337.19953)
			(xy 358.259634 -337.221576) (xy 358.259634 -337.227164) (xy 358.258792 -337.254168) (xy 358.250432 -337.307543)
			(xy 358.234625 -337.359205) (xy 358.211687 -337.408119) (xy 358.182078 -337.453308) (xy 358.146388 -337.493868)
			(xy 358.105333 -337.528986) (xy 358.059734 -337.55796) (xy 358.010504 -337.580212) (xy 357.958626 -337.595294)
			(xy 357.905139 -337.602906) (xy 357.878126 -337.603338) (xy 357.852787 -337.602925) (xy 357.802553 -337.596219)
			(xy 357.75365 -337.582922) (xy 357.706937 -337.563268) (xy 357.663238 -337.537603) (xy 357.623321 -337.506378)
			(xy 357.60533 -337.48853) (xy 357.557578 -337.440778) (xy 357.536847 -337.4192) (xy 357.501694 -337.370781)
			(xy 357.474542 -337.317461) (xy 357.456059 -337.260553) (xy 357.446699 -337.201455) (xy 357.446072 -337.171538)
			(xy 357.446072 -336.289904) (xy 357.446678 -336.259988) (xy 357.456064 -336.200895) (xy 357.47456 -336.143992)
			(xy 357.501711 -336.090673) (xy 357.536853 -336.042247) (xy 357.557578 -336.020664) (xy 358.307132 -335.271364)
			(xy 358.307132 -333.714344) (xy 358.285288 -333.6925) (xy 358.268003 -333.674501) (xy 358.238691 -333.634119)
			(xy 358.216046 -333.589653) (xy 358.200625 -333.542196) (xy 358.192806 -333.492913) (xy 358.192324 -333.467964)
			(xy 358.192324 -328.99858) (xy 356.731316 -327.537826) (xy 356.710537 -327.516212) (xy 356.675299 -327.467706)
			(xy 356.648079 -327.414287) (xy 356.629548 -327.357269) (xy 356.620161 -327.298055) (xy 356.619556 -327.268078)
			(xy 356.619556 -326.287892) (xy 350.909128 -326.287892) (xy 350.909128 -335.176368) (xy 357.302308 -335.176368)
			(xy 357.302753 -335.148997) (xy 357.310576 -335.094817) (xy 357.32607 -335.042314) (xy 357.348916 -334.992567)
			(xy 357.378645 -334.946601) (xy 357.396288 -334.92567) (xy 357.405557 -334.914366) (xy 357.417732 -334.8878)
			(xy 357.421899 -334.858876) (xy 357.417718 -334.829953) (xy 357.40553 -334.803393) (xy 357.396288 -334.792066)
			(xy 357.378665 -334.771121) (xy 357.348951 -334.725152) (xy 357.326112 -334.675408) (xy 357.310617 -334.62291)
			(xy 357.302785 -334.568736) (xy 357.302308 -334.541368) (xy 357.302794 -334.514117) (xy 357.31055 -334.460169)
			(xy 357.325905 -334.407874) (xy 357.348547 -334.358297) (xy 357.378013 -334.312447) (xy 357.413704 -334.271256)
			(xy 357.454895 -334.235565) (xy 357.500745 -334.206099) (xy 357.550322 -334.183457) (xy 357.602617 -334.168102)
			(xy 357.656565 -334.160346) (xy 357.711067 -334.160346) (xy 357.765015 -334.168102) (xy 357.81731 -334.183457)
			(xy 357.866887 -334.206099) (xy 357.912737 -334.235565) (xy 357.953928 -334.271256) (xy 357.989619 -334.312447)
			(xy 358.019085 -334.358297) (xy 358.041727 -334.407874) (xy 358.057082 -334.460169) (xy 358.064838 -334.514117)
			(xy 358.065324 -334.541368) (xy 358.064858 -334.568738) (xy 358.057043 -334.622918) (xy 358.041555 -334.675422)
			(xy 358.018713 -334.725169) (xy 357.988986 -334.771135) (xy 357.971344 -334.792066) (xy 357.962142 -334.803418)
			(xy 357.949968 -334.829968) (xy 357.945792 -334.858876) (xy 357.949954 -334.887786) (xy 357.962116 -334.914341)
			(xy 357.971344 -334.92567) (xy 357.98899 -334.946597) (xy 358.018699 -334.992572) (xy 358.041533 -335.042321)
			(xy 358.057023 -335.094822) (xy 358.064851 -335.148999) (xy 358.065324 -335.176368) (xy 358.064838 -335.203619)
			(xy 358.057082 -335.257567) (xy 358.041727 -335.309862) (xy 358.019085 -335.359439) (xy 357.989619 -335.405289)
			(xy 357.953928 -335.44648) (xy 357.912737 -335.482171) (xy 357.866887 -335.511637) (xy 357.81731 -335.534279)
			(xy 357.765015 -335.549634) (xy 357.711067 -335.55739) (xy 357.656565 -335.55739) (xy 357.602617 -335.549634)
			(xy 357.550322 -335.534279) (xy 357.500745 -335.511637) (xy 357.454895 -335.482171) (xy 357.413704 -335.44648)
			(xy 357.378013 -335.405289) (xy 357.348547 -335.359439) (xy 357.325905 -335.309862) (xy 357.31055 -335.257567)
			(xy 357.302794 -335.203619) (xy 357.302308 -335.176368) (xy 350.909128 -335.176368) (xy 350.909128 -335.421224)
			(xy 350.90852 -335.451139) (xy 350.89913 -335.51023) (xy 350.880631 -335.56713) (xy 350.874586 -335.579)
			(xy 353.390417 -335.579) (xy 353.394585 -335.523382) (xy 353.406996 -335.469006) (xy 353.427372 -335.417087)
			(xy 353.455258 -335.368785) (xy 353.490031 -335.325178) (xy 353.530916 -335.287241) (xy 353.576997 -335.255821)
			(xy 353.627247 -335.23162) (xy 353.680542 -335.215178) (xy 353.735693 -335.206862) (xy 353.76358 -335.20634)
			(xy 353.790913 -335.206792) (xy 353.844993 -335.214765) (xy 353.897328 -335.230556) (xy 353.946793 -335.253827)
			(xy 353.992325 -335.284078) (xy 354.032946 -335.320659) (xy 354.067785 -335.362784) (xy 354.08235 -335.385918)
			(xy 354.090244 -335.398163) (xy 354.111724 -335.417832) (xy 354.137885 -335.430633) (xy 354.166597 -335.435523)
			(xy 354.195521 -335.432104) (xy 354.209096 -335.426812) (xy 354.23231 -335.417332) (xy 354.280641 -335.403977)
			(xy 354.330329 -335.397245) (xy 354.3554 -335.39684) (xy 354.380469 -335.397275) (xy 354.430152 -335.40402)
			(xy 354.478486 -335.417348) (xy 354.501704 -335.426812) (xy 354.515304 -335.431992) (xy 354.544193 -335.435371)
			(xy 354.572863 -335.430475) (xy 354.598994 -335.417702) (xy 354.620468 -335.398086) (xy 354.62845 -335.385918)
			(xy 354.643019 -335.362787) (xy 354.677862 -335.320666) (xy 354.718485 -335.284087) (xy 354.764016 -335.253836)
			(xy 354.813478 -335.23056) (xy 354.865809 -335.21476) (xy 354.919888 -335.206774) (xy 354.974552 -335.206774)
			(xy 355.028631 -335.21476) (xy 355.080962 -335.23056) (xy 355.130424 -335.253836) (xy 355.175955 -335.284087)
			(xy 355.216578 -335.320666) (xy 355.251421 -335.362787) (xy 355.26599 -335.385918) (xy 355.273941 -335.398122)
			(xy 355.295405 -335.417791) (xy 355.321551 -335.430597) (xy 355.350249 -335.435498) (xy 355.379163 -335.432094)
			(xy 355.392736 -335.426812) (xy 355.415945 -335.41732) (xy 355.464278 -335.403969) (xy 355.513968 -335.397243)
			(xy 355.53904 -335.39684) (xy 355.56588 -335.397387) (xy 355.619004 -335.405082) (xy 355.670475 -335.420321)
			(xy 355.719225 -335.442789) (xy 355.764247 -335.472021) (xy 355.804608 -335.507411) (xy 355.839472 -335.548227)
			(xy 355.868118 -335.593623) (xy 355.889952 -335.642661) (xy 355.897688 -335.668366) (xy 355.902375 -335.682854)
			(xy 355.91889 -335.708414) (xy 355.9422 -335.727978) (xy 355.970239 -335.739808) (xy 356.000517 -335.742857)
			(xy 356.030351 -335.736853) (xy 356.043992 -335.730088) (xy 356.072132 -335.715442) (xy 356.132086 -335.694719)
			(xy 356.194647 -335.684226) (xy 356.226364 -335.683606) (xy 356.244384 -335.683822) (xy 356.280258 -335.687259)
			(xy 356.297992 -335.690464) (xy 356.313202 -335.69279) (xy 356.343753 -335.689265) (xy 356.371871 -335.676806)
			(xy 356.395007 -335.656544) (xy 356.411064 -335.630314) (xy 356.41534 -335.615534) (xy 356.422702 -335.588479)
			(xy 356.444336 -335.536752) (xy 356.473305 -335.488746) (xy 356.508985 -335.445495) (xy 356.550609 -335.407928)
			(xy 356.597281 -335.376856) (xy 356.647996 -335.352945) (xy 356.701664 -335.336711) (xy 356.757129 -335.328503)
			(xy 356.785164 -335.328006) (xy 356.812417 -335.328489) (xy 356.866368 -335.336241) (xy 356.918666 -335.351593)
			(xy 356.968247 -335.374233) (xy 357.014101 -335.403698) (xy 357.055294 -335.43939) (xy 357.090988 -335.480582)
			(xy 357.120457 -335.526434) (xy 357.143099 -335.576013) (xy 357.158454 -335.628311) (xy 357.16621 -335.682261)
			(xy 357.166672 -335.709514) (xy 357.166157 -335.737087) (xy 357.158216 -335.791658) (xy 357.142501 -335.844517)
			(xy 357.119341 -335.894564) (xy 357.089216 -335.940755) (xy 357.052756 -335.982127) (xy 357.032052 -336.000344)
			(xy 357.021136 -336.010226) (xy 357.005057 -336.034879) (xy 356.99667 -336.063092) (xy 356.996673 -336.092526)
			(xy 357.005064 -336.120738) (xy 357.021148 -336.145388) (xy 357.032052 -336.155284) (xy 357.052774 -336.173483)
			(xy 357.089241 -336.214855) (xy 357.119372 -336.261047) (xy 357.142536 -336.311096) (xy 357.158253 -336.363959)
			(xy 357.166193 -336.418534) (xy 357.166192 -336.473684) (xy 357.158249 -336.528259) (xy 357.14253 -336.581121)
			(xy 357.119363 -336.631169) (xy 357.08923 -336.67736) (xy 357.052761 -336.718729) (xy 357.032052 -336.736944)
			(xy 357.021136 -336.746826) (xy 357.005057 -336.771479) (xy 356.99667 -336.799692) (xy 356.996673 -336.829126)
			(xy 357.005064 -336.857338) (xy 357.021148 -336.881988) (xy 357.032052 -336.891884) (xy 357.052749 -336.910111)
			(xy 357.089222 -336.951475) (xy 357.119358 -336.997661) (xy 357.142526 -337.047706) (xy 357.158245 -337.100567)
			(xy 357.166186 -337.15514) (xy 357.166672 -337.182714) (xy 357.166258 -337.209969) (xy 357.158498 -337.263923)
			(xy 357.143139 -337.316225) (xy 357.120492 -337.365807) (xy 357.091019 -337.411662) (xy 357.05532 -337.452855)
			(xy 357.014122 -337.488549) (xy 356.968263 -337.518016) (xy 356.918678 -337.540656) (xy 356.866375 -337.556009)
			(xy 356.812419 -337.563762) (xy 356.785164 -337.564222) (xy 356.757309 -337.563715) (xy 356.702193 -337.555587)
			(xy 356.648843 -337.539538) (xy 356.598391 -337.515908) (xy 356.551907 -337.485199) (xy 356.510378 -337.448062)
			(xy 356.474685 -337.405286) (xy 356.445586 -337.357779) (xy 356.423697 -337.306547) (xy 356.416102 -337.279742)
			(xy 356.411772 -337.265645) (xy 356.396397 -337.240502) (xy 356.374492 -337.220784) (xy 356.347876 -337.208128)
			(xy 356.318757 -337.203582) (xy 356.304088 -337.205066) (xy 356.291071 -337.206735) (xy 356.264887 -337.208515)
			(xy 356.251764 -337.208622) (xy 356.237615 -337.208532) (xy 356.209392 -337.206495) (xy 356.195376 -337.204558)
			(xy 356.182023 -337.203045) (xy 356.155341 -337.206135) (xy 356.130394 -337.216092) (xy 356.108917 -337.232223)
			(xy 356.092403 -337.253406) (xy 356.082 -337.27817) (xy 356.079806 -337.291426) (xy 356.075714 -337.318579)
			(xy 356.060743 -337.37141) (xy 356.038353 -337.421549) (xy 356.009006 -337.46796) (xy 355.973309 -337.509686)
			(xy 355.932 -337.545862) (xy 355.885931 -337.575744) (xy 355.836054 -337.598712) (xy 355.7834 -337.614293)
			(xy 355.729056 -337.622165) (xy 355.7016 -337.622642) (xy 355.67435 -337.622122) (xy 355.620406 -337.614367)
			(xy 355.568114 -337.599013) (xy 355.518539 -337.576375) (xy 355.47269 -337.546911) (xy 355.4315 -337.511224)
			(xy 355.395809 -337.470037) (xy 355.366342 -337.424191) (xy 355.343699 -337.374618) (xy 355.328341 -337.322328)
			(xy 355.32058 -337.268384) (xy 355.320092 -337.241134) (xy 355.320584 -337.21356) (xy 355.328531 -337.158989)
			(xy 355.344252 -337.10613) (xy 355.367417 -337.056084) (xy 355.397544 -337.009893) (xy 355.434007 -336.968521)
			(xy 355.454712 -336.950304) (xy 355.465574 -336.94037) (xy 355.481645 -336.915729) (xy 355.490031 -336.887531)
			(xy 355.490038 -336.858113) (xy 355.481664 -336.829911) (xy 355.465603 -336.805263) (xy 355.454712 -336.795364)
			(xy 355.433983 -336.777173) (xy 355.397513 -336.7358) (xy 355.367383 -336.689606) (xy 355.34422 -336.639554)
			(xy 355.328508 -336.586688) (xy 355.320574 -336.53211) (xy 355.320092 -336.504534) (xy 355.320528 -336.478032)
			(xy 355.327878 -336.425541) (xy 355.342426 -336.374573) (xy 355.363893 -336.326111) (xy 355.391865 -336.281089)
			(xy 355.408484 -336.26044) (xy 355.417925 -336.248295) (xy 355.429707 -336.219894) (xy 355.432526 -336.189276)
			(xy 355.42613 -336.159201) (xy 355.411094 -336.13238) (xy 355.388774 -336.111232) (xy 355.37521 -336.103976)
			(xy 355.351511 -336.091892) (xy 355.307531 -336.061963) (xy 355.268253 -336.026087) (xy 355.234472 -335.984992)
			(xy 355.22027 -335.962498) (xy 355.212354 -335.950269) (xy 355.19088 -335.930598) (xy 355.164725 -335.917794)
			(xy 355.136018 -335.9129) (xy 355.107098 -335.916315) (xy 355.093524 -335.921604) (xy 355.070308 -335.931079)
			(xy 355.021978 -335.944435) (xy 354.972291 -335.951169) (xy 354.94722 -335.951576) (xy 354.922151 -335.951133)
			(xy 354.872469 -335.944392) (xy 354.824134 -335.931066) (xy 354.800916 -335.921604) (xy 354.787324 -335.916389)
			(xy 354.758423 -335.913003) (xy 354.729739 -335.917897) (xy 354.703596 -335.930674) (xy 354.682112 -335.950299)
			(xy 354.67417 -335.962498) (xy 354.659601 -335.985629) (xy 354.624758 -336.02775) (xy 354.584135 -336.064329)
			(xy 354.538604 -336.09458) (xy 354.489142 -336.117856) (xy 354.436811 -336.133656) (xy 354.382732 -336.141642)
			(xy 354.328068 -336.141642) (xy 354.273989 -336.133656) (xy 354.221658 -336.117856) (xy 354.172196 -336.09458)
			(xy 354.126665 -336.064329) (xy 354.086042 -336.02775) (xy 354.051199 -335.985629) (xy 354.03663 -335.962498)
			(xy 354.028751 -335.950242) (xy 354.007268 -335.93057) (xy 353.981103 -335.91777) (xy 353.952387 -335.912884)
			(xy 353.92346 -335.916309) (xy 353.909884 -335.921604) (xy 353.886673 -335.931091) (xy 353.838341 -335.944443)
			(xy 353.788652 -335.951172) (xy 353.76358 -335.951576) (xy 353.735693 -335.951138) (xy 353.680542 -335.942822)
			(xy 353.627247 -335.92638) (xy 353.576997 -335.902179) (xy 353.530916 -335.870759) (xy 353.490031 -335.832822)
			(xy 353.455258 -335.789215) (xy 353.427372 -335.740913) (xy 353.406996 -335.688994) (xy 353.394585 -335.634618)
			(xy 353.390417 -335.579) (xy 350.874586 -335.579) (xy 350.853477 -335.620446) (xy 350.818333 -335.668869)
			(xy 350.797622 -335.690464) (xy 350.378776 -336.10931) (xy 350.28886 -336.10931) (xy 350.181418 -336.216752)
			(xy 350.235266 -336.2706) (xy 350.260158 -336.267044) (xy 350.273737 -336.265231) (xy 350.301069 -336.263327)
			(xy 350.314768 -336.263234) (xy 350.342021 -336.263695) (xy 350.395973 -336.271449) (xy 350.448273 -336.286802)
			(xy 350.497854 -336.309444) (xy 350.543708 -336.338911) (xy 350.584901 -336.374606) (xy 350.620595 -336.4158)
			(xy 350.650061 -336.461655) (xy 350.672701 -336.511237) (xy 350.688053 -336.563536) (xy 350.695806 -336.617489)
			(xy 350.696276 -336.644742) (xy 350.69582 -336.671233) (xy 350.688486 -336.723705) (xy 350.673965 -336.774658)
			(xy 350.652537 -336.823113) (xy 350.624613 -336.868138) (xy 350.590729 -336.908869) (xy 350.551538 -336.944521)
			(xy 350.507792 -336.974411) (xy 350.460333 -336.997962) (xy 350.410073 -337.014724) (xy 350.357977 -337.024372)
			(xy 350.331532 -337.025996) (xy 350.316375 -337.027608) (xy 350.287989 -337.038678) (xy 350.264128 -337.057623)
			(xy 350.246911 -337.08276) (xy 350.237869 -337.111855) (xy 350.237298 -337.127088) (xy 350.237298 -337.180174)
			(xy 350.194372 -337.2231) (xy 350.193356 -337.242658) (xy 350.191449 -337.270859) (xy 350.18036 -337.326281)
			(xy 350.161218 -337.379461) (xy 350.134442 -337.429237) (xy 350.100617 -337.474519) (xy 350.060483 -337.514317)
			(xy 350.014918 -337.547759) (xy 349.964918 -337.574116) (xy 349.911579 -337.59281) (xy 349.856065 -337.603431)
			(xy 349.82785 -337.605116) (xy 349.812356 -337.605624) (xy 349.786414 -337.605193) (xy 349.735006 -337.598176)
			(xy 349.685022 -337.584265) (xy 349.637381 -337.563715) (xy 349.59296 -337.536904) (xy 349.552578 -337.504327)
			(xy 349.53448 -337.485736) (xy 349.533972 -337.485228) (xy 349.497396 -337.448398) (xy 349.477984 -337.428295)
			(xy 349.444659 -337.383438) (xy 349.418236 -337.334198) (xy 349.399281 -337.28163) (xy 349.393256 -337.254342)
			(xy 349.39097 -337.252056) (xy 349.37364 -337.23405) (xy 349.344246 -337.193637) (xy 349.321537 -337.149123)
			(xy 349.30607 -337.101605) (xy 349.298227 -337.052252) (xy 349.297752 -337.027266) (xy 349.297752 -336.33283)
			(xy 349.298216 -336.307842) (xy 349.30604 -336.258481) (xy 349.321499 -336.210955) (xy 349.344212 -336.166438)
			(xy 349.373618 -336.126028) (xy 349.39097 -336.10804) (xy 349.393256 -336.105754) (xy 349.399281 -336.078467)
			(xy 349.418245 -336.025904) (xy 349.444672 -335.976668) (xy 349.477999 -335.931814) (xy 349.497396 -335.911698)
			(xy 350.14662 -335.262728) (xy 350.14662 -333.726282) (xy 350.137885 -333.714478) (xy 350.122367 -333.689546)
			(xy 350.115632 -333.676498) (xy 350.104948 -333.654232) (xy 350.089817 -333.607221) (xy 350.08211 -333.558442)
			(xy 350.081596 -333.53375) (xy 350.081596 -326.287892) (xy 342.748616 -326.287892) (xy 342.748616 -335.437988)
			(xy 342.74801 -335.467904) (xy 342.738625 -335.526998) (xy 342.72013 -335.583901) (xy 342.692979 -335.63722)
			(xy 342.657836 -335.685646) (xy 342.63711 -335.707228) (xy 342.588793 -335.7555) (xy 345.217421 -335.7555)
			(xy 345.22159 -335.699879) (xy 345.234002 -335.6455) (xy 345.254381 -335.593578) (xy 345.28227 -335.545274)
			(xy 345.317048 -335.501666) (xy 345.357937 -335.463729) (xy 345.404023 -335.432311) (xy 345.454278 -335.408112)
			(xy 345.507578 -335.391674) (xy 345.562733 -335.383363) (xy 345.590622 -335.38287) (xy 345.590876 -335.38287)
			(xy 345.618412 -335.383381) (xy 345.672883 -335.391499) (xy 345.725561 -335.40756) (xy 345.750642 -335.418938)
			(xy 345.763019 -335.424383) (xy 345.789613 -335.429217) (xy 345.816543 -335.426897) (xy 345.841919 -335.417588)
			(xy 345.86396 -335.401941) (xy 345.881119 -335.381056) (xy 345.88704 -335.3689) (xy 345.898378 -335.344653)
			(xy 345.927062 -335.299459) (xy 345.96192 -335.258838) (xy 346.002233 -335.223624) (xy 346.047173 -335.194544)
			(xy 346.095812 -335.172197) (xy 346.14715 -335.157042) (xy 346.200128 -335.149393) (xy 346.226892 -335.148936)
			(xy 346.253364 -335.149401) (xy 346.305773 -335.156901) (xy 346.356596 -335.171737) (xy 346.404809 -335.193611)
			(xy 346.449445 -335.222083) (xy 346.489606 -335.256582) (xy 346.524485 -335.296413) (xy 346.55338 -335.340776)
			(xy 346.564966 -335.364582) (xy 346.571667 -335.377804) (xy 346.5913 -335.399992) (xy 346.616473 -335.415614)
			(xy 346.64507 -335.423359) (xy 346.674687 -335.422574) (xy 346.688918 -335.41843) (xy 346.717263 -335.409661)
			(xy 346.775839 -335.400225) (xy 346.805504 -335.399634) (xy 346.833361 -335.40015) (xy 346.888456 -335.40844)
			(xy 346.915232 -335.416144) (xy 346.929563 -335.419986) (xy 346.959217 -335.420195) (xy 346.987682 -335.411879)
			(xy 347.01256 -335.395739) (xy 347.031755 -335.373135) (xy 347.038168 -335.359756) (xy 347.049483 -335.335288)
			(xy 347.078037 -335.289568) (xy 347.112884 -335.248442) (xy 347.153294 -335.212767) (xy 347.198425 -335.18329)
			(xy 347.247333 -335.160625) (xy 347.298997 -335.145247) (xy 347.352338 -335.137476) (xy 347.37929 -335.136998)
			(xy 347.407178 -335.13746) (xy 347.462333 -335.145772) (xy 347.515632 -335.162211) (xy 347.54503 -335.176368)
			(xy 349.141796 -335.176368) (xy 349.142244 -335.148997) (xy 349.150067 -335.094817) (xy 349.16556 -335.042314)
			(xy 349.188405 -334.992568) (xy 349.218133 -334.946601) (xy 349.235776 -334.92567) (xy 349.245046 -334.914367)
			(xy 349.257222 -334.887801) (xy 349.26139 -334.858876) (xy 349.257208 -334.829953) (xy 349.245019 -334.803393)
			(xy 349.235776 -334.792066) (xy 349.218151 -334.771123) (xy 349.188438 -334.725153) (xy 349.165599 -334.675408)
			(xy 349.150105 -334.62291) (xy 349.142273 -334.568736) (xy 349.141796 -334.541368) (xy 349.142282 -334.514117)
			(xy 349.150038 -334.460169) (xy 349.165393 -334.407874) (xy 349.188035 -334.358297) (xy 349.217501 -334.312447)
			(xy 349.253192 -334.271256) (xy 349.294383 -334.235565) (xy 349.340233 -334.206099) (xy 349.38981 -334.183457)
			(xy 349.442105 -334.168102) (xy 349.496053 -334.160346) (xy 349.550555 -334.160346) (xy 349.604503 -334.168102)
			(xy 349.656798 -334.183457) (xy 349.706375 -334.206099) (xy 349.752225 -334.235565) (xy 349.793416 -334.271256)
			(xy 349.829107 -334.312447) (xy 349.858573 -334.358297) (xy 349.881215 -334.407874) (xy 349.89657 -334.460169)
			(xy 349.904326 -334.514117) (xy 349.904812 -334.541368) (xy 349.904324 -334.568737) (xy 349.896511 -334.622915)
			(xy 349.881027 -334.675418) (xy 349.85819 -334.725165) (xy 349.828471 -334.771133) (xy 349.810832 -334.792066)
			(xy 349.801624 -334.803415) (xy 349.789439 -334.829965) (xy 349.785259 -334.858876) (xy 349.789425 -334.887789)
			(xy 349.801598 -334.914344) (xy 349.810832 -334.92567) (xy 349.828475 -334.946598) (xy 349.858186 -334.992573)
			(xy 349.88102 -335.042321) (xy 349.89651 -335.094823) (xy 349.904338 -335.148999) (xy 349.904812 -335.176368)
			(xy 349.904326 -335.203619) (xy 349.89657 -335.257567) (xy 349.881215 -335.309862) (xy 349.858573 -335.359439)
			(xy 349.829107 -335.405289) (xy 349.793416 -335.44648) (xy 349.752225 -335.482171) (xy 349.706375 -335.511637)
			(xy 349.656798 -335.534279) (xy 349.604503 -335.549634) (xy 349.550555 -335.55739) (xy 349.496053 -335.55739)
			(xy 349.442105 -335.549634) (xy 349.38981 -335.534279) (xy 349.340233 -335.511637) (xy 349.294383 -335.482171)
			(xy 349.253192 -335.44648) (xy 349.217501 -335.405289) (xy 349.188035 -335.359439) (xy 349.165393 -335.309862)
			(xy 349.150038 -335.257567) (xy 349.142282 -335.203619) (xy 349.141796 -335.176368) (xy 347.54503 -335.176368)
			(xy 347.565885 -335.186411) (xy 347.611971 -335.217831) (xy 347.652859 -335.255768) (xy 347.687636 -335.299376)
			(xy 347.715525 -335.34768) (xy 347.735902 -335.399601) (xy 347.748314 -335.453979) (xy 347.752483 -335.5096)
			(xy 347.748314 -335.565221) (xy 347.735902 -335.619599) (xy 347.715525 -335.67152) (xy 347.687636 -335.719824)
			(xy 347.652859 -335.763432) (xy 347.611971 -335.801369) (xy 347.565885 -335.832789) (xy 347.515632 -335.856989)
			(xy 347.462333 -335.873428) (xy 347.407178 -335.88174) (xy 347.37929 -335.882234) (xy 347.351433 -335.88172)
			(xy 347.296338 -335.873428) (xy 347.269562 -335.865724) (xy 347.255229 -335.861894) (xy 347.225578 -335.861687)
			(xy 347.197116 -335.870002) (xy 347.172239 -335.886138) (xy 347.153041 -335.908736) (xy 347.146626 -335.922112)
			(xy 347.135349 -335.946598) (xy 347.106786 -335.992315) (xy 347.071933 -336.033439) (xy 347.031516 -336.069111)
			(xy 346.986381 -336.098585) (xy 346.937469 -336.121247) (xy 346.885801 -336.136624) (xy 346.832457 -336.144393)
			(xy 346.805504 -336.14487) (xy 346.779032 -336.144405) (xy 346.726623 -336.136904) (xy 346.675801 -336.122068)
			(xy 346.627587 -336.100194) (xy 346.582951 -336.071722) (xy 346.54279 -336.037224) (xy 346.507912 -335.997393)
			(xy 346.479016 -335.95303) (xy 346.46743 -335.929224) (xy 346.46073 -335.916001) (xy 346.441097 -335.893812)
			(xy 346.415924 -335.878189) (xy 346.387326 -335.870445) (xy 346.357709 -335.871231) (xy 346.343478 -335.875376)
			(xy 346.315133 -335.884146) (xy 346.256557 -335.893581) (xy 346.226892 -335.894172) (xy 346.226638 -335.894172)
			(xy 346.199102 -335.893661) (xy 346.144631 -335.885544) (xy 346.091952 -335.869482) (xy 346.066872 -335.858104)
			(xy 346.054496 -335.852654) (xy 346.027901 -335.847814) (xy 346.000968 -335.850131) (xy 345.97559 -335.859442)
			(xy 345.953548 -335.875092) (xy 345.936392 -335.895983) (xy 345.930474 -335.908142) (xy 345.919098 -335.93237)
			(xy 345.890422 -335.977566) (xy 345.855571 -336.01819) (xy 345.815263 -336.053406) (xy 345.770329 -336.082489)
			(xy 345.721693 -336.104839) (xy 345.67036 -336.119996) (xy 345.617385 -336.127648) (xy 345.590622 -336.128106)
			(xy 345.562733 -336.127637) (xy 345.507578 -336.119326) (xy 345.454278 -336.102888) (xy 345.404023 -336.078689)
			(xy 345.357937 -336.047271) (xy 345.317048 -336.009334) (xy 345.28227 -335.965726) (xy 345.254381 -335.917422)
			(xy 345.234002 -335.8655) (xy 345.22159 -335.811121) (xy 345.217421 -335.7555) (xy 342.588793 -335.7555)
			(xy 342.365076 -335.979008) (xy 342.250014 -335.979008) (xy 342.152478 -336.076544) (xy 342.142276 -336.087484)
			(xy 342.128154 -336.113837) (xy 342.122265 -336.14315) (xy 342.125114 -336.172912) (xy 342.136457 -336.200576)
			(xy 342.155323 -336.223771) (xy 342.180095 -336.240512) (xy 342.208653 -336.249364) (xy 342.223598 -336.250026)
			(xy 342.238838 -336.249772) (xy 342.266089 -336.25026) (xy 342.320035 -336.258022) (xy 342.372328 -336.273381)
			(xy 342.421903 -336.296025) (xy 342.467751 -336.325494) (xy 342.508939 -336.361188) (xy 342.544628 -336.402379)
			(xy 342.574093 -336.44823) (xy 342.596732 -336.497807) (xy 342.612086 -336.550102) (xy 342.619842 -336.604049)
			(xy 342.619842 -336.658551) (xy 342.612086 -336.712498) (xy 342.596732 -336.764793) (xy 342.574093 -336.81437)
			(xy 342.544628 -336.860221) (xy 342.508939 -336.901412) (xy 342.467751 -336.937106) (xy 342.421903 -336.966575)
			(xy 342.372328 -336.989219) (xy 342.320035 -337.004578) (xy 342.266089 -337.01234) (xy 342.238838 -337.012788)
			(xy 342.210818 -337.012297) (xy 342.155381 -337.004104) (xy 342.101739 -336.987889) (xy 342.051047 -336.964002)
			(xy 342.004394 -336.932955) (xy 341.962786 -336.895417) (xy 341.927116 -336.852195) (xy 341.898154 -336.804221)
			(xy 341.876521 -336.752526) (xy 341.862684 -336.698222) (xy 341.859362 -336.670396) (xy 341.854536 -336.624676)
			(xy 341.789258 -336.624676) (xy 341.776443 -336.621895) (xy 341.750231 -336.622221) (xy 341.724962 -336.629199)
			(xy 341.702296 -336.642369) (xy 341.692738 -336.651346) (xy 341.625936 -336.718148) (xy 341.625936 -336.911188)
			(xy 341.780876 -337.065874) (xy 341.801656 -337.087488) (xy 341.836894 -337.135993) (xy 341.864114 -337.189412)
			(xy 341.882646 -337.24643) (xy 341.892033 -337.305645) (xy 341.892636 -337.335622) (xy 341.892636 -337.352894)
			(xy 341.892151 -337.380146) (xy 341.884395 -337.434096) (xy 341.869041 -337.486393) (xy 341.8464 -337.535973)
			(xy 341.816935 -337.581826) (xy 341.781243 -337.623019) (xy 341.740053 -337.658714) (xy 341.694203 -337.688184)
			(xy 341.644625 -337.710829) (xy 341.592329 -337.726188) (xy 341.53838 -337.733948) (xy 341.511128 -337.734402)
			(xy 341.483145 -337.733906) (xy 341.427779 -337.725723) (xy 341.374202 -337.709543) (xy 341.323562 -337.685712)
			(xy 341.276945 -337.654742) (xy 341.235349 -337.617297) (xy 341.199668 -337.574179) (xy 341.184738 -337.550506)
			(xy 341.181944 -337.545934) (xy 340.974934 -337.338924) (xy 340.954198 -337.317348) (xy 340.919034 -337.268932)
			(xy 340.891871 -337.215613) (xy 340.873378 -337.158704) (xy 340.86401 -337.099603) (xy 340.863428 -337.069684)
			(xy 340.863428 -336.559652) (xy 340.864038 -336.529737) (xy 340.87343 -336.470648) (xy 340.89193 -336.413748)
			(xy 340.919084 -336.360434) (xy 340.954226 -336.312011) (xy 340.974934 -336.290412) (xy 341.986108 -335.279492)
			(xy 341.986108 -334.28051) (xy 341.977472 -334.268826) (xy 341.962332 -334.248024) (xy 341.938268 -334.202551)
			(xy 341.92184 -334.153796) (xy 341.913475 -334.103033) (xy 341.912956 -334.07731) (xy 341.912956 -327.014586)
			(xy 341.912489 -327.004619) (xy 341.904901 -326.986187) (xy 341.890845 -326.972054) (xy 341.872455 -326.964366)
			(xy 341.852522 -326.964291) (xy 341.843106 -326.967596) (xy 341.840566 -326.968612) (xy 341.832819 -326.97249)
			(xy 341.818647 -326.982451) (xy 341.812372 -326.988424) (xy 339.271864 -329.528932) (xy 339.271864 -331.751432)
			(xy 338.489544 -332.533752) (xy 334.562704 -332.533752) (xy 334.562704 -335.176368) (xy 340.981284 -335.176368)
			(xy 340.981711 -335.148996) (xy 340.989535 -335.094815) (xy 341.005032 -335.04231) (xy 341.027883 -334.992564)
			(xy 341.057618 -334.9466) (xy 341.075264 -334.92567) (xy 341.084535 -334.914367) (xy 341.096713 -334.887801)
			(xy 341.100881 -334.858876) (xy 341.096699 -334.829952) (xy 341.084508 -334.803392) (xy 341.075264 -334.792066)
			(xy 341.057637 -334.771124) (xy 341.027924 -334.725154) (xy 341.005087 -334.675409) (xy 340.989593 -334.62291)
			(xy 340.98176 -334.568736) (xy 340.981284 -334.541368) (xy 340.98177 -334.514117) (xy 340.989526 -334.460169)
			(xy 341.004881 -334.407874) (xy 341.027523 -334.358297) (xy 341.056989 -334.312447) (xy 341.09268 -334.271256)
			(xy 341.133871 -334.235565) (xy 341.179721 -334.206099) (xy 341.229298 -334.183457) (xy 341.281593 -334.168102)
			(xy 341.335541 -334.160346) (xy 341.390043 -334.160346) (xy 341.443991 -334.168102) (xy 341.496286 -334.183457)
			(xy 341.545863 -334.206099) (xy 341.591713 -334.235565) (xy 341.632904 -334.271256) (xy 341.668595 -334.312447)
			(xy 341.698061 -334.358297) (xy 341.720703 -334.407874) (xy 341.736058 -334.460169) (xy 341.743814 -334.514117)
			(xy 341.7443 -334.541368) (xy 341.743815 -334.568738) (xy 341.736002 -334.622916) (xy 341.720517 -334.675419)
			(xy 341.69768 -334.725166) (xy 341.667959 -334.771134) (xy 341.65032 -334.792066) (xy 341.641113 -334.803416)
			(xy 341.628929 -334.829965) (xy 341.62475 -334.858876) (xy 341.628916 -334.887788) (xy 341.641086 -334.914343)
			(xy 341.65032 -334.92567) (xy 341.667962 -334.9466) (xy 341.697672 -334.992574) (xy 341.720508 -335.042322)
			(xy 341.735998 -335.094823) (xy 341.743826 -335.148999) (xy 341.7443 -335.176368) (xy 341.743814 -335.203619)
			(xy 341.736058 -335.257567) (xy 341.720703 -335.309862) (xy 341.698061 -335.359439) (xy 341.668595 -335.405289)
			(xy 341.632904 -335.44648) (xy 341.591713 -335.482171) (xy 341.545863 -335.511637) (xy 341.496286 -335.534279)
			(xy 341.443991 -335.549634) (xy 341.390043 -335.55739) (xy 341.335541 -335.55739) (xy 341.281593 -335.549634)
			(xy 341.229298 -335.534279) (xy 341.179721 -335.511637) (xy 341.133871 -335.482171) (xy 341.09268 -335.44648)
			(xy 341.056989 -335.405289) (xy 341.027523 -335.359439) (xy 341.004881 -335.309862) (xy 340.989526 -335.257567)
			(xy 340.98177 -335.203619) (xy 340.981284 -335.176368) (xy 334.562704 -335.176368) (xy 334.562704 -338.238338)
			(xy 342.578944 -338.238338) (xy 342.579509 -338.20865) (xy 342.588703 -338.149991) (xy 342.606875 -338.093464)
			(xy 342.633587 -338.040436) (xy 342.668192 -337.992187) (xy 342.709855 -337.949883) (xy 342.733376 -337.93176)
			(xy 342.74396 -337.923305) (xy 342.760672 -337.902001) (xy 342.771195 -337.877053) (xy 342.77479 -337.850216)
			(xy 342.771204 -337.823377) (xy 342.760688 -337.798426) (xy 342.743982 -337.777116) (xy 342.733376 -337.768692)
			(xy 342.709857 -337.750567) (xy 342.668198 -337.70826) (xy 342.633595 -337.660011) (xy 342.606884 -337.606984)
			(xy 342.588709 -337.550459) (xy 342.57951 -337.491801) (xy 342.578944 -337.462114) (xy 342.57943 -337.434863)
			(xy 342.587186 -337.380915) (xy 342.602541 -337.32862) (xy 342.625183 -337.279043) (xy 342.654649 -337.233193)
			(xy 342.69034 -337.192002) (xy 342.731531 -337.156311) (xy 342.777381 -337.126845) (xy 342.826958 -337.104203)
			(xy 342.879253 -337.088848) (xy 342.933201 -337.081092) (xy 342.987703 -337.081092) (xy 343.041651 -337.088848)
			(xy 343.093946 -337.104203) (xy 343.143523 -337.126845) (xy 343.189373 -337.156311) (xy 343.230564 -337.192002)
			(xy 343.266255 -337.233193) (xy 343.295721 -337.279043) (xy 343.318363 -337.32862) (xy 343.333718 -337.380915)
			(xy 343.341474 -337.434863) (xy 343.34196 -337.462114) (xy 343.341431 -337.491803) (xy 343.332229 -337.550464)
			(xy 343.31405 -337.606991) (xy 343.287332 -337.660019) (xy 343.25272 -337.708267) (xy 343.211052 -337.75057)
			(xy 343.187528 -337.768692) (xy 343.176892 -337.777086) (xy 343.160179 -337.798404) (xy 343.149658 -337.823366)
			(xy 343.14607 -337.850216) (xy 343.149666 -337.877064) (xy 343.160195 -337.902023) (xy 343.176914 -337.923336)
			(xy 343.187528 -337.93176) (xy 343.211073 -337.949853) (xy 343.25273 -337.992167) (xy 343.28733 -338.040423)
			(xy 343.314037 -338.093456) (xy 343.332205 -338.149986) (xy 343.341398 -338.208649) (xy 343.34196 -338.238338)
			(xy 343.341474 -338.265589) (xy 343.333718 -338.319537) (xy 343.318363 -338.371832) (xy 343.295721 -338.421409)
			(xy 343.266255 -338.467259) (xy 343.230564 -338.50845) (xy 343.189373 -338.544141) (xy 343.143523 -338.573607)
			(xy 343.093946 -338.596249) (xy 343.041651 -338.611604) (xy 342.987703 -338.61936) (xy 342.933201 -338.61936)
			(xy 342.879253 -338.611604) (xy 342.826958 -338.596249) (xy 342.777381 -338.573607) (xy 342.731531 -338.544141)
			(xy 342.69034 -338.50845) (xy 342.654649 -338.467259) (xy 342.625183 -338.421409) (xy 342.602541 -338.371832)
			(xy 342.587186 -338.319537) (xy 342.57943 -338.265589) (xy 342.578944 -338.238338) (xy 334.562704 -338.238338)
			(xy 334.562704 -338.760054) (xy 334.562094 -338.789969) (xy 334.552701 -338.849059) (xy 334.534202 -338.905958)
			(xy 334.507049 -338.959274) (xy 334.485332 -338.9892) (xy 337.069421 -338.9892) (xy 337.073589 -338.933585)
			(xy 337.085998 -338.879212) (xy 337.106372 -338.827295) (xy 337.134256 -338.778995) (xy 337.169027 -338.73539)
			(xy 337.209907 -338.697453) (xy 337.255985 -338.666033) (xy 337.306231 -338.64183) (xy 337.359523 -338.625386)
			(xy 337.41467 -338.617068) (xy 337.442556 -338.616544) (xy 337.469888 -338.617013) (xy 337.523968 -338.624982)
			(xy 337.576303 -338.64077) (xy 337.625767 -338.664039) (xy 337.6713 -338.694287) (xy 337.711922 -338.730866)
			(xy 337.746761 -338.772989) (xy 337.761326 -338.796122) (xy 337.769241 -338.808351) (xy 337.790716 -338.82802)
			(xy 337.816871 -338.840823) (xy 337.845578 -338.845717) (xy 337.874498 -338.842304) (xy 337.888072 -338.837016)
			(xy 337.911288 -338.827544) (xy 337.959618 -338.814186) (xy 338.009305 -338.807451) (xy 338.034376 -338.807044)
			(xy 338.059446 -338.807454) (xy 338.109129 -338.814209) (xy 338.157463 -338.827547) (xy 338.18068 -338.837016)
			(xy 338.194253 -338.842275) (xy 338.223156 -338.845636) (xy 338.251835 -338.840723) (xy 338.27797 -338.827931)
			(xy 338.299445 -338.808297) (xy 338.307426 -338.796122) (xy 338.321995 -338.772991) (xy 338.356838 -338.73087)
			(xy 338.397461 -338.694291) (xy 338.442992 -338.66404) (xy 338.492454 -338.640764) (xy 338.544785 -338.624964)
			(xy 338.598864 -338.616978) (xy 338.653528 -338.616978) (xy 338.707607 -338.624964) (xy 338.759938 -338.640764)
			(xy 338.8094 -338.66404) (xy 338.854931 -338.694291) (xy 338.895554 -338.73087) (xy 338.930397 -338.772991)
			(xy 338.944966 -338.796122) (xy 338.952843 -338.808379) (xy 338.974328 -338.828047) (xy 339.000494 -338.840846)
			(xy 339.029209 -338.845733) (xy 339.058136 -338.84231) (xy 339.071712 -338.837016) (xy 339.094924 -338.827531)
			(xy 339.143256 -338.814178) (xy 339.192945 -338.807448) (xy 339.218016 -338.807044) (xy 339.245655 -338.807541)
			(xy 339.300322 -338.815736) (xy 339.35318 -338.831914) (xy 339.40307 -338.85572) (xy 339.448896 -338.886633)
			(xy 339.489656 -338.923974) (xy 339.524454 -338.966925) (xy 339.552528 -339.014544) (xy 339.573262 -339.065786)
			(xy 339.58022 -339.09254) (xy 339.583825 -339.105648) (xy 339.596965 -339.129436) (xy 339.615914 -339.148918)
			(xy 339.639329 -339.162712) (xy 339.665554 -339.169842) (xy 339.69273 -339.169804) (xy 339.718934 -339.1626)
			(xy 339.730842 -339.15604) (xy 339.752985 -339.143402) (xy 339.799938 -339.123527) (xy 339.849122 -339.110092)
			(xy 339.899659 -339.103338) (xy 339.925152 -339.102954) (xy 339.93201 -339.102954) (xy 339.947094 -339.102679)
			(xy 339.976082 -339.094373) (xy 340.001392 -339.07798) (xy 340.020827 -339.054924) (xy 340.032701 -339.027205)
			(xy 340.03488 -339.012276) (xy 340.038284 -338.984522) (xy 340.052283 -338.930385) (xy 340.07403 -338.878869)
			(xy 340.103059 -338.831077) (xy 340.13875 -338.788031) (xy 340.180338 -338.750652) (xy 340.226935 -338.71974)
			(xy 340.277543 -338.695956) (xy 340.331079 -338.67981) (xy 340.386397 -338.671646) (xy 340.414356 -338.671154)
			(xy 340.441606 -338.671696) (xy 340.495552 -338.679446) (xy 340.547846 -338.694795) (xy 340.597424 -338.717429)
			(xy 340.643275 -338.746889) (xy 340.684467 -338.782575) (xy 340.720162 -338.823759) (xy 340.749631 -338.869604)
			(xy 340.772277 -338.919177) (xy 340.787636 -338.971468) (xy 340.795398 -339.025412) (xy 340.795864 -339.052662)
			(xy 340.795316 -339.082032) (xy 340.786317 -339.14008) (xy 340.768526 -339.196061) (xy 340.742363 -339.248654)
			(xy 340.708447 -339.296614) (xy 340.66758 -339.338808) (xy 340.64448 -339.356954) (xy 340.633399 -339.366027)
			(xy 340.616251 -339.388944) (xy 340.606145 -339.415722) (xy 340.603874 -339.444253) (xy 340.609619 -339.472293)
			(xy 340.622926 -339.497633) (xy 340.642749 -339.518279) (xy 340.654894 -339.525864) (xy 340.679326 -339.540649)
			(xy 340.723967 -339.576255) (xy 340.762805 -339.618116) (xy 340.794972 -339.665295) (xy 340.819752 -339.716741)
			(xy 340.836589 -339.771304) (xy 340.845109 -339.827767) (xy 340.845648 -339.856318) (xy 340.845255 -339.882212)
			(xy 340.838252 -339.933526) (xy 340.824365 -339.983418) (xy 340.803849 -340.03097) (xy 340.777082 -340.075305)
			(xy 340.744557 -340.115607) (xy 340.726014 -340.133686) (xy 340.715911 -340.143825) (xy 340.701296 -340.168419)
			(xy 340.694088 -340.196105) (xy 340.694855 -340.224704) (xy 340.703535 -340.251965) (xy 340.719447 -340.275741)
			(xy 340.730078 -340.285324) (xy 340.750901 -340.30352) (xy 340.787573 -340.344907) (xy 340.817878 -340.39116)
			(xy 340.841179 -340.441307) (xy 340.856987 -340.494296) (xy 340.864971 -340.549014) (xy 340.86546 -340.576662)
			(xy 340.865009 -340.603916) (xy 340.857256 -340.65787) (xy 340.841903 -340.710171) (xy 340.819261 -340.759754)
			(xy 340.789792 -340.80561) (xy 340.754097 -340.846804) (xy 340.712902 -340.882498) (xy 340.667045 -340.911966)
			(xy 340.617462 -340.934606) (xy 340.56516 -340.949958) (xy 340.511206 -340.95771) (xy 340.483952 -340.95817)
			(xy 340.454875 -340.957639) (xy 340.397395 -340.948821) (xy 340.341918 -340.93138) (xy 340.289732 -340.905722)
			(xy 340.242044 -340.872441) (xy 340.19996 -340.832307) (xy 340.164454 -340.786251) (xy 340.136351 -340.735339)
			(xy 340.125812 -340.708234) (xy 340.120356 -340.694656) (xy 340.102875 -340.671198) (xy 340.07946 -340.653661)
			(xy 340.052032 -340.643485) (xy 340.022844 -340.641505) (xy 340.008464 -340.644226) (xy 339.988029 -340.648495)
			(xy 339.946534 -340.653076) (xy 339.92566 -340.65337) (xy 339.925152 -340.65337) (xy 339.910936 -340.653208)
			(xy 339.882586 -340.65105) (xy 339.86851 -340.649052) (xy 339.853186 -340.647282) (xy 339.822729 -340.652112)
			(xy 339.795094 -340.665797) (xy 339.772792 -340.687094) (xy 339.757848 -340.714069) (xy 339.75421 -340.729062)
			(xy 339.747713 -340.757293) (xy 339.727473 -340.811567) (xy 339.699262 -340.862158) (xy 339.663727 -340.907903)
			(xy 339.621687 -340.947751) (xy 339.574106 -340.980787) (xy 339.522078 -341.006251) (xy 339.466799 -341.023558)
			(xy 339.409539 -341.03231) (xy 339.380576 -341.032846) (xy 339.353326 -341.032345) (xy 339.299381 -341.024586)
			(xy 339.247089 -341.00923) (xy 339.197514 -340.986588) (xy 339.151665 -340.957123) (xy 339.110476 -340.921434)
			(xy 339.074785 -340.880246) (xy 339.045318 -340.834399) (xy 339.022675 -340.784825) (xy 339.007317 -340.732533)
			(xy 338.999556 -340.678588) (xy 338.999068 -340.651338) (xy 338.999571 -340.623765) (xy 339.007517 -340.569194)
			(xy 339.023236 -340.516336) (xy 339.046399 -340.46629) (xy 339.076524 -340.420099) (xy 339.112984 -340.378726)
			(xy 339.133688 -340.360508) (xy 339.144548 -340.350571) (xy 339.160623 -340.325932) (xy 339.169012 -340.297734)
			(xy 339.169019 -340.268315) (xy 339.160644 -340.240113) (xy 339.14458 -340.215466) (xy 339.133688 -340.205568)
			(xy 339.112956 -340.18738) (xy 339.076488 -340.146006) (xy 339.046358 -340.099811) (xy 339.023196 -340.049759)
			(xy 339.007484 -339.996892) (xy 338.99955 -339.942314) (xy 338.999068 -339.914738) (xy 338.999512 -339.888237)
			(xy 339.006861 -339.835745) (xy 339.021408 -339.784778) (xy 339.042873 -339.736316) (xy 339.070842 -339.691293)
			(xy 339.08746 -339.670644) (xy 339.096904 -339.6585) (xy 339.10869 -339.630099) (xy 339.111512 -339.599479)
			(xy 339.105115 -339.569402) (xy 339.090076 -339.542581) (xy 339.067752 -339.521435) (xy 339.054186 -339.51418)
			(xy 339.0305 -339.502071) (xy 338.986517 -339.472151) (xy 338.947235 -339.436283) (xy 338.91345 -339.395194)
			(xy 338.899246 -339.372702) (xy 338.891351 -339.360457) (xy 338.869873 -339.340786) (xy 338.843711 -339.327983)
			(xy 338.814999 -339.323094) (xy 338.786075 -339.326515) (xy 338.7725 -339.331808) (xy 338.749287 -339.34129)
			(xy 338.700956 -339.354644) (xy 338.651267 -339.361375) (xy 338.626196 -339.36178) (xy 338.601127 -339.361345)
			(xy 338.551444 -339.3546) (xy 338.50311 -339.341272) (xy 338.479892 -339.331808) (xy 338.466296 -339.326615)
			(xy 338.437405 -339.323236) (xy 338.408732 -339.328134) (xy 338.3826 -339.340911) (xy 338.361126 -339.360532)
			(xy 338.353146 -339.372702) (xy 338.338577 -339.395833) (xy 338.303734 -339.437954) (xy 338.263111 -339.474533)
			(xy 338.21758 -339.504784) (xy 338.168118 -339.52806) (xy 338.115787 -339.54386) (xy 338.061708 -339.551846)
			(xy 338.007044 -339.551846) (xy 337.952965 -339.54386) (xy 337.900634 -339.52806) (xy 337.851172 -339.504784)
			(xy 337.805641 -339.474533) (xy 337.765018 -339.437954) (xy 337.730175 -339.395833) (xy 337.715606 -339.372702)
			(xy 337.707654 -339.360498) (xy 337.686191 -339.340827) (xy 337.660045 -339.328019) (xy 337.631347 -339.323119)
			(xy 337.602432 -339.326524) (xy 337.58886 -339.331808) (xy 337.565652 -339.341303) (xy 337.517318 -339.354652)
			(xy 337.467628 -339.361378) (xy 337.442556 -339.36178) (xy 337.41467 -339.361332) (xy 337.359523 -339.353014)
			(xy 337.306231 -339.33657) (xy 337.255985 -339.312367) (xy 337.209907 -339.280947) (xy 337.169027 -339.24301)
			(xy 337.134256 -339.199405) (xy 337.106372 -339.151105) (xy 337.085998 -339.099188) (xy 337.073589 -339.044815)
			(xy 337.069421 -338.9892) (xy 334.485332 -338.9892) (xy 334.471908 -339.007698) (xy 334.451198 -339.029294)
			(xy 334.11033 -339.370162) (xy 334.020414 -339.370162) (xy 333.88935 -339.501226) (xy 333.880008 -339.511234)
			(xy 333.866541 -339.535058) (xy 333.859892 -339.561605) (xy 333.860537 -339.588965) (xy 333.868432 -339.615169)
			(xy 333.883006 -339.638332) (xy 333.903214 -339.656788) (xy 333.927599 -339.669209) (xy 333.954409 -339.674702)
			(xy 333.96809 -339.6742) (xy 333.993744 -339.673438) (xy 334.020991 -339.673927) (xy 334.074928 -339.681688)
			(xy 334.127212 -339.697046) (xy 334.176779 -339.719688) (xy 334.222619 -339.749153) (xy 334.263799 -339.784842)
			(xy 334.299482 -339.826028) (xy 334.32894 -339.871872) (xy 334.351574 -339.921442) (xy 334.366924 -339.973729)
			(xy 334.374677 -340.027667) (xy 334.374675 -340.082161) (xy 334.366918 -340.136099) (xy 334.351564 -340.188384)
			(xy 334.328926 -340.237953) (xy 334.299465 -340.283795) (xy 334.263779 -340.324978) (xy 334.222596 -340.360664)
			(xy 334.176754 -340.390126) (xy 334.127186 -340.412764) (xy 334.074901 -340.428118) (xy 334.020963 -340.435875)
			(xy 333.966469 -340.435877) (xy 333.912531 -340.428125) (xy 333.860244 -340.412775) (xy 333.810674 -340.390141)
			(xy 333.764829 -340.360683) (xy 333.723643 -340.325001) (xy 333.687954 -340.283821) (xy 333.658489 -340.237981)
			(xy 333.635847 -340.188414) (xy 333.620489 -340.13613) (xy 333.612727 -340.082193) (xy 333.612236 -340.054946)
			(xy 333.612998 -340.029292) (xy 333.613483 -340.015604) (xy 333.608009 -339.988777) (xy 333.595597 -339.964372)
			(xy 333.577141 -339.944148) (xy 333.553971 -339.929561) (xy 333.527756 -339.921662) (xy 333.500384 -339.92102)
			(xy 333.473827 -339.927682) (xy 333.449998 -339.941167) (xy 333.440024 -339.950552) (xy 333.315564 -340.075012)
			(xy 333.315564 -340.404196) (xy 333.379064 -340.46795) (xy 333.379064 -340.529672) (xy 333.488284 -340.638892)
			(xy 333.502254 -340.642448) (xy 333.529663 -340.649542) (xy 333.582165 -340.670726) (xy 333.630957 -340.699443)
			(xy 333.674963 -340.735062) (xy 333.713216 -340.776799) (xy 333.744874 -340.823735) (xy 333.769241 -340.874839)
			(xy 333.78578 -340.928984) (xy 333.794127 -340.98498) (xy 333.794608 -341.013288) (xy 333.79407 -341.041818)
			(xy 333.785563 -341.098241) (xy 333.768751 -341.152769) (xy 333.74401 -341.204187) (xy 333.71189 -341.251349)
			(xy 333.673107 -341.293204) (xy 333.628526 -341.328819) (xy 333.579139 -341.357401) (xy 333.5528 -341.36838)
			(xy 333.52831 -341.385365) (xy 333.475158 -341.41232) (xy 333.418455 -341.430663) (xy 333.359586 -341.439947)
			(xy 333.329788 -341.440516) (xy 333.329026 -341.440516) (xy 333.299084 -341.439926) (xy 333.239937 -341.43056)
			(xy 333.182979 -341.412072) (xy 333.129608 -341.384913) (xy 333.081134 -341.349751) (xy 333.059532 -341.32901)
			(xy 332.727808 -340.997286) (xy 332.707026 -340.975673) (xy 332.671781 -340.927169) (xy 332.644554 -340.873751)
			(xy 332.626014 -340.816732) (xy 332.616617 -340.757516) (xy 332.616048 -340.727538) (xy 332.616048 -339.94344)
			(xy 332.616603 -339.913459) (xy 332.625981 -339.854234) (xy 332.644511 -339.797206) (xy 332.671739 -339.743781)
			(xy 332.706991 -339.695276) (xy 332.727808 -339.673692) (xy 333.260192 -339.141308) (xy 333.270166 -339.130688)
			(xy 333.284134 -339.105133) (xy 333.290326 -339.076676) (xy 333.288239 -339.047628) (xy 333.278042 -339.020348)
			(xy 333.260565 -338.997053) (xy 333.237225 -338.979634) (xy 333.20992 -338.969506) (xy 333.195422 -338.96808)
			(xy 333.16849 -338.967137) (xy 333.115281 -338.958605) (xy 333.063802 -338.94267) (xy 333.015078 -338.919647)
			(xy 332.97008 -338.889996) (xy 332.929703 -338.854307) (xy 332.894751 -338.813291) (xy 332.865919 -338.767763)
			(xy 332.843783 -338.718631) (xy 332.828782 -338.666872) (xy 332.821215 -338.613517) (xy 332.820772 -338.586572)
			(xy 332.821259 -338.559004) (xy 332.829198 -338.504442) (xy 332.844906 -338.45159) (xy 332.868056 -338.401549)
			(xy 332.898167 -338.35536) (xy 332.916022 -338.33435) (xy 332.924772 -338.323158) (xy 332.936295 -338.297202)
			(xy 332.940233 -338.269078) (xy 332.936283 -338.240956) (xy 332.924749 -338.215006) (xy 332.916022 -338.203794)
			(xy 332.898159 -338.182788) (xy 332.86804 -338.136602) (xy 332.844884 -338.086561) (xy 332.829175 -338.033707)
			(xy 332.82124 -337.979142) (xy 332.820772 -337.951572) (xy 332.821258 -337.924321) (xy 332.829014 -337.870373)
			(xy 332.844369 -337.818078) (xy 332.867011 -337.768501) (xy 332.896477 -337.722651) (xy 332.932168 -337.68146)
			(xy 332.973359 -337.645769) (xy 333.019209 -337.616303) (xy 333.068786 -337.593661) (xy 333.121081 -337.578306)
			(xy 333.175029 -337.57055) (xy 333.229531 -337.57055) (xy 333.283479 -337.578306) (xy 333.335774 -337.593661)
			(xy 333.385351 -337.616303) (xy 333.431201 -337.645769) (xy 333.472392 -337.68146) (xy 333.508083 -337.722651)
			(xy 333.537549 -337.768501) (xy 333.560191 -337.818078) (xy 333.575546 -337.870373) (xy 333.583302 -337.924321)
			(xy 333.583788 -337.951572) (xy 333.583305 -337.979141) (xy 333.575373 -338.033707) (xy 333.559669 -338.086562)
			(xy 333.536522 -338.136607) (xy 333.506414 -338.1828) (xy 333.488538 -338.203794) (xy 333.479776 -338.214985)
			(xy 333.468231 -338.240944) (xy 333.464277 -338.269078) (xy 333.468219 -338.297214) (xy 333.479753 -338.323179)
			(xy 333.488538 -338.33435) (xy 333.505966 -338.354825) (xy 333.5355 -338.399757) (xy 333.55844 -338.448387)
			(xy 333.574331 -338.499754) (xy 333.58286 -338.552842) (xy 333.583788 -338.579714) (xy 333.585278 -338.594113)
			(xy 333.595259 -338.62127) (xy 333.612453 -338.64454) (xy 333.635481 -338.662057) (xy 333.662497 -338.672415)
			(xy 333.691333 -338.674786) (xy 333.719677 -338.668977) (xy 333.745256 -338.655456) (xy 333.756 -338.645754)
			(xy 333.800196 -338.601558) (xy 333.800196 -332.533752) (xy 321.725036 -332.533752) (xy 318.70142 -335.557368)
			(xy 318.454532 -336.153252) (xy 318.454532 -338.645246) (xy 318.48425 -338.652358) (xy 318.510554 -338.658405)
			(xy 318.561086 -338.677366) (xy 318.608177 -338.703735) (xy 318.650749 -338.73691) (xy 318.687827 -338.776129)
			(xy 318.718561 -338.820495) (xy 318.742248 -338.868991) (xy 318.758345 -338.920506) (xy 318.766484 -338.97386)
			(xy 318.766952 -339.000846) (xy 318.766473 -339.027297) (xy 318.758656 -339.079618) (xy 318.743185 -339.130207)
			(xy 318.720401 -339.177951) (xy 318.690806 -339.2218) (xy 318.65505 -339.260789) (xy 318.61392 -339.29406)
			(xy 318.568321 -339.32088) (xy 318.519257 -339.340661) (xy 318.493648 -339.347302) (xy 318.454532 -339.356446)
			(xy 318.454532 -340.94928) (xy 319.153794 -341.648542) (xy 334.418432 -341.648542) (xy 334.419005 -341.618854)
			(xy 334.428198 -341.560196) (xy 334.446369 -341.50367) (xy 334.473079 -341.450642) (xy 334.507682 -341.402392)
			(xy 334.549344 -341.360088) (xy 334.572864 -341.341964) (xy 334.583445 -341.333505) (xy 334.600159 -341.312203)
			(xy 334.610684 -341.287255) (xy 334.61428 -341.260418) (xy 334.610693 -341.23358) (xy 334.600177 -341.208628)
			(xy 334.583471 -341.18732) (xy 334.572864 -341.178896) (xy 334.549344 -341.160772) (xy 334.507686 -341.118465)
			(xy 334.473083 -341.070215) (xy 334.446373 -341.017188) (xy 334.428198 -340.960663) (xy 334.418998 -340.902005)
			(xy 334.418432 -340.872318) (xy 334.418918 -340.845067) (xy 334.426674 -340.791119) (xy 334.442029 -340.738824)
			(xy 334.464671 -340.689247) (xy 334.494137 -340.643397) (xy 334.529828 -340.602206) (xy 334.571019 -340.566515)
			(xy 334.616869 -340.537049) (xy 334.666446 -340.514407) (xy 334.718741 -340.499052) (xy 334.772689 -340.491296)
			(xy 334.827191 -340.491296) (xy 334.881139 -340.499052) (xy 334.933434 -340.514407) (xy 334.983011 -340.537049)
			(xy 335.028861 -340.566515) (xy 335.070052 -340.602206) (xy 335.105743 -340.643397) (xy 335.135209 -340.689247)
			(xy 335.157851 -340.738824) (xy 335.173206 -340.791119) (xy 335.180962 -340.845067) (xy 335.181448 -340.872318)
			(xy 335.180927 -340.902008) (xy 335.171724 -340.960669) (xy 335.153543 -341.017197) (xy 335.126824 -341.070225)
			(xy 335.114749 -341.087057) (xy 335.434825 -341.087057) (xy 335.434825 -341.032543) (xy 335.442584 -340.978584)
			(xy 335.457943 -340.926279) (xy 335.48059 -340.876692) (xy 335.510064 -340.830834) (xy 335.545765 -340.789637)
			(xy 335.586966 -340.75394) (xy 335.632828 -340.724471) (xy 335.682417 -340.701829) (xy 335.734724 -340.686475)
			(xy 335.788683 -340.678722) (xy 335.81594 -340.678262) (xy 335.816194 -340.678262) (xy 335.841398 -340.678661)
			(xy 335.891366 -340.6853) (xy 335.94002 -340.698477) (xy 335.98651 -340.71796) (xy 336.008472 -340.730332)
			(xy 336.021462 -340.737322) (xy 336.050089 -340.744366) (xy 336.079535 -340.742932) (xy 336.107342 -340.733139)
			(xy 336.131189 -340.715805) (xy 336.149085 -340.692377) (xy 336.154776 -340.67877) (xy 336.16546 -340.651988)
			(xy 336.19375 -340.601747) (xy 336.229282 -340.556338) (xy 336.271246 -340.516797) (xy 336.318685 -340.484024)
			(xy 336.370517 -340.458767) (xy 336.425562 -340.441602) (xy 336.482563 -340.432919) (xy 336.511392 -340.43239)
			(xy 336.538645 -340.432863) (xy 336.592595 -340.440619) (xy 336.644893 -340.455974) (xy 336.694473 -340.478615)
			(xy 336.740326 -340.508082) (xy 336.781518 -340.543775) (xy 336.817212 -340.584966) (xy 336.84668 -340.630819)
			(xy 336.869323 -340.680398) (xy 336.884679 -340.732695) (xy 336.892437 -340.786645) (xy 336.8929 -340.813898)
			(xy 336.8929 -340.814152) (xy 336.89233 -340.843991) (xy 336.883011 -340.902937) (xy 336.874358 -340.9315)
			(xy 336.870419 -340.945432) (xy 336.869498 -340.974349) (xy 336.876747 -341.002357) (xy 336.89158 -341.027197)
			(xy 336.9128 -341.046861) (xy 336.938695 -341.059765) (xy 336.952844 -341.062818) (xy 336.978919 -341.067975)
			(xy 337.029423 -341.084548) (xy 337.077136 -341.107974) (xy 337.121134 -341.137797) (xy 337.160564 -341.173442)
			(xy 337.194662 -341.214216) (xy 337.222769 -341.25933) (xy 337.244338 -341.30791) (xy 337.258953 -341.359015)
			(xy 337.26633 -341.411653) (xy 337.266788 -341.43823) (xy 337.265518 -341.469218) (xy 337.263486 -341.49284)
			(xy 339.170264 -343.399364) (xy 340.78418 -343.399364) (xy 340.806675 -343.399953) (xy 340.850789 -343.408801)
			(xy 340.89233 -343.426083) (xy 340.929703 -343.451134) (xy 340.945978 -343.466674) (xy 342.199214 -344.71991)
			(xy 343.394284 -344.71991) (xy 343.394284 -342.82253) (xy 343.394815 -342.800046) (xy 343.403613 -342.755945)
			(xy 343.420838 -342.714405) (xy 343.445829 -342.677019) (xy 343.46134 -342.660732) (xy 346.010484 -340.111588)
			(xy 346.010484 -338.933028) (xy 345.34602 -338.268818) (xy 345.309952 -338.303108) (xy 345.288518 -338.322944)
			(xy 345.240726 -338.356506) (xy 345.18838 -338.3824) (xy 345.132703 -338.40002) (xy 345.074991 -338.408957)
			(xy 345.045792 -338.409534) (xy 345.018542 -338.40903) (xy 344.964596 -338.401273) (xy 344.912303 -338.385918)
			(xy 344.862728 -338.363278) (xy 344.816879 -338.333813) (xy 344.775689 -338.298124) (xy 344.739998 -338.256936)
			(xy 344.710531 -338.211088) (xy 344.687888 -338.161514) (xy 344.672531 -338.109222) (xy 344.664772 -338.055276)
			(xy 344.664284 -338.028026) (xy 344.664284 -338.027772) (xy 344.66486 -337.997933) (xy 344.674175 -337.938987)
			(xy 344.682826 -337.910424) (xy 344.686863 -337.896517) (xy 344.687767 -337.867586) (xy 344.6805 -337.839567)
			(xy 344.665647 -337.814723) (xy 344.644409 -337.795057) (xy 344.618497 -337.782157) (xy 344.60434 -337.779106)
			(xy 344.571503 -337.772515) (xy 344.508649 -337.749398) (xy 344.479372 -337.733132) (xy 344.466407 -337.726095)
			(xy 344.437771 -337.719064) (xy 344.40832 -337.72051) (xy 344.38051 -337.730312) (xy 344.35666 -337.747652)
			(xy 344.338761 -337.771085) (xy 344.333068 -337.784694) (xy 344.322329 -337.811452) (xy 344.294047 -337.861692)
			(xy 344.258523 -337.907102) (xy 344.216568 -337.946646) (xy 344.169137 -337.979422) (xy 344.117312 -338.004683)
			(xy 344.062274 -338.021853) (xy 344.005279 -338.030541) (xy 343.976452 -338.031074) (xy 343.949201 -338.030653)
			(xy 343.895253 -338.02289) (xy 343.84296 -338.007529) (xy 343.793384 -337.984884) (xy 343.747536 -337.955413)
			(xy 343.706347 -337.919719) (xy 343.670658 -337.878526) (xy 343.641193 -337.832674) (xy 343.618554 -337.783095)
			(xy 343.6032 -337.7308) (xy 343.595444 -337.676851) (xy 343.595444 -337.622349) (xy 343.6032 -337.5684)
			(xy 343.618554 -337.516105) (xy 343.641193 -337.466526) (xy 343.670658 -337.420674) (xy 343.706347 -337.379481)
			(xy 343.747536 -337.343787) (xy 343.793384 -337.314316) (xy 343.84296 -337.291671) (xy 343.895253 -337.27631)
			(xy 343.949201 -337.268547) (xy 343.976452 -337.268058) (xy 343.976706 -337.268058) (xy 344.00191 -337.268452)
			(xy 344.051878 -337.275093) (xy 344.100533 -337.288271) (xy 344.147022 -337.307756) (xy 344.168984 -337.320128)
			(xy 344.181966 -337.327134) (xy 344.210596 -337.334177) (xy 344.240045 -337.33274) (xy 344.267854 -337.322944)
			(xy 344.291702 -337.305606) (xy 344.309598 -337.282175) (xy 344.315288 -337.268566) (xy 344.325959 -337.241779)
			(xy 344.354252 -337.191538) (xy 344.389785 -337.146129) (xy 344.431751 -337.106587) (xy 344.479192 -337.073815)
			(xy 344.531026 -337.048559) (xy 344.586072 -337.031395) (xy 344.643074 -337.022715) (xy 344.671904 -337.022186)
			(xy 344.699155 -337.022674) (xy 344.753102 -337.030431) (xy 344.805397 -337.045786) (xy 344.854974 -337.068427)
			(xy 344.900824 -337.097894) (xy 344.942014 -337.133585) (xy 344.977705 -337.174775) (xy 345.007172 -337.220625)
			(xy 345.016538 -337.241134) (xy 347.15958 -337.241134) (xy 347.160076 -337.213561) (xy 347.168023 -337.158989)
			(xy 347.183743 -337.10613) (xy 347.206907 -337.056085) (xy 347.237034 -337.009894) (xy 347.273496 -336.968521)
			(xy 347.2942 -336.950304) (xy 347.305063 -336.940371) (xy 347.321136 -336.91573) (xy 347.329523 -336.887532)
			(xy 347.32953 -336.858112) (xy 347.321155 -336.82991) (xy 347.305092 -336.805263) (xy 347.2942 -336.795364)
			(xy 347.273468 -336.777175) (xy 347.237 -336.735802) (xy 347.20687 -336.689607) (xy 347.183708 -336.639555)
			(xy 347.167996 -336.586688) (xy 347.160062 -336.53211) (xy 347.15958 -336.504534) (xy 347.160087 -336.477283)
			(xy 347.167839 -336.423334) (xy 347.18319 -336.371037) (xy 347.205828 -336.321458) (xy 347.235291 -336.275606)
			(xy 347.27098 -336.234413) (xy 347.312169 -336.198719) (xy 347.358018 -336.16925) (xy 347.407594 -336.146606)
			(xy 347.459889 -336.131249) (xy 347.513837 -336.12349) (xy 347.541088 -336.123026) (xy 347.541596 -336.123026)
			(xy 347.575378 -336.12455) (xy 347.588737 -336.125329) (xy 347.615099 -336.120819) (xy 347.639377 -336.109598)
			(xy 347.659895 -336.092442) (xy 347.675237 -336.070533) (xy 347.684343 -336.045386) (xy 347.685868 -336.032094)
			(xy 347.688871 -336.003927) (xy 347.702039 -335.948837) (xy 347.723211 -335.896301) (xy 347.751922 -335.847475)
			(xy 347.78754 -335.803434) (xy 347.829282 -335.765146) (xy 347.876228 -335.733455) (xy 347.927346 -335.709058)
			(xy 347.981511 -335.692491) (xy 348.037531 -335.684119) (xy 348.065852 -335.683606) (xy 348.083871 -335.683823)
			(xy 348.119746 -335.68726) (xy 348.13748 -335.690464) (xy 348.152691 -335.692778) (xy 348.183241 -335.689255)
			(xy 348.211358 -335.6768) (xy 348.234494 -335.65654) (xy 348.250551 -335.630313) (xy 348.254828 -335.615534)
			(xy 348.262201 -335.588483) (xy 348.283834 -335.536756) (xy 348.312802 -335.48875) (xy 348.348481 -335.445499)
			(xy 348.390103 -335.407933) (xy 348.436774 -335.37686) (xy 348.487488 -335.352948) (xy 348.541154 -335.336713)
			(xy 348.596618 -335.328504) (xy 348.624652 -335.328006) (xy 348.651904 -335.3285) (xy 348.705855 -335.336251)
			(xy 348.758153 -335.351601) (xy 348.807734 -335.374239) (xy 348.853588 -335.403704) (xy 348.894782 -335.439394)
			(xy 348.930476 -335.480585) (xy 348.959944 -335.526436) (xy 348.982587 -335.576015) (xy 348.997942 -335.628312)
			(xy 349.005698 -335.682262) (xy 349.00616 -335.709514) (xy 349.005649 -335.737087) (xy 348.997708 -335.791659)
			(xy 348.981993 -335.844518) (xy 348.958831 -335.894565) (xy 348.928706 -335.940755) (xy 348.892245 -335.982128)
			(xy 348.87154 -336.000344) (xy 348.860626 -336.010227) (xy 348.844548 -336.03488) (xy 348.836162 -336.063093)
			(xy 348.836165 -336.092525) (xy 348.844555 -336.120737) (xy 348.860638 -336.145387) (xy 348.87154 -336.155284)
			(xy 348.892262 -336.173483) (xy 348.928731 -336.214854) (xy 348.958862 -336.261046) (xy 348.982028 -336.311095)
			(xy 348.997745 -336.363958) (xy 349.005685 -336.418534) (xy 349.005684 -336.473684) (xy 348.997741 -336.52826)
			(xy 348.982021 -336.581122) (xy 348.958854 -336.63117) (xy 348.92872 -336.67736) (xy 348.892249 -336.71873)
			(xy 348.87154 -336.736944) (xy 348.860626 -336.746827) (xy 348.844548 -336.77148) (xy 348.836162 -336.799693)
			(xy 348.836165 -336.829125) (xy 348.844555 -336.857337) (xy 348.860638 -336.881987) (xy 348.87154 -336.891884)
			(xy 348.892255 -336.910091) (xy 348.928723 -336.951462) (xy 348.958854 -336.997653) (xy 348.982018 -337.047701)
			(xy 348.997735 -337.100564) (xy 349.005674 -337.155139) (xy 349.00616 -337.182714) (xy 349.005758 -337.209969)
			(xy 348.997998 -337.263925) (xy 348.982638 -337.316227) (xy 348.95999 -337.365811) (xy 348.930516 -337.411666)
			(xy 348.894816 -337.45286) (xy 348.853616 -337.488553) (xy 348.807756 -337.51802) (xy 348.758169 -337.540659)
			(xy 348.705864 -337.556011) (xy 348.651907 -337.563762) (xy 348.624652 -337.564222) (xy 348.596796 -337.563726)
			(xy 348.54168 -337.555596) (xy 348.48833 -337.539545) (xy 348.437878 -337.515914) (xy 348.391394 -337.485204)
			(xy 348.349865 -337.448066) (xy 348.314173 -337.405289) (xy 348.285073 -337.35778) (xy 348.263185 -337.306548)
			(xy 348.25559 -337.279742) (xy 348.251272 -337.265641) (xy 348.235894 -337.240497) (xy 348.213987 -337.220779)
			(xy 348.187368 -337.208124) (xy 348.158246 -337.203581) (xy 348.143576 -337.205066) (xy 348.13056 -337.206736)
			(xy 348.104375 -337.208515) (xy 348.091252 -337.208622) (xy 348.077103 -337.208522) (xy 348.04888 -337.206492)
			(xy 348.034864 -337.204558) (xy 348.021512 -337.203033) (xy 347.994829 -337.206126) (xy 347.969882 -337.216085)
			(xy 347.948405 -337.232218) (xy 347.931891 -337.253404) (xy 347.921488 -337.278169) (xy 347.919294 -337.291426)
			(xy 347.915213 -337.318581) (xy 347.900242 -337.371413) (xy 347.877851 -337.421553) (xy 347.848503 -337.467965)
			(xy 347.812805 -337.50969) (xy 347.771494 -337.545867) (xy 347.725423 -337.575748) (xy 347.675545 -337.598715)
			(xy 347.622889 -337.614295) (xy 347.568544 -337.622166) (xy 347.541088 -337.622642) (xy 347.513838 -337.622133)
			(xy 347.459893 -337.614376) (xy 347.407601 -337.599021) (xy 347.358026 -337.576381) (xy 347.312177 -337.546917)
			(xy 347.270988 -337.511228) (xy 347.235296 -337.470041) (xy 347.205829 -337.424194) (xy 347.183186 -337.37462)
			(xy 347.167828 -337.322329) (xy 347.160068 -337.268384) (xy 347.15958 -337.241134) (xy 345.016538 -337.241134)
			(xy 345.029813 -337.270201) (xy 345.045169 -337.322496) (xy 345.052926 -337.376443) (xy 345.053412 -337.403694)
			(xy 345.053412 -337.403948) (xy 345.05284 -337.433787) (xy 345.043522 -337.492733) (xy 345.03487 -337.521296)
			(xy 345.030926 -337.535227) (xy 345.030004 -337.564145) (xy 345.037252 -337.592155) (xy 345.052087 -337.616995)
			(xy 345.073309 -337.63666) (xy 345.099206 -337.649562) (xy 345.113356 -337.652614) (xy 345.141381 -337.658249)
			(xy 345.195487 -337.676688) (xy 345.246241 -337.702984) (xy 345.29251 -337.73655) (xy 345.333259 -337.776637)
			(xy 345.350846 -337.799172) (xy 345.429078 -337.799172) (xy 345.451562 -337.799701) (xy 345.495663 -337.8085)
			(xy 345.537203 -337.825726) (xy 345.574588 -337.850717) (xy 345.590876 -337.866228) (xy 345.962986 -338.238338)
			(xy 350.739456 -338.238338) (xy 350.740016 -338.20865) (xy 350.749211 -338.14999) (xy 350.767383 -338.093463)
			(xy 350.794096 -338.040435) (xy 350.828702 -337.992186) (xy 350.870366 -337.949883) (xy 350.893888 -337.93176)
			(xy 350.904471 -337.923305) (xy 350.921181 -337.902) (xy 350.931703 -337.877052) (xy 350.935297 -337.850216)
			(xy 350.931711 -337.823378) (xy 350.921197 -337.798427) (xy 350.904493 -337.777117) (xy 350.893888 -337.768692)
			(xy 350.870371 -337.750564) (xy 350.828712 -337.708258) (xy 350.794108 -337.66001) (xy 350.767397 -337.606983)
			(xy 350.749222 -337.550459) (xy 350.740022 -337.491801) (xy 350.739456 -337.462114) (xy 350.739942 -337.434863)
			(xy 350.747698 -337.380915) (xy 350.763053 -337.32862) (xy 350.785695 -337.279043) (xy 350.815161 -337.233193)
			(xy 350.850852 -337.192002) (xy 350.892043 -337.156311) (xy 350.937893 -337.126845) (xy 350.98747 -337.104203)
			(xy 351.039765 -337.088848) (xy 351.093713 -337.081092) (xy 351.148215 -337.081092) (xy 351.202163 -337.088848)
			(xy 351.254458 -337.104203) (xy 351.304035 -337.126845) (xy 351.349885 -337.156311) (xy 351.391076 -337.192002)
			(xy 351.426767 -337.233193) (xy 351.456233 -337.279043) (xy 351.478875 -337.32862) (xy 351.49423 -337.380915)
			(xy 351.501986 -337.434863) (xy 351.502472 -337.462114) (xy 351.501938 -337.491803) (xy 351.492737 -337.550464)
			(xy 351.474558 -337.60699) (xy 351.447841 -337.660018) (xy 351.41323 -337.708266) (xy 351.371563 -337.750569)
			(xy 351.34804 -337.768692) (xy 351.337403 -337.777085) (xy 351.320688 -337.798403) (xy 351.310166 -337.823365)
			(xy 351.306577 -337.850216) (xy 351.310174 -337.877065) (xy 351.320704 -337.902024) (xy 351.337425 -337.923336)
			(xy 351.34804 -337.93176) (xy 351.371587 -337.94985) (xy 351.413244 -337.992164) (xy 351.447843 -338.040421)
			(xy 351.474549 -338.093455) (xy 351.492718 -338.149986) (xy 351.50191 -338.208649) (xy 351.502472 -338.238338)
			(xy 351.501986 -338.265589) (xy 351.49423 -338.319537) (xy 351.478875 -338.371832) (xy 351.456233 -338.421409)
			(xy 351.426767 -338.467259) (xy 351.391076 -338.50845) (xy 351.349885 -338.544141) (xy 351.304035 -338.573607)
			(xy 351.254458 -338.596249) (xy 351.202163 -338.611604) (xy 351.148215 -338.61936) (xy 351.093713 -338.61936)
			(xy 351.039765 -338.611604) (xy 350.98747 -338.596249) (xy 350.937893 -338.573607) (xy 350.892043 -338.544141)
			(xy 350.850852 -338.50845) (xy 350.815161 -338.467259) (xy 350.785695 -338.421409) (xy 350.763053 -338.371832)
			(xy 350.747698 -338.319537) (xy 350.739942 -338.265589) (xy 350.739456 -338.238338) (xy 345.962986 -338.238338)
			(xy 346.401136 -338.676488) (xy 346.416697 -338.692733) (xy 346.441699 -338.730124) (xy 346.458915 -338.771679)
			(xy 346.467684 -338.815796) (xy 346.468192 -338.838286) (xy 346.468192 -340.20633) (xy 346.467615 -340.228812)
			(xy 346.458828 -340.272909) (xy 346.441616 -340.314448) (xy 346.416639 -340.351837) (xy 346.401136 -340.368128)
			(xy 343.851992 -342.917272) (xy 343.851992 -343.944632) (xy 344.389706 -343.944632) (xy 344.389706 -343.859936)
			(xy 344.397757 -343.775622) (xy 344.413786 -343.692456) (xy 344.437647 -343.611189) (xy 344.469126 -343.532559)
			(xy 344.507937 -343.457278) (xy 344.553727 -343.386026) (xy 344.606083 -343.31945) (xy 344.664531 -343.258152)
			(xy 344.728541 -343.202687) (xy 344.797533 -343.153558) (xy 344.870883 -343.111209) (xy 344.947926 -343.076025)
			(xy 345.027965 -343.048323) (xy 345.110274 -343.028355) (xy 345.194109 -343.016302) (xy 345.27871 -343.012272)
			(xy 345.363311 -343.016302) (xy 345.447146 -343.028355) (xy 345.529455 -343.048323) (xy 345.609494 -343.076025)
			(xy 345.686537 -343.111209) (xy 345.759887 -343.153558) (xy 345.828879 -343.202687) (xy 345.892889 -343.258152)
			(xy 345.951337 -343.31945) (xy 346.003693 -343.386026) (xy 346.049483 -343.457278) (xy 346.088294 -343.532559)
			(xy 346.119773 -343.611189) (xy 346.143634 -343.692456) (xy 346.159663 -343.775622) (xy 346.167714 -343.859936)
			(xy 346.168218 -343.902284) (xy 346.914219 -343.902284) (xy 346.918255 -343.818837) (xy 346.930327 -343.736169)
			(xy 346.95032 -343.655052) (xy 346.978049 -343.576243) (xy 347.013255 -343.500478) (xy 347.055609 -343.428465)
			(xy 347.104715 -343.360876) (xy 347.160116 -343.298342) (xy 347.221293 -343.241447) (xy 347.287676 -343.190721)
			(xy 347.358644 -343.14664) (xy 347.433536 -343.109614) (xy 347.511652 -343.079988) (xy 347.592262 -343.05804)
			(xy 347.674614 -343.043975) (xy 347.75794 -343.037923) (xy 347.84146 -343.039942) (xy 347.924396 -343.050012)
			(xy 348.005972 -343.06804) (xy 348.085428 -343.093857) (xy 348.162021 -343.127222) (xy 348.235037 -343.167823)
			(xy 348.303793 -343.215282) (xy 348.367647 -343.269155) (xy 348.426004 -343.32894) (xy 348.478319 -343.394077)
			(xy 348.524102 -343.46396) (xy 348.562927 -343.537935) (xy 348.594432 -343.615312) (xy 348.618321 -343.695369)
			(xy 348.634372 -343.777357) (xy 348.642435 -343.860512) (xy 348.64294 -343.902284) (xy 348.642435 -343.944056)
			(xy 348.634372 -344.027211) (xy 348.618321 -344.109199) (xy 348.594432 -344.189256) (xy 348.562927 -344.266633)
			(xy 348.524102 -344.340608) (xy 348.478319 -344.410491) (xy 348.426004 -344.475628) (xy 348.367647 -344.535413)
			(xy 348.303793 -344.589286) (xy 348.235037 -344.636745) (xy 348.162021 -344.677346) (xy 348.085428 -344.710711)
			(xy 348.005972 -344.736528) (xy 347.924396 -344.754556) (xy 347.84146 -344.764626) (xy 347.75794 -344.766645)
			(xy 347.674614 -344.760593) (xy 347.592262 -344.746528) (xy 347.511652 -344.72458) (xy 347.433536 -344.694954)
			(xy 347.358644 -344.657928) (xy 347.287676 -344.613847) (xy 347.221293 -344.563121) (xy 347.160116 -344.506226)
			(xy 347.104715 -344.443692) (xy 347.055609 -344.376103) (xy 347.013255 -344.30409) (xy 346.978049 -344.228325)
			(xy 346.95032 -344.149516) (xy 346.930327 -344.068399) (xy 346.918255 -343.985731) (xy 346.914219 -343.902284)
			(xy 346.168218 -343.902284) (xy 346.167714 -343.944632) (xy 346.159663 -344.028946) (xy 346.143634 -344.112112)
			(xy 346.119773 -344.193379) (xy 346.088294 -344.272009) (xy 346.049483 -344.34729) (xy 346.003693 -344.418542)
			(xy 345.951337 -344.485118) (xy 345.892889 -344.546416) (xy 345.828879 -344.601881) (xy 345.759887 -344.65101)
			(xy 345.686537 -344.693359) (xy 345.609494 -344.728543) (xy 345.529455 -344.756245) (xy 345.447146 -344.776213)
			(xy 345.363311 -344.788266) (xy 345.27871 -344.792297) (xy 345.194109 -344.788266) (xy 345.110274 -344.776213)
			(xy 345.027965 -344.756245) (xy 344.947926 -344.728543) (xy 344.870883 -344.693359) (xy 344.797533 -344.65101)
			(xy 344.728541 -344.601881) (xy 344.664531 -344.546416) (xy 344.606083 -344.485118) (xy 344.553727 -344.418542)
			(xy 344.507937 -344.34729) (xy 344.469126 -344.272009) (xy 344.437647 -344.193379) (xy 344.413786 -344.112112)
			(xy 344.397757 -344.028946) (xy 344.389706 -343.944632) (xy 343.851992 -343.944632) (xy 343.851992 -344.625168)
			(xy 346.505276 -347.278452) (xy 346.520827 -347.294706) (xy 346.545828 -347.332095) (xy 346.563047 -347.373647)
			(xy 346.571821 -347.417761) (xy 346.572332 -347.44025) (xy 346.572332 -351.857564) (xy 348.79788 -354.083112)
			(xy 349.389698 -354.083112) (xy 349.393769 -354.02749) (xy 349.405895 -353.973053) (xy 349.425818 -353.920962)
			(xy 349.453114 -353.872327) (xy 349.4872 -353.828184) (xy 349.527349 -353.789475) (xy 349.572707 -353.757024)
			(xy 349.622307 -353.731523) (xy 349.675091 -353.713516) (xy 349.729934 -353.703386) (xy 349.785668 -353.701349)
			(xy 349.841105 -353.707449) (xy 349.895062 -353.721555) (xy 349.946391 -353.743367) (xy 349.993997 -353.772421)
			(xy 350.036865 -353.808096) (xy 350.074082 -353.849633) (xy 350.104855 -353.896146) (xy 350.128527 -353.946643)
			(xy 350.144595 -354.00005) (xy 350.152715 -354.055226) (xy 350.153224 -354.083112) (xy 350.152715 -354.110998)
			(xy 350.144595 -354.166174) (xy 350.128527 -354.219581) (xy 350.104855 -354.270078) (xy 350.074082 -354.316591)
			(xy 350.036865 -354.358128) (xy 349.993997 -354.393803) (xy 349.946391 -354.422857) (xy 349.895062 -354.444669)
			(xy 349.841105 -354.458775) (xy 349.785668 -354.464875) (xy 349.729934 -354.462838) (xy 349.675091 -354.452708)
			(xy 349.622307 -354.434701) (xy 349.572707 -354.4092) (xy 349.527349 -354.376749) (xy 349.4872 -354.33804)
			(xy 349.453114 -354.293897) (xy 349.425818 -354.245262) (xy 349.405895 -354.193171) (xy 349.393769 -354.138734)
			(xy 349.389698 -354.083112) (xy 348.79788 -354.083112) (xy 349.335598 -354.62083) (xy 349.351194 -354.63706)
			(xy 349.376263 -354.674438) (xy 349.393545 -354.715993) (xy 349.402373 -354.760125) (xy 349.402908 -354.782628)
			(xy 349.402908 -358.487726) (xy 350.437704 -358.487726) (xy 350.437704 -340.567772) (xy 350.438283 -340.54529)
			(xy 350.44707 -340.501193) (xy 350.464281 -340.459654) (xy 350.489257 -340.422265) (xy 350.50476 -340.405974)
			(xy 352.828098 -338.082636) (xy 352.826066 -338.059014) (xy 352.824796 -338.028026) (xy 352.824796 -338.027772)
			(xy 352.825372 -337.997933) (xy 352.834687 -337.938987) (xy 352.843338 -337.910424) (xy 352.847365 -337.896515)
			(xy 352.848269 -337.867586) (xy 352.841003 -337.839569) (xy 352.826153 -337.814726) (xy 352.804916 -337.79506)
			(xy 352.779007 -337.782158) (xy 352.764852 -337.779106) (xy 352.732015 -337.772512) (xy 352.669162 -337.749397)
			(xy 352.639884 -337.733132) (xy 352.626912 -337.726109) (xy 352.598279 -337.719076) (xy 352.568829 -337.72052)
			(xy 352.541021 -337.730319) (xy 352.517172 -337.747656) (xy 352.499273 -337.771086) (xy 352.49358 -337.784694)
			(xy 352.482914 -337.811483) (xy 352.454624 -337.861727) (xy 352.41909 -337.907138) (xy 352.377124 -337.946681)
			(xy 352.329682 -337.979454) (xy 352.277846 -338.004709) (xy 352.222799 -338.021871) (xy 352.165794 -338.030548)
			(xy 352.136964 -338.031074) (xy 352.109712 -338.030654) (xy 352.055763 -338.022892) (xy 352.003468 -338.007533)
			(xy 351.953891 -337.984887) (xy 351.908041 -337.955418) (xy 351.866852 -337.919723) (xy 351.831161 -337.87853)
			(xy 351.801695 -337.832677) (xy 351.779055 -337.783098) (xy 351.7637 -337.730801) (xy 351.755944 -337.676852)
			(xy 351.755944 -337.622348) (xy 351.7637 -337.568399) (xy 351.779055 -337.516102) (xy 351.801695 -337.466523)
			(xy 351.831161 -337.42067) (xy 351.866852 -337.379477) (xy 351.908041 -337.343782) (xy 351.953891 -337.314313)
			(xy 352.003468 -337.291667) (xy 352.055763 -337.276308) (xy 352.109712 -337.268546) (xy 352.136964 -337.268058)
			(xy 352.137218 -337.268058) (xy 352.162422 -337.268447) (xy 352.21239 -337.27509) (xy 352.261045 -337.288269)
			(xy 352.307534 -337.307755) (xy 352.329496 -337.320128) (xy 352.342471 -337.327148) (xy 352.371104 -337.334189)
			(xy 352.400555 -337.332749) (xy 352.428366 -337.322951) (xy 352.452214 -337.30561) (xy 352.47011 -337.282176)
			(xy 352.4758 -337.268566) (xy 352.486461 -337.241775) (xy 352.514755 -337.191533) (xy 352.55029 -337.146124)
			(xy 352.592257 -337.106583) (xy 352.639699 -337.073811) (xy 352.691535 -337.048556) (xy 352.746582 -337.031393)
			(xy 352.803586 -337.022714) (xy 352.832416 -337.022186) (xy 352.859667 -337.022663) (xy 352.913615 -337.030421)
			(xy 352.96591 -337.045778) (xy 353.015487 -337.068421) (xy 353.061337 -337.097888) (xy 353.102526 -337.133581)
			(xy 353.138218 -337.174771) (xy 353.167684 -337.220622) (xy 353.190325 -337.2702) (xy 353.205681 -337.322495)
			(xy 353.213438 -337.376443) (xy 353.213924 -337.403694) (xy 353.213924 -337.403948) (xy 353.213352 -337.433787)
			(xy 353.204034 -337.492733) (xy 353.195382 -337.521296) (xy 353.191429 -337.535225) (xy 353.190506 -337.564145)
			(xy 353.197755 -337.592157) (xy 353.212592 -337.616998) (xy 353.233817 -337.636663) (xy 353.259717 -337.649563)
			(xy 353.273868 -337.652614) (xy 353.299946 -337.657757) (xy 353.350449 -337.674333) (xy 353.398162 -337.697761)
			(xy 353.442159 -337.727587) (xy 353.481589 -337.763233) (xy 353.515687 -337.804008) (xy 353.543792 -337.849124)
			(xy 353.565362 -337.897704) (xy 353.579976 -337.94881) (xy 353.587353 -338.001449) (xy 353.587812 -338.028026)
			(xy 353.587346 -338.055278) (xy 353.579586 -338.109226) (xy 353.564228 -338.161521) (xy 353.541584 -338.211098)
			(xy 353.524077 -338.238338) (xy 358.899968 -338.238338) (xy 358.900524 -338.20865) (xy 358.909719 -338.149989)
			(xy 358.927892 -338.093462) (xy 358.954605 -338.040434) (xy 358.989212 -337.992186) (xy 359.030878 -337.949883)
			(xy 359.0544 -337.93176) (xy 359.064982 -337.923304) (xy 359.08169 -337.901999) (xy 359.092211 -337.877051)
			(xy 359.095804 -337.850216) (xy 359.092219 -337.823379) (xy 359.081706 -337.798428) (xy 359.065004 -337.777118)
			(xy 359.0544 -337.768692) (xy 359.030886 -337.750561) (xy 358.989225 -337.708256) (xy 358.954621 -337.660008)
			(xy 358.927909 -337.606982) (xy 358.909734 -337.550458) (xy 358.900534 -337.491801) (xy 358.899968 -337.462114)
			(xy 358.900454 -337.434863) (xy 358.90821 -337.380915) (xy 358.923565 -337.32862) (xy 358.946207 -337.279043)
			(xy 358.975673 -337.233193) (xy 359.011364 -337.192002) (xy 359.052555 -337.156311) (xy 359.098405 -337.126845)
			(xy 359.147982 -337.104203) (xy 359.200277 -337.088848) (xy 359.254225 -337.081092) (xy 359.308727 -337.081092)
			(xy 359.362675 -337.088848) (xy 359.41497 -337.104203) (xy 359.464547 -337.126845) (xy 359.510397 -337.156311)
			(xy 359.551588 -337.192002) (xy 359.587279 -337.233193) (xy 359.616745 -337.279043) (xy 359.639387 -337.32862)
			(xy 359.654742 -337.380915) (xy 359.662498 -337.434863) (xy 359.662984 -337.462114) (xy 359.662446 -337.491803)
			(xy 359.653244 -337.550463) (xy 359.635066 -337.606989) (xy 359.60835 -337.660017) (xy 359.57374 -337.708265)
			(xy 359.532074 -337.750569) (xy 359.508552 -337.768692) (xy 359.497922 -337.77709) (xy 359.481222 -337.798411)
			(xy 359.47071 -337.823371) (xy 359.467125 -337.850216) (xy 359.470718 -337.877059) (xy 359.481238 -337.902016)
			(xy 359.497945 -337.923332) (xy 359.508552 -337.93176) (xy 359.532102 -337.949846) (xy 359.573758 -337.992162)
			(xy 359.608356 -338.04042) (xy 359.635062 -338.093454) (xy 359.65323 -338.149985) (xy 359.662422 -338.208649)
			(xy 359.662984 -338.238338) (xy 359.662498 -338.265589) (xy 359.654742 -338.319537) (xy 359.639387 -338.371832)
			(xy 359.616745 -338.421409) (xy 359.587279 -338.467259) (xy 359.551588 -338.50845) (xy 359.510397 -338.544141)
			(xy 359.464547 -338.573607) (xy 359.41497 -338.596249) (xy 359.362675 -338.611604) (xy 359.308727 -338.61936)
			(xy 359.254225 -338.61936) (xy 359.200277 -338.611604) (xy 359.147982 -338.596249) (xy 359.098405 -338.573607)
			(xy 359.052555 -338.544141) (xy 359.011364 -338.50845) (xy 358.975673 -338.467259) (xy 358.946207 -338.421409)
			(xy 358.923565 -338.371832) (xy 358.90821 -338.319537) (xy 358.900454 -338.265589) (xy 358.899968 -338.238338)
			(xy 353.524077 -338.238338) (xy 353.512116 -338.256948) (xy 353.476422 -338.298138) (xy 353.43523 -338.333829)
			(xy 353.389379 -338.363295) (xy 353.3398 -338.385936) (xy 353.287504 -338.401291) (xy 353.233556 -338.409048)
			(xy 353.206304 -338.409534) (xy 353.175316 -338.408264) (xy 353.151694 -338.406232) (xy 350.895412 -340.662514)
			(xy 350.895412 -343.944632) (xy 351.95027 -343.944632) (xy 351.95027 -343.859936) (xy 351.958321 -343.775622)
			(xy 351.97435 -343.692456) (xy 351.998211 -343.611189) (xy 352.02969 -343.532559) (xy 352.068501 -343.457278)
			(xy 352.114291 -343.386026) (xy 352.166647 -343.31945) (xy 352.225095 -343.258152) (xy 352.289105 -343.202687)
			(xy 352.358097 -343.153558) (xy 352.431447 -343.111209) (xy 352.50849 -343.076025) (xy 352.588529 -343.048323)
			(xy 352.670838 -343.028355) (xy 352.754673 -343.016302) (xy 352.839274 -343.012272) (xy 352.923875 -343.016302)
			(xy 353.00771 -343.028355) (xy 353.090019 -343.048323) (xy 353.170058 -343.076025) (xy 353.247101 -343.111209)
			(xy 353.320451 -343.153558) (xy 353.389443 -343.202687) (xy 353.453453 -343.258152) (xy 353.511901 -343.31945)
			(xy 353.564257 -343.386026) (xy 353.610047 -343.457278) (xy 353.648858 -343.532559) (xy 353.680337 -343.611189)
			(xy 353.704198 -343.692456) (xy 353.720227 -343.775622) (xy 353.728278 -343.859936) (xy 353.728782 -343.902284)
			(xy 354.474783 -343.902284) (xy 354.478819 -343.818837) (xy 354.490891 -343.736169) (xy 354.510884 -343.655052)
			(xy 354.538613 -343.576243) (xy 354.573819 -343.500478) (xy 354.616173 -343.428465) (xy 354.665279 -343.360876)
			(xy 354.72068 -343.298342) (xy 354.781857 -343.241447) (xy 354.84824 -343.190721) (xy 354.919208 -343.14664)
			(xy 354.9941 -343.109614) (xy 355.072216 -343.079988) (xy 355.152826 -343.05804) (xy 355.235178 -343.043975)
			(xy 355.318504 -343.037923) (xy 355.402024 -343.039942) (xy 355.48496 -343.050012) (xy 355.566536 -343.06804)
			(xy 355.645992 -343.093857) (xy 355.722585 -343.127222) (xy 355.795601 -343.167823) (xy 355.864357 -343.215282)
			(xy 355.928211 -343.269155) (xy 355.986568 -343.32894) (xy 356.038883 -343.394077) (xy 356.084666 -343.46396)
			(xy 356.123491 -343.537935) (xy 356.154996 -343.615312) (xy 356.178885 -343.695369) (xy 356.194936 -343.777357)
			(xy 356.202999 -343.860512) (xy 356.203504 -343.902284) (xy 356.202999 -343.944056) (xy 356.194936 -344.027211)
			(xy 356.178885 -344.109199) (xy 356.154996 -344.189256) (xy 356.123491 -344.266633) (xy 356.084666 -344.340608)
			(xy 356.038883 -344.410491) (xy 355.986568 -344.475628) (xy 355.928211 -344.535413) (xy 355.864357 -344.589286)
			(xy 355.795601 -344.636745) (xy 355.722585 -344.677346) (xy 355.645992 -344.710711) (xy 355.566536 -344.736528)
			(xy 355.48496 -344.754556) (xy 355.402024 -344.764626) (xy 355.318504 -344.766645) (xy 355.235178 -344.760593)
			(xy 355.152826 -344.746528) (xy 355.072216 -344.72458) (xy 354.9941 -344.694954) (xy 354.919208 -344.657928)
			(xy 354.84824 -344.613847) (xy 354.781857 -344.563121) (xy 354.72068 -344.506226) (xy 354.665279 -344.443692)
			(xy 354.616173 -344.376103) (xy 354.573819 -344.30409) (xy 354.538613 -344.228325) (xy 354.510884 -344.149516)
			(xy 354.490891 -344.068399) (xy 354.478819 -343.985731) (xy 354.474783 -343.902284) (xy 353.728782 -343.902284)
			(xy 353.728278 -343.944632) (xy 353.720227 -344.028946) (xy 353.704198 -344.112112) (xy 353.680337 -344.193379)
			(xy 353.648858 -344.272009) (xy 353.610047 -344.34729) (xy 353.564257 -344.418542) (xy 353.511901 -344.485118)
			(xy 353.453453 -344.546416) (xy 353.389443 -344.601881) (xy 353.320451 -344.65101) (xy 353.247101 -344.693359)
			(xy 353.170058 -344.728543) (xy 353.090019 -344.756245) (xy 353.00771 -344.776213) (xy 352.923875 -344.788266)
			(xy 352.839274 -344.792297) (xy 352.754673 -344.788266) (xy 352.670838 -344.776213) (xy 352.588529 -344.756245)
			(xy 352.50849 -344.728543) (xy 352.431447 -344.693359) (xy 352.358097 -344.65101) (xy 352.289105 -344.601881)
			(xy 352.225095 -344.546416) (xy 352.166647 -344.485118) (xy 352.114291 -344.418542) (xy 352.068501 -344.34729)
			(xy 352.02969 -344.272009) (xy 351.998211 -344.193379) (xy 351.97435 -344.112112) (xy 351.958321 -344.028946)
			(xy 351.95027 -343.944632) (xy 350.895412 -343.944632) (xy 350.895412 -352.231452) (xy 351.159572 -352.231452)
			(xy 351.159572 -350.634554) (xy 351.16018 -350.61206) (xy 351.169022 -350.567947) (xy 351.186297 -350.526406)
			(xy 351.211344 -350.489032) (xy 351.226882 -350.472756) (xy 357.674164 -344.025474) (xy 357.674164 -343.86901)
			(xy 357.674688 -343.846525) (xy 357.683489 -343.802425) (xy 357.700716 -343.760885) (xy 357.725709 -343.7235)
			(xy 357.74122 -343.707212) (xy 362.027724 -339.420708) (xy 362.027724 -339.01253) (xy 361.421426 -338.406232)
			(xy 361.397804 -338.408264) (xy 361.366816 -338.409534) (xy 361.339566 -338.409007) (xy 361.285622 -338.401253)
			(xy 361.233329 -338.385902) (xy 361.183754 -338.363264) (xy 361.137905 -338.333802) (xy 361.096715 -338.298115)
			(xy 361.061023 -338.256929) (xy 361.031556 -338.211083) (xy 361.008913 -338.16151) (xy 360.993556 -338.10922)
			(xy 360.985796 -338.055276) (xy 360.985308 -338.028026) (xy 360.985308 -338.027772) (xy 360.985883 -337.997933)
			(xy 360.995199 -337.938987) (xy 361.00385 -337.910424) (xy 361.007868 -337.896513) (xy 361.008772 -337.867586)
			(xy 361.001506 -337.839571) (xy 360.986658 -337.814728) (xy 360.965424 -337.795062) (xy 360.939518 -337.782159)
			(xy 360.925364 -337.779106) (xy 360.892528 -337.772509) (xy 360.829674 -337.749396) (xy 360.800396 -337.733132)
			(xy 360.787417 -337.726123) (xy 360.758786 -337.719088) (xy 360.729339 -337.720529) (xy 360.701532 -337.730326)
			(xy 360.677684 -337.74766) (xy 360.659785 -337.771087) (xy 360.654092 -337.784694) (xy 360.643416 -337.811479)
			(xy 360.615127 -337.861723) (xy 360.579595 -337.907133) (xy 360.53763 -337.946676) (xy 360.49019 -337.979449)
			(xy 360.438355 -338.004705) (xy 360.383309 -338.021868) (xy 360.326306 -338.030547) (xy 360.297476 -338.031074)
			(xy 360.270223 -338.030654) (xy 360.216274 -338.022895) (xy 360.163977 -338.007536) (xy 360.114398 -337.984891)
			(xy 360.068547 -337.955422) (xy 360.027356 -337.919727) (xy 359.991664 -337.878534) (xy 359.962197 -337.832681)
			(xy 359.939556 -337.783101) (xy 359.9242 -337.730803) (xy 359.916444 -337.676853) (xy 359.916444 -337.622347)
			(xy 359.9242 -337.568397) (xy 359.939556 -337.516099) (xy 359.962197 -337.466519) (xy 359.991664 -337.420666)
			(xy 360.027356 -337.379473) (xy 360.068547 -337.343778) (xy 360.114398 -337.314309) (xy 360.163977 -337.291664)
			(xy 360.216274 -337.276305) (xy 360.270223 -337.268546) (xy 360.297476 -337.268058) (xy 360.29773 -337.268058)
			(xy 360.322934 -337.268442) (xy 360.372903 -337.275086) (xy 360.421557 -337.288267) (xy 360.468047 -337.307754)
			(xy 360.490008 -337.320128) (xy 360.502976 -337.327162) (xy 360.531612 -337.334201) (xy 360.561065 -337.332759)
			(xy 360.588877 -337.322957) (xy 360.612726 -337.305614) (xy 360.630622 -337.282177) (xy 360.636312 -337.268566)
			(xy 360.646963 -337.241771) (xy 360.675258 -337.191528) (xy 360.710794 -337.146119) (xy 360.752763 -337.106578)
			(xy 360.800207 -337.073806) (xy 360.852044 -337.048552) (xy 360.907092 -337.03139) (xy 360.964097 -337.022713)
			(xy 360.992928 -337.022186) (xy 361.02018 -337.022652) (xy 361.074128 -337.030412) (xy 361.126423 -337.04577)
			(xy 361.175999 -337.068414) (xy 361.221849 -337.097883) (xy 361.263039 -337.133576) (xy 361.29873 -337.174768)
			(xy 361.328196 -337.22062) (xy 361.350837 -337.270198) (xy 361.366193 -337.322494) (xy 361.37395 -337.376442)
			(xy 361.374436 -337.403694) (xy 361.374436 -337.403948) (xy 361.373863 -337.433787) (xy 361.364546 -337.492733)
			(xy 361.355894 -337.521296) (xy 361.351931 -337.535223) (xy 361.351008 -337.564145) (xy 361.358258 -337.592159)
			(xy 361.373097 -337.617001) (xy 361.394325 -337.636666) (xy 361.420227 -337.649564) (xy 361.43438 -337.652614)
			(xy 361.460445 -337.657823) (xy 361.510948 -337.674387) (xy 361.558661 -337.697804) (xy 361.60266 -337.727621)
			(xy 361.642092 -337.763259) (xy 361.676192 -337.804028) (xy 361.704301 -337.849138) (xy 361.725872 -337.897714)
			(xy 361.740488 -337.948815) (xy 361.747865 -338.001451) (xy 361.748324 -338.028026) (xy 361.747054 -338.059014)
			(xy 361.745022 -338.082636) (xy 361.900724 -338.238338) (xy 367.06048 -338.238338) (xy 367.061071 -338.208651)
			(xy 367.070263 -338.149994) (xy 367.088432 -338.09347) (xy 367.115138 -338.040442) (xy 367.149738 -337.992192)
			(xy 367.191394 -337.949885) (xy 367.214912 -337.93176) (xy 367.225493 -337.923304) (xy 367.242199 -337.901998)
			(xy 367.252719 -337.877051) (xy 367.256312 -337.850216) (xy 367.252727 -337.82338) (xy 367.242215 -337.798429)
			(xy 367.225516 -337.777118) (xy 367.214912 -337.768692) (xy 367.1914 -337.750558) (xy 367.149739 -337.708254)
			(xy 367.115135 -337.660007) (xy 367.088422 -337.606981) (xy 367.070246 -337.550458) (xy 367.061046 -337.491801)
			(xy 367.06048 -337.462114) (xy 367.060966 -337.434863) (xy 367.068722 -337.380915) (xy 367.084077 -337.32862)
			(xy 367.106719 -337.279043) (xy 367.136185 -337.233193) (xy 367.171876 -337.192002) (xy 367.213067 -337.156311)
			(xy 367.258917 -337.126845) (xy 367.308494 -337.104203) (xy 367.360789 -337.088848) (xy 367.414737 -337.081092)
			(xy 367.469239 -337.081092) (xy 367.523187 -337.088848) (xy 367.575482 -337.104203) (xy 367.625059 -337.126845)
			(xy 367.670909 -337.156311) (xy 367.7121 -337.192002) (xy 367.747791 -337.233193) (xy 367.777257 -337.279043)
			(xy 367.799899 -337.32862) (xy 367.815254 -337.380915) (xy 367.82301 -337.434863) (xy 367.823496 -337.462114)
			(xy 367.822953 -337.491802) (xy 367.813752 -337.550462) (xy 367.795574 -337.606988) (xy 367.768859 -337.660016)
			(xy 367.734251 -337.708264) (xy 367.692586 -337.750569) (xy 367.669064 -337.768692) (xy 367.658433 -337.77709)
			(xy 367.641731 -337.79841) (xy 367.631218 -337.82337) (xy 367.627632 -337.850216) (xy 367.631226 -337.87706)
			(xy 367.641747 -337.902017) (xy 367.658456 -337.923332) (xy 367.669064 -337.93176) (xy 367.692595 -337.94987)
			(xy 367.734256 -337.992178) (xy 367.76886 -338.04043) (xy 367.795569 -338.09346) (xy 367.81374 -338.149989)
			(xy 367.822934 -338.208649) (xy 367.823496 -338.238338) (xy 367.82301 -338.265589) (xy 367.815254 -338.319537)
			(xy 367.799899 -338.371832) (xy 367.777257 -338.421409) (xy 367.747791 -338.467259) (xy 367.7121 -338.50845)
			(xy 367.670909 -338.544141) (xy 367.625059 -338.573607) (xy 367.575482 -338.596249) (xy 367.523187 -338.611604)
			(xy 367.469239 -338.61936) (xy 367.414737 -338.61936) (xy 367.360789 -338.611604) (xy 367.308494 -338.596249)
			(xy 367.258917 -338.573607) (xy 367.213067 -338.544141) (xy 367.171876 -338.50845) (xy 367.136185 -338.467259)
			(xy 367.106719 -338.421409) (xy 367.084077 -338.371832) (xy 367.068722 -338.319537) (xy 367.060966 -338.265589)
			(xy 367.06048 -338.238338) (xy 361.900724 -338.238338) (xy 362.418376 -338.75599) (xy 362.433945 -338.772228)
			(xy 362.458943 -338.809623) (xy 362.476157 -338.851179) (xy 362.484924 -338.895297) (xy 362.485432 -338.917788)
			(xy 362.485432 -339.51545) (xy 362.484885 -339.537933) (xy 362.476091 -339.582033) (xy 362.458871 -339.623573)
			(xy 362.433885 -339.66096) (xy 362.418376 -339.677248) (xy 358.150992 -343.944632) (xy 359.655614 -343.944632)
			(xy 359.655614 -343.859936) (xy 359.663665 -343.775622) (xy 359.679694 -343.692456) (xy 359.703555 -343.611189)
			(xy 359.735034 -343.532559) (xy 359.773845 -343.457278) (xy 359.819635 -343.386026) (xy 359.871991 -343.31945)
			(xy 359.930439 -343.258152) (xy 359.994449 -343.202687) (xy 360.063441 -343.153558) (xy 360.136791 -343.111209)
			(xy 360.213834 -343.076025) (xy 360.293873 -343.048323) (xy 360.376182 -343.028355) (xy 360.460017 -343.016302)
			(xy 360.544618 -343.012272) (xy 360.629219 -343.016302) (xy 360.713054 -343.028355) (xy 360.795363 -343.048323)
			(xy 360.875402 -343.076025) (xy 360.952445 -343.111209) (xy 361.025795 -343.153558) (xy 361.094787 -343.202687)
			(xy 361.158797 -343.258152) (xy 361.217245 -343.31945) (xy 361.269601 -343.386026) (xy 361.315391 -343.457278)
			(xy 361.354202 -343.532559) (xy 361.385681 -343.611189) (xy 361.409542 -343.692456) (xy 361.425571 -343.775622)
			(xy 361.433622 -343.859936) (xy 361.434126 -343.902284) (xy 362.180127 -343.902284) (xy 362.184163 -343.818837)
			(xy 362.196235 -343.736169) (xy 362.216228 -343.655052) (xy 362.243957 -343.576243) (xy 362.279163 -343.500478)
			(xy 362.321517 -343.428465) (xy 362.370623 -343.360876) (xy 362.426024 -343.298342) (xy 362.487201 -343.241447)
			(xy 362.553584 -343.190721) (xy 362.624552 -343.14664) (xy 362.699444 -343.109614) (xy 362.77756 -343.079988)
			(xy 362.85817 -343.05804) (xy 362.940522 -343.043975) (xy 363.023848 -343.037923) (xy 363.107368 -343.039942)
			(xy 363.190304 -343.050012) (xy 363.27188 -343.06804) (xy 363.351336 -343.093857) (xy 363.427929 -343.127222)
			(xy 363.500945 -343.167823) (xy 363.569701 -343.215282) (xy 363.633555 -343.269155) (xy 363.691912 -343.32894)
			(xy 363.744227 -343.394077) (xy 363.79001 -343.46396) (xy 363.828835 -343.537935) (xy 363.86034 -343.615312)
			(xy 363.884229 -343.695369) (xy 363.90028 -343.777357) (xy 363.908343 -343.860512) (xy 363.908848 -343.902284)
			(xy 363.908343 -343.944056) (xy 363.90028 -344.027211) (xy 363.884229 -344.109199) (xy 363.86034 -344.189256)
			(xy 363.828835 -344.266633) (xy 363.79001 -344.340608) (xy 363.744227 -344.410491) (xy 363.691912 -344.475628)
			(xy 363.633555 -344.535413) (xy 363.569701 -344.589286) (xy 363.500945 -344.636745) (xy 363.427929 -344.677346)
			(xy 363.351336 -344.710711) (xy 363.27188 -344.736528) (xy 363.190304 -344.754556) (xy 363.107368 -344.764626)
			(xy 363.023848 -344.766645) (xy 362.940522 -344.760593) (xy 362.85817 -344.746528) (xy 362.77756 -344.72458)
			(xy 362.699444 -344.694954) (xy 362.624552 -344.657928) (xy 362.553584 -344.613847) (xy 362.487201 -344.563121)
			(xy 362.426024 -344.506226) (xy 362.370623 -344.443692) (xy 362.321517 -344.376103) (xy 362.279163 -344.30409)
			(xy 362.243957 -344.228325) (xy 362.216228 -344.149516) (xy 362.196235 -344.068399) (xy 362.184163 -343.985731)
			(xy 362.180127 -343.902284) (xy 361.434126 -343.902284) (xy 361.433622 -343.944632) (xy 361.425571 -344.028946)
			(xy 361.409542 -344.112112) (xy 361.385681 -344.193379) (xy 361.354202 -344.272009) (xy 361.315391 -344.34729)
			(xy 361.269601 -344.418542) (xy 361.217245 -344.485118) (xy 361.158797 -344.546416) (xy 361.094787 -344.601881)
			(xy 361.025795 -344.65101) (xy 360.952445 -344.693359) (xy 360.875402 -344.728543) (xy 360.795363 -344.756245)
			(xy 360.713054 -344.776213) (xy 360.629219 -344.788266) (xy 360.544618 -344.792297) (xy 360.460017 -344.788266)
			(xy 360.376182 -344.776213) (xy 360.293873 -344.756245) (xy 360.213834 -344.728543) (xy 360.136791 -344.693359)
			(xy 360.063441 -344.65101) (xy 359.994449 -344.601881) (xy 359.930439 -344.546416) (xy 359.871991 -344.485118)
			(xy 359.819635 -344.418542) (xy 359.773845 -344.34729) (xy 359.735034 -344.272009) (xy 359.703555 -344.193379)
			(xy 359.679694 -344.112112) (xy 359.663665 -344.028946) (xy 359.655614 -343.944632) (xy 358.150992 -343.944632)
			(xy 358.131872 -343.963752) (xy 358.131872 -344.120216) (xy 358.131292 -344.142698) (xy 358.122507 -344.186795)
			(xy 358.105296 -344.228335) (xy 358.08032 -344.265724) (xy 358.064816 -344.282014) (xy 351.679254 -350.667828)
			(xy 354.882702 -350.667828) (xy 354.886773 -350.612206) (xy 354.898899 -350.557769) (xy 354.918822 -350.505678)
			(xy 354.946118 -350.457043) (xy 354.980204 -350.4129) (xy 355.020353 -350.374191) (xy 355.065711 -350.34174)
			(xy 355.115311 -350.316239) (xy 355.168095 -350.298232) (xy 355.222938 -350.288102) (xy 355.278672 -350.286065)
			(xy 355.334109 -350.292165) (xy 355.388066 -350.306271) (xy 355.439395 -350.328083) (xy 355.487001 -350.357137)
			(xy 355.529869 -350.392812) (xy 355.567086 -350.434349) (xy 355.597859 -350.480862) (xy 355.621531 -350.531359)
			(xy 355.637599 -350.584766) (xy 355.645719 -350.639942) (xy 355.646228 -350.667828) (xy 355.645719 -350.695714)
			(xy 355.637599 -350.75089) (xy 355.621531 -350.804297) (xy 355.597859 -350.854794) (xy 355.567086 -350.901307)
			(xy 355.529869 -350.942844) (xy 355.487001 -350.978519) (xy 355.439395 -351.007573) (xy 355.388066 -351.029385)
			(xy 355.334109 -351.043491) (xy 355.278672 -351.049591) (xy 355.222938 -351.047554) (xy 355.168095 -351.037424)
			(xy 355.115311 -351.019417) (xy 355.065711 -350.993916) (xy 355.020353 -350.961465) (xy 354.980204 -350.922756)
			(xy 354.946118 -350.878613) (xy 354.918822 -350.829978) (xy 354.898899 -350.777887) (xy 354.886773 -350.72345)
			(xy 354.882702 -350.667828) (xy 351.679254 -350.667828) (xy 351.617788 -350.729296) (xy 351.617788 -351.605088)
			(xy 351.934778 -351.605088) (xy 351.938849 -351.549466) (xy 351.950975 -351.495029) (xy 351.970898 -351.442938)
			(xy 351.998194 -351.394303) (xy 352.03228 -351.35016) (xy 352.072429 -351.311451) (xy 352.117787 -351.279)
			(xy 352.167387 -351.253499) (xy 352.220171 -351.235492) (xy 352.275014 -351.225362) (xy 352.330748 -351.223325)
			(xy 352.386185 -351.229425) (xy 352.440142 -351.243531) (xy 352.491471 -351.265343) (xy 352.539077 -351.294397)
			(xy 352.581945 -351.330072) (xy 352.619162 -351.371609) (xy 352.649935 -351.418122) (xy 352.673607 -351.468619)
			(xy 352.689675 -351.522026) (xy 352.697795 -351.577202) (xy 352.698304 -351.605088) (xy 352.697795 -351.632974)
			(xy 352.689675 -351.68815) (xy 352.673607 -351.741557) (xy 352.649935 -351.792054) (xy 352.627431 -351.826068)
			(xy 352.798378 -351.826068) (xy 352.802449 -351.770446) (xy 352.814575 -351.716009) (xy 352.834498 -351.663918)
			(xy 352.861794 -351.615283) (xy 352.89588 -351.57114) (xy 352.936029 -351.532431) (xy 352.981387 -351.49998)
			(xy 353.030987 -351.474479) (xy 353.083771 -351.456472) (xy 353.138614 -351.446342) (xy 353.194348 -351.444305)
			(xy 353.249785 -351.450405) (xy 353.303742 -351.464511) (xy 353.355071 -351.486323) (xy 353.402677 -351.515377)
			(xy 353.445545 -351.551052) (xy 353.482762 -351.592589) (xy 353.513535 -351.639102) (xy 353.537207 -351.689599)
			(xy 353.553275 -351.743006) (xy 353.561395 -351.798182) (xy 353.561904 -351.826068) (xy 353.561395 -351.853954)
			(xy 353.553275 -351.90913) (xy 353.537207 -351.962537) (xy 353.533311 -351.970848) (xy 354.280976 -351.970848)
			(xy 354.285047 -351.915226) (xy 354.297173 -351.860789) (xy 354.317096 -351.808698) (xy 354.344392 -351.760063)
			(xy 354.378478 -351.71592) (xy 354.418627 -351.677211) (xy 354.463985 -351.64476) (xy 354.513585 -351.619259)
			(xy 354.566369 -351.601252) (xy 354.621212 -351.591122) (xy 354.676946 -351.589085) (xy 354.732383 -351.595185)
			(xy 354.78634 -351.609291) (xy 354.837669 -351.631103) (xy 354.885275 -351.660157) (xy 354.928143 -351.695832)
			(xy 354.93878 -351.707704) (xy 355.638352 -351.707704) (xy 355.642423 -351.652082) (xy 355.654549 -351.597645)
			(xy 355.674472 -351.545554) (xy 355.701768 -351.496919) (xy 355.735854 -351.452776) (xy 355.776003 -351.414067)
			(xy 355.821361 -351.381616) (xy 355.870961 -351.356115) (xy 355.923745 -351.338108) (xy 355.978588 -351.327978)
			(xy 356.034322 -351.325941) (xy 356.089759 -351.332041) (xy 356.143716 -351.346147) (xy 356.195045 -351.367959)
			(xy 356.242651 -351.397013) (xy 356.285519 -351.432688) (xy 356.322736 -351.474225) (xy 356.340416 -351.500948)
			(xy 356.859076 -351.500948) (xy 356.863147 -351.445326) (xy 356.875273 -351.390889) (xy 356.895196 -351.338798)
			(xy 356.922492 -351.290163) (xy 356.956578 -351.24602) (xy 356.996727 -351.207311) (xy 357.042085 -351.17486)
			(xy 357.091685 -351.149359) (xy 357.144469 -351.131352) (xy 357.199312 -351.121222) (xy 357.255046 -351.119185)
			(xy 357.310483 -351.125285) (xy 357.36444 -351.139391) (xy 357.415769 -351.161203) (xy 357.463375 -351.190257)
			(xy 357.506243 -351.225932) (xy 357.54346 -351.267469) (xy 357.574233 -351.313982) (xy 357.597905 -351.364479)
			(xy 357.613973 -351.417886) (xy 357.622093 -351.473062) (xy 357.622602 -351.500948) (xy 357.622093 -351.528834)
			(xy 357.613973 -351.58401) (xy 357.597905 -351.637417) (xy 357.574233 -351.687914) (xy 357.54346 -351.734427)
			(xy 357.506243 -351.775964) (xy 357.463375 -351.811639) (xy 357.415769 -351.840693) (xy 357.36444 -351.862505)
			(xy 357.310483 -351.876611) (xy 357.255046 -351.882711) (xy 357.199312 -351.880674) (xy 357.144469 -351.870544)
			(xy 357.091685 -351.852537) (xy 357.042085 -351.827036) (xy 356.996727 -351.794585) (xy 356.956578 -351.755876)
			(xy 356.922492 -351.711733) (xy 356.895196 -351.663098) (xy 356.875273 -351.611007) (xy 356.863147 -351.55657)
			(xy 356.859076 -351.500948) (xy 356.340416 -351.500948) (xy 356.353509 -351.520738) (xy 356.377181 -351.571235)
			(xy 356.393249 -351.624642) (xy 356.401369 -351.679818) (xy 356.401878 -351.707704) (xy 356.401369 -351.73559)
			(xy 356.393249 -351.790766) (xy 356.377181 -351.844173) (xy 356.353509 -351.89467) (xy 356.322736 -351.941183)
			(xy 356.285519 -351.98272) (xy 356.242651 -352.018395) (xy 356.195045 -352.047449) (xy 356.143716 -352.069261)
			(xy 356.089759 -352.083367) (xy 356.034322 -352.089467) (xy 355.978588 -352.08743) (xy 355.923745 -352.0773)
			(xy 355.870961 -352.059293) (xy 355.821361 -352.033792) (xy 355.776003 -352.001341) (xy 355.735854 -351.962632)
			(xy 355.701768 -351.918489) (xy 355.674472 -351.869854) (xy 355.654549 -351.817763) (xy 355.642423 -351.763326)
			(xy 355.638352 -351.707704) (xy 354.93878 -351.707704) (xy 354.96536 -351.737369) (xy 354.996133 -351.783882)
			(xy 355.019805 -351.834379) (xy 355.035873 -351.887786) (xy 355.043993 -351.942962) (xy 355.044502 -351.970848)
			(xy 355.043993 -351.998734) (xy 355.035873 -352.05391) (xy 355.019805 -352.107317) (xy 354.996133 -352.157814)
			(xy 354.96536 -352.204327) (xy 354.928143 -352.245864) (xy 354.885275 -352.281539) (xy 354.837669 -352.310593)
			(xy 354.78634 -352.332405) (xy 354.732383 -352.346511) (xy 354.676946 -352.352611) (xy 354.621212 -352.350574)
			(xy 354.566369 -352.340444) (xy 354.513585 -352.322437) (xy 354.463985 -352.296936) (xy 354.418627 -352.264485)
			(xy 354.378478 -352.225776) (xy 354.344392 -352.181633) (xy 354.317096 -352.132998) (xy 354.297173 -352.080907)
			(xy 354.285047 -352.02647) (xy 354.280976 -351.970848) (xy 353.533311 -351.970848) (xy 353.513535 -352.013034)
			(xy 353.482762 -352.059547) (xy 353.445545 -352.101084) (xy 353.402677 -352.136759) (xy 353.355071 -352.165813)
			(xy 353.303742 -352.187625) (xy 353.249785 -352.201731) (xy 353.194348 -352.207831) (xy 353.138614 -352.205794)
			(xy 353.083771 -352.195664) (xy 353.030987 -352.177657) (xy 352.981387 -352.152156) (xy 352.936029 -352.119705)
			(xy 352.89588 -352.080996) (xy 352.861794 -352.036853) (xy 352.834498 -351.988218) (xy 352.814575 -351.936127)
			(xy 352.802449 -351.88169) (xy 352.798378 -351.826068) (xy 352.627431 -351.826068) (xy 352.619162 -351.838567)
			(xy 352.581945 -351.880104) (xy 352.539077 -351.915779) (xy 352.491471 -351.944833) (xy 352.440142 -351.966645)
			(xy 352.386185 -351.980751) (xy 352.330748 -351.986851) (xy 352.275014 -351.984814) (xy 352.220171 -351.974684)
			(xy 352.167387 -351.956677) (xy 352.117787 -351.931176) (xy 352.072429 -351.898725) (xy 352.03228 -351.860016)
			(xy 351.998194 -351.815873) (xy 351.970898 -351.767238) (xy 351.950975 -351.715147) (xy 351.938849 -351.66071)
			(xy 351.934778 -351.605088) (xy 351.617788 -351.605088) (xy 351.617788 -352.13671) (xy 352.1202 -352.639376)
			(xy 352.973132 -352.639376) (xy 352.995615 -352.639932) (xy 353.039714 -352.648722) (xy 353.081254 -352.66594)
			(xy 353.118641 -352.690924) (xy 353.13493 -352.706432) (xy 354.287836 -353.859338) (xy 354.303374 -353.875604)
			(xy 354.328379 -353.912988) (xy 354.345602 -353.954536) (xy 354.354379 -353.998648) (xy 354.354892 -354.021136)
			(xy 354.354892 -361.088432) (xy 355.098858 -361.832398) (xy 355.114432 -361.848648) (xy 355.139507 -361.886018)
			(xy 355.156795 -361.927568) (xy 355.16563 -361.971695) (xy 355.166168 -361.994196) (xy 355.166168 -362.900976)
			(xy 355.165567 -362.92347) (xy 355.156721 -362.967583) (xy 355.139443 -363.009124) (xy 355.114396 -363.046498)
			(xy 355.098858 -363.062774) (xy 354.938584 -363.223048) (xy 354.940616 -363.24667) (xy 354.941886 -363.277658)
			(xy 354.94149 -363.304914) (xy 354.933738 -363.358873) (xy 354.918386 -363.411178) (xy 354.895746 -363.460767)
			(xy 354.866279 -363.506629) (xy 354.830585 -363.54783) (xy 354.789391 -363.583532) (xy 354.743535 -363.613008)
			(xy 354.693951 -363.635659) (xy 354.641648 -363.651022) (xy 354.587691 -363.658785) (xy 354.533179 -363.65879)
			(xy 354.479221 -363.651037) (xy 354.426915 -363.635683) (xy 354.377327 -363.613042) (xy 354.331466 -363.583575)
			(xy 354.290265 -363.54788) (xy 354.254564 -363.506685) (xy 354.225088 -363.460829) (xy 354.202439 -363.411245)
			(xy 354.187077 -363.358942) (xy 354.179315 -363.304985) (xy 354.179311 -363.250472) (xy 354.187065 -363.196514)
			(xy 354.202419 -363.144209) (xy 354.225061 -363.094621) (xy 354.254529 -363.04876) (xy 354.290224 -363.00756)
			(xy 354.33142 -362.97186) (xy 354.377277 -362.942385) (xy 354.426861 -362.919737) (xy 354.479165 -362.904376)
			(xy 354.533122 -362.896615) (xy 354.560378 -362.89615) (xy 354.591366 -362.89742) (xy 354.614988 -362.899452)
			(xy 354.707952 -362.806234) (xy 354.707952 -362.088938) (xy 353.96424 -361.344972) (xy 353.948703 -361.328706)
			(xy 353.923698 -361.291321) (xy 353.906476 -361.249773) (xy 353.897698 -361.205662) (xy 353.897184 -361.183174)
			(xy 353.897184 -354.115878) (xy 352.87839 -353.097084) (xy 352.025458 -353.097084) (xy 352.002976 -353.096517)
			(xy 351.958878 -353.087727) (xy 351.917339 -353.070512) (xy 351.87995 -353.045533) (xy 351.86366 -353.030028)
			(xy 351.226882 -352.39325) (xy 351.211321 -352.376989) (xy 351.186246 -352.339622) (xy 351.168955 -352.298076)
			(xy 351.160114 -352.253952) (xy 351.159572 -352.231452) (xy 350.895412 -352.231452) (xy 350.895412 -354.444808)
			(xy 352.808284 -354.444808) (xy 352.812355 -354.389186) (xy 352.824481 -354.334749) (xy 352.844404 -354.282658)
			(xy 352.8717 -354.234023) (xy 352.905786 -354.18988) (xy 352.945935 -354.151171) (xy 352.991293 -354.11872)
			(xy 353.040893 -354.093219) (xy 353.093677 -354.075212) (xy 353.14852 -354.065082) (xy 353.204254 -354.063045)
			(xy 353.259691 -354.069145) (xy 353.313648 -354.083251) (xy 353.364977 -354.105063) (xy 353.412583 -354.134117)
			(xy 353.455451 -354.169792) (xy 353.492668 -354.211329) (xy 353.523441 -354.257842) (xy 353.547113 -354.308339)
			(xy 353.563181 -354.361746) (xy 353.571301 -354.416922) (xy 353.57181 -354.444808) (xy 353.571301 -354.472694)
			(xy 353.563181 -354.52787) (xy 353.547113 -354.581277) (xy 353.523441 -354.631774) (xy 353.492668 -354.678287)
			(xy 353.455451 -354.719824) (xy 353.412583 -354.755499) (xy 353.364977 -354.784553) (xy 353.313648 -354.806365)
			(xy 353.259691 -354.820471) (xy 353.204254 -354.826571) (xy 353.14852 -354.824534) (xy 353.093677 -354.814404)
			(xy 353.040893 -354.796397) (xy 352.991293 -354.770896) (xy 352.945935 -354.738445) (xy 352.905786 -354.699736)
			(xy 352.8717 -354.655593) (xy 352.844404 -354.606958) (xy 352.824481 -354.554867) (xy 352.812355 -354.50043)
			(xy 352.808284 -354.444808) (xy 350.895412 -354.444808) (xy 350.895412 -356.040436) (xy 351.932746 -356.040436)
			(xy 351.936817 -355.984814) (xy 351.948943 -355.930377) (xy 351.968866 -355.878286) (xy 351.996162 -355.829651)
			(xy 352.030248 -355.785508) (xy 352.070397 -355.746799) (xy 352.115755 -355.714348) (xy 352.165355 -355.688847)
			(xy 352.218139 -355.67084) (xy 352.272982 -355.66071) (xy 352.328716 -355.658673) (xy 352.384153 -355.664773)
			(xy 352.43811 -355.678879) (xy 352.489439 -355.700691) (xy 352.537045 -355.729745) (xy 352.579913 -355.76542)
			(xy 352.61713 -355.806957) (xy 352.647903 -355.85347) (xy 352.671575 -355.903967) (xy 352.687643 -355.957374)
			(xy 352.695763 -356.01255) (xy 352.696272 -356.040436) (xy 352.695763 -356.068322) (xy 352.687643 -356.123498)
			(xy 352.671575 -356.176905) (xy 352.647903 -356.227402) (xy 352.61713 -356.273915) (xy 352.579913 -356.315452)
			(xy 352.537045 -356.351127) (xy 352.489439 -356.380181) (xy 352.43811 -356.401993) (xy 352.384153 -356.416099)
			(xy 352.328716 -356.422199) (xy 352.272982 -356.420162) (xy 352.218139 -356.410032) (xy 352.165355 -356.392025)
			(xy 352.115755 -356.366524) (xy 352.070397 -356.334073) (xy 352.030248 -356.295364) (xy 351.996162 -356.251221)
			(xy 351.968866 -356.202586) (xy 351.948943 -356.150495) (xy 351.936817 -356.096058) (xy 351.932746 -356.040436)
			(xy 350.895412 -356.040436) (xy 350.895412 -358.221267) (xy 351.436611 -358.221267) (xy 351.444366 -358.167309)
			(xy 351.459721 -358.115003) (xy 351.482364 -358.065416) (xy 351.511833 -358.019555) (xy 351.547529 -357.978356)
			(xy 351.588725 -357.942656) (xy 351.634583 -357.913182) (xy 351.684168 -357.890534) (xy 351.736472 -357.875174)
			(xy 351.79043 -357.867414) (xy 351.817686 -357.86695) (xy 351.833829 -357.867091) (xy 351.866003 -357.869764)
			(xy 351.881948 -357.872284) (xy 351.89597 -357.874265) (xy 351.924113 -357.871202) (xy 351.950334 -357.86053)
			(xy 351.972617 -357.843069) (xy 351.989249 -357.82016) (xy 351.998953 -357.793566) (xy 352.000981 -357.765329)
			(xy 351.998534 -357.75138) (xy 351.994727 -357.732111) (xy 351.990659 -357.693042) (xy 351.990406 -357.673402)
			(xy 351.990876 -357.646151) (xy 351.998632 -357.592203) (xy 352.013987 -357.539908) (xy 352.036627 -357.490331)
			(xy 352.066093 -357.44448) (xy 352.101784 -357.40329) (xy 352.142974 -357.367598) (xy 352.188824 -357.338131)
			(xy 352.238401 -357.315489) (xy 352.290695 -357.300134) (xy 352.344643 -357.292376) (xy 352.399145 -357.292375)
			(xy 352.453093 -357.300131) (xy 352.505388 -357.315485) (xy 352.554966 -357.338125) (xy 352.600816 -357.367591)
			(xy 352.642007 -357.403281) (xy 352.6777 -357.444471) (xy 352.707167 -357.49032) (xy 352.729809 -357.539897)
			(xy 352.745166 -357.592191) (xy 352.752924 -357.646139) (xy 352.752925 -357.700641) (xy 352.74517 -357.754589)
			(xy 352.729816 -357.806884) (xy 352.707177 -357.856462) (xy 352.677712 -357.902313) (xy 352.642022 -357.943505)
			(xy 352.600832 -357.979197) (xy 352.554983 -358.008665) (xy 352.505407 -358.031308) (xy 352.453113 -358.046665)
			(xy 352.399165 -358.054423) (xy 352.371914 -358.05491) (xy 352.355771 -358.05477) (xy 352.323597 -358.052097)
			(xy 352.307652 -358.049576) (xy 352.293627 -358.047643) (xy 352.265492 -358.050705) (xy 352.239279 -358.061372)
			(xy 352.217001 -358.078825) (xy 352.200369 -358.101723) (xy 352.190662 -358.128307) (xy 352.188624 -358.156534)
			(xy 352.191066 -358.17048) (xy 352.194867 -358.18975) (xy 352.198939 -358.228818) (xy 352.199194 -358.248458)
			(xy 352.19879 -358.275714) (xy 352.191038 -358.329673) (xy 352.175685 -358.381979) (xy 352.153045 -358.431568)
			(xy 352.123578 -358.47743) (xy 352.087884 -358.518631) (xy 352.04669 -358.554333) (xy 352.000833 -358.583809)
			(xy 351.951249 -358.606459) (xy 351.898946 -358.621822) (xy 351.844989 -358.629585) (xy 351.790476 -358.629589)
			(xy 351.736518 -358.621836) (xy 351.684212 -358.606482) (xy 351.634624 -358.583841) (xy 351.588763 -358.554372)
			(xy 351.547562 -358.518677) (xy 351.511861 -358.477482) (xy 351.482386 -358.431625) (xy 351.459737 -358.38204)
			(xy 351.444376 -358.329737) (xy 351.436615 -358.27578) (xy 351.436611 -358.221267) (xy 350.895412 -358.221267)
			(xy 350.895412 -358.392984) (xy 351.504758 -359.00233) (xy 351.520347 -359.018566) (xy 351.545419 -359.055941)
			(xy 351.562704 -359.097495) (xy 351.571533 -359.141626) (xy 351.57182 -359.153714) (xy 351.933254 -359.153714)
			(xy 351.937325 -359.098092) (xy 351.949451 -359.043655) (xy 351.969374 -358.991564) (xy 351.99667 -358.942929)
			(xy 352.030756 -358.898786) (xy 352.070905 -358.860077) (xy 352.116263 -358.827626) (xy 352.165863 -358.802125)
			(xy 352.218647 -358.784118) (xy 352.27349 -358.773988) (xy 352.329224 -358.771951) (xy 352.384661 -358.778051)
			(xy 352.438618 -358.792157) (xy 352.489947 -358.813969) (xy 352.537553 -358.843023) (xy 352.580421 -358.878698)
			(xy 352.617638 -358.920235) (xy 352.648411 -358.966748) (xy 352.672083 -359.017245) (xy 352.688151 -359.070652)
			(xy 352.696271 -359.125828) (xy 352.69678 -359.153714) (xy 352.696271 -359.1816) (xy 352.688151 -359.236776)
			(xy 352.672083 -359.290183) (xy 352.648411 -359.34068) (xy 352.617638 -359.387193) (xy 352.580421 -359.42873)
			(xy 352.537553 -359.464405) (xy 352.489947 -359.493459) (xy 352.438618 -359.515271) (xy 352.384661 -359.529377)
			(xy 352.329224 -359.535477) (xy 352.27349 -359.53344) (xy 352.218647 -359.52331) (xy 352.165863 -359.505303)
			(xy 352.116263 -359.479802) (xy 352.070905 -359.447351) (xy 352.030756 -359.408642) (xy 351.99667 -359.364499)
			(xy 351.969374 -359.315864) (xy 351.949451 -359.263773) (xy 351.937325 -359.209336) (xy 351.933254 -359.153714)
			(xy 351.57182 -359.153714) (xy 351.572068 -359.164128) (xy 351.572068 -360.248708) (xy 352.035362 -360.248708)
			(xy 352.039433 -360.193086) (xy 352.051559 -360.138649) (xy 352.071482 -360.086558) (xy 352.098778 -360.037923)
			(xy 352.132864 -359.99378) (xy 352.173013 -359.955071) (xy 352.218371 -359.92262) (xy 352.267971 -359.897119)
			(xy 352.320755 -359.879112) (xy 352.375598 -359.868982) (xy 352.431332 -359.866945) (xy 352.486769 -359.873045)
			(xy 352.540726 -359.887151) (xy 352.592055 -359.908963) (xy 352.639661 -359.938017) (xy 352.682529 -359.973692)
			(xy 352.719746 -360.015229) (xy 352.750519 -360.061742) (xy 352.774191 -360.112239) (xy 352.790259 -360.165646)
			(xy 352.798379 -360.220822) (xy 352.798888 -360.248708) (xy 352.798379 -360.276594) (xy 352.790259 -360.33177)
			(xy 352.774191 -360.385177) (xy 352.750519 -360.435674) (xy 352.719746 -360.482187) (xy 352.682529 -360.523724)
			(xy 352.639661 -360.559399) (xy 352.592055 -360.588453) (xy 352.540726 -360.610265) (xy 352.486769 -360.624371)
			(xy 352.431332 -360.630471) (xy 352.375598 -360.628434) (xy 352.320755 -360.618304) (xy 352.267971 -360.600297)
			(xy 352.218371 -360.574796) (xy 352.173013 -360.542345) (xy 352.132864 -360.503636) (xy 352.098778 -360.459493)
			(xy 352.071482 -360.410858) (xy 352.051559 -360.358767) (xy 352.039433 -360.30433) (xy 352.035362 -360.248708)
			(xy 351.572068 -360.248708) (xy 351.572068 -360.377486) (xy 352.370898 -361.17657) (xy 352.386465 -361.192825)
			(xy 352.41154 -361.230194) (xy 352.42883 -361.271742) (xy 352.437668 -361.315868) (xy 352.438208 -361.338368)
			(xy 352.438208 -361.681268) (xy 352.721162 -361.681268) (xy 352.725233 -361.625646) (xy 352.737359 -361.571209)
			(xy 352.757282 -361.519118) (xy 352.784578 -361.470483) (xy 352.818664 -361.42634) (xy 352.858813 -361.387631)
			(xy 352.904171 -361.35518) (xy 352.953771 -361.329679) (xy 353.006555 -361.311672) (xy 353.061398 -361.301542)
			(xy 353.117132 -361.299505) (xy 353.172569 -361.305605) (xy 353.226526 -361.319711) (xy 353.277855 -361.341523)
			(xy 353.325461 -361.370577) (xy 353.368329 -361.406252) (xy 353.405546 -361.447789) (xy 353.436319 -361.494302)
			(xy 353.459991 -361.544799) (xy 353.476059 -361.598206) (xy 353.484179 -361.653382) (xy 353.484688 -361.681268)
			(xy 353.484179 -361.709154) (xy 353.476059 -361.76433) (xy 353.459991 -361.817737) (xy 353.436319 -361.868234)
			(xy 353.405546 -361.914747) (xy 353.368329 -361.956284) (xy 353.325461 -361.991959) (xy 353.277855 -362.021013)
			(xy 353.226526 -362.042825) (xy 353.172569 -362.056931) (xy 353.117132 -362.063031) (xy 353.061398 -362.060994)
			(xy 353.006555 -362.050864) (xy 352.953771 -362.032857) (xy 352.904171 -362.007356) (xy 352.858813 -361.974905)
			(xy 352.818664 -361.936196) (xy 352.784578 -361.892053) (xy 352.757282 -361.843418) (xy 352.737359 -361.791327)
			(xy 352.725233 -361.73689) (xy 352.721162 -361.681268) (xy 352.438208 -361.681268) (xy 352.438208 -361.982766)
			(xy 352.855276 -362.400088) (xy 352.870844 -362.416327) (xy 352.895842 -362.453721) (xy 352.913056 -362.495277)
			(xy 352.921824 -362.539395) (xy 352.922332 -362.561886) (xy 352.922332 -363.332776) (xy 352.945616 -363.350875)
			(xy 352.986781 -363.393105) (xy 353.020962 -363.441163) (xy 353.047347 -363.493905) (xy 353.065307 -363.550078)
			(xy 353.074417 -363.608344) (xy 353.074986 -363.63783) (xy 353.0745 -363.665081) (xy 353.066744 -363.719029)
			(xy 353.051389 -363.771324) (xy 353.028747 -363.820901) (xy 352.999281 -363.866751) (xy 352.96359 -363.907942)
			(xy 352.922399 -363.943633) (xy 352.876549 -363.973099) (xy 352.826972 -363.995741) (xy 352.774677 -364.011096)
			(xy 352.720729 -364.018852) (xy 352.666227 -364.018852) (xy 352.612279 -364.011096) (xy 352.559984 -363.995741)
			(xy 352.510407 -363.973099) (xy 352.464557 -363.943633) (xy 352.423366 -363.907942) (xy 352.387675 -363.866751)
			(xy 352.358209 -363.820901) (xy 352.335567 -363.771324) (xy 352.320212 -363.719029) (xy 352.312456 -363.665081)
			(xy 352.31197 -363.63783) (xy 352.312551 -363.608343) (xy 352.321642 -363.550075) (xy 352.339595 -363.493901)
			(xy 352.365982 -363.44116) (xy 352.400176 -363.393112) (xy 352.441359 -363.3509) (xy 352.464624 -363.332776)
			(xy 352.464624 -362.656628) (xy 352.047302 -362.239306) (xy 352.031723 -362.223061) (xy 352.006651 -362.185688)
			(xy 351.989364 -362.144137) (xy 351.98053 -362.100009) (xy 351.979992 -362.077508) (xy 351.979992 -361.43311)
			(xy 351.181162 -360.634026) (xy 351.165586 -360.617778) (xy 351.140515 -360.580406) (xy 351.123228 -360.538856)
			(xy 351.114392 -360.494729) (xy 351.113852 -360.472228) (xy 351.113852 -359.25887) (xy 350.50476 -358.649524)
			(xy 350.489204 -358.633275) (xy 350.464202 -358.595885) (xy 350.446984 -358.554331) (xy 350.438213 -358.510216)
			(xy 350.437704 -358.487726) (xy 349.402908 -358.487726) (xy 349.402908 -359.484168) (xy 349.7359 -359.484168)
			(xy 349.739971 -359.428546) (xy 349.752097 -359.374109) (xy 349.77202 -359.322018) (xy 349.799316 -359.273383)
			(xy 349.833402 -359.22924) (xy 349.873551 -359.190531) (xy 349.918909 -359.15808) (xy 349.968509 -359.132579)
			(xy 350.021293 -359.114572) (xy 350.076136 -359.104442) (xy 350.13187 -359.102405) (xy 350.187307 -359.108505)
			(xy 350.241264 -359.122611) (xy 350.292593 -359.144423) (xy 350.340199 -359.173477) (xy 350.383067 -359.209152)
			(xy 350.420284 -359.250689) (xy 350.451057 -359.297202) (xy 350.474729 -359.347699) (xy 350.490797 -359.401106)
			(xy 350.498917 -359.456282) (xy 350.499426 -359.484168) (xy 350.498917 -359.512054) (xy 350.490797 -359.56723)
			(xy 350.474729 -359.620637) (xy 350.451057 -359.671134) (xy 350.420284 -359.717647) (xy 350.383067 -359.759184)
			(xy 350.340199 -359.794859) (xy 350.292593 -359.823913) (xy 350.241264 -359.845725) (xy 350.187307 -359.859831)
			(xy 350.13187 -359.865931) (xy 350.076136 -359.863894) (xy 350.021293 -359.853764) (xy 349.968509 -359.835757)
			(xy 349.918909 -359.810256) (xy 349.873551 -359.777805) (xy 349.833402 -359.739096) (xy 349.799316 -359.694953)
			(xy 349.77202 -359.646318) (xy 349.752097 -359.594227) (xy 349.739971 -359.53979) (xy 349.7359 -359.484168)
			(xy 349.402908 -359.484168) (xy 349.402908 -361.333288) (xy 349.402303 -361.355782) (xy 349.393456 -361.399894)
			(xy 349.376179 -361.441434) (xy 349.351135 -361.478809) (xy 349.335598 -361.495086) (xy 349.110808 -361.72013)
			(xy 349.110808 -361.953556) (xy 349.395032 -361.953556) (xy 349.399103 -361.897934) (xy 349.411229 -361.843497)
			(xy 349.431152 -361.791406) (xy 349.458448 -361.742771) (xy 349.492534 -361.698628) (xy 349.532683 -361.659919)
			(xy 349.578041 -361.627468) (xy 349.627641 -361.601967) (xy 349.680425 -361.58396) (xy 349.735268 -361.57383)
			(xy 349.791002 -361.571793) (xy 349.846439 -361.577893) (xy 349.900396 -361.591999) (xy 349.951725 -361.613811)
			(xy 349.999331 -361.642865) (xy 350.042199 -361.67854) (xy 350.079416 -361.720077) (xy 350.110189 -361.76659)
			(xy 350.133861 -361.817087) (xy 350.149929 -361.870494) (xy 350.158049 -361.92567) (xy 350.15853 -361.952032)
			(xy 350.408746 -361.952032) (xy 350.412817 -361.89641) (xy 350.424943 -361.841973) (xy 350.444866 -361.789882)
			(xy 350.472162 -361.741247) (xy 350.506248 -361.697104) (xy 350.546397 -361.658395) (xy 350.591755 -361.625944)
			(xy 350.641355 -361.600443) (xy 350.694139 -361.582436) (xy 350.748982 -361.572306) (xy 350.804716 -361.570269)
			(xy 350.860153 -361.576369) (xy 350.91411 -361.590475) (xy 350.965439 -361.612287) (xy 351.013045 -361.641341)
			(xy 351.055913 -361.677016) (xy 351.09313 -361.718553) (xy 351.123903 -361.765066) (xy 351.147575 -361.815563)
			(xy 351.163643 -361.86897) (xy 351.171763 -361.924146) (xy 351.172272 -361.952032) (xy 351.171763 -361.979918)
			(xy 351.163643 -362.035094) (xy 351.147575 -362.088501) (xy 351.123903 -362.138998) (xy 351.09313 -362.185511)
			(xy 351.055913 -362.227048) (xy 351.013045 -362.262723) (xy 350.965439 -362.291777) (xy 350.91411 -362.313589)
			(xy 350.860153 -362.327695) (xy 350.804716 -362.333795) (xy 350.748982 -362.331758) (xy 350.694139 -362.321628)
			(xy 350.641355 -362.303621) (xy 350.591755 -362.27812) (xy 350.546397 -362.245669) (xy 350.506248 -362.20696)
			(xy 350.472162 -362.162817) (xy 350.444866 -362.114182) (xy 350.424943 -362.062091) (xy 350.412817 -362.007654)
			(xy 350.408746 -361.952032) (xy 350.15853 -361.952032) (xy 350.158558 -361.953556) (xy 350.158049 -361.981442)
			(xy 350.149929 -362.036618) (xy 350.133861 -362.090025) (xy 350.110189 -362.140522) (xy 350.079416 -362.187035)
			(xy 350.042199 -362.228572) (xy 349.999331 -362.264247) (xy 349.951725 -362.293301) (xy 349.900396 -362.315113)
			(xy 349.846439 -362.329219) (xy 349.791002 -362.335319) (xy 349.735268 -362.333282) (xy 349.680425 -362.323152)
			(xy 349.627641 -362.305145) (xy 349.578041 -362.279644) (xy 349.532683 -362.247193) (xy 349.492534 -362.208484)
			(xy 349.458448 -362.164341) (xy 349.431152 -362.115706) (xy 349.411229 -362.063615) (xy 349.399103 -362.009178)
			(xy 349.395032 -361.953556) (xy 349.110808 -361.953556) (xy 349.110808 -362.251752) (xy 349.482618 -362.623608)
			(xy 351.008948 -362.623608) (xy 351.013019 -362.567986) (xy 351.025145 -362.513549) (xy 351.045068 -362.461458)
			(xy 351.072364 -362.412823) (xy 351.10645 -362.36868) (xy 351.146599 -362.329971) (xy 351.191957 -362.29752)
			(xy 351.241557 -362.272019) (xy 351.294341 -362.254012) (xy 351.349184 -362.243882) (xy 351.404918 -362.241845)
			(xy 351.460355 -362.247945) (xy 351.514312 -362.262051) (xy 351.565641 -362.283863) (xy 351.613247 -362.312917)
			(xy 351.656115 -362.348592) (xy 351.693332 -362.390129) (xy 351.724105 -362.436642) (xy 351.747777 -362.487139)
			(xy 351.763845 -362.540546) (xy 351.771965 -362.595722) (xy 351.772474 -362.623608) (xy 351.771965 -362.651494)
			(xy 351.763845 -362.70667) (xy 351.747777 -362.760077) (xy 351.724105 -362.810574) (xy 351.693332 -362.857087)
			(xy 351.656115 -362.898624) (xy 351.613247 -362.934299) (xy 351.565641 -362.963353) (xy 351.514312 -362.985165)
			(xy 351.460355 -362.999271) (xy 351.404918 -363.005371) (xy 351.349184 -363.003334) (xy 351.294341 -362.993204)
			(xy 351.241557 -362.975197) (xy 351.191957 -362.949696) (xy 351.146599 -362.917245) (xy 351.10645 -362.878536)
			(xy 351.072364 -362.834393) (xy 351.045068 -362.785758) (xy 351.025145 -362.733667) (xy 351.013019 -362.67923)
			(xy 351.008948 -362.623608) (xy 349.482618 -362.623608) (xy 351.149158 -364.290356) (xy 352.95459 -364.290356)
			(xy 353.417632 -363.82706) (xy 353.417632 -362.682028) (xy 353.418236 -362.659534) (xy 353.427081 -362.615421)
			(xy 353.444358 -362.57388) (xy 353.469404 -362.536506) (xy 353.484942 -362.52023) (xy 353.603814 -362.401358)
			(xy 353.601782 -362.377736) (xy 353.600512 -362.346748) (xy 353.600904 -362.319491) (xy 353.608655 -362.265532)
			(xy 353.624007 -362.213224) (xy 353.646647 -362.163635) (xy 353.676113 -362.117772) (xy 353.711808 -362.076569)
			(xy 353.753002 -362.040866) (xy 353.798858 -362.011388) (xy 353.848443 -361.988737) (xy 353.900747 -361.973373)
			(xy 353.954705 -361.96561) (xy 354.009218 -361.965604) (xy 354.063177 -361.973357) (xy 354.115484 -361.98871)
			(xy 354.165074 -362.011351) (xy 354.210936 -362.040819) (xy 354.252138 -362.076514) (xy 354.28784 -362.11771)
			(xy 354.317316 -362.163567) (xy 354.339966 -362.213152) (xy 354.355329 -362.265456) (xy 354.363091 -362.319414)
			(xy 354.363095 -362.373927) (xy 354.355341 -362.427887) (xy 354.339987 -362.480193) (xy 354.317344 -362.529782)
			(xy 354.287875 -362.575643) (xy 354.252179 -362.616844) (xy 354.210983 -362.652546) (xy 354.165125 -362.682021)
			(xy 354.115539 -362.704669) (xy 354.063235 -362.720031) (xy 354.009277 -362.727792) (xy 353.98202 -362.728256)
			(xy 353.951032 -362.726986) (xy 353.92741 -362.724954) (xy 353.875848 -362.77677) (xy 353.875848 -363.921802)
			(xy 353.875268 -363.944298) (xy 353.866417 -363.988412) (xy 353.849133 -364.029952) (xy 353.824079 -364.067325)
			(xy 353.808538 -364.0836) (xy 353.451084 -364.441054) (xy 354.061455 -364.441054) (xy 354.061455 -364.386546)
			(xy 354.069213 -364.332593) (xy 354.08457 -364.280294) (xy 354.107214 -364.230712) (xy 354.136684 -364.184858)
			(xy 354.17238 -364.143665) (xy 354.213576 -364.107971) (xy 354.259431 -364.078504) (xy 354.309014 -364.055862)
			(xy 354.361315 -364.040508) (xy 354.415268 -364.032754) (xy 354.442522 -364.032292) (xy 354.472942 -364.032905)
			(xy 354.533002 -364.042617) (xy 354.590764 -364.061729) (xy 354.618036 -364.075218) (xy 354.651056 -364.092236)
			(xy 355.474524 -363.269022) (xy 355.474524 -356.90683) (xy 355.475072 -356.884347) (xy 355.483867 -356.840248)
			(xy 355.501088 -356.798709) (xy 355.526073 -356.761321) (xy 355.54158 -356.745032) (xy 357.509572 -354.776786)
			(xy 357.509572 -352.339148) (xy 357.510176 -352.316654) (xy 357.519019 -352.27254) (xy 357.536296 -352.230999)
			(xy 357.561343 -352.193625) (xy 357.576882 -352.17735) (xy 357.941372 -351.812606) (xy 357.941372 -350.942148)
			(xy 357.941976 -350.919654) (xy 357.950819 -350.87554) (xy 357.968096 -350.833999) (xy 357.993143 -350.796625)
			(xy 358.008682 -350.78035) (xy 359.151682 -349.63735) (xy 359.167924 -349.621768) (xy 359.205299 -349.596699)
			(xy 359.246851 -349.579414) (xy 359.290979 -349.570579) (xy 359.31348 -349.57004) (xy 361.649518 -349.57004)
			(xy 365.38408 -345.835732) (xy 365.38408 -343.260934) (xy 365.384614 -343.23845) (xy 365.393411 -343.194349)
			(xy 365.410635 -343.15281) (xy 365.435626 -343.115424) (xy 365.451136 -343.099136) (xy 368.2238 -340.326472)
			(xy 368.240041 -340.310906) (xy 368.277434 -340.285906) (xy 368.318989 -340.26869) (xy 368.363107 -340.259923)
			(xy 368.385598 -340.259416) (xy 369.456716 -340.259416) (xy 370.079524 -339.636608) (xy 370.079524 -338.903818)
			(xy 369.581938 -338.406232) (xy 369.558316 -338.408264) (xy 369.527328 -338.409534) (xy 369.500077 -338.409019)
			(xy 369.446129 -338.401266) (xy 369.393834 -338.385915) (xy 369.344256 -338.363278) (xy 369.298404 -338.333815)
			(xy 369.257211 -338.298127) (xy 369.221517 -338.25694) (xy 369.192048 -338.211092) (xy 369.169404 -338.161517)
			(xy 369.154045 -338.109224) (xy 369.146285 -338.055277) (xy 369.14582 -338.028026) (xy 369.14582 -338.027772)
			(xy 369.146395 -337.997933) (xy 369.15571 -337.938987) (xy 369.164362 -337.910424) (xy 369.168449 -337.896528)
			(xy 369.169356 -337.867586) (xy 369.162084 -337.839558) (xy 369.147221 -337.814708) (xy 369.125967 -337.795042)
			(xy 369.10004 -337.78215) (xy 369.085876 -337.779106) (xy 369.053035 -337.77253) (xy 368.990184 -337.749402)
			(xy 368.960908 -337.733132) (xy 368.947922 -337.726137) (xy 368.919294 -337.719101) (xy 368.889849 -337.720539)
			(xy 368.862044 -337.730333) (xy 368.838197 -337.747665) (xy 368.820298 -337.771089) (xy 368.814604 -337.784694)
			(xy 368.803918 -337.811475) (xy 368.77563 -337.861718) (xy 368.740099 -337.907128) (xy 368.698136 -337.946671)
			(xy 368.650697 -337.979445) (xy 368.598864 -338.004702) (xy 368.543819 -338.021866) (xy 368.486817 -338.030546)
			(xy 368.457988 -338.031074) (xy 368.430735 -338.030655) (xy 368.376784 -338.022897) (xy 368.324486 -338.007539)
			(xy 368.274906 -337.984895) (xy 368.229053 -337.955426) (xy 368.18786 -337.919731) (xy 368.152167 -337.878538)
			(xy 368.122699 -337.832684) (xy 368.100057 -337.783103) (xy 368.084701 -337.730805) (xy 368.076944 -337.676853)
			(xy 368.076944 -337.622347) (xy 368.084701 -337.568395) (xy 368.100057 -337.516097) (xy 368.122699 -337.466516)
			(xy 368.152167 -337.420662) (xy 368.18786 -337.379469) (xy 368.229053 -337.343774) (xy 368.274906 -337.314305)
			(xy 368.324486 -337.291661) (xy 368.376784 -337.276303) (xy 368.430735 -337.268545) (xy 368.457988 -337.268058)
			(xy 368.458242 -337.268058) (xy 368.483446 -337.268437) (xy 368.533415 -337.275082) (xy 368.58207 -337.288265)
			(xy 368.628559 -337.307753) (xy 368.65052 -337.320128) (xy 368.66348 -337.327177) (xy 368.692119 -337.334213)
			(xy 368.721575 -337.332769) (xy 368.749388 -337.322964) (xy 368.773238 -337.305619) (xy 368.791135 -337.282179)
			(xy 368.796824 -337.268566) (xy 368.807549 -337.241802) (xy 368.835835 -337.191563) (xy 368.871361 -337.146155)
			(xy 368.913319 -337.106613) (xy 368.960752 -337.073838) (xy 369.012578 -337.048578) (xy 369.067617 -337.031408)
			(xy 369.124613 -337.022719) (xy 369.15344 -337.022186) (xy 369.180692 -337.022641) (xy 369.23464 -337.030402)
			(xy 369.286935 -337.045762) (xy 369.336512 -337.068408) (xy 369.382362 -337.097878) (xy 369.423552 -337.133572)
			(xy 369.459243 -337.174765) (xy 369.488709 -337.220617) (xy 369.51135 -337.270196) (xy 369.526705 -337.322493)
			(xy 369.534462 -337.376442) (xy 369.534948 -337.403694) (xy 369.534948 -337.403948) (xy 369.534375 -337.433787)
			(xy 369.526646 -337.482688) (xy 371.647212 -337.482688) (xy 371.647734 -337.455115) (xy 371.655675 -337.400545)
			(xy 371.671388 -337.347686) (xy 371.694547 -337.29764) (xy 371.72467 -337.251449) (xy 371.761129 -337.210075)
			(xy 371.781832 -337.191858) (xy 371.792738 -337.18197) (xy 371.808804 -337.157315) (xy 371.817183 -337.129106)
			(xy 371.817181 -337.099679) (xy 371.808798 -337.071471) (xy 371.792728 -337.046819) (xy 371.781832 -337.036918)
			(xy 371.761133 -337.018694) (xy 371.72466 -336.977329) (xy 371.694526 -336.931142) (xy 371.671358 -336.881096)
			(xy 371.655639 -336.828235) (xy 371.647698 -336.773662) (xy 371.647212 -336.746088) (xy 371.647644 -336.718834)
			(xy 371.655403 -336.664881) (xy 371.670761 -336.612581) (xy 371.693407 -336.562999) (xy 371.722878 -336.517145)
			(xy 371.758575 -336.475952) (xy 371.799771 -336.440259) (xy 371.845628 -336.410791) (xy 371.895211 -336.38815)
			(xy 371.947512 -336.372796) (xy 372.001466 -336.365041) (xy 372.02872 -336.36458) (xy 372.029482 -336.36458)
			(xy 372.041453 -336.364696) (xy 372.065346 -336.366219) (xy 372.077234 -336.367628) (xy 372.090996 -336.368863)
			(xy 372.118323 -336.364892) (xy 372.143589 -336.353747) (xy 372.164947 -336.336242) (xy 372.180837 -336.313657)
			(xy 372.190098 -336.287642) (xy 372.191534 -336.273902) (xy 372.194089 -336.24537) (xy 372.206571 -336.189465)
			(xy 372.227274 -336.136055) (xy 372.255732 -336.086344) (xy 372.291306 -336.041447) (xy 372.333195 -336.002377)
			(xy 372.380457 -335.970012) (xy 372.432028 -335.945079) (xy 372.486747 -335.92814) (xy 372.543385 -335.919577)
			(xy 372.572026 -335.919064) (xy 372.590045 -335.919286) (xy 372.62592 -335.922719) (xy 372.643654 -335.925922)
			(xy 372.658866 -335.928241) (xy 372.689419 -335.924725) (xy 372.71754 -335.91227) (xy 372.740676 -335.892007)
			(xy 372.756729 -335.865774) (xy 372.761002 -335.850992) (xy 372.768437 -335.823959) (xy 372.790061 -335.772233)
			(xy 372.819019 -335.724227) (xy 372.854689 -335.680974) (xy 372.896304 -335.643406) (xy 372.942967 -335.61233)
			(xy 372.993675 -335.588415) (xy 373.047335 -335.572177) (xy 373.102794 -335.563964) (xy 373.130826 -335.563464)
			(xy 373.158077 -335.563954) (xy 373.212023 -335.571713) (xy 373.264316 -335.58707) (xy 373.313891 -335.609712)
			(xy 373.35974 -335.639178) (xy 373.400929 -335.674869) (xy 373.43662 -335.716058) (xy 373.466087 -335.761907)
			(xy 373.488729 -335.811482) (xy 373.504087 -335.863775) (xy 373.511846 -335.917721) (xy 373.512334 -335.944972)
			(xy 373.511872 -335.972547) (xy 373.503922 -336.027121) (xy 373.488198 -336.079982) (xy 373.465027 -336.130028)
			(xy 373.434893 -336.176218) (xy 373.398423 -336.217587) (xy 373.377714 -336.235802) (xy 373.366844 -336.245729)
			(xy 373.350769 -336.27037) (xy 373.342381 -336.298571) (xy 373.342376 -336.327993) (xy 373.350753 -336.356197)
			(xy 373.36682 -336.380844) (xy 373.377714 -336.390742) (xy 373.398391 -336.408989) (xy 373.434853 -336.450357)
			(xy 373.464979 -336.496543) (xy 373.488141 -336.546586) (xy 373.503857 -336.599442) (xy 373.511799 -336.65401)
			(xy 373.511802 -336.709154) (xy 373.503865 -336.763723) (xy 373.488154 -336.81658) (xy 373.464997 -336.866625)
			(xy 373.434875 -336.912815) (xy 373.398417 -336.954186) (xy 373.377714 -336.972402) (xy 373.366844 -336.982329)
			(xy 373.350769 -337.00697) (xy 373.342381 -337.035171) (xy 373.342376 -337.064593) (xy 373.350753 -337.092797)
			(xy 373.36682 -337.117444) (xy 373.377714 -337.127342) (xy 373.398403 -337.145577) (xy 373.434875 -337.186941)
			(xy 373.465009 -337.233126) (xy 373.488179 -337.283169) (xy 373.5039 -337.336028) (xy 373.511845 -337.390599)
			(xy 373.512334 -337.418172) (xy 373.511819 -337.445423) (xy 373.504066 -337.499371) (xy 373.488715 -337.551666)
			(xy 373.466078 -337.601244) (xy 373.436615 -337.647096) (xy 373.400927 -337.688289) (xy 373.35974 -337.723983)
			(xy 373.313892 -337.753452) (xy 373.264317 -337.776096) (xy 373.212024 -337.791455) (xy 373.158077 -337.799215)
			(xy 373.130826 -337.79968) (xy 373.102971 -337.799148) (xy 373.047855 -337.791028) (xy 372.994504 -337.774985)
			(xy 372.944051 -337.75136) (xy 372.897566 -337.720654) (xy 372.856036 -337.683519) (xy 372.820343 -337.640744)
			(xy 372.791244 -337.593237) (xy 372.769358 -337.542005) (xy 372.761764 -337.5152) (xy 372.757496 -337.501082)
			(xy 372.742104 -337.475937) (xy 372.720184 -337.456222) (xy 372.693554 -337.443572) (xy 372.664424 -337.439035)
			(xy 372.64975 -337.440524) (xy 372.636923 -337.442176) (xy 372.61112 -337.443953) (xy 372.598188 -337.44408)
			(xy 372.597426 -337.44408) (xy 372.579795 -337.443842) (xy 372.544687 -337.440537) (xy 372.527322 -337.437476)
			(xy 372.513546 -337.435268) (xy 372.485761 -337.437711) (xy 372.459678 -337.447592) (xy 372.437249 -337.464172)
			(xy 372.420152 -337.48621) (xy 372.409666 -337.512056) (xy 372.407688 -337.525868) (xy 372.404033 -337.553442)
			(xy 372.389802 -337.607212) (xy 372.36791 -337.658344) (xy 372.338821 -337.705752) (xy 372.303152 -337.748431)
			(xy 372.261661 -337.785475) (xy 372.215229 -337.816097) (xy 372.16484 -337.839648) (xy 372.111563 -337.855628)
			(xy 372.056531 -337.863698) (xy 372.02872 -337.864196) (xy 372.001467 -337.863726) (xy 371.947516 -337.855971)
			(xy 371.895217 -337.840617) (xy 371.845636 -337.817976) (xy 371.799783 -337.788509) (xy 371.758589 -337.752816)
			(xy 371.722896 -337.711624) (xy 371.693428 -337.665771) (xy 371.670785 -337.61619) (xy 371.65543 -337.563892)
			(xy 371.647675 -337.509941) (xy 371.647212 -337.482688) (xy 369.526646 -337.482688) (xy 369.525058 -337.492733)
			(xy 369.516406 -337.521296) (xy 369.512434 -337.535221) (xy 369.51151 -337.564145) (xy 369.518761 -337.59216)
			(xy 369.533602 -337.617004) (xy 369.554832 -337.636669) (xy 369.580738 -337.649566) (xy 369.594892 -337.652614)
			(xy 369.620959 -337.657814) (xy 369.671462 -337.67438) (xy 369.719175 -337.697798) (xy 369.763174 -337.727617)
			(xy 369.802605 -337.763256) (xy 369.836705 -337.804026) (xy 369.864813 -337.849136) (xy 369.886384 -337.897713)
			(xy 369.901 -337.948814) (xy 369.908377 -338.001451) (xy 369.908836 -338.028026) (xy 369.907566 -338.059014)
			(xy 369.905534 -338.082636) (xy 370.41582 -338.592922) (xy 373.623332 -338.592922) (xy 373.623332 -338.592668)
			(xy 373.623867 -338.564654) (xy 373.632086 -338.509233) (xy 373.648313 -338.455606) (xy 373.672201 -338.404926)
			(xy 373.703237 -338.358279) (xy 373.72163 -338.337144) (xy 373.731299 -338.325722) (xy 373.74407 -338.298671)
			(xy 373.748448 -338.269079) (xy 373.744057 -338.239489) (xy 373.731275 -338.212444) (xy 373.72163 -338.201)
			(xy 373.703193 -338.179896) (xy 373.672127 -338.133257) (xy 373.648227 -338.082572) (xy 373.632007 -338.028932)
			(xy 373.623818 -337.973495) (xy 373.623332 -337.945476) (xy 373.623332 -337.945222) (xy 373.623818 -337.917971)
			(xy 373.631574 -337.864023) (xy 373.646929 -337.811728) (xy 373.669571 -337.762151) (xy 373.699037 -337.716301)
			(xy 373.734728 -337.67511) (xy 373.775919 -337.639419) (xy 373.821769 -337.609953) (xy 373.871346 -337.587311)
			(xy 373.923641 -337.571956) (xy 373.977589 -337.5642) (xy 374.032091 -337.5642) (xy 374.086039 -337.571956)
			(xy 374.138334 -337.587311) (xy 374.187911 -337.609953) (xy 374.233761 -337.639419) (xy 374.274952 -337.67511)
			(xy 374.310643 -337.716301) (xy 374.340109 -337.762151) (xy 374.362751 -337.811728) (xy 374.378106 -337.864023)
			(xy 374.385862 -337.917971) (xy 374.386348 -337.945222) (xy 374.386348 -337.945476) (xy 374.385845 -337.973491)
			(xy 374.377619 -338.028914) (xy 374.361384 -338.082541) (xy 374.337489 -338.133221) (xy 374.306447 -338.179866)
			(xy 374.28805 -338.201) (xy 374.27843 -338.212462) (xy 374.265642 -338.239497) (xy 374.261249 -338.269079)
			(xy 374.26563 -338.298663) (xy 374.278406 -338.325704) (xy 374.28805 -338.337144) (xy 374.306457 -338.358273)
			(xy 374.337528 -338.404905) (xy 374.361434 -338.455584) (xy 374.37766 -338.509218) (xy 374.385857 -338.56465)
			(xy 374.386348 -338.592668) (xy 374.386348 -338.592922) (xy 374.385862 -338.620173) (xy 374.378106 -338.674121)
			(xy 374.362751 -338.726416) (xy 374.340109 -338.775993) (xy 374.310643 -338.821843) (xy 374.274952 -338.863034)
			(xy 374.233761 -338.898725) (xy 374.187911 -338.928191) (xy 374.138334 -338.950833) (xy 374.086039 -338.966188)
			(xy 374.032091 -338.973944) (xy 373.977589 -338.973944) (xy 373.923641 -338.966188) (xy 373.871346 -338.950833)
			(xy 373.821769 -338.928191) (xy 373.775919 -338.898725) (xy 373.734728 -338.863034) (xy 373.699037 -338.821843)
			(xy 373.669571 -338.775993) (xy 373.646929 -338.726416) (xy 373.631574 -338.674121) (xy 373.623818 -338.620173)
			(xy 373.623332 -338.592922) (xy 370.41582 -338.592922) (xy 370.470176 -338.647278) (xy 370.485739 -338.663521)
			(xy 370.510738 -338.700914) (xy 370.527954 -338.742469) (xy 370.536723 -338.786586) (xy 370.537232 -338.809076)
			(xy 370.537232 -339.73135) (xy 370.536685 -339.753833) (xy 370.527891 -339.797933) (xy 370.510671 -339.839473)
			(xy 370.485685 -339.87686) (xy 370.470176 -339.893148) (xy 369.713256 -340.650068) (xy 369.696998 -340.665614)
			(xy 369.65961 -340.690616) (xy 369.61806 -340.707837) (xy 369.573947 -340.716612) (xy 369.551458 -340.717124)
			(xy 368.48034 -340.717124) (xy 367.548922 -341.648542) (xy 375.220992 -341.648542) (xy 375.221581 -341.618855)
			(xy 375.230773 -341.560198) (xy 375.248942 -341.503673) (xy 375.275649 -341.450645) (xy 375.310249 -341.402396)
			(xy 375.351906 -341.360089) (xy 375.375424 -341.341964) (xy 375.386 -341.333502) (xy 375.402704 -341.312197)
			(xy 375.413223 -341.287251) (xy 375.416816 -341.260418) (xy 375.413232 -341.233583) (xy 375.402723 -341.208634)
			(xy 375.386026 -341.187323) (xy 375.375424 -341.178896) (xy 375.351917 -341.160756) (xy 375.310255 -341.118454)
			(xy 375.275649 -341.070208) (xy 375.248936 -341.017184) (xy 375.230759 -340.960661) (xy 375.221558 -340.902005)
			(xy 375.220992 -340.872318) (xy 375.221478 -340.845067) (xy 375.229234 -340.791119) (xy 375.244589 -340.738824)
			(xy 375.267231 -340.689247) (xy 375.296697 -340.643397) (xy 375.332388 -340.602206) (xy 375.373579 -340.566515)
			(xy 375.419429 -340.537049) (xy 375.469006 -340.514407) (xy 375.521301 -340.499052) (xy 375.575249 -340.491296)
			(xy 375.629751 -340.491296) (xy 375.683699 -340.499052) (xy 375.735994 -340.514407) (xy 375.785571 -340.537049)
			(xy 375.831421 -340.566515) (xy 375.872612 -340.602206) (xy 375.908303 -340.643397) (xy 375.937769 -340.689247)
			(xy 375.960411 -340.738824) (xy 375.975766 -340.791119) (xy 375.983522 -340.845067) (xy 375.984008 -340.872318)
			(xy 375.983463 -340.902006) (xy 375.974262 -340.960666) (xy 375.956084 -341.017192) (xy 375.929369 -341.070219)
			(xy 375.894761 -341.118468) (xy 375.853097 -341.160772) (xy 375.829576 -341.178896) (xy 375.81894 -341.187288)
			(xy 375.802236 -341.208609) (xy 375.791721 -341.233571) (xy 375.788136 -341.260418) (xy 375.791731 -341.287264)
			(xy 375.802254 -341.312222) (xy 375.818966 -341.333537) (xy 375.829576 -341.341964) (xy 375.853064 -341.360127)
			(xy 375.894727 -341.402425) (xy 375.929335 -341.450666) (xy 375.956052 -341.503686) (xy 375.974232 -341.560204)
			(xy 375.983439 -341.618857) (xy 375.984008 -341.648542) (xy 375.983522 -341.675793) (xy 375.975766 -341.729741)
			(xy 375.960411 -341.782036) (xy 375.937769 -341.831613) (xy 375.908303 -341.877463) (xy 375.872612 -341.918654)
			(xy 375.831421 -341.954345) (xy 375.785571 -341.983811) (xy 375.735994 -342.006453) (xy 375.683699 -342.021808)
			(xy 375.629751 -342.029564) (xy 375.575249 -342.029564) (xy 375.521301 -342.021808) (xy 375.469006 -342.006453)
			(xy 375.419429 -341.983811) (xy 375.373579 -341.954345) (xy 375.332388 -341.918654) (xy 375.296697 -341.877463)
			(xy 375.267231 -341.831613) (xy 375.244589 -341.782036) (xy 375.229234 -341.729741) (xy 375.221478 -341.675793)
			(xy 375.220992 -341.648542) (xy 367.548922 -341.648542) (xy 365.841788 -343.355676) (xy 365.841788 -343.944632)
			(xy 367.216178 -343.944632) (xy 367.216178 -343.859936) (xy 367.224229 -343.775622) (xy 367.240258 -343.692456)
			(xy 367.264119 -343.611189) (xy 367.295598 -343.532559) (xy 367.334409 -343.457278) (xy 367.380199 -343.386026)
			(xy 367.432555 -343.31945) (xy 367.491003 -343.258152) (xy 367.555013 -343.202687) (xy 367.624005 -343.153558)
			(xy 367.697355 -343.111209) (xy 367.774398 -343.076025) (xy 367.854437 -343.048323) (xy 367.936746 -343.028355)
			(xy 368.020581 -343.016302) (xy 368.105182 -343.012272) (xy 368.189783 -343.016302) (xy 368.273618 -343.028355)
			(xy 368.355927 -343.048323) (xy 368.435966 -343.076025) (xy 368.513009 -343.111209) (xy 368.586359 -343.153558)
			(xy 368.655351 -343.202687) (xy 368.719361 -343.258152) (xy 368.777809 -343.31945) (xy 368.830165 -343.386026)
			(xy 368.875955 -343.457278) (xy 368.914766 -343.532559) (xy 368.946245 -343.611189) (xy 368.970106 -343.692456)
			(xy 368.986135 -343.775622) (xy 368.994186 -343.859936) (xy 368.99469 -343.902284) (xy 369.740691 -343.902284)
			(xy 369.744727 -343.818837) (xy 369.756799 -343.736169) (xy 369.776792 -343.655052) (xy 369.804521 -343.576243)
			(xy 369.839727 -343.500478) (xy 369.882081 -343.428465) (xy 369.931187 -343.360876) (xy 369.986588 -343.298342)
			(xy 370.047765 -343.241447) (xy 370.114148 -343.190721) (xy 370.185116 -343.14664) (xy 370.260008 -343.109614)
			(xy 370.338124 -343.079988) (xy 370.418734 -343.05804) (xy 370.501086 -343.043975) (xy 370.584412 -343.037923)
			(xy 370.667932 -343.039942) (xy 370.750868 -343.050012) (xy 370.832444 -343.06804) (xy 370.9119 -343.093857)
			(xy 370.988493 -343.127222) (xy 371.061509 -343.167823) (xy 371.130265 -343.215282) (xy 371.194119 -343.269155)
			(xy 371.252476 -343.32894) (xy 371.304791 -343.394077) (xy 371.350574 -343.46396) (xy 371.389399 -343.537935)
			(xy 371.420904 -343.615312) (xy 371.444793 -343.695369) (xy 371.460844 -343.777357) (xy 371.468907 -343.860512)
			(xy 371.469412 -343.902284) (xy 371.468907 -343.944056) (xy 371.460844 -344.027211) (xy 371.444793 -344.109199)
			(xy 371.420904 -344.189256) (xy 371.389399 -344.266633) (xy 371.350574 -344.340608) (xy 371.304791 -344.410491)
			(xy 371.252476 -344.475628) (xy 371.194119 -344.535413) (xy 371.130265 -344.589286) (xy 371.061509 -344.636745)
			(xy 370.988493 -344.677346) (xy 370.9119 -344.710711) (xy 370.832444 -344.736528) (xy 370.750868 -344.754556)
			(xy 370.667932 -344.764626) (xy 370.584412 -344.766645) (xy 370.501086 -344.760593) (xy 370.418734 -344.746528)
			(xy 370.338124 -344.72458) (xy 370.260008 -344.694954) (xy 370.185116 -344.657928) (xy 370.114148 -344.613847)
			(xy 370.047765 -344.563121) (xy 369.986588 -344.506226) (xy 369.931187 -344.443692) (xy 369.882081 -344.376103)
			(xy 369.839727 -344.30409) (xy 369.804521 -344.228325) (xy 369.776792 -344.149516) (xy 369.756799 -344.068399)
			(xy 369.744727 -343.985731) (xy 369.740691 -343.902284) (xy 368.99469 -343.902284) (xy 368.994186 -343.944632)
			(xy 368.986135 -344.028946) (xy 368.970106 -344.112112) (xy 368.946245 -344.193379) (xy 368.914766 -344.272009)
			(xy 368.875955 -344.34729) (xy 368.830165 -344.418542) (xy 368.777809 -344.485118) (xy 368.719361 -344.546416)
			(xy 368.655351 -344.601881) (xy 368.586359 -344.65101) (xy 368.513009 -344.693359) (xy 368.435966 -344.728543)
			(xy 368.355927 -344.756245) (xy 368.273618 -344.776213) (xy 368.189783 -344.788266) (xy 368.105182 -344.792297)
			(xy 368.020581 -344.788266) (xy 367.936746 -344.776213) (xy 367.854437 -344.756245) (xy 367.774398 -344.728543)
			(xy 367.697355 -344.693359) (xy 367.624005 -344.65101) (xy 367.555013 -344.601881) (xy 367.491003 -344.546416)
			(xy 367.432555 -344.485118) (xy 367.380199 -344.418542) (xy 367.334409 -344.34729) (xy 367.295598 -344.272009)
			(xy 367.264119 -344.193379) (xy 367.240258 -344.112112) (xy 367.224229 -344.028946) (xy 367.216178 -343.944632)
			(xy 365.841788 -343.944632) (xy 365.841788 -345.930474) (xy 365.84124 -345.952957) (xy 365.832444 -345.997056)
			(xy 365.815224 -346.038595) (xy 365.790239 -346.075983) (xy 365.774732 -346.092272) (xy 361.906058 -349.960946)
			(xy 361.889841 -349.976555) (xy 361.852458 -350.00162) (xy 361.810898 -350.018898) (xy 361.766764 -350.027723)
			(xy 361.74426 -350.028256) (xy 359.408222 -350.028256) (xy 359.036182 -350.400296) (xy 363.397796 -350.400296)
			(xy 363.397796 -350.3156) (xy 363.405847 -350.231286) (xy 363.421876 -350.14812) (xy 363.445737 -350.066853)
			(xy 363.477216 -349.988223) (xy 363.516027 -349.912942) (xy 363.561817 -349.84169) (xy 363.614173 -349.775114)
			(xy 363.672621 -349.713816) (xy 363.736631 -349.658351) (xy 363.805623 -349.609222) (xy 363.878973 -349.566873)
			(xy 363.956016 -349.531689) (xy 364.036055 -349.503987) (xy 364.118364 -349.484019) (xy 364.202199 -349.471966)
			(xy 364.2868 -349.467936) (xy 364.371401 -349.471966) (xy 364.455236 -349.484019) (xy 364.537545 -349.503987)
			(xy 364.617584 -349.531689) (xy 364.694627 -349.566873) (xy 364.767977 -349.609222) (xy 364.836969 -349.658351)
			(xy 364.900979 -349.713816) (xy 364.959427 -349.775114) (xy 365.011783 -349.84169) (xy 365.057573 -349.912942)
			(xy 365.096384 -349.988223) (xy 365.127863 -350.066853) (xy 365.151724 -350.14812) (xy 365.167753 -350.231286)
			(xy 365.175804 -350.3156) (xy 365.176308 -350.357948) (xy 365.922309 -350.357948) (xy 365.926345 -350.274501)
			(xy 365.938417 -350.191833) (xy 365.95841 -350.110716) (xy 365.986139 -350.031907) (xy 366.021345 -349.956142)
			(xy 366.063699 -349.884129) (xy 366.112805 -349.81654) (xy 366.168206 -349.754006) (xy 366.229383 -349.697111)
			(xy 366.295766 -349.646385) (xy 366.366734 -349.602304) (xy 366.441626 -349.565278) (xy 366.519742 -349.535652)
			(xy 366.600352 -349.513704) (xy 366.682704 -349.499639) (xy 366.76603 -349.493587) (xy 366.84955 -349.495606)
			(xy 366.932486 -349.505676) (xy 367.014062 -349.523704) (xy 367.093518 -349.549521) (xy 367.170111 -349.582886)
			(xy 367.243127 -349.623487) (xy 367.311883 -349.670946) (xy 367.375737 -349.724819) (xy 367.434094 -349.784604)
			(xy 367.486409 -349.849741) (xy 367.532192 -349.919624) (xy 367.571017 -349.993599) (xy 367.602522 -350.070976)
			(xy 367.626411 -350.151033) (xy 367.642462 -350.233021) (xy 367.650525 -350.316176) (xy 367.65103 -350.357948)
			(xy 367.650525 -350.39972) (xy 367.642462 -350.482875) (xy 367.626411 -350.564863) (xy 367.602522 -350.64492)
			(xy 367.571017 -350.722297) (xy 367.532192 -350.796272) (xy 367.486409 -350.866155) (xy 367.434094 -350.931292)
			(xy 367.375737 -350.991077) (xy 367.311883 -351.04495) (xy 367.243127 -351.092409) (xy 367.170111 -351.13301)
			(xy 367.093518 -351.166375) (xy 367.014062 -351.192192) (xy 366.932486 -351.21022) (xy 366.84955 -351.22029)
			(xy 366.76603 -351.222309) (xy 366.682704 -351.216257) (xy 366.600352 -351.202192) (xy 366.519742 -351.180244)
			(xy 366.441626 -351.150618) (xy 366.366734 -351.113592) (xy 366.295766 -351.069511) (xy 366.229383 -351.018785)
			(xy 366.168206 -350.96189) (xy 366.112805 -350.899356) (xy 366.063699 -350.831767) (xy 366.021345 -350.759754)
			(xy 365.986139 -350.683989) (xy 365.95841 -350.60518) (xy 365.938417 -350.524063) (xy 365.926345 -350.441395)
			(xy 365.922309 -350.357948) (xy 365.176308 -350.357948) (xy 365.175804 -350.400296) (xy 365.167753 -350.48461)
			(xy 365.151724 -350.567776) (xy 365.127863 -350.649043) (xy 365.096384 -350.727673) (xy 365.057573 -350.802954)
			(xy 365.011783 -350.874206) (xy 364.959427 -350.940782) (xy 364.900979 -351.00208) (xy 364.836969 -351.057545)
			(xy 364.767977 -351.106674) (xy 364.694627 -351.149023) (xy 364.617584 -351.184207) (xy 364.537545 -351.211909)
			(xy 364.455236 -351.231877) (xy 364.371401 -351.24393) (xy 364.2868 -351.247961) (xy 364.202199 -351.24393)
			(xy 364.118364 -351.231877) (xy 364.036055 -351.211909) (xy 363.956016 -351.184207) (xy 363.878973 -351.149023)
			(xy 363.805623 -351.106674) (xy 363.736631 -351.057545) (xy 363.672621 -351.00208) (xy 363.614173 -350.940782)
			(xy 363.561817 -350.874206) (xy 363.516027 -350.802954) (xy 363.477216 -350.727673) (xy 363.445737 -350.649043)
			(xy 363.421876 -350.567776) (xy 363.405847 -350.48461) (xy 363.397796 -350.400296) (xy 359.036182 -350.400296)
			(xy 358.399588 -351.03689) (xy 358.399588 -351.457768) (xy 359.071416 -351.457768) (xy 359.075487 -351.402146)
			(xy 359.087613 -351.347709) (xy 359.107536 -351.295618) (xy 359.134832 -351.246983) (xy 359.168918 -351.20284)
			(xy 359.209067 -351.164131) (xy 359.254425 -351.13168) (xy 359.304025 -351.106179) (xy 359.356809 -351.088172)
			(xy 359.411652 -351.078042) (xy 359.467386 -351.076005) (xy 359.522823 -351.082105) (xy 359.57678 -351.096211)
			(xy 359.628109 -351.118023) (xy 359.675715 -351.147077) (xy 359.718583 -351.182752) (xy 359.7558 -351.224289)
			(xy 359.786573 -351.270802) (xy 359.810245 -351.321299) (xy 359.821423 -351.358454) (xy 360.956858 -351.358454)
			(xy 360.960929 -351.302832) (xy 360.973055 -351.248395) (xy 360.992978 -351.196304) (xy 361.020274 -351.147669)
			(xy 361.05436 -351.103526) (xy 361.094509 -351.064817) (xy 361.139867 -351.032366) (xy 361.189467 -351.006865)
			(xy 361.242251 -350.988858) (xy 361.297094 -350.978728) (xy 361.352828 -350.976691) (xy 361.408265 -350.982791)
			(xy 361.462222 -350.996897) (xy 361.513551 -351.018709) (xy 361.561157 -351.047763) (xy 361.604025 -351.083438)
			(xy 361.641242 -351.124975) (xy 361.672015 -351.171488) (xy 361.695687 -351.221985) (xy 361.711755 -351.275392)
			(xy 361.719875 -351.330568) (xy 361.720384 -351.358454) (xy 361.719875 -351.38634) (xy 361.711755 -351.441516)
			(xy 361.695687 -351.494923) (xy 361.672015 -351.54542) (xy 361.641242 -351.591933) (xy 361.604025 -351.63347)
			(xy 361.561157 -351.669145) (xy 361.513551 -351.698199) (xy 361.462222 -351.720011) (xy 361.408265 -351.734117)
			(xy 361.352828 -351.740217) (xy 361.297094 -351.73818) (xy 361.242251 -351.72805) (xy 361.189467 -351.710043)
			(xy 361.139867 -351.684542) (xy 361.094509 -351.652091) (xy 361.05436 -351.613382) (xy 361.020274 -351.569239)
			(xy 360.992978 -351.520604) (xy 360.973055 -351.468513) (xy 360.960929 -351.414076) (xy 360.956858 -351.358454)
			(xy 359.821423 -351.358454) (xy 359.826313 -351.374706) (xy 359.834433 -351.429882) (xy 359.834942 -351.457768)
			(xy 359.834433 -351.485654) (xy 359.826313 -351.54083) (xy 359.810245 -351.594237) (xy 359.786573 -351.644734)
			(xy 359.7558 -351.691247) (xy 359.718583 -351.732784) (xy 359.675715 -351.768459) (xy 359.628109 -351.797513)
			(xy 359.57678 -351.819325) (xy 359.522823 -351.833431) (xy 359.467386 -351.839531) (xy 359.411652 -351.837494)
			(xy 359.356809 -351.827364) (xy 359.304025 -351.809357) (xy 359.254425 -351.783856) (xy 359.209067 -351.751405)
			(xy 359.168918 -351.712696) (xy 359.134832 -351.668553) (xy 359.107536 -351.619918) (xy 359.087613 -351.567827)
			(xy 359.075487 -351.51339) (xy 359.071416 -351.457768) (xy 358.399588 -351.457768) (xy 358.399588 -351.907348)
			(xy 358.398964 -351.929841) (xy 358.390124 -351.973952) (xy 358.372853 -352.015493) (xy 358.347813 -352.052869)
			(xy 358.332278 -352.069146) (xy 358.005354 -352.396298) (xy 358.510076 -352.396298) (xy 358.514147 -352.340676)
			(xy 358.526273 -352.286239) (xy 358.546196 -352.234148) (xy 358.573492 -352.185513) (xy 358.607578 -352.14137)
			(xy 358.647727 -352.102661) (xy 358.693085 -352.07021) (xy 358.742685 -352.044709) (xy 358.795469 -352.026702)
			(xy 358.850312 -352.016572) (xy 358.906046 -352.014535) (xy 358.961483 -352.020635) (xy 359.01544 -352.034741)
			(xy 359.066769 -352.056553) (xy 359.114375 -352.085607) (xy 359.157243 -352.121282) (xy 359.19446 -352.162819)
			(xy 359.225233 -352.209332) (xy 359.248905 -352.259829) (xy 359.264973 -352.313236) (xy 359.273093 -352.368412)
			(xy 359.273602 -352.396298) (xy 359.273301 -352.412808) (xy 360.041442 -352.412808) (xy 360.045513 -352.357186)
			(xy 360.057639 -352.302749) (xy 360.077562 -352.250658) (xy 360.104858 -352.202023) (xy 360.138944 -352.15788)
			(xy 360.179093 -352.119171) (xy 360.224451 -352.08672) (xy 360.274051 -352.061219) (xy 360.326835 -352.043212)
			(xy 360.381678 -352.033082) (xy 360.437412 -352.031045) (xy 360.492849 -352.037145) (xy 360.546806 -352.051251)
			(xy 360.598135 -352.073063) (xy 360.645741 -352.102117) (xy 360.688609 -352.137792) (xy 360.725826 -352.179329)
			(xy 360.756599 -352.225842) (xy 360.780271 -352.276339) (xy 360.796339 -352.329746) (xy 360.804459 -352.384922)
			(xy 360.804968 -352.412808) (xy 360.804459 -352.440694) (xy 360.796339 -352.49587) (xy 360.780271 -352.549277)
			(xy 360.756599 -352.599774) (xy 360.725826 -352.646287) (xy 360.688609 -352.687824) (xy 360.645741 -352.723499)
			(xy 360.598135 -352.752553) (xy 360.546806 -352.774365) (xy 360.492849 -352.788471) (xy 360.437412 -352.794571)
			(xy 360.381678 -352.792534) (xy 360.326835 -352.782404) (xy 360.274051 -352.764397) (xy 360.224451 -352.738896)
			(xy 360.179093 -352.706445) (xy 360.138944 -352.667736) (xy 360.104858 -352.623593) (xy 360.077562 -352.574958)
			(xy 360.057639 -352.522867) (xy 360.045513 -352.46843) (xy 360.041442 -352.412808) (xy 359.273301 -352.412808)
			(xy 359.273093 -352.424184) (xy 359.264973 -352.47936) (xy 359.248905 -352.532767) (xy 359.225233 -352.583264)
			(xy 359.19446 -352.629777) (xy 359.157243 -352.671314) (xy 359.114375 -352.706989) (xy 359.066769 -352.736043)
			(xy 359.01544 -352.757855) (xy 358.961483 -352.771961) (xy 358.906046 -352.778061) (xy 358.850312 -352.776024)
			(xy 358.795469 -352.765894) (xy 358.742685 -352.747887) (xy 358.693085 -352.722386) (xy 358.647727 -352.689935)
			(xy 358.607578 -352.651226) (xy 358.573492 -352.607083) (xy 358.546196 -352.558448) (xy 358.526273 -352.506357)
			(xy 358.514147 -352.45192) (xy 358.510076 -352.396298) (xy 358.005354 -352.396298) (xy 357.967788 -352.43389)
			(xy 357.967788 -353.488498) (xy 358.420414 -353.488498) (xy 358.424485 -353.432876) (xy 358.436611 -353.378439)
			(xy 358.456534 -353.326348) (xy 358.48383 -353.277713) (xy 358.517916 -353.23357) (xy 358.558065 -353.194861)
			(xy 358.603423 -353.16241) (xy 358.653023 -353.136909) (xy 358.705807 -353.118902) (xy 358.76065 -353.108772)
			(xy 358.816384 -353.106735) (xy 358.871821 -353.112835) (xy 358.925778 -353.126941) (xy 358.977107 -353.148753)
			(xy 359.024713 -353.177807) (xy 359.067581 -353.213482) (xy 359.104798 -353.255019) (xy 359.135571 -353.301532)
			(xy 359.159243 -353.352029) (xy 359.175311 -353.405436) (xy 359.183431 -353.460612) (xy 359.18394 -353.488498)
			(xy 359.183431 -353.516384) (xy 359.175311 -353.57156) (xy 359.159243 -353.624967) (xy 359.135571 -353.675464)
			(xy 359.12315 -353.694238) (xy 360.057952 -353.694238) (xy 360.062023 -353.638616) (xy 360.074149 -353.584179)
			(xy 360.094072 -353.532088) (xy 360.121368 -353.483453) (xy 360.155454 -353.43931) (xy 360.195603 -353.400601)
			(xy 360.240961 -353.36815) (xy 360.290561 -353.342649) (xy 360.343345 -353.324642) (xy 360.398188 -353.314512)
			(xy 360.453922 -353.312475) (xy 360.509359 -353.318575) (xy 360.563316 -353.332681) (xy 360.614645 -353.354493)
			(xy 360.662251 -353.383547) (xy 360.705119 -353.419222) (xy 360.742336 -353.460759) (xy 360.773109 -353.507272)
			(xy 360.796781 -353.557769) (xy 360.812849 -353.611176) (xy 360.820969 -353.666352) (xy 360.821478 -353.694238)
			(xy 360.820969 -353.722124) (xy 360.812849 -353.7773) (xy 360.796781 -353.830707) (xy 360.773109 -353.881204)
			(xy 360.742336 -353.927717) (xy 360.705119 -353.969254) (xy 360.662251 -354.004929) (xy 360.614645 -354.033983)
			(xy 360.563316 -354.055795) (xy 360.509359 -354.069901) (xy 360.453922 -354.076001) (xy 360.398188 -354.073964)
			(xy 360.343345 -354.063834) (xy 360.290561 -354.045827) (xy 360.240961 -354.020326) (xy 360.195603 -353.987875)
			(xy 360.155454 -353.949166) (xy 360.121368 -353.905023) (xy 360.094072 -353.856388) (xy 360.074149 -353.804297)
			(xy 360.062023 -353.74986) (xy 360.057952 -353.694238) (xy 359.12315 -353.694238) (xy 359.104798 -353.721977)
			(xy 359.067581 -353.763514) (xy 359.024713 -353.799189) (xy 358.977107 -353.828243) (xy 358.925778 -353.850055)
			(xy 358.871821 -353.864161) (xy 358.816384 -353.870261) (xy 358.76065 -353.868224) (xy 358.705807 -353.858094)
			(xy 358.653023 -353.840087) (xy 358.603423 -353.814586) (xy 358.558065 -353.782135) (xy 358.517916 -353.743426)
			(xy 358.48383 -353.699283) (xy 358.456534 -353.650648) (xy 358.436611 -353.598557) (xy 358.424485 -353.54412)
			(xy 358.420414 -353.488498) (xy 357.967788 -353.488498) (xy 357.967788 -354.749608) (xy 359.185462 -354.749608)
			(xy 359.189533 -354.693986) (xy 359.201659 -354.639549) (xy 359.221582 -354.587458) (xy 359.248878 -354.538823)
			(xy 359.282964 -354.49468) (xy 359.323113 -354.455971) (xy 359.368471 -354.42352) (xy 359.418071 -354.398019)
			(xy 359.470855 -354.380012) (xy 359.525698 -354.369882) (xy 359.581432 -354.367845) (xy 359.636869 -354.373945)
			(xy 359.690826 -354.388051) (xy 359.742155 -354.409863) (xy 359.789761 -354.438917) (xy 359.832629 -354.474592)
			(xy 359.869846 -354.516129) (xy 359.900619 -354.562642) (xy 359.924291 -354.613139) (xy 359.940359 -354.666546)
			(xy 359.948479 -354.721722) (xy 359.948988 -354.749608) (xy 359.948479 -354.777494) (xy 359.940359 -354.83267)
			(xy 359.924291 -354.886077) (xy 359.900619 -354.936574) (xy 359.883157 -354.962968) (xy 360.296712 -354.962968)
			(xy 360.300783 -354.907346) (xy 360.312909 -354.852909) (xy 360.332832 -354.800818) (xy 360.360128 -354.752183)
			(xy 360.394214 -354.70804) (xy 360.434363 -354.669331) (xy 360.479721 -354.63688) (xy 360.529321 -354.611379)
			(xy 360.582105 -354.593372) (xy 360.636948 -354.583242) (xy 360.692682 -354.581205) (xy 360.748119 -354.587305)
			(xy 360.802076 -354.601411) (xy 360.853405 -354.623223) (xy 360.901011 -354.652277) (xy 360.943879 -354.687952)
			(xy 360.981096 -354.729489) (xy 360.987685 -354.739448) (xy 361.378752 -354.739448) (xy 361.382823 -354.683826)
			(xy 361.394949 -354.629389) (xy 361.414872 -354.577298) (xy 361.442168 -354.528663) (xy 361.476254 -354.48452)
			(xy 361.516403 -354.445811) (xy 361.561761 -354.41336) (xy 361.611361 -354.387859) (xy 361.664145 -354.369852)
			(xy 361.718988 -354.359722) (xy 361.774722 -354.357685) (xy 361.830159 -354.363785) (xy 361.884116 -354.377891)
			(xy 361.935445 -354.399703) (xy 361.983051 -354.428757) (xy 362.025919 -354.464432) (xy 362.063136 -354.505969)
			(xy 362.093909 -354.552482) (xy 362.117581 -354.602979) (xy 362.133649 -354.656386) (xy 362.141769 -354.711562)
			(xy 362.142278 -354.739448) (xy 362.141769 -354.767334) (xy 362.133649 -354.82251) (xy 362.117581 -354.875917)
			(xy 362.093909 -354.926414) (xy 362.063136 -354.972927) (xy 362.025919 -355.014464) (xy 361.983051 -355.050139)
			(xy 361.935445 -355.079193) (xy 361.884116 -355.101005) (xy 361.830159 -355.115111) (xy 361.774722 -355.121211)
			(xy 361.718988 -355.119174) (xy 361.664145 -355.109044) (xy 361.611361 -355.091037) (xy 361.561761 -355.065536)
			(xy 361.516403 -355.033085) (xy 361.476254 -354.994376) (xy 361.442168 -354.950233) (xy 361.414872 -354.901598)
			(xy 361.394949 -354.849507) (xy 361.382823 -354.79507) (xy 361.378752 -354.739448) (xy 360.987685 -354.739448)
			(xy 361.011869 -354.776002) (xy 361.035541 -354.826499) (xy 361.051609 -354.879906) (xy 361.059729 -354.935082)
			(xy 361.060238 -354.962968) (xy 361.059729 -354.990854) (xy 361.051609 -355.04603) (xy 361.035541 -355.099437)
			(xy 361.011869 -355.149934) (xy 360.981096 -355.196447) (xy 360.943879 -355.237984) (xy 360.901011 -355.273659)
			(xy 360.853405 -355.302713) (xy 360.802076 -355.324525) (xy 360.748119 -355.338631) (xy 360.692682 -355.344731)
			(xy 360.636948 -355.342694) (xy 360.582105 -355.332564) (xy 360.529321 -355.314557) (xy 360.479721 -355.289056)
			(xy 360.434363 -355.256605) (xy 360.394214 -355.217896) (xy 360.360128 -355.173753) (xy 360.332832 -355.125118)
			(xy 360.312909 -355.073027) (xy 360.300783 -355.01859) (xy 360.296712 -354.962968) (xy 359.883157 -354.962968)
			(xy 359.869846 -354.983087) (xy 359.832629 -355.024624) (xy 359.789761 -355.060299) (xy 359.742155 -355.089353)
			(xy 359.690826 -355.111165) (xy 359.636869 -355.125271) (xy 359.581432 -355.131371) (xy 359.525698 -355.129334)
			(xy 359.470855 -355.119204) (xy 359.418071 -355.101197) (xy 359.368471 -355.075696) (xy 359.323113 -355.043245)
			(xy 359.282964 -355.004536) (xy 359.248878 -354.960393) (xy 359.221582 -354.911758) (xy 359.201659 -354.859667)
			(xy 359.189533 -354.80523) (xy 359.185462 -354.749608) (xy 357.967788 -354.749608) (xy 357.967788 -354.871528)
			(xy 357.967213 -354.894024) (xy 357.958358 -354.938137) (xy 357.941073 -354.979678) (xy 357.916019 -355.017051)
			(xy 357.900478 -355.033326) (xy 356.77729 -356.156514) (xy 358.86593 -356.156514) (xy 358.870001 -356.100892)
			(xy 358.882127 -356.046455) (xy 358.90205 -355.994364) (xy 358.929346 -355.945729) (xy 358.963432 -355.901586)
			(xy 359.003581 -355.862877) (xy 359.048939 -355.830426) (xy 359.098539 -355.804925) (xy 359.151323 -355.786918)
			(xy 359.206166 -355.776788) (xy 359.2619 -355.774751) (xy 359.317337 -355.780851) (xy 359.371294 -355.794957)
			(xy 359.422623 -355.816769) (xy 359.470229 -355.845823) (xy 359.513097 -355.881498) (xy 359.550314 -355.923035)
			(xy 359.581087 -355.969548) (xy 359.604759 -356.020045) (xy 359.620827 -356.073452) (xy 359.628947 -356.128628)
			(xy 359.629456 -356.156514) (xy 359.628947 -356.1844) (xy 359.620827 -356.239576) (xy 359.604759 -356.292983)
			(xy 359.581087 -356.34348) (xy 359.550314 -356.389993) (xy 359.513097 -356.43153) (xy 359.470229 -356.467205)
			(xy 359.422623 -356.496259) (xy 359.371294 -356.518071) (xy 359.317337 -356.532177) (xy 359.2619 -356.538277)
			(xy 359.206166 -356.53624) (xy 359.151323 -356.52611) (xy 359.098539 -356.508103) (xy 359.048939 -356.482602)
			(xy 359.003581 -356.450151) (xy 358.963432 -356.411442) (xy 358.929346 -356.367299) (xy 358.90205 -356.318664)
			(xy 358.882127 -356.266573) (xy 358.870001 -356.212136) (xy 358.86593 -356.156514) (xy 356.77729 -356.156514)
			(xy 355.932232 -357.001572) (xy 355.932232 -363.363764) (xy 355.931693 -363.386248) (xy 355.922897 -363.430348)
			(xy 355.905674 -363.471888) (xy 355.880686 -363.509274) (xy 355.865176 -363.525562) (xy 355.00437 -364.386368)
			(xy 355.566726 -364.386368) (xy 355.567255 -364.359221) (xy 355.574957 -364.305477) (xy 355.590199 -364.253367)
			(xy 355.612676 -364.203945) (xy 355.641931 -364.158208) (xy 355.677375 -364.11708) (xy 355.718291 -364.081392)
			(xy 355.763854 -364.051866) (xy 355.813142 -364.029096) (xy 355.839014 -364.020862) (xy 355.85146 -364.017052)
			(xy 357.128064 -362.740702) (xy 357.128064 -358.720644) (xy 357.128609 -358.69816) (xy 357.137403 -358.654061)
			(xy 357.154624 -358.612521) (xy 357.179611 -358.575134) (xy 357.19512 -358.558846) (xy 357.850694 -357.903272)
			(xy 357.866937 -357.887709) (xy 357.904329 -357.862708) (xy 357.945884 -357.845492) (xy 357.990002 -357.836724)
			(xy 358.012492 -357.836216) (xy 358.62387 -357.836216) (xy 360.801158 -355.658928) (xy 360.817426 -355.643384)
			(xy 360.854779 -355.618312) (xy 360.875326 -355.609144) (xy 361.247182 -355.454966) (xy 361.26818 -355.446854)
			(xy 361.31231 -355.43802) (xy 361.334812 -355.43744) (xy 362.662724 -355.43744) (xy 362.870496 -355.229668)
			(xy 362.870496 -354.006404) (xy 362.871095 -353.98391) (xy 362.879943 -353.939798) (xy 362.897222 -353.898257)
			(xy 362.922268 -353.860883) (xy 362.937806 -353.844606) (xy 364.554262 -352.22815) (xy 364.570513 -352.212578)
			(xy 364.607884 -352.187506) (xy 364.649433 -352.170219) (xy 364.693559 -352.161381) (xy 364.71606 -352.16084)
			(xy 367.951258 -352.16084) (xy 372.854474 -347.257878) (xy 372.870724 -347.242305) (xy 372.908095 -347.217232)
			(xy 372.949645 -347.199945) (xy 372.993771 -347.191108) (xy 373.016272 -347.190568) (xy 374.21185 -347.190568)
			(xy 378.339604 -343.063068) (xy 378.339604 -342.41359) (xy 377.74245 -341.816436) (xy 377.718828 -341.818468)
			(xy 377.68784 -341.819738) (xy 377.660589 -341.819208) (xy 377.606643 -341.811457) (xy 377.554348 -341.796107)
			(xy 377.50477 -341.773472) (xy 377.458918 -341.744011) (xy 377.417726 -341.708324) (xy 377.382031 -341.667138)
			(xy 377.352562 -341.621292) (xy 377.329917 -341.571718) (xy 377.314558 -341.519426) (xy 377.306797 -341.46548)
			(xy 377.306332 -341.43823) (xy 377.306332 -341.437976) (xy 377.306911 -341.408137) (xy 377.316224 -341.349191)
			(xy 377.324874 -341.320628) (xy 377.328947 -341.306729) (xy 377.329854 -341.27779) (xy 377.322584 -341.249764)
			(xy 377.307724 -341.224915) (xy 377.286474 -341.205249) (xy 377.26055 -341.192355) (xy 377.246388 -341.18931)
			(xy 377.213548 -341.182731) (xy 377.150696 -341.159605) (xy 377.12142 -341.143336) (xy 377.108428 -341.136353)
			(xy 377.079802 -341.129314) (xy 377.050359 -341.13075) (xy 377.022554 -341.140542) (xy 376.998708 -341.157871)
			(xy 376.980809 -341.181294) (xy 376.975116 -341.194898) (xy 376.964422 -341.221675) (xy 376.936135 -341.271918)
			(xy 376.900605 -341.317328) (xy 376.858643 -341.356871) (xy 376.811205 -341.389645) (xy 376.759374 -341.414902)
			(xy 376.70433 -341.432068) (xy 376.647329 -341.440749) (xy 376.6185 -341.441278) (xy 376.591247 -341.440852)
			(xy 376.537295 -341.433095) (xy 376.484996 -341.417739) (xy 376.435415 -341.395096) (xy 376.389561 -341.365627)
			(xy 376.348367 -341.329933) (xy 376.312673 -341.288739) (xy 376.283204 -341.242885) (xy 376.260561 -341.193304)
			(xy 376.245205 -341.141005) (xy 376.237448 -341.087053) (xy 376.237448 -341.032547) (xy 376.245205 -340.978595)
			(xy 376.260561 -340.926296) (xy 376.283204 -340.876715) (xy 376.312673 -340.830861) (xy 376.348367 -340.789667)
			(xy 376.389561 -340.753973) (xy 376.435415 -340.724504) (xy 376.484996 -340.701861) (xy 376.537295 -340.686505)
			(xy 376.591247 -340.678748) (xy 376.6185 -340.678262) (xy 376.618754 -340.678262) (xy 376.643957 -340.678679)
			(xy 376.693925 -340.685313) (xy 376.742579 -340.698484) (xy 376.78907 -340.717962) (xy 376.811032 -340.730332)
			(xy 376.823986 -340.737393) (xy 376.852628 -340.744427) (xy 376.882085 -340.74298) (xy 376.909899 -340.733173)
			(xy 376.93375 -340.715825) (xy 376.951646 -340.692384) (xy 376.957336 -340.67877) (xy 376.968053 -340.652003)
			(xy 376.996339 -340.601763) (xy 377.031867 -340.556355) (xy 377.073826 -340.516813) (xy 377.12126 -340.484038)
			(xy 377.173088 -340.458779) (xy 377.228127 -340.44161) (xy 377.285124 -340.432922) (xy 377.313952 -340.43239)
			(xy 377.341204 -340.4329) (xy 377.395153 -340.44065) (xy 377.44745 -340.456) (xy 377.497029 -340.478637)
			(xy 377.542883 -340.5081) (xy 377.584076 -340.543789) (xy 377.61977 -340.584977) (xy 377.649239 -340.630827)
			(xy 377.671882 -340.680403) (xy 377.687239 -340.732698) (xy 377.694996 -340.786646) (xy 377.69546 -340.813898)
			(xy 377.69546 -340.814152) (xy 377.694888 -340.843991) (xy 377.68557 -340.902937) (xy 377.676918 -340.9315)
			(xy 377.672932 -340.945422) (xy 377.672009 -340.974348) (xy 377.679262 -341.002366) (xy 377.694105 -341.027211)
			(xy 377.715339 -341.046875) (xy 377.741249 -341.059771) (xy 377.755404 -341.062818) (xy 377.781473 -341.068005)
			(xy 377.831977 -341.084573) (xy 377.87969 -341.107993) (xy 377.923689 -341.137813) (xy 377.96312 -341.173454)
			(xy 377.99722 -341.214225) (xy 378.025327 -341.259337) (xy 378.046897 -341.307914) (xy 378.061513 -341.359017)
			(xy 378.06889 -341.411654) (xy 378.069348 -341.43823) (xy 378.068078 -341.469218) (xy 378.066046 -341.49284)
			(xy 378.730256 -342.15705) (xy 378.745803 -342.173308) (xy 378.770806 -342.210695) (xy 378.788026 -342.252246)
			(xy 378.7968 -342.296359) (xy 378.797312 -342.318848) (xy 378.797312 -343.15781) (xy 378.796717 -343.180291)
			(xy 378.787935 -343.224387) (xy 378.770728 -343.265926) (xy 378.745757 -343.303316) (xy 378.730256 -343.319608)
			(xy 374.61063 -347.439234) (xy 383.381504 -347.439234) (xy 383.382082 -347.409547) (xy 383.391276 -347.350889)
			(xy 383.409446 -347.294363) (xy 383.436155 -347.241336) (xy 383.470757 -347.193086) (xy 383.512417 -347.15078)
			(xy 383.535936 -347.132656) (xy 383.546519 -347.124203) (xy 383.563221 -347.102895) (xy 383.573738 -347.077948)
			(xy 383.57733 -347.051113) (xy 383.573745 -347.024278) (xy 383.563235 -346.999328) (xy 383.546538 -346.978015)
			(xy 383.535936 -346.969588) (xy 383.512428 -346.95145) (xy 383.470765 -346.909147) (xy 383.436159 -346.860901)
			(xy 383.409446 -346.807877) (xy 383.39127 -346.751353) (xy 383.38207 -346.692697) (xy 383.381504 -346.66301)
			(xy 383.38199 -346.635759) (xy 383.389746 -346.581811) (xy 383.405101 -346.529516) (xy 383.427743 -346.479939)
			(xy 383.457209 -346.434089) (xy 383.4929 -346.392898) (xy 383.534091 -346.357207) (xy 383.579941 -346.327741)
			(xy 383.629518 -346.305099) (xy 383.681813 -346.289744) (xy 383.735761 -346.281988) (xy 383.790263 -346.281988)
			(xy 383.844211 -346.289744) (xy 383.896506 -346.305099) (xy 383.946083 -346.327741) (xy 383.991933 -346.357207)
			(xy 384.033124 -346.392898) (xy 384.068815 -346.434089) (xy 384.098281 -346.479939) (xy 384.120923 -346.529516)
			(xy 384.136278 -346.581811) (xy 384.144034 -346.635759) (xy 384.14452 -346.66301) (xy 384.143964 -346.692698)
			(xy 384.134764 -346.751357) (xy 384.116589 -346.807882) (xy 384.089876 -346.860909) (xy 384.05527 -346.909158)
			(xy 384.013608 -346.951464) (xy 383.990088 -346.969588) (xy 383.979459 -346.977989) (xy 383.962753 -346.999307)
			(xy 383.952237 -347.024267) (xy 383.948649 -347.051113) (xy 383.952243 -347.077958) (xy 383.962766 -347.102915)
			(xy 383.979478 -347.12423) (xy 383.990088 -347.132656) (xy 384.013622 -347.150762) (xy 384.055282 -347.193072)
			(xy 384.089884 -347.241325) (xy 384.116593 -347.294356) (xy 384.134764 -347.350884) (xy 384.143958 -347.409545)
			(xy 384.14452 -347.439234) (xy 384.144034 -347.466485) (xy 384.136278 -347.520433) (xy 384.120923 -347.572728)
			(xy 384.098281 -347.622305) (xy 384.068815 -347.668155) (xy 384.033124 -347.709346) (xy 383.991933 -347.745037)
			(xy 383.946083 -347.774503) (xy 383.896506 -347.797145) (xy 383.844211 -347.8125) (xy 383.790263 -347.820256)
			(xy 383.735761 -347.820256) (xy 383.681813 -347.8125) (xy 383.629518 -347.797145) (xy 383.579941 -347.774503)
			(xy 383.534091 -347.745037) (xy 383.4929 -347.709346) (xy 383.457209 -347.668155) (xy 383.427743 -347.622305)
			(xy 383.405101 -347.572728) (xy 383.389746 -347.520433) (xy 383.38199 -347.466485) (xy 383.381504 -347.439234)
			(xy 374.61063 -347.439234) (xy 374.46839 -347.581474) (xy 374.452148 -347.597056) (xy 374.414775 -347.622129)
			(xy 374.373223 -347.639415) (xy 374.329094 -347.648247) (xy 374.306592 -347.648784) (xy 373.111014 -347.648784)
			(xy 368.207798 -352.551746) (xy 368.191564 -352.567336) (xy 368.154187 -352.592405) (xy 368.112632 -352.609687)
			(xy 368.068502 -352.618519) (xy 368.046 -352.619056) (xy 364.810802 -352.619056) (xy 363.328712 -354.101146)
			(xy 363.328712 -354.687886) (xy 364.22584 -354.687886) (xy 364.226278 -354.661506) (xy 364.233533 -354.609247)
			(xy 364.247918 -354.558486) (xy 364.269157 -354.51019) (xy 364.296845 -354.46528) (xy 364.330456 -354.424611)
			(xy 364.369348 -354.38896) (xy 364.41278 -354.359006) (xy 364.436152 -354.346764) (xy 364.448524 -354.340084)
			(xy 364.469257 -354.321106) (xy 364.484021 -354.297188) (xy 364.491693 -354.270148) (xy 364.491692 -354.24204)
			(xy 364.484016 -354.215001) (xy 364.469249 -354.191084) (xy 364.448514 -354.172109) (xy 364.436152 -354.165408)
			(xy 364.412765 -354.153197) (xy 364.369342 -354.123229) (xy 364.330458 -354.087569) (xy 364.296855 -354.046894)
			(xy 364.26917 -354.001981) (xy 364.247932 -353.953685) (xy 364.233546 -353.902924) (xy 364.226284 -353.850666)
			(xy 364.22584 -353.824286) (xy 364.226326 -353.797035) (xy 364.234082 -353.743087) (xy 364.249437 -353.690792)
			(xy 364.272079 -353.641215) (xy 364.301545 -353.595365) (xy 364.337236 -353.554174) (xy 364.378427 -353.518483)
			(xy 364.424277 -353.489017) (xy 364.473854 -353.466375) (xy 364.526149 -353.45102) (xy 364.580097 -353.443264)
			(xy 364.634599 -353.443264) (xy 364.688547 -353.45102) (xy 364.740842 -353.466375) (xy 364.790419 -353.489017)
			(xy 364.836269 -353.518483) (xy 364.87746 -353.554174) (xy 364.913151 -353.595365) (xy 364.942617 -353.641215)
			(xy 364.965259 -353.690792) (xy 364.980614 -353.743087) (xy 364.98776 -353.79279) (xy 366.64722 -353.79279)
			(xy 366.651291 -353.737168) (xy 366.663417 -353.682731) (xy 366.68334 -353.63064) (xy 366.710636 -353.582005)
			(xy 366.744722 -353.537862) (xy 366.784871 -353.499153) (xy 366.830229 -353.466702) (xy 366.879829 -353.441201)
			(xy 366.932613 -353.423194) (xy 366.987456 -353.413064) (xy 367.04319 -353.411027) (xy 367.098627 -353.417127)
			(xy 367.152584 -353.431233) (xy 367.203913 -353.453045) (xy 367.251519 -353.482099) (xy 367.294387 -353.517774)
			(xy 367.331604 -353.559311) (xy 367.362377 -353.605824) (xy 367.386049 -353.656321) (xy 367.402117 -353.709728)
			(xy 367.410237 -353.764904) (xy 367.410746 -353.79279) (xy 367.410237 -353.820676) (xy 367.402117 -353.875852)
			(xy 367.386049 -353.929259) (xy 367.362377 -353.979756) (xy 367.331604 -354.026269) (xy 367.294387 -354.067806)
			(xy 367.251519 -354.103481) (xy 367.203913 -354.132535) (xy 367.152584 -354.154347) (xy 367.098627 -354.168453)
			(xy 367.04319 -354.174553) (xy 366.987456 -354.172516) (xy 366.932613 -354.162386) (xy 366.879829 -354.144379)
			(xy 366.830229 -354.118878) (xy 366.784871 -354.086427) (xy 366.744722 -354.047718) (xy 366.710636 -354.003575)
			(xy 366.68334 -353.95494) (xy 366.663417 -353.902849) (xy 366.651291 -353.848412) (xy 366.64722 -353.79279)
			(xy 364.98776 -353.79279) (xy 364.98837 -353.797035) (xy 364.988856 -353.824286) (xy 364.988425 -353.850666)
			(xy 364.981162 -353.902922) (xy 364.966772 -353.953681) (xy 364.945531 -354.001975) (xy 364.917841 -354.046884)
			(xy 364.884232 -354.087552) (xy 364.845342 -354.123205) (xy 364.801914 -354.153164) (xy 364.778544 -354.165408)
			(xy 364.766197 -354.17213) (xy 364.745467 -354.191101) (xy 364.730705 -354.215011) (xy 364.723031 -354.242044)
			(xy 364.72303 -354.270144) (xy 364.7307 -354.297177) (xy 364.745459 -354.321089) (xy 364.766186 -354.340063)
			(xy 364.778544 -354.346764) (xy 364.801919 -354.358998) (xy 364.845341 -354.388962) (xy 364.884225 -354.42462)
			(xy 364.91783 -354.465291) (xy 364.945516 -354.5102) (xy 364.966756 -354.558494) (xy 364.981145 -354.609252)
			(xy 364.98841 -354.661507) (xy 364.988856 -354.687886) (xy 364.98837 -354.715137) (xy 364.980614 -354.769085)
			(xy 364.965259 -354.82138) (xy 364.942617 -354.870957) (xy 364.913151 -354.916807) (xy 364.87746 -354.957998)
			(xy 364.836269 -354.993689) (xy 364.790419 -355.023155) (xy 364.740842 -355.045797) (xy 364.688547 -355.061152)
			(xy 364.634599 -355.068908) (xy 364.580097 -355.068908) (xy 364.526149 -355.061152) (xy 364.473854 -355.045797)
			(xy 364.424277 -355.023155) (xy 364.378427 -354.993689) (xy 364.337236 -354.957998) (xy 364.301545 -354.916807)
			(xy 364.272079 -354.870957) (xy 364.249437 -354.82138) (xy 364.234082 -354.769085) (xy 364.226326 -354.715137)
			(xy 364.22584 -354.687886) (xy 363.328712 -354.687886) (xy 363.328712 -355.32441) (xy 363.328148 -355.346907)
			(xy 363.319293 -355.391022) (xy 363.302005 -355.432563) (xy 363.276946 -355.469935) (xy 363.261402 -355.486208)
			(xy 362.919264 -355.828346) (xy 362.903044 -355.843953) (xy 362.865662 -355.869018) (xy 362.824103 -355.886296)
			(xy 362.779969 -355.895122) (xy 362.757466 -355.895656) (xy 361.380278 -355.895656) (xy 361.09275 -356.014782)
			(xy 360.560559 -356.546912) (xy 361.125006 -356.546912) (xy 361.129077 -356.49129) (xy 361.141203 -356.436853)
			(xy 361.161126 -356.384762) (xy 361.188422 -356.336127) (xy 361.222508 -356.291984) (xy 361.262657 -356.253275)
			(xy 361.308015 -356.220824) (xy 361.357615 -356.195323) (xy 361.410399 -356.177316) (xy 361.465242 -356.167186)
			(xy 361.520976 -356.165149) (xy 361.576413 -356.171249) (xy 361.63037 -356.185355) (xy 361.681699 -356.207167)
			(xy 361.729305 -356.236221) (xy 361.772173 -356.271896) (xy 361.80939 -356.313433) (xy 361.840163 -356.359946)
			(xy 361.863835 -356.410443) (xy 361.879903 -356.46385) (xy 361.888023 -356.519026) (xy 361.888532 -356.546912)
			(xy 361.888023 -356.574798) (xy 361.879903 -356.629974) (xy 361.863835 -356.683381) (xy 361.840163 -356.733878)
			(xy 361.80939 -356.780391) (xy 361.772173 -356.821928) (xy 361.729305 -356.857603) (xy 361.681699 -356.886657)
			(xy 361.63037 -356.908469) (xy 361.576413 -356.922575) (xy 361.520976 -356.928675) (xy 361.465242 -356.926638)
			(xy 361.410399 -356.916508) (xy 361.357615 -356.898501) (xy 361.308015 -356.873) (xy 361.262657 -356.840549)
			(xy 361.222508 -356.80184) (xy 361.188422 -356.757697) (xy 361.161126 -356.709062) (xy 361.141203 -356.656971)
			(xy 361.129077 -356.602534) (xy 361.125006 -356.546912) (xy 360.560559 -356.546912) (xy 360.031416 -357.075994)
			(xy 362.04347 -357.075994) (xy 362.047541 -357.020372) (xy 362.059667 -356.965935) (xy 362.07959 -356.913844)
			(xy 362.106886 -356.865209) (xy 362.140972 -356.821066) (xy 362.181121 -356.782357) (xy 362.226479 -356.749906)
			(xy 362.276079 -356.724405) (xy 362.328863 -356.706398) (xy 362.383706 -356.696268) (xy 362.43944 -356.694231)
			(xy 362.494877 -356.700331) (xy 362.548834 -356.714437) (xy 362.600163 -356.736249) (xy 362.647769 -356.765303)
			(xy 362.690637 -356.800978) (xy 362.727854 -356.842515) (xy 362.758627 -356.889028) (xy 362.782299 -356.939525)
			(xy 362.798367 -356.992932) (xy 362.806487 -357.048108) (xy 362.806996 -357.075994) (xy 362.806487 -357.10388)
			(xy 362.798367 -357.159056) (xy 362.782299 -357.212463) (xy 362.758627 -357.26296) (xy 362.727854 -357.309473)
			(xy 362.690637 -357.35101) (xy 362.647769 -357.386685) (xy 362.600163 -357.415739) (xy 362.548834 -357.437551)
			(xy 362.494877 -357.451657) (xy 362.43944 -357.457757) (xy 362.383706 -357.45572) (xy 362.328863 -357.44559)
			(xy 362.276079 -357.427583) (xy 362.226479 -357.402082) (xy 362.181121 -357.369631) (xy 362.140972 -357.330922)
			(xy 362.106886 -357.286779) (xy 362.07959 -357.238144) (xy 362.059667 -357.186053) (xy 362.047541 -357.131616)
			(xy 362.04347 -357.075994) (xy 360.031416 -357.075994) (xy 359.545966 -357.561388) (xy 360.900216 -357.561388)
			(xy 360.904287 -357.505766) (xy 360.916413 -357.451329) (xy 360.936336 -357.399238) (xy 360.963632 -357.350603)
			(xy 360.997718 -357.30646) (xy 361.037867 -357.267751) (xy 361.083225 -357.2353) (xy 361.132825 -357.209799)
			(xy 361.185609 -357.191792) (xy 361.240452 -357.181662) (xy 361.296186 -357.179625) (xy 361.351623 -357.185725)
			(xy 361.40558 -357.199831) (xy 361.456909 -357.221643) (xy 361.504515 -357.250697) (xy 361.547383 -357.286372)
			(xy 361.5846 -357.327909) (xy 361.615373 -357.374422) (xy 361.639045 -357.424919) (xy 361.655113 -357.478326)
			(xy 361.663233 -357.533502) (xy 361.663742 -357.561388) (xy 361.663233 -357.589274) (xy 361.655113 -357.64445)
			(xy 361.639045 -357.697857) (xy 361.615373 -357.748354) (xy 361.5846 -357.794867) (xy 361.547383 -357.836404)
			(xy 361.504515 -357.872079) (xy 361.456909 -357.901133) (xy 361.40558 -357.922945) (xy 361.351623 -357.937051)
			(xy 361.296186 -357.943151) (xy 361.240452 -357.941114) (xy 361.185609 -357.930984) (xy 361.132825 -357.912977)
			(xy 361.083225 -357.887476) (xy 361.037867 -357.855025) (xy 360.997718 -357.816316) (xy 360.963632 -357.772173)
			(xy 360.936336 -357.723538) (xy 360.916413 -357.671447) (xy 360.904287 -357.61701) (xy 360.900216 -357.561388)
			(xy 359.545966 -357.561388) (xy 358.88041 -358.226868) (xy 358.864171 -358.242436) (xy 358.826777 -358.267434)
			(xy 358.785221 -358.284649) (xy 358.741103 -358.293416) (xy 358.718612 -358.293924) (xy 358.107234 -358.293924)
			(xy 357.824532 -358.576626) (xy 360.646216 -358.576626) (xy 360.650287 -358.521004) (xy 360.662413 -358.466567)
			(xy 360.682336 -358.414476) (xy 360.709632 -358.365841) (xy 360.743718 -358.321698) (xy 360.783867 -358.282989)
			(xy 360.829225 -358.250538) (xy 360.878825 -358.225037) (xy 360.931609 -358.20703) (xy 360.986452 -358.1969)
			(xy 361.042186 -358.194863) (xy 361.097623 -358.200963) (xy 361.15158 -358.215069) (xy 361.202909 -358.236881)
			(xy 361.250515 -358.265935) (xy 361.293383 -358.30161) (xy 361.3306 -358.343147) (xy 361.361373 -358.38966)
			(xy 361.385045 -358.440157) (xy 361.401113 -358.493564) (xy 361.409233 -358.54874) (xy 361.409742 -358.576626)
			(xy 361.409233 -358.604512) (xy 361.401113 -358.659688) (xy 361.385045 -358.713095) (xy 361.361373 -358.763592)
			(xy 361.3306 -358.810105) (xy 361.293383 -358.851642) (xy 361.250515 -358.887317) (xy 361.202909 -358.916371)
			(xy 361.15158 -358.938183) (xy 361.097623 -358.952289) (xy 361.042186 -358.958389) (xy 360.986452 -358.956352)
			(xy 360.931609 -358.946222) (xy 360.878825 -358.928215) (xy 360.829225 -358.902714) (xy 360.783867 -358.870263)
			(xy 360.743718 -358.831554) (xy 360.709632 -358.787411) (xy 360.682336 -358.738776) (xy 360.662413 -358.686685)
			(xy 360.650287 -358.632248) (xy 360.646216 -358.576626) (xy 357.824532 -358.576626) (xy 357.585772 -358.815386)
			(xy 357.585772 -359.595674) (xy 360.673902 -359.595674) (xy 360.677973 -359.540052) (xy 360.690099 -359.485615)
			(xy 360.710022 -359.433524) (xy 360.737318 -359.384889) (xy 360.771404 -359.340746) (xy 360.811553 -359.302037)
			(xy 360.856911 -359.269586) (xy 360.906511 -359.244085) (xy 360.959295 -359.226078) (xy 361.014138 -359.215948)
			(xy 361.069872 -359.213911) (xy 361.125309 -359.220011) (xy 361.179266 -359.234117) (xy 361.230595 -359.255929)
			(xy 361.278201 -359.284983) (xy 361.321069 -359.320658) (xy 361.358286 -359.362195) (xy 361.389059 -359.408708)
			(xy 361.412731 -359.459205) (xy 361.428799 -359.512612) (xy 361.436919 -359.567788) (xy 361.437428 -359.595674)
			(xy 361.436919 -359.62356) (xy 361.428799 -359.678736) (xy 361.412731 -359.732143) (xy 361.389059 -359.78264)
			(xy 361.358286 -359.829153) (xy 361.321069 -359.87069) (xy 361.278201 -359.906365) (xy 361.230595 -359.935419)
			(xy 361.179266 -359.957231) (xy 361.125309 -359.971337) (xy 361.069872 -359.977437) (xy 361.014138 -359.9754)
			(xy 360.959295 -359.96527) (xy 360.906511 -359.947263) (xy 360.856911 -359.921762) (xy 360.811553 -359.889311)
			(xy 360.771404 -359.850602) (xy 360.737318 -359.806459) (xy 360.710022 -359.757824) (xy 360.690099 -359.705733)
			(xy 360.677973 -359.651296) (xy 360.673902 -359.595674) (xy 357.585772 -359.595674) (xy 357.585772 -360.61142)
			(xy 360.771438 -360.61142) (xy 360.775509 -360.555798) (xy 360.787635 -360.501361) (xy 360.807558 -360.44927)
			(xy 360.834854 -360.400635) (xy 360.86894 -360.356492) (xy 360.909089 -360.317783) (xy 360.954447 -360.285332)
			(xy 361.004047 -360.259831) (xy 361.056831 -360.241824) (xy 361.111674 -360.231694) (xy 361.167408 -360.229657)
			(xy 361.222845 -360.235757) (xy 361.276802 -360.249863) (xy 361.328131 -360.271675) (xy 361.375737 -360.300729)
			(xy 361.418605 -360.336404) (xy 361.455822 -360.377941) (xy 361.486595 -360.424454) (xy 361.510267 -360.474951)
			(xy 361.526335 -360.528358) (xy 361.534455 -360.583534) (xy 361.534964 -360.61142) (xy 361.534455 -360.639306)
			(xy 361.526335 -360.694482) (xy 361.510267 -360.747889) (xy 361.486595 -360.798386) (xy 361.455822 -360.844899)
			(xy 361.418605 -360.886436) (xy 361.375737 -360.922111) (xy 361.328131 -360.951165) (xy 361.276802 -360.972977)
			(xy 361.222845 -360.987083) (xy 361.167408 -360.993183) (xy 361.111674 -360.991146) (xy 361.056831 -360.981016)
			(xy 361.004047 -360.963009) (xy 360.954447 -360.937508) (xy 360.909089 -360.905057) (xy 360.86894 -360.866348)
			(xy 360.834854 -360.822205) (xy 360.807558 -360.77357) (xy 360.787635 -360.721479) (xy 360.775509 -360.667042)
			(xy 360.771438 -360.61142) (xy 357.585772 -360.61142) (xy 357.585772 -361.544616) (xy 360.295696 -361.544616)
			(xy 360.299767 -361.488994) (xy 360.311893 -361.434557) (xy 360.331816 -361.382466) (xy 360.359112 -361.333831)
			(xy 360.393198 -361.289688) (xy 360.433347 -361.250979) (xy 360.478705 -361.218528) (xy 360.528305 -361.193027)
			(xy 360.581089 -361.17502) (xy 360.635932 -361.16489) (xy 360.691666 -361.162853) (xy 360.747103 -361.168953)
			(xy 360.80106 -361.183059) (xy 360.852389 -361.204871) (xy 360.899995 -361.233925) (xy 360.942863 -361.2696)
			(xy 360.98008 -361.311137) (xy 361.010853 -361.35765) (xy 361.034525 -361.408147) (xy 361.050593 -361.461554)
			(xy 361.058713 -361.51673) (xy 361.059222 -361.544616) (xy 361.058713 -361.572502) (xy 361.050593 -361.627678)
			(xy 361.034525 -361.681085) (xy 361.010853 -361.731582) (xy 360.98008 -361.778095) (xy 360.942863 -361.819632)
			(xy 360.899995 -361.855307) (xy 360.852389 -361.884361) (xy 360.80106 -361.906173) (xy 360.747103 -361.920279)
			(xy 360.691666 -361.926379) (xy 360.635932 -361.924342) (xy 360.581089 -361.914212) (xy 360.528305 -361.896205)
			(xy 360.478705 -361.870704) (xy 360.433347 -361.838253) (xy 360.393198 -361.799544) (xy 360.359112 -361.755401)
			(xy 360.331816 -361.706766) (xy 360.311893 -361.654675) (xy 360.299767 -361.600238) (xy 360.295696 -361.544616)
			(xy 357.585772 -361.544616) (xy 357.585772 -362.43006) (xy 358.973626 -362.43006) (xy 358.977697 -362.374438)
			(xy 358.989823 -362.320001) (xy 359.009746 -362.26791) (xy 359.037042 -362.219275) (xy 359.071128 -362.175132)
			(xy 359.111277 -362.136423) (xy 359.156635 -362.103972) (xy 359.206235 -362.078471) (xy 359.259019 -362.060464)
			(xy 359.313862 -362.050334) (xy 359.369596 -362.048297) (xy 359.425033 -362.054397) (xy 359.47899 -362.068503)
			(xy 359.530319 -362.090315) (xy 359.577925 -362.119369) (xy 359.620793 -362.155044) (xy 359.65801 -362.196581)
			(xy 359.688783 -362.243094) (xy 359.712455 -362.293591) (xy 359.728523 -362.346998) (xy 359.736643 -362.402174)
			(xy 359.737152 -362.43006) (xy 359.736643 -362.457946) (xy 359.728523 -362.513122) (xy 359.712455 -362.566529)
			(xy 359.688783 -362.617026) (xy 359.65801 -362.663539) (xy 359.620793 -362.705076) (xy 359.577925 -362.740751)
			(xy 359.530319 -362.769805) (xy 359.47899 -362.791617) (xy 359.425033 -362.805723) (xy 359.369596 -362.811823)
			(xy 359.313862 -362.809786) (xy 359.259019 -362.799656) (xy 359.206235 -362.781649) (xy 359.156635 -362.756148)
			(xy 359.111277 -362.723697) (xy 359.071128 -362.684988) (xy 359.037042 -362.640845) (xy 359.009746 -362.59221)
			(xy 358.989823 -362.540119) (xy 358.977697 -362.485682) (xy 358.973626 -362.43006) (xy 357.585772 -362.43006)
			(xy 357.585772 -362.835444) (xy 357.585209 -362.857927) (xy 357.576419 -362.902025) (xy 357.559203 -362.943564)
			(xy 357.534222 -362.980952) (xy 357.518716 -362.997242) (xy 357.140334 -363.375702) (xy 357.676702 -363.375702)
			(xy 357.680773 -363.32008) (xy 357.692899 -363.265643) (xy 357.712822 -363.213552) (xy 357.740118 -363.164917)
			(xy 357.774204 -363.120774) (xy 357.814353 -363.082065) (xy 357.859711 -363.049614) (xy 357.909311 -363.024113)
			(xy 357.962095 -363.006106) (xy 358.016938 -362.995976) (xy 358.072672 -362.993939) (xy 358.128109 -363.000039)
			(xy 358.182066 -363.014145) (xy 358.233395 -363.035957) (xy 358.281001 -363.065011) (xy 358.323869 -363.100686)
			(xy 358.361086 -363.142223) (xy 358.391859 -363.188736) (xy 358.415531 -363.239233) (xy 358.431599 -363.29264)
			(xy 358.439719 -363.347816) (xy 358.440228 -363.375702) (xy 358.439719 -363.403588) (xy 358.431599 -363.458764)
			(xy 358.415531 -363.512171) (xy 358.391859 -363.562668) (xy 358.361086 -363.609181) (xy 358.323869 -363.650718)
			(xy 358.281001 -363.686393) (xy 358.233395 -363.715447) (xy 358.182066 -363.737259) (xy 358.128109 -363.751365)
			(xy 358.072672 -363.757465) (xy 358.016938 -363.755428) (xy 357.962095 -363.745298) (xy 357.909311 -363.727291)
			(xy 357.859711 -363.70179) (xy 357.814353 -363.669339) (xy 357.774204 -363.63063) (xy 357.740118 -363.586487)
			(xy 357.712822 -363.537852) (xy 357.692899 -363.485761) (xy 357.680773 -363.431324) (xy 357.676702 -363.375702)
			(xy 357.140334 -363.375702) (xy 356.294182 -364.22203) (xy 356.305612 -364.252764) (xy 356.316839 -364.284953)
			(xy 356.32897 -364.352031) (xy 356.329742 -364.386114) (xy 356.329742 -364.386368) (xy 356.329256 -364.413619)
			(xy 356.326405 -364.43345) (xy 357.768658 -364.43345) (xy 357.768658 -364.37895) (xy 357.776413 -364.325003)
			(xy 357.791767 -364.272709) (xy 357.814406 -364.223133) (xy 357.843869 -364.177282) (xy 357.879557 -364.136091)
			(xy 357.920744 -364.100398) (xy 357.966591 -364.070929) (xy 358.016164 -364.048284) (xy 358.068456 -364.032924)
			(xy 358.122402 -364.025161) (xy 358.149652 -364.024672) (xy 358.15016 -364.024672) (xy 358.183501 -364.025371)
			(xy 358.249161 -364.036997) (xy 358.280716 -364.047786) (xy 358.311196 -364.058962) (xy 359.184702 -363.18571)
			(xy 359.200945 -363.170129) (xy 359.238318 -363.145056) (xy 359.27987 -363.12777) (xy 359.323998 -363.118937)
			(xy 359.3465 -363.1184) (xy 359.749344 -363.1184) (xy 360.003852 -362.864146) (xy 360.003852 -362.753402)
			(xy 360.004436 -362.73092) (xy 360.013219 -362.686823) (xy 360.030428 -362.645283) (xy 360.055404 -362.607894)
			(xy 360.070908 -362.591604) (xy 360.408982 -362.25353) (xy 360.425237 -362.237962) (xy 360.462605 -362.212886)
			(xy 360.504153 -362.195596) (xy 360.548279 -362.186759) (xy 360.57078 -362.18622) (xy 361.555538 -362.18622)
			(xy 362.159804 -361.582208) (xy 362.159804 -358.38257) (xy 362.160382 -358.360088) (xy 362.169169 -358.315991)
			(xy 362.186381 -358.274452) (xy 362.211357 -358.237063) (xy 362.22686 -358.220772) (xy 364.551468 -355.896164)
			(xy 364.567721 -355.880612) (xy 364.60511 -355.855609) (xy 364.646662 -355.83839) (xy 364.690777 -355.829618)
			(xy 364.713266 -355.829108) (xy 366.167416 -355.829108) (xy 372.508526 -349.487998) (xy 372.524757 -349.472404)
			(xy 372.562134 -349.447334) (xy 372.60369 -349.430052) (xy 372.647821 -349.421223) (xy 372.670324 -349.420688)
			(xy 384.71475 -349.420688) (xy 386.096764 -348.038928) (xy 386.096764 -347.80093) (xy 385.902962 -347.607128)
			(xy 385.87934 -347.60916) (xy 385.848352 -347.61043) (xy 385.821101 -347.609967) (xy 385.767153 -347.602204)
			(xy 385.714859 -347.586844) (xy 385.665283 -347.564199) (xy 385.619434 -347.53473) (xy 385.578245 -347.499036)
			(xy 385.542554 -347.457845) (xy 385.513088 -347.411994) (xy 385.490447 -347.362416) (xy 385.47509 -347.310121)
			(xy 385.467331 -347.256173) (xy 385.466844 -347.228922) (xy 385.466844 -347.228668) (xy 385.467421 -347.198829)
			(xy 385.476735 -347.139883) (xy 385.485386 -347.11132) (xy 385.489459 -347.097421) (xy 385.490364 -347.068483)
			(xy 385.483092 -347.040458) (xy 385.468233 -347.015609) (xy 385.446984 -346.995944) (xy 385.421061 -346.983049)
			(xy 385.4069 -346.980002) (xy 385.37406 -346.973421) (xy 385.311208 -346.950297) (xy 385.281932 -346.934028)
			(xy 385.26899 -346.926946) (xy 385.240345 -346.919923) (xy 385.210887 -346.921377) (xy 385.183072 -346.931188)
			(xy 385.159221 -346.948537) (xy 385.141321 -346.971977) (xy 385.135628 -346.98559) (xy 385.12492 -347.012361)
			(xy 385.096635 -347.062604) (xy 385.061107 -347.108014) (xy 385.019147 -347.147557) (xy 384.971711 -347.180332)
			(xy 384.919882 -347.20559) (xy 384.86484 -347.222757) (xy 384.80784 -347.23144) (xy 384.779012 -347.23197)
			(xy 384.751756 -347.231584) (xy 384.697798 -347.223828) (xy 384.645494 -347.208471) (xy 384.595907 -347.185827)
			(xy 384.550048 -347.156356) (xy 384.50885 -347.120659) (xy 384.473151 -347.079462) (xy 384.443679 -347.033604)
			(xy 384.421033 -346.984018) (xy 384.405675 -346.931714) (xy 384.397917 -346.877756) (xy 384.397917 -346.823244)
			(xy 384.405675 -346.769286) (xy 384.421033 -346.716982) (xy 384.443679 -346.667396) (xy 384.473151 -346.621538)
			(xy 384.50885 -346.580341) (xy 384.550048 -346.544644) (xy 384.595907 -346.515173) (xy 384.645494 -346.492529)
			(xy 384.697798 -346.477172) (xy 384.751756 -346.469416) (xy 384.779012 -346.468954) (xy 384.779266 -346.468954)
			(xy 384.804469 -346.469366) (xy 384.854437 -346.476002) (xy 384.903091 -346.489175) (xy 384.949582 -346.508654)
			(xy 384.971544 -346.521024) (xy 384.984489 -346.528103) (xy 385.013135 -346.535136) (xy 385.042595 -346.533686)
			(xy 385.070411 -346.523876) (xy 385.094263 -346.506524) (xy 385.112159 -346.483078) (xy 385.117848 -346.469462)
			(xy 385.128551 -346.442689) (xy 385.156839 -346.392449) (xy 385.192369 -346.347041) (xy 385.23433 -346.307499)
			(xy 385.281766 -346.274725) (xy 385.333596 -346.249467) (xy 385.388637 -346.232299) (xy 385.445636 -346.223613)
			(xy 385.474464 -346.223082) (xy 385.501716 -346.223589) (xy 385.555664 -346.231341) (xy 385.607961 -346.246692)
			(xy 385.65754 -346.269329) (xy 385.703393 -346.298792) (xy 385.744586 -346.334482) (xy 385.78028 -346.37567)
			(xy 385.809749 -346.421519) (xy 385.832392 -346.471096) (xy 385.84775 -346.523391) (xy 385.855508 -346.577339)
			(xy 385.855972 -346.60459) (xy 385.855972 -346.604844) (xy 385.855401 -346.634683) (xy 385.846083 -346.693629)
			(xy 385.83743 -346.722192) (xy 385.833331 -346.736085) (xy 385.832428 -346.765028) (xy 385.839703 -346.793056)
			(xy 385.854568 -346.817907) (xy 385.875823 -346.837573) (xy 385.901752 -346.850466) (xy 385.915916 -346.85351)
			(xy 385.941986 -346.858696) (xy 385.992488 -346.875265) (xy 386.040201 -346.898686) (xy 386.084199 -346.928506)
			(xy 386.12363 -346.964147) (xy 386.157729 -347.004918) (xy 386.185837 -347.05003) (xy 386.207407 -347.098607)
			(xy 386.222023 -347.149709) (xy 386.229401 -347.202346) (xy 386.22986 -347.228922) (xy 386.22859 -347.25991)
			(xy 386.226558 -347.283532) (xy 386.487416 -347.54439) (xy 386.502975 -347.560637) (xy 386.527977 -347.598027)
			(xy 386.545195 -347.639581) (xy 386.553964 -347.683698) (xy 386.554472 -347.706188) (xy 386.554472 -348.13367)
			(xy 386.553925 -348.156153) (xy 386.54513 -348.200252) (xy 386.527909 -348.241792) (xy 386.502924 -348.279179)
			(xy 386.487416 -348.295468) (xy 384.97129 -349.811594) (xy 384.955051 -349.82718) (xy 384.917677 -349.852251)
			(xy 384.876124 -349.869536) (xy 384.831994 -349.878367) (xy 384.809492 -349.878904) (xy 372.765066 -349.878904)
			(xy 366.423956 -356.21976) (xy 366.407696 -356.235304) (xy 366.370309 -356.260308) (xy 366.32876 -356.277529)
			(xy 366.284647 -356.286304) (xy 366.262158 -356.286816) (xy 364.808008 -356.286816) (xy 362.617512 -358.477312)
			(xy 362.617512 -361.67695) (xy 362.616942 -361.699432) (xy 362.608152 -361.743529) (xy 362.590938 -361.785068)
			(xy 362.56596 -361.822457) (xy 362.550456 -361.838748) (xy 361.812078 -362.577126) (xy 361.795849 -362.592723)
			(xy 361.758471 -362.617791) (xy 361.716914 -362.635072) (xy 361.672783 -362.643901) (xy 361.65028 -362.644436)
			(xy 360.665522 -362.644436) (xy 360.46156 -362.848144) (xy 360.46156 -362.958888) (xy 360.461028 -362.981372)
			(xy 360.452228 -363.025472) (xy 360.435003 -363.067011) (xy 360.410014 -363.104398) (xy 360.394504 -363.120686)
			(xy 360.18978 -363.32541) (xy 360.662472 -363.32541) (xy 360.666543 -363.269788) (xy 360.678669 -363.215351)
			(xy 360.698592 -363.16326) (xy 360.725888 -363.114625) (xy 360.759974 -363.070482) (xy 360.800123 -363.031773)
			(xy 360.845481 -362.999322) (xy 360.895081 -362.973821) (xy 360.947865 -362.955814) (xy 361.002708 -362.945684)
			(xy 361.058442 -362.943647) (xy 361.113879 -362.949747) (xy 361.167836 -362.963853) (xy 361.219165 -362.985665)
			(xy 361.266771 -363.014719) (xy 361.271713 -363.018832) (xy 363.790992 -363.018832) (xy 363.791512 -362.990525)
			(xy 363.799853 -362.934531) (xy 363.816386 -362.880386) (xy 363.840747 -362.829284) (xy 363.872401 -362.782347)
			(xy 363.910649 -362.740609) (xy 363.954652 -362.70499) (xy 364.003439 -362.676272) (xy 364.055939 -362.655087)
			(xy 364.083346 -362.647992) (xy 364.097316 -362.644436) (xy 364.126272 -362.61548) (xy 364.126272 -359.791508)
			(xy 364.101601 -359.776833) (xy 364.056565 -359.741243) (xy 364.017366 -359.699309) (xy 363.984889 -359.651978)
			(xy 363.959866 -359.600318) (xy 363.942862 -359.545492) (xy 363.93426 -359.488739) (xy 363.93374 -359.460038)
			(xy 363.934191 -359.432784) (xy 363.941944 -359.37883) (xy 363.957297 -359.326529) (xy 363.979939 -359.276946)
			(xy 364.009408 -359.23109) (xy 364.045103 -359.189896) (xy 364.086298 -359.154202) (xy 364.132155 -359.124734)
			(xy 364.181738 -359.102094) (xy 364.23404 -359.086742) (xy 364.287994 -359.07899) (xy 364.315248 -359.07853)
			(xy 364.341551 -359.078967) (xy 364.393655 -359.086213) (xy 364.44427 -359.100548) (xy 364.492435 -359.1217)
			(xy 364.537239 -359.149268) (xy 364.577831 -359.182729) (xy 364.613442 -359.221449) (xy 364.643396 -359.264693)
			(xy 364.667127 -359.311643) (xy 364.684182 -359.361407) (xy 364.689644 -359.38714) (xy 364.706643 -359.408615)
			(xy 364.733746 -359.456204) (xy 364.752283 -359.507738) (xy 364.761702 -359.561687) (xy 364.762288 -359.58907)
			(xy 364.762288 -362.747052) (xy 364.761847 -362.77204) (xy 364.754004 -362.821398) (xy 364.738535 -362.868921)
			(xy 364.715821 -362.913439) (xy 364.686422 -362.953854) (xy 364.66907 -362.971842) (xy 364.546896 -363.094016)
			(xy 364.54334 -363.107986) (xy 364.536184 -363.135373) (xy 364.514979 -363.187851) (xy 364.486252 -363.23662)
			(xy 364.450633 -363.280608) (xy 364.408906 -363.31885) (xy 364.361985 -363.350506) (xy 364.310902 -363.374881)
			(xy 364.256777 -363.391439) (xy 364.2008 -363.399818) (xy 364.1725 -363.40034) (xy 364.14525 -363.399822)
			(xy 364.091305 -363.392067) (xy 364.039013 -363.376713) (xy 363.989438 -363.354074) (xy 363.943589 -363.324611)
			(xy 363.9024 -363.288923) (xy 363.866708 -363.247737) (xy 363.837241 -363.20189) (xy 363.814598 -363.152317)
			(xy 363.79924 -363.100026) (xy 363.79148 -363.046082) (xy 363.790992 -363.018832) (xy 361.271713 -363.018832)
			(xy 361.309639 -363.050394) (xy 361.346856 -363.091931) (xy 361.377629 -363.138444) (xy 361.401301 -363.188941)
			(xy 361.417369 -363.242348) (xy 361.425489 -363.297524) (xy 361.425998 -363.32541) (xy 361.425489 -363.353296)
			(xy 361.417369 -363.408472) (xy 361.401301 -363.461879) (xy 361.377629 -363.512376) (xy 361.346856 -363.558889)
			(xy 361.309639 -363.600426) (xy 361.266771 -363.636101) (xy 361.219165 -363.665155) (xy 361.167836 -363.686967)
			(xy 361.113879 -363.701073) (xy 361.058442 -363.707173) (xy 361.002708 -363.705136) (xy 360.947865 -363.695006)
			(xy 360.895081 -363.676999) (xy 360.845481 -363.651498) (xy 360.800123 -363.619047) (xy 360.759974 -363.580338)
			(xy 360.725888 -363.536195) (xy 360.698592 -363.48756) (xy 360.678669 -363.435469) (xy 360.666543 -363.381032)
			(xy 360.662472 -363.32541) (xy 360.18978 -363.32541) (xy 360.005884 -363.509306) (xy 359.989649 -363.524896)
			(xy 359.952273 -363.549966) (xy 359.910719 -363.56725) (xy 359.866588 -363.57608) (xy 359.844086 -363.576616)
			(xy 359.441242 -363.576616) (xy 358.794812 -364.223046) (xy 359.35107 -364.223046) (xy 359.355141 -364.167424)
			(xy 359.367267 -364.112987) (xy 359.38719 -364.060896) (xy 359.414486 -364.012261) (xy 359.448572 -363.968118)
			(xy 359.488721 -363.929409) (xy 359.534079 -363.896958) (xy 359.583679 -363.871457) (xy 359.636463 -363.85345)
			(xy 359.691306 -363.84332) (xy 359.74704 -363.841283) (xy 359.802477 -363.847383) (xy 359.856434 -363.861489)
			(xy 359.907763 -363.883301) (xy 359.955369 -363.912355) (xy 359.998237 -363.94803) (xy 360.035454 -363.989567)
			(xy 360.066227 -364.03608) (xy 360.089899 -364.086577) (xy 360.105967 -364.139984) (xy 360.114087 -364.19516)
			(xy 360.114137 -364.1979) (xy 361.550712 -364.1979) (xy 361.551155 -364.170646) (xy 361.558913 -364.116694)
			(xy 361.57427 -364.064394) (xy 361.596914 -364.014813) (xy 361.626384 -363.968959) (xy 361.66208 -363.927765)
			(xy 361.703275 -363.892072) (xy 361.74913 -363.862604) (xy 361.798713 -363.839963) (xy 361.851013 -363.824609)
			(xy 361.904966 -363.816854) (xy 361.93222 -363.816392) (xy 361.960528 -363.816865) (xy 362.016525 -363.825214)
			(xy 362.07067 -363.841754) (xy 362.121773 -363.866122) (xy 362.16871 -363.897781) (xy 362.210446 -363.936035)
			(xy 362.246065 -363.980042) (xy 362.274782 -364.028834) (xy 362.295966 -364.081337) (xy 362.30306 -364.108746)
			(xy 362.306616 -364.122716) (xy 362.627672 -364.443772) (xy 364.252002 -364.443772) (xy 365.205264 -363.49051)
			(xy 365.205264 -358.808782) (xy 364.885732 -358.48925) (xy 364.8684 -358.471292) (xy 364.839075 -358.430908)
			(xy 364.816429 -358.386433) (xy 364.801019 -358.338964) (xy 364.793225 -358.289668) (xy 364.792768 -358.264714)
			(xy 364.792768 -357.40848) (xy 364.777693 -357.384909) (xy 364.753862 -357.334289) (xy 364.737683 -357.280729)
			(xy 364.729506 -357.225381) (xy 364.729014 -357.197406) (xy 364.729461 -357.170152) (xy 364.737218 -357.1162)
			(xy 364.752574 -357.0639) (xy 364.775217 -357.014319) (xy 364.804687 -356.968464) (xy 364.840382 -356.927271)
			(xy 364.881577 -356.891577) (xy 364.927433 -356.86211) (xy 364.977015 -356.839468) (xy 365.029315 -356.824114)
			(xy 365.083268 -356.81636) (xy 365.110522 -356.815898) (xy 365.138498 -356.816366) (xy 365.193849 -356.824547)
			(xy 365.247409 -356.840731) (xy 365.298028 -356.864571) (xy 365.321596 -356.879652) (xy 366.28705 -356.879652)
			(xy 368.038634 -355.127814) (xy 368.056631 -355.110473) (xy 368.097038 -355.081064) (xy 368.141553 -355.058348)
			(xy 368.189077 -355.042886) (xy 368.238436 -355.035061) (xy 368.263424 -355.034596) (xy 368.387376 -355.034596)
			(xy 368.399568 -355.02723) (xy 368.422137 -355.013913) (xy 368.470154 -354.992923) (xy 368.520592 -354.978706)
			(xy 368.572502 -354.97153) (xy 368.598704 -354.971096) (xy 368.625955 -354.971574) (xy 368.679903 -354.979331)
			(xy 368.732198 -354.994687) (xy 368.781775 -355.017328) (xy 368.827626 -355.046795) (xy 368.868816 -355.082487)
			(xy 368.904507 -355.123678) (xy 368.933974 -355.169528) (xy 368.956615 -355.219106) (xy 368.97197 -355.271401)
			(xy 368.979726 -355.325349) (xy 368.979726 -355.379851) (xy 368.97197 -355.433799) (xy 368.956615 -355.486094)
			(xy 368.933974 -355.535672) (xy 368.904507 -355.581522) (xy 368.868816 -355.622713) (xy 368.827626 -355.658405)
			(xy 368.781775 -355.687872) (xy 368.732198 -355.710513) (xy 368.679903 -355.725869) (xy 368.625955 -355.733626)
			(xy 368.598704 -355.734112) (xy 368.56843 -355.733541) (xy 368.508645 -355.723961) (xy 368.451124 -355.705055)
			(xy 368.423952 -355.691694) (xy 368.390932 -355.674676) (xy 367.69167 -356.373938) (xy 368.222274 -356.373938)
			(xy 368.226345 -356.318316) (xy 368.238471 -356.263879) (xy 368.258394 -356.211788) (xy 368.28569 -356.163153)
			(xy 368.319776 -356.11901) (xy 368.359925 -356.080301) (xy 368.405283 -356.04785) (xy 368.454883 -356.022349)
			(xy 368.507667 -356.004342) (xy 368.56251 -355.994212) (xy 368.618244 -355.992175) (xy 368.673681 -355.998275)
			(xy 368.727638 -356.012381) (xy 368.778967 -356.034193) (xy 368.826573 -356.063247) (xy 368.869441 -356.098922)
			(xy 368.906658 -356.140459) (xy 368.937431 -356.186972) (xy 368.961103 -356.237469) (xy 368.977171 -356.290876)
			(xy 368.978854 -356.30231) (xy 370.449854 -356.30231) (xy 370.453925 -356.246688) (xy 370.466051 -356.192251)
			(xy 370.485974 -356.14016) (xy 370.51327 -356.091525) (xy 370.547356 -356.047382) (xy 370.587505 -356.008673)
			(xy 370.632863 -355.976222) (xy 370.682463 -355.950721) (xy 370.735247 -355.932714) (xy 370.79009 -355.922584)
			(xy 370.845824 -355.920547) (xy 370.901261 -355.926647) (xy 370.955218 -355.940753) (xy 371.006547 -355.962565)
			(xy 371.054153 -355.991619) (xy 371.097021 -356.027294) (xy 371.134238 -356.068831) (xy 371.165011 -356.115344)
			(xy 371.188683 -356.165841) (xy 371.204751 -356.219248) (xy 371.212871 -356.274424) (xy 371.21338 -356.30231)
			(xy 371.212871 -356.330196) (xy 371.204751 -356.385372) (xy 371.188683 -356.438779) (xy 371.165011 -356.489276)
			(xy 371.134238 -356.535789) (xy 371.097021 -356.577326) (xy 371.054153 -356.613001) (xy 371.006547 -356.642055)
			(xy 370.955218 -356.663867) (xy 370.901261 -356.677973) (xy 370.845824 -356.684073) (xy 370.79009 -356.682036)
			(xy 370.735247 -356.671906) (xy 370.682463 -356.653899) (xy 370.632863 -356.628398) (xy 370.587505 -356.595947)
			(xy 370.547356 -356.557238) (xy 370.51327 -356.513095) (xy 370.485974 -356.46446) (xy 370.466051 -356.412369)
			(xy 370.453925 -356.357932) (xy 370.449854 -356.30231) (xy 368.978854 -356.30231) (xy 368.985291 -356.346052)
			(xy 368.9858 -356.373938) (xy 368.985291 -356.401824) (xy 368.977171 -356.457) (xy 368.961103 -356.510407)
			(xy 368.937431 -356.560904) (xy 368.906658 -356.607417) (xy 368.869441 -356.648954) (xy 368.826573 -356.684629)
			(xy 368.778967 -356.713683) (xy 368.727638 -356.735495) (xy 368.673681 -356.749601) (xy 368.618244 -356.755701)
			(xy 368.56251 -356.753664) (xy 368.507667 -356.743534) (xy 368.454883 -356.725527) (xy 368.405283 -356.700026)
			(xy 368.359925 -356.667575) (xy 368.319776 -356.628866) (xy 368.28569 -356.584723) (xy 368.258394 -356.536088)
			(xy 368.238471 -356.483997) (xy 368.226345 -356.42956) (xy 368.222274 -356.373938) (xy 367.69167 -356.373938)
			(xy 366.643412 -357.422196) (xy 366.625415 -357.439484) (xy 366.58504 -357.468809) (xy 366.540574 -357.491457)
			(xy 366.493114 -357.506871) (xy 366.443826 -357.514673) (xy 366.418876 -357.51516) (xy 365.428276 -357.51516)
			(xy 365.428276 -358.132888) (xy 365.748062 -358.45242) (xy 365.76541 -358.470411) (xy 365.794815 -358.510821)
			(xy 365.817528 -358.555338) (xy 365.832988 -358.602862) (xy 365.840814 -358.652222) (xy 365.84128 -358.67721)
			(xy 365.84128 -358.818688) (xy 366.653062 -358.818688) (xy 366.657133 -358.763066) (xy 366.669259 -358.708629)
			(xy 366.689182 -358.656538) (xy 366.716478 -358.607903) (xy 366.750564 -358.56376) (xy 366.790713 -358.525051)
			(xy 366.836071 -358.4926) (xy 366.885671 -358.467099) (xy 366.938455 -358.449092) (xy 366.993298 -358.438962)
			(xy 367.049032 -358.436925) (xy 367.104469 -358.443025) (xy 367.158426 -358.457131) (xy 367.209755 -358.478943)
			(xy 367.257361 -358.507997) (xy 367.300229 -358.543672) (xy 367.337446 -358.585209) (xy 367.368219 -358.631722)
			(xy 367.391891 -358.682219) (xy 367.407959 -358.735626) (xy 367.416079 -358.790802) (xy 367.416588 -358.818688)
			(xy 367.416079 -358.846574) (xy 367.407959 -358.90175) (xy 367.391891 -358.955157) (xy 367.368219 -359.005654)
			(xy 367.337446 -359.052167) (xy 367.300229 -359.093704) (xy 367.257361 -359.129379) (xy 367.209755 -359.158433)
			(xy 367.158426 -359.180245) (xy 367.104469 -359.194351) (xy 367.049032 -359.200451) (xy 366.993298 -359.198414)
			(xy 366.938455 -359.188284) (xy 366.885671 -359.170277) (xy 366.836071 -359.144776) (xy 366.790713 -359.112325)
			(xy 366.750564 -359.073616) (xy 366.716478 -359.029473) (xy 366.689182 -358.980838) (xy 366.669259 -358.928747)
			(xy 366.657133 -358.87431) (xy 366.653062 -358.818688) (xy 365.84128 -358.818688) (xy 365.84128 -360.153966)
			(xy 366.16843 -360.153966) (xy 366.172501 -360.098344) (xy 366.184627 -360.043907) (xy 366.20455 -359.991816)
			(xy 366.231846 -359.943181) (xy 366.265932 -359.899038) (xy 366.306081 -359.860329) (xy 366.351439 -359.827878)
			(xy 366.401039 -359.802377) (xy 366.453823 -359.78437) (xy 366.508666 -359.77424) (xy 366.5644 -359.772203)
			(xy 366.619837 -359.778303) (xy 366.673794 -359.792409) (xy 366.725123 -359.814221) (xy 366.772729 -359.843275)
			(xy 366.815597 -359.87895) (xy 366.852814 -359.920487) (xy 366.883587 -359.967) (xy 366.907259 -360.017497)
			(xy 366.923327 -360.070904) (xy 366.931447 -360.12608) (xy 366.931956 -360.153966) (xy 366.931447 -360.181852)
			(xy 366.923327 -360.237028) (xy 366.907259 -360.290435) (xy 366.883587 -360.340932) (xy 366.852814 -360.387445)
			(xy 366.815597 -360.428982) (xy 366.772729 -360.464657) (xy 366.725123 -360.493711) (xy 366.673794 -360.515523)
			(xy 366.619837 -360.529629) (xy 366.5644 -360.535729) (xy 366.508666 -360.533692) (xy 366.453823 -360.523562)
			(xy 366.401039 -360.505555) (xy 366.351439 -360.480054) (xy 366.306081 -360.447603) (xy 366.265932 -360.408894)
			(xy 366.231846 -360.364751) (xy 366.20455 -360.316116) (xy 366.184627 -360.264025) (xy 366.172501 -360.209588)
			(xy 366.16843 -360.153966) (xy 365.84128 -360.153966) (xy 365.84128 -363.622082) (xy 365.840743 -363.647065)
			(xy 365.832914 -363.696415) (xy 365.817461 -363.743932) (xy 365.794765 -363.788447) (xy 365.765386 -363.828864)
			(xy 365.748062 -363.846872) (xy 365.708438 -363.886496) (xy 366.311686 -363.886496) (xy 366.315757 -363.830874)
			(xy 366.327883 -363.776437) (xy 366.347806 -363.724346) (xy 366.375102 -363.675711) (xy 366.409188 -363.631568)
			(xy 366.449337 -363.592859) (xy 366.494695 -363.560408) (xy 366.544295 -363.534907) (xy 366.597079 -363.5169)
			(xy 366.651922 -363.50677) (xy 366.707656 -363.504733) (xy 366.763093 -363.510833) (xy 366.81705 -363.524939)
			(xy 366.868379 -363.546751) (xy 366.915985 -363.575805) (xy 366.958853 -363.61148) (xy 366.99607 -363.653017)
			(xy 367.026843 -363.69953) (xy 367.050515 -363.750027) (xy 367.066583 -363.803434) (xy 367.074703 -363.85861)
			(xy 367.075212 -363.886496) (xy 367.074703 -363.914382) (xy 367.066583 -363.969558) (xy 367.050515 -364.022965)
			(xy 367.026843 -364.073462) (xy 366.99607 -364.119975) (xy 366.958853 -364.161512) (xy 366.915985 -364.197187)
			(xy 366.868379 -364.226241) (xy 366.81705 -364.248053) (xy 366.763093 -364.262159) (xy 366.707656 -364.268259)
			(xy 366.651922 -364.266222) (xy 366.597079 -364.256092) (xy 366.544295 -364.238085) (xy 366.494695 -364.212584)
			(xy 366.449337 -364.180133) (xy 366.409188 -364.141424) (xy 366.375102 -364.097281) (xy 366.347806 -364.048646)
			(xy 366.327883 -363.996555) (xy 366.315757 -363.942118) (xy 366.311686 -363.886496) (xy 365.708438 -363.886496)
			(xy 364.608364 -364.98657) (xy 364.590381 -365.003927) (xy 364.587601 -365.00595) (xy 365.313474 -365.00595)
			(xy 365.313474 -364.95145) (xy 365.321229 -364.897504) (xy 365.336583 -364.845212) (xy 365.359222 -364.795636)
			(xy 365.388686 -364.749787) (xy 365.424374 -364.708597) (xy 365.465561 -364.672905) (xy 365.511408 -364.643438)
			(xy 365.560982 -364.620794) (xy 365.613273 -364.605436) (xy 365.667218 -364.597676) (xy 365.694468 -364.597188)
			(xy 365.721204 -364.597614) (xy 365.774151 -364.605077) (xy 365.825537 -364.619862) (xy 365.874355 -364.641679)
			(xy 365.919647 -364.6701) (xy 365.960526 -364.704568) (xy 365.978694 -364.724188) (xy 367.320068 -364.724188)
			(xy 367.420144 -364.624366) (xy 367.420144 -359.576624) (xy 367.420729 -359.551639) (xy 367.430481 -359.50263)
			(xy 367.449596 -359.456461) (xy 367.477342 -359.414901) (xy 367.494566 -359.396792) (xy 369.84178 -357.049578)
			(xy 369.85989 -357.032356) (xy 369.901449 -357.004613) (xy 369.947619 -356.985506) (xy 369.996628 -356.975766)
			(xy 370.021612 -356.975156) (xy 370.596668 -356.975156) (xy 370.609876 -356.974902) (xy 370.634897 -356.975437)
			(xy 370.683983 -356.985159) (xy 370.730229 -357.004275) (xy 370.771855 -357.032048) (xy 370.789962 -357.049324)
			(xy 370.87556 -357.134922) (xy 370.896388 -357.134922) (xy 370.923666 -357.135325) (xy 370.977674 -357.143023)
			(xy 371.030035 -357.158336) (xy 371.079681 -357.180952) (xy 371.1256 -357.210408) (xy 371.166854 -357.246105)
			(xy 371.202603 -357.287314) (xy 371.232117 -357.333195) (xy 371.254795 -357.382812) (xy 371.270174 -357.435154)
			(xy 371.277941 -357.489153) (xy 371.278404 -357.51643) (xy 371.27795 -357.543682) (xy 371.270189 -357.597631)
			(xy 371.25483 -357.649927) (xy 371.232185 -357.699504) (xy 371.202716 -357.745355) (xy 371.167021 -357.786545)
			(xy 371.125828 -357.822236) (xy 371.079975 -357.851702) (xy 371.030395 -357.874342) (xy 370.978098 -357.889697)
			(xy 370.924148 -357.897453) (xy 370.896896 -357.897938) (xy 370.8839 -357.897826) (xy 370.857969 -357.896049)
			(xy 370.84508 -357.894382) (xy 370.830698 -357.893022) (xy 370.802146 -357.897276) (xy 370.77593 -357.909361)
			(xy 370.754151 -357.928308) (xy 370.738553 -357.952598) (xy 370.730387 -357.980286) (xy 370.730307 -358.009153)
			(xy 370.733828 -358.02316) (xy 370.740688 -358.048778) (xy 370.748086 -358.101292) (xy 370.74856 -358.127808)
			(xy 370.74856 -358.12857) (xy 370.748154 -358.155823) (xy 370.740402 -358.209775) (xy 370.72505 -358.262075)
			(xy 370.702411 -358.311657) (xy 370.672947 -358.357513) (xy 370.637256 -358.398709) (xy 370.596066 -358.434407)
			(xy 370.550215 -358.463879) (xy 370.500637 -358.486527) (xy 370.44834 -358.501888) (xy 370.394389 -358.50965)
			(xy 370.339883 -358.509655) (xy 370.285931 -358.501903) (xy 370.233631 -358.486552) (xy 370.184048 -358.463914)
			(xy 370.138191 -358.43445) (xy 370.096995 -358.39876) (xy 370.061297 -358.357571) (xy 370.031823 -358.311721)
			(xy 370.009176 -358.262142) (xy 369.993814 -358.209846) (xy 369.986051 -358.155895) (xy 369.986045 -358.101389)
			(xy 369.993796 -358.047437) (xy 370.009146 -357.995136) (xy 370.031783 -357.945553) (xy 370.061246 -357.899696)
			(xy 370.096935 -357.858499) (xy 370.138124 -357.8228) (xy 370.183974 -357.793326) (xy 370.233552 -357.770678)
			(xy 370.285848 -357.755315) (xy 370.339799 -357.747551) (xy 370.367052 -357.747062) (xy 370.380048 -357.747169)
			(xy 370.405979 -357.748949) (xy 370.418868 -357.750618) (xy 370.433246 -357.752024) (xy 370.461801 -357.747758)
			(xy 370.488017 -357.735664) (xy 370.509796 -357.71671) (xy 370.525393 -357.692414) (xy 370.533559 -357.664721)
			(xy 370.53364 -357.635849) (xy 370.53012 -357.62184) (xy 370.524156 -357.59993) (xy 370.516902 -357.555104)
			(xy 370.515642 -357.532432) (xy 370.514118 -357.49357) (xy 370.503958 -357.483664) (xy 370.127022 -357.483664)
			(xy 368.646202 -358.964484) (xy 370.72773 -358.964484) (xy 370.731801 -358.908862) (xy 370.743927 -358.854425)
			(xy 370.76385 -358.802334) (xy 370.791146 -358.753699) (xy 370.825232 -358.709556) (xy 370.865381 -358.670847)
			(xy 370.910739 -358.638396) (xy 370.960339 -358.612895) (xy 371.013123 -358.594888) (xy 371.067966 -358.584758)
			(xy 371.1237 -358.582721) (xy 371.179137 -358.588821) (xy 371.233094 -358.602927) (xy 371.284423 -358.624739)
			(xy 371.332029 -358.653793) (xy 371.374897 -358.689468) (xy 371.412114 -358.731005) (xy 371.442887 -358.777518)
			(xy 371.466559 -358.828015) (xy 371.482627 -358.881422) (xy 371.490747 -358.936598) (xy 371.491256 -358.964484)
			(xy 371.490747 -358.99237) (xy 371.482627 -359.047546) (xy 371.466559 -359.100953) (xy 371.442887 -359.15145)
			(xy 371.412114 -359.197963) (xy 371.374897 -359.2395) (xy 371.332029 -359.275175) (xy 371.284423 -359.304229)
			(xy 371.233094 -359.326041) (xy 371.179137 -359.340147) (xy 371.1237 -359.346247) (xy 371.067966 -359.34421)
			(xy 371.013123 -359.33408) (xy 370.960339 -359.316073) (xy 370.910739 -359.290572) (xy 370.865381 -359.258121)
			(xy 370.825232 -359.219412) (xy 370.791146 -359.175269) (xy 370.76385 -359.126634) (xy 370.743927 -359.074543)
			(xy 370.731801 -359.020106) (xy 370.72773 -358.964484) (xy 368.646202 -358.964484) (xy 367.928652 -359.682034)
			(xy 367.928652 -360.680508) (xy 376.90628 -360.680508) (xy 376.910351 -360.624886) (xy 376.922477 -360.570449)
			(xy 376.9424 -360.518358) (xy 376.969696 -360.469723) (xy 377.003782 -360.42558) (xy 377.043931 -360.386871)
			(xy 377.089289 -360.35442) (xy 377.138889 -360.328919) (xy 377.191673 -360.310912) (xy 377.246516 -360.300782)
			(xy 377.30225 -360.298745) (xy 377.357687 -360.304845) (xy 377.411644 -360.318951) (xy 377.462973 -360.340763)
			(xy 377.510579 -360.369817) (xy 377.553447 -360.405492) (xy 377.590664 -360.447029) (xy 377.621437 -360.493542)
			(xy 377.645109 -360.544039) (xy 377.661177 -360.597446) (xy 377.669297 -360.652622) (xy 377.669806 -360.680508)
			(xy 377.669297 -360.708394) (xy 377.661177 -360.76357) (xy 377.645109 -360.816977) (xy 377.621437 -360.867474)
			(xy 377.590664 -360.913987) (xy 377.553447 -360.955524) (xy 377.510579 -360.991199) (xy 377.462973 -361.020253)
			(xy 377.411644 -361.042065) (xy 377.357687 -361.056171) (xy 377.30225 -361.062271) (xy 377.246516 -361.060234)
			(xy 377.191673 -361.050104) (xy 377.138889 -361.032097) (xy 377.089289 -361.006596) (xy 377.043931 -360.974145)
			(xy 377.003782 -360.935436) (xy 376.969696 -360.891293) (xy 376.9424 -360.842658) (xy 376.922477 -360.790567)
			(xy 376.910351 -360.73613) (xy 376.90628 -360.680508) (xy 367.928652 -360.680508) (xy 367.928652 -361.133136)
			(xy 369.3861 -361.133136) (xy 369.390189 -361.077254) (xy 369.402372 -361.022564) (xy 369.422388 -360.97023)
			(xy 369.449811 -360.921368) (xy 369.484056 -360.87702) (xy 369.524392 -360.83813) (xy 369.569962 -360.805528)
			(xy 369.619793 -360.779909) (xy 369.672823 -360.761817) (xy 369.727921 -360.75164) (xy 369.783915 -360.749594)
			(xy 369.83961 -360.755722) (xy 369.893819 -360.769894) (xy 369.945387 -360.791808) (xy 369.993215 -360.820997)
			(xy 370.036283 -360.856838) (xy 370.073673 -360.898568) (xy 370.104589 -360.945298) (xy 370.128372 -360.996031)
			(xy 370.144514 -361.049687) (xy 370.152673 -361.105121) (xy 370.153184 -361.133136) (xy 370.152673 -361.161151)
			(xy 370.144514 -361.216585) (xy 370.128372 -361.270241) (xy 370.104589 -361.320974) (xy 370.073673 -361.367704)
			(xy 370.036283 -361.409434) (xy 369.993215 -361.445275) (xy 369.945387 -361.474464) (xy 369.893819 -361.496378)
			(xy 369.83961 -361.51055) (xy 369.783915 -361.516678) (xy 369.727921 -361.514632) (xy 369.672823 -361.504455)
			(xy 369.619793 -361.486363) (xy 369.569962 -361.460744) (xy 369.524392 -361.428142) (xy 369.484056 -361.389252)
			(xy 369.449811 -361.344904) (xy 369.422388 -361.296042) (xy 369.402372 -361.243708) (xy 369.390189 -361.189018)
			(xy 369.3861 -361.133136) (xy 367.928652 -361.133136) (xy 367.928652 -362.097066) (xy 376.025154 -362.097066)
			(xy 376.029225 -362.041444) (xy 376.041351 -361.987007) (xy 376.061274 -361.934916) (xy 376.08857 -361.886281)
			(xy 376.122656 -361.842138) (xy 376.162805 -361.803429) (xy 376.208163 -361.770978) (xy 376.257763 -361.745477)
			(xy 376.310547 -361.72747) (xy 376.36539 -361.71734) (xy 376.421124 -361.715303) (xy 376.476561 -361.721403)
			(xy 376.530518 -361.735509) (xy 376.581847 -361.757321) (xy 376.629453 -361.786375) (xy 376.672321 -361.82205)
			(xy 376.709538 -361.863587) (xy 376.740311 -361.9101) (xy 376.763983 -361.960597) (xy 376.780051 -362.014004)
			(xy 376.788171 -362.06918) (xy 376.78868 -362.097066) (xy 376.788171 -362.124952) (xy 376.780051 -362.180128)
			(xy 376.763983 -362.233535) (xy 376.740311 -362.284032) (xy 376.709538 -362.330545) (xy 376.672321 -362.372082)
			(xy 376.629453 -362.407757) (xy 376.581847 -362.436811) (xy 376.530518 -362.458623) (xy 376.476561 -362.472729)
			(xy 376.421124 -362.478829) (xy 376.36539 -362.476792) (xy 376.310547 -362.466662) (xy 376.257763 -362.448655)
			(xy 376.208163 -362.423154) (xy 376.162805 -362.390703) (xy 376.122656 -362.351994) (xy 376.08857 -362.307851)
			(xy 376.061274 -362.259216) (xy 376.041351 -362.207125) (xy 376.029225 -362.152688) (xy 376.025154 -362.097066)
			(xy 367.928652 -362.097066) (xy 367.928652 -364.729776) (xy 367.928068 -364.754761) (xy 367.918316 -364.80377)
			(xy 367.8992 -364.84994) (xy 367.871455 -364.891499) (xy 367.85423 -364.909608) (xy 367.60531 -365.158528)
			(xy 367.587208 -365.175777) (xy 367.545665 -365.203587) (xy 367.499496 -365.222762) (xy 367.450474 -365.232565)
			(xy 367.425478 -365.233204) (xy 365.978694 -365.233204) (xy 365.960501 -365.252797) (xy 365.919622 -365.287257)
			(xy 365.874333 -365.315673) (xy 365.825521 -365.337489) (xy 365.774141 -365.352278) (xy 365.721201 -365.35975)
			(xy 365.694468 -365.360204) (xy 365.667218 -365.359724) (xy 365.613273 -365.351964) (xy 365.560982 -365.336606)
			(xy 365.511408 -365.313962) (xy 365.465561 -365.284495) (xy 365.424374 -365.248803) (xy 365.388686 -365.207613)
			(xy 365.359222 -365.161764) (xy 365.336583 -365.112188) (xy 365.321229 -365.059896) (xy 365.313474 -365.00595)
			(xy 364.587601 -365.00595) (xy 364.549969 -365.033331) (xy 364.50545 -365.056042) (xy 364.457924 -365.0715)
			(xy 364.408563 -365.079324) (xy 364.383574 -365.079788) (xy 362.4961 -365.079788) (xy 362.471113 -365.079314)
			(xy 362.421756 -365.071479) (xy 362.374234 -365.056018) (xy 362.329716 -365.033311) (xy 362.289299 -365.003919)
			(xy 362.27131 -364.98657) (xy 361.857036 -364.572296) (xy 361.843066 -364.56874) (xy 361.815671 -364.561617)
			(xy 361.763193 -364.540405) (xy 361.714425 -364.511672) (xy 361.670438 -364.476049) (xy 361.632198 -364.434317)
			(xy 361.600544 -364.387393) (xy 361.57617 -364.336307) (xy 361.559612 -364.28218) (xy 361.551234 -364.226201)
			(xy 361.550712 -364.1979) (xy 360.114137 -364.1979) (xy 360.114596 -364.223046) (xy 360.114087 -364.250932)
			(xy 360.105967 -364.306108) (xy 360.089899 -364.359515) (xy 360.066227 -364.410012) (xy 360.035454 -364.456525)
			(xy 359.998237 -364.498062) (xy 359.955369 -364.533737) (xy 359.907763 -364.562791) (xy 359.856434 -364.584603)
			(xy 359.802477 -364.598709) (xy 359.74704 -364.604809) (xy 359.691306 -364.602772) (xy 359.636463 -364.592642)
			(xy 359.583679 -364.574635) (xy 359.534079 -364.549134) (xy 359.488721 -364.516683) (xy 359.448572 -364.477974)
			(xy 359.414486 -364.433831) (xy 359.38719 -364.385196) (xy 359.367267 -364.333105) (xy 359.355141 -364.278668)
			(xy 359.35107 -364.223046) (xy 358.794812 -364.223046) (xy 358.520238 -364.49762) (xy 358.516682 -364.51032)
			(xy 358.508662 -364.536572) (xy 358.486272 -364.586684) (xy 358.456931 -364.633071) (xy 358.421245 -364.674773)
			(xy 358.37995 -364.710931) (xy 358.333901 -364.740798) (xy 358.284046 -364.763757) (xy 358.231415 -364.779334)
			(xy 358.177096 -364.787207) (xy 358.149652 -364.787688) (xy 358.122402 -364.787239) (xy 358.068456 -364.779476)
			(xy 358.016164 -364.764116) (xy 357.966591 -364.741471) (xy 357.920744 -364.712002) (xy 357.879557 -364.676309)
			(xy 357.843869 -364.635118) (xy 357.814406 -364.589267) (xy 357.791767 -364.53969) (xy 357.776413 -364.487397)
			(xy 357.768658 -364.43345) (xy 356.326405 -364.43345) (xy 356.3215 -364.467567) (xy 356.306145 -364.519862)
			(xy 356.283503 -364.569439) (xy 356.254037 -364.615289) (xy 356.218346 -364.65648) (xy 356.177155 -364.692171)
			(xy 356.131305 -364.721637) (xy 356.081728 -364.744279) (xy 356.029433 -364.759634) (xy 355.975485 -364.76739)
			(xy 355.920983 -364.76739) (xy 355.867035 -364.759634) (xy 355.81474 -364.744279) (xy 355.765163 -364.721637)
			(xy 355.719313 -364.692171) (xy 355.678122 -364.65648) (xy 355.642431 -364.615289) (xy 355.612965 -364.569439)
			(xy 355.590323 -364.519862) (xy 355.574968 -364.467567) (xy 355.567212 -364.413619) (xy 355.566726 -364.386368)
			(xy 355.00437 -364.386368) (xy 354.81514 -364.575598) (xy 354.804586 -364.585912) (xy 354.781269 -364.604001)
			(xy 354.768658 -364.611666) (xy 354.753756 -364.635327) (xy 354.718095 -364.678398) (xy 354.676526 -364.715799)
			(xy 354.62994 -364.746727) (xy 354.579337 -364.77052) (xy 354.525801 -364.786668) (xy 354.470481 -364.794823)
			(xy 354.442522 -364.795308) (xy 354.415268 -364.794846) (xy 354.361315 -364.787092) (xy 354.309014 -364.771738)
			(xy 354.259431 -364.749096) (xy 354.213576 -364.719629) (xy 354.17238 -364.683935) (xy 354.136684 -364.642742)
			(xy 354.107214 -364.596888) (xy 354.08457 -364.547306) (xy 354.069213 -364.495007) (xy 354.061455 -364.441054)
			(xy 353.451084 -364.441054) (xy 353.21113 -364.681008) (xy 353.194873 -364.696556) (xy 353.157486 -364.721561)
			(xy 353.115935 -364.738781) (xy 353.071821 -364.747554) (xy 353.049332 -364.748064) (xy 351.054416 -364.748064)
			(xy 351.031932 -364.747528) (xy 350.987833 -364.738729) (xy 350.946293 -364.721506) (xy 350.908907 -364.696517)
			(xy 350.892618 -364.681008) (xy 348.719902 -362.508292) (xy 348.704317 -362.492053) (xy 348.679245 -362.454678)
			(xy 348.661961 -362.413125) (xy 348.653129 -362.368996) (xy 348.652592 -362.346494) (xy 348.652592 -361.625388)
			(xy 348.653182 -361.602893) (xy 348.662033 -361.558781) (xy 348.679315 -361.51724) (xy 348.704363 -361.479866)
			(xy 348.719902 -361.46359) (xy 348.944692 -361.238546) (xy 348.944692 -354.87737) (xy 346.18168 -352.114104)
			(xy 346.166118 -352.09786) (xy 346.141116 -352.060469) (xy 346.123899 -352.018914) (xy 346.115132 -351.974796)
			(xy 346.114624 -351.952306) (xy 346.114624 -347.534992) (xy 343.46134 -344.881708) (xy 343.445773 -344.865469)
			(xy 343.420774 -344.828075) (xy 343.403559 -344.786519) (xy 343.394792 -344.742401) (xy 343.394284 -344.71991)
			(xy 342.199214 -344.71991) (xy 345.733116 -348.253812) (xy 345.748638 -348.270092) (xy 345.773647 -348.307471)
			(xy 345.790875 -348.349015) (xy 345.799657 -348.393123) (xy 345.800172 -348.41561) (xy 345.800172 -353.008946)
			(xy 346.559378 -353.768152) (xy 346.574933 -353.784418) (xy 346.600011 -353.821783) (xy 346.617304 -353.863328)
			(xy 346.626146 -353.907451) (xy 346.626688 -353.92995) (xy 346.626688 -355.359462) (xy 346.916246 -355.359462)
			(xy 346.920317 -355.30384) (xy 346.932443 -355.249403) (xy 346.952366 -355.197312) (xy 346.979662 -355.148677)
			(xy 347.013748 -355.104534) (xy 347.053897 -355.065825) (xy 347.099255 -355.033374) (xy 347.148855 -355.007873)
			(xy 347.201639 -354.989866) (xy 347.256482 -354.979736) (xy 347.312216 -354.977699) (xy 347.367653 -354.983799)
			(xy 347.42161 -354.997905) (xy 347.472939 -355.019717) (xy 347.520545 -355.048771) (xy 347.563413 -355.084446)
			(xy 347.60063 -355.125983) (xy 347.631403 -355.172496) (xy 347.655075 -355.222993) (xy 347.671143 -355.2764)
			(xy 347.679263 -355.331576) (xy 347.679772 -355.359462) (xy 347.679263 -355.387348) (xy 347.671143 -355.442524)
			(xy 347.655075 -355.495931) (xy 347.631403 -355.546428) (xy 347.60063 -355.592941) (xy 347.563413 -355.634478)
			(xy 347.520545 -355.670153) (xy 347.472939 -355.699207) (xy 347.42161 -355.721019) (xy 347.367653 -355.735125)
			(xy 347.312216 -355.741225) (xy 347.256482 -355.739188) (xy 347.201639 -355.729058) (xy 347.148855 -355.711051)
			(xy 347.099255 -355.68555) (xy 347.053897 -355.653099) (xy 347.013748 -355.61439) (xy 346.979662 -355.570247)
			(xy 346.952366 -355.521612) (xy 346.932443 -355.469521) (xy 346.920317 -355.415084) (xy 346.916246 -355.359462)
			(xy 346.626688 -355.359462) (xy 346.626688 -356.478332) (xy 346.916246 -356.478332) (xy 346.920317 -356.42271)
			(xy 346.932443 -356.368273) (xy 346.952366 -356.316182) (xy 346.979662 -356.267547) (xy 347.013748 -356.223404)
			(xy 347.053897 -356.184695) (xy 347.099255 -356.152244) (xy 347.148855 -356.126743) (xy 347.201639 -356.108736)
			(xy 347.256482 -356.098606) (xy 347.312216 -356.096569) (xy 347.367653 -356.102669) (xy 347.42161 -356.116775)
			(xy 347.472939 -356.138587) (xy 347.520545 -356.167641) (xy 347.563413 -356.203316) (xy 347.60063 -356.244853)
			(xy 347.631403 -356.291366) (xy 347.655075 -356.341863) (xy 347.671143 -356.39527) (xy 347.679263 -356.450446)
			(xy 347.679772 -356.478332) (xy 347.679263 -356.506218) (xy 347.671143 -356.561394) (xy 347.655075 -356.614801)
			(xy 347.631403 -356.665298) (xy 347.60063 -356.711811) (xy 347.563413 -356.753348) (xy 347.520545 -356.789023)
			(xy 347.472939 -356.818077) (xy 347.42161 -356.839889) (xy 347.367653 -356.853995) (xy 347.312216 -356.860095)
			(xy 347.256482 -356.858058) (xy 347.201639 -356.847928) (xy 347.148855 -356.829921) (xy 347.099255 -356.80442)
			(xy 347.053897 -356.771969) (xy 347.013748 -356.73326) (xy 346.979662 -356.689117) (xy 346.952366 -356.640482)
			(xy 346.932443 -356.588391) (xy 346.920317 -356.533954) (xy 346.916246 -356.478332) (xy 346.626688 -356.478332)
			(xy 346.626688 -357.494332) (xy 346.916246 -357.494332) (xy 346.920317 -357.43871) (xy 346.932443 -357.384273)
			(xy 346.952366 -357.332182) (xy 346.979662 -357.283547) (xy 347.013748 -357.239404) (xy 347.053897 -357.200695)
			(xy 347.099255 -357.168244) (xy 347.148855 -357.142743) (xy 347.201639 -357.124736) (xy 347.256482 -357.114606)
			(xy 347.312216 -357.112569) (xy 347.367653 -357.118669) (xy 347.42161 -357.132775) (xy 347.472939 -357.154587)
			(xy 347.520545 -357.183641) (xy 347.563413 -357.219316) (xy 347.60063 -357.260853) (xy 347.631403 -357.307366)
			(xy 347.655075 -357.357863) (xy 347.671143 -357.41127) (xy 347.679263 -357.466446) (xy 347.679772 -357.494332)
			(xy 347.679263 -357.522218) (xy 347.671143 -357.577394) (xy 347.655075 -357.630801) (xy 347.631403 -357.681298)
			(xy 347.60063 -357.727811) (xy 347.563413 -357.769348) (xy 347.520545 -357.805023) (xy 347.472939 -357.834077)
			(xy 347.42161 -357.855889) (xy 347.367653 -357.869995) (xy 347.312216 -357.876095) (xy 347.256482 -357.874058)
			(xy 347.201639 -357.863928) (xy 347.148855 -357.845921) (xy 347.099255 -357.82042) (xy 347.053897 -357.787969)
			(xy 347.013748 -357.74926) (xy 346.979662 -357.705117) (xy 346.952366 -357.656482) (xy 346.932443 -357.604391)
			(xy 346.920317 -357.549954) (xy 346.916246 -357.494332) (xy 346.626688 -357.494332) (xy 346.626688 -358.217724)
			(xy 347.824296 -358.217724) (xy 347.828367 -358.162102) (xy 347.840493 -358.107665) (xy 347.860416 -358.055574)
			(xy 347.887712 -358.006939) (xy 347.921798 -357.962796) (xy 347.961947 -357.924087) (xy 348.007305 -357.891636)
			(xy 348.056905 -357.866135) (xy 348.109689 -357.848128) (xy 348.164532 -357.837998) (xy 348.220266 -357.835961)
			(xy 348.275703 -357.842061) (xy 348.32966 -357.856167) (xy 348.380989 -357.877979) (xy 348.428595 -357.907033)
			(xy 348.471463 -357.942708) (xy 348.50868 -357.984245) (xy 348.539453 -358.030758) (xy 348.563125 -358.081255)
			(xy 348.579193 -358.134662) (xy 348.587313 -358.189838) (xy 348.587822 -358.217724) (xy 348.587313 -358.24561)
			(xy 348.579193 -358.300786) (xy 348.563125 -358.354193) (xy 348.539453 -358.40469) (xy 348.50868 -358.451203)
			(xy 348.471463 -358.49274) (xy 348.428595 -358.528415) (xy 348.380989 -358.557469) (xy 348.32966 -358.579281)
			(xy 348.275703 -358.593387) (xy 348.220266 -358.599487) (xy 348.164532 -358.59745) (xy 348.109689 -358.58732)
			(xy 348.056905 -358.569313) (xy 348.007305 -358.543812) (xy 347.961947 -358.511361) (xy 347.921798 -358.472652)
			(xy 347.887712 -358.428509) (xy 347.860416 -358.379874) (xy 347.840493 -358.327783) (xy 347.828367 -358.273346)
			(xy 347.824296 -358.217724) (xy 346.626688 -358.217724) (xy 346.626688 -359.353612) (xy 346.946726 -359.353612)
			(xy 346.950797 -359.29799) (xy 346.962923 -359.243553) (xy 346.982846 -359.191462) (xy 347.010142 -359.142827)
			(xy 347.044228 -359.098684) (xy 347.084377 -359.059975) (xy 347.129735 -359.027524) (xy 347.179335 -359.002023)
			(xy 347.232119 -358.984016) (xy 347.286962 -358.973886) (xy 347.342696 -358.971849) (xy 347.398133 -358.977949)
			(xy 347.45209 -358.992055) (xy 347.503419 -359.013867) (xy 347.551025 -359.042921) (xy 347.593893 -359.078596)
			(xy 347.63111 -359.120133) (xy 347.661883 -359.166646) (xy 347.685555 -359.217143) (xy 347.701623 -359.27055)
			(xy 347.709743 -359.325726) (xy 347.710252 -359.353612) (xy 347.709743 -359.381498) (xy 347.701623 -359.436674)
			(xy 347.685555 -359.490081) (xy 347.661883 -359.540578) (xy 347.63111 -359.587091) (xy 347.593893 -359.628628)
			(xy 347.551025 -359.664303) (xy 347.503419 -359.693357) (xy 347.45209 -359.715169) (xy 347.398133 -359.729275)
			(xy 347.342696 -359.735375) (xy 347.286962 -359.733338) (xy 347.232119 -359.723208) (xy 347.179335 -359.705201)
			(xy 347.129735 -359.6797) (xy 347.084377 -359.647249) (xy 347.044228 -359.60854) (xy 347.010142 -359.564397)
			(xy 346.982846 -359.515762) (xy 346.962923 -359.463671) (xy 346.950797 -359.409234) (xy 346.946726 -359.353612)
			(xy 346.626688 -359.353612) (xy 346.626688 -360.48569) (xy 347.061788 -360.48569) (xy 347.065859 -360.430068)
			(xy 347.077985 -360.375631) (xy 347.097908 -360.32354) (xy 347.125204 -360.274905) (xy 347.15929 -360.230762)
			(xy 347.199439 -360.192053) (xy 347.244797 -360.159602) (xy 347.294397 -360.134101) (xy 347.347181 -360.116094)
			(xy 347.402024 -360.105964) (xy 347.457758 -360.103927) (xy 347.513195 -360.110027) (xy 347.567152 -360.124133)
			(xy 347.618481 -360.145945) (xy 347.666087 -360.174999) (xy 347.708955 -360.210674) (xy 347.746172 -360.252211)
			(xy 347.776945 -360.298724) (xy 347.800617 -360.349221) (xy 347.816685 -360.402628) (xy 347.824805 -360.457804)
			(xy 347.825314 -360.48569) (xy 347.824805 -360.513576) (xy 347.816685 -360.568752) (xy 347.800617 -360.622159)
			(xy 347.776945 -360.672656) (xy 347.746172 -360.719169) (xy 347.708955 -360.760706) (xy 347.666087 -360.796381)
			(xy 347.618481 -360.825435) (xy 347.567152 -360.847247) (xy 347.513195 -360.861353) (xy 347.457758 -360.867453)
			(xy 347.402024 -360.865416) (xy 347.347181 -360.855286) (xy 347.294397 -360.837279) (xy 347.244797 -360.811778)
			(xy 347.199439 -360.779327) (xy 347.15929 -360.740618) (xy 347.125204 -360.696475) (xy 347.097908 -360.64784)
			(xy 347.077985 -360.595749) (xy 347.065859 -360.541312) (xy 347.061788 -360.48569) (xy 346.626688 -360.48569)
			(xy 346.626688 -360.814366) (xy 346.974668 -361.162346) (xy 347.74454 -361.162346) (xy 347.748611 -361.106724)
			(xy 347.760737 -361.052287) (xy 347.78066 -361.000196) (xy 347.807956 -360.951561) (xy 347.842042 -360.907418)
			(xy 347.882191 -360.868709) (xy 347.927549 -360.836258) (xy 347.977149 -360.810757) (xy 348.029933 -360.79275)
			(xy 348.084776 -360.78262) (xy 348.14051 -360.780583) (xy 348.195947 -360.786683) (xy 348.249904 -360.800789)
			(xy 348.301233 -360.822601) (xy 348.348839 -360.851655) (xy 348.391707 -360.88733) (xy 348.428924 -360.928867)
			(xy 348.459697 -360.97538) (xy 348.483369 -361.025877) (xy 348.499437 -361.079284) (xy 348.507557 -361.13446)
			(xy 348.508066 -361.162346) (xy 348.507557 -361.190232) (xy 348.499437 -361.245408) (xy 348.483369 -361.298815)
			(xy 348.459697 -361.349312) (xy 348.428924 -361.395825) (xy 348.391707 -361.437362) (xy 348.348839 -361.473037)
			(xy 348.301233 -361.502091) (xy 348.249904 -361.523903) (xy 348.195947 -361.538009) (xy 348.14051 -361.544109)
			(xy 348.084776 -361.542072) (xy 348.029933 -361.531942) (xy 347.977149 -361.513935) (xy 347.927549 -361.488434)
			(xy 347.882191 -361.455983) (xy 347.842042 -361.417274) (xy 347.807956 -361.373131) (xy 347.78066 -361.324496)
			(xy 347.760737 -361.272405) (xy 347.748611 -361.217968) (xy 347.74454 -361.162346) (xy 346.974668 -361.162346)
			(xy 350.876362 -365.06404) (xy 354.885498 -365.06404) (xy 354.899722 -365.037116) (xy 354.914108 -365.011368)
			(xy 354.949516 -364.964203) (xy 354.991758 -364.923046) (xy 355.039828 -364.888877) (xy 355.092582 -364.862509)
			(xy 355.148765 -364.84457) (xy 355.207038 -364.835487) (xy 355.236526 -364.834932) (xy 355.263779 -364.83534)
			(xy 355.317729 -364.8431) (xy 355.370027 -364.858459) (xy 355.419606 -364.881104) (xy 355.465458 -364.910574)
			(xy 355.500103 -364.940596) (xy 358.631742 -364.940596) (xy 358.635813 -364.884974) (xy 358.647939 -364.830537)
			(xy 358.667862 -364.778446) (xy 358.695158 -364.729811) (xy 358.729244 -364.685668) (xy 358.769393 -364.646959)
			(xy 358.814751 -364.614508) (xy 358.864351 -364.589007) (xy 358.917135 -364.571) (xy 358.971978 -364.56087)
			(xy 359.027712 -364.558833) (xy 359.083149 -364.564933) (xy 359.137106 -364.579039) (xy 359.188435 -364.600851)
			(xy 359.236041 -364.629905) (xy 359.278909 -364.66558) (xy 359.316126 -364.707117) (xy 359.329101 -364.726728)
			(xy 360.233466 -364.726728) (xy 360.237537 -364.671106) (xy 360.249663 -364.616669) (xy 360.269586 -364.564578)
			(xy 360.296882 -364.515943) (xy 360.330968 -364.4718) (xy 360.371117 -364.433091) (xy 360.416475 -364.40064)
			(xy 360.466075 -364.375139) (xy 360.518859 -364.357132) (xy 360.573702 -364.347002) (xy 360.629436 -364.344965)
			(xy 360.684873 -364.351065) (xy 360.73883 -364.365171) (xy 360.790159 -364.386983) (xy 360.837765 -364.416037)
			(xy 360.880633 -364.451712) (xy 360.91785 -364.493249) (xy 360.948623 -364.539762) (xy 360.972295 -364.590259)
			(xy 360.988363 -364.643666) (xy 360.996483 -364.698842) (xy 360.996992 -364.726728) (xy 360.996483 -364.754614)
			(xy 360.988363 -364.80979) (xy 360.972295 -364.863197) (xy 360.948623 -364.913694) (xy 360.91785 -364.960207)
			(xy 360.880633 -365.001744) (xy 360.837765 -365.037419) (xy 360.790159 -365.066473) (xy 360.73883 -365.088285)
			(xy 360.684873 -365.102391) (xy 360.629436 -365.108491) (xy 360.573702 -365.106454) (xy 360.518859 -365.096324)
			(xy 360.466075 -365.078317) (xy 360.416475 -365.052816) (xy 360.371117 -365.020365) (xy 360.330968 -364.981656)
			(xy 360.296882 -364.937513) (xy 360.269586 -364.888878) (xy 360.249663 -364.836787) (xy 360.237537 -364.78235)
			(xy 360.233466 -364.726728) (xy 359.329101 -364.726728) (xy 359.346899 -364.75363) (xy 359.370571 -364.804127)
			(xy 359.386639 -364.857534) (xy 359.394759 -364.91271) (xy 359.395268 -364.940596) (xy 359.394759 -364.968482)
			(xy 359.386639 -365.023658) (xy 359.370571 -365.077065) (xy 359.346899 -365.127562) (xy 359.316126 -365.174075)
			(xy 359.278909 -365.215612) (xy 359.236041 -365.251287) (xy 359.188435 -365.280341) (xy 359.137106 -365.302153)
			(xy 359.083149 -365.316259) (xy 359.027712 -365.322359) (xy 358.971978 -365.320322) (xy 358.917135 -365.310192)
			(xy 358.864351 -365.292185) (xy 358.814751 -365.266684) (xy 358.769393 -365.234233) (xy 358.729244 -365.195524)
			(xy 358.695158 -365.151381) (xy 358.667862 -365.102746) (xy 358.647939 -365.050655) (xy 358.635813 -364.996218)
			(xy 358.631742 -364.940596) (xy 355.500103 -364.940596) (xy 355.506649 -364.946269) (xy 355.542342 -364.987463)
			(xy 355.571809 -365.033317) (xy 355.59445 -365.082898) (xy 355.609806 -365.135196) (xy 355.617562 -365.189147)
			(xy 355.617562 -365.243653) (xy 355.609806 -365.297604) (xy 355.59445 -365.349902) (xy 355.571809 -365.399483)
			(xy 355.542342 -365.445337) (xy 355.506649 -365.486531) (xy 355.465458 -365.522226) (xy 355.419606 -365.551696)
			(xy 355.370027 -365.574341) (xy 355.317729 -365.5897) (xy 355.263779 -365.59746) (xy 355.236526 -365.597948)
			(xy 355.236018 -365.597948) (xy 355.205471 -365.597353) (xy 355.145165 -365.587571) (xy 355.087188 -365.568302)
			(xy 355.033024 -365.54004) (xy 355.00818 -365.522256) (xy 350.78162 -365.522256) (xy 350.759125 -365.521661)
			(xy 350.715012 -365.512814) (xy 350.673471 -365.495534) (xy 350.636098 -365.470485) (xy 350.619822 -365.454946)
			(xy 346.235782 -361.070906) (xy 346.2202 -361.054664) (xy 346.195129 -361.01729) (xy 346.177844 -360.975738)
			(xy 346.16901 -360.93161) (xy 346.168472 -360.909108) (xy 346.168472 -354.024692) (xy 345.40952 -353.265486)
			(xy 345.393986 -353.249217) (xy 345.368982 -353.211833) (xy 345.351759 -353.170286) (xy 345.342979 -353.126176)
			(xy 345.342464 -353.103688) (xy 345.342464 -348.510352) (xy 340.689438 -343.85758) (xy 339.075522 -343.85758)
			(xy 339.053028 -343.856977) (xy 339.008915 -343.848131) (xy 338.967375 -343.830854) (xy 338.93 -343.805808)
			(xy 338.913724 -343.79027) (xy 336.93989 -341.816436) (xy 336.916268 -341.818468) (xy 336.88528 -341.819738)
			(xy 336.85803 -341.819241) (xy 336.804084 -341.811482) (xy 336.751791 -341.796126) (xy 336.702216 -341.773485)
			(xy 336.656367 -341.744019) (xy 336.615178 -341.708329) (xy 336.579487 -341.667141) (xy 336.55002 -341.621293)
			(xy 336.527377 -341.571718) (xy 336.51202 -341.519426) (xy 336.50426 -341.46548) (xy 336.503772 -341.43823)
			(xy 336.503772 -341.437976) (xy 336.50435 -341.408137) (xy 336.513664 -341.349191) (xy 336.522314 -341.320628)
			(xy 336.526356 -341.306722) (xy 336.527261 -341.277789) (xy 336.519994 -341.24977) (xy 336.505141 -341.224924)
			(xy 336.4839 -341.205258) (xy 336.457986 -341.19236) (xy 336.443828 -341.18931) (xy 336.41099 -341.182721)
			(xy 336.348137 -341.159602) (xy 336.31886 -341.143336) (xy 336.305903 -341.136282) (xy 336.277264 -341.129254)
			(xy 336.24781 -341.130702) (xy 336.219998 -341.140507) (xy 336.196148 -341.157851) (xy 336.178248 -341.181287)
			(xy 336.172556 -341.194898) (xy 336.161829 -341.221661) (xy 336.133545 -341.271902) (xy 336.09802 -341.317312)
			(xy 336.056063 -341.356855) (xy 336.00863 -341.38963) (xy 335.956803 -341.414891) (xy 335.901764 -341.43206)
			(xy 335.844767 -341.440746) (xy 335.81594 -341.441278) (xy 335.788683 -341.440878) (xy 335.734724 -341.433125)
			(xy 335.682417 -341.417771) (xy 335.632828 -341.395129) (xy 335.586966 -341.36566) (xy 335.545765 -341.329963)
			(xy 335.510064 -341.288766) (xy 335.48059 -341.242908) (xy 335.457943 -341.193321) (xy 335.442584 -341.141016)
			(xy 335.434825 -341.087057) (xy 335.114749 -341.087057) (xy 335.092211 -341.118472) (xy 335.05054 -341.160774)
			(xy 335.027016 -341.178896) (xy 335.016377 -341.187286) (xy 334.999666 -341.208606) (xy 334.989147 -341.233568)
			(xy 334.98556 -341.260418) (xy 334.989156 -341.287267) (xy 334.999684 -341.312225) (xy 335.016403 -341.333539)
			(xy 335.027016 -341.341964) (xy 335.050513 -341.360117) (xy 335.092173 -341.402418) (xy 335.126779 -341.450661)
			(xy 335.153494 -341.503683) (xy 335.171673 -341.560203) (xy 335.180879 -341.618856) (xy 335.181448 -341.648542)
			(xy 335.180962 -341.675793) (xy 335.173206 -341.729741) (xy 335.157851 -341.782036) (xy 335.135209 -341.831613)
			(xy 335.105743 -341.877463) (xy 335.070052 -341.918654) (xy 335.028861 -341.954345) (xy 334.983011 -341.983811)
			(xy 334.933434 -342.006453) (xy 334.881139 -342.021808) (xy 334.827191 -342.029564) (xy 334.772689 -342.029564)
			(xy 334.718741 -342.021808) (xy 334.666446 -342.006453) (xy 334.616869 -341.983811) (xy 334.571019 -341.954345)
			(xy 334.529828 -341.918654) (xy 334.494137 -341.877463) (xy 334.464671 -341.831613) (xy 334.442029 -341.782036)
			(xy 334.426674 -341.729741) (xy 334.418918 -341.675793) (xy 334.418432 -341.648542) (xy 319.153794 -341.648542)
			(xy 321.560698 -344.055446) (xy 321.560698 -344.446606) (xy 324.569328 -344.446606) (xy 324.569934 -344.416953)
			(xy 324.579123 -344.358362) (xy 324.597265 -344.301898) (xy 324.623923 -344.24892) (xy 324.658456 -344.200704)
			(xy 324.700032 -344.15841) (xy 324.723506 -344.140282) (xy 324.735339 -344.13073) (xy 324.753323 -344.106233)
			(xy 324.763305 -344.077529) (xy 324.764401 -344.047159) (xy 324.756515 -344.017811) (xy 324.748906 -344.004646)
			(xy 324.735111 -343.981796) (xy 324.713366 -343.933051) (xy 324.698629 -343.88175) (xy 324.691187 -343.828896)
			(xy 324.69074 -343.802208) (xy 324.691226 -343.774957) (xy 324.698982 -343.721009) (xy 324.714337 -343.668714)
			(xy 324.736979 -343.619137) (xy 324.766445 -343.573287) (xy 324.802136 -343.532096) (xy 324.843327 -343.496405)
			(xy 324.889177 -343.466939) (xy 324.938754 -343.444297) (xy 324.991049 -343.428942) (xy 325.044997 -343.421186)
			(xy 325.099499 -343.421186) (xy 325.153447 -343.428942) (xy 325.205742 -343.444297) (xy 325.255319 -343.466939)
			(xy 325.301169 -343.496405) (xy 325.34236 -343.532096) (xy 325.378051 -343.573287) (xy 325.407517 -343.619137)
			(xy 325.430159 -343.668714) (xy 325.445514 -343.721009) (xy 325.45327 -343.774957) (xy 325.453756 -343.802208)
			(xy 325.453167 -343.831862) (xy 325.443975 -343.890454) (xy 325.42583 -343.946919) (xy 325.399169 -343.999897)
			(xy 325.364633 -344.048112) (xy 325.323054 -344.090405) (xy 325.299578 -344.108532) (xy 325.287732 -344.118069)
			(xy 325.26975 -344.142571) (xy 325.259772 -344.171279) (xy 325.258678 -344.201652) (xy 325.266567 -344.231003)
			(xy 325.274178 -344.244168) (xy 325.287977 -344.267016) (xy 325.309721 -344.315762) (xy 325.324457 -344.367063)
			(xy 325.331898 -344.419918) (xy 325.332344 -344.446606) (xy 325.331858 -344.473857) (xy 325.324102 -344.527805)
			(xy 325.308747 -344.5801) (xy 325.286105 -344.629677) (xy 325.256639 -344.675527) (xy 325.220948 -344.716718)
			(xy 325.179757 -344.752409) (xy 325.133907 -344.781875) (xy 325.08433 -344.804517) (xy 325.032035 -344.819872)
			(xy 324.978087 -344.827628) (xy 324.923585 -344.827628) (xy 324.869637 -344.819872) (xy 324.817342 -344.804517)
			(xy 324.767765 -344.781875) (xy 324.721915 -344.752409) (xy 324.680724 -344.716718) (xy 324.645033 -344.675527)
			(xy 324.615567 -344.629677) (xy 324.592925 -344.5801) (xy 324.57757 -344.527805) (xy 324.569814 -344.473857)
			(xy 324.569328 -344.446606) (xy 321.560698 -344.446606) (xy 321.560698 -344.952066) (xy 322.703442 -344.952066)
			(xy 322.707513 -344.896444) (xy 322.719639 -344.842007) (xy 322.739562 -344.789916) (xy 322.766858 -344.741281)
			(xy 322.800944 -344.697138) (xy 322.841093 -344.658429) (xy 322.886451 -344.625978) (xy 322.936051 -344.600477)
			(xy 322.988835 -344.58247) (xy 323.043678 -344.57234) (xy 323.099412 -344.570303) (xy 323.154849 -344.576403)
			(xy 323.208806 -344.590509) (xy 323.260135 -344.612321) (xy 323.307741 -344.641375) (xy 323.350609 -344.67705)
			(xy 323.387826 -344.718587) (xy 323.418599 -344.7651) (xy 323.442271 -344.815597) (xy 323.458339 -344.869004)
			(xy 323.466459 -344.92418) (xy 323.466968 -344.952066) (xy 323.46688 -344.956892) (xy 323.685406 -344.956892)
			(xy 323.689477 -344.90127) (xy 323.701603 -344.846833) (xy 323.721526 -344.794742) (xy 323.748822 -344.746107)
			(xy 323.782908 -344.701964) (xy 323.823057 -344.663255) (xy 323.868415 -344.630804) (xy 323.918015 -344.605303)
			(xy 323.970799 -344.587296) (xy 324.025642 -344.577166) (xy 324.081376 -344.575129) (xy 324.136813 -344.581229)
			(xy 324.19077 -344.595335) (xy 324.242099 -344.617147) (xy 324.289705 -344.646201) (xy 324.332573 -344.681876)
			(xy 324.36979 -344.723413) (xy 324.400563 -344.769926) (xy 324.424235 -344.820423) (xy 324.430065 -344.8398)
			(xy 328.939331 -344.8398) (xy 328.9435 -344.78418) (xy 328.955912 -344.729802) (xy 328.97629 -344.677882)
			(xy 329.004179 -344.629579) (xy 329.038956 -344.585973) (xy 329.079844 -344.548037) (xy 329.12593 -344.516619)
			(xy 329.176183 -344.492421) (xy 329.229482 -344.475983) (xy 329.284636 -344.467673) (xy 329.312524 -344.46718)
			(xy 329.339854 -344.467705) (xy 329.39393 -344.475668) (xy 329.446262 -344.491448) (xy 329.495725 -344.514708)
			(xy 329.541258 -344.544947) (xy 329.581882 -344.581516) (xy 329.616726 -344.62363) (xy 329.631294 -344.646758)
			(xy 329.639256 -344.658956) (xy 329.660714 -344.678632) (xy 329.686857 -344.691442) (xy 329.715555 -344.696344)
			(xy 329.744468 -344.692937) (xy 329.75804 -344.687652) (xy 329.781247 -344.678155) (xy 329.829581 -344.664808)
			(xy 329.879272 -344.658082) (xy 329.904344 -344.65768) (xy 329.929413 -344.658105) (xy 329.979096 -344.664855)
			(xy 330.02743 -344.678187) (xy 330.050648 -344.687652) (xy 330.064237 -344.692861) (xy 330.09313 -344.696228)
			(xy 330.121802 -344.691324) (xy 330.147934 -344.678545) (xy 330.16941 -344.658926) (xy 330.177394 -344.646758)
			(xy 330.191963 -344.623627) (xy 330.226806 -344.581506) (xy 330.267429 -344.544927) (xy 330.31296 -344.514676)
			(xy 330.362422 -344.4914) (xy 330.414753 -344.4756) (xy 330.468832 -344.467614) (xy 330.523496 -344.467614)
			(xy 330.577575 -344.4756) (xy 330.629906 -344.4914) (xy 330.679368 -344.514676) (xy 330.724899 -344.544927)
			(xy 330.765522 -344.581506) (xy 330.800365 -344.623627) (xy 330.814934 -344.646758) (xy 330.822858 -344.658983)
			(xy 330.844326 -344.678659) (xy 330.87048 -344.691467) (xy 330.899187 -344.696361) (xy 330.928107 -344.692944)
			(xy 330.94168 -344.687652) (xy 330.964894 -344.678174) (xy 331.013225 -344.664819) (xy 331.062913 -344.658086)
			(xy 331.087984 -344.65768) (xy 331.114841 -344.658135) (xy 331.167998 -344.665853) (xy 331.219498 -344.681117)
			(xy 331.268276 -344.703613) (xy 331.313321 -344.732873) (xy 331.353703 -344.768293) (xy 331.388585 -344.80914)
			(xy 331.417247 -344.854569) (xy 331.428598 -344.878914) (xy 331.434622 -344.891386) (xy 331.452244 -344.912739)
			(xy 331.474963 -344.92856) (xy 331.501102 -344.937683) (xy 331.528733 -344.939433) (xy 331.555814 -344.933682)
			(xy 331.568298 -344.927682) (xy 331.595706 -344.914059) (xy 331.653801 -344.894808) (xy 331.714226 -344.885084)
			(xy 331.744828 -344.884502) (xy 331.767947 -344.884832) (xy 331.813848 -344.890401) (xy 331.858736 -344.90149)
			(xy 331.880464 -344.909394) (xy 331.894243 -344.914198) (xy 331.923328 -344.916452) (xy 331.951865 -344.910395)
			(xy 331.977527 -344.896521) (xy 331.998222 -344.87596) (xy 332.012263 -344.850389) (xy 332.015846 -344.836242)
			(xy 332.022456 -344.808278) (xy 332.043051 -344.754635) (xy 332.071459 -344.704687) (xy 332.107036 -344.659565)
			(xy 332.148979 -344.620289) (xy 332.196338 -344.587748) (xy 332.248042 -344.562678) (xy 332.302921 -344.545646)
			(xy 332.359733 -344.537038) (xy 332.388464 -344.536522) (xy 332.415717 -344.536989) (xy 332.46967 -344.544742)
			(xy 332.521969 -344.560095) (xy 332.571551 -344.582735) (xy 332.617406 -344.612202) (xy 332.6586 -344.647896)
			(xy 332.694294 -344.689089) (xy 332.723762 -344.734943) (xy 332.746403 -344.784525) (xy 332.761757 -344.836824)
			(xy 332.769511 -344.890777) (xy 332.769972 -344.91803) (xy 332.76953 -344.945401) (xy 332.761708 -344.999582)
			(xy 332.746213 -345.052085) (xy 332.723366 -345.101832) (xy 332.693636 -345.147797) (xy 332.675992 -345.168728)
			(xy 332.666727 -345.180034) (xy 332.654554 -345.2066) (xy 332.650387 -345.235523) (xy 332.654567 -345.264444)
			(xy 332.666752 -345.291004) (xy 332.675992 -345.302332) (xy 332.693611 -345.32328) (xy 332.723326 -345.369248)
			(xy 332.746166 -345.418992) (xy 332.761662 -345.471489) (xy 332.769495 -345.525662) (xy 332.769972 -345.55303)
			(xy 332.769468 -345.580603) (xy 332.761525 -345.635175) (xy 332.745808 -345.688034) (xy 332.722645 -345.738081)
			(xy 332.692519 -345.784271) (xy 332.656057 -345.825644) (xy 332.635352 -345.84386) (xy 332.62442 -345.853726)
			(xy 332.608341 -345.878383) (xy 332.599957 -345.906601) (xy 332.599962 -345.936038) (xy 332.608358 -345.964252)
			(xy 332.624446 -345.988904) (xy 332.635352 -345.9988) (xy 332.656057 -346.017018) (xy 332.69253 -346.058384)
			(xy 332.722664 -346.104572) (xy 332.745831 -346.154619) (xy 332.761548 -346.207481) (xy 332.769487 -346.262055)
			(xy 332.769972 -346.28963) (xy 332.769573 -346.316885) (xy 332.761811 -346.37084) (xy 332.746449 -346.423142)
			(xy 332.723801 -346.472724) (xy 332.694326 -346.518579) (xy 332.658626 -346.559772) (xy 332.617426 -346.595466)
			(xy 332.571566 -346.624932) (xy 332.52198 -346.647572) (xy 332.469676 -346.662925) (xy 332.415719 -346.670678)
			(xy 332.388464 -346.671138) (xy 332.360591 -346.670614) (xy 332.305439 -346.662496) (xy 332.252055 -346.646438)
			(xy 332.201576 -346.622782) (xy 332.155078 -346.592032) (xy 332.11355 -346.554842) (xy 332.077876 -346.512004)
			(xy 332.048817 -346.464431) (xy 332.037436 -346.438982) (xy 332.030807 -346.424806) (xy 332.01038 -346.401115)
			(xy 331.983751 -346.384701) (xy 331.953407 -346.377099) (xy 331.922185 -346.379018) (xy 331.907388 -346.384118)
			(xy 331.885434 -346.392189) (xy 331.840046 -346.4035) (xy 331.793616 -346.409181) (xy 331.770228 -346.409518)
			(xy 331.756079 -346.409421) (xy 331.727856 -346.407389) (xy 331.71384 -346.405454) (xy 331.700495 -346.403821)
			(xy 331.673795 -346.406923) (xy 331.648836 -346.416899) (xy 331.627353 -346.433054) (xy 331.610843 -346.454264)
			(xy 331.600453 -346.479054) (xy 331.59827 -346.492322) (xy 331.594113 -346.519464) (xy 331.579146 -346.57229)
			(xy 331.556761 -346.622425) (xy 331.527421 -346.668834) (xy 331.491731 -346.710557) (xy 331.45043 -346.746735)
			(xy 331.404369 -346.776618) (xy 331.3545 -346.79959) (xy 331.301854 -346.815177) (xy 331.247517 -346.823056)
			(xy 331.220064 -346.823538) (xy 331.192813 -346.823056) (xy 331.138867 -346.815295) (xy 331.086574 -346.799937)
			(xy 331.036999 -346.777294) (xy 330.99115 -346.747827) (xy 330.949961 -346.712135) (xy 330.91427 -346.670945)
			(xy 330.884803 -346.625096) (xy 330.862161 -346.57552) (xy 330.846804 -346.523227) (xy 330.839044 -346.469281)
			(xy 330.838556 -346.44203) (xy 330.839023 -346.414455) (xy 330.846972 -346.359882) (xy 330.862696 -346.307021)
			(xy 330.885866 -346.256974) (xy 330.915999 -346.210785) (xy 330.952468 -346.169415) (xy 330.973176 -346.1512)
			(xy 330.984045 -346.141272) (xy 331.000122 -346.116631) (xy 331.008511 -346.08843) (xy 331.008517 -346.059008)
			(xy 331.000138 -346.030805) (xy 330.984071 -346.006157) (xy 330.973176 -345.99626) (xy 330.952486 -345.978026)
			(xy 330.916015 -345.936662) (xy 330.885881 -345.890476) (xy 330.862712 -345.840433) (xy 330.84699 -345.787575)
			(xy 330.839045 -345.733003) (xy 330.838556 -345.70543) (xy 330.838556 -345.704922) (xy 330.8391 -345.675514)
			(xy 330.848181 -345.617403) (xy 330.866068 -345.561372) (xy 330.89234 -345.508749) (xy 330.908914 -345.48445)
			(xy 330.91637 -345.473083) (xy 330.925686 -345.44756) (xy 330.927945 -345.420484) (xy 330.922989 -345.39377)
			(xy 330.911167 -345.369307) (xy 330.893316 -345.348824) (xy 330.882244 -345.34094) (xy 330.859621 -345.325432)
			(xy 330.818807 -345.288794) (xy 330.783827 -345.246549) (xy 330.769214 -345.223338) (xy 330.761245 -345.211145)
			(xy 330.739789 -345.19147) (xy 330.713648 -345.178659) (xy 330.684951 -345.173756) (xy 330.656039 -345.17716)
			(xy 330.642468 -345.182444) (xy 330.61926 -345.191938) (xy 330.570926 -345.205287) (xy 330.521236 -345.212013)
			(xy 330.496164 -345.212416) (xy 330.471095 -345.211988) (xy 330.421412 -345.20524) (xy 330.373078 -345.191909)
			(xy 330.34986 -345.182444) (xy 330.336267 -345.177245) (xy 330.307376 -345.173876) (xy 330.278705 -345.178779)
			(xy 330.252575 -345.191555) (xy 330.231098 -345.211171) (xy 330.223114 -345.223338) (xy 330.208545 -345.246469)
			(xy 330.173702 -345.28859) (xy 330.133079 -345.325169) (xy 330.087548 -345.35542) (xy 330.038086 -345.378696)
			(xy 329.985755 -345.394496) (xy 329.931676 -345.402482) (xy 329.877012 -345.402482) (xy 329.822933 -345.394496)
			(xy 329.770602 -345.378696) (xy 329.72114 -345.35542) (xy 329.675609 -345.325169) (xy 329.634986 -345.28859)
			(xy 329.600143 -345.246469) (xy 329.585574 -345.223338) (xy 329.577644 -345.211118) (xy 329.556177 -345.191442)
			(xy 329.530025 -345.178634) (xy 329.50132 -345.173738) (xy 329.472401 -345.177154) (xy 329.458828 -345.182444)
			(xy 329.435613 -345.191919) (xy 329.387282 -345.205275) (xy 329.337595 -345.212009) (xy 329.312524 -345.212416)
			(xy 329.284636 -345.211927) (xy 329.229482 -345.203617) (xy 329.176183 -345.187179) (xy 329.12593 -345.162981)
			(xy 329.079844 -345.131563) (xy 329.038956 -345.093627) (xy 329.004179 -345.050021) (xy 328.97629 -345.001718)
			(xy 328.955912 -344.949798) (xy 328.9435 -344.89542) (xy 328.939331 -344.8398) (xy 324.430065 -344.8398)
			(xy 324.440303 -344.87383) (xy 324.448423 -344.929006) (xy 324.448932 -344.956892) (xy 324.448423 -344.984778)
			(xy 324.440303 -345.039954) (xy 324.424235 -345.093361) (xy 324.400563 -345.143858) (xy 324.36979 -345.190371)
			(xy 324.332573 -345.231908) (xy 324.289705 -345.267583) (xy 324.242099 -345.296637) (xy 324.19077 -345.318449)
			(xy 324.136813 -345.332555) (xy 324.081376 -345.338655) (xy 324.025642 -345.336618) (xy 323.970799 -345.326488)
			(xy 323.918015 -345.308481) (xy 323.868415 -345.28298) (xy 323.823057 -345.250529) (xy 323.782908 -345.21182)
			(xy 323.748822 -345.167677) (xy 323.721526 -345.119042) (xy 323.701603 -345.066951) (xy 323.689477 -345.012514)
			(xy 323.685406 -344.956892) (xy 323.46688 -344.956892) (xy 323.466459 -344.979952) (xy 323.458339 -345.035128)
			(xy 323.442271 -345.088535) (xy 323.418599 -345.139032) (xy 323.387826 -345.185545) (xy 323.350609 -345.227082)
			(xy 323.307741 -345.262757) (xy 323.260135 -345.291811) (xy 323.208806 -345.313623) (xy 323.154849 -345.327729)
			(xy 323.099412 -345.333829) (xy 323.043678 -345.331792) (xy 322.988835 -345.321662) (xy 322.936051 -345.303655)
			(xy 322.886451 -345.278154) (xy 322.841093 -345.245703) (xy 322.800944 -345.206994) (xy 322.766858 -345.162851)
			(xy 322.739562 -345.114216) (xy 322.719639 -345.062125) (xy 322.707513 -345.007688) (xy 322.703442 -344.952066)
			(xy 321.560698 -344.952066) (xy 321.560698 -346.174314) (xy 323.948296 -346.174314) (xy 323.952367 -346.118692)
			(xy 323.964493 -346.064255) (xy 323.984416 -346.012164) (xy 324.011712 -345.963529) (xy 324.045798 -345.919386)
			(xy 324.085947 -345.880677) (xy 324.131305 -345.848226) (xy 324.180905 -345.822725) (xy 324.233689 -345.804718)
			(xy 324.288532 -345.794588) (xy 324.344266 -345.792551) (xy 324.399703 -345.798651) (xy 324.45366 -345.812757)
			(xy 324.504989 -345.834569) (xy 324.552595 -345.863623) (xy 324.595463 -345.899298) (xy 324.601093 -345.905582)
			(xy 325.481694 -345.905582) (xy 325.485765 -345.84996) (xy 325.497891 -345.795523) (xy 325.517814 -345.743432)
			(xy 325.54511 -345.694797) (xy 325.579196 -345.650654) (xy 325.619345 -345.611945) (xy 325.664703 -345.579494)
			(xy 325.714303 -345.553993) (xy 325.767087 -345.535986) (xy 325.82193 -345.525856) (xy 325.877664 -345.523819)
			(xy 325.933101 -345.529919) (xy 325.987058 -345.544025) (xy 326.038387 -345.565837) (xy 326.085993 -345.594891)
			(xy 326.128861 -345.630566) (xy 326.166078 -345.672103) (xy 326.196851 -345.718616) (xy 326.220523 -345.769113)
			(xy 326.236591 -345.82252) (xy 326.244711 -345.877696) (xy 326.24522 -345.905582) (xy 326.244711 -345.933468)
			(xy 326.236591 -345.988644) (xy 326.220523 -346.042051) (xy 326.196851 -346.092548) (xy 326.166078 -346.139061)
			(xy 326.128861 -346.180598) (xy 326.085993 -346.216273) (xy 326.038387 -346.245327) (xy 325.987058 -346.267139)
			(xy 325.933101 -346.281245) (xy 325.877664 -346.287345) (xy 325.82193 -346.285308) (xy 325.767087 -346.275178)
			(xy 325.714303 -346.257171) (xy 325.664703 -346.23167) (xy 325.619345 -346.199219) (xy 325.579196 -346.16051)
			(xy 325.54511 -346.116367) (xy 325.517814 -346.067732) (xy 325.497891 -346.015641) (xy 325.485765 -345.961204)
			(xy 325.481694 -345.905582) (xy 324.601093 -345.905582) (xy 324.63268 -345.940835) (xy 324.663453 -345.987348)
			(xy 324.687125 -346.037845) (xy 324.703193 -346.091252) (xy 324.711313 -346.146428) (xy 324.711822 -346.174314)
			(xy 324.711313 -346.2022) (xy 324.703193 -346.257376) (xy 324.687125 -346.310783) (xy 324.663453 -346.36128)
			(xy 324.63268 -346.407793) (xy 324.595463 -346.44933) (xy 324.552595 -346.485005) (xy 324.504989 -346.514059)
			(xy 324.45366 -346.535871) (xy 324.399703 -346.549977) (xy 324.344266 -346.556077) (xy 324.288532 -346.55404)
			(xy 324.233689 -346.54391) (xy 324.180905 -346.525903) (xy 324.131305 -346.500402) (xy 324.085947 -346.467951)
			(xy 324.045798 -346.429242) (xy 324.011712 -346.385099) (xy 323.984416 -346.336464) (xy 323.964493 -346.284373)
			(xy 323.952367 -346.229936) (xy 323.948296 -346.174314) (xy 321.560698 -346.174314) (xy 321.560698 -347.819472)
			(xy 321.808348 -348.246446) (xy 321.815567 -348.258022) (xy 321.835007 -348.277146) (xy 321.858818 -348.290438)
			(xy 321.8853 -348.296949) (xy 321.91256 -348.296213) (xy 321.938652 -348.288282) (xy 321.961711 -348.273724)
			(xy 321.980091 -348.253578) (xy 321.986656 -348.24162) (xy 321.991228 -348.232476) (xy 322.005533 -348.206466)
			(xy 322.040942 -348.158825) (xy 322.083293 -348.117234) (xy 322.131568 -348.082694) (xy 322.157852 -348.0689)
			(xy 322.170215 -348.062199) (xy 322.190952 -348.043223) (xy 322.205721 -348.019305) (xy 322.213398 -347.992265)
			(xy 322.213401 -347.964155) (xy 322.205729 -347.937113) (xy 322.190965 -347.913192) (xy 322.170231 -347.894212)
			(xy 322.157852 -347.887544) (xy 322.13448 -347.875303) (xy 322.091047 -347.845348) (xy 322.052154 -347.809697)
			(xy 322.018543 -347.769029) (xy 321.990853 -347.724119) (xy 321.969613 -347.675823) (xy 321.955228 -347.625061)
			(xy 321.947971 -347.572802) (xy 321.94754 -347.546422) (xy 321.948026 -347.519171) (xy 321.955782 -347.465223)
			(xy 321.971137 -347.412928) (xy 321.993779 -347.363351) (xy 322.023245 -347.317501) (xy 322.058936 -347.27631)
			(xy 322.100127 -347.240619) (xy 322.145977 -347.211153) (xy 322.195554 -347.188511) (xy 322.247849 -347.173156)
			(xy 322.301797 -347.1654) (xy 322.356299 -347.1654) (xy 322.410247 -347.173156) (xy 322.462542 -347.188511)
			(xy 322.512119 -347.211153) (xy 322.557969 -347.240619) (xy 322.59916 -347.27631) (xy 322.634851 -347.317501)
			(xy 322.664317 -347.363351) (xy 322.686959 -347.412928) (xy 322.702314 -347.465223) (xy 322.707196 -347.499178)
			(xy 326.2884 -347.499178) (xy 326.288939 -347.469489) (xy 326.298141 -347.410829) (xy 326.31632 -347.354303)
			(xy 326.343036 -347.301276) (xy 326.377645 -347.253028) (xy 326.41931 -347.210723) (xy 326.442832 -347.1926)
			(xy 326.453471 -347.184212) (xy 326.470174 -347.162889) (xy 326.480687 -347.137927) (xy 326.484272 -347.11108)
			(xy 326.480677 -347.084233) (xy 326.470153 -347.059275) (xy 326.453442 -347.03796) (xy 326.442832 -347.029532)
			(xy 326.419344 -347.011369) (xy 326.37768 -346.969072) (xy 326.343072 -346.920831) (xy 326.316356 -346.867811)
			(xy 326.298175 -346.811292) (xy 326.288969 -346.752639) (xy 326.2884 -346.722954) (xy 326.288886 -346.695703)
			(xy 326.296642 -346.641755) (xy 326.311997 -346.58946) (xy 326.334639 -346.539883) (xy 326.364105 -346.494033)
			(xy 326.399796 -346.452842) (xy 326.440987 -346.417151) (xy 326.486837 -346.387685) (xy 326.536414 -346.365043)
			(xy 326.588709 -346.349688) (xy 326.642657 -346.341932) (xy 326.697159 -346.341932) (xy 326.751107 -346.349688)
			(xy 326.803402 -346.365043) (xy 326.852979 -346.387685) (xy 326.898829 -346.417151) (xy 326.94002 -346.452842)
			(xy 326.975711 -346.494033) (xy 327.005177 -346.539883) (xy 327.027819 -346.58946) (xy 327.043174 -346.641755)
			(xy 327.05093 -346.695703) (xy 327.051416 -346.722954) (xy 327.050821 -346.75264) (xy 327.04163 -346.811297)
			(xy 327.023462 -346.867822) (xy 326.996756 -346.92085) (xy 326.984707 -346.937653) (xy 327.304861 -346.937653)
			(xy 327.304861 -346.883147) (xy 327.312618 -346.829196) (xy 327.327975 -346.776899) (xy 327.350617 -346.727319)
			(xy 327.380086 -346.681466) (xy 327.41578 -346.640274) (xy 327.456973 -346.604581) (xy 327.502826 -346.575113)
			(xy 327.552406 -346.552472) (xy 327.604704 -346.537117) (xy 327.658655 -346.529361) (xy 327.685908 -346.528898)
			(xy 327.686162 -346.528898) (xy 327.711365 -346.529306) (xy 327.761333 -346.535942) (xy 327.809988 -346.549116)
			(xy 327.856478 -346.568597) (xy 327.87844 -346.580968) (xy 327.891398 -346.58802) (xy 327.920037 -346.595048)
			(xy 327.94949 -346.593599) (xy 327.977302 -346.583795) (xy 328.001152 -346.566452) (xy 328.019051 -346.543016)
			(xy 328.024744 -346.529406) (xy 328.035473 -346.502644) (xy 328.063756 -346.452403) (xy 328.099281 -346.406993)
			(xy 328.141238 -346.367449) (xy 328.188671 -346.334674) (xy 328.240497 -346.309414) (xy 328.295536 -346.292244)
			(xy 328.352533 -346.283558) (xy 328.38136 -346.283026) (xy 328.408613 -346.283493) (xy 328.462566 -346.291245)
			(xy 328.514866 -346.306598) (xy 328.564448 -346.329238) (xy 328.610303 -346.358705) (xy 328.651497 -346.394399)
			(xy 328.687191 -346.435592) (xy 328.716659 -346.481447) (xy 328.7393 -346.531028) (xy 328.754654 -346.583328)
			(xy 328.762407 -346.637281) (xy 328.762868 -346.664534) (xy 328.762868 -346.664788) (xy 328.762281 -346.694626)
			(xy 328.752973 -346.753572) (xy 328.744326 -346.782136) (xy 328.740293 -346.796046) (xy 328.739378 -346.824979)
			(xy 328.74664 -346.853002) (xy 328.761492 -346.877849) (xy 328.782735 -346.897514) (xy 328.808653 -346.910408)
			(xy 328.822812 -346.913454) (xy 328.850847 -346.919045) (xy 328.904954 -346.937494) (xy 328.955707 -346.9638)
			(xy 329.001972 -346.997376) (xy 329.042718 -347.037472) (xy 329.060302 -347.060012) (xy 329.386184 -347.060012)
			(xy 329.408668 -347.060554) (xy 329.452766 -347.069352) (xy 329.494306 -347.086574) (xy 329.531693 -347.11156)
			(xy 329.547982 -347.127068) (xy 329.964288 -347.54312) (xy 333.397606 -347.54312) (xy 333.913988 -347.026992)
			(xy 333.930237 -347.011435) (xy 333.967627 -346.986432) (xy 334.00918 -346.969214) (xy 334.053296 -346.960444)
			(xy 334.075786 -346.959936) (xy 343.165938 -346.959936) (xy 343.188421 -346.9605) (xy 343.232519 -346.96929)
			(xy 343.274058 -346.986505) (xy 343.311446 -347.011486) (xy 343.327736 -347.026992) (xy 345.016836 -348.716092)
			(xy 345.032399 -348.732335) (xy 345.0574 -348.769727) (xy 345.074616 -348.811282) (xy 345.083384 -348.8554)
			(xy 345.083892 -348.87789) (xy 345.083892 -353.438206) (xy 345.789758 -354.144072) (xy 345.80532 -354.160333)
			(xy 345.830397 -354.197699) (xy 345.847689 -354.239245) (xy 345.856528 -354.28337) (xy 345.857068 -354.30587)
			(xy 345.857068 -361.892088) (xy 345.856474 -361.914583) (xy 345.847626 -361.958696) (xy 345.830346 -362.000237)
			(xy 345.805297 -362.03761) (xy 345.789758 -362.053886) (xy 345.440508 -362.40339) (xy 345.440508 -362.873798)
			(xy 346.387672 -362.873798) (xy 346.391743 -362.818176) (xy 346.403869 -362.763739) (xy 346.423792 -362.711648)
			(xy 346.451088 -362.663013) (xy 346.485174 -362.61887) (xy 346.525323 -362.580161) (xy 346.570681 -362.54771)
			(xy 346.620281 -362.522209) (xy 346.673065 -362.504202) (xy 346.727908 -362.494072) (xy 346.783642 -362.492035)
			(xy 346.839079 -362.498135) (xy 346.893036 -362.512241) (xy 346.944365 -362.534053) (xy 346.991971 -362.563107)
			(xy 347.034839 -362.598782) (xy 347.072056 -362.640319) (xy 347.102829 -362.686832) (xy 347.126501 -362.737329)
			(xy 347.142569 -362.790736) (xy 347.150689 -362.845912) (xy 347.151198 -362.873798) (xy 347.150689 -362.901684)
			(xy 347.142569 -362.95686) (xy 347.126501 -363.010267) (xy 347.102829 -363.060764) (xy 347.072056 -363.107277)
			(xy 347.034839 -363.148814) (xy 346.991971 -363.184489) (xy 346.944365 -363.213543) (xy 346.893036 -363.235355)
			(xy 346.839079 -363.249461) (xy 346.783642 -363.255561) (xy 346.727908 -363.253524) (xy 346.673065 -363.243394)
			(xy 346.620281 -363.225387) (xy 346.570681 -363.199886) (xy 346.525323 -363.167435) (xy 346.485174 -363.128726)
			(xy 346.451088 -363.084583) (xy 346.423792 -363.035948) (xy 346.403869 -362.983857) (xy 346.391743 -362.92942)
			(xy 346.387672 -362.873798) (xy 345.440508 -362.873798) (xy 345.440508 -363.113066) (xy 345.92133 -363.593888)
			(xy 346.993462 -363.593888) (xy 346.997533 -363.538266) (xy 347.009659 -363.483829) (xy 347.029582 -363.431738)
			(xy 347.056878 -363.383103) (xy 347.090964 -363.33896) (xy 347.131113 -363.300251) (xy 347.176471 -363.2678)
			(xy 347.226071 -363.242299) (xy 347.278855 -363.224292) (xy 347.333698 -363.214162) (xy 347.389432 -363.212125)
			(xy 347.444869 -363.218225) (xy 347.498826 -363.232331) (xy 347.550155 -363.254143) (xy 347.597761 -363.283197)
			(xy 347.640629 -363.318872) (xy 347.677846 -363.360409) (xy 347.708619 -363.406922) (xy 347.732291 -363.457419)
			(xy 347.748359 -363.510826) (xy 347.756479 -363.566002) (xy 347.756988 -363.593888) (xy 347.756479 -363.621774)
			(xy 347.748359 -363.67695) (xy 347.732291 -363.730357) (xy 347.708619 -363.780854) (xy 347.677846 -363.827367)
			(xy 347.640629 -363.868904) (xy 347.597761 -363.904579) (xy 347.550155 -363.933633) (xy 347.498826 -363.955445)
			(xy 347.444869 -363.969551) (xy 347.389432 -363.975651) (xy 347.333698 -363.973614) (xy 347.278855 -363.963484)
			(xy 347.226071 -363.945477) (xy 347.176471 -363.919976) (xy 347.131113 -363.887525) (xy 347.090964 -363.848816)
			(xy 347.056878 -363.804673) (xy 347.029582 -363.756038) (xy 347.009659 -363.703947) (xy 346.997533 -363.64951)
			(xy 346.993462 -363.593888) (xy 345.92133 -363.593888) (xy 346.491052 -364.16361) (xy 347.661482 -364.16361)
			(xy 347.665553 -364.107988) (xy 347.677679 -364.053551) (xy 347.697602 -364.00146) (xy 347.724898 -363.952825)
			(xy 347.758984 -363.908682) (xy 347.799133 -363.869973) (xy 347.844491 -363.837522) (xy 347.894091 -363.812021)
			(xy 347.946875 -363.794014) (xy 348.001718 -363.783884) (xy 348.057452 -363.781847) (xy 348.112889 -363.787947)
			(xy 348.166846 -363.802053) (xy 348.218175 -363.823865) (xy 348.265781 -363.852919) (xy 348.308649 -363.888594)
			(xy 348.345866 -363.930131) (xy 348.376639 -363.976644) (xy 348.400311 -364.027141) (xy 348.416379 -364.080548)
			(xy 348.424499 -364.135724) (xy 348.425008 -364.16361) (xy 348.424499 -364.191496) (xy 348.416379 -364.246672)
			(xy 348.400311 -364.300079) (xy 348.376639 -364.350576) (xy 348.345866 -364.397089) (xy 348.308649 -364.438626)
			(xy 348.265781 -364.474301) (xy 348.218175 -364.503355) (xy 348.166846 -364.525167) (xy 348.112889 -364.539273)
			(xy 348.057452 -364.545373) (xy 348.001718 -364.543336) (xy 347.946875 -364.533206) (xy 347.894091 -364.515199)
			(xy 347.844491 -364.489698) (xy 347.799133 -364.457247) (xy 347.758984 -364.418538) (xy 347.724898 -364.374395)
			(xy 347.697602 -364.32576) (xy 347.677679 -364.273669) (xy 347.665553 -364.219232) (xy 347.661482 -364.16361)
			(xy 346.491052 -364.16361) (xy 348.544642 -366.2172) (xy 354.730304 -366.2172) (xy 355.023928 -365.92383)
			(xy 355.040163 -365.90824) (xy 355.077538 -365.883168) (xy 355.119093 -365.865884) (xy 355.163224 -365.857055)
			(xy 355.185726 -365.85652) (xy 357.845106 -365.85652) (xy 357.880412 -365.821214) (xy 357.87965 -365.799624)
			(xy 357.87965 -365.789718) (xy 357.880136 -365.762463) (xy 357.887891 -365.708507) (xy 357.903246 -365.656205)
			(xy 357.925889 -365.60662) (xy 357.955358 -365.560762) (xy 357.991054 -365.519565) (xy 358.032249 -365.483868)
			(xy 358.078106 -365.454397) (xy 358.12769 -365.431752) (xy 358.179992 -365.416394) (xy 358.233947 -365.408637)
			(xy 358.288457 -365.408637) (xy 358.342412 -365.416395) (xy 358.394714 -365.431753) (xy 358.444298 -365.454399)
			(xy 358.490154 -365.48387) (xy 358.531349 -365.519568) (xy 358.567044 -365.560765) (xy 358.596513 -365.606623)
			(xy 358.612037 -365.64062) (xy 380.886211 -365.64062) (xy 380.890247 -365.557173) (xy 380.902319 -365.474505)
			(xy 380.922312 -365.393388) (xy 380.950041 -365.314579) (xy 380.985247 -365.238814) (xy 381.027601 -365.166801)
			(xy 381.076707 -365.099212) (xy 381.132108 -365.036678) (xy 381.193285 -364.979783) (xy 381.259668 -364.929057)
			(xy 381.330636 -364.884976) (xy 381.405528 -364.84795) (xy 381.483644 -364.818324) (xy 381.564254 -364.796376)
			(xy 381.646606 -364.782311) (xy 381.729932 -364.776259) (xy 381.813452 -364.778278) (xy 381.896388 -364.788348)
			(xy 381.977964 -364.806376) (xy 382.05742 -364.832193) (xy 382.134013 -364.865558) (xy 382.207029 -364.906159)
			(xy 382.275785 -364.953618) (xy 382.339639 -365.007491) (xy 382.397996 -365.067276) (xy 382.450311 -365.132413)
			(xy 382.496094 -365.202296) (xy 382.534919 -365.276271) (xy 382.566424 -365.353648) (xy 382.590313 -365.433705)
			(xy 382.606364 -365.515693) (xy 382.614427 -365.598848) (xy 382.614932 -365.64062) (xy 382.614427 -365.682392)
			(xy 382.606364 -365.765547) (xy 382.590313 -365.847535) (xy 382.566424 -365.927592) (xy 382.534919 -366.004969)
			(xy 382.496094 -366.078944) (xy 382.450311 -366.148827) (xy 382.397996 -366.213964) (xy 382.339639 -366.273749)
			(xy 382.275785 -366.327622) (xy 382.207029 -366.375081) (xy 382.134013 -366.415682) (xy 382.05742 -366.449047)
			(xy 381.977964 -366.474864) (xy 381.896388 -366.492892) (xy 381.813452 -366.502962) (xy 381.729932 -366.504981)
			(xy 381.646606 -366.498929) (xy 381.564254 -366.484864) (xy 381.483644 -366.462916) (xy 381.405528 -366.43329)
			(xy 381.330636 -366.396264) (xy 381.259668 -366.352183) (xy 381.193285 -366.301457) (xy 381.132108 -366.244562)
			(xy 381.076707 -366.182028) (xy 381.027601 -366.114439) (xy 380.985247 -366.042426) (xy 380.950041 -365.966661)
			(xy 380.922312 -365.887852) (xy 380.902319 -365.806735) (xy 380.890247 -365.724067) (xy 380.886211 -365.64062)
			(xy 358.612037 -365.64062) (xy 358.619155 -365.656208) (xy 358.63451 -365.708511) (xy 358.642265 -365.762467)
			(xy 358.642261 -365.816977) (xy 358.634501 -365.870932) (xy 358.61914 -365.923233) (xy 358.596492 -365.972816)
			(xy 358.567018 -366.01867) (xy 358.531318 -366.059863) (xy 358.490119 -366.095556) (xy 358.444259 -366.125023)
			(xy 358.394673 -366.147662) (xy 358.342369 -366.163014) (xy 358.288413 -366.170766) (xy 358.261158 -366.171226)
			(xy 358.248289 -366.171099) (xy 358.222613 -366.169321) (xy 358.20985 -366.16767) (xy 358.184958 -366.164368)
			(xy 358.101646 -366.247426) (xy 358.085388 -366.26299) (xy 358.04802 -366.288064) (xy 358.006472 -366.305354)
			(xy 357.962348 -366.314194) (xy 357.939848 -366.314736) (xy 355.280468 -366.314736) (xy 354.986844 -366.608106)
			(xy 354.970584 -366.623668) (xy 354.933217 -366.648743) (xy 354.89167 -366.666034) (xy 354.847546 -366.674874)
			(xy 354.825046 -366.675416) (xy 348.4499 -366.675416) (xy 348.427404 -366.674844) (xy 348.383289 -366.665992)
			(xy 348.341748 -366.648706) (xy 348.304376 -366.623649) (xy 348.288102 -366.608106) (xy 345.049602 -363.369606)
			(xy 345.034023 -363.353361) (xy 345.008951 -363.315988) (xy 344.991664 -363.274437) (xy 344.98283 -363.230309)
			(xy 344.982292 -363.207808) (xy 344.982292 -362.308648) (xy 344.982919 -362.286155) (xy 344.991759 -362.242044)
			(xy 345.009029 -362.200504) (xy 345.034068 -362.163128) (xy 345.049602 -362.14685) (xy 345.398852 -361.797346)
			(xy 345.398852 -354.400612) (xy 344.69324 -353.694746) (xy 344.677691 -353.678491) (xy 344.652688 -353.641102)
			(xy 344.635469 -353.599551) (xy 344.626695 -353.555437) (xy 344.626184 -353.532948) (xy 344.626184 -348.972632)
			(xy 343.071196 -347.417644) (xy 334.170528 -347.417644) (xy 333.654146 -347.934026) (xy 333.637888 -347.94959)
			(xy 333.60052 -347.974664) (xy 333.558972 -347.991954) (xy 333.514848 -348.000794) (xy 333.492348 -348.001336)
			(xy 329.869546 -348.001336) (xy 329.847052 -348.000731) (xy 329.802939 -347.991888) (xy 329.761398 -347.974611)
			(xy 329.724024 -347.949565) (xy 329.707748 -347.934026) (xy 329.291442 -347.51772) (xy 329.060302 -347.51772)
			(xy 329.042154 -347.540964) (xy 328.999934 -347.582132) (xy 328.951887 -347.616318) (xy 328.899154 -347.642709)
			(xy 328.84299 -347.660679) (xy 328.784732 -347.669799) (xy 328.755248 -347.670374) (xy 328.727995 -347.6699)
			(xy 328.674042 -347.662149) (xy 328.621743 -347.646797) (xy 328.572161 -347.624158) (xy 328.526305 -347.594691)
			(xy 328.485111 -347.558999) (xy 328.449417 -347.517806) (xy 328.419949 -347.471952) (xy 328.397308 -347.42237)
			(xy 328.381954 -347.370071) (xy 328.374201 -347.316119) (xy 328.37374 -347.288866) (xy 328.37374 -347.288612)
			(xy 328.374328 -347.258774) (xy 328.383635 -347.199828) (xy 328.392282 -347.171264) (xy 328.396308 -347.157353)
			(xy 328.397223 -347.128421) (xy 328.389962 -347.1004) (xy 328.375111 -347.075553) (xy 328.35387 -347.055888)
			(xy 328.327954 -347.042993) (xy 328.313796 -347.039946) (xy 328.280955 -347.033371) (xy 328.218103 -347.010243)
			(xy 328.188828 -346.993972) (xy 328.175839 -346.98698) (xy 328.147211 -346.979935) (xy 328.117765 -346.98137)
			(xy 328.089957 -346.991163) (xy 328.06611 -347.008498) (xy 328.048214 -347.031927) (xy 328.042524 -347.045534)
			(xy 328.031843 -347.072316) (xy 328.003552 -347.122557) (xy 327.968019 -347.167966) (xy 327.926055 -347.207508)
			(xy 327.878616 -347.24028) (xy 327.826783 -347.265537) (xy 327.771739 -347.282702) (xy 327.714737 -347.291385)
			(xy 327.685908 -347.291914) (xy 327.658655 -347.291439) (xy 327.604704 -347.283683) (xy 327.552406 -347.268328)
			(xy 327.502826 -347.245687) (xy 327.456973 -347.216219) (xy 327.41578 -347.180526) (xy 327.380086 -347.139334)
			(xy 327.350617 -347.093481) (xy 327.327975 -347.043901) (xy 327.312618 -346.991604) (xy 327.304861 -346.937653)
			(xy 326.984707 -346.937653) (xy 326.962158 -346.9691) (xy 326.920501 -347.011407) (xy 326.896984 -347.029532)
			(xy 326.886411 -347.037998) (xy 326.869706 -347.059302) (xy 326.859187 -347.084247) (xy 326.855592 -347.11108)
			(xy 326.859176 -347.137914) (xy 326.869685 -347.162863) (xy 326.886382 -347.184173) (xy 326.896984 -347.1926)
			(xy 326.920491 -347.21074) (xy 326.962153 -347.253043) (xy 326.996758 -347.301289) (xy 327.023471 -347.354313)
			(xy 327.041648 -347.410835) (xy 327.050849 -347.469491) (xy 327.051416 -347.499178) (xy 327.05093 -347.526429)
			(xy 327.043174 -347.580377) (xy 327.027819 -347.632672) (xy 327.005177 -347.682249) (xy 326.975711 -347.728099)
			(xy 326.94002 -347.76929) (xy 326.898829 -347.804981) (xy 326.852979 -347.834447) (xy 326.803402 -347.857089)
			(xy 326.751107 -347.872444) (xy 326.697159 -347.8802) (xy 326.642657 -347.8802) (xy 326.588709 -347.872444)
			(xy 326.536414 -347.857089) (xy 326.486837 -347.834447) (xy 326.440987 -347.804981) (xy 326.399796 -347.76929)
			(xy 326.364105 -347.728099) (xy 326.334639 -347.682249) (xy 326.311997 -347.632672) (xy 326.296642 -347.580377)
			(xy 326.288886 -347.526429) (xy 326.2884 -347.499178) (xy 322.707196 -347.499178) (xy 322.71007 -347.519171)
			(xy 322.710556 -347.546422) (xy 322.710109 -347.572801) (xy 322.702844 -347.625055) (xy 322.688453 -347.675812)
			(xy 322.667213 -347.724105) (xy 322.639527 -347.769014) (xy 322.605921 -347.809684) (xy 322.567038 -347.84534)
			(xy 322.523615 -347.875304) (xy 322.500244 -347.887544) (xy 322.487887 -347.894245) (xy 322.467162 -347.913218)
			(xy 322.452405 -347.937129) (xy 322.444736 -347.964161) (xy 322.444739 -347.992259) (xy 322.452413 -348.019289)
			(xy 322.467175 -348.043197) (xy 322.487904 -348.062167) (xy 322.500244 -348.0689) (xy 322.523614 -348.081145)
			(xy 322.567041 -348.111103) (xy 322.60593 -348.146756) (xy 322.639539 -348.187425) (xy 322.667227 -348.232334)
			(xy 322.688468 -348.280628) (xy 322.702856 -348.331386) (xy 322.710118 -348.383643) (xy 322.710556 -348.410022)
			(xy 322.710069 -348.437273) (xy 322.70231 -348.491221) (xy 322.686953 -348.543516) (xy 322.664312 -348.593094)
			(xy 322.634846 -348.638945) (xy 322.599155 -348.680136) (xy 322.557966 -348.71583) (xy 322.512117 -348.745299)
			(xy 322.462541 -348.767944) (xy 322.410247 -348.783304) (xy 322.356299 -348.791067) (xy 322.329048 -348.79153)
			(xy 322.303902 -348.790768) (xy 322.302886 -348.790514) (xy 322.289373 -348.79059) (xy 322.263134 -348.797009)
			(xy 322.239497 -348.810084) (xy 322.220116 -348.8289) (xy 322.206348 -348.852141) (xy 322.199157 -348.878179)
			(xy 322.199046 -348.905192) (xy 322.206024 -348.931288) (xy 322.212462 -348.943168) (xy 323.344983 -350.895412)
			(xy 336.039206 -350.895412) (xy 336.039731 -350.866495) (xy 336.048458 -350.809324) (xy 336.065715 -350.754126)
			(xy 336.091105 -350.702164) (xy 336.124048 -350.65463) (xy 336.163787 -350.612612) (xy 336.186272 -350.594422)
			(xy 336.198067 -350.584512) (xy 336.215587 -350.559193) (xy 336.224765 -350.529802) (xy 336.224768 -350.499012)
			(xy 336.215593 -350.469621) (xy 336.198077 -350.444299) (xy 336.186272 -350.434402) (xy 336.163784 -350.416217)
			(xy 336.12405 -350.374195) (xy 336.091112 -350.326659) (xy 336.065725 -350.274696) (xy 336.04847 -350.219498)
			(xy 336.039741 -350.162328) (xy 336.039206 -350.133412) (xy 336.039743 -350.1044) (xy 336.048511 -350.047042)
			(xy 336.065861 -349.991673) (xy 336.091395 -349.939569) (xy 336.124522 -349.891931) (xy 336.144108 -349.870522)
			(xy 336.154365 -349.858964) (xy 336.167938 -349.831216) (xy 336.1726 -349.80068) (xy 336.167925 -349.770145)
			(xy 336.154342 -349.742403) (xy 336.144108 -349.730822) (xy 336.124536 -349.709401) (xy 336.091417 -349.661761)
			(xy 336.065886 -349.609659) (xy 336.04853 -349.554295) (xy 336.039748 -349.496942) (xy 336.039206 -349.467932)
			(xy 336.039729 -349.440676) (xy 336.04749 -349.386719) (xy 336.062846 -349.334415) (xy 336.085484 -349.284826)
			(xy 336.114944 -349.23896) (xy 336.150627 -349.19775) (xy 336.191808 -349.162033) (xy 336.214466 -349.146876)
			(xy 336.226362 -349.138554) (xy 336.245364 -349.116627) (xy 336.25742 -349.090236) (xy 336.261553 -349.061517)
			(xy 336.25743 -349.032797) (xy 336.245383 -349.006402) (xy 336.226389 -348.984469) (xy 336.214466 -348.976188)
			(xy 336.19178 -348.961065) (xy 336.150579 -348.925356) (xy 336.11488 -348.884147) (xy 336.085409 -348.838276)
			(xy 336.062767 -348.788677) (xy 336.047415 -348.736361) (xy 336.039664 -348.682393) (xy 336.039206 -348.655132)
			(xy 336.039685 -348.627879) (xy 336.047438 -348.573928) (xy 336.062791 -348.52163) (xy 336.085431 -348.472049)
			(xy 336.114897 -348.426195) (xy 336.150589 -348.385001) (xy 336.19178 -348.349307) (xy 336.237633 -348.319839)
			(xy 336.287213 -348.297197) (xy 336.339511 -348.281842) (xy 336.393461 -348.274086) (xy 336.420714 -348.273624)
			(xy 336.446635 -348.274074) (xy 336.497997 -348.281107) (xy 336.547935 -348.295027) (xy 336.595529 -348.315578)
			(xy 336.639903 -348.342383) (xy 336.680241 -348.374947) (xy 336.698336 -348.393512) (xy 336.707692 -348.402998)
			(xy 336.730329 -348.417038) (xy 336.755831 -348.424737) (xy 336.782456 -348.425569) (xy 336.808389 -348.419477)
			(xy 336.831858 -348.406876) (xy 336.851264 -348.388627) (xy 336.85861 -348.37751) (xy 336.873637 -348.354274)
			(xy 336.909342 -348.312) (xy 336.950778 -348.275326) (xy 336.997075 -348.245019) (xy 337.047264 -348.221716)
			(xy 337.100292 -348.205904) (xy 337.155047 -348.197915) (xy 337.182714 -348.197424) (xy 337.209967 -348.197847)
			(xy 337.263918 -348.205606) (xy 337.316215 -348.220963) (xy 337.365795 -348.243607) (xy 337.411647 -348.273076)
			(xy 337.452839 -348.308771) (xy 337.488532 -348.349964) (xy 337.518 -348.395818) (xy 337.540642 -348.445398)
			(xy 337.555997 -348.497696) (xy 337.563754 -348.551647) (xy 337.563754 -348.606153) (xy 337.560749 -348.627052)
			(xy 337.766138 -348.627052) (xy 337.766138 -348.572548) (xy 337.773894 -348.518599) (xy 337.789248 -348.466303)
			(xy 337.811888 -348.416723) (xy 337.841353 -348.37087) (xy 337.877043 -348.329677) (xy 337.918232 -348.293982)
			(xy 337.964081 -348.264511) (xy 338.013657 -348.241865) (xy 338.065952 -348.226504) (xy 338.1199 -348.218741)
			(xy 338.147152 -348.218252) (xy 338.176069 -348.218785) (xy 338.23324 -348.227508) (xy 338.288439 -348.244762)
			(xy 338.340402 -348.270151) (xy 338.387936 -348.303093) (xy 338.429952 -348.342833) (xy 338.448142 -348.365318)
			(xy 338.458039 -348.377123) (xy 338.483363 -348.394642) (xy 338.512756 -348.403818) (xy 338.543548 -348.403818)
			(xy 338.572941 -348.394642) (xy 338.598265 -348.377123) (xy 338.608162 -348.365318) (xy 338.624915 -348.344535)
			(xy 338.663269 -348.307405) (xy 338.706423 -348.275983) (xy 338.753537 -348.250884) (xy 338.803689 -348.232598)
			(xy 338.8559 -348.221481) (xy 338.909152 -348.217751) (xy 338.962404 -348.221481) (xy 339.014615 -348.232598)
			(xy 339.064767 -348.250884) (xy 339.111881 -348.275983) (xy 339.155035 -348.307405) (xy 339.193389 -348.344535)
			(xy 339.210142 -348.365318) (xy 339.220039 -348.377123) (xy 339.245363 -348.394642) (xy 339.274756 -348.403818)
			(xy 339.305548 -348.403818) (xy 339.334941 -348.394642) (xy 339.360265 -348.377123) (xy 339.370162 -348.365318)
			(xy 339.386915 -348.344535) (xy 339.425269 -348.307405) (xy 339.468423 -348.275983) (xy 339.515537 -348.250884)
			(xy 339.565689 -348.232598) (xy 339.6179 -348.221481) (xy 339.671152 -348.217751) (xy 339.724404 -348.221481)
			(xy 339.776615 -348.232598) (xy 339.826767 -348.250884) (xy 339.873881 -348.275983) (xy 339.917035 -348.307405)
			(xy 339.955389 -348.344535) (xy 339.972142 -348.365318) (xy 339.982039 -348.377123) (xy 340.007363 -348.394642)
			(xy 340.036756 -348.403818) (xy 340.067548 -348.403818) (xy 340.096941 -348.394642) (xy 340.122265 -348.377123)
			(xy 340.132162 -348.365318) (xy 340.150379 -348.342856) (xy 340.192393 -348.303119) (xy 340.239922 -348.270177)
			(xy 340.291878 -348.244785) (xy 340.347072 -348.227524) (xy 340.404237 -348.21879) (xy 340.433152 -348.218252)
			(xy 340.461719 -348.218782) (xy 340.518214 -348.227316) (xy 340.572807 -348.244169) (xy 340.624281 -348.268966)
			(xy 340.671487 -348.301155) (xy 340.713371 -348.340015) (xy 340.731602 -348.362016) (xy 340.741172 -348.373259)
			(xy 340.765411 -348.390096) (xy 340.793451 -348.399307) (xy 340.822953 -348.400124) (xy 340.851459 -348.392478)
			(xy 340.876593 -348.377006) (xy 340.886796 -348.366334) (xy 340.904952 -348.346705) (xy 340.945838 -348.312247)
			(xy 340.991134 -348.283834) (xy 341.039954 -348.262024) (xy 341.09134 -348.247243) (xy 341.144287 -348.239782)
			(xy 341.171022 -348.239334) (xy 341.199937 -348.239896) (xy 341.257107 -348.248614) (xy 341.312306 -348.265862)
			(xy 341.364268 -348.291246) (xy 341.411803 -348.324183) (xy 341.453821 -348.363917) (xy 341.472012 -348.3864)
			(xy 341.481909 -348.398205) (xy 341.507233 -348.415724) (xy 341.536626 -348.4249) (xy 341.567418 -348.4249)
			(xy 341.596811 -348.415724) (xy 341.622135 -348.398205) (xy 341.632032 -348.3864) (xy 341.650205 -348.363901)
			(xy 341.692228 -348.324167) (xy 341.739767 -348.29123) (xy 341.791732 -348.265844) (xy 341.846933 -348.248591)
			(xy 341.904105 -348.239867) (xy 341.933022 -348.239334) (xy 341.960275 -348.239737) (xy 342.014227 -348.247497)
			(xy 342.066524 -348.262856) (xy 342.116104 -348.285501) (xy 342.161957 -348.314971) (xy 342.203149 -348.350666)
			(xy 342.238842 -348.391861) (xy 342.26831 -348.437715) (xy 342.290952 -348.487296) (xy 342.306307 -348.539595)
			(xy 342.314064 -348.593547) (xy 342.314064 -348.648053) (xy 342.306307 -348.702005) (xy 342.290952 -348.754304)
			(xy 342.26831 -348.803885) (xy 342.238842 -348.849739) (xy 342.203149 -348.890934) (xy 342.161957 -348.926629)
			(xy 342.116104 -348.956099) (xy 342.066524 -348.978744) (xy 342.014227 -348.994103) (xy 341.960275 -349.001863)
			(xy 341.933022 -349.00235) (xy 341.904105 -349.001835) (xy 341.846933 -348.993108) (xy 341.791733 -348.975851)
			(xy 341.739771 -348.950458) (xy 341.692237 -348.917513) (xy 341.650221 -348.877771) (xy 341.632032 -348.855284)
			(xy 341.622135 -348.843479) (xy 341.596811 -348.82596) (xy 341.567418 -348.816784) (xy 341.536626 -348.816784)
			(xy 341.507233 -348.82596) (xy 341.481909 -348.843479) (xy 341.472012 -348.855284) (xy 341.45381 -348.877758)
			(xy 341.411793 -348.917495) (xy 341.364261 -348.950435) (xy 341.312301 -348.975826) (xy 341.257106 -348.993084)
			(xy 341.199937 -349.001814) (xy 341.171022 -349.00235) (xy 341.142456 -349.001766) (xy 341.085964 -348.993244)
			(xy 341.031372 -348.976401) (xy 340.979898 -348.951614) (xy 340.932691 -348.919435) (xy 340.890804 -348.880583)
			(xy 340.872572 -348.858586) (xy 340.86303 -348.847318) (xy 340.838783 -348.83048) (xy 340.810736 -348.821272)
			(xy 340.781228 -348.82046) (xy 340.752717 -348.828113) (xy 340.727582 -348.843592) (xy 340.717378 -348.854268)
			(xy 340.699186 -348.873862) (xy 340.658307 -348.908323) (xy 340.613018 -348.93674) (xy 340.564206 -348.958556)
			(xy 340.512826 -348.973344) (xy 340.459885 -348.980815) (xy 340.433152 -348.981268) (xy 340.404236 -348.980725)
			(xy 340.347065 -348.972002) (xy 340.291866 -348.95475) (xy 340.239904 -348.929363) (xy 340.19237 -348.896424)
			(xy 340.150352 -348.856686) (xy 340.132162 -348.834202) (xy 340.122265 -348.822397) (xy 340.096941 -348.804878)
			(xy 340.067548 -348.795702) (xy 340.036756 -348.795702) (xy 340.007363 -348.804878) (xy 339.982039 -348.822397)
			(xy 339.972142 -348.834202) (xy 339.955389 -348.854985) (xy 339.917035 -348.892115) (xy 339.873881 -348.923537)
			(xy 339.826767 -348.948636) (xy 339.776615 -348.966922) (xy 339.724404 -348.978039) (xy 339.671152 -348.981769)
			(xy 339.6179 -348.978039) (xy 339.565689 -348.966922) (xy 339.515537 -348.948636) (xy 339.468423 -348.923537)
			(xy 339.425269 -348.892115) (xy 339.386915 -348.854985) (xy 339.370162 -348.834202) (xy 339.360265 -348.822397)
			(xy 339.334941 -348.804878) (xy 339.305548 -348.795702) (xy 339.274756 -348.795702) (xy 339.245363 -348.804878)
			(xy 339.220039 -348.822397) (xy 339.210142 -348.834202) (xy 339.193389 -348.854985) (xy 339.155035 -348.892115)
			(xy 339.111881 -348.923537) (xy 339.064767 -348.948636) (xy 339.014615 -348.966922) (xy 338.962404 -348.978039)
			(xy 338.909152 -348.981769) (xy 338.8559 -348.978039) (xy 338.803689 -348.966922) (xy 338.753537 -348.948636)
			(xy 338.706423 -348.923537) (xy 338.663269 -348.892115) (xy 338.624915 -348.854985) (xy 338.608162 -348.834202)
			(xy 338.598265 -348.822397) (xy 338.572941 -348.804878) (xy 338.543548 -348.795702) (xy 338.512756 -348.795702)
			(xy 338.483363 -348.804878) (xy 338.458039 -348.822397) (xy 338.448142 -348.834202) (xy 338.429928 -348.856666)
			(xy 338.387913 -348.896402) (xy 338.340383 -348.929343) (xy 338.288426 -348.954735) (xy 338.233233 -348.971996)
			(xy 338.176067 -348.98073) (xy 338.147152 -348.981268) (xy 338.1199 -348.980859) (xy 338.065952 -348.973096)
			(xy 338.013657 -348.957735) (xy 337.964081 -348.935089) (xy 337.918232 -348.905618) (xy 337.877043 -348.869923)
			(xy 337.841353 -348.82873) (xy 337.811888 -348.782877) (xy 337.789248 -348.733297) (xy 337.773894 -348.681001)
			(xy 337.766138 -348.627052) (xy 337.560749 -348.627052) (xy 337.555997 -348.660104) (xy 337.540642 -348.712402)
			(xy 337.518 -348.761982) (xy 337.488532 -348.807836) (xy 337.452839 -348.849029) (xy 337.411647 -348.884724)
			(xy 337.365795 -348.914193) (xy 337.316215 -348.936837) (xy 337.263918 -348.952194) (xy 337.209967 -348.959953)
			(xy 337.182714 -348.96044) (xy 337.156793 -348.960017) (xy 337.10543 -348.952976) (xy 337.055492 -348.939049)
			(xy 337.007899 -348.918493) (xy 336.963525 -348.891684) (xy 336.923187 -348.859117) (xy 336.905092 -348.840552)
			(xy 336.895703 -348.831104) (xy 336.873072 -348.817068) (xy 336.84758 -348.809369) (xy 336.820963 -348.808534)
			(xy 336.795038 -348.814618) (xy 336.771572 -348.827208) (xy 336.752166 -348.845443) (xy 336.744818 -348.856554)
			(xy 336.729487 -348.880269) (xy 336.692936 -348.923312) (xy 336.650442 -348.960499) (xy 336.626962 -348.976188)
			(xy 336.614968 -348.984388) (xy 336.595949 -349.006342) (xy 336.583886 -349.032766) (xy 336.579756 -349.061517)
			(xy 336.583895 -349.090268) (xy 336.595967 -349.116687) (xy 336.614994 -349.138635) (xy 336.626962 -349.146876)
			(xy 336.653745 -349.164882) (xy 336.701371 -349.208427) (xy 336.721704 -349.23349) (xy 336.731601 -349.245295)
			(xy 336.756925 -349.262814) (xy 336.786318 -349.27199) (xy 336.81711 -349.27199) (xy 336.846503 -349.262814)
			(xy 336.871827 -349.245295) (xy 336.881724 -349.23349) (xy 336.899899 -349.210993) (xy 336.941922 -349.171259)
			(xy 336.989461 -349.138322) (xy 337.041425 -349.112936) (xy 337.096625 -349.095683) (xy 337.153797 -349.086957)
			(xy 337.182714 -349.086424) (xy 337.209969 -349.086842) (xy 337.263923 -349.094602) (xy 337.316224 -349.109961)
			(xy 337.365806 -349.132608) (xy 337.411661 -349.16208) (xy 337.452854 -349.197779) (xy 337.488548 -349.238976)
			(xy 337.518015 -349.284834) (xy 337.540655 -349.33442) (xy 337.556008 -349.386722) (xy 337.563761 -349.440677)
			(xy 337.564222 -349.467932) (xy 337.563704 -349.496945) (xy 337.554931 -349.554303) (xy 337.537575 -349.609672)
			(xy 337.512038 -349.661775) (xy 337.478908 -349.709413) (xy 337.45932 -349.730822) (xy 337.449116 -349.742424)
			(xy 337.435534 -349.770156) (xy 337.43086 -349.80068) (xy 337.435521 -349.831205) (xy 337.449093 -349.858943)
			(xy 337.45932 -349.870522) (xy 337.478917 -349.891921) (xy 337.512032 -349.939567) (xy 337.537558 -349.991675)
			(xy 337.554908 -350.047044) (xy 337.563683 -350.1044) (xy 337.564222 -350.133412) (xy 337.563824 -350.15424)
			(xy 337.765644 -350.15424) (xy 337.766188 -350.125228) (xy 337.774952 -350.06787) (xy 337.792301 -350.012501)
			(xy 337.817833 -349.960397) (xy 337.85096 -349.912759) (xy 337.870546 -349.89135) (xy 337.880781 -349.879772)
			(xy 337.894365 -349.852032) (xy 337.899035 -349.8215) (xy 337.894365 -349.790968) (xy 337.880781 -349.763228)
			(xy 337.870546 -349.75165) (xy 337.850977 -349.730227) (xy 337.81786 -349.682586) (xy 337.79233 -349.630485)
			(xy 337.774972 -349.575122) (xy 337.766188 -349.51777) (xy 337.765644 -349.48876) (xy 337.76614 -349.46151)
			(xy 337.773901 -349.407565) (xy 337.789259 -349.355274) (xy 337.811901 -349.305699) (xy 337.841367 -349.259851)
			(xy 337.877057 -349.218663) (xy 337.918245 -349.182972) (xy 337.964092 -349.153505) (xy 338.013666 -349.130862)
			(xy 338.065957 -349.115503) (xy 338.119902 -349.107741) (xy 338.147152 -349.107252) (xy 338.176069 -349.107785)
			(xy 338.23324 -349.116508) (xy 338.288439 -349.133762) (xy 338.340402 -349.159151) (xy 338.387936 -349.192093)
			(xy 338.429952 -349.231833) (xy 338.448142 -349.254318) (xy 338.458039 -349.266123) (xy 338.483363 -349.283642)
			(xy 338.512756 -349.292818) (xy 338.543548 -349.292818) (xy 338.572941 -349.283642) (xy 338.598265 -349.266123)
			(xy 338.608162 -349.254318) (xy 338.624915 -349.233535) (xy 338.663269 -349.196405) (xy 338.706423 -349.164983)
			(xy 338.753537 -349.139884) (xy 338.803689 -349.121598) (xy 338.8559 -349.110481) (xy 338.909152 -349.106751)
			(xy 338.962404 -349.110481) (xy 339.014615 -349.121598) (xy 339.064767 -349.139884) (xy 339.111881 -349.164983)
			(xy 339.155035 -349.196405) (xy 339.193389 -349.233535) (xy 339.210142 -349.254318) (xy 339.220039 -349.266123)
			(xy 339.245363 -349.283642) (xy 339.274756 -349.292818) (xy 339.305548 -349.292818) (xy 339.334941 -349.283642)
			(xy 339.360265 -349.266123) (xy 339.370162 -349.254318) (xy 339.386915 -349.233535) (xy 339.425269 -349.196405)
			(xy 339.468423 -349.164983) (xy 339.515537 -349.139884) (xy 339.565689 -349.121598) (xy 339.6179 -349.110481)
			(xy 339.671152 -349.106751) (xy 339.724404 -349.110481) (xy 339.776615 -349.121598) (xy 339.826767 -349.139884)
			(xy 339.873881 -349.164983) (xy 339.917035 -349.196405) (xy 339.955389 -349.233535) (xy 339.972142 -349.254318)
			(xy 339.982039 -349.266123) (xy 340.007363 -349.283642) (xy 340.036756 -349.292818) (xy 340.067548 -349.292818)
			(xy 340.096941 -349.283642) (xy 340.122265 -349.266123) (xy 340.132162 -349.254318) (xy 340.150379 -349.231856)
			(xy 340.192393 -349.192119) (xy 340.239922 -349.159177) (xy 340.291878 -349.133785) (xy 340.347072 -349.116524)
			(xy 340.404237 -349.10779) (xy 340.433152 -349.107252) (xy 340.461719 -349.107782) (xy 340.518214 -349.116316)
			(xy 340.572807 -349.133169) (xy 340.624281 -349.157966) (xy 340.671487 -349.190155) (xy 340.713371 -349.229015)
			(xy 340.731602 -349.251016) (xy 340.741172 -349.262259) (xy 340.765411 -349.279096) (xy 340.793451 -349.288307)
			(xy 340.822953 -349.289124) (xy 340.851459 -349.281478) (xy 340.876593 -349.266006) (xy 340.886796 -349.255334)
			(xy 340.904952 -349.235705) (xy 340.945838 -349.201247) (xy 340.991134 -349.172834) (xy 341.039954 -349.151024)
			(xy 341.09134 -349.136243) (xy 341.144287 -349.128782) (xy 341.171022 -349.128334) (xy 341.199937 -349.128896)
			(xy 341.257107 -349.137614) (xy 341.312306 -349.154862) (xy 341.364268 -349.180246) (xy 341.411803 -349.213183)
			(xy 341.453821 -349.252917) (xy 341.472012 -349.2754) (xy 341.481909 -349.287205) (xy 341.507233 -349.304724)
			(xy 341.536626 -349.3139) (xy 341.567418 -349.3139) (xy 341.596811 -349.304724) (xy 341.622135 -349.287205)
			(xy 341.632032 -349.2754) (xy 341.650205 -349.252901) (xy 341.692228 -349.213167) (xy 341.739767 -349.18023)
			(xy 341.791732 -349.154844) (xy 341.846933 -349.137591) (xy 341.904105 -349.128867) (xy 341.933022 -349.128334)
			(xy 341.960275 -349.128737) (xy 342.014227 -349.136497) (xy 342.066524 -349.151856) (xy 342.116104 -349.174501)
			(xy 342.161957 -349.203971) (xy 342.203149 -349.239666) (xy 342.238842 -349.280861) (xy 342.26831 -349.326715)
			(xy 342.290952 -349.376296) (xy 342.306307 -349.428595) (xy 342.314064 -349.482547) (xy 342.314064 -349.537053)
			(xy 342.306307 -349.591005) (xy 342.290952 -349.643304) (xy 342.26831 -349.692885) (xy 342.238842 -349.738739)
			(xy 342.203149 -349.779934) (xy 342.161957 -349.815629) (xy 342.116104 -349.845099) (xy 342.066524 -349.867744)
			(xy 342.014227 -349.883103) (xy 341.960275 -349.890863) (xy 341.933022 -349.89135) (xy 341.904105 -349.890835)
			(xy 341.846933 -349.882108) (xy 341.791733 -349.864851) (xy 341.739771 -349.839458) (xy 341.692237 -349.806513)
			(xy 341.650221 -349.766771) (xy 341.632032 -349.744284) (xy 341.622135 -349.732479) (xy 341.596811 -349.71496)
			(xy 341.567418 -349.705784) (xy 341.536626 -349.705784) (xy 341.507233 -349.71496) (xy 341.481909 -349.732479)
			(xy 341.472012 -349.744284) (xy 341.45381 -349.766758) (xy 341.411793 -349.806495) (xy 341.364261 -349.839435)
			(xy 341.312301 -349.864826) (xy 341.257106 -349.882084) (xy 341.199937 -349.890814) (xy 341.171022 -349.89135)
			(xy 341.142456 -349.890766) (xy 341.085964 -349.882244) (xy 341.031372 -349.865401) (xy 340.979898 -349.840614)
			(xy 340.932691 -349.808435) (xy 340.890804 -349.769583) (xy 340.872572 -349.747586) (xy 340.86303 -349.736318)
			(xy 340.838783 -349.71948) (xy 340.810736 -349.710272) (xy 340.781228 -349.70946) (xy 340.752717 -349.717113)
			(xy 340.727582 -349.732592) (xy 340.717378 -349.743268) (xy 340.699186 -349.762862) (xy 340.658307 -349.797323)
			(xy 340.613018 -349.82574) (xy 340.564206 -349.847556) (xy 340.512826 -349.862344) (xy 340.459885 -349.869815)
			(xy 340.433152 -349.870268) (xy 340.404236 -349.869725) (xy 340.347065 -349.861002) (xy 340.291866 -349.84375)
			(xy 340.239904 -349.818363) (xy 340.19237 -349.785424) (xy 340.150352 -349.745686) (xy 340.132162 -349.723202)
			(xy 340.122265 -349.711397) (xy 340.096941 -349.693878) (xy 340.067548 -349.684702) (xy 340.036756 -349.684702)
			(xy 340.007363 -349.693878) (xy 339.982039 -349.711397) (xy 339.972142 -349.723202) (xy 339.955389 -349.743985)
			(xy 339.917035 -349.781115) (xy 339.873881 -349.812537) (xy 339.826767 -349.837636) (xy 339.776615 -349.855922)
			(xy 339.724404 -349.867039) (xy 339.671152 -349.870769) (xy 339.6179 -349.867039) (xy 339.565689 -349.855922)
			(xy 339.515537 -349.837636) (xy 339.468423 -349.812537) (xy 339.425269 -349.781115) (xy 339.386915 -349.743985)
			(xy 339.370162 -349.723202) (xy 339.360265 -349.711397) (xy 339.334941 -349.693878) (xy 339.305548 -349.684702)
			(xy 339.274756 -349.684702) (xy 339.245363 -349.693878) (xy 339.220039 -349.711397) (xy 339.210142 -349.723202)
			(xy 339.193389 -349.743985) (xy 339.155035 -349.781115) (xy 339.111881 -349.812537) (xy 339.064767 -349.837636)
			(xy 339.014615 -349.855922) (xy 338.962404 -349.867039) (xy 338.909152 -349.870769) (xy 338.8559 -349.867039)
			(xy 338.803689 -349.855922) (xy 338.753537 -349.837636) (xy 338.706423 -349.812537) (xy 338.663269 -349.781115)
			(xy 338.624915 -349.743985) (xy 338.608162 -349.723202) (xy 338.598265 -349.711397) (xy 338.572941 -349.693878)
			(xy 338.543548 -349.684702) (xy 338.512756 -349.684702) (xy 338.483363 -349.693878) (xy 338.458039 -349.711397)
			(xy 338.448142 -349.723202) (xy 338.423758 -349.75165) (xy 338.413523 -349.763228) (xy 338.399939 -349.790968)
			(xy 338.395268 -349.8215) (xy 338.399939 -349.852032) (xy 338.413523 -349.879772) (xy 338.423758 -349.89135)
			(xy 338.443327 -349.912773) (xy 338.476444 -349.960414) (xy 338.501975 -350.012515) (xy 338.519332 -350.067878)
			(xy 338.528116 -350.12523) (xy 338.52866 -350.15424) (xy 338.528174 -350.181491) (xy 338.520418 -350.235439)
			(xy 338.505063 -350.287734) (xy 338.482421 -350.337311) (xy 338.452955 -350.383161) (xy 338.417264 -350.424352)
			(xy 338.376073 -350.460043) (xy 338.330223 -350.489509) (xy 338.280646 -350.512151) (xy 338.228351 -350.527506)
			(xy 338.174403 -350.535262) (xy 338.119901 -350.535262) (xy 338.065953 -350.527506) (xy 338.013658 -350.512151)
			(xy 337.964081 -350.489509) (xy 337.918231 -350.460043) (xy 337.87704 -350.424352) (xy 337.841349 -350.383161)
			(xy 337.811883 -350.337311) (xy 337.789241 -350.287734) (xy 337.773886 -350.235439) (xy 337.76613 -350.181491)
			(xy 337.765644 -350.15424) (xy 337.563824 -350.15424) (xy 337.56367 -350.162328) (xy 337.554952 -350.219499)
			(xy 337.537703 -350.274698) (xy 337.512318 -350.326661) (xy 337.479378 -350.374195) (xy 337.43964 -350.416212)
			(xy 337.417156 -350.434402) (xy 337.405335 -350.444284) (xy 337.38781 -350.46961) (xy 337.378631 -350.499008)
			(xy 337.378634 -350.529806) (xy 337.387816 -350.559204) (xy 337.405345 -350.584527) (xy 337.417156 -350.594422)
			(xy 337.439641 -350.612612) (xy 337.479378 -350.65463) (xy 337.512318 -350.702165) (xy 337.537707 -350.754127)
			(xy 337.554962 -350.809325) (xy 337.563689 -350.866496) (xy 337.564222 -350.895412) (xy 337.563848 -350.91624)
			(xy 342.433656 -350.91624) (xy 342.434182 -350.887323) (xy 342.442906 -350.830151) (xy 342.460161 -350.774952)
			(xy 342.485551 -350.722989) (xy 342.518495 -350.675455) (xy 342.558236 -350.633439) (xy 342.580722 -350.61525)
			(xy 342.592484 -350.605307) (xy 342.609996 -350.579994) (xy 342.619172 -350.550614) (xy 342.61918 -350.519835)
			(xy 342.610018 -350.49045) (xy 342.592518 -350.465129) (xy 342.580722 -350.45523) (xy 342.558257 -350.437016)
			(xy 342.51852 -350.395002) (xy 342.485578 -350.347472) (xy 342.460186 -350.295515) (xy 342.442926 -350.240321)
			(xy 342.434193 -350.183155) (xy 342.433656 -350.15424) (xy 342.434224 -350.125229) (xy 342.442986 -350.067874)
			(xy 342.46033 -350.012505) (xy 342.485856 -349.960401) (xy 342.518976 -349.912761) (xy 342.538558 -349.89135)
			(xy 342.548791 -349.879771) (xy 342.562374 -349.852032) (xy 342.567044 -349.8215) (xy 342.562374 -349.790968)
			(xy 342.548791 -349.763229) (xy 342.538558 -349.75165) (xy 342.518991 -349.730225) (xy 342.485874 -349.682585)
			(xy 342.460342 -349.630484) (xy 342.442985 -349.575121) (xy 342.4342 -349.51777) (xy 342.433656 -349.48876)
			(xy 342.43414 -349.461509) (xy 342.441902 -349.407564) (xy 342.45726 -349.355271) (xy 342.479903 -349.305696)
			(xy 342.50937 -349.259848) (xy 342.545062 -349.218659) (xy 342.586251 -349.182968) (xy 342.632099 -349.153501)
			(xy 342.681675 -349.130858) (xy 342.733967 -349.115501) (xy 342.787913 -349.10774) (xy 342.815164 -349.107252)
			(xy 342.844081 -349.107776) (xy 342.901253 -349.116501) (xy 342.956452 -349.133757) (xy 343.008415 -349.159147)
			(xy 343.055948 -349.192091) (xy 343.097965 -349.231832) (xy 343.116154 -349.254318) (xy 343.126051 -349.266123)
			(xy 343.151375 -349.283642) (xy 343.180768 -349.292818) (xy 343.21156 -349.292818) (xy 343.240953 -349.283642)
			(xy 343.266277 -349.266123) (xy 343.276174 -349.254318) (xy 343.294384 -349.231851) (xy 343.336399 -349.192114)
			(xy 343.38393 -349.159172) (xy 343.435888 -349.133781) (xy 343.491082 -349.116521) (xy 343.548249 -349.107789)
			(xy 343.577164 -349.107252) (xy 343.604413 -349.107812) (xy 343.658355 -349.115562) (xy 343.710646 -349.130911)
			(xy 343.760221 -349.153545) (xy 343.806069 -349.183003) (xy 343.847259 -349.218687) (xy 343.882951 -349.25987)
			(xy 343.912419 -349.305713) (xy 343.935063 -349.355282) (xy 343.950422 -349.40757) (xy 343.958183 -349.461512)
			(xy 343.958672 -349.48876) (xy 343.958124 -349.517772) (xy 343.94936 -349.575129) (xy 343.932012 -349.630498)
			(xy 343.906481 -349.682603) (xy 343.873356 -349.730241) (xy 343.85377 -349.75165) (xy 343.843534 -349.763227)
			(xy 343.829948 -349.790967) (xy 343.825277 -349.8215) (xy 343.829948 -349.852033) (xy 343.843534 -349.879773)
			(xy 343.85377 -349.89135) (xy 343.873341 -349.912771) (xy 343.906457 -349.960413) (xy 343.931987 -350.012514)
			(xy 343.949344 -350.067878) (xy 343.958128 -350.12523) (xy 343.958672 -350.15424) (xy 343.958121 -350.183156)
			(xy 343.949401 -350.240326) (xy 343.93215 -350.295525) (xy 343.906764 -350.347487) (xy 343.873826 -350.395021)
			(xy 343.834089 -350.437039) (xy 343.811606 -350.45523) (xy 343.799761 -350.465084) (xy 343.782246 -350.49042)
			(xy 343.773075 -350.519824) (xy 343.773082 -350.550625) (xy 343.782267 -350.580025) (xy 343.799795 -350.605352)
			(xy 343.811606 -350.61525) (xy 343.834067 -350.633468) (xy 343.873803 -350.675482) (xy 343.906745 -350.723012)
			(xy 343.932137 -350.774968) (xy 343.949398 -350.83016) (xy 343.958133 -350.887326) (xy 343.958672 -350.91624)
			(xy 343.958259 -350.943494) (xy 343.950496 -350.997446) (xy 343.935134 -351.049744) (xy 343.912486 -351.099324)
			(xy 343.883012 -351.145176) (xy 343.847313 -351.186367) (xy 343.806115 -351.222058) (xy 343.760257 -351.251522)
			(xy 343.710673 -351.274161) (xy 343.658372 -351.289513) (xy 343.604418 -351.297265) (xy 343.577164 -351.297748)
			(xy 343.548248 -351.297203) (xy 343.491077 -351.288482) (xy 343.435878 -351.271231) (xy 343.383916 -351.245844)
			(xy 343.336381 -351.212904) (xy 343.294364 -351.173166) (xy 343.276174 -351.150682) (xy 343.266277 -351.138877)
			(xy 343.240953 -351.121358) (xy 343.21156 -351.112182) (xy 343.180768 -351.112182) (xy 343.151375 -351.121358)
			(xy 343.126051 -351.138877) (xy 343.116154 -351.150682) (xy 343.097928 -351.173136) (xy 343.055916 -351.212874)
			(xy 343.008389 -351.245817) (xy 342.956434 -351.27121) (xy 342.901243 -351.288473) (xy 342.844078 -351.297209)
			(xy 342.815164 -351.297748) (xy 342.787914 -351.297256) (xy 342.733968 -351.289495) (xy 342.681676 -351.274138)
			(xy 342.632101 -351.251495) (xy 342.586253 -351.222029) (xy 342.545064 -351.186338) (xy 342.509373 -351.14515)
			(xy 342.479907 -351.099302) (xy 342.457264 -351.049728) (xy 342.441905 -350.997436) (xy 342.434144 -350.94349)
			(xy 342.433656 -350.91624) (xy 337.563848 -350.91624) (xy 337.563733 -350.922663) (xy 337.555976 -350.97661)
			(xy 337.54062 -351.028904) (xy 337.517978 -351.07848) (xy 337.488512 -351.12433) (xy 337.452821 -351.165519)
			(xy 337.411631 -351.201211) (xy 337.365782 -351.230677) (xy 337.316206 -351.253319) (xy 337.263912 -351.268675)
			(xy 337.209965 -351.276433) (xy 337.182714 -351.27692) (xy 337.153796 -351.276422) (xy 337.096622 -351.267693)
			(xy 337.041422 -351.250433) (xy 336.98946 -351.225038) (xy 336.941926 -351.192089) (xy 336.899912 -351.152342)
			(xy 336.881724 -351.129854) (xy 336.871827 -351.118049) (xy 336.846503 -351.10053) (xy 336.81711 -351.091354)
			(xy 336.786318 -351.091354) (xy 336.756925 -351.10053) (xy 336.731601 -351.118049) (xy 336.721704 -351.129854)
			(xy 336.703524 -351.152347) (xy 336.661501 -351.192079) (xy 336.613963 -351.225015) (xy 336.562 -351.250402)
			(xy 336.506801 -351.267656) (xy 336.44963 -351.276385) (xy 336.420714 -351.27692) (xy 336.393462 -351.276432)
			(xy 336.339513 -351.268677) (xy 336.287216 -351.253323) (xy 336.237637 -351.230683) (xy 336.191784 -351.201218)
			(xy 336.150592 -351.165527) (xy 336.114898 -351.124337) (xy 336.085429 -351.078486) (xy 336.062786 -351.028908)
			(xy 336.047429 -350.976613) (xy 336.03967 -350.922664) (xy 336.039206 -350.895412) (xy 323.344983 -350.895412)
			(xy 326.824636 -356.89365) (xy 336.912199 -356.89365) (xy 336.912199 -356.83915) (xy 336.919955 -356.785205)
			(xy 336.93531 -356.732913) (xy 336.95795 -356.683338) (xy 336.987415 -356.63749) (xy 337.023105 -356.596302)
			(xy 337.064293 -356.560613) (xy 337.110142 -356.531148) (xy 337.159717 -356.508508) (xy 337.212009 -356.493155)
			(xy 337.265954 -356.485399) (xy 337.293204 -356.484936) (xy 337.319273 -356.485399) (xy 337.370924 -356.492507)
			(xy 337.421127 -356.506577) (xy 337.468949 -356.527347) (xy 337.5135 -356.55443) (xy 337.553953 -356.587323)
			(xy 337.589553 -356.625414) (xy 337.619639 -356.667995) (xy 337.63204 -356.69093) (xy 337.638853 -356.703047)
			(xy 337.65782 -356.723352) (xy 337.681561 -356.737788) (xy 337.708317 -356.745284) (xy 337.736103 -356.745284)
			(xy 337.762859 -356.737788) (xy 337.7866 -356.723352) (xy 337.805567 -356.703047) (xy 337.81238 -356.69093)
			(xy 337.825437 -356.666805) (xy 337.857419 -356.622237) (xy 337.895431 -356.582687) (xy 337.916774 -356.565454)
			(xy 337.928536 -356.555509) (xy 337.946057 -356.530199) (xy 337.955239 -356.500818) (xy 337.955247 -356.470036)
			(xy 337.946081 -356.44065) (xy 337.928574 -356.41533) (xy 337.916774 -356.405434) (xy 337.894301 -356.38723)
			(xy 337.854567 -356.345212) (xy 337.821627 -356.29768) (xy 337.796237 -356.245721) (xy 337.778978 -356.190526)
			(xy 337.770245 -356.133359) (xy 337.769708 -356.104444) (xy 337.770196 -356.077192) (xy 337.777948 -356.023241)
			(xy 337.793299 -355.970942) (xy 337.815937 -355.921361) (xy 337.845402 -355.875507) (xy 337.881094 -355.834314)
			(xy 337.922285 -355.798619) (xy 337.968137 -355.769151) (xy 338.017716 -355.746509) (xy 338.070013 -355.731154)
			(xy 338.123964 -355.723398) (xy 338.151216 -355.722936) (xy 338.180131 -355.723501) (xy 338.237301 -355.732219)
			(xy 338.292499 -355.749466) (xy 338.344462 -355.774849) (xy 338.391997 -355.807785) (xy 338.434015 -355.84752)
			(xy 338.452206 -355.870002) (xy 338.462103 -355.881807) (xy 338.487427 -355.899326) (xy 338.51682 -355.908502)
			(xy 338.547612 -355.908502) (xy 338.577005 -355.899326) (xy 338.602329 -355.881807) (xy 338.612226 -355.870002)
			(xy 338.628979 -355.849219) (xy 338.667333 -355.812089) (xy 338.710487 -355.780667) (xy 338.757601 -355.755568)
			(xy 338.807753 -355.737282) (xy 338.859964 -355.726165) (xy 338.913216 -355.722435) (xy 338.966468 -355.726165)
			(xy 339.018679 -355.737282) (xy 339.068831 -355.755568) (xy 339.115945 -355.780667) (xy 339.159099 -355.812089)
			(xy 339.197453 -355.849219) (xy 339.214206 -355.870002) (xy 339.224103 -355.881807) (xy 339.249427 -355.899326)
			(xy 339.27882 -355.908502) (xy 339.309612 -355.908502) (xy 339.339005 -355.899326) (xy 339.364329 -355.881807)
			(xy 339.374226 -355.870002) (xy 339.390979 -355.849219) (xy 339.429333 -355.812089) (xy 339.472487 -355.780667)
			(xy 339.519601 -355.755568) (xy 339.569753 -355.737282) (xy 339.621964 -355.726165) (xy 339.675216 -355.722435)
			(xy 339.728468 -355.726165) (xy 339.780679 -355.737282) (xy 339.830831 -355.755568) (xy 339.877945 -355.780667)
			(xy 339.921099 -355.812089) (xy 339.959453 -355.849219) (xy 339.976206 -355.870002) (xy 339.986103 -355.881807)
			(xy 340.011427 -355.899326) (xy 340.04082 -355.908502) (xy 340.071612 -355.908502) (xy 340.101005 -355.899326)
			(xy 340.126329 -355.881807) (xy 340.136226 -355.870002) (xy 340.152979 -355.849219) (xy 340.191333 -355.812089)
			(xy 340.234487 -355.780667) (xy 340.281601 -355.755568) (xy 340.331753 -355.737282) (xy 340.383964 -355.726165)
			(xy 340.437216 -355.722435) (xy 340.490468 -355.726165) (xy 340.542679 -355.737282) (xy 340.592831 -355.755568)
			(xy 340.639945 -355.780667) (xy 340.683099 -355.812089) (xy 340.721453 -355.849219) (xy 340.738206 -355.870002)
			(xy 340.748103 -355.881807) (xy 340.773427 -355.899326) (xy 340.80282 -355.908502) (xy 340.833612 -355.908502)
			(xy 340.863005 -355.899326) (xy 340.888329 -355.881807) (xy 340.898226 -355.870002) (xy 340.914979 -355.849219)
			(xy 340.953333 -355.812089) (xy 340.996487 -355.780667) (xy 341.043601 -355.755568) (xy 341.093753 -355.737282)
			(xy 341.145964 -355.726165) (xy 341.199216 -355.722435) (xy 341.252468 -355.726165) (xy 341.304679 -355.737282)
			(xy 341.354831 -355.755568) (xy 341.401945 -355.780667) (xy 341.445099 -355.812089) (xy 341.483453 -355.849219)
			(xy 341.500206 -355.870002) (xy 341.510103 -355.881807) (xy 341.535427 -355.899326) (xy 341.56482 -355.908502)
			(xy 341.595612 -355.908502) (xy 341.625005 -355.899326) (xy 341.650329 -355.881807) (xy 341.660226 -355.870002)
			(xy 341.678403 -355.847506) (xy 341.720425 -355.807772) (xy 341.767963 -355.774834) (xy 341.819927 -355.749448)
			(xy 341.875127 -355.732194) (xy 341.932299 -355.723469) (xy 341.961216 -355.722936) (xy 341.987469 -355.723337)
			(xy 342.03948 -355.730528) (xy 342.090012 -355.744786) (xy 342.138112 -355.76584) (xy 342.182868 -355.793294)
			(xy 342.223436 -355.826627) (xy 342.259047 -355.86521) (xy 342.274398 -355.886512) (xy 342.282762 -355.897725)
			(xy 342.304387 -355.915451) (xy 342.330011 -355.926648) (xy 342.35771 -355.930476) (xy 342.385409 -355.926648)
			(xy 342.411033 -355.915451) (xy 342.432658 -355.897725) (xy 342.441022 -355.886512) (xy 342.456356 -355.865201)
			(xy 342.491981 -355.826635) (xy 342.532557 -355.793316) (xy 342.577317 -355.765873) (xy 342.625416 -355.744825)
			(xy 342.675946 -355.730568) (xy 342.727953 -355.723372) (xy 342.754204 -355.722936) (xy 342.784327 -355.723508)
			(xy 342.843823 -355.73299) (xy 342.901091 -355.7517) (xy 342.954708 -355.779176) (xy 343.003343 -355.814733)
			(xy 343.024968 -355.835712) (xy 343.03469 -355.84493) (xy 343.057852 -355.858375) (xy 343.083713 -355.865337)
			(xy 343.110495 -355.865337) (xy 343.136356 -355.858375) (xy 343.159518 -355.84493) (xy 343.16924 -355.835712)
			(xy 343.19087 -355.814737) (xy 343.239497 -355.779168) (xy 343.293112 -355.751687) (xy 343.350382 -355.732977)
			(xy 343.40988 -355.723505) (xy 343.440004 -355.722936) (xy 343.467259 -355.723352) (xy 343.521214 -355.73111)
			(xy 343.573515 -355.746469) (xy 343.623098 -355.769115) (xy 343.668954 -355.798588) (xy 343.710147 -355.834287)
			(xy 343.745841 -355.875485) (xy 343.775308 -355.921344) (xy 343.797948 -355.97093) (xy 343.8133 -356.023233)
			(xy 343.821052 -356.077189) (xy 343.821512 -356.104444) (xy 343.820987 -356.133361) (xy 343.812264 -356.190533)
			(xy 343.795009 -356.245734) (xy 343.769619 -356.297696) (xy 343.736675 -356.34523) (xy 343.696932 -356.387245)
			(xy 343.674446 -356.405434) (xy 343.662593 -356.415281) (xy 343.645071 -356.440617) (xy 343.635897 -356.470024)
			(xy 343.635905 -356.500829) (xy 343.645095 -356.530232) (xy 343.662631 -356.555558) (xy 343.674446 -356.565454)
			(xy 343.696917 -356.583659) (xy 343.736651 -356.625678) (xy 343.76959 -356.67321) (xy 343.79498 -356.725168)
			(xy 343.81224 -356.780362) (xy 343.820974 -356.837529) (xy 343.821512 -356.866444) (xy 343.821063 -356.893696)
			(xy 343.813301 -356.947645) (xy 343.79794 -356.99994) (xy 343.775294 -357.049517) (xy 343.745824 -357.095367)
			(xy 343.710129 -357.136557) (xy 343.668935 -357.172248) (xy 343.623082 -357.201713) (xy 343.573503 -357.224354)
			(xy 343.521206 -357.239709) (xy 343.467256 -357.247466) (xy 343.440004 -357.247952) (xy 343.409881 -357.247378)
			(xy 343.350384 -357.237898) (xy 343.293117 -357.219188) (xy 343.2395 -357.191712) (xy 343.190865 -357.156155)
			(xy 343.16924 -357.135176) (xy 343.159518 -357.125958) (xy 343.136356 -357.112513) (xy 343.110495 -357.105551)
			(xy 343.083713 -357.105551) (xy 343.057852 -357.112513) (xy 343.03469 -357.125958) (xy 343.024968 -357.135176)
			(xy 343.003332 -357.156145) (xy 342.954707 -357.191715) (xy 342.901093 -357.219198) (xy 342.843825 -357.237909)
			(xy 342.784328 -357.247383) (xy 342.754204 -357.247952) (xy 342.727951 -357.247541) (xy 342.675941 -357.240352)
			(xy 342.625408 -357.226097) (xy 342.577309 -357.205044) (xy 342.532552 -357.177592) (xy 342.491984 -357.14426)
			(xy 342.456373 -357.105677) (xy 342.441022 -357.084376) (xy 342.432658 -357.073163) (xy 342.411033 -357.055437)
			(xy 342.385409 -357.04424) (xy 342.35771 -357.040412) (xy 342.330011 -357.04424) (xy 342.304387 -357.055437)
			(xy 342.282762 -357.073163) (xy 342.274398 -357.084376) (xy 342.259048 -357.105675) (xy 342.223426 -357.144242)
			(xy 342.182853 -357.177562) (xy 342.138096 -357.205006) (xy 342.09 -357.226057) (xy 342.039472 -357.240316)
			(xy 341.987467 -357.247514) (xy 341.961216 -357.247952) (xy 341.932299 -357.24744) (xy 341.875126 -357.238713)
			(xy 341.819927 -357.221454) (xy 341.767964 -357.196062) (xy 341.720431 -357.163116) (xy 341.678415 -357.123373)
			(xy 341.660226 -357.100886) (xy 341.650329 -357.089081) (xy 341.625005 -357.071562) (xy 341.595612 -357.062386)
			(xy 341.56482 -357.062386) (xy 341.535427 -357.071562) (xy 341.510103 -357.089081) (xy 341.500206 -357.100886)
			(xy 341.483453 -357.121669) (xy 341.445099 -357.158799) (xy 341.401945 -357.190221) (xy 341.354831 -357.21532)
			(xy 341.304679 -357.233606) (xy 341.252468 -357.244723) (xy 341.199216 -357.248453) (xy 341.145964 -357.244723)
			(xy 341.093753 -357.233606) (xy 341.043601 -357.21532) (xy 340.996487 -357.190221) (xy 340.953333 -357.158799)
			(xy 340.914979 -357.121669) (xy 340.898226 -357.100886) (xy 340.888329 -357.089081) (xy 340.863005 -357.071562)
			(xy 340.833612 -357.062386) (xy 340.80282 -357.062386) (xy 340.773427 -357.071562) (xy 340.748103 -357.089081)
			(xy 340.738206 -357.100886) (xy 340.721453 -357.121669) (xy 340.683099 -357.158799) (xy 340.639945 -357.190221)
			(xy 340.592831 -357.21532) (xy 340.542679 -357.233606) (xy 340.490468 -357.244723) (xy 340.437216 -357.248453)
			(xy 340.383964 -357.244723) (xy 340.331753 -357.233606) (xy 340.281601 -357.21532) (xy 340.234487 -357.190221)
			(xy 340.191333 -357.158799) (xy 340.152979 -357.121669) (xy 340.136226 -357.100886) (xy 340.126329 -357.089081)
			(xy 340.101005 -357.071562) (xy 340.071612 -357.062386) (xy 340.04082 -357.062386) (xy 340.011427 -357.071562)
			(xy 339.986103 -357.089081) (xy 339.976206 -357.100886) (xy 339.959453 -357.121669) (xy 339.921099 -357.158799)
			(xy 339.877945 -357.190221) (xy 339.830831 -357.21532) (xy 339.780679 -357.233606) (xy 339.728468 -357.244723)
			(xy 339.675216 -357.248453) (xy 339.621964 -357.244723) (xy 339.569753 -357.233606) (xy 339.519601 -357.21532)
			(xy 339.472487 -357.190221) (xy 339.429333 -357.158799) (xy 339.390979 -357.121669) (xy 339.374226 -357.100886)
			(xy 339.364329 -357.089081) (xy 339.339005 -357.071562) (xy 339.309612 -357.062386) (xy 339.27882 -357.062386)
			(xy 339.249427 -357.071562) (xy 339.224103 -357.089081) (xy 339.214206 -357.100886) (xy 339.197453 -357.121669)
			(xy 339.159099 -357.158799) (xy 339.115945 -357.190221) (xy 339.068831 -357.21532) (xy 339.018679 -357.233606)
			(xy 338.966468 -357.244723) (xy 338.913216 -357.248453) (xy 338.859964 -357.244723) (xy 338.807753 -357.233606)
			(xy 338.757601 -357.21532) (xy 338.710487 -357.190221) (xy 338.667333 -357.158799) (xy 338.628979 -357.121669)
			(xy 338.612226 -357.100886) (xy 338.602329 -357.089081) (xy 338.577005 -357.071562) (xy 338.547612 -357.062386)
			(xy 338.51682 -357.062386) (xy 338.487427 -357.071562) (xy 338.462103 -357.089081) (xy 338.452206 -357.100886)
			(xy 338.434008 -357.123364) (xy 338.39199 -357.1631) (xy 338.344457 -357.19604) (xy 338.292497 -357.221429)
			(xy 338.2373 -357.238687) (xy 338.180132 -357.247417) (xy 338.151216 -357.247952) (xy 338.125148 -357.247479)
			(xy 338.073497 -357.240373) (xy 338.023293 -357.226305) (xy 337.975471 -357.205538) (xy 337.93092 -357.178456)
			(xy 337.890467 -357.145564) (xy 337.854867 -357.107473) (xy 337.82478 -357.064893) (xy 337.81238 -357.041958)
			(xy 337.805567 -357.029841) (xy 337.7866 -357.009536) (xy 337.762859 -356.9951) (xy 337.736103 -356.987604)
			(xy 337.708317 -356.987604) (xy 337.681561 -356.9951) (xy 337.65782 -357.009536) (xy 337.638853 -357.029841)
			(xy 337.63204 -357.041958) (xy 337.619684 -357.064922) (xy 337.589607 -357.107522) (xy 337.554009 -357.145628)
			(xy 337.513553 -357.178532) (xy 337.468992 -357.20562) (xy 337.421158 -357.226386) (xy 337.370941 -357.240445)
			(xy 337.319278 -357.247534) (xy 337.293204 -357.247952) (xy 337.265954 -357.247401) (xy 337.212009 -357.239645)
			(xy 337.159717 -357.224292) (xy 337.110142 -357.201652) (xy 337.064293 -357.172187) (xy 337.023105 -357.136498)
			(xy 336.987415 -357.09531) (xy 336.95795 -357.049462) (xy 336.93531 -356.999887) (xy 336.919955 -356.947595)
			(xy 336.912199 -356.89365) (xy 326.824636 -356.89365) (xy 328.156062 -359.188766) (xy 328.187731 -359.238802)
			(xy 335.453223 -359.238802) (xy 335.456952 -359.18555) (xy 335.46807 -359.133337) (xy 335.486358 -359.083185)
			(xy 335.511459 -359.036072) (xy 335.542884 -358.992918) (xy 335.580018 -358.954566) (xy 335.600802 -358.937814)
			(xy 335.612602 -358.927911) (xy 335.630117 -358.902589) (xy 335.639292 -358.873197) (xy 335.639292 -358.842407)
			(xy 335.630119 -358.813016) (xy 335.612605 -358.787692) (xy 335.600802 -358.777794) (xy 335.578316 -358.759606)
			(xy 335.538581 -358.717586) (xy 335.505642 -358.67005) (xy 335.480254 -358.618088) (xy 335.462999 -358.56289)
			(xy 335.45427 -358.50572) (xy 335.453736 -358.476804) (xy 335.454159 -358.449549) (xy 335.461917 -358.395595)
			(xy 335.477275 -358.343293) (xy 335.49992 -358.29371) (xy 335.529391 -358.247855) (xy 335.565089 -358.206661)
			(xy 335.606287 -358.170967) (xy 335.652145 -358.141501) (xy 335.701731 -358.118861) (xy 335.754034 -358.103508)
			(xy 335.807989 -358.095756) (xy 335.835244 -358.095296) (xy 335.864296 -358.095875) (xy 335.92173 -358.104666)
			(xy 335.977166 -358.122067) (xy 336.029321 -358.147676) (xy 336.076988 -358.1809) (xy 336.119063 -358.220971)
			(xy 336.13725 -358.243632) (xy 336.146504 -358.254707) (xy 336.169828 -358.271677) (xy 336.196969 -358.281442)
			(xy 336.225758 -358.283222) (xy 336.253895 -358.276877) (xy 336.279133 -358.262911) (xy 336.28965 -358.25303)
			(xy 336.298332 -358.244396) (xy 336.316634 -358.228128) (xy 336.326226 -358.220518) (xy 336.33802 -358.21061)
			(xy 336.355531 -358.185287) (xy 336.364703 -358.155898) (xy 336.364705 -358.125111) (xy 336.355535 -358.095721)
			(xy 336.338026 -358.070397) (xy 336.326226 -358.060498) (xy 336.303747 -358.042302) (xy 336.26401 -358.000284)
			(xy 336.23107 -357.95275) (xy 336.205681 -357.90079) (xy 336.188424 -357.845593) (xy 336.179695 -357.788424)
			(xy 336.17916 -357.759508) (xy 336.179685 -357.732258) (xy 336.18744 -357.678314) (xy 336.202792 -357.626022)
			(xy 336.22543 -357.576447) (xy 336.254893 -357.530598) (xy 336.29058 -357.489408) (xy 336.331766 -357.453717)
			(xy 336.377611 -357.424249) (xy 336.427184 -357.401606) (xy 336.479475 -357.386248) (xy 336.533418 -357.378488)
			(xy 336.560668 -357.378) (xy 336.588047 -357.378477) (xy 336.64224 -357.386314) (xy 336.694757 -357.401816)
			(xy 336.744519 -357.424665) (xy 336.790505 -357.454393) (xy 336.831769 -357.490388) (xy 336.849974 -357.510842)
			(xy 336.860022 -357.521832) (xy 336.885087 -357.537887) (xy 336.913716 -357.54604) (xy 336.943479 -357.545599)
			(xy 336.971854 -357.536602) (xy 336.996433 -357.519812) (xy 337.006184 -357.508556) (xy 337.024421 -357.486776)
			(xy 337.066213 -357.448305) (xy 337.113247 -357.416454) (xy 337.164482 -357.391927) (xy 337.218787 -357.375267)
			(xy 337.274962 -357.366841) (xy 337.303364 -357.366316) (xy 337.331062 -357.366795) (xy 337.385876 -357.374797)
			(xy 337.438957 -357.390639) (xy 337.489191 -357.413988) (xy 337.535522 -357.444352) (xy 337.576978 -357.481096)
			(xy 337.59521 -357.501952) (xy 337.604729 -357.512643) (xy 337.628495 -357.528585) (xy 337.655753 -357.537301)
			(xy 337.684359 -357.538106) (xy 337.712064 -357.530938) (xy 337.736689 -357.516359) (xy 337.746848 -357.50627)
			(xy 337.764952 -357.487755) (xy 337.805259 -357.455249) (xy 337.849593 -357.428494) (xy 337.897138 -357.407982)
			(xy 337.947021 -357.394091) (xy 337.998325 -357.387075) (xy 338.024216 -357.386636) (xy 338.051471 -357.38704)
			(xy 338.105427 -357.3948) (xy 338.157728 -357.410161) (xy 338.207312 -357.432808) (xy 338.253167 -357.462282)
			(xy 338.29436 -357.497982) (xy 338.330054 -357.539181) (xy 338.35952 -357.585041) (xy 338.38216 -357.634628)
			(xy 338.397512 -357.686932) (xy 338.405264 -357.740889) (xy 338.405724 -357.768144) (xy 338.405194 -357.797061)
			(xy 338.396471 -357.854233) (xy 338.379218 -357.909433) (xy 338.353828 -357.961395) (xy 338.320885 -358.008929)
			(xy 338.281144 -358.050945) (xy 338.258658 -358.069134) (xy 338.246804 -358.078981) (xy 338.22928 -358.104316)
			(xy 338.220104 -358.133724) (xy 338.220112 -358.16453) (xy 338.229303 -358.193933) (xy 338.246842 -358.219259)
			(xy 338.258658 -358.229154) (xy 338.281111 -358.247382) (xy 338.32085 -358.289392) (xy 338.353794 -358.336919)
			(xy 338.379188 -358.388874) (xy 338.39645 -358.444065) (xy 338.405186 -358.50123) (xy 338.405724 -358.530144)
			(xy 338.405225 -358.557347) (xy 338.397493 -358.611202) (xy 338.382179 -358.663409) (xy 338.359595 -358.712906)
			(xy 338.330198 -358.758688) (xy 338.31276 -358.779572) (xy 338.303282 -358.791464) (xy 338.291054 -358.819286)
			(xy 338.287557 -358.849474) (xy 338.293099 -358.879354) (xy 338.307191 -358.906279) (xy 338.328583 -358.927865)
			(xy 338.341716 -358.935528) (xy 338.364879 -358.948451) (xy 338.407693 -358.979759) (xy 338.445736 -359.016719)
			(xy 338.462366 -359.037382) (xy 338.472263 -359.049187) (xy 338.497587 -359.066706) (xy 338.52698 -359.075882)
			(xy 338.557772 -359.075882) (xy 338.587165 -359.066706) (xy 338.612489 -359.049187) (xy 338.622386 -359.037382)
			(xy 338.639139 -359.016599) (xy 338.677493 -358.979469) (xy 338.720647 -358.948047) (xy 338.767761 -358.922948)
			(xy 338.817913 -358.904662) (xy 338.870124 -358.893545) (xy 338.923376 -358.889815) (xy 338.976628 -358.893545)
			(xy 339.028839 -358.904662) (xy 339.078991 -358.922948) (xy 339.126105 -358.948047) (xy 339.169259 -358.979469)
			(xy 339.207613 -359.016599) (xy 339.224366 -359.037382) (xy 339.234263 -359.049187) (xy 339.259587 -359.066706)
			(xy 339.28898 -359.075882) (xy 339.319772 -359.075882) (xy 339.349165 -359.066706) (xy 339.374489 -359.049187)
			(xy 339.384386 -359.037382) (xy 339.401139 -359.016599) (xy 339.439493 -358.979469) (xy 339.482647 -358.948047)
			(xy 339.529761 -358.922948) (xy 339.579913 -358.904662) (xy 339.632124 -358.893545) (xy 339.685376 -358.889815)
			(xy 339.738628 -358.893545) (xy 339.790839 -358.904662) (xy 339.840991 -358.922948) (xy 339.888105 -358.948047)
			(xy 339.931259 -358.979469) (xy 339.969613 -359.016599) (xy 339.986366 -359.037382) (xy 339.996263 -359.049187)
			(xy 340.021587 -359.066706) (xy 340.05098 -359.075882) (xy 340.081772 -359.075882) (xy 340.111165 -359.066706)
			(xy 340.136489 -359.049187) (xy 340.146386 -359.037382) (xy 340.163139 -359.016599) (xy 340.201493 -358.979469)
			(xy 340.244647 -358.948047) (xy 340.291761 -358.922948) (xy 340.341913 -358.904662) (xy 340.394124 -358.893545)
			(xy 340.447376 -358.889815) (xy 340.500628 -358.893545) (xy 340.552839 -358.904662) (xy 340.602991 -358.922948)
			(xy 340.650105 -358.948047) (xy 340.693259 -358.979469) (xy 340.731613 -359.016599) (xy 340.748366 -359.037382)
			(xy 340.758263 -359.049187) (xy 340.783587 -359.066706) (xy 340.81298 -359.075882) (xy 340.843772 -359.075882)
			(xy 340.873165 -359.066706) (xy 340.898489 -359.049187) (xy 340.908386 -359.037382) (xy 340.925139 -359.016599)
			(xy 340.963493 -358.979469) (xy 341.006647 -358.948047) (xy 341.053761 -358.922948) (xy 341.103913 -358.904662)
			(xy 341.156124 -358.893545) (xy 341.209376 -358.889815) (xy 341.262628 -358.893545) (xy 341.314839 -358.904662)
			(xy 341.364991 -358.922948) (xy 341.412105 -358.948047) (xy 341.455259 -358.979469) (xy 341.493613 -359.016599)
			(xy 341.510366 -359.037382) (xy 341.520263 -359.049187) (xy 341.545587 -359.066706) (xy 341.57498 -359.075882)
			(xy 341.605772 -359.075882) (xy 341.635165 -359.066706) (xy 341.660489 -359.049187) (xy 341.670386 -359.037382)
			(xy 341.688207 -359.015359) (xy 341.729273 -358.976336) (xy 341.752174 -358.959658) (xy 341.764272 -358.950505)
			(xy 341.782866 -358.926555) (xy 341.793608 -358.8982) (xy 341.795551 -358.867941) (xy 341.788523 -358.838446)
			(xy 341.773144 -358.812314) (xy 341.762334 -358.80167) (xy 341.743114 -358.783539) (xy 341.709397 -358.742857)
			(xy 341.681616 -358.697912) (xy 341.660303 -358.649563) (xy 341.645864 -358.598736) (xy 341.638575 -358.546403)
			(xy 341.638128 -358.519984) (xy 341.638696 -358.491069) (xy 341.647413 -358.4339) (xy 341.664661 -358.378701)
			(xy 341.690043 -358.326739) (xy 341.722978 -358.279204) (xy 341.762712 -358.237186) (xy 341.785194 -358.218994)
			(xy 341.797015 -358.209114) (xy 341.814531 -358.183785) (xy 341.823704 -358.154388) (xy 341.823701 -358.123593)
			(xy 341.814522 -358.094197) (xy 341.797001 -358.068872) (xy 341.785194 -358.058974) (xy 341.762697 -358.040799)
			(xy 341.722963 -357.998776) (xy 341.690026 -357.951238) (xy 341.66464 -357.899273) (xy 341.647386 -357.844073)
			(xy 341.638661 -357.786901) (xy 341.638128 -357.757984) (xy 341.63854 -357.730729) (xy 341.6463 -357.676774)
			(xy 341.66166 -357.624473) (xy 341.684307 -357.574891) (xy 341.71378 -357.529036) (xy 341.749479 -357.487842)
			(xy 341.790678 -357.452149) (xy 341.836536 -357.422682) (xy 341.886122 -357.400042) (xy 341.938425 -357.384689)
			(xy 341.992381 -357.376936) (xy 342.019636 -357.376476) (xy 342.01989 -357.376476) (xy 342.047433 -357.37695)
			(xy 342.101943 -357.384895) (xy 342.154745 -357.400592) (xy 342.204743 -357.423715) (xy 342.250898 -357.453785)
			(xy 342.292251 -357.490176) (xy 342.310466 -357.510842) (xy 342.320577 -357.521809) (xy 342.345631 -357.537962)
			(xy 342.374281 -357.5462) (xy 342.404088 -357.545822) (xy 342.432519 -357.536859) (xy 342.457154 -357.520074)
			(xy 342.46693 -357.50881) (xy 342.485142 -357.486967) (xy 342.526959 -357.448426) (xy 342.574034 -357.416519)
			(xy 342.625322 -357.39195) (xy 342.679689 -357.375266) (xy 342.735929 -357.366836) (xy 342.764364 -357.366316)
			(xy 342.794486 -357.366919) (xy 342.85398 -357.376394) (xy 342.911248 -357.395098) (xy 342.964865 -357.422566)
			(xy 343.013502 -357.458117) (xy 343.035128 -357.479092) (xy 343.04485 -357.48831) (xy 343.068012 -357.501755)
			(xy 343.093873 -357.508717) (xy 343.120655 -357.508717) (xy 343.146516 -357.501755) (xy 343.169678 -357.48831)
			(xy 343.1794 -357.479092) (xy 343.201 -357.458085) (xy 343.249636 -357.422521) (xy 343.303259 -357.395046)
			(xy 343.360534 -357.376344) (xy 343.420038 -357.36688) (xy 343.450164 -357.366316) (xy 343.477417 -357.366789)
			(xy 343.531369 -357.374542) (xy 343.583668 -357.389894) (xy 343.63325 -357.412534) (xy 343.679104 -357.442001)
			(xy 343.720298 -357.477694) (xy 343.755992 -357.518886) (xy 343.78546 -357.56474) (xy 343.808102 -357.614321)
			(xy 343.823456 -357.666619) (xy 343.83121 -357.720571) (xy 343.831672 -357.747824) (xy 343.83111 -357.776739)
			(xy 343.822392 -357.833909) (xy 343.805143 -357.889108) (xy 343.77976 -357.94107) (xy 343.746823 -357.988605)
			(xy 343.707089 -358.030623) (xy 343.684606 -358.048814) (xy 343.672777 -358.058686) (xy 343.655261 -358.084017)
			(xy 343.646089 -358.113416) (xy 343.646093 -358.144213) (xy 343.655274 -358.17361) (xy 343.672798 -358.198936)
			(xy 343.684606 -358.208834) (xy 343.705414 -358.225558) (xy 343.742548 -358.263913) (xy 343.773972 -358.307071)
			(xy 343.799073 -358.354188) (xy 343.81736 -358.404344) (xy 343.828477 -358.456559) (xy 343.832205 -358.509815)
			(xy 343.828473 -358.56307) (xy 343.817352 -358.615285) (xy 343.799061 -358.665439) (xy 343.773957 -358.712554)
			(xy 343.742529 -358.755709) (xy 343.705392 -358.794062) (xy 343.684606 -358.810814) (xy 343.672777 -358.820686)
			(xy 343.655261 -358.846017) (xy 343.646089 -358.875416) (xy 343.646093 -358.906213) (xy 343.655274 -358.93561)
			(xy 343.672798 -358.960936) (xy 343.684606 -358.970834) (xy 343.705414 -358.987558) (xy 343.742548 -359.025913)
			(xy 343.773972 -359.069071) (xy 343.799073 -359.116188) (xy 343.81736 -359.166344) (xy 343.828477 -359.218559)
			(xy 343.832205 -359.271815) (xy 343.828473 -359.32507) (xy 343.817352 -359.377285) (xy 343.799061 -359.427439)
			(xy 343.773957 -359.474554) (xy 343.742529 -359.517709) (xy 343.705392 -359.556062) (xy 343.684606 -359.572814)
			(xy 343.672777 -359.582686) (xy 343.655261 -359.608017) (xy 343.646089 -359.637416) (xy 343.646093 -359.668213)
			(xy 343.655274 -359.69761) (xy 343.672798 -359.722936) (xy 343.684606 -359.732834) (xy 343.705414 -359.749558)
			(xy 343.742548 -359.787913) (xy 343.773972 -359.831071) (xy 343.799073 -359.878188) (xy 343.81736 -359.928344)
			(xy 343.828477 -359.980559) (xy 343.832205 -360.033815) (xy 343.828473 -360.08707) (xy 343.817352 -360.139285)
			(xy 343.799061 -360.189439) (xy 343.773957 -360.236554) (xy 343.742529 -360.279709) (xy 343.705392 -360.318062)
			(xy 343.684606 -360.334814) (xy 343.672777 -360.344686) (xy 343.655261 -360.370017) (xy 343.646089 -360.399416)
			(xy 343.646093 -360.430213) (xy 343.655274 -360.45961) (xy 343.672798 -360.484936) (xy 343.684606 -360.494834)
			(xy 343.707107 -360.513004) (xy 343.746841 -360.555029) (xy 343.779778 -360.602568) (xy 343.805163 -360.654533)
			(xy 343.822415 -360.709734) (xy 343.83114 -360.766907) (xy 343.831672 -360.795824) (xy 343.831267 -360.823079)
			(xy 343.823506 -360.877034) (xy 343.808145 -360.929335) (xy 343.785497 -360.978918) (xy 343.756023 -361.024773)
			(xy 343.720324 -361.065966) (xy 343.679125 -361.101659) (xy 343.633265 -361.131126) (xy 343.583679 -361.153766)
			(xy 343.531375 -361.169119) (xy 343.477419 -361.176872) (xy 343.450164 -361.177332) (xy 343.420835 -361.17678)
			(xy 343.362867 -361.167803) (xy 343.306955 -361.150067) (xy 343.254413 -361.123987) (xy 343.206477 -361.090179)
			(xy 343.164276 -361.049438) (xy 343.128803 -361.002721) (xy 343.114376 -360.97718) (xy 343.109557 -360.969235)
			(xy 343.095458 -360.957159) (xy 343.077983 -360.950894) (xy 343.059423 -360.951261) (xy 343.04221 -360.958212)
			(xy 343.035128 -360.964226) (xy 343.02319 -360.974894) (xy 343.013502 -360.983802) (xy 342.998565 -361.005455)
			(xy 342.98967 -361.030211) (xy 342.987408 -361.056418) (xy 342.991932 -361.082332) (xy 343.002939 -361.106223)
			(xy 343.010998 -361.116626) (xy 343.027386 -361.137204) (xy 343.054961 -361.182004) (xy 343.076115 -361.23017)
			(xy 343.090444 -361.280787) (xy 343.097678 -361.332893) (xy 343.09812 -361.359196) (xy 343.097619 -361.386447)
			(xy 343.089863 -361.440393) (xy 343.074509 -361.492687) (xy 343.051869 -361.542263) (xy 343.022404 -361.588113)
			(xy 342.986714 -361.629303) (xy 342.945526 -361.664995) (xy 342.899677 -361.694461) (xy 342.850102 -361.717103)
			(xy 342.797809 -361.732459) (xy 342.743863 -361.740217) (xy 342.716612 -361.740704) (xy 342.687694 -361.740214)
			(xy 342.630519 -361.731484) (xy 342.575318 -361.714223) (xy 342.523356 -361.688826) (xy 342.475823 -361.655876)
			(xy 342.43381 -361.616127) (xy 342.415622 -361.593638) (xy 342.405725 -361.581833) (xy 342.380401 -361.564314)
			(xy 342.351008 -361.555138) (xy 342.320216 -361.555138) (xy 342.290823 -361.564314) (xy 342.265499 -361.581833)
			(xy 342.255602 -361.593638) (xy 342.248333 -361.602813) (xy 342.232828 -361.620351) (xy 342.224614 -361.62869)
			(xy 342.214238 -361.639813) (xy 342.200039 -361.666701) (xy 342.19437 -361.696575) (xy 342.197731 -361.726795)
			(xy 342.209827 -361.754692) (xy 342.21928 -361.766612) (xy 342.236469 -361.78743) (xy 342.265387 -361.833019)
			(xy 342.287596 -361.882227) (xy 342.302652 -361.934073) (xy 342.310254 -361.987522) (xy 342.31072 -362.014516)
			(xy 342.310237 -362.041767) (xy 342.302479 -362.095714) (xy 342.287122 -362.148008) (xy 342.26448 -362.197585)
			(xy 342.235013 -362.243435) (xy 342.199322 -362.284624) (xy 342.158131 -362.320316) (xy 342.112281 -362.349782)
			(xy 342.062705 -362.372424) (xy 342.01041 -362.38778) (xy 341.956463 -362.395537) (xy 341.929212 -362.396024)
			(xy 341.901243 -362.395556) (xy 341.845902 -362.3874) (xy 341.792347 -362.371247) (xy 341.741726 -362.347444)
			(xy 341.695126 -362.3165) (xy 341.653546 -362.279081) (xy 341.635334 -362.257848) (xy 341.625758 -362.247132)
			(xy 341.601994 -362.231) (xy 341.574677 -362.222124) (xy 341.545969 -362.221208) (xy 341.518142 -362.228325)
			(xy 341.493398 -362.24291) (xy 341.483188 -362.253022) (xy 341.465075 -362.271613) (xy 341.424725 -362.30426)
			(xy 341.38032 -362.331132) (xy 341.33268 -362.351734) (xy 341.282687 -362.365685) (xy 341.231264 -362.372726)
			(xy 341.205312 -362.373164) (xy 341.176395 -362.372651) (xy 341.119223 -362.363923) (xy 341.064023 -362.346664)
			(xy 341.012061 -362.321272) (xy 340.964528 -362.288327) (xy 340.922511 -362.248584) (xy 340.904322 -362.226098)
			(xy 340.894425 -362.214293) (xy 340.869101 -362.196774) (xy 340.839708 -362.187598) (xy 340.808916 -362.187598)
			(xy 340.779523 -362.196774) (xy 340.754199 -362.214293) (xy 340.744302 -362.226098) (xy 340.727549 -362.246881)
			(xy 340.689195 -362.284011) (xy 340.646041 -362.315433) (xy 340.598927 -362.340532) (xy 340.548775 -362.358818)
			(xy 340.496564 -362.369935) (xy 340.443312 -362.373665) (xy 340.39006 -362.369935) (xy 340.337849 -362.358818)
			(xy 340.287697 -362.340532) (xy 340.240583 -362.315433) (xy 340.197429 -362.284011) (xy 340.159075 -362.246881)
			(xy 340.142322 -362.226098) (xy 340.132425 -362.214293) (xy 340.107101 -362.196774) (xy 340.077708 -362.187598)
			(xy 340.046916 -362.187598) (xy 340.017523 -362.196774) (xy 339.992199 -362.214293) (xy 339.982302 -362.226098)
			(xy 339.964109 -362.24858) (xy 339.92209 -362.288315) (xy 339.874555 -362.321255) (xy 339.822594 -362.346643)
			(xy 339.767397 -362.3639) (xy 339.710228 -362.372629) (xy 339.681312 -362.373164) (xy 339.654097 -362.372702)
			(xy 339.600221 -362.364968) (xy 339.54799 -362.349654) (xy 339.498466 -362.327072) (xy 339.452655 -362.297681)
			(xy 339.411486 -362.262076) (xy 339.393276 -362.241846) (xy 339.383459 -362.231266) (xy 339.359238 -362.215595)
			(xy 339.331598 -362.207332) (xy 339.302751 -362.207139) (xy 339.275003 -362.215032) (xy 339.250575 -362.230378)
			(xy 339.240622 -362.24083) (xy 339.222462 -362.260636) (xy 339.18151 -362.295429) (xy 339.13608 -362.324127)
			(xy 339.08707 -362.346163) (xy 339.035452 -362.3611) (xy 338.982248 -362.368642) (xy 338.95538 -362.3691)
			(xy 338.926465 -362.368524) (xy 338.869297 -362.359807) (xy 338.814099 -362.342561) (xy 338.762137 -362.31718)
			(xy 338.714602 -362.284246) (xy 338.672582 -362.244515) (xy 338.65439 -362.222034) (xy 338.644493 -362.210229)
			(xy 338.619169 -362.19271) (xy 338.589776 -362.183534) (xy 338.558984 -362.183534) (xy 338.529591 -362.19271)
			(xy 338.504267 -362.210229) (xy 338.49437 -362.222034) (xy 338.476205 -362.244539) (xy 338.434178 -362.284271)
			(xy 338.386638 -362.317207) (xy 338.334672 -362.342591) (xy 338.27947 -362.359843) (xy 338.222297 -362.368567)
			(xy 338.19338 -362.3691) (xy 338.167312 -362.36863) (xy 338.115662 -362.361521) (xy 338.06546 -362.347451)
			(xy 338.017638 -362.326681) (xy 337.973087 -362.299599) (xy 337.932635 -362.266708) (xy 337.897034 -362.228618)
			(xy 337.866946 -362.18604) (xy 337.854544 -362.163106) (xy 337.847731 -362.150989) (xy 337.828764 -362.130684)
			(xy 337.805023 -362.116248) (xy 337.778267 -362.108752) (xy 337.750481 -362.108752) (xy 337.723725 -362.116248)
			(xy 337.699984 -362.130684) (xy 337.681017 -362.150989) (xy 337.674204 -362.163106) (xy 337.661804 -362.186044)
			(xy 337.63173 -362.228638) (xy 337.596136 -362.266741) (xy 337.555686 -362.299643) (xy 337.511132 -362.326731)
			(xy 337.463305 -362.347499) (xy 337.413096 -362.361562) (xy 337.361439 -362.368658) (xy 337.335368 -362.3691)
			(xy 337.30799 -362.368598) (xy 337.253798 -362.360767) (xy 337.201281 -362.345269) (xy 337.151519 -362.322425)
			(xy 337.105533 -362.292702) (xy 337.064268 -362.256711) (xy 337.046062 -362.236258) (xy 337.035978 -362.225304)
			(xy 337.010922 -362.209248) (xy 336.982304 -362.201091) (xy 336.952548 -362.201525) (xy 336.924179 -362.210513)
			(xy 336.899603 -362.227293) (xy 336.889852 -362.238544) (xy 336.871595 -362.260307) (xy 336.829807 -362.298779)
			(xy 336.782778 -362.330632) (xy 336.731546 -362.355162) (xy 336.677245 -362.371826) (xy 336.621073 -362.380257)
			(xy 336.592672 -362.380784) (xy 336.563618 -362.380272) (xy 336.50618 -362.371469) (xy 336.450742 -362.354055)
			(xy 336.398587 -362.328433) (xy 336.350922 -362.295197) (xy 336.30885 -362.255115) (xy 336.290666 -362.232448)
			(xy 336.281394 -362.221386) (xy 336.258079 -362.204404) (xy 336.230941 -362.19463) (xy 336.202152 -362.192845)
			(xy 336.174014 -362.199193) (xy 336.14878 -362.213165) (xy 336.138266 -362.22305) (xy 336.116651 -362.244093)
			(xy 336.067986 -362.279738) (xy 336.014317 -362.307277) (xy 335.956981 -362.326024) (xy 335.897409 -362.335512)
			(xy 335.867248 -362.33608) (xy 335.839995 -362.3356) (xy 335.786043 -362.327849) (xy 335.733744 -362.312497)
			(xy 335.684162 -362.289858) (xy 335.638307 -362.260393) (xy 335.597114 -362.224701) (xy 335.561419 -362.183509)
			(xy 335.531951 -362.137655) (xy 335.50931 -362.088075) (xy 335.493955 -362.035776) (xy 335.486201 -361.981825)
			(xy 335.48574 -361.954572) (xy 335.486232 -361.926969) (xy 335.494193 -361.872338) (xy 335.509943 -361.819426)
			(xy 335.533154 -361.769336) (xy 335.563343 -361.723113) (xy 335.581244 -361.702096) (xy 335.590775 -361.690438)
			(xy 335.603212 -361.663031) (xy 335.607139 -361.633191) (xy 335.602218 -361.6035) (xy 335.588874 -361.576523)
			(xy 335.578958 -361.56519) (xy 335.559564 -361.54383) (xy 335.526755 -361.496377) (xy 335.501471 -361.444522)
			(xy 335.484288 -361.389449) (xy 335.4756 -361.332416) (xy 335.475072 -361.30357) (xy 335.475072 -361.303316)
			(xy 335.475523 -361.275711) (xy 335.483492 -361.221079) (xy 335.499252 -361.168165) (xy 335.522473 -361.118076)
			(xy 335.55267 -361.071856) (xy 335.570576 -361.05084) (xy 335.580061 -361.039148) (xy 335.592499 -361.011753)
			(xy 335.596433 -360.981925) (xy 335.591524 -360.952241) (xy 335.578196 -360.925268) (xy 335.56829 -360.913934)
			(xy 335.548875 -360.892593) (xy 335.516067 -360.845135) (xy 335.490786 -360.793275) (xy 335.473609 -360.738198)
			(xy 335.464928 -360.681161) (xy 335.464404 -360.652314) (xy 335.464404 -360.65206) (xy 335.464898 -360.624457)
			(xy 335.472859 -360.569827) (xy 335.48861 -360.516915) (xy 335.511821 -360.466825) (xy 335.542007 -360.420602)
			(xy 335.559908 -360.399584) (xy 335.569445 -360.387932) (xy 335.581872 -360.360522) (xy 335.585794 -360.330682)
			(xy 335.580873 -360.300991) (xy 335.567534 -360.274013) (xy 335.557622 -360.262678) (xy 335.538216 -360.241329)
			(xy 335.50541 -360.193872) (xy 335.480129 -360.142014) (xy 335.462949 -360.086939) (xy 335.454263 -360.029904)
			(xy 335.453736 -360.001058) (xy 335.453736 -360.000804) (xy 335.454244 -359.971887) (xy 335.462973 -359.914714)
			(xy 335.480232 -359.859515) (xy 335.505626 -359.807553) (xy 335.538572 -359.760019) (xy 335.578315 -359.718003)
			(xy 335.600802 -359.699814) (xy 335.612602 -359.689911) (xy 335.630117 -359.664589) (xy 335.639292 -359.635197)
			(xy 335.639292 -359.604407) (xy 335.630119 -359.575016) (xy 335.612605 -359.549692) (xy 335.600802 -359.539794)
			(xy 335.580021 -359.523037) (xy 335.542887 -359.484686) (xy 335.511462 -359.441533) (xy 335.48636 -359.39442)
			(xy 335.468071 -359.344267) (xy 335.456953 -359.292055) (xy 335.453223 -359.238802) (xy 328.187731 -359.238802)
			(xy 333.162628 -367.099088) (xy 345.670122 -367.099088) (xy 345.674193 -367.043466) (xy 345.686319 -366.989029)
			(xy 345.706242 -366.936938) (xy 345.733538 -366.888303) (xy 345.767624 -366.84416) (xy 345.807773 -366.805451)
			(xy 345.853131 -366.773) (xy 345.902731 -366.747499) (xy 345.955515 -366.729492) (xy 346.010358 -366.719362)
			(xy 346.066092 -366.717325) (xy 346.121529 -366.723425) (xy 346.175486 -366.737531) (xy 346.226815 -366.759343)
			(xy 346.274421 -366.788397) (xy 346.317289 -366.824072) (xy 346.354506 -366.865609) (xy 346.385279 -366.912122)
			(xy 346.408951 -366.962619) (xy 346.415339 -366.983852) (xy 355.291872 -366.983852) (xy 355.291872 -366.929348)
			(xy 355.299628 -366.8754) (xy 355.314984 -366.823105) (xy 355.337625 -366.773527) (xy 355.367092 -366.727676)
			(xy 355.402783 -366.686485) (xy 355.443974 -366.650793) (xy 355.489825 -366.621326) (xy 355.539403 -366.598684)
			(xy 355.591698 -366.583329) (xy 355.645646 -366.575572) (xy 355.672898 -366.575086) (xy 355.699276 -366.575567)
			(xy 355.751532 -366.582819) (xy 355.802291 -366.597199) (xy 355.850585 -366.618432) (xy 355.895495 -366.646115)
			(xy 355.936164 -366.679719) (xy 355.971818 -366.718604) (xy 356.001776 -366.762029) (xy 356.01402 -366.785398)
			(xy 356.020722 -366.797757) (xy 356.039697 -366.818485) (xy 356.063611 -366.833247) (xy 356.090647 -366.840919)
			(xy 356.118749 -366.840919) (xy 356.145785 -366.833247) (xy 356.169699 -366.818485) (xy 356.188674 -366.797757)
			(xy 356.195376 -366.785398) (xy 356.207619 -366.762028) (xy 356.23758 -366.718604) (xy 356.273235 -366.679718)
			(xy 356.313905 -366.646112) (xy 356.358813 -366.618425) (xy 356.407106 -366.597184) (xy 356.457864 -366.582795)
			(xy 356.510119 -366.575531) (xy 356.536498 -366.575086) (xy 356.563751 -366.575561) (xy 356.617701 -366.583318)
			(xy 356.669998 -366.598673) (xy 356.719578 -366.621315) (xy 356.76543 -366.650783) (xy 356.806623 -366.686476)
			(xy 356.842316 -366.727668) (xy 356.871784 -366.773521) (xy 356.894426 -366.8231) (xy 356.909782 -366.875397)
			(xy 356.917539 -366.929347) (xy 356.917539 -366.983853) (xy 356.909782 -367.037803) (xy 356.894426 -367.0901)
			(xy 356.871784 -367.139679) (xy 356.842316 -367.185532) (xy 356.806623 -367.226724) (xy 356.76543 -367.262417)
			(xy 356.719578 -367.291885) (xy 356.669998 -367.314527) (xy 356.617701 -367.329882) (xy 356.563751 -367.337639)
			(xy 356.536498 -367.338102) (xy 356.510119 -367.337631) (xy 356.457863 -367.330378) (xy 356.407104 -367.315997)
			(xy 356.358809 -367.294763) (xy 356.313899 -367.267078) (xy 356.27323 -367.233473) (xy 356.237577 -367.194586)
			(xy 356.207619 -367.151159) (xy 356.195376 -367.12779) (xy 356.188674 -367.115431) (xy 356.169699 -367.094703)
			(xy 356.145785 -367.079941) (xy 356.118749 -367.072269) (xy 356.090647 -367.072269) (xy 356.063611 -367.079941)
			(xy 356.039697 -367.094703) (xy 356.020722 -367.115431) (xy 356.01402 -367.12779) (xy 356.001775 -367.151159)
			(xy 355.971814 -367.194584) (xy 355.93616 -367.23347) (xy 355.895491 -367.267077) (xy 355.850582 -367.294764)
			(xy 355.80229 -367.316004) (xy 355.751532 -367.330393) (xy 355.699277 -367.337657) (xy 355.672898 -367.338102)
			(xy 355.645646 -367.337628) (xy 355.591698 -367.329871) (xy 355.539403 -367.314516) (xy 355.489825 -367.291874)
			(xy 355.443974 -367.262407) (xy 355.402783 -367.226715) (xy 355.367092 -367.185524) (xy 355.337625 -367.139673)
			(xy 355.314984 -367.090095) (xy 355.299628 -367.0378) (xy 355.291872 -366.983852) (xy 346.415339 -366.983852)
			(xy 346.425019 -367.016026) (xy 346.433139 -367.071202) (xy 346.433648 -367.099088) (xy 346.433139 -367.126974)
			(xy 346.425019 -367.18215) (xy 346.408951 -367.235557) (xy 346.385279 -367.286054) (xy 346.354506 -367.332567)
			(xy 346.317289 -367.374104) (xy 346.274421 -367.409779) (xy 346.226815 -367.438833) (xy 346.175486 -367.460645)
			(xy 346.121529 -367.474751) (xy 346.066092 -367.480851) (xy 346.010358 -367.478814) (xy 345.955515 -367.468684)
			(xy 345.902731 -367.450677) (xy 345.853131 -367.425176) (xy 345.807773 -367.392725) (xy 345.767624 -367.354016)
			(xy 345.733538 -367.309873) (xy 345.706242 -367.261238) (xy 345.686319 -367.209147) (xy 345.674193 -367.15471)
			(xy 345.670122 -367.099088) (xy 333.162628 -367.099088) (xy 333.410706 -367.491048) (xy 352.48091 -367.491048)
			(xy 352.48091 -367.436552) (xy 352.488665 -367.382611) (xy 352.504018 -367.330322) (xy 352.526656 -367.28075)
			(xy 352.556118 -367.234905) (xy 352.591804 -367.193718) (xy 352.632989 -367.15803) (xy 352.678833 -367.128566)
			(xy 352.728403 -367.105925) (xy 352.780691 -367.09057) (xy 352.834632 -367.082812) (xy 352.86188 -367.082324)
			(xy 352.888261 -367.082716) (xy 352.940522 -367.08998) (xy 352.991284 -367.104372) (xy 353.03958 -367.125618)
			(xy 353.084489 -367.153313) (xy 353.125157 -367.18693) (xy 353.160807 -367.225826) (xy 353.190761 -367.269262)
			(xy 353.203002 -367.292636) (xy 353.209704 -367.304995) (xy 353.228679 -367.325723) (xy 353.252593 -367.340485)
			(xy 353.279629 -367.348157) (xy 353.307731 -367.348157) (xy 353.334767 -367.340485) (xy 353.358681 -367.325723)
			(xy 353.377656 -367.304995) (xy 353.384358 -367.292636) (xy 353.396587 -367.269259) (xy 353.426553 -367.225837)
			(xy 353.462212 -367.186954) (xy 353.502883 -367.15335) (xy 353.547794 -367.125665) (xy 353.596088 -367.104425)
			(xy 353.646845 -367.090035) (xy 353.699101 -367.08277) (xy 353.72548 -367.082324) (xy 353.752736 -367.082722)
			(xy 353.806694 -367.090477) (xy 353.858998 -367.105832) (xy 353.908585 -367.128476) (xy 353.954445 -367.157946)
			(xy 353.995643 -367.193642) (xy 354.031342 -367.234839) (xy 354.060815 -367.280697) (xy 354.083461 -367.330283)
			(xy 354.098819 -367.382587) (xy 354.106577 -367.436544) (xy 354.106577 -367.491056) (xy 354.098819 -367.545013)
			(xy 354.083461 -367.597317) (xy 354.060815 -367.646903) (xy 354.031342 -367.692761) (xy 353.995643 -367.733958)
			(xy 353.954445 -367.769654) (xy 353.944177 -367.776252) (xy 369.189506 -367.776252) (xy 369.193577 -367.72063)
			(xy 369.205703 -367.666193) (xy 369.225626 -367.614102) (xy 369.252922 -367.565467) (xy 369.287008 -367.521324)
			(xy 369.327157 -367.482615) (xy 369.372515 -367.450164) (xy 369.422115 -367.424663) (xy 369.474899 -367.406656)
			(xy 369.529742 -367.396526) (xy 369.585476 -367.394489) (xy 369.640913 -367.400589) (xy 369.69487 -367.414695)
			(xy 369.746199 -367.436507) (xy 369.793805 -367.465561) (xy 369.836673 -367.501236) (xy 369.87389 -367.542773)
			(xy 369.904663 -367.589286) (xy 369.928335 -367.639783) (xy 369.944403 -367.69319) (xy 369.952523 -367.748366)
			(xy 369.953032 -367.776252) (xy 369.952523 -367.804138) (xy 369.944403 -367.859314) (xy 369.928335 -367.912721)
			(xy 369.905269 -367.961926) (xy 370.232686 -367.961926) (xy 370.23319 -367.933008) (xy 370.241918 -367.875835)
			(xy 370.259176 -367.820634) (xy 370.28457 -367.768672) (xy 370.317518 -367.721139) (xy 370.357264 -367.679124)
			(xy 370.379752 -367.660936) (xy 370.391535 -367.651012) (xy 370.409059 -367.625697) (xy 370.418241 -367.59631)
			(xy 370.418245 -367.565522) (xy 370.409073 -367.536131) (xy 370.391557 -367.510811) (xy 370.379752 -367.500916)
			(xy 370.357266 -367.482728) (xy 370.317533 -367.440706) (xy 370.284596 -367.39317) (xy 370.259208 -367.341209)
			(xy 370.241952 -367.286011) (xy 370.233222 -367.228842) (xy 370.232686 -367.199926) (xy 370.233172 -367.172675)
			(xy 370.240928 -367.118727) (xy 370.256283 -367.066432) (xy 370.278925 -367.016855) (xy 370.308391 -366.971005)
			(xy 370.344082 -366.929814) (xy 370.385273 -366.894123) (xy 370.431123 -366.864657) (xy 370.4807 -366.842015)
			(xy 370.532995 -366.82666) (xy 370.586943 -366.818904) (xy 370.641445 -366.818904) (xy 370.695393 -366.82666)
			(xy 370.747688 -366.842015) (xy 370.797265 -366.864657) (xy 370.843115 -366.894123) (xy 370.884306 -366.929814)
			(xy 370.919997 -366.971005) (xy 370.949463 -367.016855) (xy 370.972105 -367.066432) (xy 370.98746 -367.118727)
			(xy 370.995216 -367.172675) (xy 370.995702 -367.199926) (xy 370.99513 -367.228841) (xy 370.986412 -367.28601)
			(xy 370.969165 -367.341207) (xy 370.943783 -367.393169) (xy 370.910849 -367.440705) (xy 370.871117 -367.482724)
			(xy 370.848636 -367.500916) (xy 370.836802 -367.510784) (xy 370.819281 -367.536114) (xy 370.810106 -367.565516)
			(xy 370.810111 -367.596316) (xy 370.819295 -367.625715) (xy 370.836825 -367.65104) (xy 370.848636 -367.660936)
			(xy 370.871144 -367.679098) (xy 370.910876 -367.721125) (xy 370.943811 -367.768666) (xy 370.969195 -367.820633)
			(xy 370.986446 -367.875835) (xy 370.99517 -367.933008) (xy 370.995702 -367.961926) (xy 372.38051 -367.961926)
			(xy 372.381043 -367.93301) (xy 372.389769 -367.875839) (xy 372.407023 -367.82064) (xy 372.432412 -367.768678)
			(xy 372.465353 -367.721144) (xy 372.505092 -367.679127) (xy 372.527576 -367.660936) (xy 372.539356 -367.651011)
			(xy 372.556876 -367.625695) (xy 372.566056 -367.596309) (xy 372.56606 -367.565523) (xy 372.55689 -367.536134)
			(xy 372.539378 -367.510813) (xy 372.527576 -367.500916) (xy 372.505095 -367.482722) (xy 372.465361 -367.440702)
			(xy 372.432422 -367.393168) (xy 372.407034 -367.341207) (xy 372.389777 -367.28601) (xy 372.381046 -367.228842)
			(xy 372.38051 -367.199926) (xy 372.380996 -367.172675) (xy 372.388752 -367.118727) (xy 372.404107 -367.066432)
			(xy 372.426749 -367.016855) (xy 372.456215 -366.971005) (xy 372.491906 -366.929814) (xy 372.533097 -366.894123)
			(xy 372.578947 -366.864657) (xy 372.628524 -366.842015) (xy 372.680819 -366.82666) (xy 372.734767 -366.818904)
			(xy 372.789269 -366.818904) (xy 372.843217 -366.82666) (xy 372.895512 -366.842015) (xy 372.945089 -366.864657)
			(xy 372.990939 -366.894123) (xy 373.03213 -366.929814) (xy 373.067821 -366.971005) (xy 373.097287 -367.016855)
			(xy 373.119929 -367.066432) (xy 373.135284 -367.118727) (xy 373.14304 -367.172675) (xy 373.143526 -367.199926)
			(xy 373.142982 -367.228842) (xy 373.134263 -367.286014) (xy 373.117011 -367.341213) (xy 373.091625 -367.393176)
			(xy 373.058684 -367.44071) (xy 373.018945 -367.482726) (xy 372.99646 -367.500916) (xy 372.984624 -367.510783)
			(xy 372.967099 -367.536112) (xy 372.957922 -367.565515) (xy 372.957926 -367.596317) (xy 372.967113 -367.625716)
			(xy 372.984647 -367.651041) (xy 372.99646 -367.660936) (xy 373.018952 -367.679117) (xy 373.058689 -367.721137)
			(xy 373.091628 -367.768674) (xy 373.117015 -367.820638) (xy 373.134269 -367.875838) (xy 373.142994 -367.933009)
			(xy 373.143526 -367.961926) (xy 374.51411 -367.961926) (xy 374.514643 -367.93301) (xy 374.523369 -367.875839)
			(xy 374.540623 -367.82064) (xy 374.566012 -367.768678) (xy 374.598953 -367.721144) (xy 374.638692 -367.679127)
			(xy 374.661176 -367.660936) (xy 374.672956 -367.651011) (xy 374.690476 -367.625695) (xy 374.699656 -367.596309)
			(xy 374.69966 -367.565523) (xy 374.69049 -367.536134) (xy 374.672978 -367.510813) (xy 374.661176 -367.500916)
			(xy 374.638695 -367.482722) (xy 374.598961 -367.440702) (xy 374.566022 -367.393168) (xy 374.540634 -367.341207)
			(xy 374.523377 -367.28601) (xy 374.514646 -367.228842) (xy 374.51411 -367.199926) (xy 374.514596 -367.172675)
			(xy 374.522352 -367.118727) (xy 374.537707 -367.066432) (xy 374.560349 -367.016855) (xy 374.589815 -366.971005)
			(xy 374.625506 -366.929814) (xy 374.666697 -366.894123) (xy 374.712547 -366.864657) (xy 374.762124 -366.842015)
			(xy 374.814419 -366.82666) (xy 374.868367 -366.818904) (xy 374.922869 -366.818904) (xy 374.976817 -366.82666)
			(xy 375.029112 -366.842015) (xy 375.078689 -366.864657) (xy 375.124539 -366.894123) (xy 375.16573 -366.929814)
			(xy 375.201421 -366.971005) (xy 375.230887 -367.016855) (xy 375.253529 -367.066432) (xy 375.268884 -367.118727)
			(xy 375.27664 -367.172675) (xy 375.277126 -367.199926) (xy 375.276582 -367.228842) (xy 375.267863 -367.286014)
			(xy 375.250611 -367.341213) (xy 375.225225 -367.393176) (xy 375.192284 -367.44071) (xy 375.152545 -367.482726)
			(xy 375.13006 -367.500916) (xy 375.118224 -367.510783) (xy 375.100699 -367.536112) (xy 375.091522 -367.565515)
			(xy 375.091526 -367.596317) (xy 375.100713 -367.625716) (xy 375.118247 -367.651041) (xy 375.13006 -367.660936)
			(xy 375.152552 -367.679117) (xy 375.192289 -367.721137) (xy 375.225228 -367.768674) (xy 375.250615 -367.820638)
			(xy 375.267869 -367.875838) (xy 375.276594 -367.933009) (xy 375.276603 -367.933478) (xy 376.66676 -367.933478)
			(xy 376.667312 -367.904562) (xy 376.676031 -367.847391) (xy 376.693281 -367.792192) (xy 376.718666 -367.74023)
			(xy 376.751605 -367.692695) (xy 376.791342 -367.650678) (xy 376.813826 -367.632488) (xy 376.825649 -367.622612)
			(xy 376.84316 -367.597281) (xy 376.852329 -367.567884) (xy 376.852325 -367.537089) (xy 376.843148 -367.507694)
			(xy 376.825631 -367.482368) (xy 376.813826 -367.472468) (xy 376.791333 -367.454288) (xy 376.751597 -367.412267)
			(xy 376.718658 -367.36473) (xy 376.693271 -367.312766) (xy 376.676018 -367.257566) (xy 376.667293 -367.200395)
			(xy 376.66676 -367.171478) (xy 376.667246 -367.144227) (xy 376.675002 -367.090279) (xy 376.690357 -367.037984)
			(xy 376.712999 -366.988407) (xy 376.742465 -366.942557) (xy 376.778156 -366.901366) (xy 376.819347 -366.865675)
			(xy 376.865197 -366.836209) (xy 376.914774 -366.813567) (xy 376.967069 -366.798212) (xy 377.021017 -366.790456)
			(xy 377.075519 -366.790456) (xy 377.129467 -366.798212) (xy 377.181762 -366.813567) (xy 377.231339 -366.836209)
			(xy 377.277189 -366.865675) (xy 377.31838 -366.901366) (xy 377.354071 -366.942557) (xy 377.383537 -366.988407)
			(xy 377.406179 -367.037984) (xy 377.421534 -367.090279) (xy 377.42929 -367.144227) (xy 377.429776 -367.171478)
			(xy 377.429251 -367.200395) (xy 377.420525 -367.257566) (xy 377.403269 -367.312765) (xy 377.377878 -367.364727)
			(xy 377.344935 -367.412261) (xy 377.305195 -367.454278) (xy 377.28271 -367.472468) (xy 377.270927 -367.48239)
			(xy 377.25341 -367.507707) (xy 377.244232 -367.537093) (xy 377.244228 -367.56788) (xy 377.253398 -367.597269)
			(xy 377.270909 -367.62259) (xy 377.28271 -367.632488) (xy 377.30519 -367.650683) (xy 377.344925 -367.692702)
			(xy 377.377864 -367.740237) (xy 377.403253 -367.792197) (xy 377.42051 -367.847394) (xy 377.42924 -367.904562)
			(xy 377.429776 -367.933478) (xy 377.42929 -367.960729) (xy 377.421534 -368.014677) (xy 377.406179 -368.066972)
			(xy 377.383537 -368.116549) (xy 377.354071 -368.162399) (xy 377.336143 -368.18309) (xy 380.86182 -368.18309)
			(xy 380.86182 -368.098394) (xy 380.869871 -368.01408) (xy 380.8859 -367.930914) (xy 380.909761 -367.849647)
			(xy 380.94124 -367.771017) (xy 380.980051 -367.695736) (xy 381.025841 -367.624484) (xy 381.078197 -367.557908)
			(xy 381.136645 -367.49661) (xy 381.200655 -367.441145) (xy 381.269647 -367.392016) (xy 381.342997 -367.349667)
			(xy 381.42004 -367.314483) (xy 381.500079 -367.286781) (xy 381.582388 -367.266813) (xy 381.666223 -367.25476)
			(xy 381.750824 -367.25073) (xy 381.835425 -367.25476) (xy 381.91926 -367.266813) (xy 382.001569 -367.286781)
			(xy 382.081608 -367.314483) (xy 382.158651 -367.349667) (xy 382.232001 -367.392016) (xy 382.300993 -367.441145)
			(xy 382.365003 -367.49661) (xy 382.423451 -367.557908) (xy 382.475807 -367.624484) (xy 382.521597 -367.695736)
			(xy 382.560408 -367.771017) (xy 382.591887 -367.849647) (xy 382.615748 -367.930914) (xy 382.631777 -368.01408)
			(xy 382.639828 -368.098394) (xy 382.640332 -368.140742) (xy 382.639828 -368.18309) (xy 382.631777 -368.267404)
			(xy 382.615748 -368.35057) (xy 382.591887 -368.431837) (xy 382.560408 -368.510467) (xy 382.521597 -368.585748)
			(xy 382.475807 -368.657) (xy 382.423451 -368.723576) (xy 382.365003 -368.784874) (xy 382.300993 -368.840339)
			(xy 382.232001 -368.889468) (xy 382.158651 -368.931817) (xy 382.081608 -368.967001) (xy 382.001569 -368.994703)
			(xy 381.91926 -369.014671) (xy 381.835425 -369.026724) (xy 381.750824 -369.030755) (xy 381.666223 -369.026724)
			(xy 381.582388 -369.014671) (xy 381.500079 -368.994703) (xy 381.42004 -368.967001) (xy 381.342997 -368.931817)
			(xy 381.269647 -368.889468) (xy 381.200655 -368.840339) (xy 381.136645 -368.784874) (xy 381.078197 -368.723576)
			(xy 381.025841 -368.657) (xy 380.980051 -368.585748) (xy 380.94124 -368.510467) (xy 380.909761 -368.431837)
			(xy 380.8859 -368.35057) (xy 380.869871 -368.267404) (xy 380.86182 -368.18309) (xy 377.336143 -368.18309)
			(xy 377.31838 -368.20359) (xy 377.277189 -368.239281) (xy 377.231339 -368.268747) (xy 377.181762 -368.291389)
			(xy 377.129467 -368.306744) (xy 377.075519 -368.3145) (xy 377.021017 -368.3145) (xy 376.967069 -368.306744)
			(xy 376.914774 -368.291389) (xy 376.865197 -368.268747) (xy 376.819347 -368.239281) (xy 376.778156 -368.20359)
			(xy 376.742465 -368.162399) (xy 376.712999 -368.116549) (xy 376.690357 -368.066972) (xy 376.675002 -368.014677)
			(xy 376.667246 -367.960729) (xy 376.66676 -367.933478) (xy 375.276603 -367.933478) (xy 375.277126 -367.961926)
			(xy 375.27664 -367.989177) (xy 375.268884 -368.043125) (xy 375.253529 -368.09542) (xy 375.230887 -368.144997)
			(xy 375.201421 -368.190847) (xy 375.16573 -368.232038) (xy 375.124539 -368.267729) (xy 375.078689 -368.297195)
			(xy 375.029112 -368.319837) (xy 374.976817 -368.335192) (xy 374.922869 -368.342948) (xy 374.868367 -368.342948)
			(xy 374.814419 -368.335192) (xy 374.762124 -368.319837) (xy 374.712547 -368.297195) (xy 374.666697 -368.267729)
			(xy 374.625506 -368.232038) (xy 374.589815 -368.190847) (xy 374.560349 -368.144997) (xy 374.537707 -368.09542)
			(xy 374.522352 -368.043125) (xy 374.514596 -367.989177) (xy 374.51411 -367.961926) (xy 373.143526 -367.961926)
			(xy 373.14304 -367.989177) (xy 373.135284 -368.043125) (xy 373.119929 -368.09542) (xy 373.097287 -368.144997)
			(xy 373.067821 -368.190847) (xy 373.03213 -368.232038) (xy 372.990939 -368.267729) (xy 372.945089 -368.297195)
			(xy 372.895512 -368.319837) (xy 372.843217 -368.335192) (xy 372.789269 -368.342948) (xy 372.734767 -368.342948)
			(xy 372.680819 -368.335192) (xy 372.628524 -368.319837) (xy 372.578947 -368.297195) (xy 372.533097 -368.267729)
			(xy 372.491906 -368.232038) (xy 372.456215 -368.190847) (xy 372.426749 -368.144997) (xy 372.404107 -368.09542)
			(xy 372.388752 -368.043125) (xy 372.380996 -367.989177) (xy 372.38051 -367.961926) (xy 370.995702 -367.961926)
			(xy 370.995216 -367.989177) (xy 370.98746 -368.043125) (xy 370.972105 -368.09542) (xy 370.949463 -368.144997)
			(xy 370.919997 -368.190847) (xy 370.884306 -368.232038) (xy 370.843115 -368.267729) (xy 370.797265 -368.297195)
			(xy 370.747688 -368.319837) (xy 370.695393 -368.335192) (xy 370.641445 -368.342948) (xy 370.586943 -368.342948)
			(xy 370.532995 -368.335192) (xy 370.4807 -368.319837) (xy 370.431123 -368.297195) (xy 370.385273 -368.267729)
			(xy 370.344082 -368.232038) (xy 370.308391 -368.190847) (xy 370.278925 -368.144997) (xy 370.256283 -368.09542)
			(xy 370.240928 -368.043125) (xy 370.233172 -367.989177) (xy 370.232686 -367.961926) (xy 369.905269 -367.961926)
			(xy 369.904663 -367.963218) (xy 369.87389 -368.009731) (xy 369.836673 -368.051268) (xy 369.793805 -368.086943)
			(xy 369.746199 -368.115997) (xy 369.69487 -368.137809) (xy 369.640913 -368.151915) (xy 369.585476 -368.158015)
			(xy 369.529742 -368.155978) (xy 369.474899 -368.145848) (xy 369.422115 -368.127841) (xy 369.372515 -368.10234)
			(xy 369.327157 -368.069889) (xy 369.287008 -368.03118) (xy 369.252922 -367.987037) (xy 369.225626 -367.938402)
			(xy 369.205703 -367.886311) (xy 369.193577 -367.831874) (xy 369.189506 -367.776252) (xy 353.944177 -367.776252)
			(xy 353.908585 -367.799124) (xy 353.858998 -367.821768) (xy 353.806694 -367.837123) (xy 353.752736 -367.844878)
			(xy 353.72548 -367.84534) (xy 353.699102 -367.844863) (xy 353.646847 -367.837609) (xy 353.596089 -367.823227)
			(xy 353.547795 -367.801992) (xy 353.502885 -367.774309) (xy 353.462216 -367.740705) (xy 353.426562 -367.70182)
			(xy 353.396603 -367.658396) (xy 353.384358 -367.635028) (xy 353.377656 -367.622669) (xy 353.358681 -367.601941)
			(xy 353.334767 -367.587179) (xy 353.307731 -367.579507) (xy 353.279629 -367.579507) (xy 353.252593 -367.587179)
			(xy 353.228679 -367.601941) (xy 353.209704 -367.622669) (xy 353.203002 -367.635028) (xy 353.190787 -367.658413)
			(xy 353.160821 -367.701837) (xy 353.125161 -367.740721) (xy 353.084488 -367.774326) (xy 353.039575 -367.802011)
			(xy 352.991278 -367.823249) (xy 352.940518 -367.837635) (xy 352.88826 -367.844896) (xy 352.86188 -367.84534)
			(xy 352.834632 -367.844788) (xy 352.780691 -367.83703) (xy 352.728403 -367.821675) (xy 352.678833 -367.799034)
			(xy 352.632989 -367.76957) (xy 352.591804 -367.733882) (xy 352.556118 -367.692695) (xy 352.526656 -367.64685)
			(xy 352.504018 -367.597278) (xy 352.488665 -367.544989) (xy 352.48091 -367.491048) (xy 333.410706 -367.491048)
			(xy 333.799079 -368.104674) (xy 346.277182 -368.104674) (xy 346.281253 -368.049052) (xy 346.293379 -367.994615)
			(xy 346.313302 -367.942524) (xy 346.340598 -367.893889) (xy 346.374684 -367.849746) (xy 346.414833 -367.811037)
			(xy 346.460191 -367.778586) (xy 346.509791 -367.753085) (xy 346.562575 -367.735078) (xy 346.617418 -367.724948)
			(xy 346.673152 -367.722911) (xy 346.728589 -367.729011) (xy 346.782546 -367.743117) (xy 346.833875 -367.764929)
			(xy 346.881481 -367.793983) (xy 346.924349 -367.829658) (xy 346.961566 -367.871195) (xy 346.992339 -367.917708)
			(xy 347.016011 -367.968205) (xy 347.032079 -368.021612) (xy 347.040199 -368.076788) (xy 347.040708 -368.104674)
			(xy 347.040569 -368.112294) (xy 347.30385 -368.112294) (xy 347.307921 -368.056672) (xy 347.320047 -368.002235)
			(xy 347.33997 -367.950144) (xy 347.367266 -367.901509) (xy 347.401352 -367.857366) (xy 347.441501 -367.818657)
			(xy 347.486859 -367.786206) (xy 347.536459 -367.760705) (xy 347.589243 -367.742698) (xy 347.644086 -367.732568)
			(xy 347.69982 -367.730531) (xy 347.755257 -367.736631) (xy 347.809214 -367.750737) (xy 347.860543 -367.772549)
			(xy 347.908149 -367.801603) (xy 347.951017 -367.837278) (xy 347.988234 -367.878815) (xy 348.019007 -367.925328)
			(xy 348.042679 -367.975825) (xy 348.058747 -368.029232) (xy 348.066867 -368.084408) (xy 348.067376 -368.112294)
			(xy 348.066867 -368.14018) (xy 348.058747 -368.195356) (xy 348.042679 -368.248763) (xy 348.019007 -368.29926)
			(xy 347.988234 -368.345773) (xy 347.951017 -368.38731) (xy 347.908149 -368.422985) (xy 347.860543 -368.452039)
			(xy 347.809214 -368.473851) (xy 347.755257 -368.487957) (xy 347.69982 -368.494057) (xy 347.644086 -368.49202)
			(xy 347.589243 -368.48189) (xy 347.536459 -368.463883) (xy 347.486859 -368.438382) (xy 347.441501 -368.405931)
			(xy 347.401352 -368.367222) (xy 347.367266 -368.323079) (xy 347.33997 -368.274444) (xy 347.320047 -368.222353)
			(xy 347.307921 -368.167916) (xy 347.30385 -368.112294) (xy 347.040569 -368.112294) (xy 347.040199 -368.13256)
			(xy 347.032079 -368.187736) (xy 347.016011 -368.241143) (xy 346.992339 -368.29164) (xy 346.961566 -368.338153)
			(xy 346.924349 -368.37969) (xy 346.881481 -368.415365) (xy 346.833875 -368.444419) (xy 346.782546 -368.466231)
			(xy 346.728589 -368.480337) (xy 346.673152 -368.486437) (xy 346.617418 -368.4844) (xy 346.562575 -368.47427)
			(xy 346.509791 -368.456263) (xy 346.460191 -368.430762) (xy 346.414833 -368.398311) (xy 346.374684 -368.359602)
			(xy 346.340598 -368.315459) (xy 346.313302 -368.266824) (xy 346.293379 -368.214733) (xy 346.281253 -368.160296)
			(xy 346.277182 -368.104674) (xy 333.799079 -368.104674) (xy 334.4926 -369.20043) (xy 334.933102 -369.640932)
			(xy 346.293341 -369.640932) (xy 346.293345 -369.586423) (xy 346.301105 -369.532469) (xy 346.316466 -369.480169)
			(xy 346.339113 -369.430588) (xy 346.368587 -369.384734) (xy 346.404286 -369.343541) (xy 346.445484 -369.307849)
			(xy 346.491343 -369.278383) (xy 346.540928 -369.255744) (xy 346.59323 -369.240392) (xy 346.647185 -369.23264)
			(xy 346.67444 -369.23218) (xy 346.695505 -369.232424) (xy 346.737385 -369.237011) (xy 346.758006 -369.241324)
			(xy 346.77144 -369.243944) (xy 346.79877 -369.24259) (xy 346.824757 -369.234019) (xy 346.847531 -369.218848)
			(xy 346.865453 -369.19817) (xy 346.877234 -369.173471) (xy 346.882025 -369.14653) (xy 346.881196 -369.132866)
			(xy 346.879672 -369.098068) (xy 346.880212 -369.070819) (xy 346.887973 -369.016877) (xy 346.903331 -368.964588)
			(xy 346.925974 -368.915018) (xy 346.955441 -368.869174) (xy 346.991133 -368.82799) (xy 347.032322 -368.792305)
			(xy 347.07817 -368.762845) (xy 347.127745 -368.74021) (xy 347.180036 -368.72486) (xy 347.233979 -368.717108)
			(xy 347.288477 -368.717112) (xy 347.342419 -368.724872) (xy 347.394708 -368.740229) (xy 347.444279 -368.762872)
			(xy 347.490123 -368.792339) (xy 347.531307 -368.82803) (xy 347.566993 -368.869219) (xy 347.596453 -368.915067)
			(xy 347.619089 -368.964641) (xy 347.634439 -369.016932) (xy 347.642192 -369.070875) (xy 347.642188 -369.125373)
			(xy 347.634429 -369.179315) (xy 347.619072 -369.231604) (xy 347.59643 -369.281175) (xy 347.566964 -369.32702)
			(xy 347.531273 -369.368204) (xy 347.490085 -369.40389) (xy 347.444237 -369.433351) (xy 347.394663 -369.455987)
			(xy 347.342372 -369.471338) (xy 347.288429 -369.479091) (xy 347.26118 -369.479576) (xy 347.240115 -369.479329)
			(xy 347.198235 -369.474745) (xy 347.177614 -369.470432) (xy 347.16417 -369.467881) (xy 347.136851 -369.469231)
			(xy 347.110873 -369.477794) (xy 347.088105 -369.492953) (xy 347.070184 -369.513618) (xy 347.060002 -369.534948)
			(xy 364.036862 -369.534948) (xy 364.040933 -369.479326) (xy 364.053059 -369.424889) (xy 364.072982 -369.372798)
			(xy 364.100278 -369.324163) (xy 364.134364 -369.28002) (xy 364.174513 -369.241311) (xy 364.219871 -369.20886)
			(xy 364.269471 -369.183359) (xy 364.322255 -369.165352) (xy 364.377098 -369.155222) (xy 364.432832 -369.153185)
			(xy 364.488269 -369.159285) (xy 364.542226 -369.173391) (xy 364.593555 -369.195203) (xy 364.641161 -369.224257)
			(xy 364.684029 -369.259932) (xy 364.721246 -369.301469) (xy 364.752019 -369.347982) (xy 364.775691 -369.398479)
			(xy 364.791759 -369.451886) (xy 364.799879 -369.507062) (xy 364.800388 -369.534948) (xy 364.800249 -369.542568)
			(xy 365.489742 -369.542568) (xy 365.493813 -369.486946) (xy 365.505939 -369.432509) (xy 365.525862 -369.380418)
			(xy 365.553158 -369.331783) (xy 365.587244 -369.28764) (xy 365.627393 -369.248931) (xy 365.672751 -369.21648)
			(xy 365.722351 -369.190979) (xy 365.775135 -369.172972) (xy 365.829978 -369.162842) (xy 365.885712 -369.160805)
			(xy 365.941149 -369.166905) (xy 365.995106 -369.181011) (xy 366.046435 -369.202823) (xy 366.094041 -369.231877)
			(xy 366.136909 -369.267552) (xy 366.174126 -369.309089) (xy 366.204899 -369.355602) (xy 366.228571 -369.406099)
			(xy 366.244639 -369.459506) (xy 366.252759 -369.514682) (xy 366.253268 -369.542568) (xy 366.252759 -369.570454)
			(xy 366.244639 -369.62563) (xy 366.228571 -369.679037) (xy 366.204899 -369.729534) (xy 366.174126 -369.776047)
			(xy 366.136909 -369.817584) (xy 366.094041 -369.853259) (xy 366.046435 -369.882313) (xy 365.995106 -369.904125)
			(xy 365.941149 -369.918231) (xy 365.885712 -369.924331) (xy 365.829978 -369.922294) (xy 365.775135 -369.912164)
			(xy 365.722351 -369.894157) (xy 365.672751 -369.868656) (xy 365.627393 -369.836205) (xy 365.587244 -369.797496)
			(xy 365.553158 -369.753353) (xy 365.525862 -369.704718) (xy 365.505939 -369.652627) (xy 365.493813 -369.59819)
			(xy 365.489742 -369.542568) (xy 364.800249 -369.542568) (xy 364.799879 -369.562834) (xy 364.791759 -369.61801)
			(xy 364.775691 -369.671417) (xy 364.752019 -369.721914) (xy 364.721246 -369.768427) (xy 364.684029 -369.809964)
			(xy 364.641161 -369.845639) (xy 364.593555 -369.874693) (xy 364.542226 -369.896505) (xy 364.488269 -369.910611)
			(xy 364.432832 -369.916711) (xy 364.377098 -369.914674) (xy 364.322255 -369.904544) (xy 364.269471 -369.886537)
			(xy 364.219871 -369.861036) (xy 364.174513 -369.828585) (xy 364.134364 -369.789876) (xy 364.100278 -369.745733)
			(xy 364.072982 -369.697098) (xy 364.053059 -369.645007) (xy 364.040933 -369.59057) (xy 364.036862 -369.534948)
			(xy 347.060002 -369.534948) (xy 347.0584 -369.538303) (xy 347.053601 -369.565231) (xy 347.054424 -369.57889)
			(xy 347.055948 -369.613688) (xy 347.055458 -369.640943) (xy 347.047702 -369.694897) (xy 347.032346 -369.747198)
			(xy 347.009703 -369.796782) (xy 346.980234 -369.842638) (xy 346.944539 -369.883834) (xy 346.903344 -369.91953)
			(xy 346.857488 -369.949) (xy 346.807905 -369.971644) (xy 346.755604 -369.987001) (xy 346.701649 -369.994757)
			(xy 346.64714 -369.994757) (xy 346.593186 -369.986998) (xy 346.540885 -369.97164) (xy 346.491303 -369.948995)
			(xy 346.445448 -369.919524) (xy 346.404254 -369.883826) (xy 346.368559 -369.84263) (xy 346.339092 -369.796773)
			(xy 346.31645 -369.747188) (xy 346.301096 -369.694887) (xy 346.293341 -369.640932) (xy 334.933102 -369.640932)
			(xy 335.401158 -370.108988) (xy 347.338902 -370.108988) (xy 347.342973 -370.053366) (xy 347.355099 -369.998929)
			(xy 347.375022 -369.946838) (xy 347.402318 -369.898203) (xy 347.436404 -369.85406) (xy 347.476553 -369.815351)
			(xy 347.521911 -369.7829) (xy 347.571511 -369.757399) (xy 347.624295 -369.739392) (xy 347.679138 -369.729262)
			(xy 347.734872 -369.727225) (xy 347.790309 -369.733325) (xy 347.844266 -369.747431) (xy 347.895595 -369.769243)
			(xy 347.943201 -369.798297) (xy 347.986069 -369.833972) (xy 348.023286 -369.875509) (xy 348.054059 -369.922022)
			(xy 348.077731 -369.972519) (xy 348.093799 -370.025926) (xy 348.101919 -370.081102) (xy 348.102428 -370.108988)
			(xy 348.101919 -370.136874) (xy 348.093799 -370.19205) (xy 348.077731 -370.245457) (xy 348.054059 -370.295954)
			(xy 348.023286 -370.342467) (xy 347.986069 -370.384004) (xy 347.943201 -370.419679) (xy 347.895595 -370.448733)
			(xy 347.844266 -370.470545) (xy 347.790309 -370.484651) (xy 347.734872 -370.490751) (xy 347.679138 -370.488714)
			(xy 347.624295 -370.478584) (xy 347.571511 -370.460577) (xy 347.521911 -370.435076) (xy 347.476553 -370.402625)
			(xy 347.436404 -370.363916) (xy 347.402318 -370.319773) (xy 347.375022 -370.271138) (xy 347.355099 -370.219047)
			(xy 347.342973 -370.16461) (xy 347.338902 -370.108988) (xy 335.401158 -370.108988) (xy 336.227166 -370.934996)
			(xy 347.608396 -370.934996) (xy 347.612467 -370.879374) (xy 347.624593 -370.824937) (xy 347.644516 -370.772846)
			(xy 347.671812 -370.724211) (xy 347.705898 -370.680068) (xy 347.746047 -370.641359) (xy 347.791405 -370.608908)
			(xy 347.841005 -370.583407) (xy 347.893789 -370.5654) (xy 347.948632 -370.55527) (xy 348.004366 -370.553233)
			(xy 348.059803 -370.559333) (xy 348.11376 -370.573439) (xy 348.165089 -370.595251) (xy 348.212695 -370.624305)
			(xy 348.255563 -370.65998) (xy 348.29278 -370.701517) (xy 348.323553 -370.74803) (xy 348.347225 -370.798527)
			(xy 348.363293 -370.851934) (xy 348.371413 -370.90711) (xy 348.371922 -370.934996) (xy 348.371413 -370.962882)
			(xy 348.363293 -371.018058) (xy 348.347225 -371.071465) (xy 348.323553 -371.121962) (xy 348.29278 -371.168475)
			(xy 348.255563 -371.210012) (xy 348.212695 -371.245687) (xy 348.165089 -371.274741) (xy 348.11376 -371.296553)
			(xy 348.059803 -371.310659) (xy 348.004366 -371.316759) (xy 347.948632 -371.314722) (xy 347.893789 -371.304592)
			(xy 347.841005 -371.286585) (xy 347.791405 -371.261084) (xy 347.746047 -371.228633) (xy 347.705898 -371.189924)
			(xy 347.671812 -371.145781) (xy 347.644516 -371.097146) (xy 347.624593 -371.045055) (xy 347.612467 -370.990618)
			(xy 347.608396 -370.934996) (xy 336.227166 -370.934996) (xy 342.802718 -377.510548) (xy 374.882156 -377.510548)
		)
		(stroke
			(width 0)
			(type solid)
		)
		(fill yes)
		(layer "In2.Cu")
		(net "GND")
	)
	(gr_poly
		(pts
			(xy 57.484264 -324.11797) (xy 57.509231 -324.083161) (xy 57.5643 -324.017536) (xy 57.594246 -323.986906)
			(xy 57.683146 -323.89826) (xy 57.693613 -323.886987) (xy 57.707834 -323.859727) (xy 57.713309 -323.829471)
			(xy 57.709541 -323.798955) (xy 57.696872 -323.77094) (xy 57.676447 -323.747957) (xy 57.663588 -323.73951)
			(xy 57.643197 -323.726728) (xy 57.605729 -323.696527) (xy 57.588912 -323.679312) (xy 57.578343 -323.668903)
			(xy 57.552624 -323.654152) (xy 57.523751 -323.647408) (xy 57.494158 -323.649241) (xy 57.466337 -323.659495)
			(xy 57.442634 -323.677306) (xy 57.433464 -323.688964) (xy 57.416555 -323.711034) (xy 57.377041 -323.750143)
			(xy 57.331931 -323.782638) (xy 57.28232 -323.80773) (xy 57.229413 -323.82481) (xy 57.174496 -323.833462)
			(xy 57.146698 -323.833998) (xy 57.12005 -323.8335) (xy 57.067348 -323.825556) (xy 57.016419 -323.809847)
			(xy 56.9684 -323.786722) (xy 56.924364 -323.756698) (xy 56.885295 -323.720447) (xy 56.852065 -323.678778)
			(xy 56.825417 -323.632621) (xy 56.805945 -323.583009) (xy 56.794085 -323.531048) (xy 56.790102 -323.4779)
			(xy 56.794085 -323.424752) (xy 56.805945 -323.372791) (xy 56.825417 -323.323179) (xy 56.852065 -323.277022)
			(xy 56.885295 -323.235353) (xy 56.924364 -323.199102) (xy 56.9684 -323.169078) (xy 57.016419 -323.145953)
			(xy 57.067348 -323.130244) (xy 57.12005 -323.1223) (xy 57.146698 -323.121782) (xy 57.175654 -323.122349)
			(xy 57.232804 -323.13172) (xy 57.287685 -323.150214) (xy 57.338849 -323.177345) (xy 57.38495 -323.212397)
			(xy 57.40527 -323.233034) (xy 57.415841 -323.243442) (xy 57.441563 -323.258191) (xy 57.470438 -323.264936)
			(xy 57.500033 -323.263107) (xy 57.527857 -323.25286) (xy 57.551569 -323.235056) (xy 57.560718 -323.223382)
			(xy 57.577628 -323.201314) (xy 57.617144 -323.162208) (xy 57.662254 -323.129716) (xy 57.711865 -323.104625)
			(xy 57.76477 -323.087546) (xy 57.819687 -323.078892) (xy 57.847484 -323.078348) (xy 57.873656 -323.078809)
			(xy 57.925436 -323.086465) (xy 57.975538 -323.101617) (xy 58.022884 -323.123936) (xy 58.066454 -323.152943)
			(xy 58.105311 -323.188013) (xy 58.138618 -323.228392) (xy 58.152538 -323.25056) (xy 58.160911 -323.26348)
			(xy 58.183887 -323.28395) (xy 58.211921 -323.29664) (xy 58.242464 -323.300394) (xy 58.272737 -323.294873)
			(xy 58.299987 -323.280577) (xy 58.311288 -323.270118) (xy 59.684412 -321.896994) (xy 59.693883 -321.886871)
			(xy 59.707491 -321.862734) (xy 59.714096 -321.835823) (xy 59.713212 -321.808128) (xy 59.704902 -321.781694)
			(xy 59.689782 -321.758474) (xy 59.668968 -321.740183) (xy 59.656726 -321.733672) (xy 59.631311 -321.720749)
			(xy 59.584605 -321.688055) (xy 59.543707 -321.648336) (xy 59.509661 -321.602606) (xy 59.483337 -321.552035)
			(xy 59.46541 -321.497915) (xy 59.456336 -321.44163) (xy 59.455812 -321.413124) (xy 59.456331 -321.385138)
			(xy 59.465084 -321.329855) (xy 59.482378 -321.276621) (xy 59.507787 -321.226749) (xy 59.540686 -321.181467)
			(xy 59.580263 -321.141888) (xy 59.625546 -321.108989) (xy 59.675418 -321.083579) (xy 59.728651 -321.066285)
			(xy 59.783934 -321.057531) (xy 59.81192 -321.057016) (xy 59.839823 -321.05756) (xy 59.894947 -321.066267)
			(xy 59.948037 -321.083464) (xy 59.997797 -321.10873) (xy 60.043007 -321.141448) (xy 60.082561 -321.180816)
			(xy 60.115491 -321.225871) (xy 60.140991 -321.275511) (xy 60.158438 -321.32852) (xy 60.163456 -321.355974)
			(xy 60.166292 -321.370235) (xy 60.178833 -321.396453) (xy 60.198248 -321.418079) (xy 60.222967 -321.433364)
			(xy 60.250989 -321.441071) (xy 60.280047 -321.440578) (xy 60.307791 -321.431923) (xy 60.320174 -321.4243)
			(xy 61.851286 -320.400934) (xy 61.86208 -320.393197) (xy 61.87959 -320.373242) (xy 61.891359 -320.349445)
			(xy 61.89659 -320.323418) (xy 61.894929 -320.296922) (xy 61.886488 -320.271752) (xy 61.87948 -320.260472)
			(xy 61.865464 -320.238476) (xy 61.843325 -320.191252) (xy 61.828311 -320.141304) (xy 61.820743 -320.0897)
			(xy 61.820298 -320.063622) (xy 61.820817 -320.035636) (xy 61.82957 -319.980352) (xy 61.846864 -319.927118)
			(xy 61.872273 -319.877245) (xy 61.905172 -319.831961) (xy 61.944749 -319.792382) (xy 61.990031 -319.759481)
			(xy 62.039903 -319.73407) (xy 62.093136 -319.716774) (xy 62.14842 -319.708018) (xy 62.176406 -319.707514)
			(xy 62.2013 -319.70793) (xy 62.250602 -319.714866) (xy 62.298458 -319.728602) (xy 62.343933 -319.748871)
			(xy 62.386142 -319.775278) (xy 62.42426 -319.807306) (xy 62.457546 -319.844332) (xy 62.471808 -319.86474)
			(xy 62.479588 -319.875526) (xy 62.499625 -319.892997) (xy 62.523495 -319.904699) (xy 62.549577 -319.90984)
			(xy 62.576102 -319.908069) (xy 62.601269 -319.899507) (xy 62.612524 -319.892426) (xy 62.6491 -319.867788)
			(xy 62.648084 -319.83934) (xy 62.64783 -319.82537) (xy 62.648353 -319.797387) (xy 62.657113 -319.742112)
			(xy 62.674412 -319.688887) (xy 62.699824 -319.639023) (xy 62.732724 -319.593749) (xy 62.772301 -319.55418)
			(xy 62.817581 -319.521288) (xy 62.86745 -319.495885) (xy 62.920678 -319.478597) (xy 62.975955 -319.469847)
			(xy 63.003938 -319.469262) (xy 63.028373 -319.469668) (xy 63.076784 -319.476353) (xy 63.123827 -319.489594)
			(xy 63.168618 -319.50914) (xy 63.210317 -319.534626) (xy 63.22949 -319.54978) (xy 63.253112 -319.569084)
			(xy 64.026542 -319.24879) (xy 64.026542 -318.474344) (xy 64.026123 -318.461197) (xy 64.019392 -318.435778)
			(xy 64.006391 -318.412922) (xy 63.987984 -318.394145) (xy 63.96539 -318.380693) (xy 63.94011 -318.373459)
			(xy 63.926974 -318.372744) (xy 63.899277 -318.371709) (xy 63.844691 -318.36212) (xy 63.79225 -318.344191)
			(xy 63.743219 -318.318354) (xy 63.698783 -318.285233) (xy 63.660015 -318.245628) (xy 63.62785 -318.200495)
			(xy 63.603066 -318.150923) (xy 63.586261 -318.098111) (xy 63.577841 -318.043332) (xy 63.57747 -318.01562)
			(xy 63.57747 -317.964566) (xy 61.887354 -317.964566) (xy 61.355732 -318.496188) (xy 59.122564 -318.496188)
			(xy 59.109374 -318.49661) (xy 59.083878 -318.503381) (xy 59.06097 -318.516461) (xy 59.042179 -318.534976)
			(xy 59.028763 -318.557689) (xy 59.021616 -318.583082) (xy 59.020964 -318.596264) (xy 59.020054 -318.624553)
			(xy 59.010911 -318.680408) (xy 58.993617 -318.7343) (xy 58.968552 -318.785046) (xy 58.936266 -318.831532)
			(xy 58.897466 -318.872739) (xy 58.853005 -318.907761) (xy 58.803858 -318.935832) (xy 58.751103 -318.956334)
			(xy 58.695899 -318.968818) (xy 58.639456 -318.97301) (xy 58.583013 -318.968818) (xy 58.527809 -318.956334)
			(xy 58.475054 -318.935832) (xy 58.425907 -318.907761) (xy 58.381446 -318.872739) (xy 58.342646 -318.831532)
			(xy 58.31036 -318.785046) (xy 58.285295 -318.7343) (xy 58.268001 -318.680408) (xy 58.258858 -318.624553)
			(xy 58.257948 -318.596264) (xy 58.25733 -318.583082) (xy 58.25018 -318.557689) (xy 58.236756 -318.534979)
			(xy 58.217957 -318.516472) (xy 58.19504 -318.503405) (xy 58.169538 -318.496652) (xy 58.156348 -318.496188)
			(xy 56.768746 -318.496188) (xy 56.754764 -318.496635) (xy 56.727851 -318.504234) (xy 56.704008 -318.518848)
			(xy 56.685022 -318.539381) (xy 56.672318 -318.564294) (xy 56.666847 -318.591719) (xy 56.669019 -318.6196)
			(xy 56.678672 -318.645846) (xy 56.68645 -318.657478) (xy 56.702483 -318.68042) (xy 56.727904 -318.730283)
			(xy 56.745208 -318.78351) (xy 56.75397 -318.838789) (xy 56.754522 -318.866774) (xy 56.754024 -318.893423)
			(xy 56.746081 -318.946127) (xy 56.730371 -318.997057) (xy 56.707245 -319.045078) (xy 56.677221 -319.089115)
			(xy 56.640969 -319.128186) (xy 56.599298 -319.161417) (xy 56.55314 -319.188066) (xy 56.503526 -319.207538)
			(xy 56.451564 -319.219398) (xy 56.398414 -319.223382) (xy 56.345264 -319.219398) (xy 56.293302 -319.207538)
			(xy 56.243688 -319.188066) (xy 56.19753 -319.161417) (xy 56.155859 -319.128186) (xy 56.119607 -319.089115)
			(xy 56.089583 -319.045078) (xy 56.066457 -318.997057) (xy 56.050747 -318.946127) (xy 56.042804 -318.893423)
			(xy 56.042306 -318.866774) (xy 56.04283 -318.838789) (xy 56.0516 -318.78351) (xy 56.068919 -318.730287)
			(xy 56.09436 -318.680432) (xy 56.110378 -318.657478) (xy 56.118238 -318.645892) (xy 56.127906 -318.619627)
			(xy 56.130084 -318.591724) (xy 56.124608 -318.564277) (xy 56.11189 -318.539346) (xy 56.092883 -318.518802)
			(xy 56.069015 -318.504186) (xy 56.042076 -318.496596) (xy 56.028082 -318.496188) (xy 55.44439 -318.496188)
			(xy 54.705504 -319.235074) (xy 54.696183 -319.245006) (xy 54.682702 -319.268664) (xy 54.675957 -319.295045)
			(xy 54.676431 -319.32227) (xy 54.684087 -319.3484) (xy 54.698382 -319.371575) (xy 54.718297 -319.390144)
			(xy 54.730142 -319.396872) (xy 54.75448 -319.410177) (xy 54.799069 -319.443162) (xy 54.838002 -319.482664)
			(xy 54.870336 -319.527728) (xy 54.89529 -319.577261) (xy 54.912259 -319.630065) (xy 54.920832 -319.684862)
			(xy 54.921404 -319.712594) (xy 54.920906 -319.739243) (xy 54.912963 -319.791947) (xy 54.897253 -319.842877)
			(xy 54.874127 -319.890898) (xy 54.844103 -319.934935) (xy 54.807851 -319.974006) (xy 54.76618 -320.007237)
			(xy 54.720022 -320.033886) (xy 54.670408 -320.053358) (xy 54.618446 -320.065218) (xy 54.565296 -320.069202)
			(xy 54.512146 -320.065218) (xy 54.460184 -320.053358) (xy 54.41057 -320.033886) (xy 54.364412 -320.007237)
			(xy 54.322741 -319.974006) (xy 54.286489 -319.934935) (xy 54.256465 -319.890898) (xy 54.233339 -319.842877)
			(xy 54.217629 -319.791947) (xy 54.209686 -319.739243) (xy 54.209188 -319.712594) (xy 54.209631 -319.687867)
			(xy 54.216504 -319.638893) (xy 54.230077 -319.591337) (xy 54.250089 -319.546113) (xy 54.262782 -319.524888)
			(xy 54.26956 -319.513173) (xy 54.277293 -319.487245) (xy 54.277941 -319.460197) (xy 54.271457 -319.433929)
			(xy 54.258299 -319.410289) (xy 54.23939 -319.390937) (xy 54.216061 -319.377234) (xy 54.18995 -319.370144)
			(xy 54.176422 -319.369694) (xy 51.55946 -319.369694) (xy 51.545474 -319.370138) (xy 51.518553 -319.37773)
			(xy 51.494697 -319.392335) (xy 51.475692 -319.412859) (xy 51.462962 -319.437766) (xy 51.45746 -319.465191)
			(xy 51.458114 -319.479168) (xy 51.45913 -319.5066) (xy 51.458632 -319.533249) (xy 51.450689 -319.585953)
			(xy 51.434979 -319.636883) (xy 51.411853 -319.684904) (xy 51.381829 -319.728941) (xy 51.345577 -319.768012)
			(xy 51.303906 -319.801243) (xy 51.257748 -319.827892) (xy 51.208134 -319.847364) (xy 51.156172 -319.859224)
			(xy 51.103022 -319.863208) (xy 51.049872 -319.859224) (xy 50.99791 -319.847364) (xy 50.948296 -319.827892)
			(xy 50.902138 -319.801243) (xy 50.860467 -319.768012) (xy 50.824215 -319.728941) (xy 50.794191 -319.684904)
			(xy 50.771065 -319.636883) (xy 50.755355 -319.585953) (xy 50.747412 -319.533249) (xy 50.746914 -319.5066)
			(xy 50.74793 -319.479168) (xy 50.748574 -319.465191) (xy 50.74309 -319.437765) (xy 50.730367 -319.412858)
			(xy 50.71136 -319.392339) (xy 50.687497 -319.377751) (xy 50.660569 -319.370189) (xy 50.646584 -319.369694)
			(xy 49.240948 -319.369694) (xy 49.227382 -319.370156) (xy 49.201225 -319.377369) (xy 49.177891 -319.391218)
			(xy 49.159031 -319.410725) (xy 49.145975 -319.434512) (xy 49.139648 -319.460897) (xy 49.140494 -319.488018)
			(xy 49.148456 -319.513957) (xy 49.15535 -319.52565) (xy 49.168485 -319.547168) (xy 49.189217 -319.593119)
			(xy 49.203256 -319.641537) (xy 49.210321 -319.691452) (xy 49.210722 -319.716658) (xy 49.210224 -319.743307)
			(xy 49.202281 -319.796011) (xy 49.186571 -319.846941) (xy 49.163445 -319.894962) (xy 49.133421 -319.938999)
			(xy 49.097169 -319.97807) (xy 49.055498 -320.011301) (xy 49.00934 -320.03795) (xy 48.959726 -320.057422)
			(xy 48.907764 -320.069282) (xy 48.854614 -320.073266) (xy 48.801464 -320.069282) (xy 48.749502 -320.057422)
			(xy 48.699888 -320.03795) (xy 48.65373 -320.011301) (xy 48.612059 -319.97807) (xy 48.575807 -319.938999)
			(xy 48.545783 -319.894962) (xy 48.522657 -319.846941) (xy 48.506947 -319.796011) (xy 48.499004 -319.743307)
			(xy 48.498506 -319.716658) (xy 48.498924 -319.691452) (xy 48.505991 -319.641539) (xy 48.520022 -319.59312)
			(xy 48.540735 -319.547162) (xy 48.553878 -319.52565) (xy 48.560772 -319.513957) (xy 48.568732 -319.488015)
			(xy 48.569577 -319.460893) (xy 48.563249 -319.434506) (xy 48.550195 -319.410718) (xy 48.531336 -319.391207)
			(xy 48.508004 -319.377353) (xy 48.481846 -319.370134) (xy 48.46828 -319.369694) (xy 47.330868 -319.369694)
			(xy 47.316658 -319.370157) (xy 47.289336 -319.377977) (xy 47.265231 -319.393031) (xy 47.246213 -319.414149)
			(xy 47.233758 -319.439694) (xy 47.228833 -319.467683) (xy 47.231818 -319.495946) (xy 47.242484 -319.522288)
			(xy 47.250858 -319.533778) (xy 47.268626 -319.557431) (xy 47.296889 -319.609398) (xy 47.316182 -319.665318)
			(xy 47.325977 -319.723657) (xy 47.32655 -319.753234) (xy 47.326052 -319.779883) (xy 47.318109 -319.832587)
			(xy 47.302399 -319.883517) (xy 47.279273 -319.931538) (xy 47.249249 -319.975575) (xy 47.212997 -320.014646)
			(xy 47.171326 -320.047877) (xy 47.125168 -320.074526) (xy 47.075554 -320.093998) (xy 47.023592 -320.105858)
			(xy 46.970442 -320.109842) (xy 46.917292 -320.105858) (xy 46.86533 -320.093998) (xy 46.815716 -320.074526)
			(xy 46.769558 -320.047877) (xy 46.727887 -320.014646) (xy 46.691635 -319.975575) (xy 46.661611 -319.931538)
			(xy 46.638485 -319.883517) (xy 46.622775 -319.832587) (xy 46.614832 -319.779883) (xy 46.614334 -319.753234)
			(xy 46.614917 -319.723656) (xy 46.624693 -319.665314) (xy 46.643982 -319.609391) (xy 46.672253 -319.557428)
			(xy 46.690026 -319.533778) (xy 46.698388 -319.522291) (xy 46.709008 -319.495951) (xy 46.711965 -319.467705)
			(xy 46.707028 -319.439737) (xy 46.694581 -319.41421) (xy 46.675585 -319.393097) (xy 46.651509 -319.378033)
			(xy 46.624216 -319.37018) (xy 46.610016 -319.369694) (xy 45.40631 -319.369694) (xy 44.59605 -318.559434)
			(xy 44.000166 -318.559434) (xy 43.985214 -318.559953) (xy 43.956589 -318.568603) (xy 43.931701 -318.58518)
			(xy 43.912687 -318.60826) (xy 43.901181 -318.635861) (xy 43.89817 -318.665612) (xy 43.903913 -318.694958)
			(xy 43.917917 -318.72138) (xy 43.92803 -318.732408) (xy 43.947139 -318.752541) (xy 43.979513 -318.797625)
			(xy 44.004509 -318.847182) (xy 44.021521 -318.900015) (xy 44.03014 -318.954846) (xy 44.030646 -318.982598)
			(xy 44.030148 -319.009247) (xy 44.022205 -319.061951) (xy 44.006495 -319.112881) (xy 43.983369 -319.160902)
			(xy 43.953345 -319.204939) (xy 43.917093 -319.24401) (xy 43.875422 -319.277241) (xy 43.829264 -319.30389)
			(xy 43.77965 -319.323362) (xy 43.727688 -319.335222) (xy 43.674538 -319.339206) (xy 43.621388 -319.335222)
			(xy 43.569426 -319.323362) (xy 43.519812 -319.30389) (xy 43.473654 -319.277241) (xy 43.431983 -319.24401)
			(xy 43.395731 -319.204939) (xy 43.365707 -319.160902) (xy 43.342581 -319.112881) (xy 43.326871 -319.061951)
			(xy 43.318928 -319.009247) (xy 43.31843 -318.982598) (xy 43.31896 -318.954847) (xy 43.327567 -318.900016)
			(xy 43.344574 -318.847183) (xy 43.369567 -318.797626) (xy 43.401943 -318.752545) (xy 43.421046 -318.732408)
			(xy 43.431178 -318.721409) (xy 43.445138 -318.694978) (xy 43.450849 -318.665638) (xy 43.447822 -318.635901)
			(xy 43.436318 -318.608312) (xy 43.417321 -318.585235) (xy 43.392457 -318.568645) (xy 43.363855 -318.559961)
			(xy 43.34891 -318.559434) (xy 41.719754 -318.559434) (xy 41.704918 -318.559906) (xy 41.676478 -318.568363)
			(xy 41.651669 -318.584635) (xy 41.632584 -318.607352) (xy 41.620832 -318.634595) (xy 41.617406 -318.664067)
			(xy 41.622595 -318.69328) (xy 41.628822 -318.706754) (xy 41.640812 -318.731709) (xy 41.657777 -318.784406)
			(xy 41.666381 -318.839094) (xy 41.666922 -318.866774) (xy 41.666424 -318.893423) (xy 41.658481 -318.946127)
			(xy 41.642771 -318.997057) (xy 41.619645 -319.045078) (xy 41.589621 -319.089115) (xy 41.553369 -319.128186)
			(xy 41.511698 -319.161417) (xy 41.46554 -319.188066) (xy 41.415926 -319.207538) (xy 41.363964 -319.219398)
			(xy 41.310814 -319.223382) (xy 41.257664 -319.219398) (xy 41.205702 -319.207538) (xy 41.156088 -319.188066)
			(xy 41.10993 -319.161417) (xy 41.068259 -319.128186) (xy 41.032007 -319.089115) (xy 41.001983 -319.045078)
			(xy 40.978857 -318.997057) (xy 40.963147 -318.946127) (xy 40.955204 -318.893423) (xy 40.954706 -318.866774)
			(xy 40.955249 -318.839094) (xy 40.963849 -318.784404) (xy 40.980807 -318.731704) (xy 40.992806 -318.706754)
			(xy 40.999033 -318.693279) (xy 41.00422 -318.664064) (xy 41.000794 -318.63459) (xy 40.989043 -318.607345)
			(xy 40.969958 -318.584625) (xy 40.94515 -318.568347) (xy 40.916711 -318.559884) (xy 40.901874 -318.559434)
			(xy 40.836342 -318.559434) (xy 40.593518 -318.31661) (xy 40.58031 -318.313054) (xy 40.554773 -318.305663)
			(xy 40.50607 -318.284356) (xy 40.461073 -318.256048) (xy 40.420783 -318.221367) (xy 40.386095 -318.181084)
			(xy 40.357778 -318.136093) (xy 40.336461 -318.087394) (xy 40.329104 -318.061848) (xy 40.325548 -318.04864)
			(xy 39.685722 -317.408814) (xy 39.650162 -317.43904) (xy 39.630803 -317.454804) (xy 39.588508 -317.481328)
			(xy 39.542924 -317.501687) (xy 39.494944 -317.515483) (xy 39.445508 -317.522446) (xy 39.420546 -317.52286)
			(xy 39.393896 -317.52239) (xy 39.341191 -317.514452) (xy 39.290258 -317.498748) (xy 39.242235 -317.475626)
			(xy 39.198194 -317.445605) (xy 39.15912 -317.409355) (xy 39.125886 -317.367685) (xy 39.099235 -317.321528)
			(xy 39.079761 -317.271913) (xy 39.067899 -317.21995) (xy 39.063916 -317.1668) (xy 39.067899 -317.11365)
			(xy 39.079761 -317.061687) (xy 39.099235 -317.012072) (xy 39.125886 -316.965915) (xy 39.15912 -316.924245)
			(xy 39.198194 -316.887995) (xy 39.242235 -316.857974) (xy 39.290258 -316.834852) (xy 39.341191 -316.819148)
			(xy 39.393896 -316.81121) (xy 39.420546 -316.810644) (xy 39.454836 -316.812168) (xy 39.468946 -316.813054)
			(xy 39.496739 -316.80793) (xy 39.522063 -316.795388) (xy 39.542983 -316.776386) (xy 39.557895 -316.75238)
			(xy 39.565658 -316.725206) (xy 39.566088 -316.711076) (xy 39.566088 -315.922406) (xy 39.565628 -315.908279)
			(xy 39.55788 -315.881109) (xy 39.542976 -315.857107) (xy 39.52206 -315.838113) (xy 39.496737 -315.825584)
			(xy 39.468948 -315.820483) (xy 39.454836 -315.821314) (xy 39.420546 -315.822838) (xy 39.39389 -315.822368)
			(xy 39.341174 -315.814429) (xy 39.290229 -315.79872) (xy 39.242196 -315.775594) (xy 39.198145 -315.745566)
			(xy 39.159063 -315.709308) (xy 39.125822 -315.667629) (xy 39.099164 -315.621462) (xy 39.079686 -315.571836)
			(xy 39.067822 -315.519862) (xy 39.063838 -315.4667) (xy 39.067822 -315.413538) (xy 39.079686 -315.361564)
			(xy 39.099164 -315.311938) (xy 39.125822 -315.265771) (xy 39.159063 -315.224092) (xy 39.198145 -315.187834)
			(xy 39.242196 -315.157806) (xy 39.290229 -315.13468) (xy 39.341174 -315.118971) (xy 39.39389 -315.111032)
			(xy 39.420546 -315.110622) (xy 39.454836 -315.112146) (xy 39.468945 -315.113032) (xy 39.496735 -315.107908)
			(xy 39.522058 -315.095365) (xy 39.542973 -315.076363) (xy 39.557881 -315.052356) (xy 39.565639 -315.025183)
			(xy 39.566088 -315.011054) (xy 39.566088 -314.222384) (xy 39.565625 -314.208259) (xy 39.557873 -314.181095)
			(xy 39.542969 -314.157098) (xy 39.522054 -314.138108) (xy 39.496733 -314.125583) (xy 39.468948 -314.120483)
			(xy 39.454836 -314.121292) (xy 39.420546 -314.122816) (xy 39.393892 -314.122346) (xy 39.341179 -314.114407)
			(xy 39.290237 -314.0987) (xy 39.242207 -314.075575) (xy 39.198159 -314.045549) (xy 39.159079 -314.009293)
			(xy 39.12584 -313.967617) (xy 39.099184 -313.921452) (xy 39.079707 -313.87183) (xy 39.067844 -313.819859)
			(xy 39.06386 -313.7667) (xy 39.067844 -313.713541) (xy 39.079707 -313.66157) (xy 39.099184 -313.611948)
			(xy 39.12584 -313.565783) (xy 39.159079 -313.524107) (xy 39.198159 -313.487851) (xy 39.242207 -313.457825)
			(xy 39.290237 -313.4347) (xy 39.341179 -313.418993) (xy 39.393892 -313.411054) (xy 39.420546 -313.4106)
			(xy 39.454836 -313.412124) (xy 39.468944 -313.41301) (xy 39.496732 -313.407886) (xy 39.522052 -313.395342)
			(xy 39.542964 -313.376339) (xy 39.557868 -313.352332) (xy 39.565621 -313.32516) (xy 39.566088 -313.311032)
			(xy 39.566088 -311.672478) (xy 39.565637 -311.658344) (xy 39.557901 -311.631157) (xy 39.543001 -311.607137)
			(xy 39.522082 -311.588127) (xy 39.496749 -311.575588) (xy 39.468948 -311.570483) (xy 39.454836 -311.571386)
			(xy 39.420546 -311.57291) (xy 39.393892 -311.57244) (xy 39.34118 -311.564501) (xy 39.29024 -311.548794)
			(xy 39.24221 -311.525669) (xy 39.198163 -311.495644) (xy 39.159084 -311.459389) (xy 39.125845 -311.417714)
			(xy 39.09919 -311.37155) (xy 39.079713 -311.321928) (xy 39.06785 -311.269958) (xy 39.063866 -311.2168)
			(xy 39.06785 -311.163642) (xy 39.079713 -311.111672) (xy 39.09919 -311.06205) (xy 39.125845 -311.015886)
			(xy 39.159084 -310.974211) (xy 39.198163 -310.937956) (xy 39.24221 -310.907931) (xy 39.29024 -310.884806)
			(xy 39.34118 -310.869099) (xy 39.393892 -310.86116) (xy 39.420546 -310.860694) (xy 39.454836 -310.862218)
			(xy 39.468948 -310.863104) (xy 39.496746 -310.857981) (xy 39.522077 -310.845439) (xy 39.543004 -310.826439)
			(xy 39.557926 -310.802433) (xy 39.565702 -310.775258) (xy 39.566088 -310.761126) (xy 39.566088 -309.972456)
			(xy 39.565634 -309.958325) (xy 39.557895 -309.931143) (xy 39.542994 -309.907128) (xy 39.522075 -309.888123)
			(xy 39.496745 -309.875587) (xy 39.468948 -309.870483) (xy 39.454836 -309.871364) (xy 39.420546 -309.872888)
			(xy 39.393894 -309.872418) (xy 39.341185 -309.86448) (xy 39.290248 -309.848774) (xy 39.242221 -309.82565)
			(xy 39.198177 -309.795627) (xy 39.1591 -309.759374) (xy 39.125863 -309.717701) (xy 39.099209 -309.67154)
			(xy 39.079734 -309.621922) (xy 39.067872 -309.569955) (xy 39.063888 -309.5168) (xy 39.067872 -309.463645)
			(xy 39.079734 -309.411678) (xy 39.099209 -309.36206) (xy 39.125863 -309.315899) (xy 39.1591 -309.274226)
			(xy 39.198177 -309.237973) (xy 39.242221 -309.20795) (xy 39.290248 -309.184826) (xy 39.341185 -309.16912)
			(xy 39.393894 -309.161182) (xy 39.420546 -309.160672) (xy 39.454836 -309.162196) (xy 39.468947 -309.163082)
			(xy 39.496743 -309.157958) (xy 39.522071 -309.145416) (xy 39.542994 -309.126416) (xy 39.557912 -309.10241)
			(xy 39.565682 -309.075235) (xy 39.566088 -309.061104) (xy 39.566088 -308.272434) (xy 39.565631 -308.258305)
			(xy 39.557888 -308.231128) (xy 39.542986 -308.207118) (xy 39.522069 -308.188118) (xy 39.496742 -308.175586)
			(xy 39.468948 -308.170483) (xy 39.454836 -308.171342) (xy 39.420546 -308.172866) (xy 39.393896 -308.172396)
			(xy 39.34119 -308.164458) (xy 39.290256 -308.148753) (xy 39.242232 -308.125631) (xy 39.19819 -308.09561)
			(xy 39.159116 -308.059359) (xy 39.125881 -308.017689) (xy 39.099229 -307.97153) (xy 39.079755 -307.921915)
			(xy 39.067893 -307.869951) (xy 39.06391 -307.8168) (xy 39.067893 -307.763649) (xy 39.079755 -307.711685)
			(xy 39.099229 -307.66207) (xy 39.125881 -307.615911) (xy 39.159116 -307.574241) (xy 39.19819 -307.53799)
			(xy 39.242232 -307.507969) (xy 39.290256 -307.484847) (xy 39.34119 -307.469142) (xy 39.393896 -307.461204)
			(xy 39.420546 -307.46065) (xy 39.454836 -307.462174) (xy 39.468946 -307.46306) (xy 39.496739 -307.457936)
			(xy 39.522065 -307.445394) (xy 39.542985 -307.426392) (xy 39.557898 -307.402386) (xy 39.565664 -307.375212)
			(xy 39.566088 -307.361082) (xy 39.566088 -306.572412) (xy 39.565629 -306.558285) (xy 39.557882 -306.531113)
			(xy 39.542978 -306.507109) (xy 39.522062 -306.488114) (xy 39.496738 -306.475585) (xy 39.468948 -306.470483)
			(xy 39.454836 -306.47132) (xy 39.420546 -306.472844) (xy 39.39389 -306.472374) (xy 39.341172 -306.464434)
			(xy 39.290227 -306.448726) (xy 39.242193 -306.425599) (xy 39.198142 -306.395571) (xy 39.159059 -306.359312)
			(xy 39.125817 -306.317633) (xy 39.099159 -306.271464) (xy 39.07968 -306.221838) (xy 39.067816 -306.169863)
			(xy 39.063832 -306.1167) (xy 39.067816 -306.063537) (xy 39.07968 -306.011562) (xy 39.099159 -305.961936)
			(xy 39.125817 -305.915767) (xy 39.159059 -305.874088) (xy 39.198142 -305.837829) (xy 39.242193 -305.807801)
			(xy 39.290227 -305.784674) (xy 39.341172 -305.768966) (xy 39.39389 -305.761026) (xy 39.420546 -305.760628)
			(xy 39.454836 -305.762152) (xy 39.468945 -305.763038) (xy 39.496736 -305.757914) (xy 39.522059 -305.745371)
			(xy 39.542976 -305.726369) (xy 39.557885 -305.702362) (xy 39.565645 -305.675189) (xy 39.566088 -305.66106)
			(xy 39.566088 -304.87239) (xy 39.565626 -304.858265) (xy 39.557875 -304.831099) (xy 39.542971 -304.8071)
			(xy 39.522056 -304.788109) (xy 39.496734 -304.775583) (xy 39.468948 -304.770483) (xy 39.454836 -304.771298)
			(xy 39.420546 -304.772822) (xy 39.393892 -304.772352) (xy 39.341177 -304.764413) (xy 39.290235 -304.748705)
			(xy 39.242204 -304.72558) (xy 39.198155 -304.695553) (xy 39.159075 -304.659297) (xy 39.125835 -304.61762)
			(xy 39.099179 -304.571455) (xy 39.079701 -304.521832) (xy 39.067838 -304.46986) (xy 39.063854 -304.4167)
			(xy 39.067838 -304.36354) (xy 39.079701 -304.311568) (xy 39.099179 -304.261945) (xy 39.125835 -304.21578)
			(xy 39.159075 -304.174103) (xy 39.198155 -304.137847) (xy 39.242204 -304.10782) (xy 39.290235 -304.084695)
			(xy 39.341177 -304.068987) (xy 39.393892 -304.061048) (xy 39.420546 -304.060606) (xy 39.454836 -304.06213)
			(xy 39.468944 -304.063016) (xy 39.496733 -304.057892) (xy 39.522054 -304.045349) (xy 39.542967 -304.026346)
			(xy 39.557871 -304.002339) (xy 39.565626 -303.975166) (xy 39.566088 -303.961038) (xy 39.566088 -302.322484)
			(xy 39.565625 -302.308359) (xy 39.557873 -302.281195) (xy 39.542969 -302.257198) (xy 39.522054 -302.238208)
			(xy 39.496733 -302.225683) (xy 39.468948 -302.220583) (xy 39.454836 -302.221392) (xy 39.420546 -302.222916)
			(xy 39.393892 -302.222446) (xy 39.341179 -302.214507) (xy 39.290237 -302.1988) (xy 39.242207 -302.175675)
			(xy 39.198159 -302.145649) (xy 39.159079 -302.109393) (xy 39.12584 -302.067717) (xy 39.099184 -302.021552)
			(xy 39.079707 -301.97193) (xy 39.067844 -301.919959) (xy 39.06386 -301.8668) (xy 39.067844 -301.813641)
			(xy 39.079707 -301.76167) (xy 39.099184 -301.712048) (xy 39.12584 -301.665883) (xy 39.159079 -301.624207)
			(xy 39.198159 -301.587951) (xy 39.242207 -301.557925) (xy 39.290237 -301.5348) (xy 39.341179 -301.519093)
			(xy 39.393892 -301.511154) (xy 39.420546 -301.5107) (xy 39.454836 -301.512224) (xy 39.468944 -301.51311)
			(xy 39.496732 -301.507986) (xy 39.522052 -301.495442) (xy 39.542964 -301.476439) (xy 39.557868 -301.452432)
			(xy 39.565621 -301.42526) (xy 39.566088 -301.411132) (xy 39.566088 -300.622462) (xy 39.565635 -300.60833)
			(xy 39.557896 -300.581147) (xy 39.542996 -300.55713) (xy 39.522077 -300.538124) (xy 39.496746 -300.525588)
			(xy 39.468948 -300.520483) (xy 39.454836 -300.52137) (xy 39.420546 -300.522894) (xy 39.393894 -300.522424)
			(xy 39.341184 -300.514486) (xy 39.290245 -300.498779) (xy 39.242218 -300.475656) (xy 39.198173 -300.445632)
			(xy 39.159095 -300.409378) (xy 39.125858 -300.367705) (xy 39.099204 -300.321543) (xy 39.079728 -300.271923)
			(xy 39.067866 -300.219955) (xy 39.063882 -300.1668) (xy 39.067866 -300.113645) (xy 39.079728 -300.061677)
			(xy 39.099204 -300.012057) (xy 39.125858 -299.965895) (xy 39.159095 -299.924222) (xy 39.198173 -299.887968)
			(xy 39.242218 -299.857944) (xy 39.290245 -299.834821) (xy 39.341184 -299.819114) (xy 39.393894 -299.811176)
			(xy 39.420546 -299.810678) (xy 39.454836 -299.812202) (xy 39.468948 -299.813088) (xy 39.496743 -299.807964)
			(xy 39.522072 -299.795423) (xy 39.542997 -299.776422) (xy 39.557916 -299.752416) (xy 39.565688 -299.725242)
			(xy 39.566088 -299.71111) (xy 39.566088 -298.92244) (xy 39.565632 -298.90831) (xy 39.55789 -298.881132)
			(xy 39.542988 -298.857121) (xy 39.522071 -298.83812) (xy 39.496743 -298.825586) (xy 39.468948 -298.820483)
			(xy 39.454836 -298.821348) (xy 39.420546 -298.822872) (xy 39.393895 -298.822402) (xy 39.341188 -298.814464)
			(xy 39.290254 -298.798759) (xy 39.242229 -298.775637) (xy 39.198187 -298.745614) (xy 39.159112 -298.709363)
			(xy 39.125876 -298.667692) (xy 39.099224 -298.621533) (xy 39.079749 -298.571917) (xy 39.067888 -298.519952)
			(xy 39.063904 -298.4668) (xy 39.067888 -298.413648) (xy 39.079749 -298.361683) (xy 39.099224 -298.312067)
			(xy 39.125876 -298.265908) (xy 39.159112 -298.224237) (xy 39.198187 -298.187986) (xy 39.242229 -298.157963)
			(xy 39.290254 -298.134841) (xy 39.341188 -298.119136) (xy 39.393895 -298.111198) (xy 39.420546 -298.110656)
			(xy 39.454836 -298.11218) (xy 39.468947 -298.113066) (xy 39.49674 -298.107942) (xy 39.522067 -298.0954)
			(xy 39.542988 -298.076399) (xy 39.557902 -298.052392) (xy 39.565669 -298.025219) (xy 39.566088 -298.011088)
			(xy 39.566088 -297.222418) (xy 39.565629 -297.20829) (xy 39.557883 -297.181117) (xy 39.54298 -297.157112)
			(xy 39.522064 -297.138115) (xy 39.496739 -297.125585) (xy 39.468948 -297.120483) (xy 39.454836 -297.121326)
			(xy 39.420546 -297.12285) (xy 39.393889 -297.12238) (xy 39.341171 -297.11444) (xy 39.290225 -297.098731)
			(xy 39.24219 -297.075604) (xy 39.198138 -297.045575) (xy 39.159054 -297.009316) (xy 39.125812 -296.967636)
			(xy 39.099154 -296.921467) (xy 39.079675 -296.87184) (xy 39.06781 -296.819864) (xy 39.063826 -296.7667)
			(xy 39.06781 -296.713536) (xy 39.079675 -296.66156) (xy 39.099154 -296.611933) (xy 39.125812 -296.565764)
			(xy 39.159054 -296.524084) (xy 39.198138 -296.487825) (xy 39.24219 -296.457796) (xy 39.290225 -296.434669)
			(xy 39.341171 -296.41896) (xy 39.393889 -296.41102) (xy 39.420546 -296.410634) (xy 39.454836 -296.412158)
			(xy 39.468946 -296.413044) (xy 39.496737 -296.40792) (xy 39.522061 -296.395377) (xy 39.542978 -296.376375)
			(xy 39.557889 -296.352369) (xy 39.56565 -296.325196) (xy 39.566088 -296.311066) (xy 39.566088 -295.522396)
			(xy 39.565627 -295.50827) (xy 39.557877 -295.481103) (xy 39.542973 -295.457103) (xy 39.522057 -295.438111)
			(xy 39.496735 -295.425584) (xy 39.468948 -295.420483) (xy 39.454836 -295.421304) (xy 39.420546 -295.422828)
			(xy 39.393891 -295.422358) (xy 39.341176 -295.414419) (xy 39.290233 -295.398711) (xy 39.242201 -295.375585)
			(xy 39.198152 -295.345558) (xy 39.159071 -295.309301) (xy 39.12583 -295.267624) (xy 39.099173 -295.221457)
			(xy 39.079696 -295.171833) (xy 39.067832 -295.119861) (xy 39.063848 -295.0667) (xy 39.067832 -295.013539)
			(xy 39.079696 -294.961567) (xy 39.099173 -294.911943) (xy 39.12583 -294.865776) (xy 39.159071 -294.824099)
			(xy 39.198152 -294.787842) (xy 39.242201 -294.757815) (xy 39.290233 -294.734689) (xy 39.341176 -294.718981)
			(xy 39.393891 -294.711042) (xy 39.420546 -294.710612) (xy 39.454836 -294.712136) (xy 39.468945 -294.713022)
			(xy 39.496734 -294.707898) (xy 39.522055 -294.695355) (xy 39.542969 -294.676352) (xy 39.557875 -294.652345)
			(xy 39.565631 -294.625173) (xy 39.566088 -294.611044) (xy 39.566088 -292.97249) (xy 39.565626 -292.958365)
			(xy 39.557875 -292.931199) (xy 39.542971 -292.9072) (xy 39.522056 -292.888209) (xy 39.496734 -292.875683)
			(xy 39.468948 -292.870583) (xy 39.454836 -292.871398) (xy 39.420546 -292.872922) (xy 39.393892 -292.872452)
			(xy 39.341177 -292.864513) (xy 39.290235 -292.848805) (xy 39.242204 -292.82568) (xy 39.198155 -292.795653)
			(xy 39.159075 -292.759397) (xy 39.125835 -292.71772) (xy 39.099179 -292.671555) (xy 39.079701 -292.621932)
			(xy 39.067838 -292.56996) (xy 39.063854 -292.5168) (xy 39.067838 -292.46364) (xy 39.079701 -292.411668)
			(xy 39.099179 -292.362045) (xy 39.125835 -292.31588) (xy 39.159075 -292.274203) (xy 39.198155 -292.237947)
			(xy 39.242204 -292.20792) (xy 39.290235 -292.184795) (xy 39.341177 -292.169087) (xy 39.393892 -292.161148)
			(xy 39.420546 -292.160706) (xy 39.454836 -292.16223) (xy 39.468944 -292.163116) (xy 39.496733 -292.157992)
			(xy 39.522054 -292.145449) (xy 39.542967 -292.126446) (xy 39.557871 -292.102439) (xy 39.565626 -292.075266)
			(xy 39.566088 -292.061138) (xy 39.566088 -291.272468) (xy 39.565636 -291.258335) (xy 39.557898 -291.231151)
			(xy 39.542998 -291.207133) (xy 39.522079 -291.188125) (xy 39.496747 -291.175588) (xy 39.468948 -291.170483)
			(xy 39.454836 -291.171376) (xy 39.420546 -291.1729) (xy 39.393893 -291.17243) (xy 39.341182 -291.164491)
			(xy 39.290243 -291.148785) (xy 39.242215 -291.125661) (xy 39.198169 -291.095636) (xy 39.159091 -291.059382)
			(xy 39.125853 -291.017708) (xy 39.099199 -290.971545) (xy 39.079722 -290.921925) (xy 39.06786 -290.869956)
			(xy 39.063876 -290.8168) (xy 39.06786 -290.763644) (xy 39.079722 -290.711675) (xy 39.099199 -290.662055)
			(xy 39.125853 -290.615892) (xy 39.159091 -290.574218) (xy 39.198169 -290.537964) (xy 39.242215 -290.507939)
			(xy 39.290243 -290.484815) (xy 39.341182 -290.469109) (xy 39.393893 -290.46117) (xy 39.420546 -290.460684)
			(xy 39.454836 -290.462208) (xy 39.468948 -290.463094) (xy 39.496744 -290.45797) (xy 39.522074 -290.445429)
			(xy 39.542999 -290.426428) (xy 39.557919 -290.402422) (xy 39.565693 -290.375248) (xy 39.566088 -290.361116)
			(xy 39.566088 -289.572446) (xy 39.565633 -289.558316) (xy 39.557892 -289.531136) (xy 39.54299 -289.507124)
			(xy 39.522072 -289.488121) (xy 39.496744 -289.475587) (xy 39.468948 -289.470483) (xy 39.454836 -289.471354)
			(xy 39.420546 -289.472878) (xy 39.393895 -289.472408) (xy 39.341187 -289.46447) (xy 39.290251 -289.448764)
			(xy 39.242226 -289.425642) (xy 39.198183 -289.395619) (xy 39.159107 -289.359367) (xy 39.125871 -289.317696)
			(xy 39.099218 -289.271536) (xy 39.079743 -289.221919) (xy 39.067882 -289.169953) (xy 39.063898 -289.1168)
			(xy 39.067882 -289.063647) (xy 39.079743 -289.011681) (xy 39.099218 -288.962064) (xy 39.125871 -288.915904)
			(xy 39.159107 -288.874233) (xy 39.198183 -288.837981) (xy 39.242226 -288.807958) (xy 39.290251 -288.784836)
			(xy 39.341187 -288.76913) (xy 39.393895 -288.761192) (xy 39.420546 -288.760662) (xy 39.454836 -288.762186)
			(xy 39.468947 -288.763072) (xy 39.496741 -288.757948) (xy 39.522068 -288.745406) (xy 39.54299 -288.726405)
			(xy 39.557906 -288.702399) (xy 39.565674 -288.675225) (xy 39.566088 -288.661094) (xy 39.566088 -287.872424)
			(xy 39.56563 -287.858296) (xy 39.557885 -287.831121) (xy 39.542983 -287.807114) (xy 39.522066 -287.788116)
			(xy 39.49674 -287.775585) (xy 39.468948 -287.770483) (xy 39.454836 -287.771332) (xy 39.420546 -287.772856)
			(xy 39.393889 -287.772386) (xy 39.34117 -287.764446) (xy 39.290223 -287.748737) (xy 39.242187 -287.725609)
			(xy 39.198134 -287.69558) (xy 39.15905 -287.65932) (xy 39.125807 -287.617639) (xy 39.099148 -287.57147)
			(xy 39.079669 -287.521842) (xy 39.067804 -287.469865) (xy 39.06382 -287.4167) (xy 39.067804 -287.363535)
			(xy 39.079669 -287.311558) (xy 39.099148 -287.26193) (xy 39.125807 -287.21576) (xy 39.15905 -287.17408)
			(xy 39.198134 -287.13782) (xy 39.242187 -287.107791) (xy 39.290223 -287.084663) (xy 39.34117 -287.068954)
			(xy 39.393889 -287.061014) (xy 39.420546 -287.06064) (xy 39.454836 -287.062164) (xy 39.468946 -287.06305)
			(xy 39.496738 -287.057926) (xy 39.522062 -287.045384) (xy 39.542981 -287.026382) (xy 39.557892 -287.002375)
			(xy 39.565655 -286.975202) (xy 39.566088 -286.961072) (xy 39.566088 -286.172402) (xy 39.565627 -286.158276)
			(xy 39.557879 -286.131107) (xy 39.542975 -286.107105) (xy 39.522059 -286.088112) (xy 39.496736 -286.075584)
			(xy 39.468948 -286.070483) (xy 39.454836 -286.07131) (xy 39.420546 -286.072834) (xy 39.393891 -286.072364)
			(xy 39.341175 -286.064425) (xy 39.290231 -286.048716) (xy 39.242198 -286.02559) (xy 39.198148 -285.995563)
			(xy 39.159066 -285.959305) (xy 39.125825 -285.917627) (xy 39.099168 -285.87146) (xy 39.07969 -285.821835)
			(xy 39.067826 -285.769861) (xy 39.063842 -285.7167) (xy 39.067826 -285.663539) (xy 39.07969 -285.611565)
			(xy 39.099168 -285.56194) (xy 39.125825 -285.515773) (xy 39.159066 -285.474095) (xy 39.198148 -285.437837)
			(xy 39.242198 -285.40781) (xy 39.290231 -285.384684) (xy 39.341175 -285.368975) (xy 39.393891 -285.361036)
			(xy 39.420546 -285.360618) (xy 39.454836 -285.362142) (xy 39.468945 -285.363028) (xy 39.496735 -285.357904)
			(xy 39.522057 -285.345361) (xy 39.542972 -285.326358) (xy 39.557879 -285.302352) (xy 39.565636 -285.275179)
			(xy 39.566088 -285.26105) (xy 39.566088 -283.622242) (xy 39.565633 -283.608112) (xy 39.55789 -283.580933)
			(xy 39.542989 -283.556922) (xy 39.522071 -283.53792) (xy 39.496743 -283.525386) (xy 39.468948 -283.520283)
			(xy 39.454836 -283.52115) (xy 39.420546 -283.522674) (xy 39.393895 -283.522204) (xy 39.341188 -283.514266)
			(xy 39.290253 -283.498561) (xy 39.242228 -283.475438) (xy 39.198185 -283.445416) (xy 39.15911 -283.409164)
			(xy 39.125875 -283.367493) (xy 39.099222 -283.321334) (xy 39.079747 -283.271717) (xy 39.067886 -283.219753)
			(xy 39.063902 -283.1666) (xy 39.067886 -283.113447) (xy 39.079747 -283.061483) (xy 39.099222 -283.011866)
			(xy 39.125875 -282.965707) (xy 39.15911 -282.924036) (xy 39.198185 -282.887784) (xy 39.242228 -282.857762)
			(xy 39.290253 -282.834639) (xy 39.341188 -282.818934) (xy 39.393895 -282.810996) (xy 39.420546 -282.810458)
			(xy 39.454836 -282.811982) (xy 39.468947 -282.812868) (xy 39.496741 -282.807744) (xy 39.522067 -282.795202)
			(xy 39.542988 -282.776201) (xy 39.557903 -282.752195) (xy 39.56567 -282.725021) (xy 39.566088 -282.71089)
			(xy 39.566088 -281.922474) (xy 39.565637 -281.908341) (xy 39.5579 -281.881155) (xy 39.543 -281.857135)
			(xy 39.522081 -281.838127) (xy 39.496748 -281.825588) (xy 39.468948 -281.820483) (xy 39.454836 -281.821382)
			(xy 39.420546 -281.822906) (xy 39.393893 -281.822436) (xy 39.341181 -281.814497) (xy 39.290241 -281.79879)
			(xy 39.242212 -281.775666) (xy 39.198165 -281.745641) (xy 39.159087 -281.709386) (xy 39.125848 -281.667711)
			(xy 39.099193 -281.621548) (xy 39.079717 -281.571927) (xy 39.067854 -281.519957) (xy 39.06387 -281.4668)
			(xy 39.067854 -281.413643) (xy 39.079717 -281.361673) (xy 39.099193 -281.312052) (xy 39.125848 -281.265889)
			(xy 39.159087 -281.224214) (xy 39.198165 -281.187959) (xy 39.242212 -281.157934) (xy 39.290241 -281.13481)
			(xy 39.341181 -281.119103) (xy 39.393893 -281.111164) (xy 39.420546 -281.11069) (xy 39.454836 -281.112214)
			(xy 39.468948 -281.1131) (xy 39.496745 -281.107977) (xy 39.522076 -281.095435) (xy 39.543002 -281.076435)
			(xy 39.557923 -281.052429) (xy 39.565698 -281.025254) (xy 39.566088 -281.011122) (xy 39.566088 -280.222452)
			(xy 39.565634 -280.208321) (xy 39.557893 -280.18114) (xy 39.542992 -280.157126) (xy 39.522074 -280.138122)
			(xy 39.496745 -280.125587) (xy 39.468948 -280.120483) (xy 39.454836 -280.12136) (xy 39.420546 -280.122884)
			(xy 39.393894 -280.122414) (xy 39.341186 -280.114476) (xy 39.290249 -280.09877) (xy 39.242223 -280.075647)
			(xy 39.198179 -280.045624) (xy 39.159103 -280.009371) (xy 39.125867 -279.967699) (xy 39.099213 -279.921538)
			(xy 39.079738 -279.87192) (xy 39.067876 -279.819954) (xy 39.063892 -279.7668) (xy 39.067876 -279.713646)
			(xy 39.079738 -279.66168) (xy 39.099213 -279.612062) (xy 39.125867 -279.565901) (xy 39.159103 -279.524229)
			(xy 39.198179 -279.487976) (xy 39.242223 -279.457953) (xy 39.290249 -279.43483) (xy 39.341186 -279.419124)
			(xy 39.393894 -279.411186) (xy 39.420546 -279.410668) (xy 39.454836 -279.412192) (xy 39.468947 -279.413078)
			(xy 39.496742 -279.407954) (xy 39.52207 -279.395412) (xy 39.542993 -279.376411) (xy 39.557909 -279.352405)
			(xy 39.565679 -279.325231) (xy 39.566088 -279.3111) (xy 39.566088 -278.52243) (xy 39.565631 -278.508301)
			(xy 39.557887 -278.481125) (xy 39.542985 -278.457117) (xy 39.522068 -278.438118) (xy 39.496741 -278.425586)
			(xy 39.468948 -278.420483) (xy 39.454836 -278.421338) (xy 39.420546 -278.422862) (xy 39.393896 -278.422392)
			(xy 39.341191 -278.414454) (xy 39.290257 -278.398749) (xy 39.242234 -278.375628) (xy 39.198193 -278.345607)
			(xy 39.159119 -278.309356) (xy 39.125885 -278.267687) (xy 39.099233 -278.221529) (xy 39.079759 -278.171914)
			(xy 39.067897 -278.119951) (xy 39.063914 -278.0668) (xy 39.067897 -278.013649) (xy 39.079759 -277.961686)
			(xy 39.099233 -277.912071) (xy 39.125885 -277.865913) (xy 39.159119 -277.824244) (xy 39.198193 -277.787993)
			(xy 39.242234 -277.757972) (xy 39.290257 -277.734851) (xy 39.341191 -277.719146) (xy 39.393896 -277.711208)
			(xy 39.420546 -277.710646) (xy 39.454836 -277.71217) (xy 39.468946 -277.713056) (xy 39.496739 -277.707932)
			(xy 39.522064 -277.69539) (xy 39.542983 -277.676388) (xy 39.557896 -277.652382) (xy 39.56566 -277.625208)
			(xy 39.566088 -277.611078) (xy 39.566088 -276.822408) (xy 39.565628 -276.808281) (xy 39.55788 -276.781111)
			(xy 39.542977 -276.757108) (xy 39.522061 -276.738113) (xy 39.496737 -276.725584) (xy 39.468948 -276.720483)
			(xy 39.454836 -276.721316) (xy 39.420546 -276.72284) (xy 39.39389 -276.72237) (xy 39.341173 -276.71443)
			(xy 39.290229 -276.698722) (xy 39.242195 -276.675595) (xy 39.198144 -276.645568) (xy 39.159062 -276.609309)
			(xy 39.12582 -276.56763) (xy 39.099163 -276.521463) (xy 39.079684 -276.471837) (xy 39.06782 -276.419862)
			(xy 39.063836 -276.3667) (xy 39.06782 -276.313538) (xy 39.079684 -276.261563) (xy 39.099163 -276.211937)
			(xy 39.12582 -276.16577) (xy 39.159062 -276.124091) (xy 39.198144 -276.087832) (xy 39.242195 -276.057805)
			(xy 39.290229 -276.034678) (xy 39.341173 -276.01897) (xy 39.39389 -276.01103) (xy 39.420546 -276.010624)
			(xy 39.454836 -276.012148) (xy 39.468945 -276.013034) (xy 39.496736 -276.00791) (xy 39.522058 -275.995367)
			(xy 39.542974 -275.976365) (xy 39.557882 -275.952358) (xy 39.565641 -275.925185) (xy 39.566088 -275.911056)
			(xy 39.566088 -274.272248) (xy 39.565633 -274.258117) (xy 39.557892 -274.230937) (xy 39.542991 -274.206924)
			(xy 39.522073 -274.187921) (xy 39.496744 -274.175387) (xy 39.468948 -274.170283) (xy 39.454836 -274.171156)
			(xy 39.420546 -274.17268) (xy 39.393895 -274.17221) (xy 39.341187 -274.164272) (xy 39.290251 -274.148566)
			(xy 39.242225 -274.125443) (xy 39.198182 -274.095421) (xy 39.159106 -274.059168) (xy 39.12587 -274.017497)
			(xy 39.099217 -273.971337) (xy 39.079741 -273.921719) (xy 39.06788 -273.869753) (xy 39.063896 -273.8166)
			(xy 39.06788 -273.763447) (xy 39.079741 -273.711481) (xy 39.099217 -273.661863) (xy 39.12587 -273.615703)
			(xy 39.159106 -273.574032) (xy 39.198182 -273.537779) (xy 39.242225 -273.507757) (xy 39.290251 -273.484634)
			(xy 39.341187 -273.468928) (xy 39.393895 -273.46099) (xy 39.420546 -273.460464) (xy 39.454836 -273.461988)
			(xy 39.468947 -273.462874) (xy 39.496741 -273.45775) (xy 39.522069 -273.445208) (xy 39.542991 -273.426207)
			(xy 39.557907 -273.402201) (xy 39.565676 -273.375027) (xy 39.566088 -273.360896) (xy 39.566088 -272.57248)
			(xy 39.565637 -272.558346) (xy 39.557902 -272.531159) (xy 39.543002 -272.507138) (xy 39.522083 -272.488128)
			(xy 39.496749 -272.475589) (xy 39.468948 -272.470483) (xy 39.454836 -272.471388) (xy 39.420546 -272.472912)
			(xy 39.393892 -272.472442) (xy 39.34118 -272.464503) (xy 39.290239 -272.448796) (xy 39.242209 -272.425671)
			(xy 39.198162 -272.395646) (xy 39.159082 -272.35939) (xy 39.125843 -272.317715) (xy 39.099188 -272.27155)
			(xy 39.079711 -272.221929) (xy 39.067848 -272.169958) (xy 39.063864 -272.1168) (xy 39.067848 -272.063642)
			(xy 39.079711 -272.011671) (xy 39.099188 -271.96205) (xy 39.125843 -271.915885) (xy 39.159082 -271.87421)
			(xy 39.198162 -271.837954) (xy 39.242209 -271.807929) (xy 39.290239 -271.784804) (xy 39.34118 -271.769097)
			(xy 39.393892 -271.761158) (xy 39.420546 -271.760696) (xy 39.454836 -271.76222) (xy 39.468944 -271.763106)
			(xy 39.496732 -271.757982) (xy 39.522051 -271.745438) (xy 39.542963 -271.726435) (xy 39.557865 -271.702428)
			(xy 39.565617 -271.675256) (xy 39.566088 -271.661128) (xy 39.566088 -271.02308) (xy 39.292022 -270.749014)
			(xy 39.282878 -270.745204) (xy 39.257549 -270.73402) (xy 39.210413 -270.704975) (xy 39.168341 -270.668985)
			(xy 39.132346 -270.626916) (xy 39.103297 -270.579783) (xy 39.092124 -270.55445) (xy 39.088314 -270.545306)
			(xy 38.532562 -269.989554) (xy 38.532562 -269.822676) (xy 37.61613 -269.822676) (xy 37.605999 -269.822192)
			(xy 37.587266 -269.814471) (xy 37.572897 -269.800185) (xy 37.565067 -269.781497) (xy 37.564568 -269.771368)
			(xy 37.564568 -269.362428) (xy 37.564993 -269.352269) (xy 37.572781 -269.333505) (xy 37.587175 -269.319167)
			(xy 37.60597 -269.311453) (xy 37.61613 -269.31112) (xy 38.532562 -269.31112) (xy 38.532562 -268.122908)
			(xy 37.61613 -268.122908) (xy 37.605965 -268.122418) (xy 37.587178 -268.114651) (xy 37.572792 -268.100286)
			(xy 37.564997 -268.08151) (xy 37.564568 -268.071346) (xy 37.564568 -267.662406) (xy 37.564993 -267.652236)
			(xy 37.572778 -267.633444) (xy 37.587164 -267.619065) (xy 37.60596 -267.611289) (xy 37.61613 -267.610844)
			(xy 38.532562 -267.610844) (xy 38.532562 -266.422632) (xy 37.61613 -266.422632) (xy 37.606002 -266.422148)
			(xy 37.587276 -266.414425) (xy 37.572918 -266.400137) (xy 37.565103 -266.38145) (xy 37.564568 -266.371324)
			(xy 37.564568 -265.962384) (xy 37.565 -265.952231) (xy 37.572796 -265.933482) (xy 37.587189 -265.919158)
			(xy 37.605975 -265.911452) (xy 37.61613 -265.911076) (xy 39.01567 -265.911076) (xy 39.022753 -265.911234)
			(xy 39.036412 -265.91498) (xy 39.042594 -265.918442) (xy 39.07663 -265.93927) (xy 39.243254 -265.772646)
			(xy 39.253574 -265.761575) (xy 39.2678 -265.734879) (xy 39.273587 -265.705189) (xy 39.270428 -265.675104)
			(xy 39.2586 -265.647263) (xy 39.239139 -265.624105) (xy 39.226744 -265.61542) (xy 39.205745 -265.601259)
			(xy 39.167596 -265.567946) (xy 39.134549 -265.529566) (xy 39.107271 -265.486892) (xy 39.086313 -265.440785)
			(xy 39.072095 -265.392174) (xy 39.064906 -265.342039) (xy 39.064438 -265.316716) (xy 39.064957 -265.288731)
			(xy 39.073711 -265.23345) (xy 39.091006 -265.18022) (xy 39.116417 -265.130351) (xy 39.149316 -265.085071)
			(xy 39.188894 -265.045496) (xy 39.234176 -265.012601) (xy 39.284048 -264.987195) (xy 39.33728 -264.969904)
			(xy 39.392561 -264.961155) (xy 39.420546 -264.960608) (xy 39.451206 -264.961273) (xy 39.511614 -264.971809)
			(xy 39.569334 -264.992511) (xy 39.596314 -265.00709) (xy 39.609787 -265.014083) (xy 39.639411 -265.020629)
			(xy 39.669651 -265.018187) (xy 39.697841 -265.006973) (xy 39.721495 -264.987975) (xy 39.738528 -264.962869)
			(xy 39.747436 -264.933867) (xy 39.747952 -264.918698) (xy 39.747952 -264.014712) (xy 39.747395 -263.999548)
			(xy 39.738492 -263.970556) (xy 39.721467 -263.945457) (xy 39.697822 -263.926465) (xy 39.669642 -263.915254)
			(xy 39.639412 -263.912814) (xy 39.609799 -263.919359) (xy 39.596314 -263.92632) (xy 39.569344 -263.940924)
			(xy 39.511627 -263.961654) (xy 39.451209 -263.97217) (xy 39.420546 -263.972802) (xy 39.393893 -263.972332)
			(xy 39.341182 -263.964393) (xy 39.290243 -263.948687) (xy 39.242214 -263.925563) (xy 39.198168 -263.895538)
			(xy 39.15909 -263.859283) (xy 39.125852 -263.817609) (xy 39.099197 -263.771446) (xy 39.07972 -263.721826)
			(xy 39.067858 -263.669857) (xy 39.063874 -263.6167) (xy 39.067858 -263.563543) (xy 39.07972 -263.511574)
			(xy 39.099197 -263.461954) (xy 39.125852 -263.415791) (xy 39.15909 -263.374117) (xy 39.198168 -263.337862)
			(xy 39.242214 -263.307837) (xy 39.290243 -263.284713) (xy 39.341182 -263.269007) (xy 39.393893 -263.261068)
			(xy 39.420546 -263.260586) (xy 39.451206 -263.261251) (xy 39.511615 -263.271786) (xy 39.569335 -263.292487)
			(xy 39.596314 -263.307068) (xy 39.609791 -263.314057) (xy 39.63942 -263.320598) (xy 39.669664 -263.318154)
			(xy 39.697858 -263.306942) (xy 39.72152 -263.287948) (xy 39.738566 -263.262846) (xy 39.747493 -263.233847)
			(xy 39.747952 -263.218676) (xy 39.747952 -262.31469) (xy 39.747392 -262.299528) (xy 39.738485 -262.270542)
			(xy 39.72146 -262.24545) (xy 39.697817 -262.226462) (xy 39.669641 -262.215254) (xy 39.639416 -262.212814)
			(xy 39.609807 -262.219356) (xy 39.596314 -262.226298) (xy 39.569344 -262.240903) (xy 39.511628 -262.261634)
			(xy 39.45121 -262.272151) (xy 39.420546 -262.27278) (xy 39.393895 -262.27231) (xy 39.341187 -262.264372)
			(xy 39.290251 -262.248666) (xy 39.242225 -262.225543) (xy 39.198182 -262.195521) (xy 39.159106 -262.159268)
			(xy 39.12587 -262.117597) (xy 39.099217 -262.071437) (xy 39.079741 -262.021819) (xy 39.06788 -261.969853)
			(xy 39.063896 -261.9167) (xy 39.06788 -261.863547) (xy 39.079741 -261.811581) (xy 39.099217 -261.761963)
			(xy 39.12587 -261.715803) (xy 39.159106 -261.674132) (xy 39.198182 -261.637879) (xy 39.242225 -261.607857)
			(xy 39.290251 -261.584734) (xy 39.341187 -261.569028) (xy 39.393895 -261.56109) (xy 39.420546 -261.560564)
			(xy 39.451206 -261.561229) (xy 39.511615 -261.571764) (xy 39.569336 -261.592463) (xy 39.596314 -261.607046)
			(xy 39.60979 -261.614036) (xy 39.639417 -261.620578) (xy 39.66966 -261.618135) (xy 39.697854 -261.606922)
			(xy 39.721513 -261.587928) (xy 39.738555 -261.562824) (xy 39.747477 -261.533824) (xy 39.747952 -261.518654)
			(xy 39.747952 -260.614668) (xy 39.747389 -260.599509) (xy 39.738479 -260.570529) (xy 39.721453 -260.545442)
			(xy 39.697812 -260.526459) (xy 39.66964 -260.515254) (xy 39.63942 -260.512813) (xy 39.609815 -260.519353)
			(xy 39.596314 -260.526276) (xy 39.569343 -260.540878) (xy 39.511626 -260.561604) (xy 39.451209 -260.572119)
			(xy 39.420546 -260.572758) (xy 39.393889 -260.572288) (xy 39.341169 -260.564348) (xy 39.290222 -260.548639)
			(xy 39.242186 -260.525511) (xy 39.198133 -260.495482) (xy 39.159049 -260.459221) (xy 39.125805 -260.417541)
			(xy 39.099146 -260.37137) (xy 39.079667 -260.321742) (xy 39.067802 -260.269765) (xy 39.063818 -260.2166)
			(xy 39.067802 -260.163435) (xy 39.079667 -260.111458) (xy 39.099146 -260.06183) (xy 39.125805 -260.015659)
			(xy 39.159049 -259.973979) (xy 39.198133 -259.937718) (xy 39.242186 -259.907689) (xy 39.290222 -259.884561)
			(xy 39.341169 -259.868852) (xy 39.393889 -259.860912) (xy 39.420546 -259.860542) (xy 39.451206 -259.861206)
			(xy 39.511615 -259.87174) (xy 39.569337 -259.892439) (xy 39.596314 -259.907024) (xy 39.609789 -259.914015)
			(xy 39.639415 -259.920559) (xy 39.669657 -259.918116) (xy 39.697849 -259.906903) (xy 39.721506 -259.887907)
			(xy 39.738544 -259.862802) (xy 39.747461 -259.833802) (xy 39.747952 -259.818632) (xy 39.747952 -258.914646)
			(xy 39.7474 -258.899478) (xy 39.738502 -258.870477) (xy 39.721478 -258.845369) (xy 39.69783 -258.826369)
			(xy 39.669643 -258.815155) (xy 39.639406 -258.812714) (xy 39.609786 -258.819263) (xy 39.596314 -258.826254)
			(xy 39.569344 -258.840857) (xy 39.511627 -258.861585) (xy 39.451209 -258.8721) (xy 39.420546 -258.872736)
			(xy 39.393891 -258.872266) (xy 39.341174 -258.864327) (xy 39.29023 -258.848618) (xy 39.242197 -258.825492)
			(xy 39.198147 -258.795464) (xy 39.159065 -258.759206) (xy 39.125824 -258.717528) (xy 39.099166 -258.671361)
			(xy 39.079688 -258.621736) (xy 39.067824 -258.569762) (xy 39.06384 -258.5166) (xy 39.067824 -258.463438)
			(xy 39.079688 -258.411464) (xy 39.099166 -258.361839) (xy 39.125824 -258.315672) (xy 39.159065 -258.273994)
			(xy 39.198147 -258.237736) (xy 39.242197 -258.207708) (xy 39.29023 -258.184582) (xy 39.341174 -258.168873)
			(xy 39.393891 -258.160934) (xy 39.420546 -258.16052) (xy 39.451206 -258.161185) (xy 39.511614 -258.171721)
			(xy 39.569334 -258.192424) (xy 39.596314 -258.207002) (xy 39.609788 -258.213994) (xy 39.639412 -258.22054)
			(xy 39.669653 -258.218098) (xy 39.697844 -258.206884) (xy 39.721499 -258.187886) (xy 39.738533 -258.162781)
			(xy 39.747445 -258.13378) (xy 39.747952 -258.11861) (xy 39.747952 -255.131316) (xy 39.74338 -255.131316)
			(xy 39.701115 -255.130828) (xy 39.616947 -255.123029) (xy 39.533857 -255.107496) (xy 39.452555 -255.084364)
			(xy 39.373734 -255.053829) (xy 39.298067 -255.016151) (xy 39.226199 -254.971652) (xy 39.158743 -254.920712)
			(xy 39.096275 -254.863765) (xy 39.039328 -254.801297) (xy 38.988388 -254.733841) (xy 38.943889 -254.661973)
			(xy 38.906211 -254.586306) (xy 38.875676 -254.507485) (xy 38.852544 -254.426183) (xy 38.837011 -254.343093)
			(xy 38.829212 -254.258925) (xy 38.829212 -254.174395) (xy 38.837011 -254.090227) (xy 38.852544 -254.007137)
			(xy 38.875676 -253.925835) (xy 38.906211 -253.847014) (xy 38.943889 -253.771347) (xy 38.988388 -253.699479)
			(xy 39.039328 -253.632023) (xy 39.096275 -253.569555) (xy 39.158743 -253.512608) (xy 39.226199 -253.461668)
			(xy 39.298067 -253.417169) (xy 39.373734 -253.379491) (xy 39.452555 -253.348956) (xy 39.533857 -253.325824)
			(xy 39.616947 -253.310291) (xy 39.701115 -253.302492) (xy 39.74338 -253.302008) (xy 39.747952 -253.302008)
			(xy 39.747952 -252.114812) (xy 39.747395 -252.099648) (xy 39.738492 -252.070656) (xy 39.721467 -252.045557)
			(xy 39.697822 -252.026565) (xy 39.669642 -252.015354) (xy 39.639412 -252.012914) (xy 39.609799 -252.019459)
			(xy 39.596314 -252.02642) (xy 39.569344 -252.041024) (xy 39.511627 -252.061754) (xy 39.451209 -252.07227)
			(xy 39.420546 -252.072902) (xy 39.393893 -252.072432) (xy 39.341182 -252.064493) (xy 39.290243 -252.048787)
			(xy 39.242214 -252.025663) (xy 39.198168 -251.995638) (xy 39.15909 -251.959383) (xy 39.125852 -251.917709)
			(xy 39.099197 -251.871546) (xy 39.07972 -251.821926) (xy 39.067858 -251.769957) (xy 39.063874 -251.7168)
			(xy 39.067858 -251.663643) (xy 39.07972 -251.611674) (xy 39.099197 -251.562054) (xy 39.125852 -251.515891)
			(xy 39.15909 -251.474217) (xy 39.198168 -251.437962) (xy 39.242214 -251.407937) (xy 39.290243 -251.384813)
			(xy 39.341182 -251.369107) (xy 39.393893 -251.361168) (xy 39.420546 -251.360686) (xy 39.451206 -251.361351)
			(xy 39.511615 -251.371886) (xy 39.569335 -251.392587) (xy 39.596314 -251.407168) (xy 39.609791 -251.414157)
			(xy 39.63942 -251.420698) (xy 39.669664 -251.418254) (xy 39.697858 -251.407042) (xy 39.72152 -251.388048)
			(xy 39.738566 -251.362946) (xy 39.747493 -251.333947) (xy 39.747952 -251.318776) (xy 39.747952 -250.41479)
			(xy 39.747392 -250.399628) (xy 39.738485 -250.370642) (xy 39.72146 -250.34555) (xy 39.697817 -250.326562)
			(xy 39.669641 -250.315354) (xy 39.639416 -250.312914) (xy 39.609807 -250.319456) (xy 39.596314 -250.326398)
			(xy 39.569344 -250.341003) (xy 39.511628 -250.361734) (xy 39.45121 -250.372251) (xy 39.420546 -250.37288)
			(xy 39.393895 -250.37241) (xy 39.341187 -250.364472) (xy 39.290251 -250.348766) (xy 39.242225 -250.325643)
			(xy 39.198182 -250.295621) (xy 39.159106 -250.259368) (xy 39.12587 -250.217697) (xy 39.099217 -250.171537)
			(xy 39.079741 -250.121919) (xy 39.06788 -250.069953) (xy 39.063896 -250.0168) (xy 39.06788 -249.963647)
			(xy 39.079741 -249.911681) (xy 39.099217 -249.862063) (xy 39.12587 -249.815903) (xy 39.159106 -249.774232)
			(xy 39.198182 -249.737979) (xy 39.242225 -249.707957) (xy 39.290251 -249.684834) (xy 39.341187 -249.669128)
			(xy 39.393895 -249.66119) (xy 39.420546 -249.660664) (xy 39.451206 -249.661329) (xy 39.511615 -249.671864)
			(xy 39.569336 -249.692563) (xy 39.596314 -249.707146) (xy 39.60979 -249.714136) (xy 39.639417 -249.720678)
			(xy 39.66966 -249.718235) (xy 39.697854 -249.707022) (xy 39.721513 -249.688028) (xy 39.738555 -249.662924)
			(xy 39.747477 -249.633924) (xy 39.747952 -249.618754) (xy 39.747952 -248.714768) (xy 39.747389 -248.699609)
			(xy 39.738479 -248.670629) (xy 39.721453 -248.645542) (xy 39.697812 -248.626559) (xy 39.66964 -248.615354)
			(xy 39.63942 -248.612913) (xy 39.609815 -248.619453) (xy 39.596314 -248.626376) (xy 39.569343 -248.640978)
			(xy 39.511626 -248.661704) (xy 39.451209 -248.672219) (xy 39.420546 -248.672858) (xy 39.393889 -248.672388)
			(xy 39.341169 -248.664448) (xy 39.290222 -248.648739) (xy 39.242186 -248.625611) (xy 39.198133 -248.595582)
			(xy 39.159049 -248.559321) (xy 39.125805 -248.517641) (xy 39.099146 -248.47147) (xy 39.079667 -248.421842)
			(xy 39.067802 -248.369865) (xy 39.063818 -248.3167) (xy 39.067802 -248.263535) (xy 39.079667 -248.211558)
			(xy 39.099146 -248.16193) (xy 39.125805 -248.115759) (xy 39.159049 -248.074079) (xy 39.198133 -248.037818)
			(xy 39.242186 -248.007789) (xy 39.290222 -247.984661) (xy 39.341169 -247.968952) (xy 39.393889 -247.961012)
			(xy 39.420546 -247.960642) (xy 39.451206 -247.961306) (xy 39.511615 -247.97184) (xy 39.569337 -247.992539)
			(xy 39.596314 -248.007124) (xy 39.609789 -248.014115) (xy 39.639415 -248.020659) (xy 39.669657 -248.018216)
			(xy 39.697849 -248.007003) (xy 39.721506 -247.988007) (xy 39.738544 -247.962902) (xy 39.747461 -247.933902)
			(xy 39.747952 -247.918732) (xy 39.747952 -247.014746) (xy 39.7474 -246.999578) (xy 39.738502 -246.970577)
			(xy 39.721478 -246.945469) (xy 39.69783 -246.926469) (xy 39.669643 -246.915255) (xy 39.639406 -246.912814)
			(xy 39.609786 -246.919363) (xy 39.596314 -246.926354) (xy 39.569344 -246.940957) (xy 39.511627 -246.961685)
			(xy 39.451209 -246.9722) (xy 39.420546 -246.972836) (xy 39.393891 -246.972366) (xy 39.341174 -246.964427)
			(xy 39.29023 -246.948718) (xy 39.242197 -246.925592) (xy 39.198147 -246.895564) (xy 39.159065 -246.859306)
			(xy 39.125824 -246.817628) (xy 39.099166 -246.771461) (xy 39.079688 -246.721836) (xy 39.067824 -246.669862)
			(xy 39.06384 -246.6167) (xy 39.067824 -246.563538) (xy 39.079688 -246.511564) (xy 39.099166 -246.461939)
			(xy 39.125824 -246.415772) (xy 39.159065 -246.374094) (xy 39.198147 -246.337836) (xy 39.242197 -246.307808)
			(xy 39.29023 -246.284682) (xy 39.341174 -246.268973) (xy 39.393891 -246.261034) (xy 39.420546 -246.26062)
			(xy 39.451206 -246.261285) (xy 39.511614 -246.271821) (xy 39.569334 -246.292524) (xy 39.596314 -246.307102)
			(xy 39.609788 -246.314094) (xy 39.639412 -246.32064) (xy 39.669653 -246.318198) (xy 39.697844 -246.306984)
			(xy 39.721499 -246.287986) (xy 39.738533 -246.262881) (xy 39.747445 -246.23388) (xy 39.747952 -246.21871)
			(xy 39.747952 -246.112284) (xy 39.505636 -246.112284) (xy 39.500048 -246.113808) (xy 39.480438 -246.117978)
			(xy 39.440593 -246.122436) (xy 39.420546 -246.122698) (xy 39.393286 -246.122173) (xy 39.339404 -246.11385)
			(xy 39.287422 -246.097405) (xy 39.238556 -246.073225) (xy 39.19395 -246.041875) (xy 39.173912 -246.023384)
			(xy 39.163494 -246.013983) (xy 39.138746 -246.000774) (xy 39.111339 -245.994799) (xy 39.083339 -245.996508)
			(xy 39.056861 -246.005772) (xy 39.045134 -246.013478) (xy 39.03854 -246.017787) (xy 39.023541 -246.022575)
			(xy 39.01567 -246.022876) (xy 37.61613 -246.022876) (xy 37.605953 -246.022455) (xy 37.587146 -246.014676)
			(xy 37.572748 -246.000291) (xy 37.564953 -245.98149) (xy 37.564568 -245.971314) (xy 37.564568 -245.562374)
			(xy 37.564999 -245.552208) (xy 37.57279 -245.533428) (xy 37.587175 -245.519058) (xy 37.605964 -245.511288)
			(xy 37.61613 -245.510812) (xy 39.01567 -245.510812) (xy 39.023539 -245.511128) (xy 39.038538 -245.515907)
			(xy 39.045134 -245.52021) (xy 39.056862 -245.527862) (xy 39.083307 -245.537046) (xy 39.111252 -245.538688)
			(xy 39.13859 -245.532664) (xy 39.163257 -245.519429) (xy 39.173658 -245.51005) (xy 39.193664 -245.491469)
			(xy 39.238311 -245.460042) (xy 39.287235 -245.435805) (xy 39.339288 -245.419326) (xy 39.393247 -245.410992)
			(xy 39.420546 -245.410482) (xy 39.440594 -245.410728) (xy 39.48044 -245.415187) (xy 39.500048 -245.419372)
			(xy 39.505636 -245.420896) (xy 39.747952 -245.420896) (xy 39.747952 -245.314724) (xy 39.747397 -245.299559)
			(xy 39.738496 -245.270563) (xy 39.721471 -245.245461) (xy 39.697825 -245.226467) (xy 39.669642 -245.215255)
			(xy 39.63941 -245.212814) (xy 39.609794 -245.21936) (xy 39.596314 -245.226332) (xy 39.569344 -245.240935)
			(xy 39.511627 -245.261665) (xy 39.451209 -245.272181) (xy 39.420546 -245.272814) (xy 39.393892 -245.272344)
			(xy 39.341179 -245.264405) (xy 39.290238 -245.248698) (xy 39.242208 -245.225573) (xy 39.19816 -245.195547)
			(xy 39.159081 -245.159292) (xy 39.125842 -245.117616) (xy 39.099186 -245.071451) (xy 39.079709 -245.021829)
			(xy 39.067846 -244.969858) (xy 39.063862 -244.9167) (xy 39.067846 -244.863542) (xy 39.079709 -244.811571)
			(xy 39.099186 -244.761949) (xy 39.125842 -244.715784) (xy 39.159081 -244.674108) (xy 39.19816 -244.637853)
			(xy 39.242208 -244.607827) (xy 39.290238 -244.584702) (xy 39.341179 -244.568995) (xy 39.393892 -244.561056)
			(xy 39.420546 -244.560598) (xy 39.451206 -244.561263) (xy 39.511614 -244.571799) (xy 39.569335 -244.5925)
			(xy 39.596314 -244.60708) (xy 39.609787 -244.614073) (xy 39.63941 -244.62062) (xy 39.66965 -244.618178)
			(xy 39.697839 -244.606964) (xy 39.721492 -244.587965) (xy 39.738522 -244.562858) (xy 39.747428 -244.533857)
			(xy 39.747952 -244.518688) (xy 39.747952 -244.464586) (xy 39.747392 -244.449425) (xy 39.738484 -244.42044)
			(xy 39.721459 -244.395348) (xy 39.697816 -244.376362) (xy 39.669641 -244.365154) (xy 39.639417 -244.362714)
			(xy 39.609808 -244.369255) (xy 39.596314 -244.376194) (xy 39.569343 -244.390795) (xy 39.511626 -244.411521)
			(xy 39.451209 -244.422035) (xy 39.420546 -244.422676) (xy 39.393285 -244.422152) (xy 39.339402 -244.41383)
			(xy 39.287418 -244.397388) (xy 39.238549 -244.373212) (xy 39.193938 -244.341866) (xy 39.173912 -244.323362)
			(xy 39.163493 -244.313963) (xy 39.138745 -244.300757) (xy 39.111339 -244.294783) (xy 39.08334 -244.296492)
			(xy 39.056863 -244.305754) (xy 39.045134 -244.313456) (xy 39.038519 -244.317693) (xy 39.023522 -244.322338)
			(xy 39.01567 -244.3226) (xy 37.61613 -244.3226) (xy 37.605997 -244.322117) (xy 37.58726 -244.314396)
			(xy 37.572885 -244.300111) (xy 37.565047 -244.281422) (xy 37.564568 -244.271292) (xy 37.564568 -243.862352)
			(xy 37.565006 -243.852204) (xy 37.572808 -243.833465) (xy 37.587199 -243.819152) (xy 37.605979 -243.811451)
			(xy 37.61613 -243.811044) (xy 39.01567 -243.811044) (xy 39.023522 -243.811292) (xy 39.038514 -243.815958)
			(xy 39.045134 -243.820188) (xy 39.056862 -243.827841) (xy 39.083306 -243.837027) (xy 39.111252 -243.838669)
			(xy 39.13859 -243.832644) (xy 39.163257 -243.819407) (xy 39.173658 -243.810028) (xy 39.193665 -243.791448)
			(xy 39.238312 -243.760023) (xy 39.287236 -243.735787) (xy 39.339289 -243.719309) (xy 39.393247 -243.710976)
			(xy 39.420546 -243.71046) (xy 39.451206 -243.711125) (xy 39.511615 -243.721659) (xy 39.569336 -243.742359)
			(xy 39.596314 -243.756942) (xy 39.60979 -243.763932) (xy 39.639417 -243.770475) (xy 39.66966 -243.768032)
			(xy 39.697853 -243.756819) (xy 39.721512 -243.737824) (xy 39.738553 -243.71272) (xy 39.747474 -243.68372)
			(xy 39.747952 -243.66855) (xy 39.747952 -243.614702) (xy 39.747394 -243.599539) (xy 39.738489 -243.57055)
			(xy 39.721464 -243.545454) (xy 39.69782 -243.526464) (xy 39.669642 -243.515254) (xy 39.639414 -243.512814)
			(xy 39.609802 -243.519357) (xy 39.596314 -243.52631) (xy 39.569344 -243.540914) (xy 39.511628 -243.561645)
			(xy 39.451209 -243.572161) (xy 39.420546 -243.572792) (xy 39.393286 -243.572267) (xy 39.339404 -243.563944)
			(xy 39.287422 -243.547499) (xy 39.238557 -243.523318) (xy 39.193951 -243.491968) (xy 39.173912 -243.473478)
			(xy 39.163494 -243.464077) (xy 39.138746 -243.45087) (xy 39.111339 -243.444895) (xy 39.083339 -243.446604)
			(xy 39.056862 -243.455867) (xy 39.045134 -243.463572) (xy 39.038519 -243.467808) (xy 39.023521 -243.472452)
			(xy 39.01567 -243.472716) (xy 37.61613 -243.472716) (xy 37.606003 -243.472231) (xy 37.58728 -243.464508)
			(xy 37.572926 -243.450219) (xy 37.565116 -243.431533) (xy 37.564568 -243.421408) (xy 37.564568 -243.012468)
			(xy 37.565003 -243.002317) (xy 37.572802 -242.983574) (xy 37.587194 -242.969255) (xy 37.605977 -242.961552)
			(xy 37.61613 -242.96116) (xy 39.01567 -242.96116) (xy 39.023522 -242.961409) (xy 39.038512 -242.966075)
			(xy 39.045134 -242.970304) (xy 39.056862 -242.977957) (xy 39.083306 -242.987141) (xy 39.111252 -242.988783)
			(xy 39.13859 -242.982759) (xy 39.163257 -242.969523) (xy 39.173658 -242.960144) (xy 39.193664 -242.941563)
			(xy 39.238312 -242.910137) (xy 39.287236 -242.8859) (xy 39.339288 -242.869421) (xy 39.393247 -242.861087)
			(xy 39.420546 -242.860576) (xy 39.451206 -242.861241) (xy 39.511615 -242.871776) (xy 39.569336 -242.892476)
			(xy 39.596314 -242.907058) (xy 39.609791 -242.914047) (xy 39.639419 -242.920589) (xy 39.669662 -242.918146)
			(xy 39.697856 -242.906933) (xy 39.721517 -242.887939) (xy 39.738561 -242.862836) (xy 39.747486 -242.833837)
			(xy 39.747952 -242.818666) (xy 39.747952 -242.764818) (xy 39.747396 -242.749653) (xy 39.738494 -242.72066)
			(xy 39.721469 -242.695559) (xy 39.697823 -242.676566) (xy 39.669642 -242.665354) (xy 39.639411 -242.662914)
			(xy 39.609797 -242.66946) (xy 39.596314 -242.676426) (xy 39.569344 -242.69103) (xy 39.511627 -242.711759)
			(xy 39.451209 -242.722275) (xy 39.420546 -242.722908) (xy 39.393893 -242.722438) (xy 39.34118 -242.714499)
			(xy 39.29024 -242.698792) (xy 39.242211 -242.675668) (xy 39.198164 -242.645643) (xy 39.159085 -242.609387)
			(xy 39.125847 -242.567712) (xy 39.099191 -242.521549) (xy 39.079715 -242.471928) (xy 39.067852 -242.419958)
			(xy 39.063868 -242.3668) (xy 39.067852 -242.313642) (xy 39.079715 -242.261672) (xy 39.099191 -242.212051)
			(xy 39.125847 -242.165888) (xy 39.159085 -242.124213) (xy 39.198164 -242.087957) (xy 39.242211 -242.057932)
			(xy 39.29024 -242.034808) (xy 39.34118 -242.019101) (xy 39.393893 -242.011162) (xy 39.420546 -242.010692)
			(xy 39.451206 -242.011357) (xy 39.511614 -242.021892) (xy 39.569335 -242.042594) (xy 39.596314 -242.057174)
			(xy 39.609791 -242.064163) (xy 39.639421 -242.070703) (xy 39.669665 -242.068259) (xy 39.69786 -242.057047)
			(xy 39.721522 -242.038054) (xy 39.738569 -242.012952) (xy 39.747497 -241.983953) (xy 39.747952 -241.968782)
			(xy 39.747952 -241.064796) (xy 39.747393 -241.049634) (xy 39.738487 -241.020646) (xy 39.721462 -240.995552)
			(xy 39.697818 -240.976563) (xy 39.669641 -240.965354) (xy 39.639415 -240.962914) (xy 39.609805 -240.969456)
			(xy 39.596314 -240.976404) (xy 39.569344 -240.991009) (xy 39.511628 -241.011739) (xy 39.451209 -241.022256)
			(xy 39.420546 -241.022886) (xy 39.393894 -241.022416) (xy 39.341185 -241.014478) (xy 39.290248 -240.998772)
			(xy 39.242222 -240.975649) (xy 39.198178 -240.945625) (xy 39.159101 -240.909372) (xy 39.125865 -240.8677)
			(xy 39.099211 -240.821539) (xy 39.079736 -240.771921) (xy 39.067874 -240.719954) (xy 39.06389 -240.6668)
			(xy 39.067874 -240.613646) (xy 39.079736 -240.561679) (xy 39.099211 -240.512061) (xy 39.125865 -240.4659)
			(xy 39.159101 -240.424228) (xy 39.198178 -240.387975) (xy 39.242222 -240.357951) (xy 39.290248 -240.334828)
			(xy 39.341185 -240.319122) (xy 39.393894 -240.311184) (xy 39.420546 -240.31067) (xy 39.451206 -240.311335)
			(xy 39.511615 -240.32187) (xy 39.569336 -240.34257) (xy 39.596314 -240.357152) (xy 39.60979 -240.364142)
			(xy 39.639418 -240.370684) (xy 39.669661 -240.36824) (xy 39.697855 -240.357028) (xy 39.721515 -240.338033)
			(xy 39.738558 -240.31293) (xy 39.747481 -240.28393) (xy 39.747952 -240.26876) (xy 39.747952 -239.364774)
			(xy 39.74739 -239.349614) (xy 39.738481 -239.320633) (xy 39.721455 -239.295544) (xy 39.697814 -239.27656)
			(xy 39.66964 -239.265354) (xy 39.639419 -239.262913) (xy 39.609813 -239.269453) (xy 39.596314 -239.276382)
			(xy 39.569343 -239.290984) (xy 39.511626 -239.31171) (xy 39.451209 -239.322224) (xy 39.420546 -239.322864)
			(xy 39.393896 -239.322394) (xy 39.34119 -239.314456) (xy 39.290256 -239.298751) (xy 39.242233 -239.27563)
			(xy 39.198192 -239.245608) (xy 39.159117 -239.209358) (xy 39.125883 -239.167688) (xy 39.099231 -239.12153)
			(xy 39.079757 -239.071915) (xy 39.067895 -239.019951) (xy 39.063912 -238.9668) (xy 39.067895 -238.913649)
			(xy 39.079757 -238.861685) (xy 39.099231 -238.81207) (xy 39.125883 -238.765912) (xy 39.159117 -238.724242)
			(xy 39.198192 -238.687992) (xy 39.242233 -238.65797) (xy 39.290256 -238.634849) (xy 39.34119 -238.619144)
			(xy 39.393896 -238.611206) (xy 39.420546 -238.610648) (xy 39.451206 -238.611313) (xy 39.511615 -238.621847)
			(xy 39.569337 -238.642546) (xy 39.596314 -238.65713) (xy 39.609789 -238.664121) (xy 39.639416 -238.670664)
			(xy 39.669658 -238.668222) (xy 39.69785 -238.657008) (xy 39.721508 -238.638013) (xy 39.738547 -238.612908)
			(xy 39.747465 -238.583908) (xy 39.747952 -238.568738) (xy 39.747952 -236.814614) (xy 39.747395 -236.79945)
			(xy 39.738493 -236.770457) (xy 39.721468 -236.745358) (xy 39.697822 -236.726365) (xy 39.669642 -236.715154)
			(xy 39.639412 -236.712714) (xy 39.609798 -236.719259) (xy 39.596314 -236.726222) (xy 39.569344 -236.740826)
			(xy 39.511627 -236.761556) (xy 39.451209 -236.772072) (xy 39.420546 -236.772704) (xy 39.393893 -236.772234)
			(xy 39.341181 -236.764295) (xy 39.290242 -236.748588) (xy 39.242213 -236.725464) (xy 39.198167 -236.695439)
			(xy 39.159088 -236.659185) (xy 39.12585 -236.61751) (xy 39.099195 -236.571347) (xy 39.079719 -236.521726)
			(xy 39.067856 -236.469757) (xy 39.063872 -236.4166) (xy 39.067856 -236.363443) (xy 39.079719 -236.311474)
			(xy 39.099195 -236.261853) (xy 39.12585 -236.21569) (xy 39.159088 -236.174015) (xy 39.198167 -236.137761)
			(xy 39.242213 -236.107736) (xy 39.290242 -236.084612) (xy 39.341181 -236.068905) (xy 39.393893 -236.060966)
			(xy 39.420546 -236.060488) (xy 39.451206 -236.061153) (xy 39.511614 -236.071688) (xy 39.569335 -236.092389)
			(xy 39.596314 -236.10697) (xy 39.609791 -236.113959) (xy 39.63942 -236.120499) (xy 39.669664 -236.118056)
			(xy 39.697859 -236.106844) (xy 39.721521 -236.08785) (xy 39.738567 -236.062748) (xy 39.747494 -236.033749)
			(xy 39.747952 -236.018578) (xy 39.747952 -235.114592) (xy 39.747393 -235.09943) (xy 39.738486 -235.070444)
			(xy 39.721461 -235.04535) (xy 39.697818 -235.026363) (xy 39.669641 -235.015154) (xy 39.639416 -235.012714)
			(xy 39.609806 -235.019256) (xy 39.596314 -235.0262) (xy 39.569344 -235.040805) (xy 39.511628 -235.061536)
			(xy 39.451209 -235.072053) (xy 39.420546 -235.072682) (xy 39.393895 -235.072212) (xy 39.341186 -235.064274)
			(xy 39.29025 -235.048568) (xy 39.242224 -235.025445) (xy 39.19818 -234.995422) (xy 39.159104 -234.95917)
			(xy 39.125868 -234.917498) (xy 39.099215 -234.871337) (xy 39.07974 -234.82172) (xy 39.067878 -234.769754)
			(xy 39.063894 -234.7166) (xy 39.067878 -234.663446) (xy 39.07974 -234.61148) (xy 39.099215 -234.561863)
			(xy 39.125868 -234.515702) (xy 39.159104 -234.47403) (xy 39.19818 -234.437778) (xy 39.242224 -234.407755)
			(xy 39.29025 -234.384632) (xy 39.341186 -234.368926) (xy 39.393895 -234.360988) (xy 39.420546 -234.360466)
			(xy 39.451206 -234.361131) (xy 39.511615 -234.371666) (xy 39.569336 -234.392366) (xy 39.596314 -234.406948)
			(xy 39.60979 -234.413938) (xy 39.639418 -234.42048) (xy 39.669661 -234.418037) (xy 39.697854 -234.406824)
			(xy 39.721514 -234.387829) (xy 39.738556 -234.362726) (xy 39.747478 -234.333726) (xy 39.747952 -234.318556)
			(xy 39.747952 -233.414824) (xy 39.747397 -233.399659) (xy 39.738496 -233.370663) (xy 39.721471 -233.345561)
			(xy 39.697825 -233.326567) (xy 39.669642 -233.315355) (xy 39.63941 -233.312914) (xy 39.609794 -233.31946)
			(xy 39.596314 -233.326432) (xy 39.569344 -233.341035) (xy 39.511627 -233.361765) (xy 39.451209 -233.372281)
			(xy 39.420546 -233.372914) (xy 39.393892 -233.372444) (xy 39.341179 -233.364505) (xy 39.290238 -233.348798)
			(xy 39.242208 -233.325673) (xy 39.19816 -233.295647) (xy 39.159081 -233.259392) (xy 39.125842 -233.217716)
			(xy 39.099186 -233.171551) (xy 39.079709 -233.121929) (xy 39.067846 -233.069958) (xy 39.063862 -233.0168)
			(xy 39.067846 -232.963642) (xy 39.079709 -232.911671) (xy 39.099186 -232.862049) (xy 39.125842 -232.815884)
			(xy 39.159081 -232.774208) (xy 39.19816 -232.737953) (xy 39.242208 -232.707927) (xy 39.290238 -232.684802)
			(xy 39.341179 -232.669095) (xy 39.393892 -232.661156) (xy 39.420546 -232.660698) (xy 39.451206 -232.661363)
			(xy 39.511614 -232.671899) (xy 39.569335 -232.6926) (xy 39.596314 -232.70718) (xy 39.609787 -232.714173)
			(xy 39.63941 -232.72072) (xy 39.66965 -232.718278) (xy 39.697839 -232.707064) (xy 39.721492 -232.688065)
			(xy 39.738522 -232.662958) (xy 39.747428 -232.633957) (xy 39.747952 -232.618788) (xy 39.747952 -231.714802)
			(xy 39.747394 -231.699639) (xy 39.738489 -231.67065) (xy 39.721464 -231.645554) (xy 39.69782 -231.626564)
			(xy 39.669642 -231.615354) (xy 39.639414 -231.612914) (xy 39.609802 -231.619457) (xy 39.596314 -231.62641)
			(xy 39.569344 -231.641014) (xy 39.511628 -231.661745) (xy 39.451209 -231.672261) (xy 39.420546 -231.672892)
			(xy 39.393894 -231.672422) (xy 39.341184 -231.664484) (xy 39.290246 -231.648777) (xy 39.242219 -231.625654)
			(xy 39.198174 -231.59563) (xy 39.159097 -231.559377) (xy 39.12586 -231.517703) (xy 39.099206 -231.471542)
			(xy 39.07973 -231.421923) (xy 39.067868 -231.369955) (xy 39.063884 -231.3168) (xy 39.067868 -231.263645)
			(xy 39.07973 -231.211677) (xy 39.099206 -231.162058) (xy 39.12586 -231.115897) (xy 39.159097 -231.074223)
			(xy 39.198174 -231.03797) (xy 39.242219 -231.007946) (xy 39.290246 -230.984823) (xy 39.341184 -230.969116)
			(xy 39.393894 -230.961178) (xy 39.420546 -230.960676) (xy 39.451206 -230.961341) (xy 39.511615 -230.971876)
			(xy 39.569336 -230.992576) (xy 39.596314 -231.007158) (xy 39.609791 -231.014147) (xy 39.639419 -231.020689)
			(xy 39.669662 -231.018246) (xy 39.697856 -231.007033) (xy 39.721517 -230.988039) (xy 39.738561 -230.962936)
			(xy 39.747486 -230.933937) (xy 39.747952 -230.918766) (xy 39.747952 -230.01478) (xy 39.747391 -229.999619)
			(xy 39.738483 -229.970636) (xy 39.721457 -229.945546) (xy 39.697815 -229.926561) (xy 39.669641 -229.915354)
			(xy 39.639418 -229.912913) (xy 39.60981 -229.919454) (xy 39.596314 -229.926388) (xy 39.569343 -229.940989)
			(xy 39.511626 -229.961715) (xy 39.451209 -229.972229) (xy 39.420546 -229.97287) (xy 39.393895 -229.9724)
			(xy 39.341189 -229.964462) (xy 39.290254 -229.948757) (xy 39.24223 -229.925635) (xy 39.198188 -229.895613)
			(xy 39.159113 -229.859362) (xy 39.125878 -229.817691) (xy 39.099226 -229.771532) (xy 39.079751 -229.721916)
			(xy 39.06789 -229.669952) (xy 39.063906 -229.6168) (xy 39.06789 -229.563648) (xy 39.079751 -229.511684)
			(xy 39.099226 -229.462068) (xy 39.125878 -229.415909) (xy 39.159113 -229.374238) (xy 39.198188 -229.337987)
			(xy 39.24223 -229.307965) (xy 39.290254 -229.284843) (xy 39.341189 -229.269138) (xy 39.393895 -229.2612)
			(xy 39.420546 -229.260654) (xy 39.451206 -229.261319) (xy 39.511615 -229.271853) (xy 39.569337 -229.292553)
			(xy 39.596314 -229.307136) (xy 39.609789 -229.314126) (xy 39.639416 -229.320669) (xy 39.669659 -229.318227)
			(xy 39.697851 -229.307014) (xy 39.72151 -229.288018) (xy 39.73855 -229.262914) (xy 39.74747 -229.233914)
			(xy 39.747952 -229.218744) (xy 39.747952 -227.46462) (xy 39.747396 -227.449455) (xy 39.738494 -227.420461)
			(xy 39.72147 -227.39536) (xy 39.697824 -227.376366) (xy 39.669642 -227.365154) (xy 39.639411 -227.362714)
			(xy 39.609796 -227.36926) (xy 39.596314 -227.376228) (xy 39.569344 -227.390832) (xy 39.511627 -227.411561)
			(xy 39.451209 -227.422077) (xy 39.420546 -227.42271) (xy 39.393892 -227.42224) (xy 39.34118 -227.414301)
			(xy 39.29024 -227.398594) (xy 39.24221 -227.375469) (xy 39.198163 -227.345444) (xy 39.159084 -227.309189)
			(xy 39.125845 -227.267514) (xy 39.09919 -227.22135) (xy 39.079713 -227.171728) (xy 39.06785 -227.119758)
			(xy 39.063866 -227.0666) (xy 39.06785 -227.013442) (xy 39.079713 -226.961472) (xy 39.09919 -226.91185)
			(xy 39.125845 -226.865686) (xy 39.159084 -226.824011) (xy 39.198163 -226.787756) (xy 39.24221 -226.757731)
			(xy 39.29024 -226.734606) (xy 39.34118 -226.718899) (xy 39.393892 -226.71096) (xy 39.420546 -226.710494)
			(xy 39.451206 -226.711159) (xy 39.511614 -226.721694) (xy 39.569335 -226.742396) (xy 39.596314 -226.756976)
			(xy 39.609787 -226.763969) (xy 39.63941 -226.770516) (xy 39.669649 -226.768075) (xy 39.697838 -226.75686)
			(xy 39.72149 -226.737862) (xy 39.73852 -226.712754) (xy 39.747426 -226.683753) (xy 39.747952 -226.668584)
			(xy 39.747952 -225.764598) (xy 39.747393 -225.749435) (xy 39.738488 -225.720447) (xy 39.721463 -225.695352)
			(xy 39.697819 -225.676363) (xy 39.669641 -225.665154) (xy 39.639415 -225.662714) (xy 39.609804 -225.669257)
			(xy 39.596314 -225.676206) (xy 39.569344 -225.69081) (xy 39.511628 -225.711541) (xy 39.451209 -225.722058)
			(xy 39.420546 -225.722688) (xy 39.393894 -225.722218) (xy 39.341185 -225.71428) (xy 39.290248 -225.698574)
			(xy 39.242221 -225.67545) (xy 39.198177 -225.645427) (xy 39.1591 -225.609174) (xy 39.125863 -225.567501)
			(xy 39.099209 -225.52134) (xy 39.079734 -225.471722) (xy 39.067872 -225.419755) (xy 39.063888 -225.3666)
			(xy 39.067872 -225.313445) (xy 39.079734 -225.261478) (xy 39.099209 -225.21186) (xy 39.125863 -225.165699)
			(xy 39.1591 -225.124026) (xy 39.198177 -225.087773) (xy 39.242221 -225.05775) (xy 39.290248 -225.034626)
			(xy 39.341185 -225.01892) (xy 39.393894 -225.010982) (xy 39.420546 -225.010472) (xy 39.451206 -225.011137)
			(xy 39.511615 -225.021672) (xy 39.569336 -225.042372) (xy 39.596314 -225.056954) (xy 39.60979 -225.063944)
			(xy 39.639418 -225.070485) (xy 39.669661 -225.068042) (xy 39.697855 -225.056829) (xy 39.721516 -225.037835)
			(xy 39.738559 -225.012732) (xy 39.747483 -224.983733) (xy 39.747952 -224.968562) (xy 39.747952 -224.064576)
			(xy 39.74739 -224.049416) (xy 39.738481 -224.020434) (xy 39.721456 -223.995345) (xy 39.697814 -223.97636)
			(xy 39.669641 -223.965154) (xy 39.639418 -223.962713) (xy 39.609812 -223.969254) (xy 39.596314 -223.976184)
			(xy 39.569343 -223.990785) (xy 39.511626 -224.011512) (xy 39.451209 -224.022026) (xy 39.420546 -224.022666)
			(xy 39.393896 -224.022196) (xy 39.34119 -224.014258) (xy 39.290256 -223.998553) (xy 39.242232 -223.975431)
			(xy 39.19819 -223.94541) (xy 39.159116 -223.909159) (xy 39.125881 -223.867489) (xy 39.099229 -223.82133)
			(xy 39.079755 -223.771715) (xy 39.067893 -223.719751) (xy 39.06391 -223.6666) (xy 39.067893 -223.613449)
			(xy 39.079755 -223.561485) (xy 39.099229 -223.51187) (xy 39.125881 -223.465711) (xy 39.159116 -223.424041)
			(xy 39.19819 -223.38779) (xy 39.242232 -223.357769) (xy 39.290256 -223.334647) (xy 39.34119 -223.318942)
			(xy 39.393896 -223.311004) (xy 39.420546 -223.31045) (xy 39.451206 -223.311115) (xy 39.511615 -223.321649)
			(xy 39.569337 -223.342348) (xy 39.596314 -223.356932) (xy 39.609789 -223.363923) (xy 39.639416 -223.370466)
			(xy 39.669658 -223.368023) (xy 39.69785 -223.35681) (xy 39.721509 -223.337814) (xy 39.738548 -223.31271)
			(xy 39.747467 -223.28371) (xy 39.747952 -223.26854) (xy 39.747952 -222.364808) (xy 39.747395 -222.349644)
			(xy 39.738491 -222.320654) (xy 39.721466 -222.295556) (xy 39.697821 -222.276565) (xy 39.669642 -222.265354)
			(xy 39.639413 -222.262914) (xy 39.6098 -222.269458) (xy 39.596314 -222.276416) (xy 39.569344 -222.29102)
			(xy 39.511628 -222.31175) (xy 39.451209 -222.322267) (xy 39.420546 -222.322898) (xy 39.393893 -222.322428)
			(xy 39.341183 -222.31449) (xy 39.290244 -222.298783) (xy 39.242216 -222.275659) (xy 39.19817 -222.245635)
			(xy 39.159092 -222.209381) (xy 39.125855 -222.167707) (xy 39.0992 -222.121544) (xy 39.079724 -222.071925)
			(xy 39.067862 -222.019956) (xy 39.063878 -221.9668) (xy 39.067862 -221.913644) (xy 39.079724 -221.861675)
			(xy 39.0992 -221.812056) (xy 39.125855 -221.765893) (xy 39.159092 -221.724219) (xy 39.19817 -221.687965)
			(xy 39.242216 -221.657941) (xy 39.290244 -221.634817) (xy 39.341183 -221.61911) (xy 39.393893 -221.611172)
			(xy 39.420546 -221.610682) (xy 39.451206 -221.611347) (xy 39.511615 -221.621882) (xy 39.569335 -221.642583)
			(xy 39.596314 -221.657164) (xy 39.609791 -221.664153) (xy 39.639419 -221.670694) (xy 39.669663 -221.668251)
			(xy 39.697857 -221.657038) (xy 39.721519 -221.638044) (xy 39.738564 -221.612942) (xy 39.74749 -221.583943)
			(xy 39.747952 -221.568772) (xy 39.747952 -220.664786) (xy 39.747392 -220.649625) (xy 39.738484 -220.62064)
			(xy 39.721459 -220.595548) (xy 39.697816 -220.576562) (xy 39.669641 -220.565354) (xy 39.639417 -220.562914)
			(xy 39.609808 -220.569455) (xy 39.596314 -220.576394) (xy 39.569343 -220.590995) (xy 39.511626 -220.611721)
			(xy 39.451209 -220.622235) (xy 39.420546 -220.622876) (xy 39.393895 -220.622406) (xy 39.341188 -220.614468)
			(xy 39.290252 -220.598762) (xy 39.242227 -220.57564) (xy 39.198184 -220.545618) (xy 39.159109 -220.509366)
			(xy 39.125873 -220.467694) (xy 39.09922 -220.421535) (xy 39.079745 -220.371918) (xy 39.067884 -220.319953)
			(xy 39.0639 -220.2668) (xy 39.067884 -220.213647) (xy 39.079745 -220.161682) (xy 39.09922 -220.112065)
			(xy 39.125873 -220.065906) (xy 39.159109 -220.024234) (xy 39.198184 -219.987982) (xy 39.242227 -219.95796)
			(xy 39.290252 -219.934838) (xy 39.341188 -219.919132) (xy 39.393895 -219.911194) (xy 39.420546 -219.91066)
			(xy 39.451206 -219.911325) (xy 39.511615 -219.921859) (xy 39.569336 -219.942559) (xy 39.596314 -219.957142)
			(xy 39.60979 -219.964132) (xy 39.639417 -219.970675) (xy 39.66966 -219.968232) (xy 39.697853 -219.957019)
			(xy 39.721512 -219.938024) (xy 39.738553 -219.91292) (xy 39.747474 -219.88392) (xy 39.747952 -219.86875)
			(xy 39.747952 -218.114626) (xy 39.747397 -218.09946) (xy 39.738496 -218.070465) (xy 39.721472 -218.045362)
			(xy 39.697825 -218.026367) (xy 39.669643 -218.015155) (xy 39.63941 -218.012714) (xy 39.609794 -218.019261)
			(xy 39.596314 -218.026234) (xy 39.569344 -218.040837) (xy 39.511627 -218.061566) (xy 39.451209 -218.072082)
			(xy 39.420546 -218.072716) (xy 39.393892 -218.072246) (xy 39.341179 -218.064307) (xy 39.290237 -218.0486)
			(xy 39.242207 -218.025475) (xy 39.198159 -217.995449) (xy 39.159079 -217.959193) (xy 39.12584 -217.917517)
			(xy 39.099184 -217.871352) (xy 39.079707 -217.82173) (xy 39.067844 -217.769759) (xy 39.06386 -217.7166)
			(xy 39.067844 -217.663441) (xy 39.079707 -217.61147) (xy 39.099184 -217.561848) (xy 39.12584 -217.515683)
			(xy 39.159079 -217.474007) (xy 39.198159 -217.437751) (xy 39.242207 -217.407725) (xy 39.290237 -217.3846)
			(xy 39.341179 -217.368893) (xy 39.393892 -217.360954) (xy 39.420546 -217.3605) (xy 39.451206 -217.361165)
			(xy 39.511614 -217.371701) (xy 39.569335 -217.392402) (xy 39.596314 -217.406982) (xy 39.609787 -217.413975)
			(xy 39.63941 -217.420521) (xy 39.66965 -217.41808) (xy 39.697839 -217.406866) (xy 39.721492 -217.387867)
			(xy 39.738523 -217.36276) (xy 39.74743 -217.333759) (xy 39.747952 -217.31859) (xy 39.747952 -216.414604)
			(xy 39.747394 -216.399441) (xy 39.73849 -216.370451) (xy 39.721465 -216.345355) (xy 39.69782 -216.326364)
			(xy 39.669642 -216.315154) (xy 39.639414 -216.312714) (xy 39.609802 -216.319258) (xy 39.596314 -216.326212)
			(xy 39.569344 -216.340816) (xy 39.511628 -216.361547) (xy 39.451209 -216.372063) (xy 39.420546 -216.372694)
			(xy 39.393894 -216.372224) (xy 39.341184 -216.364286) (xy 39.290245 -216.348579) (xy 39.242218 -216.325456)
			(xy 39.198173 -216.295432) (xy 39.159095 -216.259178) (xy 39.125858 -216.217505) (xy 39.099204 -216.171343)
			(xy 39.079728 -216.121723) (xy 39.067866 -216.069755) (xy 39.063882 -216.0166) (xy 39.067866 -215.963445)
			(xy 39.079728 -215.911477) (xy 39.099204 -215.861857) (xy 39.125858 -215.815695) (xy 39.159095 -215.774022)
			(xy 39.198173 -215.737768) (xy 39.242218 -215.707744) (xy 39.290245 -215.684621) (xy 39.341184 -215.668914)
			(xy 39.393894 -215.660976) (xy 39.420546 -215.660478) (xy 39.451206 -215.661143) (xy 39.511615 -215.671678)
			(xy 39.569336 -215.692379) (xy 39.596314 -215.70696) (xy 39.609791 -215.713949) (xy 39.639419 -215.720491)
			(xy 39.669662 -215.718047) (xy 39.697857 -215.706835) (xy 39.721518 -215.687841) (xy 39.738562 -215.662738)
			(xy 39.747487 -215.633739) (xy 39.747952 -215.618568) (xy 39.747952 -214.714582) (xy 39.747391 -214.699421)
			(xy 39.738483 -214.670438) (xy 39.721458 -214.645347) (xy 39.697815 -214.626361) (xy 39.669641 -214.615154)
			(xy 39.639417 -214.612713) (xy 39.60981 -214.619255) (xy 39.596314 -214.62619) (xy 39.569343 -214.640791)
			(xy 39.511626 -214.661517) (xy 39.451209 -214.672031) (xy 39.420546 -214.672672) (xy 39.393895 -214.672202)
			(xy 39.341188 -214.664264) (xy 39.290254 -214.648559) (xy 39.242229 -214.625437) (xy 39.198187 -214.595414)
			(xy 39.159112 -214.559163) (xy 39.125876 -214.517492) (xy 39.099224 -214.471333) (xy 39.079749 -214.421717)
			(xy 39.067888 -214.369752) (xy 39.063904 -214.3166) (xy 39.067888 -214.263448) (xy 39.079749 -214.211483)
			(xy 39.099224 -214.161867) (xy 39.125876 -214.115708) (xy 39.159112 -214.074037) (xy 39.198187 -214.037786)
			(xy 39.242229 -214.007763) (xy 39.290254 -213.984641) (xy 39.341188 -213.968936) (xy 39.393895 -213.960998)
			(xy 39.420546 -213.960456) (xy 39.451206 -213.961121) (xy 39.511615 -213.971655) (xy 39.569337 -213.992355)
			(xy 39.596314 -214.006938) (xy 39.60979 -214.013928) (xy 39.639417 -214.020471) (xy 39.669659 -214.018028)
			(xy 39.697852 -214.006815) (xy 39.721511 -213.98782) (xy 39.738551 -213.962716) (xy 39.747471 -213.933716)
			(xy 39.747952 -213.918546) (xy 39.747952 -213.014814) (xy 39.747395 -212.99965) (xy 39.738493 -212.970657)
			(xy 39.721468 -212.945558) (xy 39.697822 -212.926565) (xy 39.669642 -212.915354) (xy 39.639412 -212.912914)
			(xy 39.609798 -212.919459) (xy 39.596314 -212.926422) (xy 39.569344 -212.941026) (xy 39.511627 -212.961756)
			(xy 39.451209 -212.972272) (xy 39.420546 -212.972904) (xy 39.393893 -212.972434) (xy 39.341181 -212.964495)
			(xy 39.290242 -212.948788) (xy 39.242213 -212.925664) (xy 39.198167 -212.895639) (xy 39.159088 -212.859385)
			(xy 39.12585 -212.81771) (xy 39.099195 -212.771547) (xy 39.079719 -212.721926) (xy 39.067856 -212.669957)
			(xy 39.063872 -212.6168) (xy 39.067856 -212.563643) (xy 39.079719 -212.511674) (xy 39.099195 -212.462053)
			(xy 39.12585 -212.41589) (xy 39.159088 -212.374215) (xy 39.198167 -212.337961) (xy 39.242213 -212.307936)
			(xy 39.290242 -212.284812) (xy 39.341181 -212.269105) (xy 39.393893 -212.261166) (xy 39.420546 -212.260688)
			(xy 39.451206 -212.261353) (xy 39.511614 -212.271888) (xy 39.569335 -212.292589) (xy 39.596314 -212.30717)
			(xy 39.609791 -212.314159) (xy 39.63942 -212.320699) (xy 39.669664 -212.318256) (xy 39.697859 -212.307044)
			(xy 39.721521 -212.28805) (xy 39.738567 -212.262948) (xy 39.747494 -212.233949) (xy 39.747952 -212.218778)
			(xy 39.747952 -211.314792) (xy 39.747393 -211.29963) (xy 39.738486 -211.270644) (xy 39.721461 -211.24555)
			(xy 39.697818 -211.226563) (xy 39.669641 -211.215354) (xy 39.639416 -211.212914) (xy 39.609806 -211.219456)
			(xy 39.596314 -211.2264) (xy 39.569344 -211.241005) (xy 39.511628 -211.261736) (xy 39.451209 -211.272253)
			(xy 39.420546 -211.272882) (xy 39.393895 -211.272412) (xy 39.341186 -211.264474) (xy 39.29025 -211.248768)
			(xy 39.242224 -211.225645) (xy 39.19818 -211.195622) (xy 39.159104 -211.15937) (xy 39.125868 -211.117698)
			(xy 39.099215 -211.071537) (xy 39.07974 -211.02192) (xy 39.067878 -210.969954) (xy 39.063894 -210.9168)
			(xy 39.067878 -210.863646) (xy 39.07974 -210.81168) (xy 39.099215 -210.762063) (xy 39.125868 -210.715902)
			(xy 39.159104 -210.67423) (xy 39.19818 -210.637978) (xy 39.242224 -210.607955) (xy 39.29025 -210.584832)
			(xy 39.341186 -210.569126) (xy 39.393895 -210.561188) (xy 39.420546 -210.560666) (xy 39.451206 -210.561331)
			(xy 39.511615 -210.571866) (xy 39.569336 -210.592566) (xy 39.596314 -210.607148) (xy 39.60979 -210.614138)
			(xy 39.639418 -210.62068) (xy 39.669661 -210.618237) (xy 39.697854 -210.607024) (xy 39.721514 -210.588029)
			(xy 39.738556 -210.562926) (xy 39.747478 -210.533926) (xy 39.747952 -210.518756) (xy 39.747952 -208.764632)
			(xy 39.747398 -208.749466) (xy 39.738498 -208.720468) (xy 39.721473 -208.695364) (xy 39.697826 -208.676368)
			(xy 39.669643 -208.665155) (xy 39.639409 -208.662714) (xy 39.609792 -208.669261) (xy 39.596314 -208.67624)
			(xy 39.569344 -208.690843) (xy 39.511627 -208.711572) (xy 39.451209 -208.722088) (xy 39.420546 -208.722722)
			(xy 39.393892 -208.722252) (xy 39.341177 -208.714313) (xy 39.290235 -208.698605) (xy 39.242204 -208.67548)
			(xy 39.198155 -208.645453) (xy 39.159075 -208.609197) (xy 39.125835 -208.56752) (xy 39.099179 -208.521355)
			(xy 39.079701 -208.471732) (xy 39.067838 -208.41976) (xy 39.063854 -208.3666) (xy 39.067838 -208.31344)
			(xy 39.079701 -208.261468) (xy 39.099179 -208.211845) (xy 39.125835 -208.16568) (xy 39.159075 -208.124003)
			(xy 39.198155 -208.087747) (xy 39.242204 -208.05772) (xy 39.290235 -208.034595) (xy 39.341177 -208.018887)
			(xy 39.393892 -208.010948) (xy 39.420546 -208.010506) (xy 39.451206 -208.011171) (xy 39.511614 -208.021707)
			(xy 39.569334 -208.042409) (xy 39.596314 -208.056988) (xy 39.609787 -208.063981) (xy 39.639411 -208.070527)
			(xy 39.669651 -208.068086) (xy 39.697841 -208.056871) (xy 39.721495 -208.037873) (xy 39.738527 -208.012767)
			(xy 39.747435 -207.983765) (xy 39.747952 -207.968596) (xy 39.747952 -207.06461) (xy 39.747395 -207.049446)
			(xy 39.738491 -207.020455) (xy 39.721466 -206.995357) (xy 39.697822 -206.976365) (xy 39.669642 -206.965154)
			(xy 39.639413 -206.962714) (xy 39.609799 -206.969258) (xy 39.596314 -206.976218) (xy 39.569344 -206.990822)
			(xy 39.511627 -207.011552) (xy 39.451209 -207.022068) (xy 39.420546 -207.0227) (xy 39.393893 -207.02223)
			(xy 39.341182 -207.014291) (xy 39.290243 -206.998585) (xy 39.242215 -206.975461) (xy 39.198169 -206.945436)
			(xy 39.159091 -206.909182) (xy 39.125853 -206.867508) (xy 39.099199 -206.821345) (xy 39.079722 -206.771725)
			(xy 39.06786 -206.719756) (xy 39.063876 -206.6666) (xy 39.06786 -206.613444) (xy 39.079722 -206.561475)
			(xy 39.099199 -206.511855) (xy 39.125853 -206.465692) (xy 39.159091 -206.424018) (xy 39.198169 -206.387764)
			(xy 39.242215 -206.357739) (xy 39.290243 -206.334615) (xy 39.341182 -206.318909) (xy 39.393893 -206.31097)
			(xy 39.420546 -206.310484) (xy 39.451206 -206.311149) (xy 39.511615 -206.321684) (xy 39.569335 -206.342385)
			(xy 39.596314 -206.356966) (xy 39.609791 -206.363955) (xy 39.63942 -206.370496) (xy 39.669663 -206.368052)
			(xy 39.697858 -206.35684) (xy 39.72152 -206.337846) (xy 39.738565 -206.312744) (xy 39.747491 -206.283745)
			(xy 39.747952 -206.268574) (xy 39.747952 -205.364588) (xy 39.747392 -205.349427) (xy 39.738485 -205.320441)
			(xy 39.721459 -205.295349) (xy 39.697817 -205.276362) (xy 39.669641 -205.265154) (xy 39.639416 -205.262714)
			(xy 39.609807 -205.269255) (xy 39.596314 -205.276196) (xy 39.569344 -205.290801) (xy 39.511628 -205.311532)
			(xy 39.45121 -205.322049) (xy 39.420546 -205.322678) (xy 39.393895 -205.322208) (xy 39.341187 -205.31427)
			(xy 39.290251 -205.298564) (xy 39.242226 -205.275442) (xy 39.198183 -205.245419) (xy 39.159107 -205.209167)
			(xy 39.125871 -205.167496) (xy 39.099218 -205.121336) (xy 39.079743 -205.071719) (xy 39.067882 -205.019753)
			(xy 39.063898 -204.9666) (xy 39.067882 -204.913447) (xy 39.079743 -204.861481) (xy 39.099218 -204.811864)
			(xy 39.125871 -204.765704) (xy 39.159107 -204.724033) (xy 39.198183 -204.687781) (xy 39.242226 -204.657758)
			(xy 39.290251 -204.634636) (xy 39.341187 -204.61893) (xy 39.393895 -204.610992) (xy 39.420546 -204.610462)
			(xy 39.451206 -204.611127) (xy 39.511615 -204.621661) (xy 39.569336 -204.642361) (xy 39.596314 -204.656944)
			(xy 39.60979 -204.663934) (xy 39.639417 -204.670476) (xy 39.66966 -204.668034) (xy 39.697853 -204.656821)
			(xy 39.721513 -204.637826) (xy 39.738554 -204.612722) (xy 39.747475 -204.583722) (xy 39.747952 -204.568552)
			(xy 39.747952 -203.66482) (xy 39.747396 -203.649655) (xy 39.738494 -203.620661) (xy 39.72147 -203.59556)
			(xy 39.697824 -203.576566) (xy 39.669642 -203.565354) (xy 39.639411 -203.562914) (xy 39.609796 -203.56946)
			(xy 39.596314 -203.576428) (xy 39.569344 -203.591032) (xy 39.511627 -203.611761) (xy 39.451209 -203.622277)
			(xy 39.420546 -203.62291) (xy 39.393892 -203.62244) (xy 39.34118 -203.614501) (xy 39.29024 -203.598794)
			(xy 39.24221 -203.575669) (xy 39.198163 -203.545644) (xy 39.159084 -203.509389) (xy 39.125845 -203.467714)
			(xy 39.09919 -203.42155) (xy 39.079713 -203.371928) (xy 39.06785 -203.319958) (xy 39.063866 -203.2668)
			(xy 39.06785 -203.213642) (xy 39.079713 -203.161672) (xy 39.09919 -203.11205) (xy 39.125845 -203.065886)
			(xy 39.159084 -203.024211) (xy 39.198163 -202.987956) (xy 39.24221 -202.957931) (xy 39.29024 -202.934806)
			(xy 39.34118 -202.919099) (xy 39.393892 -202.91116) (xy 39.420546 -202.910694) (xy 39.451206 -202.911359)
			(xy 39.511614 -202.921894) (xy 39.569335 -202.942596) (xy 39.596314 -202.957176) (xy 39.609787 -202.964169)
			(xy 39.63941 -202.970716) (xy 39.669649 -202.968275) (xy 39.697838 -202.95706) (xy 39.72149 -202.938062)
			(xy 39.73852 -202.912954) (xy 39.747426 -202.883953) (xy 39.747952 -202.868784) (xy 39.747952 -201.964798)
			(xy 39.747393 -201.949635) (xy 39.738488 -201.920647) (xy 39.721463 -201.895552) (xy 39.697819 -201.876563)
			(xy 39.669641 -201.865354) (xy 39.639415 -201.862914) (xy 39.609804 -201.869457) (xy 39.596314 -201.876406)
			(xy 39.569344 -201.89101) (xy 39.511628 -201.911741) (xy 39.451209 -201.922258) (xy 39.420546 -201.922888)
			(xy 39.393894 -201.922418) (xy 39.341185 -201.91448) (xy 39.290248 -201.898774) (xy 39.242221 -201.87565)
			(xy 39.198177 -201.845627) (xy 39.1591 -201.809374) (xy 39.125863 -201.767701) (xy 39.099209 -201.72154)
			(xy 39.079734 -201.671922) (xy 39.067872 -201.619955) (xy 39.063888 -201.5668) (xy 39.067872 -201.513645)
			(xy 39.079734 -201.461678) (xy 39.099209 -201.41206) (xy 39.125863 -201.365899) (xy 39.1591 -201.324226)
			(xy 39.198177 -201.287973) (xy 39.242221 -201.25795) (xy 39.290248 -201.234826) (xy 39.341185 -201.21912)
			(xy 39.393894 -201.211182) (xy 39.420546 -201.210672) (xy 39.451206 -201.211337) (xy 39.511615 -201.221872)
			(xy 39.569336 -201.242572) (xy 39.596314 -201.257154) (xy 39.60979 -201.264144) (xy 39.639418 -201.270685)
			(xy 39.669661 -201.268242) (xy 39.697855 -201.257029) (xy 39.721516 -201.238035) (xy 39.738559 -201.212932)
			(xy 39.747483 -201.183933) (xy 39.747952 -201.168762) (xy 39.747952 -199.414638) (xy 39.747399 -199.399471)
			(xy 39.7385 -199.370472) (xy 39.721475 -199.345366) (xy 39.697828 -199.326368) (xy 39.669643 -199.315155)
			(xy 39.639408 -199.312714) (xy 39.609789 -199.319262) (xy 39.596314 -199.326246) (xy 39.569344 -199.340849)
			(xy 39.511627 -199.361577) (xy 39.451209 -199.372093) (xy 39.420546 -199.372728) (xy 39.393891 -199.372258)
			(xy 39.341176 -199.364319) (xy 39.290233 -199.348611) (xy 39.242201 -199.325485) (xy 39.198152 -199.295458)
			(xy 39.159071 -199.259201) (xy 39.12583 -199.217524) (xy 39.099173 -199.171357) (xy 39.079696 -199.121733)
			(xy 39.067832 -199.069761) (xy 39.063848 -199.0166) (xy 39.067832 -198.963439) (xy 39.079696 -198.911467)
			(xy 39.099173 -198.861843) (xy 39.12583 -198.815676) (xy 39.159071 -198.773999) (xy 39.198152 -198.737742)
			(xy 39.242201 -198.707715) (xy 39.290233 -198.684589) (xy 39.341176 -198.668881) (xy 39.393891 -198.660942)
			(xy 39.420546 -198.660512) (xy 39.451206 -198.661177) (xy 39.511614 -198.671713) (xy 39.569334 -198.692415)
			(xy 39.596314 -198.706994) (xy 39.609787 -198.713986) (xy 39.639412 -198.720532) (xy 39.669652 -198.718091)
			(xy 39.697842 -198.706877) (xy 39.721497 -198.687879) (xy 39.73853 -198.662773) (xy 39.747439 -198.633771)
			(xy 39.747952 -198.618602) (xy 39.747952 -198.006716) (xy 40.651938 -197.10273) (xy 40.651938 -193.40703)
			(xy 43.190922 -190.868046) (xy 50.071274 -190.868046) (xy 53.41874 -187.52058) (xy 53.41874 -186.373516)
			(xy 53.418276 -186.359338) (xy 53.410486 -186.332073) (xy 53.395502 -186.307999) (xy 53.374477 -186.288972)
			(xy 53.349033 -186.276456) (xy 53.321128 -186.271417) (xy 53.30698 -186.272424) (xy 53.26888 -186.274456)
			(xy 53.239964 -186.27392) (xy 53.182796 -186.26519) (xy 53.1276 -186.247932) (xy 53.07564 -186.222543)
			(xy 53.028107 -186.189603) (xy 52.986089 -186.149867) (xy 52.96789 -186.12739) (xy 52.957993 -186.115585)
			(xy 52.932669 -186.098066) (xy 52.903276 -186.08889) (xy 52.872484 -186.08889) (xy 52.843091 -186.098066)
			(xy 52.817767 -186.115585) (xy 52.80787 -186.12739) (xy 52.789681 -186.149876) (xy 52.747665 -186.189619)
			(xy 52.700131 -186.222564) (xy 52.648169 -186.247956) (xy 52.592969 -186.265213) (xy 52.535797 -186.27394)
			(xy 52.50688 -186.274456) (xy 52.480852 -186.274013) (xy 52.42928 -186.266935) (xy 52.379148 -186.252913)
			(xy 52.331387 -186.232207) (xy 52.286884 -186.205202) (xy 52.246465 -186.172399) (xy 52.210879 -186.134406)
			(xy 52.195476 -186.11342) (xy 52.187272 -186.102595) (xy 52.166281 -186.085372) (xy 52.141492 -186.074292)
			(xy 52.114659 -186.070139) (xy 52.087681 -186.073206) (xy 52.062465 -186.083277) (xy 52.040797 -186.099639)
			(xy 52.032154 -186.110118) (xy 52.013971 -186.132875) (xy 51.97187 -186.173129) (xy 51.92414 -186.206517)
			(xy 51.871891 -186.232263) (xy 51.816335 -186.249769) (xy 51.758764 -186.258627) (xy 51.72964 -186.259216)
			(xy 51.702385 -186.258755) (xy 51.648428 -186.251003) (xy 51.596125 -186.23565) (xy 51.546538 -186.213009)
			(xy 51.500679 -186.183542) (xy 51.459481 -186.147847) (xy 51.423782 -186.106653) (xy 51.39431 -186.060797)
			(xy 51.371664 -186.011213) (xy 51.356306 -185.958911) (xy 51.348547 -185.904955) (xy 51.348547 -185.850445)
			(xy 51.356306 -185.796489) (xy 51.371664 -185.744187) (xy 51.39431 -185.694603) (xy 51.423782 -185.648747)
			(xy 51.459481 -185.607553) (xy 51.500679 -185.571858) (xy 51.546538 -185.542391) (xy 51.596125 -185.51975)
			(xy 51.648428 -185.504397) (xy 51.702385 -185.496645) (xy 51.72964 -185.4962) (xy 51.755668 -185.496644)
			(xy 51.80724 -185.503724) (xy 51.857371 -185.517747) (xy 51.905131 -185.538453) (xy 51.949634 -185.565457)
			(xy 51.990055 -185.598259) (xy 52.025642 -185.63625) (xy 52.041044 -185.657236) (xy 52.049251 -185.668054)
			(xy 52.070243 -185.685262) (xy 52.095028 -185.696331) (xy 52.121853 -185.700478) (xy 52.148823 -185.69741)
			(xy 52.174031 -185.687343) (xy 52.195696 -185.670991) (xy 52.204366 -185.660538) (xy 52.222546 -185.637774)
			(xy 52.264642 -185.597505) (xy 52.312369 -185.564102) (xy 52.364619 -185.538342) (xy 52.420177 -185.520822)
			(xy 52.477753 -185.51195) (xy 52.50688 -185.51144) (xy 52.535797 -185.511973) (xy 52.592969 -185.520698)
			(xy 52.648169 -185.537951) (xy 52.700134 -185.563337) (xy 52.747672 -185.596275) (xy 52.789694 -185.636009)
			(xy 52.80787 -185.658506) (xy 52.817767 -185.670311) (xy 52.843091 -185.68783) (xy 52.872484 -185.697006)
			(xy 52.903276 -185.697006) (xy 52.932669 -185.68783) (xy 52.957993 -185.670311) (xy 52.96789 -185.658506)
			(xy 52.986081 -185.636023) (xy 53.028099 -185.596288) (xy 53.075634 -185.563351) (xy 53.127596 -185.537967)
			(xy 53.182795 -185.520719) (xy 53.239964 -185.512001) (xy 53.26888 -185.51144) (xy 53.30698 -185.513472)
			(xy 53.321126 -185.51442) (xy 53.349014 -185.509384) (xy 53.374443 -185.496876) (xy 53.395455 -185.477859)
			(xy 53.41043 -185.453799) (xy 53.418215 -185.42655) (xy 53.41874 -185.41238) (xy 53.41874 -184.836816)
			(xy 52.802282 -184.220358) (xy 30.039056 -184.220358) (xy 29.582364 -184.67705) (xy 29.582364 -186.146948)
			(xy 50.346862 -186.146948) (xy 50.350933 -186.091326) (xy 50.363059 -186.036889) (xy 50.382982 -185.984798)
			(xy 50.410278 -185.936163) (xy 50.444364 -185.89202) (xy 50.484513 -185.853311) (xy 50.529871 -185.82086)
			(xy 50.579471 -185.795359) (xy 50.632255 -185.777352) (xy 50.687098 -185.767222) (xy 50.742832 -185.765185)
			(xy 50.798269 -185.771285) (xy 50.852226 -185.785391) (xy 50.903555 -185.807203) (xy 50.951161 -185.836257)
			(xy 50.994029 -185.871932) (xy 51.031246 -185.913469) (xy 51.062019 -185.959982) (xy 51.085691 -186.010479)
			(xy 51.101759 -186.063886) (xy 51.109879 -186.119062) (xy 51.110388 -186.146948) (xy 51.109879 -186.174834)
			(xy 51.101759 -186.23001) (xy 51.085691 -186.283417) (xy 51.062019 -186.333914) (xy 51.031246 -186.380427)
			(xy 50.994029 -186.421964) (xy 50.951161 -186.457639) (xy 50.903555 -186.486693) (xy 50.852226 -186.508505)
			(xy 50.798269 -186.522611) (xy 50.742832 -186.528711) (xy 50.687098 -186.526674) (xy 50.632255 -186.516544)
			(xy 50.579471 -186.498537) (xy 50.529871 -186.473036) (xy 50.484513 -186.440585) (xy 50.444364 -186.401876)
			(xy 50.410278 -186.357733) (xy 50.382982 -186.309098) (xy 50.363059 -186.257007) (xy 50.350933 -186.20257)
			(xy 50.346862 -186.146948) (xy 29.582364 -186.146948) (xy 29.582364 -187.825144) (xy 50.220926 -187.825144)
			(xy 50.220926 -187.770651) (xy 50.228682 -187.716712) (xy 50.244034 -187.664426) (xy 50.266671 -187.614856)
			(xy 50.296132 -187.569013) (xy 50.331817 -187.527829) (xy 50.372999 -187.492142) (xy 50.418841 -187.462679)
			(xy 50.468409 -187.44004) (xy 50.520695 -187.424685) (xy 50.574633 -187.416928) (xy 50.60188 -187.41644)
			(xy 50.61616 -187.416594) (xy 50.644637 -187.418753) (xy 50.658776 -187.420758) (xy 50.672463 -187.422461)
			(xy 50.699839 -187.419145) (xy 50.725325 -187.408615) (xy 50.747058 -187.391641) (xy 50.763448 -187.369464)
			(xy 50.773297 -187.343707) (xy 50.775884 -187.316253) (xy 50.771021 -187.289109) (xy 50.765456 -187.276486)
			(xy 50.753743 -187.250691) (xy 50.737209 -187.196507) (xy 50.72887 -187.140474) (xy 50.728372 -187.112148)
			(xy 50.728804 -187.084891) (xy 50.736555 -187.03093) (xy 50.751908 -186.978622) (xy 50.774549 -186.929031)
			(xy 50.804017 -186.883167) (xy 50.839712 -186.841964) (xy 50.880908 -186.806261) (xy 50.926766 -186.776784)
			(xy 50.976353 -186.754134) (xy 51.028658 -186.738771) (xy 51.082617 -186.731009) (xy 51.137132 -186.731005)
			(xy 51.191092 -186.73876) (xy 51.2434 -186.754116) (xy 51.292989 -186.77676) (xy 51.338851 -186.80623)
			(xy 51.380052 -186.841928) (xy 51.415753 -186.883127) (xy 51.445227 -186.928986) (xy 51.467874 -186.978574)
			(xy 51.483234 -187.03088) (xy 51.490993 -187.08484) (xy 51.490993 -187.113947) (xy 51.744926 -187.113947)
			(xy 51.744926 -187.059453) (xy 51.752681 -187.005514) (xy 51.768033 -186.953227) (xy 51.79067 -186.903658)
			(xy 51.820131 -186.857814) (xy 51.855816 -186.81663) (xy 51.896998 -186.780943) (xy 51.94284 -186.75148)
			(xy 51.992409 -186.72884) (xy 52.044694 -186.713485) (xy 52.098633 -186.705728) (xy 52.12588 -186.70524)
			(xy 52.153121 -186.705696) (xy 52.20705 -186.713445) (xy 52.259328 -186.728787) (xy 52.308892 -186.751411)
			(xy 52.354732 -186.780856) (xy 52.395917 -186.816523) (xy 52.431609 -186.857687) (xy 52.461081 -186.90351)
			(xy 52.483734 -186.95306) (xy 52.499107 -187.005329) (xy 52.506888 -187.059253) (xy 52.507388 -187.086494)
			(xy 52.507798 -187.099882) (xy 52.514833 -187.125718) (xy 52.528343 -187.148838) (xy 52.547397 -187.167651)
			(xy 52.570688 -187.180864) (xy 52.596612 -187.187569) (xy 52.610004 -187.18784) (xy 52.61356 -187.18784)
			(xy 52.640818 -187.188204) (xy 52.69478 -187.195958) (xy 52.74709 -187.211312) (xy 52.796681 -187.233955)
			(xy 52.842545 -187.263426) (xy 52.883748 -187.299124) (xy 52.91945 -187.340323) (xy 52.948926 -187.386184)
			(xy 52.971574 -187.435773) (xy 52.986934 -187.488081) (xy 52.994693 -187.542042) (xy 52.994693 -187.596558)
			(xy 52.986934 -187.650519) (xy 52.971574 -187.702827) (xy 52.948926 -187.752416) (xy 52.91945 -187.798277)
			(xy 52.883748 -187.839476) (xy 52.842545 -187.875174) (xy 52.796681 -187.904645) (xy 52.74709 -187.927288)
			(xy 52.69478 -187.942642) (xy 52.640818 -187.950396) (xy 52.61356 -187.950856) (xy 52.586321 -187.95036)
			(xy 52.532399 -187.942606) (xy 52.480128 -187.927261) (xy 52.43057 -187.904638) (xy 52.384735 -187.875195)
			(xy 52.343553 -187.839533) (xy 52.307862 -187.798375) (xy 52.278388 -187.75256) (xy 52.25573 -187.703018)
			(xy 52.24035 -187.650757) (xy 52.232558 -187.59684) (xy 52.232052 -187.569602) (xy 52.231618 -187.556214)
			(xy 52.224601 -187.530372) (xy 52.2111 -187.507245) (xy 52.192048 -187.488428) (xy 52.168756 -187.475217)
			(xy 52.142829 -187.468521) (xy 52.129436 -187.468256) (xy 52.12588 -187.468256) (xy 52.098633 -187.467672)
			(xy 52.044694 -187.459915) (xy 51.992409 -187.44456) (xy 51.94284 -187.42192) (xy 51.896998 -187.392457)
			(xy 51.855816 -187.35677) (xy 51.820131 -187.315586) (xy 51.79067 -187.269742) (xy 51.768033 -187.220173)
			(xy 51.752681 -187.167886) (xy 51.744926 -187.113947) (xy 51.490993 -187.113947) (xy 51.490993 -187.139355)
			(xy 51.483235 -187.193314) (xy 51.467876 -187.245621) (xy 51.44523 -187.295209) (xy 51.415756 -187.341069)
			(xy 51.380056 -187.382268) (xy 51.338855 -187.417966) (xy 51.292994 -187.447438) (xy 51.243405 -187.470082)
			(xy 51.191098 -187.485439) (xy 51.137137 -187.493194) (xy 51.10988 -187.493656) (xy 51.0956 -187.493507)
			(xy 51.067123 -187.491345) (xy 51.052984 -187.489338) (xy 51.03929 -187.487695) (xy 51.011917 -187.490998)
			(xy 50.986432 -187.501517) (xy 50.964698 -187.518481) (xy 50.948307 -187.540651) (xy 50.938458 -187.566403)
			(xy 50.935872 -187.593852) (xy 50.940737 -187.62099) (xy 50.946304 -187.63361) (xy 50.958019 -187.659404)
			(xy 50.974551 -187.713589) (xy 50.98289 -187.769622) (xy 50.983388 -187.797948) (xy 50.98287 -187.825195)
			(xy 50.975109 -187.879133) (xy 50.95975 -187.931417) (xy 50.937107 -187.980984) (xy 50.907641 -188.026823)
			(xy 50.871951 -188.068003) (xy 50.830765 -188.103685) (xy 50.784919 -188.133142) (xy 50.735348 -188.155776)
			(xy 50.683061 -188.171124) (xy 50.629121 -188.178876) (xy 50.574628 -188.178872) (xy 50.52069 -188.171114)
			(xy 50.468404 -188.155758) (xy 50.418836 -188.133118) (xy 50.372995 -188.103655) (xy 50.331813 -188.067967)
			(xy 50.296129 -188.026783) (xy 50.266668 -187.980939) (xy 50.244032 -187.931369) (xy 50.22868 -187.879083)
			(xy 50.220926 -187.825144) (xy 29.582364 -187.825144) (xy 29.582364 -189.158975) (xy 31.285196 -189.158975)
			(xy 31.285196 -189.074425) (xy 31.292997 -188.990236) (xy 31.308533 -188.907126) (xy 31.331671 -188.825804)
			(xy 31.362213 -188.746963) (xy 31.3999 -188.671277) (xy 31.444409 -188.599391) (xy 31.495361 -188.531919)
			(xy 31.552321 -188.469435) (xy 31.614803 -188.412474) (xy 31.682275 -188.36152) (xy 31.75416 -188.31701)
			(xy 31.829845 -188.279321) (xy 31.908685 -188.248777) (xy 31.990007 -188.225638) (xy 32.073116 -188.2101)
			(xy 32.157305 -188.202297) (xy 32.19958 -188.201808) (xy 33.44418 -188.201808) (xy 33.486458 -188.202248)
			(xy 33.570654 -188.210049) (xy 33.653771 -188.225584) (xy 33.7351 -188.248723) (xy 33.813947 -188.279267)
			(xy 33.889639 -188.316955) (xy 33.961531 -188.361468) (xy 34.029009 -188.412423) (xy 34.091498 -188.469388)
			(xy 34.148464 -188.531875) (xy 34.199421 -188.599352) (xy 34.243935 -188.671243) (xy 34.281625 -188.746935)
			(xy 34.312171 -188.825781) (xy 34.335311 -188.90711) (xy 34.350849 -188.990226) (xy 34.358651 -189.074422)
			(xy 34.358651 -189.158975) (xy 38.828996 -189.158975) (xy 38.828996 -189.074425) (xy 38.836797 -188.990236)
			(xy 38.852333 -188.907126) (xy 38.875471 -188.825804) (xy 38.906013 -188.746963) (xy 38.9437 -188.671277)
			(xy 38.988209 -188.599391) (xy 39.039161 -188.531919) (xy 39.096121 -188.469435) (xy 39.158603 -188.412474)
			(xy 39.226075 -188.36152) (xy 39.29796 -188.31701) (xy 39.373645 -188.279321) (xy 39.452485 -188.248777)
			(xy 39.533807 -188.225638) (xy 39.616916 -188.2101) (xy 39.701105 -188.202297) (xy 39.74338 -188.201808)
			(xy 40.98798 -188.201808) (xy 41.030258 -188.202248) (xy 41.114454 -188.210049) (xy 41.197571 -188.225584)
			(xy 41.2789 -188.248723) (xy 41.357747 -188.279267) (xy 41.433439 -188.316955) (xy 41.505331 -188.361468)
			(xy 41.572809 -188.412423) (xy 41.635298 -188.469388) (xy 41.692264 -188.531875) (xy 41.743221 -188.599352)
			(xy 41.787735 -188.671243) (xy 41.825425 -188.746935) (xy 41.855971 -188.825781) (xy 41.879111 -188.90711)
			(xy 41.894649 -188.990226) (xy 41.902451 -189.074422) (xy 41.902451 -189.158975) (xy 46.372796 -189.158975)
			(xy 46.372796 -189.074425) (xy 46.380597 -188.990236) (xy 46.396133 -188.907126) (xy 46.419271 -188.825804)
			(xy 46.449813 -188.746963) (xy 46.4875 -188.671277) (xy 46.532009 -188.599391) (xy 46.582961 -188.531919)
			(xy 46.639921 -188.469435) (xy 46.702403 -188.412474) (xy 46.769875 -188.36152) (xy 46.84176 -188.31701)
			(xy 46.917445 -188.279321) (xy 46.996285 -188.248777) (xy 47.077607 -188.225638) (xy 47.160716 -188.2101)
			(xy 47.244905 -188.202297) (xy 47.28718 -188.201808) (xy 48.53178 -188.201808) (xy 48.574058 -188.202248)
			(xy 48.658254 -188.210049) (xy 48.741371 -188.225584) (xy 48.8227 -188.248723) (xy 48.901547 -188.279267)
			(xy 48.977239 -188.316955) (xy 49.049131 -188.361468) (xy 49.116609 -188.412423) (xy 49.179098 -188.469388)
			(xy 49.236064 -188.531875) (xy 49.287021 -188.599352) (xy 49.331535 -188.671243) (xy 49.369225 -188.746935)
			(xy 49.399771 -188.825781) (xy 49.422911 -188.90711) (xy 49.438449 -188.990226) (xy 49.446251 -189.074422)
			(xy 49.446251 -189.158978) (xy 49.438449 -189.243174) (xy 49.422911 -189.32629) (xy 49.399771 -189.407619)
			(xy 49.369225 -189.486465) (xy 49.331535 -189.562157) (xy 49.287021 -189.634048) (xy 49.236064 -189.701525)
			(xy 49.179098 -189.764012) (xy 49.116609 -189.820977) (xy 49.049131 -189.871932) (xy 48.977239 -189.916445)
			(xy 48.901547 -189.954133) (xy 48.8227 -189.984677) (xy 48.741371 -190.007816) (xy 48.658254 -190.023351)
			(xy 48.574058 -190.031152) (xy 48.53178 -190.031624) (xy 47.28718 -190.031624) (xy 47.244905 -190.031103)
			(xy 47.160716 -190.0233) (xy 47.077607 -190.007762) (xy 46.996285 -189.984623) (xy 46.917445 -189.954079)
			(xy 46.84176 -189.91639) (xy 46.769875 -189.87188) (xy 46.702403 -189.820926) (xy 46.639921 -189.763965)
			(xy 46.582961 -189.701481) (xy 46.532009 -189.634009) (xy 46.4875 -189.562123) (xy 46.449813 -189.486437)
			(xy 46.419271 -189.407596) (xy 46.396133 -189.326274) (xy 46.380597 -189.243164) (xy 46.372796 -189.158975)
			(xy 41.902451 -189.158975) (xy 41.902451 -189.158978) (xy 41.894649 -189.243174) (xy 41.879111 -189.32629)
			(xy 41.855971 -189.407619) (xy 41.825425 -189.486465) (xy 41.787735 -189.562157) (xy 41.743221 -189.634048)
			(xy 41.692264 -189.701525) (xy 41.635298 -189.764012) (xy 41.572809 -189.820977) (xy 41.505331 -189.871932)
			(xy 41.433439 -189.916445) (xy 41.357747 -189.954133) (xy 41.2789 -189.984677) (xy 41.197571 -190.007816)
			(xy 41.114454 -190.023351) (xy 41.030258 -190.031152) (xy 40.98798 -190.031624) (xy 39.74338 -190.031624)
			(xy 39.701105 -190.031103) (xy 39.616916 -190.0233) (xy 39.533807 -190.007762) (xy 39.452485 -189.984623)
			(xy 39.373645 -189.954079) (xy 39.29796 -189.91639) (xy 39.226075 -189.87188) (xy 39.158603 -189.820926)
			(xy 39.096121 -189.763965) (xy 39.039161 -189.701481) (xy 38.988209 -189.634009) (xy 38.9437 -189.562123)
			(xy 38.906013 -189.486437) (xy 38.875471 -189.407596) (xy 38.852333 -189.326274) (xy 38.836797 -189.243164)
			(xy 38.828996 -189.158975) (xy 34.358651 -189.158975) (xy 34.358651 -189.158978) (xy 34.350849 -189.243174)
			(xy 34.335311 -189.32629) (xy 34.312171 -189.407619) (xy 34.281625 -189.486465) (xy 34.243935 -189.562157)
			(xy 34.199421 -189.634048) (xy 34.148464 -189.701525) (xy 34.091498 -189.764012) (xy 34.029009 -189.820977)
			(xy 33.961531 -189.871932) (xy 33.889639 -189.916445) (xy 33.813947 -189.954133) (xy 33.7351 -189.984677)
			(xy 33.653771 -190.007816) (xy 33.570654 -190.023351) (xy 33.486458 -190.031152) (xy 33.44418 -190.031624)
			(xy 32.19958 -190.031624) (xy 32.157305 -190.031103) (xy 32.073116 -190.0233) (xy 31.990007 -190.007762)
			(xy 31.908685 -189.984623) (xy 31.829845 -189.954079) (xy 31.75416 -189.91639) (xy 31.682275 -189.87188)
			(xy 31.614803 -189.820926) (xy 31.552321 -189.763965) (xy 31.495361 -189.701481) (xy 31.444409 -189.634009)
			(xy 31.3999 -189.562123) (xy 31.362213 -189.486437) (xy 31.331671 -189.407596) (xy 31.308533 -189.326274)
			(xy 31.292997 -189.243164) (xy 31.285196 -189.158975) (xy 29.582364 -189.158975) (xy 29.582364 -192.045082)
			(xy 30.061408 -192.524126) (xy 37.94074 -192.524126) (xy 37.944811 -192.468504) (xy 37.956937 -192.414067)
			(xy 37.97686 -192.361976) (xy 38.004156 -192.313341) (xy 38.038242 -192.269198) (xy 38.078391 -192.230489)
			(xy 38.123749 -192.198038) (xy 38.173349 -192.172537) (xy 38.226133 -192.15453) (xy 38.280976 -192.1444)
			(xy 38.33671 -192.142363) (xy 38.392147 -192.148463) (xy 38.446104 -192.162569) (xy 38.497433 -192.184381)
			(xy 38.545039 -192.213435) (xy 38.587907 -192.24911) (xy 38.625124 -192.290647) (xy 38.655897 -192.33716)
			(xy 38.679569 -192.387657) (xy 38.695637 -192.441064) (xy 38.703757 -192.49624) (xy 38.704266 -192.524126)
			(xy 38.703757 -192.552012) (xy 38.695637 -192.607188) (xy 38.679569 -192.660595) (xy 38.655897 -192.711092)
			(xy 38.625124 -192.757605) (xy 38.587907 -192.799142) (xy 38.545039 -192.834817) (xy 38.497433 -192.863871)
			(xy 38.446104 -192.885683) (xy 38.392147 -192.899789) (xy 38.33671 -192.905889) (xy 38.280976 -192.903852)
			(xy 38.226133 -192.893722) (xy 38.173349 -192.875715) (xy 38.123749 -192.850214) (xy 38.078391 -192.817763)
			(xy 38.038242 -192.779054) (xy 38.004156 -192.734911) (xy 37.97686 -192.686276) (xy 37.956937 -192.634185)
			(xy 37.944811 -192.579748) (xy 37.94074 -192.524126) (xy 30.061408 -192.524126) (xy 30.710632 -193.17335)
			(xy 33.3916 -193.17335) (xy 33.395671 -193.117728) (xy 33.407797 -193.063291) (xy 33.42772 -193.0112)
			(xy 33.455016 -192.962565) (xy 33.489102 -192.918422) (xy 33.529251 -192.879713) (xy 33.574609 -192.847262)
			(xy 33.624209 -192.821761) (xy 33.676993 -192.803754) (xy 33.731836 -192.793624) (xy 33.78757 -192.791587)
			(xy 33.843007 -192.797687) (xy 33.896964 -192.811793) (xy 33.948293 -192.833605) (xy 33.995899 -192.862659)
			(xy 34.038767 -192.898334) (xy 34.075984 -192.939871) (xy 34.106757 -192.986384) (xy 34.130429 -193.036881)
			(xy 34.146497 -193.090288) (xy 34.154617 -193.145464) (xy 34.155126 -193.17335) (xy 34.154617 -193.201236)
			(xy 34.146497 -193.256412) (xy 34.130429 -193.309819) (xy 34.106757 -193.360316) (xy 34.075984 -193.406829)
			(xy 34.038767 -193.448366) (xy 33.995899 -193.484041) (xy 33.948293 -193.513095) (xy 33.896964 -193.534907)
			(xy 33.843007 -193.549013) (xy 33.78757 -193.555113) (xy 33.731836 -193.553076) (xy 33.676993 -193.542946)
			(xy 33.624209 -193.524939) (xy 33.574609 -193.499438) (xy 33.529251 -193.466987) (xy 33.489102 -193.428278)
			(xy 33.455016 -193.384135) (xy 33.42772 -193.3355) (xy 33.407797 -193.283409) (xy 33.395671 -193.228972)
			(xy 33.3916 -193.17335) (xy 30.710632 -193.17335) (xy 32.330623 -194.793341) (xy 33.411404 -194.793341)
			(xy 33.411404 -194.740043) (xy 33.419347 -194.687339) (xy 33.435057 -194.636409) (xy 33.458183 -194.588388)
			(xy 33.488207 -194.544351) (xy 33.524459 -194.50528) (xy 33.56613 -194.472049) (xy 33.612288 -194.4454)
			(xy 33.661902 -194.425928) (xy 33.713864 -194.414068) (xy 33.767014 -194.410085) (xy 33.820164 -194.414068)
			(xy 33.872126 -194.425928) (xy 33.92174 -194.4454) (xy 33.967898 -194.472049) (xy 34.009569 -194.50528)
			(xy 34.045821 -194.544351) (xy 34.075845 -194.588388) (xy 34.098971 -194.636409) (xy 34.114681 -194.687339)
			(xy 34.122624 -194.740043) (xy 34.123122 -194.766692) (xy 34.122624 -194.793341) (xy 35.621204 -194.793341)
			(xy 35.621204 -194.740043) (xy 35.629147 -194.687339) (xy 35.644857 -194.636409) (xy 35.667983 -194.588388)
			(xy 35.698007 -194.544351) (xy 35.734259 -194.50528) (xy 35.77593 -194.472049) (xy 35.822088 -194.4454)
			(xy 35.871702 -194.425928) (xy 35.923664 -194.414068) (xy 35.976814 -194.410085) (xy 36.029964 -194.414068)
			(xy 36.081926 -194.425928) (xy 36.13154 -194.4454) (xy 36.177698 -194.472049) (xy 36.219369 -194.50528)
			(xy 36.255621 -194.544351) (xy 36.285645 -194.588388) (xy 36.308771 -194.636409) (xy 36.324481 -194.687339)
			(xy 36.332424 -194.740043) (xy 36.332922 -194.766692) (xy 36.332533 -194.787499) (xy 36.821608 -194.787499)
			(xy 36.821608 -194.734201) (xy 36.829551 -194.681497) (xy 36.845261 -194.630567) (xy 36.868387 -194.582546)
			(xy 36.898411 -194.538509) (xy 36.934663 -194.499438) (xy 36.976334 -194.466207) (xy 37.022492 -194.439558)
			(xy 37.072106 -194.420086) (xy 37.124068 -194.408226) (xy 37.177218 -194.404243) (xy 37.230368 -194.408226)
			(xy 37.28233 -194.420086) (xy 37.331944 -194.439558) (xy 37.378102 -194.466207) (xy 37.419773 -194.499438)
			(xy 37.456025 -194.538509) (xy 37.486049 -194.582546) (xy 37.509175 -194.630567) (xy 37.524885 -194.681497)
			(xy 37.532828 -194.734201) (xy 37.533326 -194.76085) (xy 37.532828 -194.787499) (xy 37.524885 -194.840203)
			(xy 37.509175 -194.891133) (xy 37.486049 -194.939154) (xy 37.456025 -194.983191) (xy 37.419773 -195.022262)
			(xy 37.378102 -195.055493) (xy 37.331944 -195.082142) (xy 37.28233 -195.101614) (xy 37.230368 -195.113474)
			(xy 37.177218 -195.117458) (xy 37.124068 -195.113474) (xy 37.072106 -195.101614) (xy 37.022492 -195.082142)
			(xy 36.976334 -195.055493) (xy 36.934663 -195.022262) (xy 36.898411 -194.983191) (xy 36.868387 -194.939154)
			(xy 36.845261 -194.891133) (xy 36.829551 -194.840203) (xy 36.821608 -194.787499) (xy 36.332533 -194.787499)
			(xy 36.332424 -194.793341) (xy 36.324481 -194.846045) (xy 36.308771 -194.896975) (xy 36.285645 -194.944996)
			(xy 36.255621 -194.989033) (xy 36.219369 -195.028104) (xy 36.177698 -195.061335) (xy 36.13154 -195.087984)
			(xy 36.081926 -195.107456) (xy 36.029964 -195.119316) (xy 35.976814 -195.1233) (xy 35.923664 -195.119316)
			(xy 35.871702 -195.107456) (xy 35.822088 -195.087984) (xy 35.77593 -195.061335) (xy 35.734259 -195.028104)
			(xy 35.698007 -194.989033) (xy 35.667983 -194.944996) (xy 35.644857 -194.896975) (xy 35.629147 -194.846045)
			(xy 35.621204 -194.793341) (xy 34.122624 -194.793341) (xy 34.114681 -194.846045) (xy 34.098971 -194.896975)
			(xy 34.075845 -194.944996) (xy 34.045821 -194.989033) (xy 34.009569 -195.028104) (xy 33.967898 -195.061335)
			(xy 33.92174 -195.087984) (xy 33.872126 -195.107456) (xy 33.820164 -195.119316) (xy 33.767014 -195.1233)
			(xy 33.713864 -195.119316) (xy 33.661902 -195.107456) (xy 33.612288 -195.087984) (xy 33.56613 -195.061335)
			(xy 33.524459 -195.028104) (xy 33.488207 -194.989033) (xy 33.458183 -194.944996) (xy 33.435057 -194.896975)
			(xy 33.419347 -194.846045) (xy 33.411404 -194.793341) (xy 32.330623 -194.793341) (xy 32.391858 -194.854576)
			(xy 32.391858 -195.821554) (xy 34.120836 -195.821554) (xy 34.120836 -195.412614) (xy 34.121275 -195.402444)
			(xy 34.129055 -195.383649) (xy 34.143436 -195.369264) (xy 34.162228 -195.361478) (xy 34.172398 -195.361052)
			(xy 35.571938 -195.361052) (xy 35.579809 -195.361362) (xy 35.594807 -195.366143) (xy 35.601402 -195.37045)
			(xy 35.613129 -195.378056) (xy 35.639547 -195.387155) (xy 35.667444 -195.388735) (xy 35.694721 -195.382675)
			(xy 35.719325 -195.369433) (xy 35.729672 -195.360036) (xy 35.74971 -195.341451) (xy 35.794396 -195.309989)
			(xy 35.843368 -195.285734) (xy 35.895475 -195.269256) (xy 35.949489 -195.260944) (xy 35.976814 -195.260468)
			(xy 36.003461 -195.261015) (xy 36.056159 -195.26896) (xy 36.107084 -195.28467) (xy 36.1551 -195.307795)
			(xy 36.199132 -195.337817) (xy 36.238198 -195.374067) (xy 36.271426 -195.415734) (xy 36.298072 -195.461888)
			(xy 36.317542 -195.511498) (xy 36.3294 -195.563455) (xy 36.333383 -195.6166) (xy 36.331388 -195.643225)
			(xy 36.855136 -195.643225) (xy 36.855136 -195.589927) (xy 36.863079 -195.537223) (xy 36.878789 -195.486293)
			(xy 36.901915 -195.438272) (xy 36.931939 -195.394235) (xy 36.968191 -195.355164) (xy 37.009862 -195.321933)
			(xy 37.05602 -195.295284) (xy 37.105634 -195.275812) (xy 37.157596 -195.263952) (xy 37.210746 -195.259969)
			(xy 37.263896 -195.263952) (xy 37.315858 -195.275812) (xy 37.365472 -195.295284) (xy 37.41163 -195.321933)
			(xy 37.453301 -195.355164) (xy 37.489553 -195.394235) (xy 37.519577 -195.438272) (xy 37.542703 -195.486293)
			(xy 37.558413 -195.537223) (xy 37.566356 -195.589927) (xy 37.566854 -195.616576) (xy 37.566356 -195.643225)
			(xy 39.064936 -195.643225) (xy 39.064936 -195.589927) (xy 39.072879 -195.537223) (xy 39.088589 -195.486293)
			(xy 39.111715 -195.438272) (xy 39.141739 -195.394235) (xy 39.177991 -195.355164) (xy 39.219662 -195.321933)
			(xy 39.26582 -195.295284) (xy 39.315434 -195.275812) (xy 39.367396 -195.263952) (xy 39.420546 -195.259969)
			(xy 39.473696 -195.263952) (xy 39.525658 -195.275812) (xy 39.575272 -195.295284) (xy 39.62143 -195.321933)
			(xy 39.663101 -195.355164) (xy 39.699353 -195.394235) (xy 39.729377 -195.438272) (xy 39.752503 -195.486293)
			(xy 39.768213 -195.537223) (xy 39.776156 -195.589927) (xy 39.776654 -195.616576) (xy 39.776156 -195.643225)
			(xy 39.768213 -195.695929) (xy 39.752503 -195.746859) (xy 39.729377 -195.79488) (xy 39.699353 -195.838917)
			(xy 39.663101 -195.877988) (xy 39.62143 -195.911219) (xy 39.575272 -195.937868) (xy 39.525658 -195.95734)
			(xy 39.473696 -195.9692) (xy 39.420546 -195.973184) (xy 39.367396 -195.9692) (xy 39.315434 -195.95734)
			(xy 39.26582 -195.937868) (xy 39.219662 -195.911219) (xy 39.177991 -195.877988) (xy 39.141739 -195.838917)
			(xy 39.111715 -195.79488) (xy 39.088589 -195.746859) (xy 39.072879 -195.695929) (xy 39.064936 -195.643225)
			(xy 37.566356 -195.643225) (xy 37.558413 -195.695929) (xy 37.542703 -195.746859) (xy 37.519577 -195.79488)
			(xy 37.489553 -195.838917) (xy 37.453301 -195.877988) (xy 37.41163 -195.911219) (xy 37.365472 -195.937868)
			(xy 37.315858 -195.95734) (xy 37.263896 -195.9692) (xy 37.210746 -195.973184) (xy 37.157596 -195.9692)
			(xy 37.105634 -195.95734) (xy 37.05602 -195.937868) (xy 37.009862 -195.911219) (xy 36.968191 -195.877988)
			(xy 36.931939 -195.838917) (xy 36.901915 -195.79488) (xy 36.878789 -195.746859) (xy 36.863079 -195.695929)
			(xy 36.855136 -195.643225) (xy 36.331388 -195.643225) (xy 36.3294 -195.669745) (xy 36.317542 -195.721702)
			(xy 36.298072 -195.771312) (xy 36.271426 -195.817466) (xy 36.238198 -195.859133) (xy 36.199132 -195.895383)
			(xy 36.1551 -195.925405) (xy 36.107084 -195.94853) (xy 36.056159 -195.96424) (xy 36.003461 -195.972185)
			(xy 35.976814 -195.972684) (xy 35.949551 -195.972187) (xy 35.895662 -195.963869) (xy 35.843674 -195.947428)
			(xy 35.794802 -195.923246) (xy 35.750193 -195.891891) (xy 35.73018 -195.87337) (xy 35.719729 -195.864022)
			(xy 35.694956 -195.85091) (xy 35.667554 -195.845007) (xy 35.63958 -195.846758) (xy 35.613128 -195.856029)
			(xy 35.601402 -195.863718) (xy 35.594793 -195.867998) (xy 35.579804 -195.872791) (xy 35.571938 -195.873116)
			(xy 34.172398 -195.873116) (xy 34.162221 -195.872737) (xy 34.143417 -195.864942) (xy 34.129031 -195.850543)
			(xy 34.121254 -195.831732) (xy 34.120836 -195.821554) (xy 32.391858 -195.821554) (xy 32.391858 -196.493363)
			(xy 33.411404 -196.493363) (xy 33.411404 -196.440065) (xy 33.419347 -196.387361) (xy 33.435057 -196.336431)
			(xy 33.458183 -196.28841) (xy 33.488207 -196.244373) (xy 33.524459 -196.205302) (xy 33.56613 -196.172071)
			(xy 33.612288 -196.145422) (xy 33.661902 -196.12595) (xy 33.713864 -196.11409) (xy 33.767014 -196.110107)
			(xy 33.820164 -196.11409) (xy 33.872126 -196.12595) (xy 33.92174 -196.145422) (xy 33.967898 -196.172071)
			(xy 34.009569 -196.205302) (xy 34.045821 -196.244373) (xy 34.075845 -196.28841) (xy 34.098971 -196.336431)
			(xy 34.114681 -196.387361) (xy 34.122624 -196.440065) (xy 34.123122 -196.466714) (xy 34.122624 -196.493363)
			(xy 35.621204 -196.493363) (xy 35.621204 -196.440065) (xy 35.629147 -196.387361) (xy 35.644857 -196.336431)
			(xy 35.667983 -196.28841) (xy 35.698007 -196.244373) (xy 35.734259 -196.205302) (xy 35.77593 -196.172071)
			(xy 35.822088 -196.145422) (xy 35.871702 -196.12595) (xy 35.923664 -196.11409) (xy 35.976814 -196.110107)
			(xy 36.029964 -196.11409) (xy 36.081926 -196.12595) (xy 36.13154 -196.145422) (xy 36.177698 -196.172071)
			(xy 36.219369 -196.205302) (xy 36.255621 -196.244373) (xy 36.285645 -196.28841) (xy 36.308771 -196.336431)
			(xy 36.324481 -196.387361) (xy 36.332424 -196.440065) (xy 36.332922 -196.466714) (xy 36.332424 -196.493363)
			(xy 36.324481 -196.546067) (xy 36.308771 -196.596997) (xy 36.285645 -196.645018) (xy 36.267632 -196.671438)
			(xy 37.564568 -196.671438) (xy 37.564568 -196.262498) (xy 37.564963 -196.252323) (xy 37.572754 -196.233522)
			(xy 37.587149 -196.219136) (xy 37.605954 -196.211357) (xy 37.61613 -196.210936) (xy 39.01567 -196.210936)
			(xy 39.025839 -196.211389) (xy 39.044633 -196.219163) (xy 39.059019 -196.23354) (xy 39.066805 -196.252329)
			(xy 39.067232 -196.262498) (xy 39.067232 -196.671438) (xy 39.066797 -196.681602) (xy 39.059004 -196.700378)
			(xy 39.044621 -196.714743) (xy 39.025835 -196.72251) (xy 39.01567 -196.723) (xy 37.61613 -196.723)
			(xy 37.605979 -196.722443) (xy 37.587217 -196.714686) (xy 37.572852 -196.70034) (xy 37.56507 -196.681589)
			(xy 37.564568 -196.671438) (xy 36.267632 -196.671438) (xy 36.255621 -196.689055) (xy 36.219369 -196.728126)
			(xy 36.177698 -196.761357) (xy 36.13154 -196.788006) (xy 36.081926 -196.807478) (xy 36.029964 -196.819338)
			(xy 35.976814 -196.823322) (xy 35.923664 -196.819338) (xy 35.871702 -196.807478) (xy 35.822088 -196.788006)
			(xy 35.77593 -196.761357) (xy 35.734259 -196.728126) (xy 35.698007 -196.689055) (xy 35.667983 -196.645018)
			(xy 35.644857 -196.596997) (xy 35.629147 -196.546067) (xy 35.621204 -196.493363) (xy 34.122624 -196.493363)
			(xy 34.114681 -196.546067) (xy 34.098971 -196.596997) (xy 34.075845 -196.645018) (xy 34.045821 -196.689055)
			(xy 34.009569 -196.728126) (xy 33.967898 -196.761357) (xy 33.92174 -196.788006) (xy 33.872126 -196.807478)
			(xy 33.820164 -196.819338) (xy 33.767014 -196.823322) (xy 33.713864 -196.819338) (xy 33.661902 -196.807478)
			(xy 33.612288 -196.788006) (xy 33.56613 -196.761357) (xy 33.524459 -196.728126) (xy 33.488207 -196.689055)
			(xy 33.458183 -196.645018) (xy 33.435057 -196.596997) (xy 33.419347 -196.546067) (xy 33.411404 -196.493363)
			(xy 32.391858 -196.493363) (xy 32.391858 -197.521322) (xy 34.120836 -197.521322) (xy 34.120836 -197.112382)
			(xy 34.121318 -197.102223) (xy 34.129098 -197.083454) (xy 34.143467 -197.069089) (xy 34.162239 -197.061315)
			(xy 34.172398 -197.06082) (xy 35.571938 -197.06082) (xy 35.579808 -197.061135) (xy 35.594807 -197.065913)
			(xy 35.601402 -197.070218) (xy 35.613162 -197.077808) (xy 35.639599 -197.086959) (xy 35.667527 -197.088599)
			(xy 35.694853 -197.082606) (xy 35.719532 -197.069429) (xy 35.729926 -197.060058) (xy 35.749921 -197.041464)
			(xy 35.794572 -197.010039) (xy 35.843499 -196.985802) (xy 35.895553 -196.969322) (xy 35.949514 -196.960985)
			(xy 35.976814 -196.96049) (xy 36.003462 -196.960993) (xy 36.056164 -196.968938) (xy 36.107093 -196.984649)
			(xy 36.155111 -197.007775) (xy 36.199146 -197.0378) (xy 36.238215 -197.074052) (xy 36.271444 -197.115721)
			(xy 36.298092 -197.161878) (xy 36.317563 -197.211491) (xy 36.329423 -197.263452) (xy 36.333406 -197.3166)
			(xy 36.331409 -197.343247) (xy 36.855136 -197.343247) (xy 36.855136 -197.289949) (xy 36.863079 -197.237245)
			(xy 36.878789 -197.186315) (xy 36.901915 -197.138294) (xy 36.931939 -197.094257) (xy 36.968191 -197.055186)
			(xy 37.009862 -197.021955) (xy 37.05602 -196.995306) (xy 37.105634 -196.975834) (xy 37.157596 -196.963974)
			(xy 37.210746 -196.959991) (xy 37.263896 -196.963974) (xy 37.315858 -196.975834) (xy 37.365472 -196.995306)
			(xy 37.41163 -197.021955) (xy 37.453301 -197.055186) (xy 37.489553 -197.094257) (xy 37.519577 -197.138294)
			(xy 37.542703 -197.186315) (xy 37.558413 -197.237245) (xy 37.566356 -197.289949) (xy 37.566854 -197.316598)
			(xy 37.566356 -197.343247) (xy 39.064936 -197.343247) (xy 39.064936 -197.289949) (xy 39.072879 -197.237245)
			(xy 39.088589 -197.186315) (xy 39.111715 -197.138294) (xy 39.141739 -197.094257) (xy 39.177991 -197.055186)
			(xy 39.219662 -197.021955) (xy 39.26582 -196.995306) (xy 39.315434 -196.975834) (xy 39.367396 -196.963974)
			(xy 39.420546 -196.959991) (xy 39.473696 -196.963974) (xy 39.525658 -196.975834) (xy 39.575272 -196.995306)
			(xy 39.62143 -197.021955) (xy 39.663101 -197.055186) (xy 39.699353 -197.094257) (xy 39.729377 -197.138294)
			(xy 39.752503 -197.186315) (xy 39.768213 -197.237245) (xy 39.776156 -197.289949) (xy 39.776654 -197.316598)
			(xy 39.776156 -197.343247) (xy 39.768213 -197.395951) (xy 39.752503 -197.446881) (xy 39.729377 -197.494902)
			(xy 39.699353 -197.538939) (xy 39.663101 -197.57801) (xy 39.62143 -197.611241) (xy 39.575272 -197.63789)
			(xy 39.525658 -197.657362) (xy 39.473696 -197.669222) (xy 39.420546 -197.673206) (xy 39.367396 -197.669222)
			(xy 39.315434 -197.657362) (xy 39.26582 -197.63789) (xy 39.219662 -197.611241) (xy 39.177991 -197.57801)
			(xy 39.141739 -197.538939) (xy 39.111715 -197.494902) (xy 39.088589 -197.446881) (xy 39.072879 -197.395951)
			(xy 39.064936 -197.343247) (xy 37.566356 -197.343247) (xy 37.558413 -197.395951) (xy 37.542703 -197.446881)
			(xy 37.519577 -197.494902) (xy 37.489553 -197.538939) (xy 37.453301 -197.57801) (xy 37.41163 -197.611241)
			(xy 37.365472 -197.63789) (xy 37.315858 -197.657362) (xy 37.263896 -197.669222) (xy 37.210746 -197.673206)
			(xy 37.157596 -197.669222) (xy 37.105634 -197.657362) (xy 37.05602 -197.63789) (xy 37.009862 -197.611241)
			(xy 36.968191 -197.57801) (xy 36.931939 -197.538939) (xy 36.901915 -197.494902) (xy 36.878789 -197.446881)
			(xy 36.863079 -197.395951) (xy 36.855136 -197.343247) (xy 36.331409 -197.343247) (xy 36.329423 -197.369748)
			(xy 36.317563 -197.421709) (xy 36.298092 -197.471322) (xy 36.271444 -197.517479) (xy 36.238215 -197.559148)
			(xy 36.199146 -197.5954) (xy 36.155111 -197.625425) (xy 36.107093 -197.648551) (xy 36.056164 -197.664262)
			(xy 36.003462 -197.672207) (xy 35.976814 -197.672706) (xy 35.949551 -197.672203) (xy 35.895663 -197.663886)
			(xy 35.843675 -197.647445) (xy 35.794804 -197.623265) (xy 35.750193 -197.591912) (xy 35.73018 -197.573392)
			(xy 35.719773 -197.563972) (xy 35.695028 -197.550744) (xy 35.667614 -197.544763) (xy 35.639607 -197.546483)
			(xy 35.613131 -197.555774) (xy 35.601402 -197.563486) (xy 35.594791 -197.567763) (xy 35.579804 -197.572558)
			(xy 35.571938 -197.572884) (xy 34.172398 -197.572884) (xy 34.162243 -197.572369) (xy 34.143478 -197.564598)
			(xy 34.129113 -197.550239) (xy 34.121335 -197.531477) (xy 34.120836 -197.521322) (xy 32.391858 -197.521322)
			(xy 32.391858 -198.193385) (xy 33.411404 -198.193385) (xy 33.411404 -198.140087) (xy 33.419347 -198.087383)
			(xy 33.435057 -198.036453) (xy 33.458183 -197.988432) (xy 33.488207 -197.944395) (xy 33.524459 -197.905324)
			(xy 33.56613 -197.872093) (xy 33.612288 -197.845444) (xy 33.661902 -197.825972) (xy 33.713864 -197.814112)
			(xy 33.767014 -197.810129) (xy 33.820164 -197.814112) (xy 33.872126 -197.825972) (xy 33.92174 -197.845444)
			(xy 33.967898 -197.872093) (xy 34.009569 -197.905324) (xy 34.045821 -197.944395) (xy 34.075845 -197.988432)
			(xy 34.098971 -198.036453) (xy 34.114681 -198.087383) (xy 34.122624 -198.140087) (xy 34.123122 -198.166736)
			(xy 34.122624 -198.193385) (xy 35.621204 -198.193385) (xy 35.621204 -198.140087) (xy 35.629147 -198.087383)
			(xy 35.644857 -198.036453) (xy 35.667983 -197.988432) (xy 35.698007 -197.944395) (xy 35.734259 -197.905324)
			(xy 35.77593 -197.872093) (xy 35.822088 -197.845444) (xy 35.871702 -197.825972) (xy 35.923664 -197.814112)
			(xy 35.976814 -197.810129) (xy 36.029964 -197.814112) (xy 36.081926 -197.825972) (xy 36.13154 -197.845444)
			(xy 36.177698 -197.872093) (xy 36.219369 -197.905324) (xy 36.255621 -197.944395) (xy 36.285645 -197.988432)
			(xy 36.308771 -198.036453) (xy 36.324481 -198.087383) (xy 36.332424 -198.140087) (xy 36.332922 -198.166736)
			(xy 36.332424 -198.193385) (xy 36.324481 -198.246089) (xy 36.308771 -198.297019) (xy 36.285645 -198.34504)
			(xy 36.267632 -198.37146) (xy 37.564568 -198.37146) (xy 37.564568 -197.96252) (xy 37.565037 -197.952371)
			(xy 37.57282 -197.933625) (xy 37.587202 -197.919302) (xy 37.60598 -197.911596) (xy 37.61613 -197.911212)
			(xy 39.01567 -197.911212) (xy 39.025791 -197.91175) (xy 39.044507 -197.919463) (xy 39.058863 -197.933733)
			(xy 39.066688 -197.952402) (xy 39.067232 -197.96252) (xy 39.067232 -198.37146) (xy 39.066746 -198.381608)
			(xy 39.05897 -198.400353) (xy 39.044593 -198.414676) (xy 39.025819 -198.422383) (xy 39.01567 -198.422768)
			(xy 37.61613 -198.422768) (xy 37.606006 -198.422249) (xy 37.587287 -198.414533) (xy 37.57293 -198.400256)
			(xy 37.565108 -198.381581) (xy 37.564568 -198.37146) (xy 36.267632 -198.37146) (xy 36.255621 -198.389077)
			(xy 36.219369 -198.428148) (xy 36.177698 -198.461379) (xy 36.13154 -198.488028) (xy 36.081926 -198.5075)
			(xy 36.029964 -198.51936) (xy 35.976814 -198.523344) (xy 35.923664 -198.51936) (xy 35.871702 -198.5075)
			(xy 35.822088 -198.488028) (xy 35.77593 -198.461379) (xy 35.734259 -198.428148) (xy 35.698007 -198.389077)
			(xy 35.667983 -198.34504) (xy 35.644857 -198.297019) (xy 35.629147 -198.246089) (xy 35.621204 -198.193385)
			(xy 34.122624 -198.193385) (xy 34.114681 -198.246089) (xy 34.098971 -198.297019) (xy 34.075845 -198.34504)
			(xy 34.045821 -198.389077) (xy 34.009569 -198.428148) (xy 33.967898 -198.461379) (xy 33.92174 -198.488028)
			(xy 33.872126 -198.5075) (xy 33.820164 -198.51936) (xy 33.767014 -198.523344) (xy 33.713864 -198.51936)
			(xy 33.661902 -198.5075) (xy 33.612288 -198.488028) (xy 33.56613 -198.461379) (xy 33.524459 -198.428148)
			(xy 33.488207 -198.389077) (xy 33.458183 -198.34504) (xy 33.435057 -198.297019) (xy 33.419347 -198.246089)
			(xy 33.411404 -198.193385) (xy 32.391858 -198.193385) (xy 32.391858 -199.221344) (xy 34.120836 -199.221344)
			(xy 34.120836 -198.812404) (xy 34.121226 -198.802246) (xy 34.129027 -198.783486) (xy 34.143434 -198.769162)
			(xy 34.162237 -198.761468) (xy 34.172398 -198.761096) (xy 35.571938 -198.761096) (xy 35.579792 -198.76133)
			(xy 35.59479 -198.765994) (xy 35.601402 -198.77024) (xy 35.613163 -198.777826) (xy 35.6396 -198.786975)
			(xy 35.667527 -198.788615) (xy 35.694852 -198.782623) (xy 35.719531 -198.769449) (xy 35.729926 -198.76008)
			(xy 35.749925 -198.74149) (xy 35.794574 -198.710064) (xy 35.8435 -198.685826) (xy 35.895554 -198.669345)
			(xy 35.949514 -198.661008) (xy 35.976814 -198.660512) (xy 36.003464 -198.660971) (xy 36.056169 -198.668917)
			(xy 36.107101 -198.684629) (xy 36.155122 -198.707756) (xy 36.19916 -198.737782) (xy 36.238231 -198.774037)
			(xy 36.271462 -198.815709) (xy 36.298112 -198.861869) (xy 36.317584 -198.911485) (xy 36.329444 -198.963449)
			(xy 36.333428 -199.0166) (xy 36.331429 -199.043269) (xy 36.855136 -199.043269) (xy 36.855136 -198.989971)
			(xy 36.863079 -198.937267) (xy 36.878789 -198.886337) (xy 36.901915 -198.838316) (xy 36.931939 -198.794279)
			(xy 36.968191 -198.755208) (xy 37.009862 -198.721977) (xy 37.05602 -198.695328) (xy 37.105634 -198.675856)
			(xy 37.157596 -198.663996) (xy 37.210746 -198.660013) (xy 37.263896 -198.663996) (xy 37.315858 -198.675856)
			(xy 37.365472 -198.695328) (xy 37.41163 -198.721977) (xy 37.453301 -198.755208) (xy 37.489553 -198.794279)
			(xy 37.519577 -198.838316) (xy 37.542703 -198.886337) (xy 37.558413 -198.937267) (xy 37.566356 -198.989971)
			(xy 37.566854 -199.01662) (xy 37.566356 -199.043269) (xy 37.558413 -199.095973) (xy 37.542703 -199.146903)
			(xy 37.519577 -199.194924) (xy 37.489553 -199.238961) (xy 37.453301 -199.278032) (xy 37.41163 -199.311263)
			(xy 37.365472 -199.337912) (xy 37.315858 -199.357384) (xy 37.263896 -199.369244) (xy 37.210746 -199.373228)
			(xy 37.157596 -199.369244) (xy 37.105634 -199.357384) (xy 37.05602 -199.337912) (xy 37.009862 -199.311263)
			(xy 36.968191 -199.278032) (xy 36.931939 -199.238961) (xy 36.901915 -199.194924) (xy 36.878789 -199.146903)
			(xy 36.863079 -199.095973) (xy 36.855136 -199.043269) (xy 36.331429 -199.043269) (xy 36.329444 -199.069751)
			(xy 36.317584 -199.121715) (xy 36.298112 -199.171331) (xy 36.271462 -199.217491) (xy 36.238231 -199.259163)
			(xy 36.19916 -199.295418) (xy 36.155122 -199.325444) (xy 36.107101 -199.348571) (xy 36.056169 -199.364283)
			(xy 36.003464 -199.372229) (xy 35.976814 -199.372728) (xy 35.949551 -199.372218) (xy 35.895664 -199.363902)
			(xy 35.843676 -199.347463) (xy 35.794805 -199.323284) (xy 35.750194 -199.291933) (xy 35.73018 -199.273414)
			(xy 35.719775 -199.263994) (xy 35.695027 -199.250775) (xy 35.667614 -199.244799) (xy 35.639609 -199.246517)
			(xy 35.613132 -199.255801) (xy 35.601402 -199.263508) (xy 35.594788 -199.26775) (xy 35.579791 -199.272409)
			(xy 35.571938 -199.272652) (xy 34.172398 -199.272652) (xy 34.16227 -199.272175) (xy 34.143548 -199.264445)
			(xy 34.129191 -199.250156) (xy 34.121373 -199.231469) (xy 34.120836 -199.221344) (xy 32.391858 -199.221344)
			(xy 32.391858 -200.071482) (xy 34.120836 -200.071482) (xy 34.120836 -199.662542) (xy 34.121298 -199.652373)
			(xy 34.129069 -199.63358) (xy 34.143443 -199.619194) (xy 34.16223 -199.611407) (xy 34.172398 -199.61098)
			(xy 35.571938 -199.61098) (xy 35.579809 -199.611285) (xy 35.594808 -199.616069) (xy 35.601402 -199.620378)
			(xy 35.613166 -199.627959) (xy 35.639602 -199.637103) (xy 35.667527 -199.638743) (xy 35.694851 -199.632753)
			(xy 35.719529 -199.619584) (xy 35.729926 -199.610218) (xy 35.74993 -199.591634) (xy 35.794578 -199.560206)
			(xy 35.843502 -199.535966) (xy 35.895555 -199.519484) (xy 35.949514 -199.511146) (xy 35.976814 -199.51065)
			(xy 36.003459 -199.511233) (xy 36.056155 -199.519178) (xy 36.107078 -199.534887) (xy 36.155091 -199.55801)
			(xy 36.199121 -199.588031) (xy 36.238185 -199.624279) (xy 36.271411 -199.665944) (xy 36.298056 -199.712096)
			(xy 36.317525 -199.761703) (xy 36.329383 -199.813658) (xy 36.333365 -199.8668) (xy 36.329383 -199.919942)
			(xy 36.317525 -199.971897) (xy 36.298056 -200.021504) (xy 36.271411 -200.067656) (xy 36.26836 -200.071482)
			(xy 37.564568 -200.071482) (xy 37.564568 -199.662542) (xy 37.564999 -199.652369) (xy 37.572776 -199.63357)
			(xy 37.58716 -199.619182) (xy 37.605957 -199.611401) (xy 37.61613 -199.61098) (xy 39.01567 -199.61098)
			(xy 39.025845 -199.61139) (xy 39.044647 -199.619172) (xy 39.059034 -199.633563) (xy 39.066813 -199.652367)
			(xy 39.067232 -199.662542) (xy 39.067232 -200.071482) (xy 39.066821 -200.081656) (xy 39.059036 -200.100456)
			(xy 39.044646 -200.114843) (xy 39.025844 -200.122623) (xy 39.01567 -200.123044) (xy 37.61613 -200.123044)
			(xy 37.605958 -200.122611) (xy 37.587161 -200.114833) (xy 37.572774 -200.100449) (xy 37.564991 -200.081654)
			(xy 37.564568 -200.071482) (xy 36.26836 -200.071482) (xy 36.238185 -200.109321) (xy 36.199121 -200.145569)
			(xy 36.155091 -200.17559) (xy 36.107078 -200.198713) (xy 36.056155 -200.214422) (xy 36.003459 -200.222367)
			(xy 35.976814 -200.222866) (xy 35.94955 -200.222374) (xy 35.895662 -200.214056) (xy 35.843673 -200.197613)
			(xy 35.794802 -200.173431) (xy 35.750192 -200.142074) (xy 35.73018 -200.123552) (xy 35.719774 -200.114133)
			(xy 35.695028 -200.100909) (xy 35.667614 -200.09493) (xy 35.639608 -200.09665) (xy 35.613132 -200.105937)
			(xy 35.601402 -200.113646) (xy 35.594794 -200.117928) (xy 35.579804 -200.122719) (xy 35.571938 -200.123044)
			(xy 34.172398 -200.123044) (xy 34.162224 -200.122637) (xy 34.143426 -200.114848) (xy 34.12904 -200.100457)
			(xy 34.121259 -200.081656) (xy 34.120836 -200.071482) (xy 32.391858 -200.071482) (xy 32.391858 -200.743291)
			(xy 33.411404 -200.743291) (xy 33.411404 -200.689993) (xy 33.419347 -200.637289) (xy 33.435057 -200.586359)
			(xy 33.458183 -200.538338) (xy 33.488207 -200.494301) (xy 33.524459 -200.45523) (xy 33.56613 -200.421999)
			(xy 33.612288 -200.39535) (xy 33.661902 -200.375878) (xy 33.713864 -200.364018) (xy 33.767014 -200.360035)
			(xy 33.820164 -200.364018) (xy 33.872126 -200.375878) (xy 33.92174 -200.39535) (xy 33.967898 -200.421999)
			(xy 34.009569 -200.45523) (xy 34.045821 -200.494301) (xy 34.075845 -200.538338) (xy 34.098971 -200.586359)
			(xy 34.114681 -200.637289) (xy 34.122624 -200.689993) (xy 34.123122 -200.716642) (xy 34.122624 -200.743291)
			(xy 35.621204 -200.743291) (xy 35.621204 -200.689993) (xy 35.629147 -200.637289) (xy 35.644857 -200.586359)
			(xy 35.667983 -200.538338) (xy 35.698007 -200.494301) (xy 35.734259 -200.45523) (xy 35.77593 -200.421999)
			(xy 35.822088 -200.39535) (xy 35.871702 -200.375878) (xy 35.923664 -200.364018) (xy 35.976814 -200.360035)
			(xy 36.029964 -200.364018) (xy 36.081926 -200.375878) (xy 36.13154 -200.39535) (xy 36.177698 -200.421999)
			(xy 36.219369 -200.45523) (xy 36.255621 -200.494301) (xy 36.285645 -200.538338) (xy 36.308771 -200.586359)
			(xy 36.324481 -200.637289) (xy 36.332424 -200.689993) (xy 36.332922 -200.716642) (xy 36.332424 -200.743291)
			(xy 36.324481 -200.795995) (xy 36.308771 -200.846925) (xy 36.285645 -200.894946) (xy 36.267632 -200.921366)
			(xy 37.564568 -200.921366) (xy 37.564568 -200.512426) (xy 37.564986 -200.502252) (xy 37.572768 -200.483453)
			(xy 37.587156 -200.469066) (xy 37.605956 -200.461285) (xy 37.61613 -200.460864) (xy 39.01567 -200.460864)
			(xy 39.025843 -200.461289) (xy 39.044642 -200.469069) (xy 39.059029 -200.483455) (xy 39.06681 -200.502253)
			(xy 39.067232 -200.512426) (xy 39.067232 -200.921366) (xy 39.066807 -200.931539) (xy 39.059028 -200.950339)
			(xy 39.044642 -200.964726) (xy 39.025843 -200.972507) (xy 39.01567 -200.972928) (xy 37.61613 -200.972928)
			(xy 37.605956 -200.972511) (xy 37.587156 -200.964729) (xy 37.572769 -200.950341) (xy 37.564989 -200.93154)
			(xy 37.564568 -200.921366) (xy 36.267632 -200.921366) (xy 36.255621 -200.938983) (xy 36.219369 -200.978054)
			(xy 36.177698 -201.011285) (xy 36.13154 -201.037934) (xy 36.081926 -201.057406) (xy 36.029964 -201.069266)
			(xy 35.976814 -201.07325) (xy 35.923664 -201.069266) (xy 35.871702 -201.057406) (xy 35.822088 -201.037934)
			(xy 35.77593 -201.011285) (xy 35.734259 -200.978054) (xy 35.698007 -200.938983) (xy 35.667983 -200.894946)
			(xy 35.644857 -200.846925) (xy 35.629147 -200.795995) (xy 35.621204 -200.743291) (xy 34.122624 -200.743291)
			(xy 34.114681 -200.795995) (xy 34.098971 -200.846925) (xy 34.075845 -200.894946) (xy 34.045821 -200.938983)
			(xy 34.009569 -200.978054) (xy 33.967898 -201.011285) (xy 33.92174 -201.037934) (xy 33.872126 -201.057406)
			(xy 33.820164 -201.069266) (xy 33.767014 -201.07325) (xy 33.713864 -201.069266) (xy 33.661902 -201.057406)
			(xy 33.612288 -201.037934) (xy 33.56613 -201.011285) (xy 33.524459 -200.978054) (xy 33.488207 -200.938983)
			(xy 33.458183 -200.894946) (xy 33.435057 -200.846925) (xy 33.419347 -200.795995) (xy 33.411404 -200.743291)
			(xy 32.391858 -200.743291) (xy 32.391858 -201.771504) (xy 34.120836 -201.771504) (xy 34.120836 -201.362564)
			(xy 34.121193 -201.352403) (xy 34.129007 -201.333643) (xy 34.143424 -201.31932) (xy 34.162234 -201.311628)
			(xy 34.172398 -201.311256) (xy 35.571938 -201.311256) (xy 35.579791 -201.311496) (xy 35.594788 -201.316157)
			(xy 35.601402 -201.3204) (xy 35.613161 -201.327993) (xy 35.639598 -201.337145) (xy 35.667527 -201.338786)
			(xy 35.694854 -201.332792) (xy 35.719532 -201.319612) (xy 35.729926 -201.31024) (xy 35.749918 -201.291643)
			(xy 35.79457 -201.260219) (xy 35.843498 -201.235983) (xy 35.895553 -201.219504) (xy 35.949513 -201.211167)
			(xy 35.976814 -201.210672) (xy 36.003461 -201.211211) (xy 36.05616 -201.219156) (xy 36.107086 -201.234866)
			(xy 36.155102 -201.257991) (xy 36.199135 -201.288014) (xy 36.238201 -201.324264) (xy 36.271429 -201.365932)
			(xy 36.298076 -201.412086) (xy 36.317546 -201.461697) (xy 36.329404 -201.513655) (xy 36.333387 -201.5668)
			(xy 36.331391 -201.593429) (xy 36.855136 -201.593429) (xy 36.855136 -201.540131) (xy 36.863079 -201.487427)
			(xy 36.878789 -201.436497) (xy 36.901915 -201.388476) (xy 36.931939 -201.344439) (xy 36.968191 -201.305368)
			(xy 37.009862 -201.272137) (xy 37.05602 -201.245488) (xy 37.105634 -201.226016) (xy 37.157596 -201.214156)
			(xy 37.210746 -201.210173) (xy 37.263896 -201.214156) (xy 37.315858 -201.226016) (xy 37.365472 -201.245488)
			(xy 37.41163 -201.272137) (xy 37.453301 -201.305368) (xy 37.489553 -201.344439) (xy 37.519577 -201.388476)
			(xy 37.542703 -201.436497) (xy 37.558413 -201.487427) (xy 37.566356 -201.540131) (xy 37.566854 -201.56678)
			(xy 37.566356 -201.593429) (xy 37.558413 -201.646133) (xy 37.542703 -201.697063) (xy 37.519577 -201.745084)
			(xy 37.489553 -201.789121) (xy 37.453301 -201.828192) (xy 37.41163 -201.861423) (xy 37.365472 -201.888072)
			(xy 37.315858 -201.907544) (xy 37.263896 -201.919404) (xy 37.210746 -201.923388) (xy 37.157596 -201.919404)
			(xy 37.105634 -201.907544) (xy 37.05602 -201.888072) (xy 37.009862 -201.861423) (xy 36.968191 -201.828192)
			(xy 36.931939 -201.789121) (xy 36.901915 -201.745084) (xy 36.878789 -201.697063) (xy 36.863079 -201.646133)
			(xy 36.855136 -201.593429) (xy 36.331391 -201.593429) (xy 36.329404 -201.619945) (xy 36.317546 -201.671903)
			(xy 36.298076 -201.721514) (xy 36.271429 -201.767668) (xy 36.238201 -201.809336) (xy 36.199135 -201.845586)
			(xy 36.155102 -201.875609) (xy 36.107086 -201.898734) (xy 36.05616 -201.914444) (xy 36.003461 -201.922389)
			(xy 35.976814 -201.922888) (xy 35.949551 -201.922389) (xy 35.895662 -201.914072) (xy 35.843674 -201.897631)
			(xy 35.794803 -201.87345) (xy 35.750193 -201.842095) (xy 35.73018 -201.823574) (xy 35.719774 -201.814155)
			(xy 35.695028 -201.800928) (xy 35.667614 -201.794948) (xy 35.639608 -201.796668) (xy 35.613131 -201.805957)
			(xy 35.601402 -201.813668) (xy 35.594786 -201.817906) (xy 35.579791 -201.822568) (xy 35.571938 -201.822812)
			(xy 34.172398 -201.822812) (xy 34.162278 -201.822277) (xy 34.143566 -201.814558) (xy 34.129212 -201.800287)
			(xy 34.121384 -201.781621) (xy 34.120836 -201.771504) (xy 32.391858 -201.771504) (xy 32.391858 -202.443313)
			(xy 33.411404 -202.443313) (xy 33.411404 -202.390015) (xy 33.419347 -202.337311) (xy 33.435057 -202.286381)
			(xy 33.458183 -202.23836) (xy 33.488207 -202.194323) (xy 33.524459 -202.155252) (xy 33.56613 -202.122021)
			(xy 33.612288 -202.095372) (xy 33.661902 -202.0759) (xy 33.713864 -202.06404) (xy 33.767014 -202.060057)
			(xy 33.820164 -202.06404) (xy 33.872126 -202.0759) (xy 33.92174 -202.095372) (xy 33.967898 -202.122021)
			(xy 34.009569 -202.155252) (xy 34.045821 -202.194323) (xy 34.075845 -202.23836) (xy 34.098971 -202.286381)
			(xy 34.114681 -202.337311) (xy 34.122624 -202.390015) (xy 34.123122 -202.416664) (xy 34.122624 -202.443313)
			(xy 35.621204 -202.443313) (xy 35.621204 -202.390015) (xy 35.629147 -202.337311) (xy 35.644857 -202.286381)
			(xy 35.667983 -202.23836) (xy 35.698007 -202.194323) (xy 35.734259 -202.155252) (xy 35.77593 -202.122021)
			(xy 35.822088 -202.095372) (xy 35.871702 -202.0759) (xy 35.923664 -202.06404) (xy 35.976814 -202.060057)
			(xy 36.029964 -202.06404) (xy 36.081926 -202.0759) (xy 36.13154 -202.095372) (xy 36.177698 -202.122021)
			(xy 36.219369 -202.155252) (xy 36.255621 -202.194323) (xy 36.285645 -202.23836) (xy 36.308771 -202.286381)
			(xy 36.324481 -202.337311) (xy 36.332424 -202.390015) (xy 36.332922 -202.416664) (xy 36.332424 -202.443313)
			(xy 36.324481 -202.496017) (xy 36.308771 -202.546947) (xy 36.285645 -202.594968) (xy 36.267632 -202.621388)
			(xy 37.564568 -202.621388) (xy 37.564568 -202.212448) (xy 37.56506 -202.202301) (xy 37.572834 -202.183556)
			(xy 37.587209 -202.169232) (xy 37.605982 -202.161525) (xy 37.61613 -202.16114) (xy 39.01567 -202.16114)
			(xy 39.025795 -202.161651) (xy 39.044515 -202.169369) (xy 39.058873 -202.183648) (xy 39.066693 -202.202326)
			(xy 39.067232 -202.212448) (xy 39.067232 -202.621388) (xy 39.066769 -202.631537) (xy 39.058984 -202.650283)
			(xy 39.0446 -202.664606) (xy 39.025821 -202.672312) (xy 39.01567 -202.672696) (xy 37.61613 -202.672696)
			(xy 37.60601 -202.67215) (xy 37.587296 -202.664439) (xy 37.57294 -202.650171) (xy 37.565113 -202.631505)
			(xy 37.564568 -202.621388) (xy 36.267632 -202.621388) (xy 36.255621 -202.639005) (xy 36.219369 -202.678076)
			(xy 36.177698 -202.711307) (xy 36.13154 -202.737956) (xy 36.081926 -202.757428) (xy 36.029964 -202.769288)
			(xy 35.976814 -202.773272) (xy 35.923664 -202.769288) (xy 35.871702 -202.757428) (xy 35.822088 -202.737956)
			(xy 35.77593 -202.711307) (xy 35.734259 -202.678076) (xy 35.698007 -202.639005) (xy 35.667983 -202.594968)
			(xy 35.644857 -202.546947) (xy 35.629147 -202.496017) (xy 35.621204 -202.443313) (xy 34.122624 -202.443313)
			(xy 34.114681 -202.496017) (xy 34.098971 -202.546947) (xy 34.075845 -202.594968) (xy 34.045821 -202.639005)
			(xy 34.009569 -202.678076) (xy 33.967898 -202.711307) (xy 33.92174 -202.737956) (xy 33.872126 -202.757428)
			(xy 33.820164 -202.769288) (xy 33.767014 -202.773272) (xy 33.713864 -202.769288) (xy 33.661902 -202.757428)
			(xy 33.612288 -202.737956) (xy 33.56613 -202.711307) (xy 33.524459 -202.678076) (xy 33.488207 -202.639005)
			(xy 33.458183 -202.594968) (xy 33.435057 -202.546947) (xy 33.419347 -202.496017) (xy 33.411404 -202.443313)
			(xy 32.391858 -202.443313) (xy 32.391858 -203.471526) (xy 34.120836 -203.471526) (xy 34.120836 -203.062586)
			(xy 34.121322 -203.052428) (xy 34.129101 -203.033659) (xy 34.143469 -203.019294) (xy 34.16224 -203.01152)
			(xy 34.172398 -203.011024) (xy 35.571938 -203.011024) (xy 35.579808 -203.011338) (xy 35.594807 -203.016117)
			(xy 35.601402 -203.020422) (xy 35.613162 -203.028011) (xy 35.639599 -203.037162) (xy 35.667527 -203.038802)
			(xy 35.694853 -203.032809) (xy 35.719531 -203.019633) (xy 35.729926 -203.010262) (xy 35.749921 -202.991668)
			(xy 35.794572 -202.960243) (xy 35.843499 -202.936006) (xy 35.895553 -202.919526) (xy 35.949514 -202.911189)
			(xy 35.976814 -202.910694) (xy 36.003463 -202.911189) (xy 36.056165 -202.919134) (xy 36.107094 -202.934845)
			(xy 36.155113 -202.957972) (xy 36.199149 -202.987996) (xy 36.238218 -203.024249) (xy 36.271448 -203.065919)
			(xy 36.298096 -203.112077) (xy 36.317567 -203.16169) (xy 36.329427 -203.213651) (xy 36.33341 -203.2668)
			(xy 36.331413 -203.293451) (xy 36.855136 -203.293451) (xy 36.855136 -203.240153) (xy 36.863079 -203.187449)
			(xy 36.878789 -203.136519) (xy 36.901915 -203.088498) (xy 36.931939 -203.044461) (xy 36.968191 -203.00539)
			(xy 37.009862 -202.972159) (xy 37.05602 -202.94551) (xy 37.105634 -202.926038) (xy 37.157596 -202.914178)
			(xy 37.210746 -202.910195) (xy 37.263896 -202.914178) (xy 37.315858 -202.926038) (xy 37.365472 -202.94551)
			(xy 37.41163 -202.972159) (xy 37.453301 -203.00539) (xy 37.489553 -203.044461) (xy 37.519577 -203.088498)
			(xy 37.542703 -203.136519) (xy 37.558413 -203.187449) (xy 37.566356 -203.240153) (xy 37.566854 -203.266802)
			(xy 37.566356 -203.293451) (xy 37.558413 -203.346155) (xy 37.542703 -203.397085) (xy 37.519577 -203.445106)
			(xy 37.489553 -203.489143) (xy 37.453301 -203.528214) (xy 37.41163 -203.561445) (xy 37.365472 -203.588094)
			(xy 37.315858 -203.607566) (xy 37.263896 -203.619426) (xy 37.210746 -203.62341) (xy 37.157596 -203.619426)
			(xy 37.105634 -203.607566) (xy 37.05602 -203.588094) (xy 37.009862 -203.561445) (xy 36.968191 -203.528214)
			(xy 36.931939 -203.489143) (xy 36.901915 -203.445106) (xy 36.878789 -203.397085) (xy 36.863079 -203.346155)
			(xy 36.855136 -203.293451) (xy 36.331413 -203.293451) (xy 36.329427 -203.319949) (xy 36.317567 -203.37191)
			(xy 36.298096 -203.421523) (xy 36.271448 -203.467681) (xy 36.238218 -203.509351) (xy 36.199149 -203.545604)
			(xy 36.155113 -203.575628) (xy 36.107094 -203.598755) (xy 36.056165 -203.614466) (xy 36.003463 -203.622411)
			(xy 35.976814 -203.62291) (xy 35.949551 -203.622405) (xy 35.895663 -203.614089) (xy 35.843675 -203.597648)
			(xy 35.794804 -203.573469) (xy 35.750193 -203.542116) (xy 35.73018 -203.523596) (xy 35.719773 -203.514176)
			(xy 35.695028 -203.500947) (xy 35.667614 -203.494966) (xy 35.639607 -203.496687) (xy 35.61313 -203.505978)
			(xy 35.601402 -203.51369) (xy 35.594791 -203.517967) (xy 35.579804 -203.522762) (xy 35.571938 -203.523088)
			(xy 34.172398 -203.523088) (xy 34.162243 -203.522569) (xy 34.143479 -203.514799) (xy 34.129115 -203.500441)
			(xy 34.121336 -203.48168) (xy 34.120836 -203.471526) (xy 32.391858 -203.471526) (xy 32.391858 -204.143335)
			(xy 33.411404 -204.143335) (xy 33.411404 -204.090037) (xy 33.419347 -204.037333) (xy 33.435057 -203.986403)
			(xy 33.458183 -203.938382) (xy 33.488207 -203.894345) (xy 33.524459 -203.855274) (xy 33.56613 -203.822043)
			(xy 33.612288 -203.795394) (xy 33.661902 -203.775922) (xy 33.713864 -203.764062) (xy 33.767014 -203.760079)
			(xy 33.820164 -203.764062) (xy 33.872126 -203.775922) (xy 33.92174 -203.795394) (xy 33.967898 -203.822043)
			(xy 34.009569 -203.855274) (xy 34.045821 -203.894345) (xy 34.075845 -203.938382) (xy 34.098971 -203.986403)
			(xy 34.114681 -204.037333) (xy 34.122624 -204.090037) (xy 34.123122 -204.116686) (xy 34.122624 -204.143335)
			(xy 35.621204 -204.143335) (xy 35.621204 -204.090037) (xy 35.629147 -204.037333) (xy 35.644857 -203.986403)
			(xy 35.667983 -203.938382) (xy 35.698007 -203.894345) (xy 35.734259 -203.855274) (xy 35.77593 -203.822043)
			(xy 35.822088 -203.795394) (xy 35.871702 -203.775922) (xy 35.923664 -203.764062) (xy 35.976814 -203.760079)
			(xy 36.029964 -203.764062) (xy 36.081926 -203.775922) (xy 36.13154 -203.795394) (xy 36.177698 -203.822043)
			(xy 36.219369 -203.855274) (xy 36.255621 -203.894345) (xy 36.285645 -203.938382) (xy 36.308771 -203.986403)
			(xy 36.324481 -204.037333) (xy 36.332424 -204.090037) (xy 36.332922 -204.116686) (xy 36.332424 -204.143335)
			(xy 36.324481 -204.196039) (xy 36.308771 -204.246969) (xy 36.285645 -204.29499) (xy 36.267632 -204.32141)
			(xy 37.564568 -204.32141) (xy 37.564568 -203.91247) (xy 37.565009 -203.902307) (xy 37.572799 -203.883531)
			(xy 37.587181 -203.869166) (xy 37.605966 -203.861398) (xy 37.61613 -203.860908) (xy 39.01567 -203.860908)
			(xy 39.025822 -203.861457) (xy 39.044585 -203.869216) (xy 39.05895 -203.883565) (xy 39.066731 -203.902318)
			(xy 39.067232 -203.91247) (xy 39.067232 -204.32141) (xy 39.066844 -204.331586) (xy 39.05905 -204.350387)
			(xy 39.044653 -204.364772) (xy 39.025846 -204.372551) (xy 39.01567 -204.372972) (xy 37.61613 -204.372972)
			(xy 37.605962 -204.372512) (xy 37.58717 -204.364738) (xy 37.572784 -204.350364) (xy 37.564996 -204.331578)
			(xy 37.564568 -204.32141) (xy 36.267632 -204.32141) (xy 36.255621 -204.339027) (xy 36.219369 -204.378098)
			(xy 36.177698 -204.411329) (xy 36.13154 -204.437978) (xy 36.081926 -204.45745) (xy 36.029964 -204.46931)
			(xy 35.976814 -204.473294) (xy 35.923664 -204.46931) (xy 35.871702 -204.45745) (xy 35.822088 -204.437978)
			(xy 35.77593 -204.411329) (xy 35.734259 -204.378098) (xy 35.698007 -204.339027) (xy 35.667983 -204.29499)
			(xy 35.644857 -204.246969) (xy 35.629147 -204.196039) (xy 35.621204 -204.143335) (xy 34.122624 -204.143335)
			(xy 34.114681 -204.196039) (xy 34.098971 -204.246969) (xy 34.075845 -204.29499) (xy 34.045821 -204.339027)
			(xy 34.009569 -204.378098) (xy 33.967898 -204.411329) (xy 33.92174 -204.437978) (xy 33.872126 -204.45745)
			(xy 33.820164 -204.46931) (xy 33.767014 -204.473294) (xy 33.713864 -204.46931) (xy 33.661902 -204.45745)
			(xy 33.612288 -204.437978) (xy 33.56613 -204.411329) (xy 33.524459 -204.378098) (xy 33.488207 -204.339027)
			(xy 33.458183 -204.29499) (xy 33.435057 -204.246969) (xy 33.419347 -204.196039) (xy 33.411404 -204.143335)
			(xy 32.391858 -204.143335) (xy 32.391858 -205.171548) (xy 34.120836 -205.171548) (xy 34.120836 -204.762608)
			(xy 34.121229 -204.75245) (xy 34.129029 -204.733691) (xy 34.143435 -204.719366) (xy 34.162238 -204.711672)
			(xy 34.172398 -204.7113) (xy 35.571938 -204.7113) (xy 35.579792 -204.711533) (xy 35.59479 -204.716198)
			(xy 35.601402 -204.720444) (xy 35.613129 -204.728051) (xy 35.639547 -204.737151) (xy 35.667444 -204.73873)
			(xy 35.694721 -204.732671) (xy 35.719325 -204.719428) (xy 35.729672 -204.71003) (xy 35.749709 -204.691444)
			(xy 35.794395 -204.659983) (xy 35.843368 -204.635728) (xy 35.895474 -204.61925) (xy 35.949489 -204.610938)
			(xy 35.976814 -204.610462) (xy 36.00346 -204.611021) (xy 36.056158 -204.618966) (xy 36.107082 -204.634676)
			(xy 36.155097 -204.6578) (xy 36.199128 -204.687822) (xy 36.238194 -204.724071) (xy 36.271421 -204.765737)
			(xy 36.298067 -204.811891) (xy 36.317536 -204.8615) (xy 36.329395 -204.913456) (xy 36.333377 -204.9666)
			(xy 36.331382 -204.993219) (xy 36.855136 -204.993219) (xy 36.855136 -204.939921) (xy 36.863079 -204.887217)
			(xy 36.878789 -204.836287) (xy 36.901915 -204.788266) (xy 36.931939 -204.744229) (xy 36.968191 -204.705158)
			(xy 37.009862 -204.671927) (xy 37.05602 -204.645278) (xy 37.105634 -204.625806) (xy 37.157596 -204.613946)
			(xy 37.210746 -204.609963) (xy 37.263896 -204.613946) (xy 37.315858 -204.625806) (xy 37.365472 -204.645278)
			(xy 37.41163 -204.671927) (xy 37.453301 -204.705158) (xy 37.489553 -204.744229) (xy 37.519577 -204.788266)
			(xy 37.542703 -204.836287) (xy 37.558413 -204.887217) (xy 37.566356 -204.939921) (xy 37.566854 -204.96657)
			(xy 37.566356 -204.993219) (xy 37.558413 -205.045923) (xy 37.542703 -205.096853) (xy 37.519577 -205.144874)
			(xy 37.489553 -205.188911) (xy 37.453301 -205.227982) (xy 37.41163 -205.261213) (xy 37.365472 -205.287862)
			(xy 37.315858 -205.307334) (xy 37.263896 -205.319194) (xy 37.210746 -205.323178) (xy 37.157596 -205.319194)
			(xy 37.105634 -205.307334) (xy 37.05602 -205.287862) (xy 37.009862 -205.261213) (xy 36.968191 -205.227982)
			(xy 36.931939 -205.188911) (xy 36.901915 -205.144874) (xy 36.878789 -205.096853) (xy 36.863079 -205.045923)
			(xy 36.855136 -204.993219) (xy 36.331382 -204.993219) (xy 36.329395 -205.019744) (xy 36.317536 -205.0717)
			(xy 36.298067 -205.121309) (xy 36.271421 -205.167463) (xy 36.238194 -205.209129) (xy 36.199128 -205.245378)
			(xy 36.155097 -205.2754) (xy 36.107082 -205.298524) (xy 36.056158 -205.314234) (xy 36.00346 -205.322179)
			(xy 35.976814 -205.322678) (xy 35.949551 -205.322182) (xy 35.895662 -205.313865) (xy 35.843673 -205.297423)
			(xy 35.794802 -205.273241) (xy 35.750193 -205.241886) (xy 35.73018 -205.223364) (xy 35.719729 -205.214016)
			(xy 35.694955 -205.200904) (xy 35.667554 -205.195002) (xy 35.63958 -205.196753) (xy 35.613128 -205.206024)
			(xy 35.601402 -205.213712) (xy 35.594789 -205.217955) (xy 35.579791 -205.222613) (xy 35.571938 -205.222856)
			(xy 34.172398 -205.222856) (xy 34.162271 -205.222375) (xy 34.143549 -205.214646) (xy 34.129192 -205.200358)
			(xy 34.121374 -205.181673) (xy 34.120836 -205.171548) (xy 32.391858 -205.171548) (xy 32.391858 -205.843357)
			(xy 33.411404 -205.843357) (xy 33.411404 -205.790059) (xy 33.419347 -205.737355) (xy 33.435057 -205.686425)
			(xy 33.458183 -205.638404) (xy 33.488207 -205.594367) (xy 33.524459 -205.555296) (xy 33.56613 -205.522065)
			(xy 33.612288 -205.495416) (xy 33.661902 -205.475944) (xy 33.713864 -205.464084) (xy 33.767014 -205.460101)
			(xy 33.820164 -205.464084) (xy 33.872126 -205.475944) (xy 33.92174 -205.495416) (xy 33.967898 -205.522065)
			(xy 34.009569 -205.555296) (xy 34.045821 -205.594367) (xy 34.075845 -205.638404) (xy 34.098971 -205.686425)
			(xy 34.114681 -205.737355) (xy 34.122624 -205.790059) (xy 34.123122 -205.816708) (xy 34.122624 -205.843357)
			(xy 35.621204 -205.843357) (xy 35.621204 -205.790059) (xy 35.629147 -205.737355) (xy 35.644857 -205.686425)
			(xy 35.667983 -205.638404) (xy 35.698007 -205.594367) (xy 35.734259 -205.555296) (xy 35.77593 -205.522065)
			(xy 35.822088 -205.495416) (xy 35.871702 -205.475944) (xy 35.923664 -205.464084) (xy 35.976814 -205.460101)
			(xy 36.029964 -205.464084) (xy 36.081926 -205.475944) (xy 36.13154 -205.495416) (xy 36.177698 -205.522065)
			(xy 36.219369 -205.555296) (xy 36.255621 -205.594367) (xy 36.285645 -205.638404) (xy 36.308771 -205.686425)
			(xy 36.324481 -205.737355) (xy 36.332424 -205.790059) (xy 36.332922 -205.816708) (xy 36.332424 -205.843357)
			(xy 36.324481 -205.896061) (xy 36.308771 -205.946991) (xy 36.285645 -205.995012) (xy 36.267632 -206.021432)
			(xy 37.564568 -206.021432) (xy 37.564568 -205.612492) (xy 37.565015 -205.602341) (xy 37.572807 -205.583595)
			(xy 37.587195 -205.569273) (xy 37.605978 -205.561568) (xy 37.61613 -205.561184) (xy 39.01567 -205.561184)
			(xy 39.0258 -205.561652) (xy 39.044529 -205.569378) (xy 39.058888 -205.583671) (xy 39.066701 -205.602364)
			(xy 39.067232 -205.612492) (xy 39.067232 -206.021432) (xy 39.066805 -206.031584) (xy 39.059005 -206.050331)
			(xy 39.044611 -206.064652) (xy 39.025824 -206.072357) (xy 39.01567 -206.07274) (xy 37.61613 -206.07274)
			(xy 37.606003 -206.072248) (xy 37.587278 -206.064527) (xy 37.57292 -206.050242) (xy 37.565104 -206.031557)
			(xy 37.564568 -206.021432) (xy 36.267632 -206.021432) (xy 36.255621 -206.039049) (xy 36.219369 -206.07812)
			(xy 36.177698 -206.111351) (xy 36.13154 -206.138) (xy 36.081926 -206.157472) (xy 36.029964 -206.169332)
			(xy 35.976814 -206.173316) (xy 35.923664 -206.169332) (xy 35.871702 -206.157472) (xy 35.822088 -206.138)
			(xy 35.77593 -206.111351) (xy 35.734259 -206.07812) (xy 35.698007 -206.039049) (xy 35.667983 -205.995012)
			(xy 35.644857 -205.946991) (xy 35.629147 -205.896061) (xy 35.621204 -205.843357) (xy 34.122624 -205.843357)
			(xy 34.114681 -205.896061) (xy 34.098971 -205.946991) (xy 34.075845 -205.995012) (xy 34.045821 -206.039049)
			(xy 34.009569 -206.07812) (xy 33.967898 -206.111351) (xy 33.92174 -206.138) (xy 33.872126 -206.157472)
			(xy 33.820164 -206.169332) (xy 33.767014 -206.173316) (xy 33.713864 -206.169332) (xy 33.661902 -206.157472)
			(xy 33.612288 -206.138) (xy 33.56613 -206.111351) (xy 33.524459 -206.07812) (xy 33.488207 -206.039049)
			(xy 33.458183 -205.995012) (xy 33.435057 -205.946991) (xy 33.419347 -205.896061) (xy 33.411404 -205.843357)
			(xy 32.391858 -205.843357) (xy 32.391858 -206.871316) (xy 34.120836 -206.871316) (xy 34.120836 -206.462376)
			(xy 34.121203 -206.452216) (xy 34.129013 -206.433456) (xy 34.143427 -206.419132) (xy 34.162235 -206.41144)
			(xy 34.172398 -206.411068) (xy 35.571938 -206.411068) (xy 35.579791 -206.411306) (xy 35.594789 -206.415968)
			(xy 35.601402 -206.420212) (xy 35.613161 -206.427803) (xy 35.639599 -206.436954) (xy 35.667527 -206.438595)
			(xy 35.694854 -206.432601) (xy 35.719532 -206.419423) (xy 35.729926 -206.410052) (xy 35.74992 -206.391457)
			(xy 35.794571 -206.360032) (xy 35.843498 -206.335796) (xy 35.895553 -206.319316) (xy 35.949514 -206.310979)
			(xy 35.976814 -206.310484) (xy 36.003462 -206.310999) (xy 36.056163 -206.318944) (xy 36.10709 -206.334655)
			(xy 36.155108 -206.35778) (xy 36.199142 -206.387804) (xy 36.23821 -206.424056) (xy 36.271439 -206.465725)
			(xy 36.298087 -206.511881) (xy 36.317558 -206.561493) (xy 36.329417 -206.613453) (xy 36.3334 -206.6666)
			(xy 36.331403 -206.693241) (xy 36.855136 -206.693241) (xy 36.855136 -206.639943) (xy 36.863079 -206.587239)
			(xy 36.878789 -206.536309) (xy 36.901915 -206.488288) (xy 36.931939 -206.444251) (xy 36.968191 -206.40518)
			(xy 37.009862 -206.371949) (xy 37.05602 -206.3453) (xy 37.105634 -206.325828) (xy 37.157596 -206.313968)
			(xy 37.210746 -206.309985) (xy 37.263896 -206.313968) (xy 37.315858 -206.325828) (xy 37.365472 -206.3453)
			(xy 37.41163 -206.371949) (xy 37.453301 -206.40518) (xy 37.489553 -206.444251) (xy 37.519577 -206.488288)
			(xy 37.542703 -206.536309) (xy 37.558413 -206.587239) (xy 37.566356 -206.639943) (xy 37.566854 -206.666592)
			(xy 37.566356 -206.693241) (xy 37.558413 -206.745945) (xy 37.542703 -206.796875) (xy 37.519577 -206.844896)
			(xy 37.489553 -206.888933) (xy 37.453301 -206.928004) (xy 37.41163 -206.961235) (xy 37.365472 -206.987884)
			(xy 37.315858 -207.007356) (xy 37.263896 -207.019216) (xy 37.210746 -207.0232) (xy 37.157596 -207.019216)
			(xy 37.105634 -207.007356) (xy 37.05602 -206.987884) (xy 37.009862 -206.961235) (xy 36.968191 -206.928004)
			(xy 36.931939 -206.888933) (xy 36.901915 -206.844896) (xy 36.878789 -206.796875) (xy 36.863079 -206.745945)
			(xy 36.855136 -206.693241) (xy 36.331403 -206.693241) (xy 36.329417 -206.719747) (xy 36.317558 -206.771707)
			(xy 36.298087 -206.821319) (xy 36.271439 -206.867475) (xy 36.23821 -206.909144) (xy 36.199142 -206.945396)
			(xy 36.155108 -206.97542) (xy 36.10709 -206.998545) (xy 36.056163 -207.014256) (xy 36.003462 -207.022201)
			(xy 35.976814 -207.0227) (xy 35.949551 -207.022198) (xy 35.895663 -207.013881) (xy 35.843675 -206.99744)
			(xy 35.794803 -206.97326) (xy 35.750193 -206.941907) (xy 35.73018 -206.923386) (xy 35.719773 -206.913966)
			(xy 35.695028 -206.900739) (xy 35.667614 -206.894758) (xy 35.639607 -206.896478) (xy 35.613131 -206.905768)
			(xy 35.601402 -206.91348) (xy 35.594787 -206.91772) (xy 35.579791 -206.92238) (xy 35.571938 -206.922624)
			(xy 34.172398 -206.922624) (xy 34.162267 -206.922174) (xy 34.143539 -206.914439) (xy 34.129181 -206.900141)
			(xy 34.121369 -206.881445) (xy 34.120836 -206.871316) (xy 32.391858 -206.871316) (xy 32.391858 -207.543379)
			(xy 33.411404 -207.543379) (xy 33.411404 -207.490081) (xy 33.419347 -207.437377) (xy 33.435057 -207.386447)
			(xy 33.458183 -207.338426) (xy 33.488207 -207.294389) (xy 33.524459 -207.255318) (xy 33.56613 -207.222087)
			(xy 33.612288 -207.195438) (xy 33.661902 -207.175966) (xy 33.713864 -207.164106) (xy 33.767014 -207.160123)
			(xy 33.820164 -207.164106) (xy 33.872126 -207.175966) (xy 33.92174 -207.195438) (xy 33.967898 -207.222087)
			(xy 34.009569 -207.255318) (xy 34.045821 -207.294389) (xy 34.075845 -207.338426) (xy 34.098971 -207.386447)
			(xy 34.114681 -207.437377) (xy 34.122624 -207.490081) (xy 34.123122 -207.51673) (xy 34.122624 -207.543379)
			(xy 35.621204 -207.543379) (xy 35.621204 -207.490081) (xy 35.629147 -207.437377) (xy 35.644857 -207.386447)
			(xy 35.667983 -207.338426) (xy 35.698007 -207.294389) (xy 35.734259 -207.255318) (xy 35.77593 -207.222087)
			(xy 35.822088 -207.195438) (xy 35.871702 -207.175966) (xy 35.923664 -207.164106) (xy 35.976814 -207.160123)
			(xy 36.029964 -207.164106) (xy 36.081926 -207.175966) (xy 36.13154 -207.195438) (xy 36.177698 -207.222087)
			(xy 36.219369 -207.255318) (xy 36.255621 -207.294389) (xy 36.285645 -207.338426) (xy 36.308771 -207.386447)
			(xy 36.324481 -207.437377) (xy 36.332424 -207.490081) (xy 36.332922 -207.51673) (xy 36.332424 -207.543379)
			(xy 36.324481 -207.596083) (xy 36.308771 -207.647013) (xy 36.285645 -207.695034) (xy 36.267632 -207.721454)
			(xy 37.564568 -207.721454) (xy 37.564568 -207.312514) (xy 37.564976 -207.30234) (xy 37.572762 -207.283539)
			(xy 37.587153 -207.269153) (xy 37.605955 -207.261373) (xy 37.61613 -207.260952) (xy 39.01567 -207.260952)
			(xy 39.025841 -207.261389) (xy 39.044638 -207.269167) (xy 39.059024 -207.283549) (xy 39.066808 -207.302343)
			(xy 39.067232 -207.312514) (xy 39.067232 -207.721454) (xy 39.066798 -207.731626) (xy 39.059022 -207.750426)
			(xy 39.044639 -207.764813) (xy 39.025842 -207.772595) (xy 39.01567 -207.773016) (xy 37.61613 -207.773016)
			(xy 37.605955 -207.77261) (xy 37.587152 -207.764827) (xy 37.572764 -207.750435) (xy 37.564987 -207.731629)
			(xy 37.564568 -207.721454) (xy 36.267632 -207.721454) (xy 36.255621 -207.739071) (xy 36.219369 -207.778142)
			(xy 36.177698 -207.811373) (xy 36.13154 -207.838022) (xy 36.081926 -207.857494) (xy 36.029964 -207.869354)
			(xy 35.976814 -207.873338) (xy 35.923664 -207.869354) (xy 35.871702 -207.857494) (xy 35.822088 -207.838022)
			(xy 35.77593 -207.811373) (xy 35.734259 -207.778142) (xy 35.698007 -207.739071) (xy 35.667983 -207.695034)
			(xy 35.644857 -207.647013) (xy 35.629147 -207.596083) (xy 35.621204 -207.543379) (xy 34.122624 -207.543379)
			(xy 34.114681 -207.596083) (xy 34.098971 -207.647013) (xy 34.075845 -207.695034) (xy 34.045821 -207.739071)
			(xy 34.009569 -207.778142) (xy 33.967898 -207.811373) (xy 33.92174 -207.838022) (xy 33.872126 -207.857494)
			(xy 33.820164 -207.869354) (xy 33.767014 -207.873338) (xy 33.713864 -207.869354) (xy 33.661902 -207.857494)
			(xy 33.612288 -207.838022) (xy 33.56613 -207.811373) (xy 33.524459 -207.778142) (xy 33.488207 -207.739071)
			(xy 33.458183 -207.695034) (xy 33.435057 -207.647013) (xy 33.419347 -207.596083) (xy 33.411404 -207.543379)
			(xy 32.391858 -207.543379) (xy 32.391858 -208.571338) (xy 34.120836 -208.571338) (xy 34.120836 -208.162398)
			(xy 34.121332 -208.15224) (xy 34.129106 -208.133472) (xy 34.143472 -208.119106) (xy 34.16224 -208.111332)
			(xy 34.172398 -208.110836) (xy 35.571938 -208.110836) (xy 35.579808 -208.111148) (xy 35.594807 -208.115928)
			(xy 35.601402 -208.120234) (xy 35.613163 -208.127821) (xy 35.6396 -208.136971) (xy 35.667527 -208.138611)
			(xy 35.694853 -208.132619) (xy 35.719531 -208.119444) (xy 35.729926 -208.110074) (xy 35.749924 -208.091483)
			(xy 35.794574 -208.060057) (xy 35.8435 -208.03582) (xy 35.895554 -208.019339) (xy 35.949514 -208.011002)
			(xy 35.976814 -208.010506) (xy 36.003464 -208.010977) (xy 36.056167 -208.018922) (xy 36.107098 -208.034634)
			(xy 36.155119 -208.057761) (xy 36.199156 -208.087787) (xy 36.238227 -208.124041) (xy 36.271458 -208.165712)
			(xy 36.298107 -208.211871) (xy 36.317579 -208.261487) (xy 36.329439 -208.31345) (xy 36.333422 -208.3666)
			(xy 36.331424 -208.393263) (xy 36.855136 -208.393263) (xy 36.855136 -208.339965) (xy 36.863079 -208.287261)
			(xy 36.878789 -208.236331) (xy 36.901915 -208.18831) (xy 36.931939 -208.144273) (xy 36.968191 -208.105202)
			(xy 37.009862 -208.071971) (xy 37.05602 -208.045322) (xy 37.105634 -208.02585) (xy 37.157596 -208.01399)
			(xy 37.210746 -208.010007) (xy 37.263896 -208.01399) (xy 37.315858 -208.02585) (xy 37.365472 -208.045322)
			(xy 37.41163 -208.071971) (xy 37.453301 -208.105202) (xy 37.489553 -208.144273) (xy 37.519577 -208.18831)
			(xy 37.542703 -208.236331) (xy 37.558413 -208.287261) (xy 37.566356 -208.339965) (xy 37.566854 -208.366614)
			(xy 37.566356 -208.393263) (xy 37.558413 -208.445967) (xy 37.542703 -208.496897) (xy 37.519577 -208.544918)
			(xy 37.489553 -208.588955) (xy 37.453301 -208.628026) (xy 37.41163 -208.661257) (xy 37.365472 -208.687906)
			(xy 37.315858 -208.707378) (xy 37.263896 -208.719238) (xy 37.210746 -208.723222) (xy 37.157596 -208.719238)
			(xy 37.105634 -208.707378) (xy 37.05602 -208.687906) (xy 37.009862 -208.661257) (xy 36.968191 -208.628026)
			(xy 36.931939 -208.588955) (xy 36.901915 -208.544918) (xy 36.878789 -208.496897) (xy 36.863079 -208.445967)
			(xy 36.855136 -208.393263) (xy 36.331424 -208.393263) (xy 36.329439 -208.41975) (xy 36.317579 -208.471713)
			(xy 36.298107 -208.521329) (xy 36.271458 -208.567488) (xy 36.238227 -208.609159) (xy 36.199156 -208.645413)
			(xy 36.155119 -208.675439) (xy 36.107098 -208.698566) (xy 36.056167 -208.714278) (xy 36.003464 -208.722223)
			(xy 35.976814 -208.722722) (xy 35.949551 -208.722214) (xy 35.895664 -208.713898) (xy 35.843676 -208.697458)
			(xy 35.794804 -208.673279) (xy 35.750194 -208.641928) (xy 35.73018 -208.623408) (xy 35.719773 -208.613988)
			(xy 35.695028 -208.600758) (xy 35.667614 -208.594776) (xy 35.639607 -208.596497) (xy 35.61313 -208.605789)
			(xy 35.601402 -208.613502) (xy 35.594792 -208.61778) (xy 35.579804 -208.622574) (xy 35.571938 -208.6229)
			(xy 34.172398 -208.6229) (xy 34.162245 -208.622369) (xy 34.143483 -208.614601) (xy 34.129119 -208.600247)
			(xy 34.121338 -208.581491) (xy 34.120836 -208.571338) (xy 32.391858 -208.571338) (xy 32.391858 -209.421476)
			(xy 34.120836 -209.421476) (xy 34.120836 -209.012536) (xy 34.121252 -209.00238) (xy 34.129042 -208.983621)
			(xy 34.143442 -208.969295) (xy 34.16224 -208.961601) (xy 34.172398 -208.961228) (xy 35.571938 -208.961228)
			(xy 35.579791 -208.961472) (xy 35.594788 -208.966131) (xy 35.601402 -208.970372) (xy 35.613166 -208.977953)
			(xy 35.639602 -208.987099) (xy 35.667527 -208.988738) (xy 35.694851 -208.982749) (xy 35.71953 -208.969578)
			(xy 35.729926 -208.960212) (xy 35.749929 -208.941627) (xy 35.794577 -208.910199) (xy 35.843502 -208.88596)
			(xy 35.895555 -208.869478) (xy 35.949514 -208.86114) (xy 35.976814 -208.860644) (xy 36.003459 -208.861239)
			(xy 36.056154 -208.869183) (xy 36.107076 -208.884892) (xy 36.155088 -208.908016) (xy 36.199117 -208.938036)
			(xy 36.238181 -208.974283) (xy 36.271406 -209.015948) (xy 36.29805 -209.062098) (xy 36.317519 -209.111705)
			(xy 36.329377 -209.163659) (xy 36.333359 -209.2168) (xy 36.329377 -209.269941) (xy 36.317519 -209.321895)
			(xy 36.29805 -209.371502) (xy 36.271406 -209.417652) (xy 36.268357 -209.421476) (xy 37.564568 -209.421476)
			(xy 37.564568 -209.012536) (xy 37.565051 -209.002388) (xy 37.572828 -208.983643) (xy 37.587206 -208.969319)
			(xy 37.605981 -208.961613) (xy 37.61613 -208.961228) (xy 39.01567 -208.961228) (xy 39.025793 -208.961751)
			(xy 39.044512 -208.969466) (xy 39.058869 -208.983742) (xy 39.066691 -209.002416) (xy 39.067232 -209.012536)
			(xy 39.067232 -209.421476) (xy 39.06676 -209.431625) (xy 39.058978 -209.45037) (xy 39.044597 -209.464694)
			(xy 39.02582 -209.4724) (xy 39.01567 -209.472784) (xy 37.61613 -209.472784) (xy 37.606008 -209.47225)
			(xy 37.587292 -209.464536) (xy 37.572936 -209.450265) (xy 37.565111 -209.431595) (xy 37.564568 -209.421476)
			(xy 36.268357 -209.421476) (xy 36.238181 -209.459317) (xy 36.199117 -209.495564) (xy 36.155088 -209.525584)
			(xy 36.107076 -209.548708) (xy 36.056154 -209.564417) (xy 36.003459 -209.572361) (xy 35.976814 -209.57286)
			(xy 35.94955 -209.572369) (xy 35.895661 -209.564051) (xy 35.843672 -209.547608) (xy 35.794801 -209.523425)
			(xy 35.750192 -209.492069) (xy 35.73018 -209.473546) (xy 35.719774 -209.464127) (xy 35.695027 -209.450904)
			(xy 35.667614 -209.444925) (xy 35.639608 -209.446645) (xy 35.613132 -209.455931) (xy 35.601402 -209.46364)
			(xy 35.59479 -209.467885) (xy 35.579792 -209.472541) (xy 35.571938 -209.472784) (xy 34.172398 -209.472784)
			(xy 34.162274 -209.472276) (xy 34.143558 -209.464552) (xy 34.129202 -209.450272) (xy 34.121379 -209.431597)
			(xy 34.120836 -209.421476) (xy 32.391858 -209.421476) (xy 32.391858 -210.093285) (xy 33.411404 -210.093285)
			(xy 33.411404 -210.039987) (xy 33.419347 -209.987283) (xy 33.435057 -209.936353) (xy 33.458183 -209.888332)
			(xy 33.488207 -209.844295) (xy 33.524459 -209.805224) (xy 33.56613 -209.771993) (xy 33.612288 -209.745344)
			(xy 33.661902 -209.725872) (xy 33.713864 -209.714012) (xy 33.767014 -209.710029) (xy 33.820164 -209.714012)
			(xy 33.872126 -209.725872) (xy 33.92174 -209.745344) (xy 33.967898 -209.771993) (xy 34.009569 -209.805224)
			(xy 34.045821 -209.844295) (xy 34.075845 -209.888332) (xy 34.098971 -209.936353) (xy 34.114681 -209.987283)
			(xy 34.122624 -210.039987) (xy 34.123122 -210.066636) (xy 34.122624 -210.093285) (xy 35.621204 -210.093285)
			(xy 35.621204 -210.039987) (xy 35.629147 -209.987283) (xy 35.644857 -209.936353) (xy 35.667983 -209.888332)
			(xy 35.698007 -209.844295) (xy 35.734259 -209.805224) (xy 35.77593 -209.771993) (xy 35.822088 -209.745344)
			(xy 35.871702 -209.725872) (xy 35.923664 -209.714012) (xy 35.976814 -209.710029) (xy 36.029964 -209.714012)
			(xy 36.081926 -209.725872) (xy 36.13154 -209.745344) (xy 36.177698 -209.771993) (xy 36.219369 -209.805224)
			(xy 36.255621 -209.844295) (xy 36.285645 -209.888332) (xy 36.308771 -209.936353) (xy 36.324481 -209.987283)
			(xy 36.332424 -210.039987) (xy 36.332922 -210.066636) (xy 36.332424 -210.093285) (xy 36.324481 -210.145989)
			(xy 36.308771 -210.196919) (xy 36.285645 -210.24494) (xy 36.267632 -210.27136) (xy 37.564568 -210.27136)
			(xy 37.564568 -209.86242) (xy 37.565037 -209.852271) (xy 37.57282 -209.833525) (xy 37.587202 -209.819202)
			(xy 37.60598 -209.811496) (xy 37.61613 -209.811112) (xy 39.01567 -209.811112) (xy 39.025791 -209.81165)
			(xy 39.044507 -209.819363) (xy 39.058863 -209.833633) (xy 39.066688 -209.852302) (xy 39.067232 -209.86242)
			(xy 39.067232 -210.27136) (xy 39.066746 -210.281508) (xy 39.05897 -210.300253) (xy 39.044593 -210.314576)
			(xy 39.025819 -210.322283) (xy 39.01567 -210.322668) (xy 37.61613 -210.322668) (xy 37.606006 -210.322149)
			(xy 37.587287 -210.314433) (xy 37.57293 -210.300156) (xy 37.565108 -210.281481) (xy 37.564568 -210.27136)
			(xy 36.267632 -210.27136) (xy 36.255621 -210.288977) (xy 36.219369 -210.328048) (xy 36.177698 -210.361279)
			(xy 36.13154 -210.387928) (xy 36.081926 -210.4074) (xy 36.029964 -210.41926) (xy 35.976814 -210.423244)
			(xy 35.923664 -210.41926) (xy 35.871702 -210.4074) (xy 35.822088 -210.387928) (xy 35.77593 -210.361279)
			(xy 35.734259 -210.328048) (xy 35.698007 -210.288977) (xy 35.667983 -210.24494) (xy 35.644857 -210.196919)
			(xy 35.629147 -210.145989) (xy 35.621204 -210.093285) (xy 34.122624 -210.093285) (xy 34.114681 -210.145989)
			(xy 34.098971 -210.196919) (xy 34.075845 -210.24494) (xy 34.045821 -210.288977) (xy 34.009569 -210.328048)
			(xy 33.967898 -210.361279) (xy 33.92174 -210.387928) (xy 33.872126 -210.4074) (xy 33.820164 -210.41926)
			(xy 33.767014 -210.423244) (xy 33.713864 -210.41926) (xy 33.661902 -210.4074) (xy 33.612288 -210.387928)
			(xy 33.56613 -210.361279) (xy 33.524459 -210.328048) (xy 33.488207 -210.288977) (xy 33.458183 -210.24494)
			(xy 33.435057 -210.196919) (xy 33.419347 -210.145989) (xy 33.411404 -210.093285) (xy 32.391858 -210.093285)
			(xy 32.391858 -211.121498) (xy 34.120836 -211.121498) (xy 34.120836 -210.712558) (xy 34.121299 -210.702398)
			(xy 34.129087 -210.683628) (xy 34.143462 -210.669264) (xy 34.162237 -210.661491) (xy 34.172398 -210.660996)
			(xy 35.571938 -210.660996) (xy 35.579808 -210.661315) (xy 35.594806 -210.666091) (xy 35.601402 -210.670394)
			(xy 35.613167 -210.677972) (xy 35.639603 -210.687115) (xy 35.667526 -210.688754) (xy 35.69485 -210.682766)
			(xy 35.719529 -210.669599) (xy 35.729926 -210.660234) (xy 35.749917 -210.641636) (xy 35.79457 -210.610212)
			(xy 35.843497 -210.585977) (xy 35.895552 -210.569498) (xy 35.949513 -210.561161) (xy 35.976814 -210.560666)
			(xy 36.003461 -210.561217) (xy 36.056158 -210.569162) (xy 36.107084 -210.584872) (xy 36.155099 -210.607996)
			(xy 36.199131 -210.638019) (xy 36.238197 -210.674268) (xy 36.271424 -210.715935) (xy 36.29807 -210.762089)
			(xy 36.31754 -210.811698) (xy 36.329398 -210.863656) (xy 36.333381 -210.9168) (xy 36.331386 -210.943423)
			(xy 36.855136 -210.943423) (xy 36.855136 -210.890125) (xy 36.863079 -210.837421) (xy 36.878789 -210.786491)
			(xy 36.901915 -210.73847) (xy 36.931939 -210.694433) (xy 36.968191 -210.655362) (xy 37.009862 -210.622131)
			(xy 37.05602 -210.595482) (xy 37.105634 -210.57601) (xy 37.157596 -210.56415) (xy 37.210746 -210.560167)
			(xy 37.263896 -210.56415) (xy 37.315858 -210.57601) (xy 37.365472 -210.595482) (xy 37.41163 -210.622131)
			(xy 37.453301 -210.655362) (xy 37.489553 -210.694433) (xy 37.519577 -210.73847) (xy 37.542703 -210.786491)
			(xy 37.558413 -210.837421) (xy 37.566356 -210.890125) (xy 37.566854 -210.916774) (xy 37.566356 -210.943423)
			(xy 37.558413 -210.996127) (xy 37.542703 -211.047057) (xy 37.519577 -211.095078) (xy 37.489553 -211.139115)
			(xy 37.453301 -211.178186) (xy 37.41163 -211.211417) (xy 37.365472 -211.238066) (xy 37.315858 -211.257538)
			(xy 37.263896 -211.269398) (xy 37.210746 -211.273382) (xy 37.157596 -211.269398) (xy 37.105634 -211.257538)
			(xy 37.05602 -211.238066) (xy 37.009862 -211.211417) (xy 36.968191 -211.178186) (xy 36.931939 -211.139115)
			(xy 36.901915 -211.095078) (xy 36.878789 -211.047057) (xy 36.863079 -210.996127) (xy 36.855136 -210.943423)
			(xy 36.331386 -210.943423) (xy 36.329398 -210.969944) (xy 36.31754 -211.021902) (xy 36.29807 -211.071511)
			(xy 36.271424 -211.117665) (xy 36.238197 -211.159332) (xy 36.199131 -211.195581) (xy 36.155099 -211.225604)
			(xy 36.107084 -211.248728) (xy 36.056158 -211.264438) (xy 36.003461 -211.272383) (xy 35.976814 -211.272882)
			(xy 35.949551 -211.272385) (xy 35.895662 -211.264068) (xy 35.843674 -211.247626) (xy 35.794802 -211.223444)
			(xy 35.750193 -211.19209) (xy 35.73018 -211.173568) (xy 35.719774 -211.164149) (xy 35.695028 -211.150923)
			(xy 35.667614 -211.144943) (xy 35.639608 -211.146663) (xy 35.613131 -211.155952) (xy 35.601402 -211.163662)
			(xy 35.59479 -211.167936) (xy 35.579804 -211.172733) (xy 35.571938 -211.17306) (xy 34.172398 -211.17306)
			(xy 34.16224 -211.172568) (xy 34.14347 -211.164793) (xy 34.129105 -211.150426) (xy 34.121331 -211.131656)
			(xy 34.120836 -211.121498) (xy 32.391858 -211.121498) (xy 32.391858 -211.793307) (xy 33.411404 -211.793307)
			(xy 33.411404 -211.740009) (xy 33.419347 -211.687305) (xy 33.435057 -211.636375) (xy 33.458183 -211.588354)
			(xy 33.488207 -211.544317) (xy 33.524459 -211.505246) (xy 33.56613 -211.472015) (xy 33.612288 -211.445366)
			(xy 33.661902 -211.425894) (xy 33.713864 -211.414034) (xy 33.767014 -211.410051) (xy 33.820164 -211.414034)
			(xy 33.872126 -211.425894) (xy 33.92174 -211.445366) (xy 33.967898 -211.472015) (xy 34.009569 -211.505246)
			(xy 34.045821 -211.544317) (xy 34.075845 -211.588354) (xy 34.098971 -211.636375) (xy 34.114681 -211.687305)
			(xy 34.122624 -211.740009) (xy 34.123122 -211.766658) (xy 34.122624 -211.793307) (xy 35.621204 -211.793307)
			(xy 35.621204 -211.740009) (xy 35.629147 -211.687305) (xy 35.644857 -211.636375) (xy 35.667983 -211.588354)
			(xy 35.698007 -211.544317) (xy 35.734259 -211.505246) (xy 35.77593 -211.472015) (xy 35.822088 -211.445366)
			(xy 35.871702 -211.425894) (xy 35.923664 -211.414034) (xy 35.976814 -211.410051) (xy 36.029964 -211.414034)
			(xy 36.081926 -211.425894) (xy 36.13154 -211.445366) (xy 36.177698 -211.472015) (xy 36.219369 -211.505246)
			(xy 36.255621 -211.544317) (xy 36.285645 -211.588354) (xy 36.308771 -211.636375) (xy 36.324481 -211.687305)
			(xy 36.332424 -211.740009) (xy 36.332922 -211.766658) (xy 36.332424 -211.793307) (xy 36.324481 -211.846011)
			(xy 36.308771 -211.896941) (xy 36.285645 -211.944962) (xy 36.267632 -211.971382) (xy 37.564568 -211.971382)
			(xy 37.564568 -211.562442) (xy 37.564999 -211.552269) (xy 37.572776 -211.53347) (xy 37.58716 -211.519082)
			(xy 37.605957 -211.511301) (xy 37.61613 -211.51088) (xy 39.01567 -211.51088) (xy 39.025845 -211.51129)
			(xy 39.044647 -211.519072) (xy 39.059034 -211.533463) (xy 39.066813 -211.552267) (xy 39.067232 -211.562442)
			(xy 39.067232 -211.971382) (xy 39.066821 -211.981556) (xy 39.059036 -212.000356) (xy 39.044646 -212.014743)
			(xy 39.025844 -212.022523) (xy 39.01567 -212.022944) (xy 37.61613 -212.022944) (xy 37.605958 -212.022511)
			(xy 37.587161 -212.014733) (xy 37.572774 -212.000349) (xy 37.564991 -211.981554) (xy 37.564568 -211.971382)
			(xy 36.267632 -211.971382) (xy 36.255621 -211.988999) (xy 36.219369 -212.02807) (xy 36.177698 -212.061301)
			(xy 36.13154 -212.08795) (xy 36.081926 -212.107422) (xy 36.029964 -212.119282) (xy 35.976814 -212.123266)
			(xy 35.923664 -212.119282) (xy 35.871702 -212.107422) (xy 35.822088 -212.08795) (xy 35.77593 -212.061301)
			(xy 35.734259 -212.02807) (xy 35.698007 -211.988999) (xy 35.667983 -211.944962) (xy 35.644857 -211.896941)
			(xy 35.629147 -211.846011) (xy 35.621204 -211.793307) (xy 34.122624 -211.793307) (xy 34.114681 -211.846011)
			(xy 34.098971 -211.896941) (xy 34.075845 -211.944962) (xy 34.045821 -211.988999) (xy 34.009569 -212.02807)
			(xy 33.967898 -212.061301) (xy 33.92174 -212.08795) (xy 33.872126 -212.107422) (xy 33.820164 -212.119282)
			(xy 33.767014 -212.123266) (xy 33.713864 -212.119282) (xy 33.661902 -212.107422) (xy 33.612288 -212.08795)
			(xy 33.56613 -212.061301) (xy 33.524459 -212.02807) (xy 33.488207 -211.988999) (xy 33.458183 -211.944962)
			(xy 33.435057 -211.896941) (xy 33.419347 -211.846011) (xy 33.411404 -211.793307) (xy 32.391858 -211.793307)
			(xy 32.391858 -212.82152) (xy 34.120836 -212.82152) (xy 34.120836 -212.41258) (xy 34.121206 -212.40242)
			(xy 34.129015 -212.38366) (xy 34.143428 -212.369336) (xy 34.162236 -212.361644) (xy 34.172398 -212.361272)
			(xy 35.571938 -212.361272) (xy 35.579792 -212.36151) (xy 35.594789 -212.366172) (xy 35.601402 -212.370416)
			(xy 35.613162 -212.378006) (xy 35.639599 -212.387157) (xy 35.667527 -212.388798) (xy 35.694853 -212.382805)
			(xy 35.719532 -212.369627) (xy 35.729926 -212.360256) (xy 35.749921 -212.341661) (xy 35.794572 -212.310237)
			(xy 35.843499 -212.286) (xy 35.895553 -212.26952) (xy 35.949514 -212.261183) (xy 35.976814 -212.260688)
			(xy 36.003462 -212.261195) (xy 36.056163 -212.26914) (xy 36.107092 -212.284851) (xy 36.15511 -212.307977)
			(xy 36.199145 -212.338001) (xy 36.238213 -212.374253) (xy 36.271443 -212.415923) (xy 36.29809 -212.462079)
			(xy 36.317561 -212.511692) (xy 36.329421 -212.563652) (xy 36.333404 -212.6168) (xy 36.331407 -212.643445)
			(xy 36.855136 -212.643445) (xy 36.855136 -212.590147) (xy 36.863079 -212.537443) (xy 36.878789 -212.486513)
			(xy 36.901915 -212.438492) (xy 36.931939 -212.394455) (xy 36.968191 -212.355384) (xy 37.009862 -212.322153)
			(xy 37.05602 -212.295504) (xy 37.105634 -212.276032) (xy 37.157596 -212.264172) (xy 37.210746 -212.260189)
			(xy 37.263896 -212.264172) (xy 37.315858 -212.276032) (xy 37.365472 -212.295504) (xy 37.41163 -212.322153)
			(xy 37.453301 -212.355384) (xy 37.489553 -212.394455) (xy 37.519577 -212.438492) (xy 37.542703 -212.486513)
			(xy 37.558413 -212.537443) (xy 37.566356 -212.590147) (xy 37.566854 -212.616796) (xy 37.566356 -212.643445)
			(xy 37.558413 -212.696149) (xy 37.542703 -212.747079) (xy 37.519577 -212.7951) (xy 37.489553 -212.839137)
			(xy 37.453301 -212.878208) (xy 37.41163 -212.911439) (xy 37.365472 -212.938088) (xy 37.315858 -212.95756)
			(xy 37.263896 -212.96942) (xy 37.210746 -212.973404) (xy 37.157596 -212.96942) (xy 37.105634 -212.95756)
			(xy 37.05602 -212.938088) (xy 37.009862 -212.911439) (xy 36.968191 -212.878208) (xy 36.931939 -212.839137)
			(xy 36.901915 -212.7951) (xy 36.878789 -212.747079) (xy 36.863079 -212.696149) (xy 36.855136 -212.643445)
			(xy 36.331407 -212.643445) (xy 36.329421 -212.669948) (xy 36.317561 -212.721908) (xy 36.29809 -212.771521)
			(xy 36.271443 -212.817677) (xy 36.238213 -212.859347) (xy 36.199145 -212.895599) (xy 36.15511 -212.925623)
			(xy 36.107092 -212.948749) (xy 36.056163 -212.96446) (xy 36.003462 -212.972405) (xy 35.976814 -212.972904)
			(xy 35.949551 -212.972401) (xy 35.895663 -212.964084) (xy 35.843675 -212.947644) (xy 35.794803 -212.923464)
			(xy 35.750193 -212.89211) (xy 35.73018 -212.87359) (xy 35.719773 -212.86417) (xy 35.695028 -212.850942)
			(xy 35.667614 -212.844961) (xy 35.639607 -212.846682) (xy 35.613131 -212.855972) (xy 35.601402 -212.863684)
			(xy 35.594787 -212.867924) (xy 35.579791 -212.872584) (xy 35.571938 -212.872828) (xy 34.172398 -212.872828)
			(xy 34.162267 -212.872374) (xy 34.14354 -212.86464) (xy 34.129183 -212.850343) (xy 34.121369 -212.831649)
			(xy 34.120836 -212.82152) (xy 32.391858 -212.82152) (xy 32.391858 -213.493329) (xy 33.411404 -213.493329)
			(xy 33.411404 -213.440031) (xy 33.419347 -213.387327) (xy 33.435057 -213.336397) (xy 33.458183 -213.288376)
			(xy 33.488207 -213.244339) (xy 33.524459 -213.205268) (xy 33.56613 -213.172037) (xy 33.612288 -213.145388)
			(xy 33.661902 -213.125916) (xy 33.713864 -213.114056) (xy 33.767014 -213.110073) (xy 33.820164 -213.114056)
			(xy 33.872126 -213.125916) (xy 33.92174 -213.145388) (xy 33.967898 -213.172037) (xy 34.009569 -213.205268)
			(xy 34.045821 -213.244339) (xy 34.075845 -213.288376) (xy 34.098971 -213.336397) (xy 34.114681 -213.387327)
			(xy 34.122624 -213.440031) (xy 34.123122 -213.46668) (xy 34.122624 -213.493329) (xy 35.621204 -213.493329)
			(xy 35.621204 -213.440031) (xy 35.629147 -213.387327) (xy 35.644857 -213.336397) (xy 35.667983 -213.288376)
			(xy 35.698007 -213.244339) (xy 35.734259 -213.205268) (xy 35.77593 -213.172037) (xy 35.822088 -213.145388)
			(xy 35.871702 -213.125916) (xy 35.923664 -213.114056) (xy 35.976814 -213.110073) (xy 36.029964 -213.114056)
			(xy 36.081926 -213.125916) (xy 36.13154 -213.145388) (xy 36.177698 -213.172037) (xy 36.219369 -213.205268)
			(xy 36.255621 -213.244339) (xy 36.285645 -213.288376) (xy 36.308771 -213.336397) (xy 36.324481 -213.387327)
			(xy 36.332424 -213.440031) (xy 36.332922 -213.46668) (xy 36.332424 -213.493329) (xy 36.324481 -213.546033)
			(xy 36.308771 -213.596963) (xy 36.285645 -213.644984) (xy 36.267632 -213.671404) (xy 37.564568 -213.671404)
			(xy 37.564568 -213.262464) (xy 37.564991 -213.252312) (xy 37.572793 -213.233565) (xy 37.587188 -213.219244)
			(xy 37.605975 -213.211539) (xy 37.61613 -213.211156) (xy 39.01567 -213.211156) (xy 39.025797 -213.211651)
			(xy 39.04452 -213.219372) (xy 39.058878 -213.233656) (xy 39.066696 -213.25234) (xy 39.067232 -213.262464)
			(xy 39.067232 -213.671404) (xy 39.066782 -213.681554) (xy 39.058991 -213.700301) (xy 39.044604 -213.714623)
			(xy 39.025822 -213.722328) (xy 39.01567 -213.722712) (xy 37.61613 -213.722712) (xy 37.606012 -213.722151)
			(xy 37.587301 -213.714442) (xy 37.572945 -213.700179) (xy 37.565116 -213.681519) (xy 37.564568 -213.671404)
			(xy 36.267632 -213.671404) (xy 36.255621 -213.689021) (xy 36.219369 -213.728092) (xy 36.177698 -213.761323)
			(xy 36.13154 -213.787972) (xy 36.081926 -213.807444) (xy 36.029964 -213.819304) (xy 35.976814 -213.823288)
			(xy 35.923664 -213.819304) (xy 35.871702 -213.807444) (xy 35.822088 -213.787972) (xy 35.77593 -213.761323)
			(xy 35.734259 -213.728092) (xy 35.698007 -213.689021) (xy 35.667983 -213.644984) (xy 35.644857 -213.596963)
			(xy 35.629147 -213.546033) (xy 35.621204 -213.493329) (xy 34.122624 -213.493329) (xy 34.114681 -213.546033)
			(xy 34.098971 -213.596963) (xy 34.075845 -213.644984) (xy 34.045821 -213.689021) (xy 34.009569 -213.728092)
			(xy 33.967898 -213.761323) (xy 33.92174 -213.787972) (xy 33.872126 -213.807444) (xy 33.820164 -213.819304)
			(xy 33.767014 -213.823288) (xy 33.713864 -213.819304) (xy 33.661902 -213.807444) (xy 33.612288 -213.787972)
			(xy 33.56613 -213.761323) (xy 33.524459 -213.728092) (xy 33.488207 -213.689021) (xy 33.458183 -213.644984)
			(xy 33.435057 -213.596963) (xy 33.419347 -213.546033) (xy 33.411404 -213.493329) (xy 32.391858 -213.493329)
			(xy 32.391858 -214.521542) (xy 34.120836 -214.521542) (xy 34.120836 -214.112602) (xy 34.121335 -214.102445)
			(xy 34.129108 -214.083676) (xy 34.143473 -214.069311) (xy 34.162241 -214.061536) (xy 34.172398 -214.06104)
			(xy 35.571938 -214.06104) (xy 35.579808 -214.061352) (xy 35.594807 -214.066132) (xy 35.601402 -214.070438)
			(xy 35.613128 -214.078046) (xy 35.639547 -214.087146) (xy 35.667444 -214.088726) (xy 35.694721 -214.082666)
			(xy 35.719325 -214.069422) (xy 35.729672 -214.060024) (xy 35.749708 -214.041437) (xy 35.794394 -214.009976)
			(xy 35.843367 -213.985721) (xy 35.895474 -213.969244) (xy 35.949489 -213.960932) (xy 35.976814 -213.960456)
			(xy 36.00346 -213.961027) (xy 36.056156 -213.968972) (xy 36.10708 -213.984681) (xy 36.155094 -214.007805)
			(xy 36.199125 -214.037827) (xy 36.23819 -214.074075) (xy 36.271416 -214.115741) (xy 36.298061 -214.161893)
			(xy 36.31753 -214.211501) (xy 36.329389 -214.263457) (xy 36.333371 -214.3166) (xy 36.331377 -214.343213)
			(xy 36.855136 -214.343213) (xy 36.855136 -214.289915) (xy 36.863079 -214.237211) (xy 36.878789 -214.186281)
			(xy 36.901915 -214.13826) (xy 36.931939 -214.094223) (xy 36.968191 -214.055152) (xy 37.009862 -214.021921)
			(xy 37.05602 -213.995272) (xy 37.105634 -213.9758) (xy 37.157596 -213.96394) (xy 37.210746 -213.959957)
			(xy 37.263896 -213.96394) (xy 37.315858 -213.9758) (xy 37.365472 -213.995272) (xy 37.41163 -214.021921)
			(xy 37.453301 -214.055152) (xy 37.489553 -214.094223) (xy 37.519577 -214.13826) (xy 37.542703 -214.186281)
			(xy 37.558413 -214.237211) (xy 37.566356 -214.289915) (xy 37.566854 -214.316564) (xy 37.566356 -214.343213)
			(xy 37.558413 -214.395917) (xy 37.542703 -214.446847) (xy 37.519577 -214.494868) (xy 37.489553 -214.538905)
			(xy 37.453301 -214.577976) (xy 37.41163 -214.611207) (xy 37.365472 -214.637856) (xy 37.315858 -214.657328)
			(xy 37.263896 -214.669188) (xy 37.210746 -214.673172) (xy 37.157596 -214.669188) (xy 37.105634 -214.657328)
			(xy 37.05602 -214.637856) (xy 37.009862 -214.611207) (xy 36.968191 -214.577976) (xy 36.931939 -214.538905)
			(xy 36.901915 -214.494868) (xy 36.878789 -214.446847) (xy 36.863079 -214.395917) (xy 36.855136 -214.343213)
			(xy 36.331377 -214.343213) (xy 36.329389 -214.369743) (xy 36.31753 -214.421699) (xy 36.298061 -214.471307)
			(xy 36.271416 -214.517459) (xy 36.23819 -214.559125) (xy 36.199125 -214.595373) (xy 36.155094 -214.625395)
			(xy 36.10708 -214.648519) (xy 36.056156 -214.664228) (xy 36.00346 -214.672173) (xy 35.976814 -214.672672)
			(xy 35.949551 -214.672178) (xy 35.895662 -214.66386) (xy 35.843673 -214.647418) (xy 35.794802 -214.623236)
			(xy 35.750193 -214.59188) (xy 35.73018 -214.573358) (xy 35.71973 -214.564009) (xy 35.694956 -214.550899)
			(xy 35.667554 -214.544997) (xy 35.63958 -214.546747) (xy 35.613128 -214.556018) (xy 35.601402 -214.563706)
			(xy 35.594792 -214.567985) (xy 35.579804 -214.572778) (xy 35.571938 -214.573104) (xy 34.172398 -214.573104)
			(xy 34.162245 -214.572569) (xy 34.143484 -214.564802) (xy 34.129121 -214.550449) (xy 34.121339 -214.531694)
			(xy 34.120836 -214.521542) (xy 32.391858 -214.521542) (xy 32.391858 -215.193351) (xy 33.411404 -215.193351)
			(xy 33.411404 -215.140053) (xy 33.419347 -215.087349) (xy 33.435057 -215.036419) (xy 33.458183 -214.988398)
			(xy 33.488207 -214.944361) (xy 33.524459 -214.90529) (xy 33.56613 -214.872059) (xy 33.612288 -214.84541)
			(xy 33.661902 -214.825938) (xy 33.713864 -214.814078) (xy 33.767014 -214.810095) (xy 33.820164 -214.814078)
			(xy 33.872126 -214.825938) (xy 33.92174 -214.84541) (xy 33.967898 -214.872059) (xy 34.009569 -214.90529)
			(xy 34.045821 -214.944361) (xy 34.075845 -214.988398) (xy 34.098971 -215.036419) (xy 34.114681 -215.087349)
			(xy 34.122624 -215.140053) (xy 34.123122 -215.166702) (xy 34.122624 -215.193351) (xy 35.621204 -215.193351)
			(xy 35.621204 -215.140053) (xy 35.629147 -215.087349) (xy 35.644857 -215.036419) (xy 35.667983 -214.988398)
			(xy 35.698007 -214.944361) (xy 35.734259 -214.90529) (xy 35.77593 -214.872059) (xy 35.822088 -214.84541)
			(xy 35.871702 -214.825938) (xy 35.923664 -214.814078) (xy 35.976814 -214.810095) (xy 36.029964 -214.814078)
			(xy 36.081926 -214.825938) (xy 36.13154 -214.84541) (xy 36.177698 -214.872059) (xy 36.219369 -214.90529)
			(xy 36.255621 -214.944361) (xy 36.285645 -214.988398) (xy 36.308771 -215.036419) (xy 36.324481 -215.087349)
			(xy 36.332424 -215.140053) (xy 36.332922 -215.166702) (xy 36.332424 -215.193351) (xy 36.324481 -215.246055)
			(xy 36.308771 -215.296985) (xy 36.285645 -215.345006) (xy 36.267632 -215.371426) (xy 37.564568 -215.371426)
			(xy 37.564568 -214.962486) (xy 37.564953 -214.95231) (xy 37.572748 -214.933509) (xy 37.587146 -214.919124)
			(xy 37.605953 -214.911345) (xy 37.61613 -214.910924) (xy 39.01567 -214.910924) (xy 39.025838 -214.911388)
			(xy 39.044629 -214.919161) (xy 39.059015 -214.933534) (xy 39.066803 -214.952318) (xy 39.067232 -214.962486)
			(xy 39.067232 -215.371426) (xy 39.066857 -215.381603) (xy 39.059058 -215.400404) (xy 39.044657 -215.414789)
			(xy 39.025848 -215.422568) (xy 39.01567 -215.422988) (xy 37.61613 -215.422988) (xy 37.605964 -215.422512)
			(xy 37.587175 -215.414742) (xy 37.57279 -215.400372) (xy 37.564999 -215.381592) (xy 37.564568 -215.371426)
			(xy 36.267632 -215.371426) (xy 36.255621 -215.389043) (xy 36.219369 -215.428114) (xy 36.177698 -215.461345)
			(xy 36.13154 -215.487994) (xy 36.081926 -215.507466) (xy 36.029964 -215.519326) (xy 35.976814 -215.52331)
			(xy 35.923664 -215.519326) (xy 35.871702 -215.507466) (xy 35.822088 -215.487994) (xy 35.77593 -215.461345)
			(xy 35.734259 -215.428114) (xy 35.698007 -215.389043) (xy 35.667983 -215.345006) (xy 35.644857 -215.296985)
			(xy 35.629147 -215.246055) (xy 35.621204 -215.193351) (xy 34.122624 -215.193351) (xy 34.114681 -215.246055)
			(xy 34.098971 -215.296985) (xy 34.075845 -215.345006) (xy 34.045821 -215.389043) (xy 34.009569 -215.428114)
			(xy 33.967898 -215.461345) (xy 33.92174 -215.487994) (xy 33.872126 -215.507466) (xy 33.820164 -215.519326)
			(xy 33.767014 -215.52331) (xy 33.713864 -215.519326) (xy 33.661902 -215.507466) (xy 33.612288 -215.487994)
			(xy 33.56613 -215.461345) (xy 33.524459 -215.428114) (xy 33.488207 -215.389043) (xy 33.458183 -215.345006)
			(xy 33.435057 -215.296985) (xy 33.419347 -215.246055) (xy 33.411404 -215.193351) (xy 32.391858 -215.193351)
			(xy 32.391858 -216.22131) (xy 34.120836 -216.22131) (xy 34.120836 -215.81237) (xy 34.121309 -215.802211)
			(xy 34.129093 -215.783441) (xy 34.143465 -215.769077) (xy 34.162238 -215.761303) (xy 34.172398 -215.760808)
			(xy 35.571938 -215.760808) (xy 35.579808 -215.761125) (xy 35.594806 -215.765902) (xy 35.601402 -215.770206)
			(xy 35.613161 -215.777798) (xy 35.639598 -215.78695) (xy 35.667527 -215.78859) (xy 35.694854 -215.782597)
			(xy 35.719532 -215.769418) (xy 35.729926 -215.760046) (xy 35.749919 -215.74145) (xy 35.794571 -215.710026)
			(xy 35.843498 -215.68579) (xy 35.895553 -215.66931) (xy 35.949514 -215.660973) (xy 35.976814 -215.660478)
			(xy 36.003462 -215.661005) (xy 36.056161 -215.66895) (xy 36.107088 -215.68466) (xy 36.155105 -215.707786)
			(xy 36.199139 -215.737809) (xy 36.238206 -215.77406) (xy 36.271434 -215.815728) (xy 36.298081 -215.861883)
			(xy 36.317552 -215.911495) (xy 36.329411 -215.963454) (xy 36.333394 -216.0166) (xy 36.331398 -216.043235)
			(xy 36.855136 -216.043235) (xy 36.855136 -215.989937) (xy 36.863079 -215.937233) (xy 36.878789 -215.886303)
			(xy 36.901915 -215.838282) (xy 36.931939 -215.794245) (xy 36.968191 -215.755174) (xy 37.009862 -215.721943)
			(xy 37.05602 -215.695294) (xy 37.105634 -215.675822) (xy 37.157596 -215.663962) (xy 37.210746 -215.659979)
			(xy 37.263896 -215.663962) (xy 37.315858 -215.675822) (xy 37.365472 -215.695294) (xy 37.41163 -215.721943)
			(xy 37.453301 -215.755174) (xy 37.489553 -215.794245) (xy 37.519577 -215.838282) (xy 37.542703 -215.886303)
			(xy 37.558413 -215.937233) (xy 37.566356 -215.989937) (xy 37.566854 -216.016586) (xy 37.566356 -216.043235)
			(xy 37.558413 -216.095939) (xy 37.542703 -216.146869) (xy 37.519577 -216.19489) (xy 37.489553 -216.238927)
			(xy 37.453301 -216.277998) (xy 37.41163 -216.311229) (xy 37.365472 -216.337878) (xy 37.315858 -216.35735)
			(xy 37.263896 -216.36921) (xy 37.210746 -216.373194) (xy 37.157596 -216.36921) (xy 37.105634 -216.35735)
			(xy 37.05602 -216.337878) (xy 37.009862 -216.311229) (xy 36.968191 -216.277998) (xy 36.931939 -216.238927)
			(xy 36.901915 -216.19489) (xy 36.878789 -216.146869) (xy 36.863079 -216.095939) (xy 36.855136 -216.043235)
			(xy 36.331398 -216.043235) (xy 36.329411 -216.069746) (xy 36.317552 -216.121705) (xy 36.298081 -216.171317)
			(xy 36.271434 -216.217472) (xy 36.238206 -216.25914) (xy 36.199139 -216.295391) (xy 36.155105 -216.325414)
			(xy 36.107088 -216.34854) (xy 36.056161 -216.36425) (xy 36.003462 -216.372195) (xy 35.976814 -216.372694)
			(xy 35.949551 -216.372194) (xy 35.895663 -216.363877) (xy 35.843674 -216.347436) (xy 35.794803 -216.323255)
			(xy 35.750193 -216.291901) (xy 35.73018 -216.27338) (xy 35.719774 -216.26396) (xy 35.695028 -216.250733)
			(xy 35.667614 -216.244753) (xy 35.639607 -216.246473) (xy 35.613131 -216.255763) (xy 35.601402 -216.263474)
			(xy 35.59479 -216.267749) (xy 35.579804 -216.272546) (xy 35.571938 -216.272872) (xy 34.172398 -216.272872)
			(xy 34.162241 -216.272368) (xy 34.143474 -216.264595) (xy 34.129109 -216.250233) (xy 34.121333 -216.231467)
			(xy 34.120836 -216.22131) (xy 32.391858 -216.22131) (xy 32.391858 -216.893373) (xy 33.411404 -216.893373)
			(xy 33.411404 -216.840075) (xy 33.419347 -216.787371) (xy 33.435057 -216.736441) (xy 33.458183 -216.68842)
			(xy 33.488207 -216.644383) (xy 33.524459 -216.605312) (xy 33.56613 -216.572081) (xy 33.612288 -216.545432)
			(xy 33.661902 -216.52596) (xy 33.713864 -216.5141) (xy 33.767014 -216.510117) (xy 33.820164 -216.5141)
			(xy 33.872126 -216.52596) (xy 33.92174 -216.545432) (xy 33.967898 -216.572081) (xy 34.009569 -216.605312)
			(xy 34.045821 -216.644383) (xy 34.075845 -216.68842) (xy 34.098971 -216.736441) (xy 34.114681 -216.787371)
			(xy 34.122624 -216.840075) (xy 34.123122 -216.866724) (xy 34.122624 -216.893373) (xy 35.621204 -216.893373)
			(xy 35.621204 -216.840075) (xy 35.629147 -216.787371) (xy 35.644857 -216.736441) (xy 35.667983 -216.68842)
			(xy 35.698007 -216.644383) (xy 35.734259 -216.605312) (xy 35.77593 -216.572081) (xy 35.822088 -216.545432)
			(xy 35.871702 -216.52596) (xy 35.923664 -216.5141) (xy 35.976814 -216.510117) (xy 36.029964 -216.5141)
			(xy 36.081926 -216.52596) (xy 36.13154 -216.545432) (xy 36.177698 -216.572081) (xy 36.219369 -216.605312)
			(xy 36.255621 -216.644383) (xy 36.285645 -216.68842) (xy 36.308771 -216.736441) (xy 36.324481 -216.787371)
			(xy 36.332424 -216.840075) (xy 36.332922 -216.866724) (xy 36.332424 -216.893373) (xy 36.324481 -216.946077)
			(xy 36.308771 -216.997007) (xy 36.285645 -217.045028) (xy 36.267632 -217.071448) (xy 37.564568 -217.071448)
			(xy 37.564568 -216.662508) (xy 37.565028 -216.652358) (xy 37.572814 -216.633612) (xy 37.587199 -216.61929)
			(xy 37.605979 -216.611584) (xy 37.61613 -216.6112) (xy 39.01567 -216.6112) (xy 39.02579 -216.61175)
			(xy 39.044503 -216.61946) (xy 39.058859 -216.633727) (xy 39.066686 -216.652391) (xy 39.067232 -216.662508)
			(xy 39.067232 -217.071448) (xy 39.066818 -217.081601) (xy 39.059013 -217.100348) (xy 39.044615 -217.114669)
			(xy 39.025825 -217.122373) (xy 39.01567 -217.122756) (xy 37.61613 -217.122756) (xy 37.606005 -217.122249)
			(xy 37.587283 -217.11453) (xy 37.572926 -217.10025) (xy 37.565106 -217.081571) (xy 37.564568 -217.071448)
			(xy 36.267632 -217.071448) (xy 36.255621 -217.089065) (xy 36.219369 -217.128136) (xy 36.177698 -217.161367)
			(xy 36.13154 -217.188016) (xy 36.081926 -217.207488) (xy 36.029964 -217.219348) (xy 35.976814 -217.223332)
			(xy 35.923664 -217.219348) (xy 35.871702 -217.207488) (xy 35.822088 -217.188016) (xy 35.77593 -217.161367)
			(xy 35.734259 -217.128136) (xy 35.698007 -217.089065) (xy 35.667983 -217.045028) (xy 35.644857 -216.997007)
			(xy 35.629147 -216.946077) (xy 35.621204 -216.893373) (xy 34.122624 -216.893373) (xy 34.114681 -216.946077)
			(xy 34.098971 -216.997007) (xy 34.075845 -217.045028) (xy 34.045821 -217.089065) (xy 34.009569 -217.128136)
			(xy 33.967898 -217.161367) (xy 33.92174 -217.188016) (xy 33.872126 -217.207488) (xy 33.820164 -217.219348)
			(xy 33.767014 -217.223332) (xy 33.713864 -217.219348) (xy 33.661902 -217.207488) (xy 33.612288 -217.188016)
			(xy 33.56613 -217.161367) (xy 33.524459 -217.128136) (xy 33.488207 -217.089065) (xy 33.458183 -217.045028)
			(xy 33.435057 -216.997007) (xy 33.419347 -216.946077) (xy 33.411404 -216.893373) (xy 32.391858 -216.893373)
			(xy 32.391858 -217.921332) (xy 34.120836 -217.921332) (xy 34.120836 -217.512392) (xy 34.121216 -217.502233)
			(xy 34.129021 -217.483473) (xy 34.143431 -217.469149) (xy 34.162237 -217.461456) (xy 34.172398 -217.461084)
			(xy 35.571938 -217.461084) (xy 35.579792 -217.46132) (xy 35.594789 -217.465983) (xy 35.601402 -217.470228)
			(xy 35.613163 -217.477816) (xy 35.639599 -217.486966) (xy 35.667527 -217.488606) (xy 35.694853 -217.482614)
			(xy 35.719531 -217.469438) (xy 35.729926 -217.460068) (xy 35.749922 -217.441475) (xy 35.794573 -217.41005)
			(xy 35.843499 -217.385813) (xy 35.895553 -217.369332) (xy 35.949514 -217.360995) (xy 35.976814 -217.3605)
			(xy 36.003463 -217.360983) (xy 36.056166 -217.368928) (xy 36.107096 -217.38464) (xy 36.155116 -217.407767)
			(xy 36.199152 -217.437792) (xy 36.238222 -217.474045) (xy 36.271453 -217.515716) (xy 36.298101 -217.561874)
			(xy 36.317573 -217.611488) (xy 36.329433 -217.663451) (xy 36.333416 -217.7166) (xy 36.331418 -217.743257)
			(xy 36.855136 -217.743257) (xy 36.855136 -217.689959) (xy 36.863079 -217.637255) (xy 36.878789 -217.586325)
			(xy 36.901915 -217.538304) (xy 36.931939 -217.494267) (xy 36.968191 -217.455196) (xy 37.009862 -217.421965)
			(xy 37.05602 -217.395316) (xy 37.105634 -217.375844) (xy 37.157596 -217.363984) (xy 37.210746 -217.360001)
			(xy 37.263896 -217.363984) (xy 37.315858 -217.375844) (xy 37.365472 -217.395316) (xy 37.41163 -217.421965)
			(xy 37.453301 -217.455196) (xy 37.489553 -217.494267) (xy 37.519577 -217.538304) (xy 37.542703 -217.586325)
			(xy 37.558413 -217.637255) (xy 37.566356 -217.689959) (xy 37.566854 -217.716608) (xy 37.566356 -217.743257)
			(xy 37.558413 -217.795961) (xy 37.542703 -217.846891) (xy 37.519577 -217.894912) (xy 37.489553 -217.938949)
			(xy 37.453301 -217.97802) (xy 37.41163 -218.011251) (xy 37.365472 -218.0379) (xy 37.315858 -218.057372)
			(xy 37.263896 -218.069232) (xy 37.210746 -218.073216) (xy 37.157596 -218.069232) (xy 37.105634 -218.057372)
			(xy 37.05602 -218.0379) (xy 37.009862 -218.011251) (xy 36.968191 -217.97802) (xy 36.931939 -217.938949)
			(xy 36.901915 -217.894912) (xy 36.878789 -217.846891) (xy 36.863079 -217.795961) (xy 36.855136 -217.743257)
			(xy 36.331418 -217.743257) (xy 36.329433 -217.769749) (xy 36.317573 -217.821712) (xy 36.298101 -217.871326)
			(xy 36.271453 -217.917484) (xy 36.238222 -217.959155) (xy 36.199152 -217.995408) (xy 36.155116 -218.025433)
			(xy 36.107096 -218.04856) (xy 36.056166 -218.064272) (xy 36.003463 -218.072217) (xy 35.976814 -218.072716)
			(xy 35.949551 -218.07221) (xy 35.895664 -218.063893) (xy 35.843675 -218.047453) (xy 35.794804 -218.023274)
			(xy 35.750194 -217.991922) (xy 35.73018 -217.973402) (xy 35.719773 -217.963982) (xy 35.695028 -217.950753)
			(xy 35.667614 -217.944771) (xy 35.639607 -217.946492) (xy 35.61313 -217.955783) (xy 35.601402 -217.963496)
			(xy 35.594788 -217.967737) (xy 35.579791 -217.972396) (xy 35.571938 -217.97264) (xy 34.172398 -217.97264)
			(xy 34.162269 -217.972174) (xy 34.143544 -217.964442) (xy 34.129187 -217.950149) (xy 34.121371 -217.931459)
			(xy 34.120836 -217.921332) (xy 32.391858 -217.921332) (xy 32.391858 -218.77147) (xy 34.120836 -218.77147)
			(xy 34.120836 -218.36253) (xy 34.121289 -218.352361) (xy 34.129063 -218.333567) (xy 34.14344 -218.319181)
			(xy 34.162229 -218.311395) (xy 34.172398 -218.310968) (xy 35.571938 -218.310968) (xy 35.579809 -218.311275)
			(xy 35.594808 -218.316058) (xy 35.601402 -218.320366) (xy 35.613165 -218.327948) (xy 35.639601 -218.337094)
			(xy 35.667527 -218.338734) (xy 35.694851 -218.332744) (xy 35.71953 -218.319573) (xy 35.729926 -218.310206)
			(xy 35.749929 -218.29162) (xy 35.794577 -218.260193) (xy 35.843501 -218.235953) (xy 35.895554 -218.219472)
			(xy 35.949514 -218.211134) (xy 35.976814 -218.210638) (xy 36.003466 -218.211045) (xy 36.056175 -218.218991)
			(xy 36.10711 -218.234705) (xy 36.155135 -218.257834) (xy 36.199176 -218.287862) (xy 36.23825 -218.324119)
			(xy 36.271484 -218.365794) (xy 36.298135 -218.411957) (xy 36.317609 -218.461577) (xy 36.32947 -218.513545)
			(xy 36.333454 -218.5667) (xy 36.32947 -218.619855) (xy 36.317609 -218.671823) (xy 36.298135 -218.721443)
			(xy 36.271484 -218.767606) (xy 36.268403 -218.77147) (xy 37.564568 -218.77147) (xy 37.564568 -218.36253)
			(xy 37.564989 -218.352357) (xy 37.57277 -218.333557) (xy 37.587157 -218.31917) (xy 37.605957 -218.311389)
			(xy 37.61613 -218.310968) (xy 39.01567 -218.310968) (xy 39.025843 -218.311389) (xy 39.044643 -218.31917)
			(xy 39.05903 -218.333557) (xy 39.066811 -218.352357) (xy 39.067232 -218.36253) (xy 39.067232 -218.77147)
			(xy 39.066811 -218.781643) (xy 39.05903 -218.800443) (xy 39.044643 -218.81483) (xy 39.025843 -218.822611)
			(xy 39.01567 -218.823032) (xy 37.61613 -218.823032) (xy 37.605957 -218.822611) (xy 37.587157 -218.81483)
			(xy 37.57277 -218.800443) (xy 37.564989 -218.781643) (xy 37.564568 -218.77147) (xy 36.268403 -218.77147)
			(xy 36.23825 -218.809281) (xy 36.199176 -218.845538) (xy 36.155135 -218.875566) (xy 36.10711 -218.898695)
			(xy 36.056175 -218.914409) (xy 36.003466 -218.922355) (xy 35.976814 -218.922854) (xy 35.94955 -218.922365)
			(xy 35.895661 -218.914047) (xy 35.843672 -218.897604) (xy 35.794801 -218.87342) (xy 35.750192 -218.842063)
			(xy 35.73018 -218.82354) (xy 35.719774 -218.814121) (xy 35.695027 -218.800898) (xy 35.667614 -218.79492)
			(xy 35.639609 -218.79664) (xy 35.613132 -218.805926) (xy 35.601402 -218.813634) (xy 35.594794 -218.817915)
			(xy 35.579804 -218.822707) (xy 35.571938 -218.823032) (xy 34.172398 -218.823032) (xy 34.162223 -218.822637)
			(xy 34.143422 -218.814846) (xy 34.129036 -218.800451) (xy 34.121257 -218.781646) (xy 34.120836 -218.77147)
			(xy 32.391858 -218.77147) (xy 32.391858 -219.443279) (xy 33.411404 -219.443279) (xy 33.411404 -219.389981)
			(xy 33.419347 -219.337277) (xy 33.435057 -219.286347) (xy 33.458183 -219.238326) (xy 33.488207 -219.194289)
			(xy 33.524459 -219.155218) (xy 33.56613 -219.121987) (xy 33.612288 -219.095338) (xy 33.661902 -219.075866)
			(xy 33.713864 -219.064006) (xy 33.767014 -219.060023) (xy 33.820164 -219.064006) (xy 33.872126 -219.075866)
			(xy 33.92174 -219.095338) (xy 33.967898 -219.121987) (xy 34.009569 -219.155218) (xy 34.045821 -219.194289)
			(xy 34.075845 -219.238326) (xy 34.098971 -219.286347) (xy 34.114681 -219.337277) (xy 34.122624 -219.389981)
			(xy 34.123122 -219.41663) (xy 34.122624 -219.443279) (xy 35.621204 -219.443279) (xy 35.621204 -219.389981)
			(xy 35.629147 -219.337277) (xy 35.644857 -219.286347) (xy 35.667983 -219.238326) (xy 35.698007 -219.194289)
			(xy 35.734259 -219.155218) (xy 35.77593 -219.121987) (xy 35.822088 -219.095338) (xy 35.871702 -219.075866)
			(xy 35.923664 -219.064006) (xy 35.976814 -219.060023) (xy 36.029964 -219.064006) (xy 36.081926 -219.075866)
			(xy 36.13154 -219.095338) (xy 36.177698 -219.121987) (xy 36.219369 -219.155218) (xy 36.255621 -219.194289)
			(xy 36.285645 -219.238326) (xy 36.308771 -219.286347) (xy 36.324481 -219.337277) (xy 36.332424 -219.389981)
			(xy 36.332922 -219.41663) (xy 36.332424 -219.443279) (xy 36.324481 -219.495983) (xy 36.308771 -219.546913)
			(xy 36.285645 -219.594934) (xy 36.267632 -219.621354) (xy 37.564568 -219.621354) (xy 37.564568 -219.212414)
			(xy 37.564976 -219.20224) (xy 37.572762 -219.183439) (xy 37.587153 -219.169053) (xy 37.605955 -219.161273)
			(xy 37.61613 -219.160852) (xy 39.01567 -219.160852) (xy 39.025841 -219.161289) (xy 39.044638 -219.169067)
			(xy 39.059024 -219.183449) (xy 39.066808 -219.202243) (xy 39.067232 -219.212414) (xy 39.067232 -219.621354)
			(xy 39.066798 -219.631526) (xy 39.059022 -219.650326) (xy 39.044639 -219.664713) (xy 39.025842 -219.672495)
			(xy 39.01567 -219.672916) (xy 37.61613 -219.672916) (xy 37.605955 -219.67251) (xy 37.587152 -219.664727)
			(xy 37.572764 -219.650335) (xy 37.564987 -219.631529) (xy 37.564568 -219.621354) (xy 36.267632 -219.621354)
			(xy 36.255621 -219.638971) (xy 36.219369 -219.678042) (xy 36.177698 -219.711273) (xy 36.13154 -219.737922)
			(xy 36.081926 -219.757394) (xy 36.029964 -219.769254) (xy 35.976814 -219.773238) (xy 35.923664 -219.769254)
			(xy 35.871702 -219.757394) (xy 35.822088 -219.737922) (xy 35.77593 -219.711273) (xy 35.734259 -219.678042)
			(xy 35.698007 -219.638971) (xy 35.667983 -219.594934) (xy 35.644857 -219.546913) (xy 35.629147 -219.495983)
			(xy 35.621204 -219.443279) (xy 34.122624 -219.443279) (xy 34.114681 -219.495983) (xy 34.098971 -219.546913)
			(xy 34.075845 -219.594934) (xy 34.045821 -219.638971) (xy 34.009569 -219.678042) (xy 33.967898 -219.711273)
			(xy 33.92174 -219.737922) (xy 33.872126 -219.757394) (xy 33.820164 -219.769254) (xy 33.767014 -219.773238)
			(xy 33.713864 -219.769254) (xy 33.661902 -219.757394) (xy 33.612288 -219.737922) (xy 33.56613 -219.711273)
			(xy 33.524459 -219.678042) (xy 33.488207 -219.638971) (xy 33.458183 -219.594934) (xy 33.435057 -219.546913)
			(xy 33.419347 -219.495983) (xy 33.411404 -219.443279) (xy 32.391858 -219.443279) (xy 32.391858 -220.471492)
			(xy 34.120836 -220.471492) (xy 34.120836 -220.062552) (xy 34.121183 -220.05239) (xy 34.129001 -220.03363)
			(xy 34.143421 -220.019307) (xy 34.162234 -220.011616) (xy 34.172398 -220.011244) (xy 35.571938 -220.011244)
			(xy 35.579791 -220.011486) (xy 35.594788 -220.016146) (xy 35.601402 -220.020388) (xy 35.613167 -220.027967)
			(xy 35.639602 -220.037111) (xy 35.667526 -220.03875) (xy 35.69485 -220.032761) (xy 35.719529 -220.019593)
			(xy 35.729926 -220.010228) (xy 35.749916 -219.991629) (xy 35.794569 -219.960206) (xy 35.843497 -219.935971)
			(xy 35.895552 -219.919492) (xy 35.949513 -219.911155) (xy 35.976814 -219.91066) (xy 36.00346 -219.911223)
			(xy 36.056157 -219.919168) (xy 36.107081 -219.934878) (xy 36.155096 -219.958002) (xy 36.199127 -219.988023)
			(xy 36.238193 -220.024272) (xy 36.271419 -220.065939) (xy 36.298065 -220.112092) (xy 36.317534 -220.1617)
			(xy 36.329393 -220.213657) (xy 36.333375 -220.2668) (xy 36.331381 -220.293417) (xy 36.855136 -220.293417)
			(xy 36.855136 -220.240119) (xy 36.863079 -220.187415) (xy 36.878789 -220.136485) (xy 36.901915 -220.088464)
			(xy 36.931939 -220.044427) (xy 36.968191 -220.005356) (xy 37.009862 -219.972125) (xy 37.05602 -219.945476)
			(xy 37.105634 -219.926004) (xy 37.157596 -219.914144) (xy 37.210746 -219.910161) (xy 37.263896 -219.914144)
			(xy 37.315858 -219.926004) (xy 37.365472 -219.945476) (xy 37.41163 -219.972125) (xy 37.453301 -220.005356)
			(xy 37.489553 -220.044427) (xy 37.519577 -220.088464) (xy 37.542703 -220.136485) (xy 37.558413 -220.187415)
			(xy 37.566356 -220.240119) (xy 37.566854 -220.266768) (xy 37.566356 -220.293417) (xy 37.558413 -220.346121)
			(xy 37.542703 -220.397051) (xy 37.519577 -220.445072) (xy 37.489553 -220.489109) (xy 37.453301 -220.52818)
			(xy 37.41163 -220.561411) (xy 37.365472 -220.58806) (xy 37.315858 -220.607532) (xy 37.263896 -220.619392)
			(xy 37.210746 -220.623376) (xy 37.157596 -220.619392) (xy 37.105634 -220.607532) (xy 37.05602 -220.58806)
			(xy 37.009862 -220.561411) (xy 36.968191 -220.52818) (xy 36.931939 -220.489109) (xy 36.901915 -220.445072)
			(xy 36.878789 -220.397051) (xy 36.863079 -220.346121) (xy 36.855136 -220.293417) (xy 36.331381 -220.293417)
			(xy 36.329393 -220.319943) (xy 36.317534 -220.3719) (xy 36.298065 -220.421508) (xy 36.271419 -220.467661)
			(xy 36.238193 -220.509328) (xy 36.199127 -220.545577) (xy 36.155096 -220.575598) (xy 36.107081 -220.598722)
			(xy 36.056157 -220.614432) (xy 36.00346 -220.622377) (xy 35.976814 -220.622876) (xy 35.949551 -220.622381)
			(xy 35.895662 -220.614063) (xy 35.843673 -220.597621) (xy 35.794802 -220.573439) (xy 35.750193 -220.542084)
			(xy 35.73018 -220.523562) (xy 35.719774 -220.514143) (xy 35.695028 -220.500918) (xy 35.667614 -220.494939)
			(xy 35.639608 -220.496658) (xy 35.613131 -220.505946) (xy 35.601402 -220.513656) (xy 35.594785 -220.517893)
			(xy 35.579791 -220.522556) (xy 35.571938 -220.5228) (xy 34.172398 -220.5228) (xy 34.162276 -220.522276)
			(xy 34.143563 -220.514555) (xy 34.129208 -220.500281) (xy 34.121382 -220.481611) (xy 34.120836 -220.471492)
			(xy 32.391858 -220.471492) (xy 32.391858 -221.143301) (xy 33.411404 -221.143301) (xy 33.411404 -221.090003)
			(xy 33.419347 -221.037299) (xy 33.435057 -220.986369) (xy 33.458183 -220.938348) (xy 33.488207 -220.894311)
			(xy 33.524459 -220.85524) (xy 33.56613 -220.822009) (xy 33.612288 -220.79536) (xy 33.661902 -220.775888)
			(xy 33.713864 -220.764028) (xy 33.767014 -220.760045) (xy 33.820164 -220.764028) (xy 33.872126 -220.775888)
			(xy 33.92174 -220.79536) (xy 33.967898 -220.822009) (xy 34.009569 -220.85524) (xy 34.045821 -220.894311)
			(xy 34.075845 -220.938348) (xy 34.098971 -220.986369) (xy 34.114681 -221.037299) (xy 34.122624 -221.090003)
			(xy 34.123122 -221.116652) (xy 34.122624 -221.143301) (xy 35.621204 -221.143301) (xy 35.621204 -221.090003)
			(xy 35.629147 -221.037299) (xy 35.644857 -220.986369) (xy 35.667983 -220.938348) (xy 35.698007 -220.894311)
			(xy 35.734259 -220.85524) (xy 35.77593 -220.822009) (xy 35.822088 -220.79536) (xy 35.871702 -220.775888)
			(xy 35.923664 -220.764028) (xy 35.976814 -220.760045) (xy 36.029964 -220.764028) (xy 36.081926 -220.775888)
			(xy 36.13154 -220.79536) (xy 36.177698 -220.822009) (xy 36.219369 -220.85524) (xy 36.255621 -220.894311)
			(xy 36.285645 -220.938348) (xy 36.308771 -220.986369) (xy 36.324481 -221.037299) (xy 36.332424 -221.090003)
			(xy 36.332922 -221.116652) (xy 36.332424 -221.143301) (xy 36.324481 -221.196005) (xy 36.308771 -221.246935)
			(xy 36.285645 -221.294956) (xy 36.267632 -221.321376) (xy 37.564568 -221.321376) (xy 37.564568 -220.912436)
			(xy 37.565051 -220.902288) (xy 37.572828 -220.883543) (xy 37.587206 -220.869219) (xy 37.605981 -220.861513)
			(xy 37.61613 -220.861128) (xy 39.01567 -220.861128) (xy 39.025793 -220.861651) (xy 39.044512 -220.869366)
			(xy 39.058869 -220.883642) (xy 39.066691 -220.902316) (xy 39.067232 -220.912436) (xy 39.067232 -221.321376)
			(xy 39.06676 -221.331525) (xy 39.058978 -221.35027) (xy 39.044597 -221.364594) (xy 39.02582 -221.3723)
			(xy 39.01567 -221.372684) (xy 37.61613 -221.372684) (xy 37.606008 -221.37215) (xy 37.587292 -221.364436)
			(xy 37.572936 -221.350165) (xy 37.565111 -221.331495) (xy 37.564568 -221.321376) (xy 36.267632 -221.321376)
			(xy 36.255621 -221.338993) (xy 36.219369 -221.378064) (xy 36.177698 -221.411295) (xy 36.13154 -221.437944)
			(xy 36.081926 -221.457416) (xy 36.029964 -221.469276) (xy 35.976814 -221.47326) (xy 35.923664 -221.469276)
			(xy 35.871702 -221.457416) (xy 35.822088 -221.437944) (xy 35.77593 -221.411295) (xy 35.734259 -221.378064)
			(xy 35.698007 -221.338993) (xy 35.667983 -221.294956) (xy 35.644857 -221.246935) (xy 35.629147 -221.196005)
			(xy 35.621204 -221.143301) (xy 34.122624 -221.143301) (xy 34.114681 -221.196005) (xy 34.098971 -221.246935)
			(xy 34.075845 -221.294956) (xy 34.045821 -221.338993) (xy 34.009569 -221.378064) (xy 33.967898 -221.411295)
			(xy 33.92174 -221.437944) (xy 33.872126 -221.457416) (xy 33.820164 -221.469276) (xy 33.767014 -221.47326)
			(xy 33.713864 -221.469276) (xy 33.661902 -221.457416) (xy 33.612288 -221.437944) (xy 33.56613 -221.411295)
			(xy 33.524459 -221.378064) (xy 33.488207 -221.338993) (xy 33.458183 -221.294956) (xy 33.435057 -221.246935)
			(xy 33.419347 -221.196005) (xy 33.411404 -221.143301) (xy 32.391858 -221.143301) (xy 32.391858 -222.171514)
			(xy 34.120836 -222.171514) (xy 34.120836 -221.762574) (xy 34.121312 -221.752415) (xy 34.129095 -221.733645)
			(xy 34.143466 -221.719281) (xy 34.162239 -221.711507) (xy 34.172398 -221.711012) (xy 35.571938 -221.711012)
			(xy 35.579808 -221.711329) (xy 35.594806 -221.716106) (xy 35.601402 -221.72041) (xy 35.613161 -221.728001)
			(xy 35.639599 -221.737153) (xy 35.667527 -221.738793) (xy 35.694854 -221.7328) (xy 35.719532 -221.719622)
			(xy 35.729926 -221.71025) (xy 35.74992 -221.691654) (xy 35.794571 -221.66023) (xy 35.843498 -221.635994)
			(xy 35.895553 -221.619514) (xy 35.949514 -221.611177) (xy 35.976814 -221.610682) (xy 36.003462 -221.611201)
			(xy 36.056162 -221.619146) (xy 36.10709 -221.634857) (xy 36.155107 -221.657982) (xy 36.199141 -221.688006)
			(xy 36.238209 -221.724257) (xy 36.271438 -221.765926) (xy 36.298085 -221.812082) (xy 36.317556 -221.861694)
			(xy 36.329415 -221.913653) (xy 36.333398 -221.9668) (xy 36.331402 -221.993439) (xy 36.855136 -221.993439)
			(xy 36.855136 -221.940141) (xy 36.863079 -221.887437) (xy 36.878789 -221.836507) (xy 36.901915 -221.788486)
			(xy 36.931939 -221.744449) (xy 36.968191 -221.705378) (xy 37.009862 -221.672147) (xy 37.05602 -221.645498)
			(xy 37.105634 -221.626026) (xy 37.157596 -221.614166) (xy 37.210746 -221.610183) (xy 37.263896 -221.614166)
			(xy 37.315858 -221.626026) (xy 37.365472 -221.645498) (xy 37.41163 -221.672147) (xy 37.453301 -221.705378)
			(xy 37.489553 -221.744449) (xy 37.519577 -221.788486) (xy 37.542703 -221.836507) (xy 37.558413 -221.887437)
			(xy 37.566356 -221.940141) (xy 37.566854 -221.96679) (xy 37.566356 -221.993439) (xy 37.558413 -222.046143)
			(xy 37.542703 -222.097073) (xy 37.519577 -222.145094) (xy 37.489553 -222.189131) (xy 37.453301 -222.228202)
			(xy 37.41163 -222.261433) (xy 37.365472 -222.288082) (xy 37.315858 -222.307554) (xy 37.263896 -222.319414)
			(xy 37.210746 -222.323398) (xy 37.157596 -222.319414) (xy 37.105634 -222.307554) (xy 37.05602 -222.288082)
			(xy 37.009862 -222.261433) (xy 36.968191 -222.228202) (xy 36.931939 -222.189131) (xy 36.901915 -222.145094)
			(xy 36.878789 -222.097073) (xy 36.863079 -222.046143) (xy 36.855136 -221.993439) (xy 36.331402 -221.993439)
			(xy 36.329415 -222.019947) (xy 36.317556 -222.071906) (xy 36.298085 -222.121518) (xy 36.271438 -222.167674)
			(xy 36.238209 -222.209343) (xy 36.199141 -222.245594) (xy 36.155107 -222.275618) (xy 36.10709 -222.298743)
			(xy 36.056162 -222.314454) (xy 36.003462 -222.322399) (xy 35.976814 -222.322898) (xy 35.949551 -222.322397)
			(xy 35.895663 -222.31408) (xy 35.843674 -222.297639) (xy 35.794803 -222.273458) (xy 35.750193 -222.242105)
			(xy 35.73018 -222.223584) (xy 35.719774 -222.214164) (xy 35.695028 -222.200937) (xy 35.667614 -222.194957)
			(xy 35.639607 -222.196677) (xy 35.613131 -222.205967) (xy 35.601402 -222.213678) (xy 35.59479 -222.217954)
			(xy 35.579804 -222.22275) (xy 35.571938 -222.223076) (xy 34.172398 -222.223076) (xy 34.162242 -222.222569)
			(xy 34.143475 -222.214796) (xy 34.129111 -222.200435) (xy 34.121334 -222.18167) (xy 34.120836 -222.171514)
			(xy 32.391858 -222.171514) (xy 32.391858 -222.843323) (xy 33.411404 -222.843323) (xy 33.411404 -222.790025)
			(xy 33.419347 -222.737321) (xy 33.435057 -222.686391) (xy 33.458183 -222.63837) (xy 33.488207 -222.594333)
			(xy 33.524459 -222.555262) (xy 33.56613 -222.522031) (xy 33.612288 -222.495382) (xy 33.661902 -222.47591)
			(xy 33.713864 -222.46405) (xy 33.767014 -222.460067) (xy 33.820164 -222.46405) (xy 33.872126 -222.47591)
			(xy 33.92174 -222.495382) (xy 33.967898 -222.522031) (xy 34.009569 -222.555262) (xy 34.045821 -222.594333)
			(xy 34.075845 -222.63837) (xy 34.098971 -222.686391) (xy 34.114681 -222.737321) (xy 34.122624 -222.790025)
			(xy 34.123122 -222.816674) (xy 34.122624 -222.843323) (xy 35.621204 -222.843323) (xy 35.621204 -222.790025)
			(xy 35.629147 -222.737321) (xy 35.644857 -222.686391) (xy 35.667983 -222.63837) (xy 35.698007 -222.594333)
			(xy 35.734259 -222.555262) (xy 35.77593 -222.522031) (xy 35.822088 -222.495382) (xy 35.871702 -222.47591)
			(xy 35.923664 -222.46405) (xy 35.976814 -222.460067) (xy 36.029964 -222.46405) (xy 36.081926 -222.47591)
			(xy 36.13154 -222.495382) (xy 36.177698 -222.522031) (xy 36.219369 -222.555262) (xy 36.255621 -222.594333)
			(xy 36.285645 -222.63837) (xy 36.308771 -222.686391) (xy 36.324481 -222.737321) (xy 36.332424 -222.790025)
			(xy 36.332922 -222.816674) (xy 36.332424 -222.843323) (xy 36.324481 -222.896027) (xy 36.308771 -222.946957)
			(xy 36.285645 -222.994978) (xy 36.267632 -223.021398) (xy 37.564568 -223.021398) (xy 37.564568 -222.612458)
			(xy 37.565 -222.602294) (xy 37.572794 -222.583518) (xy 37.587178 -222.569153) (xy 37.605965 -222.561386)
			(xy 37.61613 -222.560896) (xy 39.01567 -222.560896) (xy 39.025821 -222.561457) (xy 39.044581 -222.569213)
			(xy 39.058946 -222.583558) (xy 39.066729 -222.602308) (xy 39.067232 -222.612458) (xy 39.067232 -223.021398)
			(xy 39.066834 -223.031573) (xy 39.059044 -223.050374) (xy 39.04465 -223.06476) (xy 39.025845 -223.072539)
			(xy 39.01567 -223.07296) (xy 37.61613 -223.07296) (xy 37.60596 -223.072511) (xy 37.587166 -223.064736)
			(xy 37.57278 -223.050358) (xy 37.564994 -223.031568) (xy 37.564568 -223.021398) (xy 36.267632 -223.021398)
			(xy 36.255621 -223.039015) (xy 36.219369 -223.078086) (xy 36.177698 -223.111317) (xy 36.13154 -223.137966)
			(xy 36.081926 -223.157438) (xy 36.029964 -223.169298) (xy 35.976814 -223.173282) (xy 35.923664 -223.169298)
			(xy 35.871702 -223.157438) (xy 35.822088 -223.137966) (xy 35.77593 -223.111317) (xy 35.734259 -223.078086)
			(xy 35.698007 -223.039015) (xy 35.667983 -222.994978) (xy 35.644857 -222.946957) (xy 35.629147 -222.896027)
			(xy 35.621204 -222.843323) (xy 34.122624 -222.843323) (xy 34.114681 -222.896027) (xy 34.098971 -222.946957)
			(xy 34.075845 -222.994978) (xy 34.045821 -223.039015) (xy 34.009569 -223.078086) (xy 33.967898 -223.111317)
			(xy 33.92174 -223.137966) (xy 33.872126 -223.157438) (xy 33.820164 -223.169298) (xy 33.767014 -223.173282)
			(xy 33.713864 -223.169298) (xy 33.661902 -223.157438) (xy 33.612288 -223.137966) (xy 33.56613 -223.111317)
			(xy 33.524459 -223.078086) (xy 33.488207 -223.039015) (xy 33.458183 -222.994978) (xy 33.435057 -222.946957)
			(xy 33.419347 -222.896027) (xy 33.411404 -222.843323) (xy 32.391858 -222.843323) (xy 32.391858 -223.871536)
			(xy 34.120836 -223.871536) (xy 34.120836 -223.462596) (xy 34.121219 -223.452437) (xy 34.129023 -223.433678)
			(xy 34.143432 -223.419353) (xy 34.162237 -223.41166) (xy 34.172398 -223.411288) (xy 35.571938 -223.411288)
			(xy 35.579792 -223.411523) (xy 35.594789 -223.416187) (xy 35.601402 -223.420432) (xy 35.613128 -223.42804)
			(xy 35.639546 -223.437142) (xy 35.667444 -223.438722) (xy 35.694721 -223.432661) (xy 35.719325 -223.419417)
			(xy 35.729672 -223.410018) (xy 35.749707 -223.39143) (xy 35.794394 -223.359969) (xy 35.843367 -223.335715)
			(xy 35.895474 -223.319238) (xy 35.949488 -223.310926) (xy 35.976814 -223.31045) (xy 36.003459 -223.311033)
			(xy 36.056155 -223.318978) (xy 36.107078 -223.334687) (xy 36.155091 -223.35781) (xy 36.199121 -223.387831)
			(xy 36.238185 -223.424079) (xy 36.271411 -223.465744) (xy 36.298056 -223.511896) (xy 36.317525 -223.561503)
			(xy 36.329383 -223.613458) (xy 36.333365 -223.6666) (xy 36.331371 -223.693207) (xy 36.855136 -223.693207)
			(xy 36.855136 -223.639909) (xy 36.863079 -223.587205) (xy 36.878789 -223.536275) (xy 36.901915 -223.488254)
			(xy 36.931939 -223.444217) (xy 36.968191 -223.405146) (xy 37.009862 -223.371915) (xy 37.05602 -223.345266)
			(xy 37.105634 -223.325794) (xy 37.157596 -223.313934) (xy 37.210746 -223.309951) (xy 37.263896 -223.313934)
			(xy 37.315858 -223.325794) (xy 37.365472 -223.345266) (xy 37.41163 -223.371915) (xy 37.453301 -223.405146)
			(xy 37.489553 -223.444217) (xy 37.519577 -223.488254) (xy 37.542703 -223.536275) (xy 37.558413 -223.587205)
			(xy 37.566356 -223.639909) (xy 37.566854 -223.666558) (xy 37.566356 -223.693207) (xy 37.558413 -223.745911)
			(xy 37.542703 -223.796841) (xy 37.519577 -223.844862) (xy 37.489553 -223.888899) (xy 37.453301 -223.92797)
			(xy 37.41163 -223.961201) (xy 37.365472 -223.98785) (xy 37.315858 -224.007322) (xy 37.263896 -224.019182)
			(xy 37.210746 -224.023166) (xy 37.157596 -224.019182) (xy 37.105634 -224.007322) (xy 37.05602 -223.98785)
			(xy 37.009862 -223.961201) (xy 36.968191 -223.92797) (xy 36.931939 -223.888899) (xy 36.901915 -223.844862)
			(xy 36.878789 -223.796841) (xy 36.863079 -223.745911) (xy 36.855136 -223.693207) (xy 36.331371 -223.693207)
			(xy 36.329383 -223.719742) (xy 36.317525 -223.771697) (xy 36.298056 -223.821304) (xy 36.271411 -223.867456)
			(xy 36.238185 -223.909121) (xy 36.199121 -223.945369) (xy 36.155091 -223.97539) (xy 36.107078 -223.998513)
			(xy 36.056155 -224.014222) (xy 36.003459 -224.022167) (xy 35.976814 -224.022666) (xy 35.94955 -224.022174)
			(xy 35.895662 -224.013856) (xy 35.843673 -223.997413) (xy 35.794802 -223.973231) (xy 35.750192 -223.941874)
			(xy 35.73018 -223.923352) (xy 35.71973 -223.914004) (xy 35.694955 -223.900893) (xy 35.667554 -223.894992)
			(xy 35.63958 -223.896742) (xy 35.613128 -223.906012) (xy 35.601402 -223.9137) (xy 35.594788 -223.917942)
			(xy 35.579791 -223.922601) (xy 35.571938 -223.922844) (xy 34.172398 -223.922844) (xy 34.162269 -223.922374)
			(xy 34.143545 -223.914643) (xy 34.129188 -223.900351) (xy 34.121372 -223.881662) (xy 34.120836 -223.871536)
			(xy 32.391858 -223.871536) (xy 32.391858 -224.543345) (xy 33.411404 -224.543345) (xy 33.411404 -224.490047)
			(xy 33.419347 -224.437343) (xy 33.435057 -224.386413) (xy 33.458183 -224.338392) (xy 33.488207 -224.294355)
			(xy 33.524459 -224.255284) (xy 33.56613 -224.222053) (xy 33.612288 -224.195404) (xy 33.661902 -224.175932)
			(xy 33.713864 -224.164072) (xy 33.767014 -224.160089) (xy 33.820164 -224.164072) (xy 33.872126 -224.175932)
			(xy 33.92174 -224.195404) (xy 33.967898 -224.222053) (xy 34.009569 -224.255284) (xy 34.045821 -224.294355)
			(xy 34.075845 -224.338392) (xy 34.098971 -224.386413) (xy 34.114681 -224.437343) (xy 34.122624 -224.490047)
			(xy 34.123122 -224.516696) (xy 34.122624 -224.543345) (xy 35.621204 -224.543345) (xy 35.621204 -224.490047)
			(xy 35.629147 -224.437343) (xy 35.644857 -224.386413) (xy 35.667983 -224.338392) (xy 35.698007 -224.294355)
			(xy 35.734259 -224.255284) (xy 35.77593 -224.222053) (xy 35.822088 -224.195404) (xy 35.871702 -224.175932)
			(xy 35.923664 -224.164072) (xy 35.976814 -224.160089) (xy 36.029964 -224.164072) (xy 36.081926 -224.175932)
			(xy 36.13154 -224.195404) (xy 36.177698 -224.222053) (xy 36.219369 -224.255284) (xy 36.255621 -224.294355)
			(xy 36.285645 -224.338392) (xy 36.308771 -224.386413) (xy 36.324481 -224.437343) (xy 36.332424 -224.490047)
			(xy 36.332922 -224.516696) (xy 36.332424 -224.543345) (xy 36.324481 -224.596049) (xy 36.308771 -224.646979)
			(xy 36.285645 -224.695) (xy 36.267632 -224.72142) (xy 37.564568 -224.72142) (xy 37.564568 -224.31248)
			(xy 37.565004 -224.302329) (xy 37.572801 -224.283582) (xy 37.587192 -224.26926) (xy 37.605977 -224.261555)
			(xy 37.61613 -224.261172) (xy 39.01567 -224.261172) (xy 39.025799 -224.261652) (xy 39.044525 -224.269376)
			(xy 39.058884 -224.283665) (xy 39.066699 -224.302354) (xy 39.067232 -224.31248) (xy 39.067232 -224.72142)
			(xy 39.066796 -224.731571) (xy 39.058999 -224.750318) (xy 39.044608 -224.76464) (xy 39.025823 -224.772345)
			(xy 39.01567 -224.772728) (xy 37.61613 -224.772728) (xy 37.606001 -224.772248) (xy 37.587275 -224.764524)
			(xy 37.572916 -224.750235) (xy 37.565101 -224.731546) (xy 37.564568 -224.72142) (xy 36.267632 -224.72142)
			(xy 36.255621 -224.739037) (xy 36.219369 -224.778108) (xy 36.177698 -224.811339) (xy 36.13154 -224.837988)
			(xy 36.081926 -224.85746) (xy 36.029964 -224.86932) (xy 35.976814 -224.873304) (xy 35.923664 -224.86932)
			(xy 35.871702 -224.85746) (xy 35.822088 -224.837988) (xy 35.77593 -224.811339) (xy 35.734259 -224.778108)
			(xy 35.698007 -224.739037) (xy 35.667983 -224.695) (xy 35.644857 -224.646979) (xy 35.629147 -224.596049)
			(xy 35.621204 -224.543345) (xy 34.122624 -224.543345) (xy 34.114681 -224.596049) (xy 34.098971 -224.646979)
			(xy 34.075845 -224.695) (xy 34.045821 -224.739037) (xy 34.009569 -224.778108) (xy 33.967898 -224.811339)
			(xy 33.92174 -224.837988) (xy 33.872126 -224.85746) (xy 33.820164 -224.86932) (xy 33.767014 -224.873304)
			(xy 33.713864 -224.86932) (xy 33.661902 -224.85746) (xy 33.612288 -224.837988) (xy 33.56613 -224.811339)
			(xy 33.524459 -224.778108) (xy 33.488207 -224.739037) (xy 33.458183 -224.695) (xy 33.435057 -224.646979)
			(xy 33.419347 -224.596049) (xy 33.411404 -224.543345) (xy 32.391858 -224.543345) (xy 32.391858 -225.571304)
			(xy 34.120836 -225.571304) (xy 34.120836 -225.162364) (xy 34.121193 -225.152203) (xy 34.129007 -225.133443)
			(xy 34.143424 -225.11912) (xy 34.162234 -225.111428) (xy 34.172398 -225.111056) (xy 35.571938 -225.111056)
			(xy 35.579791 -225.111296) (xy 35.594788 -225.115957) (xy 35.601402 -225.1202) (xy 35.613161 -225.127793)
			(xy 35.639598 -225.136945) (xy 35.667527 -225.138586) (xy 35.694854 -225.132592) (xy 35.719532 -225.119412)
			(xy 35.729926 -225.11004) (xy 35.749918 -225.091443) (xy 35.79457 -225.060019) (xy 35.843498 -225.035783)
			(xy 35.895553 -225.019304) (xy 35.949513 -225.010967) (xy 35.976814 -225.010472) (xy 36.003461 -225.011011)
			(xy 36.05616 -225.018956) (xy 36.107086 -225.034666) (xy 36.155102 -225.057791) (xy 36.199135 -225.087814)
			(xy 36.238201 -225.124064) (xy 36.271429 -225.165732) (xy 36.298076 -225.211886) (xy 36.317546 -225.261497)
			(xy 36.329404 -225.313455) (xy 36.333387 -225.3666) (xy 36.331391 -225.393229) (xy 36.855136 -225.393229)
			(xy 36.855136 -225.339931) (xy 36.863079 -225.287227) (xy 36.878789 -225.236297) (xy 36.901915 -225.188276)
			(xy 36.931939 -225.144239) (xy 36.968191 -225.105168) (xy 37.009862 -225.071937) (xy 37.05602 -225.045288)
			(xy 37.105634 -225.025816) (xy 37.157596 -225.013956) (xy 37.210746 -225.009973) (xy 37.263896 -225.013956)
			(xy 37.315858 -225.025816) (xy 37.365472 -225.045288) (xy 37.41163 -225.071937) (xy 37.453301 -225.105168)
			(xy 37.489553 -225.144239) (xy 37.519577 -225.188276) (xy 37.542703 -225.236297) (xy 37.558413 -225.287227)
			(xy 37.566356 -225.339931) (xy 37.566854 -225.36658) (xy 37.566356 -225.393229) (xy 37.558413 -225.445933)
			(xy 37.542703 -225.496863) (xy 37.519577 -225.544884) (xy 37.489553 -225.588921) (xy 37.453301 -225.627992)
			(xy 37.41163 -225.661223) (xy 37.365472 -225.687872) (xy 37.315858 -225.707344) (xy 37.263896 -225.719204)
			(xy 37.210746 -225.723188) (xy 37.157596 -225.719204) (xy 37.105634 -225.707344) (xy 37.05602 -225.687872)
			(xy 37.009862 -225.661223) (xy 36.968191 -225.627992) (xy 36.931939 -225.588921) (xy 36.901915 -225.544884)
			(xy 36.878789 -225.496863) (xy 36.863079 -225.445933) (xy 36.855136 -225.393229) (xy 36.331391 -225.393229)
			(xy 36.329404 -225.419745) (xy 36.317546 -225.471703) (xy 36.298076 -225.521314) (xy 36.271429 -225.567468)
			(xy 36.238201 -225.609136) (xy 36.199135 -225.645386) (xy 36.155102 -225.675409) (xy 36.107086 -225.698534)
			(xy 36.05616 -225.714244) (xy 36.003461 -225.722189) (xy 35.976814 -225.722688) (xy 35.949551 -225.722189)
			(xy 35.895662 -225.713872) (xy 35.843674 -225.697431) (xy 35.794803 -225.67325) (xy 35.750193 -225.641895)
			(xy 35.73018 -225.623374) (xy 35.719774 -225.613955) (xy 35.695028 -225.600728) (xy 35.667614 -225.594748)
			(xy 35.639608 -225.596468) (xy 35.613131 -225.605757) (xy 35.601402 -225.613468) (xy 35.594786 -225.617706)
			(xy 35.579791 -225.622368) (xy 35.571938 -225.622612) (xy 34.172398 -225.622612) (xy 34.162278 -225.622077)
			(xy 34.143566 -225.614358) (xy 34.129212 -225.600087) (xy 34.121384 -225.581421) (xy 34.120836 -225.571304)
			(xy 32.391858 -225.571304) (xy 32.391858 -226.243367) (xy 33.411404 -226.243367) (xy 33.411404 -226.190069)
			(xy 33.419347 -226.137365) (xy 33.435057 -226.086435) (xy 33.458183 -226.038414) (xy 33.488207 -225.994377)
			(xy 33.524459 -225.955306) (xy 33.56613 -225.922075) (xy 33.612288 -225.895426) (xy 33.661902 -225.875954)
			(xy 33.713864 -225.864094) (xy 33.767014 -225.860111) (xy 33.820164 -225.864094) (xy 33.872126 -225.875954)
			(xy 33.92174 -225.895426) (xy 33.967898 -225.922075) (xy 34.009569 -225.955306) (xy 34.045821 -225.994377)
			(xy 34.075845 -226.038414) (xy 34.098971 -226.086435) (xy 34.114681 -226.137365) (xy 34.122624 -226.190069)
			(xy 34.123122 -226.216718) (xy 34.122624 -226.243367) (xy 35.621204 -226.243367) (xy 35.621204 -226.190069)
			(xy 35.629147 -226.137365) (xy 35.644857 -226.086435) (xy 35.667983 -226.038414) (xy 35.698007 -225.994377)
			(xy 35.734259 -225.955306) (xy 35.77593 -225.922075) (xy 35.822088 -225.895426) (xy 35.871702 -225.875954)
			(xy 35.923664 -225.864094) (xy 35.976814 -225.860111) (xy 36.029964 -225.864094) (xy 36.081926 -225.875954)
			(xy 36.13154 -225.895426) (xy 36.177698 -225.922075) (xy 36.219369 -225.955306) (xy 36.255621 -225.994377)
			(xy 36.285645 -226.038414) (xy 36.308771 -226.086435) (xy 36.324481 -226.137365) (xy 36.332424 -226.190069)
			(xy 36.332922 -226.216718) (xy 36.332424 -226.243367) (xy 36.324481 -226.296071) (xy 36.308771 -226.347001)
			(xy 36.285645 -226.395022) (xy 36.267632 -226.421442) (xy 37.564568 -226.421442) (xy 37.564568 -226.012502)
			(xy 37.564966 -226.002327) (xy 37.572756 -225.983526) (xy 37.58715 -225.96914) (xy 37.605955 -225.961361)
			(xy 37.61613 -225.96094) (xy 39.01567 -225.96094) (xy 39.02584 -225.961389) (xy 39.044634 -225.969164)
			(xy 39.05902 -225.983542) (xy 39.066806 -226.002332) (xy 39.067232 -226.012502) (xy 39.067232 -226.421442)
			(xy 39.0668 -226.431606) (xy 39.059006 -226.450382) (xy 39.044622 -226.464747) (xy 39.025835 -226.472514)
			(xy 39.01567 -226.473004) (xy 37.61613 -226.473004) (xy 37.605979 -226.472443) (xy 37.587219 -226.464687)
			(xy 37.572854 -226.450342) (xy 37.565071 -226.431592) (xy 37.564568 -226.421442) (xy 36.267632 -226.421442)
			(xy 36.255621 -226.439059) (xy 36.219369 -226.47813) (xy 36.177698 -226.511361) (xy 36.13154 -226.53801)
			(xy 36.081926 -226.557482) (xy 36.029964 -226.569342) (xy 35.976814 -226.573326) (xy 35.923664 -226.569342)
			(xy 35.871702 -226.557482) (xy 35.822088 -226.53801) (xy 35.77593 -226.511361) (xy 35.734259 -226.47813)
			(xy 35.698007 -226.439059) (xy 35.667983 -226.395022) (xy 35.644857 -226.347001) (xy 35.629147 -226.296071)
			(xy 35.621204 -226.243367) (xy 34.122624 -226.243367) (xy 34.114681 -226.296071) (xy 34.098971 -226.347001)
			(xy 34.075845 -226.395022) (xy 34.045821 -226.439059) (xy 34.009569 -226.47813) (xy 33.967898 -226.511361)
			(xy 33.92174 -226.53801) (xy 33.872126 -226.557482) (xy 33.820164 -226.569342) (xy 33.767014 -226.573326)
			(xy 33.713864 -226.569342) (xy 33.661902 -226.557482) (xy 33.612288 -226.53801) (xy 33.56613 -226.511361)
			(xy 33.524459 -226.47813) (xy 33.488207 -226.439059) (xy 33.458183 -226.395022) (xy 33.435057 -226.347001)
			(xy 33.419347 -226.296071) (xy 33.411404 -226.243367) (xy 32.391858 -226.243367) (xy 32.391858 -227.271326)
			(xy 34.120836 -227.271326) (xy 34.120836 -226.862386) (xy 34.121322 -226.852228) (xy 34.129101 -226.833459)
			(xy 34.143469 -226.819094) (xy 34.16224 -226.81132) (xy 34.172398 -226.810824) (xy 35.571938 -226.810824)
			(xy 35.579808 -226.811138) (xy 35.594807 -226.815917) (xy 35.601402 -226.820222) (xy 35.613162 -226.827811)
			(xy 35.639599 -226.836962) (xy 35.667527 -226.838602) (xy 35.694853 -226.832609) (xy 35.719531 -226.819433)
			(xy 35.729926 -226.810062) (xy 35.749921 -226.791468) (xy 35.794572 -226.760043) (xy 35.843499 -226.735806)
			(xy 35.895553 -226.719326) (xy 35.949514 -226.710989) (xy 35.976814 -226.710494) (xy 36.003463 -226.710989)
			(xy 36.056165 -226.718934) (xy 36.107094 -226.734645) (xy 36.155113 -226.757772) (xy 36.199149 -226.787796)
			(xy 36.238218 -226.824049) (xy 36.271448 -226.865719) (xy 36.298096 -226.911877) (xy 36.317567 -226.96149)
			(xy 36.329427 -227.013451) (xy 36.33341 -227.0666) (xy 36.331413 -227.093251) (xy 36.855136 -227.093251)
			(xy 36.855136 -227.039953) (xy 36.863079 -226.987249) (xy 36.878789 -226.936319) (xy 36.901915 -226.888298)
			(xy 36.931939 -226.844261) (xy 36.968191 -226.80519) (xy 37.009862 -226.771959) (xy 37.05602 -226.74531)
			(xy 37.105634 -226.725838) (xy 37.157596 -226.713978) (xy 37.210746 -226.709995) (xy 37.263896 -226.713978)
			(xy 37.315858 -226.725838) (xy 37.365472 -226.74531) (xy 37.41163 -226.771959) (xy 37.453301 -226.80519)
			(xy 37.489553 -226.844261) (xy 37.519577 -226.888298) (xy 37.542703 -226.936319) (xy 37.558413 -226.987249)
			(xy 37.566356 -227.039953) (xy 37.566854 -227.066602) (xy 37.566356 -227.093251) (xy 37.558413 -227.145955)
			(xy 37.542703 -227.196885) (xy 37.519577 -227.244906) (xy 37.489553 -227.288943) (xy 37.453301 -227.328014)
			(xy 37.41163 -227.361245) (xy 37.365472 -227.387894) (xy 37.315858 -227.407366) (xy 37.263896 -227.419226)
			(xy 37.210746 -227.42321) (xy 37.157596 -227.419226) (xy 37.105634 -227.407366) (xy 37.05602 -227.387894)
			(xy 37.009862 -227.361245) (xy 36.968191 -227.328014) (xy 36.931939 -227.288943) (xy 36.901915 -227.244906)
			(xy 36.878789 -227.196885) (xy 36.863079 -227.145955) (xy 36.855136 -227.093251) (xy 36.331413 -227.093251)
			(xy 36.329427 -227.119749) (xy 36.317567 -227.17171) (xy 36.298096 -227.221323) (xy 36.271448 -227.267481)
			(xy 36.238218 -227.309151) (xy 36.199149 -227.345404) (xy 36.155113 -227.375428) (xy 36.107094 -227.398555)
			(xy 36.056165 -227.414266) (xy 36.003463 -227.422211) (xy 35.976814 -227.42271) (xy 35.949551 -227.422205)
			(xy 35.895663 -227.413889) (xy 35.843675 -227.397448) (xy 35.794804 -227.373269) (xy 35.750193 -227.341916)
			(xy 35.73018 -227.323396) (xy 35.719773 -227.313976) (xy 35.695028 -227.300747) (xy 35.667614 -227.294766)
			(xy 35.639607 -227.296487) (xy 35.61313 -227.305778) (xy 35.601402 -227.31349) (xy 35.594791 -227.317767)
			(xy 35.579804 -227.322562) (xy 35.571938 -227.322888) (xy 34.172398 -227.322888) (xy 34.162243 -227.322369)
			(xy 34.143479 -227.314599) (xy 34.129115 -227.300241) (xy 34.121336 -227.28148) (xy 34.120836 -227.271326)
			(xy 32.391858 -227.271326) (xy 32.391858 -228.121464) (xy 34.120836 -228.121464) (xy 34.120836 -227.712524)
			(xy 34.121242 -227.702367) (xy 34.129036 -227.683608) (xy 34.143439 -227.669282) (xy 34.162239 -227.661588)
			(xy 34.172398 -227.661216) (xy 35.571938 -227.661216) (xy 35.579791 -227.661462) (xy 35.594788 -227.66612)
			(xy 35.601402 -227.67036) (xy 35.613165 -227.677943) (xy 35.639601 -227.68709) (xy 35.667527 -227.68873)
			(xy 35.694851 -227.682739) (xy 35.71953 -227.669567) (xy 35.729926 -227.6602) (xy 35.749928 -227.641613)
			(xy 35.794576 -227.610186) (xy 35.843501 -227.585947) (xy 35.895554 -227.569466) (xy 35.949514 -227.561128)
			(xy 35.976814 -227.560632) (xy 36.003466 -227.561051) (xy 36.056173 -227.568997) (xy 36.107108 -227.58471)
			(xy 36.155132 -227.607839) (xy 36.199172 -227.637867) (xy 36.238246 -227.674123) (xy 36.271479 -227.715798)
			(xy 36.29813 -227.76196) (xy 36.317603 -227.811579) (xy 36.329464 -227.863546) (xy 36.333448 -227.9167)
			(xy 36.329464 -227.969854) (xy 36.317603 -228.021821) (xy 36.29813 -228.07144) (xy 36.271479 -228.117602)
			(xy 36.268399 -228.121464) (xy 37.564568 -228.121464) (xy 37.564568 -227.712524) (xy 37.56504 -227.702375)
			(xy 37.572822 -227.68363) (xy 37.587203 -227.669306) (xy 37.60598 -227.6616) (xy 37.61613 -227.661216)
			(xy 39.01567 -227.661216) (xy 39.025792 -227.66175) (xy 39.044508 -227.669464) (xy 39.058864 -227.683735)
			(xy 39.066689 -227.702405) (xy 39.067232 -227.712524) (xy 39.067232 -228.121464) (xy 39.066749 -228.131612)
			(xy 39.058972 -228.150357) (xy 39.044594 -228.164681) (xy 39.025819 -228.172387) (xy 39.01567 -228.172772)
			(xy 37.61613 -228.172772) (xy 37.606007 -228.172249) (xy 37.587288 -228.164534) (xy 37.572931 -228.150258)
			(xy 37.565109 -228.131584) (xy 37.564568 -228.121464) (xy 36.268399 -228.121464) (xy 36.238246 -228.159277)
			(xy 36.199172 -228.195533) (xy 36.155132 -228.225561) (xy 36.107108 -228.24869) (xy 36.056173 -228.264403)
			(xy 36.003466 -228.272349) (xy 35.976814 -228.272848) (xy 35.94955 -228.272361) (xy 35.895661 -228.264042)
			(xy 35.843672 -228.247599) (xy 35.794801 -228.223415) (xy 35.750192 -228.192057) (xy 35.73018 -228.173534)
			(xy 35.719775 -228.164115) (xy 35.695027 -228.150893) (xy 35.667614 -228.144916) (xy 35.639609 -228.146635)
			(xy 35.613132 -228.15592) (xy 35.601402 -228.163628) (xy 35.594789 -228.167872) (xy 35.579791 -228.172529)
			(xy 35.571938 -228.172772) (xy 34.172398 -228.172772) (xy 34.162273 -228.172275) (xy 34.143554 -228.164549)
			(xy 34.129198 -228.150266) (xy 34.121377 -228.131587) (xy 34.120836 -228.121464) (xy 32.391858 -228.121464)
			(xy 32.391858 -228.793273) (xy 33.411404 -228.793273) (xy 33.411404 -228.739975) (xy 33.419347 -228.687271)
			(xy 33.435057 -228.636341) (xy 33.458183 -228.58832) (xy 33.488207 -228.544283) (xy 33.524459 -228.505212)
			(xy 33.56613 -228.471981) (xy 33.612288 -228.445332) (xy 33.661902 -228.42586) (xy 33.713864 -228.414)
			(xy 33.767014 -228.410017) (xy 33.820164 -228.414) (xy 33.872126 -228.42586) (xy 33.92174 -228.445332)
			(xy 33.967898 -228.471981) (xy 34.009569 -228.505212) (xy 34.045821 -228.544283) (xy 34.075845 -228.58832)
			(xy 34.098971 -228.636341) (xy 34.114681 -228.687271) (xy 34.122624 -228.739975) (xy 34.123122 -228.766624)
			(xy 34.122624 -228.793273) (xy 35.621204 -228.793273) (xy 35.621204 -228.739975) (xy 35.629147 -228.687271)
			(xy 35.644857 -228.636341) (xy 35.667983 -228.58832) (xy 35.698007 -228.544283) (xy 35.734259 -228.505212)
			(xy 35.77593 -228.471981) (xy 35.822088 -228.445332) (xy 35.871702 -228.42586) (xy 35.923664 -228.414)
			(xy 35.976814 -228.410017) (xy 36.029964 -228.414) (xy 36.081926 -228.42586) (xy 36.13154 -228.445332)
			(xy 36.177698 -228.471981) (xy 36.219369 -228.505212) (xy 36.255621 -228.544283) (xy 36.285645 -228.58832)
			(xy 36.308771 -228.636341) (xy 36.324481 -228.687271) (xy 36.332424 -228.739975) (xy 36.332922 -228.766624)
			(xy 36.332424 -228.793273) (xy 36.324481 -228.845977) (xy 36.308771 -228.896907) (xy 36.285645 -228.944928)
			(xy 36.267632 -228.971348) (xy 37.564568 -228.971348) (xy 37.564568 -228.562408) (xy 37.565028 -228.552258)
			(xy 37.572814 -228.533512) (xy 37.587199 -228.51919) (xy 37.605979 -228.511484) (xy 37.61613 -228.5111)
			(xy 39.01567 -228.5111) (xy 39.02579 -228.51165) (xy 39.044503 -228.51936) (xy 39.058859 -228.533627)
			(xy 39.066686 -228.552291) (xy 39.067232 -228.562408) (xy 39.067232 -228.971348) (xy 39.066818 -228.981501)
			(xy 39.059013 -229.000248) (xy 39.044615 -229.014569) (xy 39.025825 -229.022273) (xy 39.01567 -229.022656)
			(xy 37.61613 -229.022656) (xy 37.606005 -229.022149) (xy 37.587283 -229.01443) (xy 37.572926 -229.00015)
			(xy 37.565106 -228.981471) (xy 37.564568 -228.971348) (xy 36.267632 -228.971348) (xy 36.255621 -228.988965)
			(xy 36.219369 -229.028036) (xy 36.177698 -229.061267) (xy 36.13154 -229.087916) (xy 36.081926 -229.107388)
			(xy 36.029964 -229.119248) (xy 35.976814 -229.123232) (xy 35.923664 -229.119248) (xy 35.871702 -229.107388)
			(xy 35.822088 -229.087916) (xy 35.77593 -229.061267) (xy 35.734259 -229.028036) (xy 35.698007 -228.988965)
			(xy 35.667983 -228.944928) (xy 35.644857 -228.896907) (xy 35.629147 -228.845977) (xy 35.621204 -228.793273)
			(xy 34.122624 -228.793273) (xy 34.114681 -228.845977) (xy 34.098971 -228.896907) (xy 34.075845 -228.944928)
			(xy 34.045821 -228.988965) (xy 34.009569 -229.028036) (xy 33.967898 -229.061267) (xy 33.92174 -229.087916)
			(xy 33.872126 -229.107388) (xy 33.820164 -229.119248) (xy 33.767014 -229.123232) (xy 33.713864 -229.119248)
			(xy 33.661902 -229.107388) (xy 33.612288 -229.087916) (xy 33.56613 -229.061267) (xy 33.524459 -229.028036)
			(xy 33.488207 -228.988965) (xy 33.458183 -228.944928) (xy 33.435057 -228.896907) (xy 33.419347 -228.845977)
			(xy 33.411404 -228.793273) (xy 32.391858 -228.793273) (xy 32.391858 -229.821486) (xy 34.120836 -229.821486)
			(xy 34.120836 -229.412546) (xy 34.121301 -229.402378) (xy 34.129071 -229.383584) (xy 34.143444 -229.369198)
			(xy 34.16223 -229.361411) (xy 34.172398 -229.360984) (xy 35.571938 -229.360984) (xy 35.579809 -229.361288)
			(xy 35.594808 -229.366073) (xy 35.601402 -229.370382) (xy 35.613166 -229.377962) (xy 35.639602 -229.387106)
			(xy 35.667527 -229.388745) (xy 35.69485 -229.382757) (xy 35.719529 -229.369588) (xy 35.729926 -229.360222)
			(xy 35.749915 -229.341622) (xy 35.794569 -229.310199) (xy 35.843497 -229.285964) (xy 35.895552 -229.269485)
			(xy 35.949513 -229.261149) (xy 35.976814 -229.260654) (xy 36.00346 -229.261229) (xy 36.056156 -229.269174)
			(xy 36.107079 -229.284883) (xy 36.155093 -229.308007) (xy 36.199123 -229.338028) (xy 36.238188 -229.374276)
			(xy 36.271414 -229.415942) (xy 36.298059 -229.462094) (xy 36.317528 -229.511702) (xy 36.329387 -229.563657)
			(xy 36.333369 -229.6168) (xy 36.331375 -229.643411) (xy 36.855136 -229.643411) (xy 36.855136 -229.590113)
			(xy 36.863079 -229.537409) (xy 36.878789 -229.486479) (xy 36.901915 -229.438458) (xy 36.931939 -229.394421)
			(xy 36.968191 -229.35535) (xy 37.009862 -229.322119) (xy 37.05602 -229.29547) (xy 37.105634 -229.275998)
			(xy 37.157596 -229.264138) (xy 37.210746 -229.260155) (xy 37.263896 -229.264138) (xy 37.315858 -229.275998)
			(xy 37.365472 -229.29547) (xy 37.41163 -229.322119) (xy 37.453301 -229.35535) (xy 37.489553 -229.394421)
			(xy 37.519577 -229.438458) (xy 37.542703 -229.486479) (xy 37.558413 -229.537409) (xy 37.566356 -229.590113)
			(xy 37.566854 -229.616762) (xy 37.566356 -229.643411) (xy 37.558413 -229.696115) (xy 37.542703 -229.747045)
			(xy 37.519577 -229.795066) (xy 37.489553 -229.839103) (xy 37.453301 -229.878174) (xy 37.41163 -229.911405)
			(xy 37.365472 -229.938054) (xy 37.315858 -229.957526) (xy 37.263896 -229.969386) (xy 37.210746 -229.97337)
			(xy 37.157596 -229.969386) (xy 37.105634 -229.957526) (xy 37.05602 -229.938054) (xy 37.009862 -229.911405)
			(xy 36.968191 -229.878174) (xy 36.931939 -229.839103) (xy 36.901915 -229.795066) (xy 36.878789 -229.747045)
			(xy 36.863079 -229.696115) (xy 36.855136 -229.643411) (xy 36.331375 -229.643411) (xy 36.329387 -229.669943)
			(xy 36.317528 -229.721898) (xy 36.298059 -229.771506) (xy 36.271414 -229.817658) (xy 36.238188 -229.859324)
			(xy 36.199123 -229.895572) (xy 36.155093 -229.925593) (xy 36.107079 -229.948717) (xy 36.056156 -229.964426)
			(xy 36.00346 -229.972371) (xy 35.976814 -229.97287) (xy 35.949551 -229.972376) (xy 35.895662 -229.964059)
			(xy 35.843673 -229.947616) (xy 35.794802 -229.923434) (xy 35.750193 -229.892078) (xy 35.73018 -229.873556)
			(xy 35.719774 -229.864137) (xy 35.695028 -229.850912) (xy 35.667614 -229.844934) (xy 35.639608 -229.846653)
			(xy 35.613131 -229.85594) (xy 35.601402 -229.86365) (xy 35.594789 -229.867923) (xy 35.579803 -229.872721)
			(xy 35.571938 -229.873048) (xy 34.172398 -229.873048) (xy 34.162225 -229.872637) (xy 34.143427 -229.864849)
			(xy 34.129042 -229.850459) (xy 34.121259 -229.83166) (xy 34.120836 -229.821486) (xy 32.391858 -229.821486)
			(xy 32.391858 -230.493295) (xy 33.411404 -230.493295) (xy 33.411404 -230.439997) (xy 33.419347 -230.387293)
			(xy 33.435057 -230.336363) (xy 33.458183 -230.288342) (xy 33.488207 -230.244305) (xy 33.524459 -230.205234)
			(xy 33.56613 -230.172003) (xy 33.612288 -230.145354) (xy 33.661902 -230.125882) (xy 33.713864 -230.114022)
			(xy 33.767014 -230.110039) (xy 33.820164 -230.114022) (xy 33.872126 -230.125882) (xy 33.92174 -230.145354)
			(xy 33.967898 -230.172003) (xy 34.009569 -230.205234) (xy 34.045821 -230.244305) (xy 34.075845 -230.288342)
			(xy 34.098971 -230.336363) (xy 34.114681 -230.387293) (xy 34.122624 -230.439997) (xy 34.123122 -230.466646)
			(xy 34.122624 -230.493295) (xy 35.621204 -230.493295) (xy 35.621204 -230.439997) (xy 35.629147 -230.387293)
			(xy 35.644857 -230.336363) (xy 35.667983 -230.288342) (xy 35.698007 -230.244305) (xy 35.734259 -230.205234)
			(xy 35.77593 -230.172003) (xy 35.822088 -230.145354) (xy 35.871702 -230.125882) (xy 35.923664 -230.114022)
			(xy 35.976814 -230.110039) (xy 36.029964 -230.114022) (xy 36.081926 -230.125882) (xy 36.13154 -230.145354)
			(xy 36.177698 -230.172003) (xy 36.219369 -230.205234) (xy 36.255621 -230.244305) (xy 36.285645 -230.288342)
			(xy 36.308771 -230.336363) (xy 36.324481 -230.387293) (xy 36.332424 -230.439997) (xy 36.332922 -230.466646)
			(xy 36.332424 -230.493295) (xy 36.324481 -230.545999) (xy 36.308771 -230.596929) (xy 36.285645 -230.64495)
			(xy 36.267632 -230.67137) (xy 37.564568 -230.67137) (xy 37.564568 -230.26243) (xy 37.564989 -230.252257)
			(xy 37.57277 -230.233457) (xy 37.587157 -230.21907) (xy 37.605957 -230.211289) (xy 37.61613 -230.210868)
			(xy 39.01567 -230.210868) (xy 39.025843 -230.211289) (xy 39.044643 -230.21907) (xy 39.05903 -230.233457)
			(xy 39.066811 -230.252257) (xy 39.067232 -230.26243) (xy 39.067232 -230.67137) (xy 39.066811 -230.681543)
			(xy 39.05903 -230.700343) (xy 39.044643 -230.71473) (xy 39.025843 -230.722511) (xy 39.01567 -230.722932)
			(xy 37.61613 -230.722932) (xy 37.605957 -230.722511) (xy 37.587157 -230.71473) (xy 37.57277 -230.700343)
			(xy 37.564989 -230.681543) (xy 37.564568 -230.67137) (xy 36.267632 -230.67137) (xy 36.255621 -230.688987)
			(xy 36.219369 -230.728058) (xy 36.177698 -230.761289) (xy 36.13154 -230.787938) (xy 36.081926 -230.80741)
			(xy 36.029964 -230.81927) (xy 35.976814 -230.823254) (xy 35.923664 -230.81927) (xy 35.871702 -230.80741)
			(xy 35.822088 -230.787938) (xy 35.77593 -230.761289) (xy 35.734259 -230.728058) (xy 35.698007 -230.688987)
			(xy 35.667983 -230.64495) (xy 35.644857 -230.596929) (xy 35.629147 -230.545999) (xy 35.621204 -230.493295)
			(xy 34.122624 -230.493295) (xy 34.114681 -230.545999) (xy 34.098971 -230.596929) (xy 34.075845 -230.64495)
			(xy 34.045821 -230.688987) (xy 34.009569 -230.728058) (xy 33.967898 -230.761289) (xy 33.92174 -230.787938)
			(xy 33.872126 -230.80741) (xy 33.820164 -230.81927) (xy 33.767014 -230.823254) (xy 33.713864 -230.81927)
			(xy 33.661902 -230.80741) (xy 33.612288 -230.787938) (xy 33.56613 -230.761289) (xy 33.524459 -230.728058)
			(xy 33.488207 -230.688987) (xy 33.458183 -230.64495) (xy 33.435057 -230.596929) (xy 33.419347 -230.545999)
			(xy 33.411404 -230.493295) (xy 32.391858 -230.493295) (xy 32.391858 -231.521508) (xy 34.120836 -231.521508)
			(xy 34.120836 -231.112568) (xy 34.121196 -231.102407) (xy 34.129009 -231.083647) (xy 34.143425 -231.069324)
			(xy 34.162235 -231.061632) (xy 34.172398 -231.06126) (xy 35.571938 -231.06126) (xy 35.579791 -231.0615)
			(xy 35.594789 -231.066161) (xy 35.601402 -231.070404) (xy 35.613161 -231.077996) (xy 35.639598 -231.087148)
			(xy 35.667527 -231.088789) (xy 35.694854 -231.082795) (xy 35.719532 -231.069616) (xy 35.729926 -231.060244)
			(xy 35.749919 -231.041647) (xy 35.794571 -231.010224) (xy 35.843498 -230.985987) (xy 35.895553 -230.969508)
			(xy 35.949513 -230.961171) (xy 35.976814 -230.960676) (xy 36.003461 -230.961207) (xy 36.056161 -230.969152)
			(xy 36.107087 -230.984863) (xy 36.155104 -231.007988) (xy 36.199137 -231.038011) (xy 36.238204 -231.074261)
			(xy 36.271432 -231.11593) (xy 36.298079 -231.162085) (xy 36.317549 -231.211696) (xy 36.329408 -231.263654)
			(xy 36.333391 -231.3168) (xy 36.331395 -231.343433) (xy 36.855136 -231.343433) (xy 36.855136 -231.290135)
			(xy 36.863079 -231.237431) (xy 36.878789 -231.186501) (xy 36.901915 -231.13848) (xy 36.931939 -231.094443)
			(xy 36.968191 -231.055372) (xy 37.009862 -231.022141) (xy 37.05602 -230.995492) (xy 37.105634 -230.97602)
			(xy 37.157596 -230.96416) (xy 37.210746 -230.960177) (xy 37.263896 -230.96416) (xy 37.315858 -230.97602)
			(xy 37.365472 -230.995492) (xy 37.41163 -231.022141) (xy 37.453301 -231.055372) (xy 37.489553 -231.094443)
			(xy 37.519577 -231.13848) (xy 37.542703 -231.186501) (xy 37.558413 -231.237431) (xy 37.566356 -231.290135)
			(xy 37.566854 -231.316784) (xy 37.566356 -231.343433) (xy 37.558413 -231.396137) (xy 37.542703 -231.447067)
			(xy 37.519577 -231.495088) (xy 37.489553 -231.539125) (xy 37.453301 -231.578196) (xy 37.41163 -231.611427)
			(xy 37.365472 -231.638076) (xy 37.315858 -231.657548) (xy 37.263896 -231.669408) (xy 37.210746 -231.673392)
			(xy 37.157596 -231.669408) (xy 37.105634 -231.657548) (xy 37.05602 -231.638076) (xy 37.009862 -231.611427)
			(xy 36.968191 -231.578196) (xy 36.931939 -231.539125) (xy 36.901915 -231.495088) (xy 36.878789 -231.447067)
			(xy 36.863079 -231.396137) (xy 36.855136 -231.343433) (xy 36.331395 -231.343433) (xy 36.329408 -231.369946)
			(xy 36.317549 -231.421904) (xy 36.298079 -231.471515) (xy 36.271432 -231.51767) (xy 36.238204 -231.559339)
			(xy 36.199137 -231.595589) (xy 36.155104 -231.625612) (xy 36.107087 -231.648737) (xy 36.056161 -231.664448)
			(xy 36.003461 -231.672393) (xy 35.976814 -231.672892) (xy 35.949551 -231.672392) (xy 35.895663 -231.664075)
			(xy 35.843674 -231.647634) (xy 35.794803 -231.623453) (xy 35.750193 -231.592099) (xy 35.73018 -231.573578)
			(xy 35.719774 -231.564159) (xy 35.695028 -231.550932) (xy 35.667614 -231.544952) (xy 35.639607 -231.546672)
			(xy 35.613131 -231.555961) (xy 35.601402 -231.563672) (xy 35.594786 -231.567911) (xy 35.579791 -231.572572)
			(xy 35.571938 -231.572816) (xy 34.172398 -231.572816) (xy 34.162266 -231.572374) (xy 34.143536 -231.564637)
			(xy 34.129179 -231.550337) (xy 34.121367 -231.531638) (xy 34.120836 -231.521508) (xy 32.391858 -231.521508)
			(xy 32.391858 -232.193317) (xy 33.411404 -232.193317) (xy 33.411404 -232.140019) (xy 33.419347 -232.087315)
			(xy 33.435057 -232.036385) (xy 33.458183 -231.988364) (xy 33.488207 -231.944327) (xy 33.524459 -231.905256)
			(xy 33.56613 -231.872025) (xy 33.612288 -231.845376) (xy 33.661902 -231.825904) (xy 33.713864 -231.814044)
			(xy 33.767014 -231.810061) (xy 33.820164 -231.814044) (xy 33.872126 -231.825904) (xy 33.92174 -231.845376)
			(xy 33.967898 -231.872025) (xy 34.009569 -231.905256) (xy 34.045821 -231.944327) (xy 34.075845 -231.988364)
			(xy 34.098971 -232.036385) (xy 34.114681 -232.087315) (xy 34.122624 -232.140019) (xy 34.123122 -232.166668)
			(xy 34.122624 -232.193317) (xy 35.621204 -232.193317) (xy 35.621204 -232.140019) (xy 35.629147 -232.087315)
			(xy 35.644857 -232.036385) (xy 35.667983 -231.988364) (xy 35.698007 -231.944327) (xy 35.734259 -231.905256)
			(xy 35.77593 -231.872025) (xy 35.822088 -231.845376) (xy 35.871702 -231.825904) (xy 35.923664 -231.814044)
			(xy 35.976814 -231.810061) (xy 36.029964 -231.814044) (xy 36.081926 -231.825904) (xy 36.13154 -231.845376)
			(xy 36.177698 -231.872025) (xy 36.219369 -231.905256) (xy 36.255621 -231.944327) (xy 36.285645 -231.988364)
			(xy 36.308771 -232.036385) (xy 36.324481 -232.087315) (xy 36.332424 -232.140019) (xy 36.332922 -232.166668)
			(xy 36.332424 -232.193317) (xy 36.324481 -232.246021) (xy 36.308771 -232.296951) (xy 36.285645 -232.344972)
			(xy 36.267632 -232.371392) (xy 37.564568 -232.371392) (xy 37.564568 -231.962452) (xy 37.564982 -231.952299)
			(xy 37.572787 -231.933552) (xy 37.587185 -231.919231) (xy 37.605975 -231.911527) (xy 37.61613 -231.911144)
			(xy 39.01567 -231.911144) (xy 39.025795 -231.911651) (xy 39.044517 -231.91937) (xy 39.058874 -231.93365)
			(xy 39.066694 -231.952329) (xy 39.067232 -231.962452) (xy 39.067232 -232.371392) (xy 39.066772 -232.381542)
			(xy 39.058986 -232.400288) (xy 39.044601 -232.41461) (xy 39.025821 -232.422316) (xy 39.01567 -232.4227)
			(xy 37.61613 -232.4227) (xy 37.60601 -232.42215) (xy 37.587297 -232.41444) (xy 37.572941 -232.400173)
			(xy 37.565114 -232.381509) (xy 37.564568 -232.371392) (xy 36.267632 -232.371392) (xy 36.255621 -232.389009)
			(xy 36.219369 -232.42808) (xy 36.177698 -232.461311) (xy 36.13154 -232.48796) (xy 36.081926 -232.507432)
			(xy 36.029964 -232.519292) (xy 35.976814 -232.523276) (xy 35.923664 -232.519292) (xy 35.871702 -232.507432)
			(xy 35.822088 -232.48796) (xy 35.77593 -232.461311) (xy 35.734259 -232.42808) (xy 35.698007 -232.389009)
			(xy 35.667983 -232.344972) (xy 35.644857 -232.296951) (xy 35.629147 -232.246021) (xy 35.621204 -232.193317)
			(xy 34.122624 -232.193317) (xy 34.114681 -232.246021) (xy 34.098971 -232.296951) (xy 34.075845 -232.344972)
			(xy 34.045821 -232.389009) (xy 34.009569 -232.42808) (xy 33.967898 -232.461311) (xy 33.92174 -232.48796)
			(xy 33.872126 -232.507432) (xy 33.820164 -232.519292) (xy 33.767014 -232.523276) (xy 33.713864 -232.519292)
			(xy 33.661902 -232.507432) (xy 33.612288 -232.48796) (xy 33.56613 -232.461311) (xy 33.524459 -232.42808)
			(xy 33.488207 -232.389009) (xy 33.458183 -232.344972) (xy 33.435057 -232.296951) (xy 33.419347 -232.246021)
			(xy 33.411404 -232.193317) (xy 32.391858 -232.193317) (xy 32.391858 -233.22153) (xy 34.120836 -233.22153)
			(xy 34.120836 -232.81259) (xy 34.121325 -232.802432) (xy 34.129103 -232.783663) (xy 34.14347 -232.769298)
			(xy 34.16224 -232.761524) (xy 34.172398 -232.761028) (xy 35.571938 -232.761028) (xy 35.579808 -232.761342)
			(xy 35.594807 -232.766121) (xy 35.601402 -232.770426) (xy 35.613162 -232.778015) (xy 35.639599 -232.787165)
			(xy 35.667527 -232.788805) (xy 35.694853 -232.782812) (xy 35.719531 -232.769636) (xy 35.729926 -232.760266)
			(xy 35.749922 -232.741673) (xy 35.794573 -232.710248) (xy 35.843499 -232.686011) (xy 35.895553 -232.66953)
			(xy 35.949514 -232.661193) (xy 35.976814 -232.660698) (xy 36.003463 -232.661185) (xy 36.056166 -232.66913)
			(xy 36.107095 -232.684842) (xy 36.155115 -232.707968) (xy 36.199151 -232.737993) (xy 36.238221 -232.774246)
			(xy 36.271451 -232.815917) (xy 36.298099 -232.862075) (xy 36.317571 -232.911689) (xy 36.329431 -232.963651)
			(xy 36.333414 -233.0168) (xy 36.331416 -233.043455) (xy 36.855136 -233.043455) (xy 36.855136 -232.990157)
			(xy 36.863079 -232.937453) (xy 36.878789 -232.886523) (xy 36.901915 -232.838502) (xy 36.931939 -232.794465)
			(xy 36.968191 -232.755394) (xy 37.009862 -232.722163) (xy 37.05602 -232.695514) (xy 37.105634 -232.676042)
			(xy 37.157596 -232.664182) (xy 37.210746 -232.660199) (xy 37.263896 -232.664182) (xy 37.315858 -232.676042)
			(xy 37.365472 -232.695514) (xy 37.41163 -232.722163) (xy 37.453301 -232.755394) (xy 37.489553 -232.794465)
			(xy 37.519577 -232.838502) (xy 37.542703 -232.886523) (xy 37.558413 -232.937453) (xy 37.566356 -232.990157)
			(xy 37.566854 -233.016806) (xy 37.566356 -233.043455) (xy 37.558413 -233.096159) (xy 37.542703 -233.147089)
			(xy 37.519577 -233.19511) (xy 37.489553 -233.239147) (xy 37.453301 -233.278218) (xy 37.41163 -233.311449)
			(xy 37.365472 -233.338098) (xy 37.315858 -233.35757) (xy 37.263896 -233.36943) (xy 37.210746 -233.373414)
			(xy 37.157596 -233.36943) (xy 37.105634 -233.35757) (xy 37.05602 -233.338098) (xy 37.009862 -233.311449)
			(xy 36.968191 -233.278218) (xy 36.931939 -233.239147) (xy 36.901915 -233.19511) (xy 36.878789 -233.147089)
			(xy 36.863079 -233.096159) (xy 36.855136 -233.043455) (xy 36.331416 -233.043455) (xy 36.329431 -233.069949)
			(xy 36.317571 -233.121911) (xy 36.298099 -233.171525) (xy 36.271451 -233.217683) (xy 36.238221 -233.259354)
			(xy 36.199151 -233.295607) (xy 36.155115 -233.325632) (xy 36.107095 -233.348758) (xy 36.056166 -233.36447)
			(xy 36.003463 -233.372415) (xy 35.976814 -233.372914) (xy 35.949551 -233.372408) (xy 35.895663 -233.364092)
			(xy 35.843675 -233.347652) (xy 35.794804 -233.323472) (xy 35.750194 -233.29212) (xy 35.73018 -233.2736)
			(xy 35.719773 -233.26418) (xy 35.695028 -233.250951) (xy 35.667614 -233.24497) (xy 35.639607 -233.24669)
			(xy 35.61313 -233.255982) (xy 35.601402 -233.263694) (xy 35.594792 -233.267972) (xy 35.579804 -233.272766)
			(xy 35.571938 -233.273092) (xy 34.172398 -233.273092) (xy 34.162244 -233.272569) (xy 34.14348 -233.264799)
			(xy 34.129116 -233.250443) (xy 34.121337 -233.231684) (xy 34.120836 -233.22153) (xy 32.391858 -233.22153)
			(xy 32.391858 -233.893339) (xy 33.411404 -233.893339) (xy 33.411404 -233.840041) (xy 33.419347 -233.787337)
			(xy 33.435057 -233.736407) (xy 33.458183 -233.688386) (xy 33.488207 -233.644349) (xy 33.524459 -233.605278)
			(xy 33.56613 -233.572047) (xy 33.612288 -233.545398) (xy 33.661902 -233.525926) (xy 33.713864 -233.514066)
			(xy 33.767014 -233.510083) (xy 33.820164 -233.514066) (xy 33.872126 -233.525926) (xy 33.92174 -233.545398)
			(xy 33.967898 -233.572047) (xy 34.009569 -233.605278) (xy 34.045821 -233.644349) (xy 34.075845 -233.688386)
			(xy 34.098971 -233.736407) (xy 34.114681 -233.787337) (xy 34.122624 -233.840041) (xy 34.123122 -233.86669)
			(xy 34.122624 -233.893339) (xy 35.621204 -233.893339) (xy 35.621204 -233.840041) (xy 35.629147 -233.787337)
			(xy 35.644857 -233.736407) (xy 35.667983 -233.688386) (xy 35.698007 -233.644349) (xy 35.734259 -233.605278)
			(xy 35.77593 -233.572047) (xy 35.822088 -233.545398) (xy 35.871702 -233.525926) (xy 35.923664 -233.514066)
			(xy 35.976814 -233.510083) (xy 36.029964 -233.514066) (xy 36.081926 -233.525926) (xy 36.13154 -233.545398)
			(xy 36.177698 -233.572047) (xy 36.219369 -233.605278) (xy 36.255621 -233.644349) (xy 36.285645 -233.688386)
			(xy 36.308771 -233.736407) (xy 36.324481 -233.787337) (xy 36.332424 -233.840041) (xy 36.332922 -233.86669)
			(xy 36.332424 -233.893339) (xy 36.324481 -233.946043) (xy 36.308771 -233.996973) (xy 36.285645 -234.044994)
			(xy 36.267632 -234.071414) (xy 37.564568 -234.071414) (xy 37.564568 -233.662474) (xy 37.564943 -233.652297)
			(xy 37.572742 -233.633496) (xy 37.587143 -233.619111) (xy 37.605952 -233.611332) (xy 37.61613 -233.610912)
			(xy 39.01567 -233.610912) (xy 39.025836 -233.611388) (xy 39.044625 -233.619158) (xy 39.05901 -233.633528)
			(xy 39.066801 -233.652308) (xy 39.067232 -233.662474) (xy 39.067232 -234.071414) (xy 39.066847 -234.08159)
			(xy 39.059052 -234.100391) (xy 39.044654 -234.114776) (xy 39.025847 -234.122555) (xy 39.01567 -234.122976)
			(xy 37.61613 -234.122976) (xy 37.605962 -234.122512) (xy 37.587171 -234.114739) (xy 37.572785 -234.100366)
			(xy 37.564997 -234.081582) (xy 37.564568 -234.071414) (xy 36.267632 -234.071414) (xy 36.255621 -234.089031)
			(xy 36.219369 -234.128102) (xy 36.177698 -234.161333) (xy 36.13154 -234.187982) (xy 36.081926 -234.207454)
			(xy 36.029964 -234.219314) (xy 35.976814 -234.223298) (xy 35.923664 -234.219314) (xy 35.871702 -234.207454)
			(xy 35.822088 -234.187982) (xy 35.77593 -234.161333) (xy 35.734259 -234.128102) (xy 35.698007 -234.089031)
			(xy 35.667983 -234.044994) (xy 35.644857 -233.996973) (xy 35.629147 -233.946043) (xy 35.621204 -233.893339)
			(xy 34.122624 -233.893339) (xy 34.114681 -233.946043) (xy 34.098971 -233.996973) (xy 34.075845 -234.044994)
			(xy 34.045821 -234.089031) (xy 34.009569 -234.128102) (xy 33.967898 -234.161333) (xy 33.92174 -234.187982)
			(xy 33.872126 -234.207454) (xy 33.820164 -234.219314) (xy 33.767014 -234.223298) (xy 33.713864 -234.219314)
			(xy 33.661902 -234.207454) (xy 33.612288 -234.187982) (xy 33.56613 -234.161333) (xy 33.524459 -234.128102)
			(xy 33.488207 -234.089031) (xy 33.458183 -234.044994) (xy 33.435057 -233.996973) (xy 33.419347 -233.946043)
			(xy 33.411404 -233.893339) (xy 32.391858 -233.893339) (xy 32.391858 -234.921298) (xy 34.120836 -234.921298)
			(xy 34.120836 -234.512358) (xy 34.121299 -234.502198) (xy 34.129087 -234.483428) (xy 34.143462 -234.469064)
			(xy 34.162237 -234.461291) (xy 34.172398 -234.460796) (xy 35.571938 -234.460796) (xy 35.579808 -234.461115)
			(xy 35.594806 -234.465891) (xy 35.601402 -234.470194) (xy 35.613167 -234.477772) (xy 35.639603 -234.486915)
			(xy 35.667526 -234.488554) (xy 35.69485 -234.482566) (xy 35.719529 -234.469399) (xy 35.729926 -234.460034)
			(xy 35.749917 -234.441436) (xy 35.79457 -234.410012) (xy 35.843497 -234.385777) (xy 35.895552 -234.369298)
			(xy 35.949513 -234.360961) (xy 35.976814 -234.360466) (xy 36.003461 -234.361017) (xy 36.056158 -234.368962)
			(xy 36.107084 -234.384672) (xy 36.155099 -234.407796) (xy 36.199131 -234.437819) (xy 36.238197 -234.474068)
			(xy 36.271424 -234.515735) (xy 36.29807 -234.561889) (xy 36.31754 -234.611498) (xy 36.329398 -234.663456)
			(xy 36.333381 -234.7166) (xy 36.331386 -234.743223) (xy 36.855136 -234.743223) (xy 36.855136 -234.689925)
			(xy 36.863079 -234.637221) (xy 36.878789 -234.586291) (xy 36.901915 -234.53827) (xy 36.931939 -234.494233)
			(xy 36.968191 -234.455162) (xy 37.009862 -234.421931) (xy 37.05602 -234.395282) (xy 37.105634 -234.37581)
			(xy 37.157596 -234.36395) (xy 37.210746 -234.359967) (xy 37.263896 -234.36395) (xy 37.315858 -234.37581)
			(xy 37.365472 -234.395282) (xy 37.41163 -234.421931) (xy 37.453301 -234.455162) (xy 37.489553 -234.494233)
			(xy 37.519577 -234.53827) (xy 37.542703 -234.586291) (xy 37.558413 -234.637221) (xy 37.566356 -234.689925)
			(xy 37.566854 -234.716574) (xy 37.566356 -234.743223) (xy 37.558413 -234.795927) (xy 37.542703 -234.846857)
			(xy 37.519577 -234.894878) (xy 37.489553 -234.938915) (xy 37.453301 -234.977986) (xy 37.41163 -235.011217)
			(xy 37.365472 -235.037866) (xy 37.315858 -235.057338) (xy 37.263896 -235.069198) (xy 37.210746 -235.073182)
			(xy 37.157596 -235.069198) (xy 37.105634 -235.057338) (xy 37.05602 -235.037866) (xy 37.009862 -235.011217)
			(xy 36.968191 -234.977986) (xy 36.931939 -234.938915) (xy 36.901915 -234.894878) (xy 36.878789 -234.846857)
			(xy 36.863079 -234.795927) (xy 36.855136 -234.743223) (xy 36.331386 -234.743223) (xy 36.329398 -234.769744)
			(xy 36.31754 -234.821702) (xy 36.29807 -234.871311) (xy 36.271424 -234.917465) (xy 36.238197 -234.959132)
			(xy 36.199131 -234.995381) (xy 36.155099 -235.025404) (xy 36.107084 -235.048528) (xy 36.056158 -235.064238)
			(xy 36.003461 -235.072183) (xy 35.976814 -235.072682) (xy 35.949551 -235.072185) (xy 35.895662 -235.063868)
			(xy 35.843674 -235.047426) (xy 35.794802 -235.023244) (xy 35.750193 -234.99189) (xy 35.73018 -234.973368)
			(xy 35.719774 -234.963949) (xy 35.695028 -234.950723) (xy 35.667614 -234.944743) (xy 35.639608 -234.946463)
			(xy 35.613131 -234.955752) (xy 35.601402 -234.963462) (xy 35.59479 -234.967736) (xy 35.579804 -234.972533)
			(xy 35.571938 -234.97286) (xy 34.172398 -234.97286) (xy 34.16224 -234.972368) (xy 34.14347 -234.964593)
			(xy 34.129105 -234.950226) (xy 34.121331 -234.931456) (xy 34.120836 -234.921298) (xy 32.391858 -234.921298)
			(xy 32.391858 -235.593361) (xy 33.411404 -235.593361) (xy 33.411404 -235.540063) (xy 33.419347 -235.487359)
			(xy 33.435057 -235.436429) (xy 33.458183 -235.388408) (xy 33.488207 -235.344371) (xy 33.524459 -235.3053)
			(xy 33.56613 -235.272069) (xy 33.612288 -235.24542) (xy 33.661902 -235.225948) (xy 33.713864 -235.214088)
			(xy 33.767014 -235.210105) (xy 33.820164 -235.214088) (xy 33.872126 -235.225948) (xy 33.92174 -235.24542)
			(xy 33.967898 -235.272069) (xy 34.009569 -235.3053) (xy 34.045821 -235.344371) (xy 34.075845 -235.388408)
			(xy 34.098971 -235.436429) (xy 34.114681 -235.487359) (xy 34.122624 -235.540063) (xy 34.123122 -235.566712)
			(xy 34.122624 -235.593361) (xy 35.621204 -235.593361) (xy 35.621204 -235.540063) (xy 35.629147 -235.487359)
			(xy 35.644857 -235.436429) (xy 35.667983 -235.388408) (xy 35.698007 -235.344371) (xy 35.734259 -235.3053)
			(xy 35.77593 -235.272069) (xy 35.822088 -235.24542) (xy 35.871702 -235.225948) (xy 35.923664 -235.214088)
			(xy 35.976814 -235.210105) (xy 36.029964 -235.214088) (xy 36.081926 -235.225948) (xy 36.13154 -235.24542)
			(xy 36.177698 -235.272069) (xy 36.219369 -235.3053) (xy 36.255621 -235.344371) (xy 36.285645 -235.388408)
			(xy 36.308771 -235.436429) (xy 36.324481 -235.487359) (xy 36.332424 -235.540063) (xy 36.332922 -235.566712)
			(xy 36.332424 -235.593361) (xy 36.324481 -235.646065) (xy 36.308771 -235.696995) (xy 36.285645 -235.745016)
			(xy 36.267632 -235.771436) (xy 37.564568 -235.771436) (xy 37.564568 -235.362496) (xy 37.565018 -235.352346)
			(xy 37.572809 -235.333599) (xy 37.587196 -235.319277) (xy 37.605978 -235.311572) (xy 37.61613 -235.311188)
			(xy 39.01567 -235.311188) (xy 39.025788 -235.311749) (xy 39.044499 -235.319458) (xy 39.058855 -235.333721)
			(xy 39.066684 -235.352381) (xy 39.067232 -235.362496) (xy 39.067232 -235.771436) (xy 39.066809 -235.781588)
			(xy 39.059007 -235.800335) (xy 39.044612 -235.814656) (xy 39.025825 -235.822361) (xy 39.01567 -235.822744)
			(xy 37.61613 -235.822744) (xy 37.606003 -235.822249) (xy 37.58728 -235.814528) (xy 37.572922 -235.800244)
			(xy 37.565104 -235.78156) (xy 37.564568 -235.771436) (xy 36.267632 -235.771436) (xy 36.255621 -235.789053)
			(xy 36.219369 -235.828124) (xy 36.177698 -235.861355) (xy 36.13154 -235.888004) (xy 36.081926 -235.907476)
			(xy 36.029964 -235.919336) (xy 35.976814 -235.92332) (xy 35.923664 -235.919336) (xy 35.871702 -235.907476)
			(xy 35.822088 -235.888004) (xy 35.77593 -235.861355) (xy 35.734259 -235.828124) (xy 35.698007 -235.789053)
			(xy 35.667983 -235.745016) (xy 35.644857 -235.696995) (xy 35.629147 -235.646065) (xy 35.621204 -235.593361)
			(xy 34.122624 -235.593361) (xy 34.114681 -235.646065) (xy 34.098971 -235.696995) (xy 34.075845 -235.745016)
			(xy 34.045821 -235.789053) (xy 34.009569 -235.828124) (xy 33.967898 -235.861355) (xy 33.92174 -235.888004)
			(xy 33.872126 -235.907476) (xy 33.820164 -235.919336) (xy 33.767014 -235.92332) (xy 33.713864 -235.919336)
			(xy 33.661902 -235.907476) (xy 33.612288 -235.888004) (xy 33.56613 -235.861355) (xy 33.524459 -235.828124)
			(xy 33.488207 -235.789053) (xy 33.458183 -235.745016) (xy 33.435057 -235.696995) (xy 33.419347 -235.646065)
			(xy 33.411404 -235.593361) (xy 32.391858 -235.593361) (xy 32.391858 -236.62132) (xy 34.120836 -236.62132)
			(xy 34.120836 -236.21238) (xy 34.121206 -236.20222) (xy 34.129015 -236.18346) (xy 34.143428 -236.169136)
			(xy 34.162236 -236.161444) (xy 34.172398 -236.161072) (xy 35.571938 -236.161072) (xy 35.579792 -236.16131)
			(xy 35.594789 -236.165972) (xy 35.601402 -236.170216) (xy 35.613162 -236.177806) (xy 35.639599 -236.186957)
			(xy 35.667527 -236.188598) (xy 35.694853 -236.182605) (xy 35.719532 -236.169427) (xy 35.729926 -236.160056)
			(xy 35.749921 -236.141461) (xy 35.794572 -236.110037) (xy 35.843499 -236.0858) (xy 35.895553 -236.06932)
			(xy 35.949514 -236.060983) (xy 35.976814 -236.060488) (xy 36.003462 -236.060995) (xy 36.056163 -236.06894)
			(xy 36.107092 -236.084651) (xy 36.15511 -236.107777) (xy 36.199145 -236.137801) (xy 36.238213 -236.174053)
			(xy 36.271443 -236.215723) (xy 36.29809 -236.261879) (xy 36.317561 -236.311492) (xy 36.329421 -236.363452)
			(xy 36.333404 -236.4166) (xy 36.331407 -236.443245) (xy 36.855136 -236.443245) (xy 36.855136 -236.389947)
			(xy 36.863079 -236.337243) (xy 36.878789 -236.286313) (xy 36.901915 -236.238292) (xy 36.931939 -236.194255)
			(xy 36.968191 -236.155184) (xy 37.009862 -236.121953) (xy 37.05602 -236.095304) (xy 37.105634 -236.075832)
			(xy 37.157596 -236.063972) (xy 37.210746 -236.059989) (xy 37.263896 -236.063972) (xy 37.315858 -236.075832)
			(xy 37.365472 -236.095304) (xy 37.41163 -236.121953) (xy 37.453301 -236.155184) (xy 37.489553 -236.194255)
			(xy 37.519577 -236.238292) (xy 37.542703 -236.286313) (xy 37.558413 -236.337243) (xy 37.566356 -236.389947)
			(xy 37.566854 -236.416596) (xy 37.566356 -236.443245) (xy 37.558413 -236.495949) (xy 37.542703 -236.546879)
			(xy 37.519577 -236.5949) (xy 37.489553 -236.638937) (xy 37.453301 -236.678008) (xy 37.41163 -236.711239)
			(xy 37.365472 -236.737888) (xy 37.315858 -236.75736) (xy 37.263896 -236.76922) (xy 37.210746 -236.773204)
			(xy 37.157596 -236.76922) (xy 37.105634 -236.75736) (xy 37.05602 -236.737888) (xy 37.009862 -236.711239)
			(xy 36.968191 -236.678008) (xy 36.931939 -236.638937) (xy 36.901915 -236.5949) (xy 36.878789 -236.546879)
			(xy 36.863079 -236.495949) (xy 36.855136 -236.443245) (xy 36.331407 -236.443245) (xy 36.329421 -236.469748)
			(xy 36.317561 -236.521708) (xy 36.29809 -236.571321) (xy 36.271443 -236.617477) (xy 36.238213 -236.659147)
			(xy 36.199145 -236.695399) (xy 36.15511 -236.725423) (xy 36.107092 -236.748549) (xy 36.056163 -236.76426)
			(xy 36.003462 -236.772205) (xy 35.976814 -236.772704) (xy 35.949551 -236.772201) (xy 35.895663 -236.763884)
			(xy 35.843675 -236.747444) (xy 35.794803 -236.723264) (xy 35.750193 -236.69191) (xy 35.73018 -236.67339)
			(xy 35.719773 -236.66397) (xy 35.695028 -236.650742) (xy 35.667614 -236.644761) (xy 35.639607 -236.646482)
			(xy 35.613131 -236.655772) (xy 35.601402 -236.663484) (xy 35.594787 -236.667724) (xy 35.579791 -236.672384)
			(xy 35.571938 -236.672628) (xy 34.172398 -236.672628) (xy 34.162267 -236.672174) (xy 34.14354 -236.66444)
			(xy 34.129183 -236.650143) (xy 34.121369 -236.631449) (xy 34.120836 -236.62132) (xy 32.391858 -236.62132)
			(xy 32.391858 -237.471458) (xy 34.120836 -237.471458) (xy 34.120836 -237.062518) (xy 34.121278 -237.052348)
			(xy 34.129057 -237.033554) (xy 34.143437 -237.019168) (xy 34.162228 -237.011382) (xy 34.172398 -237.010956)
			(xy 35.571938 -237.010956) (xy 35.579809 -237.011265) (xy 35.594808 -237.016047) (xy 35.601402 -237.020354)
			(xy 35.613164 -237.027938) (xy 35.639601 -237.037086) (xy 35.667527 -237.038725) (xy 35.694852 -237.032734)
			(xy 35.71953 -237.019562) (xy 35.729926 -237.010194) (xy 35.749927 -236.991606) (xy 35.794576 -236.960179)
			(xy 35.843501 -236.935941) (xy 35.895554 -236.919459) (xy 35.949514 -236.911122) (xy 35.976814 -236.910626)
			(xy 36.003465 -236.911057) (xy 36.056172 -236.919003) (xy 36.107106 -236.934716) (xy 36.155129 -236.957844)
			(xy 36.199169 -236.987871) (xy 36.238241 -237.024127) (xy 36.271474 -237.065801) (xy 36.298125 -237.111963)
			(xy 36.317598 -237.161581) (xy 36.329458 -237.213547) (xy 36.333442 -237.2667) (xy 36.329458 -237.319853)
			(xy 36.317598 -237.371819) (xy 36.298125 -237.421437) (xy 36.271474 -237.467599) (xy 36.268397 -237.471458)
			(xy 37.564568 -237.471458) (xy 37.564568 -237.062518) (xy 37.564979 -237.052344) (xy 37.572764 -237.033544)
			(xy 37.587154 -237.019157) (xy 37.605956 -237.011377) (xy 37.61613 -237.010956) (xy 39.01567 -237.010956)
			(xy 39.025842 -237.011389) (xy 39.044639 -237.019167) (xy 39.059026 -237.033551) (xy 39.066809 -237.052346)
			(xy 39.067232 -237.062518) (xy 39.067232 -237.471458) (xy 39.066801 -237.481631) (xy 39.059024 -237.50043)
			(xy 39.04464 -237.514818) (xy 39.025843 -237.522599) (xy 39.01567 -237.52302) (xy 37.61613 -237.52302)
			(xy 37.605955 -237.52261) (xy 37.587153 -237.514828) (xy 37.572766 -237.500437) (xy 37.564987 -237.481633)
			(xy 37.564568 -237.471458) (xy 36.268397 -237.471458) (xy 36.238241 -237.509273) (xy 36.199169 -237.545529)
			(xy 36.155129 -237.575556) (xy 36.107106 -237.598684) (xy 36.056172 -237.614397) (xy 36.003465 -237.622343)
			(xy 35.976814 -237.622842) (xy 35.94955 -237.622356) (xy 35.895661 -237.614038) (xy 35.843672 -237.597594)
			(xy 35.7948 -237.57341) (xy 35.750192 -237.542051) (xy 35.73018 -237.523528) (xy 35.719775 -237.514109)
			(xy 35.695027 -237.500888) (xy 35.667614 -237.494911) (xy 35.639609 -237.49663) (xy 35.613132 -237.505914)
			(xy 35.601402 -237.513622) (xy 35.594793 -237.517902) (xy 35.579804 -237.522695) (xy 35.571938 -237.52302)
			(xy 34.172398 -237.52302) (xy 34.162221 -237.522637) (xy 34.143418 -237.514843) (xy 34.129032 -237.500445)
			(xy 34.121255 -237.481635) (xy 34.120836 -237.471458) (xy 32.391858 -237.471458) (xy 32.391858 -238.143267)
			(xy 33.411404 -238.143267) (xy 33.411404 -238.089969) (xy 33.419347 -238.037265) (xy 33.435057 -237.986335)
			(xy 33.458183 -237.938314) (xy 33.488207 -237.894277) (xy 33.524459 -237.855206) (xy 33.56613 -237.821975)
			(xy 33.612288 -237.795326) (xy 33.661902 -237.775854) (xy 33.713864 -237.763994) (xy 33.767014 -237.760011)
			(xy 33.820164 -237.763994) (xy 33.872126 -237.775854) (xy 33.92174 -237.795326) (xy 33.967898 -237.821975)
			(xy 34.009569 -237.855206) (xy 34.045821 -237.894277) (xy 34.075845 -237.938314) (xy 34.098971 -237.986335)
			(xy 34.114681 -238.037265) (xy 34.122624 -238.089969) (xy 34.123122 -238.116618) (xy 34.122624 -238.143267)
			(xy 35.621204 -238.143267) (xy 35.621204 -238.089969) (xy 35.629147 -238.037265) (xy 35.644857 -237.986335)
			(xy 35.667983 -237.938314) (xy 35.698007 -237.894277) (xy 35.734259 -237.855206) (xy 35.77593 -237.821975)
			(xy 35.822088 -237.795326) (xy 35.871702 -237.775854) (xy 35.923664 -237.763994) (xy 35.976814 -237.760011)
			(xy 36.029964 -237.763994) (xy 36.081926 -237.775854) (xy 36.13154 -237.795326) (xy 36.177698 -237.821975)
			(xy 36.219369 -237.855206) (xy 36.255621 -237.894277) (xy 36.285645 -237.938314) (xy 36.308771 -237.986335)
			(xy 36.324481 -238.037265) (xy 36.332424 -238.089969) (xy 36.332922 -238.116618) (xy 36.332424 -238.143267)
			(xy 36.324481 -238.195971) (xy 36.308771 -238.246901) (xy 36.285645 -238.294922) (xy 36.267632 -238.321342)
			(xy 37.564568 -238.321342) (xy 37.564568 -237.912402) (xy 37.564966 -237.902227) (xy 37.572756 -237.883426)
			(xy 37.58715 -237.86904) (xy 37.605955 -237.861261) (xy 37.61613 -237.86084) (xy 39.01567 -237.86084)
			(xy 39.02584 -237.861289) (xy 39.044634 -237.869064) (xy 39.05902 -237.883442) (xy 39.066806 -237.902232)
			(xy 39.067232 -237.912402) (xy 39.067232 -238.321342) (xy 39.0668 -238.331506) (xy 39.059006 -238.350282)
			(xy 39.044622 -238.364647) (xy 39.025835 -238.372414) (xy 39.01567 -238.372904) (xy 37.61613 -238.372904)
			(xy 37.605979 -238.372343) (xy 37.587219 -238.364587) (xy 37.572854 -238.350242) (xy 37.565071 -238.331492)
			(xy 37.564568 -238.321342) (xy 36.267632 -238.321342) (xy 36.255621 -238.338959) (xy 36.219369 -238.37803)
			(xy 36.177698 -238.411261) (xy 36.13154 -238.43791) (xy 36.081926 -238.457382) (xy 36.029964 -238.469242)
			(xy 35.976814 -238.473226) (xy 35.923664 -238.469242) (xy 35.871702 -238.457382) (xy 35.822088 -238.43791)
			(xy 35.77593 -238.411261) (xy 35.734259 -238.37803) (xy 35.698007 -238.338959) (xy 35.667983 -238.294922)
			(xy 35.644857 -238.246901) (xy 35.629147 -238.195971) (xy 35.621204 -238.143267) (xy 34.122624 -238.143267)
			(xy 34.114681 -238.195971) (xy 34.098971 -238.246901) (xy 34.075845 -238.294922) (xy 34.045821 -238.338959)
			(xy 34.009569 -238.37803) (xy 33.967898 -238.411261) (xy 33.92174 -238.43791) (xy 33.872126 -238.457382)
			(xy 33.820164 -238.469242) (xy 33.767014 -238.473226) (xy 33.713864 -238.469242) (xy 33.661902 -238.457382)
			(xy 33.612288 -238.43791) (xy 33.56613 -238.411261) (xy 33.524459 -238.37803) (xy 33.488207 -238.338959)
			(xy 33.458183 -238.294922) (xy 33.435057 -238.246901) (xy 33.419347 -238.195971) (xy 33.411404 -238.143267)
			(xy 32.391858 -238.143267) (xy 32.391858 -239.17148) (xy 34.120836 -239.17148) (xy 34.120836 -238.76254)
			(xy 34.121255 -238.752384) (xy 34.129044 -238.733626) (xy 34.143443 -238.7193) (xy 34.16224 -238.711605)
			(xy 34.172398 -238.711232) (xy 35.571938 -238.711232) (xy 35.579791 -238.711476) (xy 35.594788 -238.716135)
			(xy 35.601402 -238.720376) (xy 35.613166 -238.727957) (xy 35.639602 -238.737102) (xy 35.667527 -238.738741)
			(xy 35.694851 -238.732752) (xy 35.719529 -238.719582) (xy 35.729926 -238.710216) (xy 35.74993 -238.691632)
			(xy 35.794578 -238.660204) (xy 35.843502 -238.635964) (xy 35.895555 -238.619482) (xy 35.949514 -238.611144)
			(xy 35.976814 -238.610648) (xy 36.003459 -238.611235) (xy 36.056154 -238.619179) (xy 36.107077 -238.634889)
			(xy 36.15509 -238.658012) (xy 36.19912 -238.688033) (xy 36.238184 -238.72428) (xy 36.271409 -238.765945)
			(xy 36.298054 -238.812097) (xy 36.317523 -238.861704) (xy 36.329381 -238.913658) (xy 36.333363 -238.9668)
			(xy 36.331369 -238.993405) (xy 36.855136 -238.993405) (xy 36.855136 -238.940107) (xy 36.863079 -238.887403)
			(xy 36.878789 -238.836473) (xy 36.901915 -238.788452) (xy 36.931939 -238.744415) (xy 36.968191 -238.705344)
			(xy 37.009862 -238.672113) (xy 37.05602 -238.645464) (xy 37.105634 -238.625992) (xy 37.157596 -238.614132)
			(xy 37.210746 -238.610149) (xy 37.263896 -238.614132) (xy 37.315858 -238.625992) (xy 37.365472 -238.645464)
			(xy 37.41163 -238.672113) (xy 37.453301 -238.705344) (xy 37.489553 -238.744415) (xy 37.519577 -238.788452)
			(xy 37.542703 -238.836473) (xy 37.558413 -238.887403) (xy 37.566356 -238.940107) (xy 37.566854 -238.966756)
			(xy 37.566356 -238.993405) (xy 37.558413 -239.046109) (xy 37.542703 -239.097039) (xy 37.519577 -239.14506)
			(xy 37.489553 -239.189097) (xy 37.453301 -239.228168) (xy 37.41163 -239.261399) (xy 37.365472 -239.288048)
			(xy 37.315858 -239.30752) (xy 37.263896 -239.31938) (xy 37.210746 -239.323364) (xy 37.157596 -239.31938)
			(xy 37.105634 -239.30752) (xy 37.05602 -239.288048) (xy 37.009862 -239.261399) (xy 36.968191 -239.228168)
			(xy 36.931939 -239.189097) (xy 36.901915 -239.14506) (xy 36.878789 -239.097039) (xy 36.863079 -239.046109)
			(xy 36.855136 -238.993405) (xy 36.331369 -238.993405) (xy 36.329381 -239.019942) (xy 36.317523 -239.071896)
			(xy 36.298054 -239.121503) (xy 36.271409 -239.167655) (xy 36.238184 -239.20932) (xy 36.19912 -239.245567)
			(xy 36.15509 -239.275588) (xy 36.107077 -239.298711) (xy 36.056154 -239.314421) (xy 36.003459 -239.322365)
			(xy 35.976814 -239.322864) (xy 35.94955 -239.322372) (xy 35.895662 -239.314054) (xy 35.843673 -239.297612)
			(xy 35.794801 -239.273429) (xy 35.750192 -239.242072) (xy 35.73018 -239.22355) (xy 35.719774 -239.214131)
			(xy 35.695028 -239.200907) (xy 35.667614 -239.194929) (xy 35.639608 -239.196648) (xy 35.613132 -239.205935)
			(xy 35.601402 -239.213644) (xy 35.59479 -239.21789) (xy 35.579792 -239.222545) (xy 35.571938 -239.222788)
			(xy 34.172398 -239.222788) (xy 34.162275 -239.222276) (xy 34.143559 -239.214553) (xy 34.129204 -239.200275)
			(xy 34.12138 -239.181601) (xy 34.120836 -239.17148) (xy 32.391858 -239.17148) (xy 32.391858 -239.843289)
			(xy 33.411404 -239.843289) (xy 33.411404 -239.789991) (xy 33.419347 -239.737287) (xy 33.435057 -239.686357)
			(xy 33.458183 -239.638336) (xy 33.488207 -239.594299) (xy 33.524459 -239.555228) (xy 33.56613 -239.521997)
			(xy 33.612288 -239.495348) (xy 33.661902 -239.475876) (xy 33.713864 -239.464016) (xy 33.767014 -239.460033)
			(xy 33.820164 -239.464016) (xy 33.872126 -239.475876) (xy 33.92174 -239.495348) (xy 33.967898 -239.521997)
			(xy 34.009569 -239.555228) (xy 34.045821 -239.594299) (xy 34.075845 -239.638336) (xy 34.098971 -239.686357)
			(xy 34.114681 -239.737287) (xy 34.122624 -239.789991) (xy 34.123122 -239.81664) (xy 34.122624 -239.843289)
			(xy 35.621204 -239.843289) (xy 35.621204 -239.789991) (xy 35.629147 -239.737287) (xy 35.644857 -239.686357)
			(xy 35.667983 -239.638336) (xy 35.698007 -239.594299) (xy 35.734259 -239.555228) (xy 35.77593 -239.521997)
			(xy 35.822088 -239.495348) (xy 35.871702 -239.475876) (xy 35.923664 -239.464016) (xy 35.976814 -239.460033)
			(xy 36.029964 -239.464016) (xy 36.081926 -239.475876) (xy 36.13154 -239.495348) (xy 36.177698 -239.521997)
			(xy 36.219369 -239.555228) (xy 36.255621 -239.594299) (xy 36.285645 -239.638336) (xy 36.308771 -239.686357)
			(xy 36.324481 -239.737287) (xy 36.332424 -239.789991) (xy 36.332922 -239.81664) (xy 36.332424 -239.843289)
			(xy 36.324481 -239.895993) (xy 36.308771 -239.946923) (xy 36.285645 -239.994944) (xy 36.267632 -240.021364)
			(xy 37.564568 -240.021364) (xy 37.564568 -239.612424) (xy 37.56504 -239.602275) (xy 37.572822 -239.58353)
			(xy 37.587203 -239.569206) (xy 37.60598 -239.5615) (xy 37.61613 -239.561116) (xy 39.01567 -239.561116)
			(xy 39.025792 -239.56165) (xy 39.044508 -239.569364) (xy 39.058864 -239.583635) (xy 39.066689 -239.602305)
			(xy 39.067232 -239.612424) (xy 39.067232 -240.021364) (xy 39.066749 -240.031512) (xy 39.058972 -240.050257)
			(xy 39.044594 -240.064581) (xy 39.025819 -240.072287) (xy 39.01567 -240.072672) (xy 37.61613 -240.072672)
			(xy 37.606007 -240.072149) (xy 37.587288 -240.064434) (xy 37.572931 -240.050158) (xy 37.565109 -240.031484)
			(xy 37.564568 -240.021364) (xy 36.267632 -240.021364) (xy 36.255621 -240.038981) (xy 36.219369 -240.078052)
			(xy 36.177698 -240.111283) (xy 36.13154 -240.137932) (xy 36.081926 -240.157404) (xy 36.029964 -240.169264)
			(xy 35.976814 -240.173248) (xy 35.923664 -240.169264) (xy 35.871702 -240.157404) (xy 35.822088 -240.137932)
			(xy 35.77593 -240.111283) (xy 35.734259 -240.078052) (xy 35.698007 -240.038981) (xy 35.667983 -239.994944)
			(xy 35.644857 -239.946923) (xy 35.629147 -239.895993) (xy 35.621204 -239.843289) (xy 34.122624 -239.843289)
			(xy 34.114681 -239.895993) (xy 34.098971 -239.946923) (xy 34.075845 -239.994944) (xy 34.045821 -240.038981)
			(xy 34.009569 -240.078052) (xy 33.967898 -240.111283) (xy 33.92174 -240.137932) (xy 33.872126 -240.157404)
			(xy 33.820164 -240.169264) (xy 33.767014 -240.173248) (xy 33.713864 -240.169264) (xy 33.661902 -240.157404)
			(xy 33.612288 -240.137932) (xy 33.56613 -240.111283) (xy 33.524459 -240.078052) (xy 33.488207 -240.038981)
			(xy 33.458183 -239.994944) (xy 33.435057 -239.946923) (xy 33.419347 -239.895993) (xy 33.411404 -239.843289)
			(xy 32.391858 -239.843289) (xy 32.391858 -240.871502) (xy 34.120836 -240.871502) (xy 34.120836 -240.462562)
			(xy 34.121302 -240.452402) (xy 34.129089 -240.433632) (xy 34.143463 -240.419269) (xy 34.162238 -240.411495)
			(xy 34.172398 -240.411) (xy 35.571938 -240.411) (xy 35.579808 -240.411318) (xy 35.594806 -240.416095)
			(xy 35.601402 -240.420398) (xy 35.613168 -240.427975) (xy 35.639603 -240.437118) (xy 35.667526 -240.438757)
			(xy 35.69485 -240.432769) (xy 35.719529 -240.419602) (xy 35.729926 -240.410238) (xy 35.749918 -240.39164)
			(xy 35.79457 -240.360217) (xy 35.843498 -240.335981) (xy 35.895553 -240.319502) (xy 35.949513 -240.311165)
			(xy 35.976814 -240.31067) (xy 36.003461 -240.311213) (xy 36.056159 -240.319158) (xy 36.107085 -240.334868)
			(xy 36.155101 -240.357993) (xy 36.199133 -240.388016) (xy 36.2382 -240.424265) (xy 36.271427 -240.465933)
			(xy 36.298074 -240.512087) (xy 36.317544 -240.561697) (xy 36.329402 -240.613655) (xy 36.333385 -240.6668)
			(xy 36.331389 -240.693427) (xy 36.855136 -240.693427) (xy 36.855136 -240.640129) (xy 36.863079 -240.587425)
			(xy 36.878789 -240.536495) (xy 36.901915 -240.488474) (xy 36.931939 -240.444437) (xy 36.968191 -240.405366)
			(xy 37.009862 -240.372135) (xy 37.05602 -240.345486) (xy 37.105634 -240.326014) (xy 37.157596 -240.314154)
			(xy 37.210746 -240.310171) (xy 37.263896 -240.314154) (xy 37.315858 -240.326014) (xy 37.365472 -240.345486)
			(xy 37.41163 -240.372135) (xy 37.453301 -240.405366) (xy 37.489553 -240.444437) (xy 37.519577 -240.488474)
			(xy 37.542703 -240.536495) (xy 37.558413 -240.587425) (xy 37.566356 -240.640129) (xy 37.566854 -240.666778)
			(xy 37.566356 -240.693427) (xy 37.558413 -240.746131) (xy 37.542703 -240.797061) (xy 37.519577 -240.845082)
			(xy 37.489553 -240.889119) (xy 37.453301 -240.92819) (xy 37.41163 -240.961421) (xy 37.365472 -240.98807)
			(xy 37.315858 -241.007542) (xy 37.263896 -241.019402) (xy 37.210746 -241.023386) (xy 37.157596 -241.019402)
			(xy 37.105634 -241.007542) (xy 37.05602 -240.98807) (xy 37.009862 -240.961421) (xy 36.968191 -240.92819)
			(xy 36.931939 -240.889119) (xy 36.901915 -240.845082) (xy 36.878789 -240.797061) (xy 36.863079 -240.746131)
			(xy 36.855136 -240.693427) (xy 36.331389 -240.693427) (xy 36.329402 -240.719945) (xy 36.317544 -240.771903)
			(xy 36.298074 -240.821513) (xy 36.271427 -240.867667) (xy 36.2382 -240.909335) (xy 36.199133 -240.945584)
			(xy 36.155101 -240.975607) (xy 36.107085 -240.998732) (xy 36.056159 -241.014442) (xy 36.003461 -241.022387)
			(xy 35.976814 -241.022886) (xy 35.949551 -241.022388) (xy 35.895662 -241.014071) (xy 35.843674 -240.997629)
			(xy 35.794803 -240.973448) (xy 35.750193 -240.942093) (xy 35.73018 -240.923572) (xy 35.719774 -240.914153)
			(xy 35.695028 -240.900926) (xy 35.667614 -240.894947) (xy 35.639608 -240.896666) (xy 35.613131 -240.905955)
			(xy 35.601402 -240.913666) (xy 35.59479 -240.917941) (xy 35.579804 -240.922738) (xy 35.571938 -240.923064)
			(xy 34.172398 -240.923064) (xy 34.16224 -240.922568) (xy 34.143472 -240.914794) (xy 34.129106 -240.900428)
			(xy 34.121332 -240.88166) (xy 34.120836 -240.871502) (xy 32.391858 -240.871502) (xy 32.391858 -241.543311)
			(xy 33.411404 -241.543311) (xy 33.411404 -241.490013) (xy 33.419347 -241.437309) (xy 33.435057 -241.386379)
			(xy 33.458183 -241.338358) (xy 33.488207 -241.294321) (xy 33.524459 -241.25525) (xy 33.56613 -241.222019)
			(xy 33.612288 -241.19537) (xy 33.661902 -241.175898) (xy 33.713864 -241.164038) (xy 33.767014 -241.160055)
			(xy 33.820164 -241.164038) (xy 33.872126 -241.175898) (xy 33.92174 -241.19537) (xy 33.967898 -241.222019)
			(xy 34.009569 -241.25525) (xy 34.045821 -241.294321) (xy 34.075845 -241.338358) (xy 34.098971 -241.386379)
			(xy 34.114681 -241.437309) (xy 34.122624 -241.490013) (xy 34.123122 -241.516662) (xy 34.122624 -241.543311)
			(xy 35.621204 -241.543311) (xy 35.621204 -241.490013) (xy 35.629147 -241.437309) (xy 35.644857 -241.386379)
			(xy 35.667983 -241.338358) (xy 35.698007 -241.294321) (xy 35.734259 -241.25525) (xy 35.77593 -241.222019)
			(xy 35.822088 -241.19537) (xy 35.871702 -241.175898) (xy 35.923664 -241.164038) (xy 35.976814 -241.160055)
			(xy 36.029964 -241.164038) (xy 36.081926 -241.175898) (xy 36.13154 -241.19537) (xy 36.177698 -241.222019)
			(xy 36.219369 -241.25525) (xy 36.255621 -241.294321) (xy 36.285645 -241.338358) (xy 36.308771 -241.386379)
			(xy 36.324481 -241.437309) (xy 36.332424 -241.490013) (xy 36.332922 -241.516662) (xy 36.332424 -241.543311)
			(xy 36.324481 -241.596015) (xy 36.308771 -241.646945) (xy 36.285645 -241.694966) (xy 36.267632 -241.721386)
			(xy 37.564568 -241.721386) (xy 37.564568 -241.312446) (xy 37.565002 -241.302274) (xy 37.572778 -241.283474)
			(xy 37.587161 -241.269087) (xy 37.605958 -241.261305) (xy 37.61613 -241.260884) (xy 39.01567 -241.260884)
			(xy 39.025845 -241.26129) (xy 39.044648 -241.269073) (xy 39.059036 -241.283465) (xy 39.066813 -241.302271)
			(xy 39.067232 -241.312446) (xy 39.067232 -241.721386) (xy 39.066824 -241.73156) (xy 39.059038 -241.750361)
			(xy 39.044647 -241.764747) (xy 39.025845 -241.772527) (xy 39.01567 -241.772948) (xy 37.61613 -241.772948)
			(xy 37.605959 -241.772511) (xy 37.587162 -241.764733) (xy 37.572776 -241.750351) (xy 37.564992 -241.731557)
			(xy 37.564568 -241.721386) (xy 36.267632 -241.721386) (xy 36.255621 -241.739003) (xy 36.219369 -241.778074)
			(xy 36.177698 -241.811305) (xy 36.13154 -241.837954) (xy 36.081926 -241.857426) (xy 36.029964 -241.869286)
			(xy 35.976814 -241.87327) (xy 35.923664 -241.869286) (xy 35.871702 -241.857426) (xy 35.822088 -241.837954)
			(xy 35.77593 -241.811305) (xy 35.734259 -241.778074) (xy 35.698007 -241.739003) (xy 35.667983 -241.694966)
			(xy 35.644857 -241.646945) (xy 35.629147 -241.596015) (xy 35.621204 -241.543311) (xy 34.122624 -241.543311)
			(xy 34.114681 -241.596015) (xy 34.098971 -241.646945) (xy 34.075845 -241.694966) (xy 34.045821 -241.739003)
			(xy 34.009569 -241.778074) (xy 33.967898 -241.811305) (xy 33.92174 -241.837954) (xy 33.872126 -241.857426)
			(xy 33.820164 -241.869286) (xy 33.767014 -241.87327) (xy 33.713864 -241.869286) (xy 33.661902 -241.857426)
			(xy 33.612288 -241.837954) (xy 33.56613 -241.811305) (xy 33.524459 -241.778074) (xy 33.488207 -241.739003)
			(xy 33.458183 -241.694966) (xy 33.435057 -241.646945) (xy 33.419347 -241.596015) (xy 33.411404 -241.543311)
			(xy 32.391858 -241.543311) (xy 32.391858 -242.393449) (xy 35.621204 -242.393449) (xy 35.621204 -242.340151)
			(xy 35.629147 -242.287447) (xy 35.644857 -242.236517) (xy 35.667983 -242.188496) (xy 35.698007 -242.144459)
			(xy 35.734259 -242.105388) (xy 35.77593 -242.072157) (xy 35.822088 -242.045508) (xy 35.871702 -242.026036)
			(xy 35.923664 -242.014176) (xy 35.976814 -242.010193) (xy 36.029964 -242.014176) (xy 36.081926 -242.026036)
			(xy 36.13154 -242.045508) (xy 36.177698 -242.072157) (xy 36.219369 -242.105388) (xy 36.255621 -242.144459)
			(xy 36.285645 -242.188496) (xy 36.308771 -242.236517) (xy 36.324481 -242.287447) (xy 36.332424 -242.340151)
			(xy 36.332922 -242.3668) (xy 36.332424 -242.393449) (xy 36.855136 -242.393449) (xy 36.855136 -242.340151)
			(xy 36.863079 -242.287447) (xy 36.878789 -242.236517) (xy 36.901915 -242.188496) (xy 36.931939 -242.144459)
			(xy 36.968191 -242.105388) (xy 37.009862 -242.072157) (xy 37.05602 -242.045508) (xy 37.105634 -242.026036)
			(xy 37.157596 -242.014176) (xy 37.210746 -242.010193) (xy 37.263896 -242.014176) (xy 37.315858 -242.026036)
			(xy 37.365472 -242.045508) (xy 37.41163 -242.072157) (xy 37.453301 -242.105388) (xy 37.489553 -242.144459)
			(xy 37.519577 -242.188496) (xy 37.542703 -242.236517) (xy 37.558413 -242.287447) (xy 37.566356 -242.340151)
			(xy 37.566854 -242.3668) (xy 37.566356 -242.393449) (xy 37.558413 -242.446153) (xy 37.542703 -242.497083)
			(xy 37.519577 -242.545104) (xy 37.489553 -242.589141) (xy 37.453301 -242.628212) (xy 37.41163 -242.661443)
			(xy 37.365472 -242.688092) (xy 37.315858 -242.707564) (xy 37.263896 -242.719424) (xy 37.210746 -242.723408)
			(xy 37.157596 -242.719424) (xy 37.105634 -242.707564) (xy 37.05602 -242.688092) (xy 37.009862 -242.661443)
			(xy 36.968191 -242.628212) (xy 36.931939 -242.589141) (xy 36.901915 -242.545104) (xy 36.878789 -242.497083)
			(xy 36.863079 -242.446153) (xy 36.855136 -242.393449) (xy 36.332424 -242.393449) (xy 36.324481 -242.446153)
			(xy 36.308771 -242.497083) (xy 36.285645 -242.545104) (xy 36.255621 -242.589141) (xy 36.219369 -242.628212)
			(xy 36.177698 -242.661443) (xy 36.13154 -242.688092) (xy 36.081926 -242.707564) (xy 36.029964 -242.719424)
			(xy 35.976814 -242.723408) (xy 35.923664 -242.719424) (xy 35.871702 -242.707564) (xy 35.822088 -242.688092)
			(xy 35.77593 -242.661443) (xy 35.734259 -242.628212) (xy 35.698007 -242.589141) (xy 35.667983 -242.545104)
			(xy 35.644857 -242.497083) (xy 35.629147 -242.446153) (xy 35.621204 -242.393449) (xy 32.391858 -242.393449)
			(xy 32.391858 -243.243333) (xy 35.621204 -243.243333) (xy 35.621204 -243.190035) (xy 35.629147 -243.137331)
			(xy 35.644857 -243.086401) (xy 35.667983 -243.03838) (xy 35.698007 -242.994343) (xy 35.734259 -242.955272)
			(xy 35.77593 -242.922041) (xy 35.822088 -242.895392) (xy 35.871702 -242.87592) (xy 35.923664 -242.86406)
			(xy 35.976814 -242.860077) (xy 36.029964 -242.86406) (xy 36.081926 -242.87592) (xy 36.13154 -242.895392)
			(xy 36.177698 -242.922041) (xy 36.219369 -242.955272) (xy 36.255621 -242.994343) (xy 36.285645 -243.03838)
			(xy 36.308771 -243.086401) (xy 36.324481 -243.137331) (xy 36.332424 -243.190035) (xy 36.332922 -243.216684)
			(xy 36.332424 -243.243333) (xy 36.324481 -243.296037) (xy 36.308771 -243.346967) (xy 36.285645 -243.394988)
			(xy 36.255621 -243.439025) (xy 36.219369 -243.478096) (xy 36.177698 -243.511327) (xy 36.13154 -243.537976)
			(xy 36.081926 -243.557448) (xy 36.029964 -243.569308) (xy 35.976814 -243.573292) (xy 35.923664 -243.569308)
			(xy 35.871702 -243.557448) (xy 35.822088 -243.537976) (xy 35.77593 -243.511327) (xy 35.734259 -243.478096)
			(xy 35.698007 -243.439025) (xy 35.667983 -243.394988) (xy 35.644857 -243.346967) (xy 35.629147 -243.296037)
			(xy 35.621204 -243.243333) (xy 32.391858 -243.243333) (xy 32.391858 -244.093217) (xy 33.411404 -244.093217)
			(xy 33.411404 -244.039919) (xy 33.419347 -243.987215) (xy 33.435057 -243.936285) (xy 33.458183 -243.888264)
			(xy 33.488207 -243.844227) (xy 33.524459 -243.805156) (xy 33.56613 -243.771925) (xy 33.612288 -243.745276)
			(xy 33.661902 -243.725804) (xy 33.713864 -243.713944) (xy 33.767014 -243.709961) (xy 33.820164 -243.713944)
			(xy 33.872126 -243.725804) (xy 33.92174 -243.745276) (xy 33.967898 -243.771925) (xy 34.009569 -243.805156)
			(xy 34.045821 -243.844227) (xy 34.075845 -243.888264) (xy 34.098971 -243.936285) (xy 34.114681 -243.987215)
			(xy 34.122624 -244.039919) (xy 34.123122 -244.066568) (xy 34.122624 -244.093217) (xy 35.621204 -244.093217)
			(xy 35.621204 -244.039919) (xy 35.629147 -243.987215) (xy 35.644857 -243.936285) (xy 35.667983 -243.888264)
			(xy 35.698007 -243.844227) (xy 35.734259 -243.805156) (xy 35.77593 -243.771925) (xy 35.822088 -243.745276)
			(xy 35.871702 -243.725804) (xy 35.923664 -243.713944) (xy 35.976814 -243.709961) (xy 36.029964 -243.713944)
			(xy 36.081926 -243.725804) (xy 36.13154 -243.745276) (xy 36.177698 -243.771925) (xy 36.219369 -243.805156)
			(xy 36.255621 -243.844227) (xy 36.285645 -243.888264) (xy 36.308771 -243.936285) (xy 36.324481 -243.987215)
			(xy 36.332424 -244.039919) (xy 36.332922 -244.066568) (xy 36.332424 -244.093217) (xy 36.324481 -244.145921)
			(xy 36.308771 -244.196851) (xy 36.285645 -244.244872) (xy 36.255621 -244.288909) (xy 36.219369 -244.32798)
			(xy 36.177698 -244.361211) (xy 36.13154 -244.38786) (xy 36.081926 -244.407332) (xy 36.029964 -244.419192)
			(xy 35.976814 -244.423176) (xy 35.923664 -244.419192) (xy 35.871702 -244.407332) (xy 35.822088 -244.38786)
			(xy 35.77593 -244.361211) (xy 35.734259 -244.32798) (xy 35.698007 -244.288909) (xy 35.667983 -244.244872)
			(xy 35.644857 -244.196851) (xy 35.629147 -244.145921) (xy 35.621204 -244.093217) (xy 34.122624 -244.093217)
			(xy 34.114681 -244.145921) (xy 34.098971 -244.196851) (xy 34.075845 -244.244872) (xy 34.045821 -244.288909)
			(xy 34.009569 -244.32798) (xy 33.967898 -244.361211) (xy 33.92174 -244.38786) (xy 33.872126 -244.407332)
			(xy 33.820164 -244.419192) (xy 33.767014 -244.423176) (xy 33.713864 -244.419192) (xy 33.661902 -244.407332)
			(xy 33.612288 -244.38786) (xy 33.56613 -244.361211) (xy 33.524459 -244.32798) (xy 33.488207 -244.288909)
			(xy 33.458183 -244.244872) (xy 33.435057 -244.196851) (xy 33.419347 -244.145921) (xy 33.411404 -244.093217)
			(xy 32.391858 -244.093217) (xy 32.391858 -245.12143) (xy 34.120836 -245.12143) (xy 34.120836 -244.71249)
			(xy 34.121325 -244.702332) (xy 34.129103 -244.683563) (xy 34.14347 -244.669198) (xy 34.16224 -244.661424)
			(xy 34.172398 -244.660928) (xy 35.571938 -244.660928) (xy 35.579808 -244.661242) (xy 35.594807 -244.666021)
			(xy 35.601402 -244.670326) (xy 35.613162 -244.677915) (xy 35.639599 -244.687065) (xy 35.667527 -244.688705)
			(xy 35.694853 -244.682712) (xy 35.719531 -244.669536) (xy 35.729926 -244.660166) (xy 35.749922 -244.641573)
			(xy 35.794573 -244.610148) (xy 35.843499 -244.585911) (xy 35.895553 -244.56943) (xy 35.949514 -244.561093)
			(xy 35.976814 -244.560598) (xy 36.003463 -244.561085) (xy 36.056166 -244.56903) (xy 36.107095 -244.584742)
			(xy 36.155115 -244.607868) (xy 36.199151 -244.637893) (xy 36.238221 -244.674146) (xy 36.271451 -244.715817)
			(xy 36.298099 -244.761975) (xy 36.317571 -244.811589) (xy 36.329431 -244.863551) (xy 36.333414 -244.9167)
			(xy 36.331416 -244.943355) (xy 36.855136 -244.943355) (xy 36.855136 -244.890057) (xy 36.863079 -244.837353)
			(xy 36.878789 -244.786423) (xy 36.901915 -244.738402) (xy 36.931939 -244.694365) (xy 36.968191 -244.655294)
			(xy 37.009862 -244.622063) (xy 37.05602 -244.595414) (xy 37.105634 -244.575942) (xy 37.157596 -244.564082)
			(xy 37.210746 -244.560099) (xy 37.263896 -244.564082) (xy 37.315858 -244.575942) (xy 37.365472 -244.595414)
			(xy 37.41163 -244.622063) (xy 37.453301 -244.655294) (xy 37.489553 -244.694365) (xy 37.519577 -244.738402)
			(xy 37.542703 -244.786423) (xy 37.558413 -244.837353) (xy 37.566356 -244.890057) (xy 37.566854 -244.916706)
			(xy 37.566356 -244.943355) (xy 37.558413 -244.996059) (xy 37.542703 -245.046989) (xy 37.519577 -245.09501)
			(xy 37.489553 -245.139047) (xy 37.453301 -245.178118) (xy 37.41163 -245.211349) (xy 37.365472 -245.237998)
			(xy 37.315858 -245.25747) (xy 37.263896 -245.26933) (xy 37.210746 -245.273314) (xy 37.157596 -245.26933)
			(xy 37.105634 -245.25747) (xy 37.05602 -245.237998) (xy 37.009862 -245.211349) (xy 36.968191 -245.178118)
			(xy 36.931939 -245.139047) (xy 36.901915 -245.09501) (xy 36.878789 -245.046989) (xy 36.863079 -244.996059)
			(xy 36.855136 -244.943355) (xy 36.331416 -244.943355) (xy 36.329431 -244.969849) (xy 36.317571 -245.021811)
			(xy 36.298099 -245.071425) (xy 36.271451 -245.117583) (xy 36.238221 -245.159254) (xy 36.199151 -245.195507)
			(xy 36.155115 -245.225532) (xy 36.107095 -245.248658) (xy 36.056166 -245.26437) (xy 36.003463 -245.272315)
			(xy 35.976814 -245.272814) (xy 35.949551 -245.272308) (xy 35.895663 -245.263992) (xy 35.843675 -245.247552)
			(xy 35.794804 -245.223372) (xy 35.750194 -245.19202) (xy 35.73018 -245.1735) (xy 35.719773 -245.16408)
			(xy 35.695028 -245.150851) (xy 35.667614 -245.14487) (xy 35.639607 -245.14659) (xy 35.61313 -245.155882)
			(xy 35.601402 -245.163594) (xy 35.594792 -245.167872) (xy 35.579804 -245.172666) (xy 35.571938 -245.172992)
			(xy 34.172398 -245.172992) (xy 34.162244 -245.172469) (xy 34.14348 -245.164699) (xy 34.129116 -245.150343)
			(xy 34.121337 -245.131584) (xy 34.120836 -245.12143) (xy 32.391858 -245.12143) (xy 32.391858 -245.793239)
			(xy 33.411404 -245.793239) (xy 33.411404 -245.739941) (xy 33.419347 -245.687237) (xy 33.435057 -245.636307)
			(xy 33.458183 -245.588286) (xy 33.488207 -245.544249) (xy 33.524459 -245.505178) (xy 33.56613 -245.471947)
			(xy 33.612288 -245.445298) (xy 33.661902 -245.425826) (xy 33.713864 -245.413966) (xy 33.767014 -245.409983)
			(xy 33.820164 -245.413966) (xy 33.872126 -245.425826) (xy 33.92174 -245.445298) (xy 33.967898 -245.471947)
			(xy 34.009569 -245.505178) (xy 34.045821 -245.544249) (xy 34.075845 -245.588286) (xy 34.098971 -245.636307)
			(xy 34.114681 -245.687237) (xy 34.122624 -245.739941) (xy 34.123122 -245.76659) (xy 34.122624 -245.793239)
			(xy 35.621204 -245.793239) (xy 35.621204 -245.739941) (xy 35.629147 -245.687237) (xy 35.644857 -245.636307)
			(xy 35.667983 -245.588286) (xy 35.698007 -245.544249) (xy 35.734259 -245.505178) (xy 35.77593 -245.471947)
			(xy 35.822088 -245.445298) (xy 35.871702 -245.425826) (xy 35.923664 -245.413966) (xy 35.976814 -245.409983)
			(xy 36.029964 -245.413966) (xy 36.081926 -245.425826) (xy 36.13154 -245.445298) (xy 36.177698 -245.471947)
			(xy 36.219369 -245.505178) (xy 36.255621 -245.544249) (xy 36.285645 -245.588286) (xy 36.308771 -245.636307)
			(xy 36.324481 -245.687237) (xy 36.332424 -245.739941) (xy 36.332922 -245.76659) (xy 36.332424 -245.793239)
			(xy 36.324481 -245.845943) (xy 36.308771 -245.896873) (xy 36.285645 -245.944894) (xy 36.255621 -245.988931)
			(xy 36.219369 -246.028002) (xy 36.177698 -246.061233) (xy 36.13154 -246.087882) (xy 36.081926 -246.107354)
			(xy 36.029964 -246.119214) (xy 35.976814 -246.123198) (xy 35.923664 -246.119214) (xy 35.871702 -246.107354)
			(xy 35.822088 -246.087882) (xy 35.77593 -246.061233) (xy 35.734259 -246.028002) (xy 35.698007 -245.988931)
			(xy 35.667983 -245.944894) (xy 35.644857 -245.896873) (xy 35.629147 -245.845943) (xy 35.621204 -245.793239)
			(xy 34.122624 -245.793239) (xy 34.114681 -245.845943) (xy 34.098971 -245.896873) (xy 34.075845 -245.944894)
			(xy 34.045821 -245.988931) (xy 34.009569 -246.028002) (xy 33.967898 -246.061233) (xy 33.92174 -246.087882)
			(xy 33.872126 -246.107354) (xy 33.820164 -246.119214) (xy 33.767014 -246.123198) (xy 33.713864 -246.119214)
			(xy 33.661902 -246.107354) (xy 33.612288 -246.087882) (xy 33.56613 -246.061233) (xy 33.524459 -246.028002)
			(xy 33.488207 -245.988931) (xy 33.458183 -245.944894) (xy 33.435057 -245.896873) (xy 33.419347 -245.845943)
			(xy 33.411404 -245.793239) (xy 32.391858 -245.793239) (xy 32.391858 -246.821452) (xy 34.120836 -246.821452)
			(xy 34.120836 -246.412512) (xy 34.121232 -246.402354) (xy 34.12903 -246.383595) (xy 34.143436 -246.36927)
			(xy 34.162238 -246.361576) (xy 34.172398 -246.361204) (xy 35.571938 -246.361204) (xy 35.57979 -246.361452)
			(xy 35.594787 -246.366109) (xy 35.601402 -246.370348) (xy 35.613164 -246.377933) (xy 35.6396 -246.387081)
			(xy 35.667527 -246.388721) (xy 35.694852 -246.38273) (xy 35.71953 -246.369556) (xy 35.729926 -246.360188)
			(xy 35.749926 -246.341599) (xy 35.794575 -246.310173) (xy 35.8435 -246.285934) (xy 35.895554 -246.269453)
			(xy 35.949514 -246.261116) (xy 35.976814 -246.26062) (xy 36.003465 -246.261063) (xy 36.056171 -246.269009)
			(xy 36.107104 -246.284721) (xy 36.155126 -246.307849) (xy 36.199165 -246.337876) (xy 36.238237 -246.374131)
			(xy 36.271469 -246.415804) (xy 36.298119 -246.461965) (xy 36.317592 -246.511582) (xy 36.329452 -246.563548)
			(xy 36.333436 -246.6167) (xy 36.331436 -246.643377) (xy 36.855136 -246.643377) (xy 36.855136 -246.590079)
			(xy 36.863079 -246.537375) (xy 36.878789 -246.486445) (xy 36.901915 -246.438424) (xy 36.931939 -246.394387)
			(xy 36.968191 -246.355316) (xy 37.009862 -246.322085) (xy 37.05602 -246.295436) (xy 37.105634 -246.275964)
			(xy 37.157596 -246.264104) (xy 37.210746 -246.260121) (xy 37.263896 -246.264104) (xy 37.315858 -246.275964)
			(xy 37.365472 -246.295436) (xy 37.41163 -246.322085) (xy 37.453301 -246.355316) (xy 37.489553 -246.394387)
			(xy 37.519577 -246.438424) (xy 37.542703 -246.486445) (xy 37.558413 -246.537375) (xy 37.566356 -246.590079)
			(xy 37.566854 -246.616728) (xy 37.566356 -246.643377) (xy 37.558413 -246.696081) (xy 37.542703 -246.747011)
			(xy 37.519577 -246.795032) (xy 37.489553 -246.839069) (xy 37.453301 -246.87814) (xy 37.41163 -246.911371)
			(xy 37.365472 -246.93802) (xy 37.315858 -246.957492) (xy 37.263896 -246.969352) (xy 37.210746 -246.973336)
			(xy 37.157596 -246.969352) (xy 37.105634 -246.957492) (xy 37.05602 -246.93802) (xy 37.009862 -246.911371)
			(xy 36.968191 -246.87814) (xy 36.931939 -246.839069) (xy 36.901915 -246.795032) (xy 36.878789 -246.747011)
			(xy 36.863079 -246.696081) (xy 36.855136 -246.643377) (xy 36.331436 -246.643377) (xy 36.329452 -246.669852)
			(xy 36.317592 -246.721818) (xy 36.298119 -246.771435) (xy 36.271469 -246.817596) (xy 36.238237 -246.859269)
			(xy 36.199165 -246.895524) (xy 36.155126 -246.925551) (xy 36.107104 -246.948679) (xy 36.056171 -246.964391)
			(xy 36.003465 -246.972337) (xy 35.976814 -246.972836) (xy 35.94955 -246.972352) (xy 35.89566 -246.964033)
			(xy 35.843671 -246.947589) (xy 35.7948 -246.923405) (xy 35.750192 -246.892046) (xy 35.73018 -246.873522)
			(xy 35.719775 -246.864103) (xy 35.695027 -246.850883) (xy 35.667614 -246.844906) (xy 35.639609 -246.846624)
			(xy 35.613132 -246.855909) (xy 35.601402 -246.863616) (xy 35.594789 -246.867859) (xy 35.579791 -246.872517)
			(xy 35.571938 -246.87276) (xy 34.172398 -246.87276) (xy 34.162271 -246.872275) (xy 34.14355 -246.864547)
			(xy 34.129194 -246.85026) (xy 34.121375 -246.831576) (xy 34.120836 -246.821452) (xy 32.391858 -246.821452)
			(xy 32.391858 -247.493261) (xy 33.411404 -247.493261) (xy 33.411404 -247.439963) (xy 33.419347 -247.387259)
			(xy 33.435057 -247.336329) (xy 33.458183 -247.288308) (xy 33.488207 -247.244271) (xy 33.524459 -247.2052)
			(xy 33.56613 -247.171969) (xy 33.612288 -247.14532) (xy 33.661902 -247.125848) (xy 33.713864 -247.113988)
			(xy 33.767014 -247.110005) (xy 33.820164 -247.113988) (xy 33.872126 -247.125848) (xy 33.92174 -247.14532)
			(xy 33.967898 -247.171969) (xy 34.009569 -247.2052) (xy 34.045821 -247.244271) (xy 34.075845 -247.288308)
			(xy 34.098971 -247.336329) (xy 34.114681 -247.387259) (xy 34.122624 -247.439963) (xy 34.123122 -247.466612)
			(xy 34.122624 -247.493261) (xy 35.621204 -247.493261) (xy 35.621204 -247.439963) (xy 35.629147 -247.387259)
			(xy 35.644857 -247.336329) (xy 35.667983 -247.288308) (xy 35.698007 -247.244271) (xy 35.734259 -247.2052)
			(xy 35.77593 -247.171969) (xy 35.822088 -247.14532) (xy 35.871702 -247.125848) (xy 35.923664 -247.113988)
			(xy 35.976814 -247.110005) (xy 36.029964 -247.113988) (xy 36.081926 -247.125848) (xy 36.13154 -247.14532)
			(xy 36.177698 -247.171969) (xy 36.219369 -247.2052) (xy 36.255621 -247.244271) (xy 36.285645 -247.288308)
			(xy 36.308771 -247.336329) (xy 36.324481 -247.387259) (xy 36.332424 -247.439963) (xy 36.332922 -247.466612)
			(xy 36.332424 -247.493261) (xy 36.324481 -247.545965) (xy 36.308771 -247.596895) (xy 36.285645 -247.644916)
			(xy 36.267632 -247.671336) (xy 37.564568 -247.671336) (xy 37.564568 -247.262396) (xy 37.565018 -247.252246)
			(xy 37.572809 -247.233499) (xy 37.587196 -247.219177) (xy 37.605978 -247.211472) (xy 37.61613 -247.211088)
			(xy 39.01567 -247.211088) (xy 39.025788 -247.211649) (xy 39.044499 -247.219358) (xy 39.058855 -247.233621)
			(xy 39.066684 -247.252281) (xy 39.067232 -247.262396) (xy 39.067232 -247.671336) (xy 39.066809 -247.681488)
			(xy 39.059007 -247.700235) (xy 39.044612 -247.714556) (xy 39.025825 -247.722261) (xy 39.01567 -247.722644)
			(xy 37.61613 -247.722644) (xy 37.606003 -247.722149) (xy 37.58728 -247.714428) (xy 37.572922 -247.700144)
			(xy 37.565104 -247.68146) (xy 37.564568 -247.671336) (xy 36.267632 -247.671336) (xy 36.255621 -247.688953)
			(xy 36.219369 -247.728024) (xy 36.177698 -247.761255) (xy 36.13154 -247.787904) (xy 36.081926 -247.807376)
			(xy 36.029964 -247.819236) (xy 35.976814 -247.82322) (xy 35.923664 -247.819236) (xy 35.871702 -247.807376)
			(xy 35.822088 -247.787904) (xy 35.77593 -247.761255) (xy 35.734259 -247.728024) (xy 35.698007 -247.688953)
			(xy 35.667983 -247.644916) (xy 35.644857 -247.596895) (xy 35.629147 -247.545965) (xy 35.621204 -247.493261)
			(xy 34.122624 -247.493261) (xy 34.114681 -247.545965) (xy 34.098971 -247.596895) (xy 34.075845 -247.644916)
			(xy 34.045821 -247.688953) (xy 34.009569 -247.728024) (xy 33.967898 -247.761255) (xy 33.92174 -247.787904)
			(xy 33.872126 -247.807376) (xy 33.820164 -247.819236) (xy 33.767014 -247.82322) (xy 33.713864 -247.819236)
			(xy 33.661902 -247.807376) (xy 33.612288 -247.787904) (xy 33.56613 -247.761255) (xy 33.524459 -247.728024)
			(xy 33.488207 -247.688953) (xy 33.458183 -247.644916) (xy 33.435057 -247.596895) (xy 33.419347 -247.545965)
			(xy 33.411404 -247.493261) (xy 32.391858 -247.493261) (xy 32.391858 -248.521474) (xy 34.120836 -248.521474)
			(xy 34.120836 -248.112534) (xy 34.121292 -248.102365) (xy 34.129065 -248.083571) (xy 34.143441 -248.069185)
			(xy 34.162229 -248.061399) (xy 34.172398 -248.060972) (xy 35.571938 -248.060972) (xy 35.579809 -248.061278)
			(xy 35.594808 -248.066062) (xy 35.601402 -248.07037) (xy 35.613166 -248.077952) (xy 35.639601 -248.087097)
			(xy 35.667527 -248.088737) (xy 35.694851 -248.082747) (xy 35.71953 -248.069577) (xy 35.729926 -248.06021)
			(xy 35.749929 -248.041625) (xy 35.794577 -248.010197) (xy 35.843502 -247.985958) (xy 35.895554 -247.969476)
			(xy 35.949514 -247.961138) (xy 35.976814 -247.960642) (xy 36.003466 -247.961041) (xy 36.056175 -247.968987)
			(xy 36.107112 -247.984701) (xy 36.155137 -248.00783) (xy 36.199179 -248.037859) (xy 36.238253 -248.074116)
			(xy 36.271487 -248.115792) (xy 36.298139 -248.161956) (xy 36.317613 -248.211576) (xy 36.329474 -248.263544)
			(xy 36.333458 -248.3167) (xy 36.331457 -248.343399) (xy 36.855136 -248.343399) (xy 36.855136 -248.290101)
			(xy 36.863079 -248.237397) (xy 36.878789 -248.186467) (xy 36.901915 -248.138446) (xy 36.931939 -248.094409)
			(xy 36.968191 -248.055338) (xy 37.009862 -248.022107) (xy 37.05602 -247.995458) (xy 37.105634 -247.975986)
			(xy 37.157596 -247.964126) (xy 37.210746 -247.960143) (xy 37.263896 -247.964126) (xy 37.315858 -247.975986)
			(xy 37.365472 -247.995458) (xy 37.41163 -248.022107) (xy 37.453301 -248.055338) (xy 37.489553 -248.094409)
			(xy 37.519577 -248.138446) (xy 37.542703 -248.186467) (xy 37.558413 -248.237397) (xy 37.566356 -248.290101)
			(xy 37.566854 -248.31675) (xy 37.566356 -248.343399) (xy 37.558413 -248.396103) (xy 37.542703 -248.447033)
			(xy 37.519577 -248.495054) (xy 37.489553 -248.539091) (xy 37.453301 -248.578162) (xy 37.41163 -248.611393)
			(xy 37.365472 -248.638042) (xy 37.315858 -248.657514) (xy 37.263896 -248.669374) (xy 37.210746 -248.673358)
			(xy 37.157596 -248.669374) (xy 37.105634 -248.657514) (xy 37.05602 -248.638042) (xy 37.009862 -248.611393)
			(xy 36.968191 -248.578162) (xy 36.931939 -248.539091) (xy 36.901915 -248.495054) (xy 36.878789 -248.447033)
			(xy 36.863079 -248.396103) (xy 36.855136 -248.343399) (xy 36.331457 -248.343399) (xy 36.329474 -248.369856)
			(xy 36.317613 -248.421824) (xy 36.298139 -248.471444) (xy 36.271487 -248.517608) (xy 36.238253 -248.559284)
			(xy 36.199179 -248.595541) (xy 36.155137 -248.62557) (xy 36.107112 -248.648699) (xy 36.056175 -248.664413)
			(xy 36.003466 -248.672359) (xy 35.976814 -248.672858) (xy 35.94955 -248.672368) (xy 35.895661 -248.66405)
			(xy 35.843672 -248.647607) (xy 35.794801 -248.623424) (xy 35.750192 -248.592067) (xy 35.73018 -248.573544)
			(xy 35.719774 -248.564125) (xy 35.695027 -248.550902) (xy 35.667614 -248.544924) (xy 35.639608 -248.546643)
			(xy 35.613132 -248.555929) (xy 35.601402 -248.563638) (xy 35.594794 -248.56792) (xy 35.579804 -248.572711)
			(xy 35.571938 -248.573036) (xy 34.172398 -248.573036) (xy 34.162223 -248.572637) (xy 34.143423 -248.564847)
			(xy 34.129038 -248.550453) (xy 34.121257 -248.531649) (xy 34.120836 -248.521474) (xy 32.391858 -248.521474)
			(xy 32.391858 -249.193283) (xy 33.411404 -249.193283) (xy 33.411404 -249.139985) (xy 33.419347 -249.087281)
			(xy 33.435057 -249.036351) (xy 33.458183 -248.98833) (xy 33.488207 -248.944293) (xy 33.524459 -248.905222)
			(xy 33.56613 -248.871991) (xy 33.612288 -248.845342) (xy 33.661902 -248.82587) (xy 33.713864 -248.81401)
			(xy 33.767014 -248.810027) (xy 33.820164 -248.81401) (xy 33.872126 -248.82587) (xy 33.92174 -248.845342)
			(xy 33.967898 -248.871991) (xy 34.009569 -248.905222) (xy 34.045821 -248.944293) (xy 34.075845 -248.98833)
			(xy 34.098971 -249.036351) (xy 34.114681 -249.087281) (xy 34.122624 -249.139985) (xy 34.123122 -249.166634)
			(xy 34.122624 -249.193283) (xy 35.621204 -249.193283) (xy 35.621204 -249.139985) (xy 35.629147 -249.087281)
			(xy 35.644857 -249.036351) (xy 35.667983 -248.98833) (xy 35.698007 -248.944293) (xy 35.734259 -248.905222)
			(xy 35.77593 -248.871991) (xy 35.822088 -248.845342) (xy 35.871702 -248.82587) (xy 35.923664 -248.81401)
			(xy 35.976814 -248.810027) (xy 36.029964 -248.81401) (xy 36.081926 -248.82587) (xy 36.13154 -248.845342)
			(xy 36.177698 -248.871991) (xy 36.219369 -248.905222) (xy 36.255621 -248.944293) (xy 36.285645 -248.98833)
			(xy 36.308771 -249.036351) (xy 36.324481 -249.087281) (xy 36.332424 -249.139985) (xy 36.332922 -249.166634)
			(xy 36.332424 -249.193283) (xy 36.324481 -249.245987) (xy 36.308771 -249.296917) (xy 36.285645 -249.344938)
			(xy 36.267632 -249.371358) (xy 37.564568 -249.371358) (xy 37.564568 -248.962418) (xy 37.564979 -248.952244)
			(xy 37.572764 -248.933444) (xy 37.587154 -248.919057) (xy 37.605956 -248.911277) (xy 37.61613 -248.910856)
			(xy 39.01567 -248.910856) (xy 39.025842 -248.911289) (xy 39.044639 -248.919067) (xy 39.059026 -248.933451)
			(xy 39.066809 -248.952246) (xy 39.067232 -248.962418) (xy 39.067232 -249.371358) (xy 39.066801 -249.381531)
			(xy 39.059024 -249.40033) (xy 39.04464 -249.414718) (xy 39.025843 -249.422499) (xy 39.01567 -249.42292)
			(xy 37.61613 -249.42292) (xy 37.605955 -249.42251) (xy 37.587153 -249.414728) (xy 37.572766 -249.400337)
			(xy 37.564987 -249.381533) (xy 37.564568 -249.371358) (xy 36.267632 -249.371358) (xy 36.255621 -249.388975)
			(xy 36.219369 -249.428046) (xy 36.177698 -249.461277) (xy 36.13154 -249.487926) (xy 36.081926 -249.507398)
			(xy 36.029964 -249.519258) (xy 35.976814 -249.523242) (xy 35.923664 -249.519258) (xy 35.871702 -249.507398)
			(xy 35.822088 -249.487926) (xy 35.77593 -249.461277) (xy 35.734259 -249.428046) (xy 35.698007 -249.388975)
			(xy 35.667983 -249.344938) (xy 35.644857 -249.296917) (xy 35.629147 -249.245987) (xy 35.621204 -249.193283)
			(xy 34.122624 -249.193283) (xy 34.114681 -249.245987) (xy 34.098971 -249.296917) (xy 34.075845 -249.344938)
			(xy 34.045821 -249.388975) (xy 34.009569 -249.428046) (xy 33.967898 -249.461277) (xy 33.92174 -249.487926)
			(xy 33.872126 -249.507398) (xy 33.820164 -249.519258) (xy 33.767014 -249.523242) (xy 33.713864 -249.519258)
			(xy 33.661902 -249.507398) (xy 33.612288 -249.487926) (xy 33.56613 -249.461277) (xy 33.524459 -249.428046)
			(xy 33.488207 -249.388975) (xy 33.458183 -249.344938) (xy 33.435057 -249.296917) (xy 33.419347 -249.245987)
			(xy 33.411404 -249.193283) (xy 32.391858 -249.193283) (xy 32.391858 -250.221496) (xy 34.120836 -250.221496)
			(xy 34.120836 -249.812556) (xy 34.121186 -249.802394) (xy 34.129003 -249.783634) (xy 34.143422 -249.769311)
			(xy 34.162234 -249.76162) (xy 34.172398 -249.761248) (xy 35.571938 -249.761248) (xy 35.579791 -249.761489)
			(xy 35.594789 -249.76615) (xy 35.601402 -249.770392) (xy 35.613167 -249.77797) (xy 35.639603 -249.787114)
			(xy 35.667526 -249.788753) (xy 35.69485 -249.782764) (xy 35.719529 -249.769597) (xy 35.729926 -249.760232)
			(xy 35.749917 -249.741633) (xy 35.79457 -249.71021) (xy 35.843497 -249.685975) (xy 35.895552 -249.669496)
			(xy 35.949513 -249.661159) (xy 35.976814 -249.660664) (xy 36.00346 -249.661219) (xy 36.056158 -249.669164)
			(xy 36.107083 -249.684874) (xy 36.155098 -249.707998) (xy 36.19913 -249.73802) (xy 36.238195 -249.77427)
			(xy 36.271422 -249.815936) (xy 36.298068 -249.86209) (xy 36.317538 -249.911699) (xy 36.329397 -249.963656)
			(xy 36.333379 -250.0168) (xy 36.331384 -250.043421) (xy 36.855136 -250.043421) (xy 36.855136 -249.990123)
			(xy 36.863079 -249.937419) (xy 36.878789 -249.886489) (xy 36.901915 -249.838468) (xy 36.931939 -249.794431)
			(xy 36.968191 -249.75536) (xy 37.009862 -249.722129) (xy 37.05602 -249.69548) (xy 37.105634 -249.676008)
			(xy 37.157596 -249.664148) (xy 37.210746 -249.660165) (xy 37.263896 -249.664148) (xy 37.315858 -249.676008)
			(xy 37.365472 -249.69548) (xy 37.41163 -249.722129) (xy 37.453301 -249.75536) (xy 37.489553 -249.794431)
			(xy 37.519577 -249.838468) (xy 37.542703 -249.886489) (xy 37.558413 -249.937419) (xy 37.566356 -249.990123)
			(xy 37.566854 -250.016772) (xy 37.566356 -250.043421) (xy 37.558413 -250.096125) (xy 37.542703 -250.147055)
			(xy 37.519577 -250.195076) (xy 37.489553 -250.239113) (xy 37.453301 -250.278184) (xy 37.41163 -250.311415)
			(xy 37.365472 -250.338064) (xy 37.315858 -250.357536) (xy 37.263896 -250.369396) (xy 37.210746 -250.37338)
			(xy 37.157596 -250.369396) (xy 37.105634 -250.357536) (xy 37.05602 -250.338064) (xy 37.009862 -250.311415)
			(xy 36.968191 -250.278184) (xy 36.931939 -250.239113) (xy 36.901915 -250.195076) (xy 36.878789 -250.147055)
			(xy 36.863079 -250.096125) (xy 36.855136 -250.043421) (xy 36.331384 -250.043421) (xy 36.329397 -250.069944)
			(xy 36.317538 -250.121901) (xy 36.298068 -250.17151) (xy 36.271422 -250.217664) (xy 36.238195 -250.25933)
			(xy 36.19913 -250.29558) (xy 36.155098 -250.325602) (xy 36.107083 -250.348726) (xy 36.056158 -250.364436)
			(xy 36.00346 -250.372381) (xy 35.976814 -250.37288) (xy 35.949551 -250.372384) (xy 35.895662 -250.364066)
			(xy 35.843674 -250.347624) (xy 35.794802 -250.323443) (xy 35.750193 -250.292088) (xy 35.73018 -250.273566)
			(xy 35.719774 -250.264147) (xy 35.695028 -250.250921) (xy 35.667614 -250.244942) (xy 35.639608 -250.246661)
			(xy 35.613131 -250.25595) (xy 35.601402 -250.26366) (xy 35.594786 -250.267898) (xy 35.579791 -250.27256)
			(xy 35.571938 -250.272804) (xy 34.172398 -250.272804) (xy 34.162277 -250.272276) (xy 34.143564 -250.264556)
			(xy 34.129209 -250.250283) (xy 34.121382 -250.231614) (xy 34.120836 -250.221496) (xy 32.391858 -250.221496)
			(xy 32.391858 -250.893305) (xy 33.411404 -250.893305) (xy 33.411404 -250.840007) (xy 33.419347 -250.787303)
			(xy 33.435057 -250.736373) (xy 33.458183 -250.688352) (xy 33.488207 -250.644315) (xy 33.524459 -250.605244)
			(xy 33.56613 -250.572013) (xy 33.612288 -250.545364) (xy 33.661902 -250.525892) (xy 33.713864 -250.514032)
			(xy 33.767014 -250.510049) (xy 33.820164 -250.514032) (xy 33.872126 -250.525892) (xy 33.92174 -250.545364)
			(xy 33.967898 -250.572013) (xy 34.009569 -250.605244) (xy 34.045821 -250.644315) (xy 34.075845 -250.688352)
			(xy 34.098971 -250.736373) (xy 34.114681 -250.787303) (xy 34.122624 -250.840007) (xy 34.123122 -250.866656)
			(xy 34.122624 -250.893305) (xy 35.621204 -250.893305) (xy 35.621204 -250.840007) (xy 35.629147 -250.787303)
			(xy 35.644857 -250.736373) (xy 35.667983 -250.688352) (xy 35.698007 -250.644315) (xy 35.734259 -250.605244)
			(xy 35.77593 -250.572013) (xy 35.822088 -250.545364) (xy 35.871702 -250.525892) (xy 35.923664 -250.514032)
			(xy 35.976814 -250.510049) (xy 36.029964 -250.514032) (xy 36.081926 -250.525892) (xy 36.13154 -250.545364)
			(xy 36.177698 -250.572013) (xy 36.219369 -250.605244) (xy 36.255621 -250.644315) (xy 36.285645 -250.688352)
			(xy 36.308771 -250.736373) (xy 36.324481 -250.787303) (xy 36.332424 -250.840007) (xy 36.332922 -250.866656)
			(xy 36.332424 -250.893305) (xy 36.324481 -250.946009) (xy 36.308771 -250.996939) (xy 36.285645 -251.04496)
			(xy 36.267632 -251.07138) (xy 37.564568 -251.07138) (xy 37.564568 -250.66244) (xy 37.565054 -250.652292)
			(xy 37.57283 -250.633547) (xy 37.587207 -250.619224) (xy 37.605981 -250.611517) (xy 37.61613 -250.611132)
			(xy 39.01567 -250.611132) (xy 39.025794 -250.611651) (xy 39.044513 -250.619367) (xy 39.05887 -250.633644)
			(xy 39.066692 -250.652319) (xy 39.067232 -250.66244) (xy 39.067232 -251.07138) (xy 39.066763 -251.081529)
			(xy 39.05898 -251.100275) (xy 39.044598 -251.114598) (xy 39.02582 -251.122304) (xy 39.01567 -251.122688)
			(xy 37.61613 -251.122688) (xy 37.606009 -251.12215) (xy 37.587293 -251.114437) (xy 37.572937 -251.100167)
			(xy 37.565112 -251.081498) (xy 37.564568 -251.07138) (xy 36.267632 -251.07138) (xy 36.255621 -251.088997)
			(xy 36.219369 -251.128068) (xy 36.177698 -251.161299) (xy 36.13154 -251.187948) (xy 36.081926 -251.20742)
			(xy 36.029964 -251.21928) (xy 35.976814 -251.223264) (xy 35.923664 -251.21928) (xy 35.871702 -251.20742)
			(xy 35.822088 -251.187948) (xy 35.77593 -251.161299) (xy 35.734259 -251.128068) (xy 35.698007 -251.088997)
			(xy 35.667983 -251.04496) (xy 35.644857 -250.996939) (xy 35.629147 -250.946009) (xy 35.621204 -250.893305)
			(xy 34.122624 -250.893305) (xy 34.114681 -250.946009) (xy 34.098971 -250.996939) (xy 34.075845 -251.04496)
			(xy 34.045821 -251.088997) (xy 34.009569 -251.128068) (xy 33.967898 -251.161299) (xy 33.92174 -251.187948)
			(xy 33.872126 -251.20742) (xy 33.820164 -251.21928) (xy 33.767014 -251.223264) (xy 33.713864 -251.21928)
			(xy 33.661902 -251.20742) (xy 33.612288 -251.187948) (xy 33.56613 -251.161299) (xy 33.524459 -251.128068)
			(xy 33.488207 -251.088997) (xy 33.458183 -251.04496) (xy 33.435057 -250.996939) (xy 33.419347 -250.946009)
			(xy 33.411404 -250.893305) (xy 32.391858 -250.893305) (xy 32.391858 -251.921518) (xy 34.120836 -251.921518)
			(xy 34.120836 -251.512578) (xy 34.121315 -251.502419) (xy 34.129096 -251.48365) (xy 34.143467 -251.469285)
			(xy 34.162239 -251.461511) (xy 34.172398 -251.461016) (xy 35.571938 -251.461016) (xy 35.579808 -251.461332)
			(xy 35.594806 -251.46611) (xy 35.601402 -251.470414) (xy 35.613162 -251.478004) (xy 35.639599 -251.487156)
			(xy 35.667527 -251.488796) (xy 35.694854 -251.482803) (xy 35.719532 -251.469625) (xy 35.729926 -251.460254)
			(xy 35.74992 -251.441659) (xy 35.794572 -251.410235) (xy 35.843499 -251.385998) (xy 35.895553 -251.369518)
			(xy 35.949514 -251.361181) (xy 35.976814 -251.360686) (xy 36.003462 -251.361197) (xy 36.056163 -251.369142)
			(xy 36.107091 -251.384853) (xy 36.155109 -251.407979) (xy 36.199144 -251.438003) (xy 36.238212 -251.474254)
			(xy 36.271441 -251.515924) (xy 36.298089 -251.56208) (xy 36.317559 -251.611692) (xy 36.329419 -251.663653)
			(xy 36.333402 -251.7168) (xy 36.331405 -251.743443) (xy 36.855136 -251.743443) (xy 36.855136 -251.690145)
			(xy 36.863079 -251.637441) (xy 36.878789 -251.586511) (xy 36.901915 -251.53849) (xy 36.931939 -251.494453)
			(xy 36.968191 -251.455382) (xy 37.009862 -251.422151) (xy 37.05602 -251.395502) (xy 37.105634 -251.37603)
			(xy 37.157596 -251.36417) (xy 37.210746 -251.360187) (xy 37.263896 -251.36417) (xy 37.315858 -251.37603)
			(xy 37.365472 -251.395502) (xy 37.41163 -251.422151) (xy 37.453301 -251.455382) (xy 37.489553 -251.494453)
			(xy 37.519577 -251.53849) (xy 37.542703 -251.586511) (xy 37.558413 -251.637441) (xy 37.566356 -251.690145)
			(xy 37.566854 -251.716794) (xy 37.566356 -251.743443) (xy 37.558413 -251.796147) (xy 37.542703 -251.847077)
			(xy 37.519577 -251.895098) (xy 37.489553 -251.939135) (xy 37.453301 -251.978206) (xy 37.41163 -252.011437)
			(xy 37.365472 -252.038086) (xy 37.315858 -252.057558) (xy 37.263896 -252.069418) (xy 37.210746 -252.073402)
			(xy 37.157596 -252.069418) (xy 37.105634 -252.057558) (xy 37.05602 -252.038086) (xy 37.009862 -252.011437)
			(xy 36.968191 -251.978206) (xy 36.931939 -251.939135) (xy 36.901915 -251.895098) (xy 36.878789 -251.847077)
			(xy 36.863079 -251.796147) (xy 36.855136 -251.743443) (xy 36.331405 -251.743443) (xy 36.329419 -251.769947)
			(xy 36.317559 -251.821908) (xy 36.298089 -251.87152) (xy 36.271441 -251.917676) (xy 36.238212 -251.959346)
			(xy 36.199144 -251.995597) (xy 36.155109 -252.025621) (xy 36.107091 -252.048747) (xy 36.056163 -252.064458)
			(xy 36.003462 -252.072403) (xy 35.976814 -252.072902) (xy 35.949551 -252.0724) (xy 35.895663 -252.064083)
			(xy 35.843675 -252.047642) (xy 35.794803 -252.023462) (xy 35.750193 -251.992109) (xy 35.73018 -251.973588)
			(xy 35.719773 -251.964168) (xy 35.695028 -251.95094) (xy 35.667614 -251.94496) (xy 35.639607 -251.94668)
			(xy 35.613131 -251.95597) (xy 35.601402 -251.963682) (xy 35.594791 -251.967958) (xy 35.579804 -251.972754)
			(xy 35.571938 -251.97308) (xy 34.172398 -251.97308) (xy 34.162242 -251.972569) (xy 34.143477 -251.964797)
			(xy 34.129112 -251.950437) (xy 34.121335 -251.931674) (xy 34.120836 -251.921518) (xy 32.391858 -251.921518)
			(xy 32.391858 -252.593327) (xy 35.621204 -252.593327) (xy 35.621204 -252.540029) (xy 35.629147 -252.487325)
			(xy 35.644857 -252.436395) (xy 35.667983 -252.388374) (xy 35.698007 -252.344337) (xy 35.734259 -252.305266)
			(xy 35.77593 -252.272035) (xy 35.822088 -252.245386) (xy 35.871702 -252.225914) (xy 35.923664 -252.214054)
			(xy 35.976814 -252.210071) (xy 36.029964 -252.214054) (xy 36.081926 -252.225914) (xy 36.13154 -252.245386)
			(xy 36.177698 -252.272035) (xy 36.219369 -252.305266) (xy 36.255621 -252.344337) (xy 36.285645 -252.388374)
			(xy 36.308771 -252.436395) (xy 36.324481 -252.487325) (xy 36.332424 -252.540029) (xy 36.332922 -252.566678)
			(xy 36.332424 -252.593327) (xy 36.324481 -252.646031) (xy 36.308771 -252.696961) (xy 36.285645 -252.744982)
			(xy 36.267632 -252.771402) (xy 37.564568 -252.771402) (xy 37.564568 -252.362462) (xy 37.565003 -252.352298)
			(xy 37.572796 -252.333522) (xy 37.587179 -252.319157) (xy 37.605965 -252.31139) (xy 37.61613 -252.3109)
			(xy 39.01567 -252.3109) (xy 39.025821 -252.311457) (xy 39.044583 -252.319214) (xy 39.058948 -252.33356)
			(xy 39.06673 -252.352311) (xy 39.067232 -252.362462) (xy 39.067232 -252.771402) (xy 39.066837 -252.781577)
			(xy 39.059046 -252.800378) (xy 39.044651 -252.814764) (xy 39.025846 -252.822543) (xy 39.01567 -252.822964)
			(xy 37.61613 -252.822964) (xy 37.605961 -252.822511) (xy 37.587167 -252.814737) (xy 37.572781 -252.80036)
			(xy 37.564995 -252.781571) (xy 37.564568 -252.771402) (xy 36.267632 -252.771402) (xy 36.255621 -252.789019)
			(xy 36.219369 -252.82809) (xy 36.177698 -252.861321) (xy 36.13154 -252.88797) (xy 36.081926 -252.907442)
			(xy 36.029964 -252.919302) (xy 35.976814 -252.923286) (xy 35.923664 -252.919302) (xy 35.871702 -252.907442)
			(xy 35.822088 -252.88797) (xy 35.77593 -252.861321) (xy 35.734259 -252.82809) (xy 35.698007 -252.789019)
			(xy 35.667983 -252.744982) (xy 35.644857 -252.696961) (xy 35.629147 -252.646031) (xy 35.621204 -252.593327)
			(xy 32.391858 -252.593327) (xy 32.391858 -253.302008) (xy 33.44418 -253.302008) (xy 33.486444 -253.302496)
			(xy 33.570612 -253.310295) (xy 33.653702 -253.325827) (xy 33.735004 -253.34896) (xy 33.813824 -253.379495)
			(xy 33.889491 -253.417173) (xy 33.961359 -253.461671) (xy 34.028815 -253.512611) (xy 34.091282 -253.569558)
			(xy 34.148229 -253.632025) (xy 34.199169 -253.699481) (xy 34.243667 -253.771349) (xy 34.281345 -253.847016)
			(xy 34.31188 -253.925836) (xy 34.335013 -254.007138) (xy 34.350545 -254.090228) (xy 34.358344 -254.174396)
			(xy 34.358344 -254.258924) (xy 34.350545 -254.343092) (xy 34.335013 -254.426182) (xy 34.31188 -254.507484)
			(xy 34.281345 -254.586304) (xy 34.243667 -254.661971) (xy 34.199169 -254.733839) (xy 34.148229 -254.801295)
			(xy 34.091282 -254.863762) (xy 34.028815 -254.920709) (xy 33.961359 -254.971649) (xy 33.889491 -255.016147)
			(xy 33.813824 -255.053825) (xy 33.735004 -255.08436) (xy 33.653702 -255.107493) (xy 33.570612 -255.123025)
			(xy 33.486444 -255.130824) (xy 33.44418 -255.131316) (xy 32.391858 -255.131316) (xy 32.391858 -258.543277)
			(xy 33.411404 -258.543277) (xy 33.411404 -258.489979) (xy 33.419347 -258.437275) (xy 33.435057 -258.386345)
			(xy 33.458183 -258.338324) (xy 33.488207 -258.294287) (xy 33.524459 -258.255216) (xy 33.56613 -258.221985)
			(xy 33.612288 -258.195336) (xy 33.661902 -258.175864) (xy 33.713864 -258.164004) (xy 33.767014 -258.160021)
			(xy 33.820164 -258.164004) (xy 33.872126 -258.175864) (xy 33.92174 -258.195336) (xy 33.967898 -258.221985)
			(xy 34.009569 -258.255216) (xy 34.045821 -258.294287) (xy 34.075845 -258.338324) (xy 34.098971 -258.386345)
			(xy 34.114681 -258.437275) (xy 34.122624 -258.489979) (xy 34.123122 -258.516628) (xy 34.122624 -258.543277)
			(xy 35.621204 -258.543277) (xy 35.621204 -258.489979) (xy 35.629147 -258.437275) (xy 35.644857 -258.386345)
			(xy 35.667983 -258.338324) (xy 35.698007 -258.294287) (xy 35.734259 -258.255216) (xy 35.77593 -258.221985)
			(xy 35.822088 -258.195336) (xy 35.871702 -258.175864) (xy 35.923664 -258.164004) (xy 35.976814 -258.160021)
			(xy 36.029964 -258.164004) (xy 36.081926 -258.175864) (xy 36.13154 -258.195336) (xy 36.177698 -258.221985)
			(xy 36.219369 -258.255216) (xy 36.255621 -258.294287) (xy 36.285645 -258.338324) (xy 36.308771 -258.386345)
			(xy 36.324481 -258.437275) (xy 36.332424 -258.489979) (xy 36.332922 -258.516628) (xy 36.332424 -258.543277)
			(xy 36.855136 -258.543277) (xy 36.855136 -258.489979) (xy 36.863079 -258.437275) (xy 36.878789 -258.386345)
			(xy 36.901915 -258.338324) (xy 36.931939 -258.294287) (xy 36.968191 -258.255216) (xy 37.009862 -258.221985)
			(xy 37.05602 -258.195336) (xy 37.105634 -258.175864) (xy 37.157596 -258.164004) (xy 37.210746 -258.160021)
			(xy 37.263896 -258.164004) (xy 37.315858 -258.175864) (xy 37.365472 -258.195336) (xy 37.41163 -258.221985)
			(xy 37.453301 -258.255216) (xy 37.489553 -258.294287) (xy 37.519577 -258.338324) (xy 37.542703 -258.386345)
			(xy 37.558413 -258.437275) (xy 37.566356 -258.489979) (xy 37.566854 -258.516628) (xy 37.566356 -258.543277)
			(xy 37.558413 -258.595981) (xy 37.542703 -258.646911) (xy 37.519577 -258.694932) (xy 37.489553 -258.738969)
			(xy 37.453301 -258.77804) (xy 37.41163 -258.811271) (xy 37.365472 -258.83792) (xy 37.315858 -258.857392)
			(xy 37.263896 -258.869252) (xy 37.210746 -258.873236) (xy 37.157596 -258.869252) (xy 37.105634 -258.857392)
			(xy 37.05602 -258.83792) (xy 37.009862 -258.811271) (xy 36.968191 -258.77804) (xy 36.931939 -258.738969)
			(xy 36.901915 -258.694932) (xy 36.878789 -258.646911) (xy 36.863079 -258.595981) (xy 36.855136 -258.543277)
			(xy 36.332424 -258.543277) (xy 36.324481 -258.595981) (xy 36.308771 -258.646911) (xy 36.285645 -258.694932)
			(xy 36.255621 -258.738969) (xy 36.219369 -258.77804) (xy 36.177698 -258.811271) (xy 36.13154 -258.83792)
			(xy 36.081926 -258.857392) (xy 36.029964 -258.869252) (xy 35.976814 -258.873236) (xy 35.923664 -258.869252)
			(xy 35.871702 -258.857392) (xy 35.822088 -258.83792) (xy 35.77593 -258.811271) (xy 35.734259 -258.77804)
			(xy 35.698007 -258.738969) (xy 35.667983 -258.694932) (xy 35.644857 -258.646911) (xy 35.629147 -258.595981)
			(xy 35.621204 -258.543277) (xy 34.122624 -258.543277) (xy 34.114681 -258.595981) (xy 34.098971 -258.646911)
			(xy 34.075845 -258.694932) (xy 34.045821 -258.738969) (xy 34.009569 -258.77804) (xy 33.967898 -258.811271)
			(xy 33.92174 -258.83792) (xy 33.872126 -258.857392) (xy 33.820164 -258.869252) (xy 33.767014 -258.873236)
			(xy 33.713864 -258.869252) (xy 33.661902 -258.857392) (xy 33.612288 -258.83792) (xy 33.56613 -258.811271)
			(xy 33.524459 -258.77804) (xy 33.488207 -258.738969) (xy 33.458183 -258.694932) (xy 33.435057 -258.646911)
			(xy 33.419347 -258.595981) (xy 33.411404 -258.543277) (xy 32.391858 -258.543277) (xy 32.391858 -259.57149)
			(xy 34.120836 -259.57149) (xy 34.120836 -259.16255) (xy 34.121305 -259.152382) (xy 34.129073 -259.133589)
			(xy 34.143445 -259.119202) (xy 34.16223 -259.111415) (xy 34.172398 -259.110988) (xy 35.571938 -259.110988)
			(xy 35.579809 -259.111292) (xy 35.594808 -259.116076) (xy 35.601402 -259.120386) (xy 35.613167 -259.127965)
			(xy 35.639602 -259.137109) (xy 35.667526 -259.138748) (xy 35.69485 -259.13276) (xy 35.719529 -259.119591)
			(xy 35.729926 -259.110226) (xy 35.749916 -259.091626) (xy 35.794569 -259.060204) (xy 35.843497 -259.035968)
			(xy 35.895552 -259.019489) (xy 35.949513 -259.011153) (xy 35.976814 -259.010658) (xy 36.00346 -259.011225)
			(xy 36.056157 -259.01917) (xy 36.107081 -259.034879) (xy 36.155095 -259.058003) (xy 36.199126 -259.088025)
			(xy 36.238191 -259.124274) (xy 36.271417 -259.16594) (xy 36.298063 -259.212092) (xy 36.317532 -259.261701)
			(xy 36.329391 -259.313657) (xy 36.333373 -259.3668) (xy 36.329391 -259.419943) (xy 36.317532 -259.471899)
			(xy 36.298063 -259.521508) (xy 36.271417 -259.56766) (xy 36.268363 -259.57149) (xy 37.564568 -259.57149)
			(xy 37.564568 -259.16255) (xy 37.565005 -259.152378) (xy 37.57278 -259.133579) (xy 37.587162 -259.119191)
			(xy 37.605958 -259.111409) (xy 37.61613 -259.110988) (xy 39.01567 -259.110988) (xy 39.025846 -259.11139)
			(xy 39.044649 -259.119174) (xy 39.059037 -259.133567) (xy 39.066814 -259.152374) (xy 39.067232 -259.16255)
			(xy 39.067232 -259.57149) (xy 39.066827 -259.581665) (xy 39.05904 -259.600465) (xy 39.044648 -259.614851)
			(xy 39.025845 -259.622631) (xy 39.01567 -259.623052) (xy 37.61613 -259.623052) (xy 37.605959 -259.622611)
			(xy 37.587163 -259.614834) (xy 37.572777 -259.600454) (xy 37.564993 -259.581661) (xy 37.564568 -259.57149)
			(xy 36.268363 -259.57149) (xy 36.238191 -259.609326) (xy 36.199126 -259.645575) (xy 36.155095 -259.675597)
			(xy 36.107081 -259.698721) (xy 36.056157 -259.71443) (xy 36.00346 -259.722375) (xy 35.976814 -259.722874)
			(xy 35.949551 -259.722379) (xy 35.895662 -259.714062) (xy 35.843673 -259.69762) (xy 35.794802 -259.673438)
			(xy 35.750193 -259.642082) (xy 35.73018 -259.62356) (xy 35.719774 -259.614141) (xy 35.695028 -259.600916)
			(xy 35.667614 -259.594937) (xy 35.639608 -259.596656) (xy 35.613131 -259.605944) (xy 35.601402 -259.613654)
			(xy 35.594789 -259.617928) (xy 35.579804 -259.622725) (xy 35.571938 -259.623052) (xy 34.172398 -259.623052)
			(xy 34.162225 -259.622638) (xy 34.143428 -259.61485) (xy 34.129043 -259.600462) (xy 34.12126 -259.581663)
			(xy 34.120836 -259.57149) (xy 32.391858 -259.57149) (xy 32.391858 -260.421374) (xy 34.120836 -260.421374)
			(xy 34.120836 -260.012434) (xy 34.121292 -260.002265) (xy 34.129065 -259.983471) (xy 34.143441 -259.969085)
			(xy 34.162229 -259.961299) (xy 34.172398 -259.960872) (xy 35.571938 -259.960872) (xy 35.579809 -259.961178)
			(xy 35.594808 -259.965962) (xy 35.601402 -259.97027) (xy 35.613166 -259.977852) (xy 35.639601 -259.986997)
			(xy 35.667527 -259.988637) (xy 35.694851 -259.982647) (xy 35.71953 -259.969477) (xy 35.729926 -259.96011)
			(xy 35.749929 -259.941525) (xy 35.794577 -259.910097) (xy 35.843502 -259.885858) (xy 35.895554 -259.869376)
			(xy 35.949514 -259.861038) (xy 35.976814 -259.860542) (xy 36.003466 -259.860941) (xy 36.056175 -259.868887)
			(xy 36.107112 -259.884601) (xy 36.155137 -259.90773) (xy 36.199179 -259.937759) (xy 36.238253 -259.974016)
			(xy 36.271487 -260.015692) (xy 36.298139 -260.061856) (xy 36.317613 -260.111476) (xy 36.329474 -260.163444)
			(xy 36.333458 -260.2166) (xy 36.331457 -260.243299) (xy 36.855136 -260.243299) (xy 36.855136 -260.190001)
			(xy 36.863079 -260.137297) (xy 36.878789 -260.086367) (xy 36.901915 -260.038346) (xy 36.931939 -259.994309)
			(xy 36.968191 -259.955238) (xy 37.009862 -259.922007) (xy 37.05602 -259.895358) (xy 37.105634 -259.875886)
			(xy 37.157596 -259.864026) (xy 37.210746 -259.860043) (xy 37.263896 -259.864026) (xy 37.315858 -259.875886)
			(xy 37.365472 -259.895358) (xy 37.41163 -259.922007) (xy 37.453301 -259.955238) (xy 37.489553 -259.994309)
			(xy 37.519577 -260.038346) (xy 37.542703 -260.086367) (xy 37.558413 -260.137297) (xy 37.566356 -260.190001)
			(xy 37.566854 -260.21665) (xy 37.566356 -260.243299) (xy 37.558413 -260.296003) (xy 37.542703 -260.346933)
			(xy 37.519577 -260.394954) (xy 37.489553 -260.438991) (xy 37.453301 -260.478062) (xy 37.41163 -260.511293)
			(xy 37.365472 -260.537942) (xy 37.315858 -260.557414) (xy 37.263896 -260.569274) (xy 37.210746 -260.573258)
			(xy 37.157596 -260.569274) (xy 37.105634 -260.557414) (xy 37.05602 -260.537942) (xy 37.009862 -260.511293)
			(xy 36.968191 -260.478062) (xy 36.931939 -260.438991) (xy 36.901915 -260.394954) (xy 36.878789 -260.346933)
			(xy 36.863079 -260.296003) (xy 36.855136 -260.243299) (xy 36.331457 -260.243299) (xy 36.329474 -260.269756)
			(xy 36.317613 -260.321724) (xy 36.298139 -260.371344) (xy 36.271487 -260.417508) (xy 36.238253 -260.459184)
			(xy 36.199179 -260.495441) (xy 36.155137 -260.52547) (xy 36.107112 -260.548599) (xy 36.056175 -260.564313)
			(xy 36.003466 -260.572259) (xy 35.976814 -260.572758) (xy 35.94955 -260.572268) (xy 35.895661 -260.56395)
			(xy 35.843672 -260.547507) (xy 35.794801 -260.523324) (xy 35.750192 -260.491967) (xy 35.73018 -260.473444)
			(xy 35.719774 -260.464025) (xy 35.695027 -260.450802) (xy 35.667614 -260.444824) (xy 35.639608 -260.446543)
			(xy 35.613132 -260.455829) (xy 35.601402 -260.463538) (xy 35.594794 -260.46782) (xy 35.579804 -260.472611)
			(xy 35.571938 -260.472936) (xy 34.172398 -260.472936) (xy 34.162223 -260.472537) (xy 34.143423 -260.464747)
			(xy 34.129038 -260.450353) (xy 34.121257 -260.431549) (xy 34.120836 -260.421374) (xy 32.391858 -260.421374)
			(xy 32.391858 -261.093437) (xy 33.411404 -261.093437) (xy 33.411404 -261.040139) (xy 33.419347 -260.987435)
			(xy 33.435057 -260.936505) (xy 33.458183 -260.888484) (xy 33.488207 -260.844447) (xy 33.524459 -260.805376)
			(xy 33.56613 -260.772145) (xy 33.612288 -260.745496) (xy 33.661902 -260.726024) (xy 33.713864 -260.714164)
			(xy 33.767014 -260.710181) (xy 33.820164 -260.714164) (xy 33.872126 -260.726024) (xy 33.92174 -260.745496)
			(xy 33.967898 -260.772145) (xy 34.009569 -260.805376) (xy 34.045821 -260.844447) (xy 34.075845 -260.888484)
			(xy 34.098971 -260.936505) (xy 34.114681 -260.987435) (xy 34.122624 -261.040139) (xy 34.123122 -261.066788)
			(xy 34.122624 -261.093437) (xy 35.621204 -261.093437) (xy 35.621204 -261.040139) (xy 35.629147 -260.987435)
			(xy 35.644857 -260.936505) (xy 35.667983 -260.888484) (xy 35.698007 -260.844447) (xy 35.734259 -260.805376)
			(xy 35.77593 -260.772145) (xy 35.822088 -260.745496) (xy 35.871702 -260.726024) (xy 35.923664 -260.714164)
			(xy 35.976814 -260.710181) (xy 36.029964 -260.714164) (xy 36.081926 -260.726024) (xy 36.13154 -260.745496)
			(xy 36.177698 -260.772145) (xy 36.219369 -260.805376) (xy 36.255621 -260.844447) (xy 36.285645 -260.888484)
			(xy 36.308771 -260.936505) (xy 36.324481 -260.987435) (xy 36.332424 -261.040139) (xy 36.332922 -261.066788)
			(xy 36.332424 -261.093437) (xy 36.324481 -261.146141) (xy 36.308771 -261.197071) (xy 36.285645 -261.245092)
			(xy 36.267632 -261.271512) (xy 37.564568 -261.271512) (xy 37.564568 -260.862572) (xy 37.564998 -260.85242)
			(xy 37.572797 -260.833673) (xy 37.58719 -260.819352) (xy 37.605976 -260.811647) (xy 37.61613 -260.811264)
			(xy 39.01567 -260.811264) (xy 39.025798 -260.811752) (xy 39.044523 -260.819474) (xy 39.058881 -260.833761)
			(xy 39.066697 -260.852447) (xy 39.067232 -260.862572) (xy 39.067232 -261.271512) (xy 39.066789 -261.281663)
			(xy 39.058996 -261.30041) (xy 39.044606 -261.314731) (xy 39.025823 -261.322436) (xy 39.01567 -261.32282)
			(xy 37.61613 -261.32282) (xy 37.606 -261.322348) (xy 37.587272 -261.314623) (xy 37.572913 -261.300331)
			(xy 37.5651 -261.281639) (xy 37.564568 -261.271512) (xy 36.267632 -261.271512) (xy 36.255621 -261.289129)
			(xy 36.219369 -261.3282) (xy 36.177698 -261.361431) (xy 36.13154 -261.38808) (xy 36.081926 -261.407552)
			(xy 36.029964 -261.419412) (xy 35.976814 -261.423396) (xy 35.923664 -261.419412) (xy 35.871702 -261.407552)
			(xy 35.822088 -261.38808) (xy 35.77593 -261.361431) (xy 35.734259 -261.3282) (xy 35.698007 -261.289129)
			(xy 35.667983 -261.245092) (xy 35.644857 -261.197071) (xy 35.629147 -261.146141) (xy 35.621204 -261.093437)
			(xy 34.122624 -261.093437) (xy 34.114681 -261.146141) (xy 34.098971 -261.197071) (xy 34.075845 -261.245092)
			(xy 34.045821 -261.289129) (xy 34.009569 -261.3282) (xy 33.967898 -261.361431) (xy 33.92174 -261.38808)
			(xy 33.872126 -261.407552) (xy 33.820164 -261.419412) (xy 33.767014 -261.423396) (xy 33.713864 -261.419412)
			(xy 33.661902 -261.407552) (xy 33.612288 -261.38808) (xy 33.56613 -261.361431) (xy 33.524459 -261.3282)
			(xy 33.488207 -261.289129) (xy 33.458183 -261.245092) (xy 33.435057 -261.197071) (xy 33.419347 -261.146141)
			(xy 33.411404 -261.093437) (xy 32.391858 -261.093437) (xy 32.391858 -262.121396) (xy 34.120836 -262.121396)
			(xy 34.120836 -261.712456) (xy 34.121186 -261.702294) (xy 34.129003 -261.683534) (xy 34.143422 -261.669211)
			(xy 34.162234 -261.66152) (xy 34.172398 -261.661148) (xy 35.571938 -261.661148) (xy 35.579791 -261.661389)
			(xy 35.594789 -261.66605) (xy 35.601402 -261.670292) (xy 35.613167 -261.67787) (xy 35.639603 -261.687014)
			(xy 35.667526 -261.688653) (xy 35.69485 -261.682664) (xy 35.719529 -261.669497) (xy 35.729926 -261.660132)
			(xy 35.749917 -261.641533) (xy 35.79457 -261.61011) (xy 35.843497 -261.585875) (xy 35.895552 -261.569396)
			(xy 35.949513 -261.561059) (xy 35.976814 -261.560564) (xy 36.00346 -261.561119) (xy 36.056158 -261.569064)
			(xy 36.107083 -261.584774) (xy 36.155098 -261.607898) (xy 36.19913 -261.63792) (xy 36.238195 -261.67417)
			(xy 36.271422 -261.715836) (xy 36.298068 -261.76199) (xy 36.317538 -261.811599) (xy 36.329397 -261.863556)
			(xy 36.333379 -261.9167) (xy 36.331384 -261.943321) (xy 36.855136 -261.943321) (xy 36.855136 -261.890023)
			(xy 36.863079 -261.837319) (xy 36.878789 -261.786389) (xy 36.901915 -261.738368) (xy 36.931939 -261.694331)
			(xy 36.968191 -261.65526) (xy 37.009862 -261.622029) (xy 37.05602 -261.59538) (xy 37.105634 -261.575908)
			(xy 37.157596 -261.564048) (xy 37.210746 -261.560065) (xy 37.263896 -261.564048) (xy 37.315858 -261.575908)
			(xy 37.365472 -261.59538) (xy 37.41163 -261.622029) (xy 37.453301 -261.65526) (xy 37.489553 -261.694331)
			(xy 37.519577 -261.738368) (xy 37.542703 -261.786389) (xy 37.558413 -261.837319) (xy 37.566356 -261.890023)
			(xy 37.566854 -261.916672) (xy 37.566356 -261.943321) (xy 37.558413 -261.996025) (xy 37.542703 -262.046955)
			(xy 37.519577 -262.094976) (xy 37.489553 -262.139013) (xy 37.453301 -262.178084) (xy 37.41163 -262.211315)
			(xy 37.365472 -262.237964) (xy 37.315858 -262.257436) (xy 37.263896 -262.269296) (xy 37.210746 -262.27328)
			(xy 37.157596 -262.269296) (xy 37.105634 -262.257436) (xy 37.05602 -262.237964) (xy 37.009862 -262.211315)
			(xy 36.968191 -262.178084) (xy 36.931939 -262.139013) (xy 36.901915 -262.094976) (xy 36.878789 -262.046955)
			(xy 36.863079 -261.996025) (xy 36.855136 -261.943321) (xy 36.331384 -261.943321) (xy 36.329397 -261.969844)
			(xy 36.317538 -262.021801) (xy 36.298068 -262.07141) (xy 36.271422 -262.117564) (xy 36.238195 -262.15923)
			(xy 36.19913 -262.19548) (xy 36.155098 -262.225502) (xy 36.107083 -262.248626) (xy 36.056158 -262.264336)
			(xy 36.00346 -262.272281) (xy 35.976814 -262.27278) (xy 35.949551 -262.272284) (xy 35.895662 -262.263966)
			(xy 35.843674 -262.247524) (xy 35.794802 -262.223343) (xy 35.750193 -262.191988) (xy 35.73018 -262.173466)
			(xy 35.719774 -262.164047) (xy 35.695028 -262.150821) (xy 35.667614 -262.144842) (xy 35.639608 -262.146561)
			(xy 35.613131 -262.15585) (xy 35.601402 -262.16356) (xy 35.594786 -262.167798) (xy 35.579791 -262.17246)
			(xy 35.571938 -262.172704) (xy 34.172398 -262.172704) (xy 34.162277 -262.172176) (xy 34.143564 -262.164456)
			(xy 34.129209 -262.150183) (xy 34.121382 -262.131514) (xy 34.120836 -262.121396) (xy 32.391858 -262.121396)
			(xy 32.391858 -262.793459) (xy 33.411404 -262.793459) (xy 33.411404 -262.740161) (xy 33.419347 -262.687457)
			(xy 33.435057 -262.636527) (xy 33.458183 -262.588506) (xy 33.488207 -262.544469) (xy 33.524459 -262.505398)
			(xy 33.56613 -262.472167) (xy 33.612288 -262.445518) (xy 33.661902 -262.426046) (xy 33.713864 -262.414186)
			(xy 33.767014 -262.410203) (xy 33.820164 -262.414186) (xy 33.872126 -262.426046) (xy 33.92174 -262.445518)
			(xy 33.967898 -262.472167) (xy 34.009569 -262.505398) (xy 34.045821 -262.544469) (xy 34.075845 -262.588506)
			(xy 34.098971 -262.636527) (xy 34.114681 -262.687457) (xy 34.122624 -262.740161) (xy 34.123122 -262.76681)
			(xy 34.122624 -262.793459) (xy 35.621204 -262.793459) (xy 35.621204 -262.740161) (xy 35.629147 -262.687457)
			(xy 35.644857 -262.636527) (xy 35.667983 -262.588506) (xy 35.698007 -262.544469) (xy 35.734259 -262.505398)
			(xy 35.77593 -262.472167) (xy 35.822088 -262.445518) (xy 35.871702 -262.426046) (xy 35.923664 -262.414186)
			(xy 35.976814 -262.410203) (xy 36.029964 -262.414186) (xy 36.081926 -262.426046) (xy 36.13154 -262.445518)
			(xy 36.177698 -262.472167) (xy 36.219369 -262.505398) (xy 36.255621 -262.544469) (xy 36.285645 -262.588506)
			(xy 36.308771 -262.636527) (xy 36.324481 -262.687457) (xy 36.332424 -262.740161) (xy 36.332922 -262.76681)
			(xy 36.332424 -262.793459) (xy 36.324481 -262.846163) (xy 36.308771 -262.897093) (xy 36.285645 -262.945114)
			(xy 36.267632 -262.971534) (xy 37.564568 -262.971534) (xy 37.564568 -262.562594) (xy 37.56496 -262.552418)
			(xy 37.572752 -262.533618) (xy 37.587148 -262.519232) (xy 37.605954 -262.511453) (xy 37.61613 -262.511032)
			(xy 39.01567 -262.511032) (xy 39.025839 -262.511488) (xy 39.044632 -262.519262) (xy 39.059017 -262.533638)
			(xy 39.066804 -262.552425) (xy 39.067232 -262.562594) (xy 39.067232 -262.971534) (xy 39.066794 -262.981698)
			(xy 39.059003 -263.000473) (xy 39.04462 -263.014838) (xy 39.025834 -263.022606) (xy 39.01567 -263.023096)
			(xy 37.61613 -263.023096) (xy 37.605978 -263.022543) (xy 37.587216 -263.014785) (xy 37.572851 -263.000437)
			(xy 37.565069 -262.981685) (xy 37.564568 -262.971534) (xy 36.267632 -262.971534) (xy 36.255621 -262.989151)
			(xy 36.219369 -263.028222) (xy 36.177698 -263.061453) (xy 36.13154 -263.088102) (xy 36.081926 -263.107574)
			(xy 36.029964 -263.119434) (xy 35.976814 -263.123418) (xy 35.923664 -263.119434) (xy 35.871702 -263.107574)
			(xy 35.822088 -263.088102) (xy 35.77593 -263.061453) (xy 35.734259 -263.028222) (xy 35.698007 -262.989151)
			(xy 35.667983 -262.945114) (xy 35.644857 -262.897093) (xy 35.629147 -262.846163) (xy 35.621204 -262.793459)
			(xy 34.122624 -262.793459) (xy 34.114681 -262.846163) (xy 34.098971 -262.897093) (xy 34.075845 -262.945114)
			(xy 34.045821 -262.989151) (xy 34.009569 -263.028222) (xy 33.967898 -263.061453) (xy 33.92174 -263.088102)
			(xy 33.872126 -263.107574) (xy 33.820164 -263.119434) (xy 33.767014 -263.123418) (xy 33.713864 -263.119434)
			(xy 33.661902 -263.107574) (xy 33.612288 -263.088102) (xy 33.56613 -263.061453) (xy 33.524459 -263.028222)
			(xy 33.488207 -262.989151) (xy 33.458183 -262.945114) (xy 33.435057 -262.897093) (xy 33.419347 -262.846163)
			(xy 33.411404 -262.793459) (xy 32.391858 -262.793459) (xy 32.391858 -263.821418) (xy 34.120836 -263.821418)
			(xy 34.120836 -263.412478) (xy 34.121315 -263.402319) (xy 34.129096 -263.38355) (xy 34.143467 -263.369185)
			(xy 34.162239 -263.361411) (xy 34.172398 -263.360916) (xy 35.571938 -263.360916) (xy 35.579808 -263.361232)
			(xy 35.594806 -263.36601) (xy 35.601402 -263.370314) (xy 35.613162 -263.377904) (xy 35.639599 -263.387056)
			(xy 35.667527 -263.388696) (xy 35.694854 -263.382703) (xy 35.719532 -263.369525) (xy 35.729926 -263.360154)
			(xy 35.74992 -263.341559) (xy 35.794572 -263.310135) (xy 35.843499 -263.285898) (xy 35.895553 -263.269418)
			(xy 35.949514 -263.261081) (xy 35.976814 -263.260586) (xy 36.003462 -263.261097) (xy 36.056163 -263.269042)
			(xy 36.107091 -263.284753) (xy 36.155109 -263.307879) (xy 36.199144 -263.337903) (xy 36.238212 -263.374154)
			(xy 36.271441 -263.415824) (xy 36.298089 -263.46198) (xy 36.317559 -263.511592) (xy 36.329419 -263.563553)
			(xy 36.333402 -263.6167) (xy 36.331405 -263.643343) (xy 36.855136 -263.643343) (xy 36.855136 -263.590045)
			(xy 36.863079 -263.537341) (xy 36.878789 -263.486411) (xy 36.901915 -263.43839) (xy 36.931939 -263.394353)
			(xy 36.968191 -263.355282) (xy 37.009862 -263.322051) (xy 37.05602 -263.295402) (xy 37.105634 -263.27593)
			(xy 37.157596 -263.26407) (xy 37.210746 -263.260087) (xy 37.263896 -263.26407) (xy 37.315858 -263.27593)
			(xy 37.365472 -263.295402) (xy 37.41163 -263.322051) (xy 37.453301 -263.355282) (xy 37.489553 -263.394353)
			(xy 37.519577 -263.43839) (xy 37.542703 -263.486411) (xy 37.558413 -263.537341) (xy 37.566356 -263.590045)
			(xy 37.566854 -263.616694) (xy 37.566356 -263.643343) (xy 37.558413 -263.696047) (xy 37.542703 -263.746977)
			(xy 37.519577 -263.794998) (xy 37.489553 -263.839035) (xy 37.453301 -263.878106) (xy 37.41163 -263.911337)
			(xy 37.365472 -263.937986) (xy 37.315858 -263.957458) (xy 37.263896 -263.969318) (xy 37.210746 -263.973302)
			(xy 37.157596 -263.969318) (xy 37.105634 -263.957458) (xy 37.05602 -263.937986) (xy 37.009862 -263.911337)
			(xy 36.968191 -263.878106) (xy 36.931939 -263.839035) (xy 36.901915 -263.794998) (xy 36.878789 -263.746977)
			(xy 36.863079 -263.696047) (xy 36.855136 -263.643343) (xy 36.331405 -263.643343) (xy 36.329419 -263.669847)
			(xy 36.317559 -263.721808) (xy 36.298089 -263.77142) (xy 36.271441 -263.817576) (xy 36.238212 -263.859246)
			(xy 36.199144 -263.895497) (xy 36.155109 -263.925521) (xy 36.107091 -263.948647) (xy 36.056163 -263.964358)
			(xy 36.003462 -263.972303) (xy 35.976814 -263.972802) (xy 35.949551 -263.9723) (xy 35.895663 -263.963983)
			(xy 35.843675 -263.947542) (xy 35.794803 -263.923362) (xy 35.750193 -263.892009) (xy 35.73018 -263.873488)
			(xy 35.719773 -263.864068) (xy 35.695028 -263.85084) (xy 35.667614 -263.84486) (xy 35.639607 -263.84658)
			(xy 35.613131 -263.85587) (xy 35.601402 -263.863582) (xy 35.594791 -263.867858) (xy 35.579804 -263.872654)
			(xy 35.571938 -263.87298) (xy 34.172398 -263.87298) (xy 34.162242 -263.872469) (xy 34.143477 -263.864697)
			(xy 34.129112 -263.850337) (xy 34.121335 -263.831574) (xy 34.120836 -263.821418) (xy 32.391858 -263.821418)
			(xy 32.391858 -264.493227) (xy 33.411404 -264.493227) (xy 33.411404 -264.439929) (xy 33.419347 -264.387225)
			(xy 33.435057 -264.336295) (xy 33.458183 -264.288274) (xy 33.488207 -264.244237) (xy 33.524459 -264.205166)
			(xy 33.56613 -264.171935) (xy 33.612288 -264.145286) (xy 33.661902 -264.125814) (xy 33.713864 -264.113954)
			(xy 33.767014 -264.109971) (xy 33.820164 -264.113954) (xy 33.872126 -264.125814) (xy 33.92174 -264.145286)
			(xy 33.967898 -264.171935) (xy 34.009569 -264.205166) (xy 34.045821 -264.244237) (xy 34.075845 -264.288274)
			(xy 34.098971 -264.336295) (xy 34.114681 -264.387225) (xy 34.122624 -264.439929) (xy 34.123122 -264.466578)
			(xy 34.122624 -264.493227) (xy 35.621204 -264.493227) (xy 35.621204 -264.439929) (xy 35.629147 -264.387225)
			(xy 35.644857 -264.336295) (xy 35.667983 -264.288274) (xy 35.698007 -264.244237) (xy 35.734259 -264.205166)
			(xy 35.77593 -264.171935) (xy 35.822088 -264.145286) (xy 35.871702 -264.125814) (xy 35.923664 -264.113954)
			(xy 35.976814 -264.109971) (xy 36.029964 -264.113954) (xy 36.081926 -264.125814) (xy 36.13154 -264.145286)
			(xy 36.177698 -264.171935) (xy 36.219369 -264.205166) (xy 36.255621 -264.244237) (xy 36.285645 -264.288274)
			(xy 36.308771 -264.336295) (xy 36.324481 -264.387225) (xy 36.332424 -264.439929) (xy 36.332922 -264.466578)
			(xy 36.332424 -264.493227) (xy 36.324481 -264.545931) (xy 36.308771 -264.596861) (xy 36.285645 -264.644882)
			(xy 36.267632 -264.671302) (xy 37.564568 -264.671302) (xy 37.564568 -264.262362) (xy 37.565003 -264.252198)
			(xy 37.572796 -264.233422) (xy 37.587179 -264.219057) (xy 37.605965 -264.21129) (xy 37.61613 -264.2108)
			(xy 39.01567 -264.2108) (xy 39.025821 -264.211357) (xy 39.044583 -264.219114) (xy 39.058948 -264.23346)
			(xy 39.06673 -264.252211) (xy 39.067232 -264.262362) (xy 39.067232 -264.671302) (xy 39.066837 -264.681477)
			(xy 39.059046 -264.700278) (xy 39.044651 -264.714664) (xy 39.025846 -264.722443) (xy 39.01567 -264.722864)
			(xy 37.61613 -264.722864) (xy 37.605961 -264.722411) (xy 37.587167 -264.714637) (xy 37.572781 -264.70026)
			(xy 37.564995 -264.681471) (xy 37.564568 -264.671302) (xy 36.267632 -264.671302) (xy 36.255621 -264.688919)
			(xy 36.219369 -264.72799) (xy 36.177698 -264.761221) (xy 36.13154 -264.78787) (xy 36.081926 -264.807342)
			(xy 36.029964 -264.819202) (xy 35.976814 -264.823186) (xy 35.923664 -264.819202) (xy 35.871702 -264.807342)
			(xy 35.822088 -264.78787) (xy 35.77593 -264.761221) (xy 35.734259 -264.72799) (xy 35.698007 -264.688919)
			(xy 35.667983 -264.644882) (xy 35.644857 -264.596861) (xy 35.629147 -264.545931) (xy 35.621204 -264.493227)
			(xy 34.122624 -264.493227) (xy 34.114681 -264.545931) (xy 34.098971 -264.596861) (xy 34.075845 -264.644882)
			(xy 34.045821 -264.688919) (xy 34.009569 -264.72799) (xy 33.967898 -264.761221) (xy 33.92174 -264.78787)
			(xy 33.872126 -264.807342) (xy 33.820164 -264.819202) (xy 33.767014 -264.823186) (xy 33.713864 -264.819202)
			(xy 33.661902 -264.807342) (xy 33.612288 -264.78787) (xy 33.56613 -264.761221) (xy 33.524459 -264.72799)
			(xy 33.488207 -264.688919) (xy 33.458183 -264.644882) (xy 33.435057 -264.596861) (xy 33.419347 -264.545931)
			(xy 33.411404 -264.493227) (xy 32.391858 -264.493227) (xy 32.391858 -265.52144) (xy 34.120836 -265.52144)
			(xy 34.120836 -265.1125) (xy 34.121222 -265.102341) (xy 34.129025 -265.083582) (xy 34.143433 -265.069257)
			(xy 34.162237 -265.061564) (xy 34.172398 -265.061192) (xy 35.571938 -265.061192) (xy 35.579792 -265.061426)
			(xy 35.594789 -265.066091) (xy 35.601402 -265.070336) (xy 35.613163 -265.077923) (xy 35.6396 -265.087072)
			(xy 35.667527 -265.088712) (xy 35.694853 -265.08272) (xy 35.719531 -265.069545) (xy 35.729926 -265.060176)
			(xy 35.749924 -265.041585) (xy 35.794574 -265.010159) (xy 35.8435 -264.985922) (xy 35.895554 -264.969441)
			(xy 35.949514 -264.961104) (xy 35.976814 -264.960608) (xy 36.003464 -264.961075) (xy 36.056168 -264.96902)
			(xy 36.107099 -264.984732) (xy 36.15512 -265.00786) (xy 36.199157 -265.037886) (xy 36.238228 -265.074139)
			(xy 36.271459 -265.115811) (xy 36.298108 -265.16197) (xy 36.317581 -265.211586) (xy 36.329441 -265.263549)
			(xy 36.333424 -265.3167) (xy 36.331426 -265.343365) (xy 36.855136 -265.343365) (xy 36.855136 -265.290067)
			(xy 36.863079 -265.237363) (xy 36.878789 -265.186433) (xy 36.901915 -265.138412) (xy 36.931939 -265.094375)
			(xy 36.968191 -265.055304) (xy 37.009862 -265.022073) (xy 37.05602 -264.995424) (xy 37.105634 -264.975952)
			(xy 37.157596 -264.964092) (xy 37.210746 -264.960109) (xy 37.263896 -264.964092) (xy 37.315858 -264.975952)
			(xy 37.365472 -264.995424) (xy 37.41163 -265.022073) (xy 37.453301 -265.055304) (xy 37.489553 -265.094375)
			(xy 37.519577 -265.138412) (xy 37.542703 -265.186433) (xy 37.558413 -265.237363) (xy 37.566356 -265.290067)
			(xy 37.566854 -265.316716) (xy 37.566356 -265.343365) (xy 37.558413 -265.396069) (xy 37.542703 -265.446999)
			(xy 37.519577 -265.49502) (xy 37.489553 -265.539057) (xy 37.453301 -265.578128) (xy 37.41163 -265.611359)
			(xy 37.365472 -265.638008) (xy 37.315858 -265.65748) (xy 37.263896 -265.66934) (xy 37.210746 -265.673324)
			(xy 37.157596 -265.66934) (xy 37.105634 -265.65748) (xy 37.05602 -265.638008) (xy 37.009862 -265.611359)
			(xy 36.968191 -265.578128) (xy 36.931939 -265.539057) (xy 36.901915 -265.49502) (xy 36.878789 -265.446999)
			(xy 36.863079 -265.396069) (xy 36.855136 -265.343365) (xy 36.331426 -265.343365) (xy 36.329441 -265.369851)
			(xy 36.317581 -265.421814) (xy 36.298108 -265.47143) (xy 36.271459 -265.517589) (xy 36.238228 -265.559261)
			(xy 36.199157 -265.595514) (xy 36.15512 -265.62554) (xy 36.107099 -265.648668) (xy 36.056168 -265.66438)
			(xy 36.003464 -265.672325) (xy 35.976814 -265.672824) (xy 35.949551 -265.672316) (xy 35.895664 -265.663999)
			(xy 35.843676 -265.64756) (xy 35.794804 -265.623381) (xy 35.750194 -265.59203) (xy 35.73018 -265.57351)
			(xy 35.719775 -265.56409) (xy 35.695027 -265.550872) (xy 35.667614 -265.544895) (xy 35.639609 -265.546614)
			(xy 35.613132 -265.555897) (xy 35.601402 -265.563604) (xy 35.594788 -265.567846) (xy 35.579791 -265.572505)
			(xy 35.571938 -265.572748) (xy 34.172398 -265.572748) (xy 34.16227 -265.572275) (xy 34.143546 -265.564544)
			(xy 34.12919 -265.550253) (xy 34.121373 -265.531566) (xy 34.120836 -265.52144) (xy 32.391858 -265.52144)
			(xy 32.391858 -266.193249) (xy 33.411404 -266.193249) (xy 33.411404 -266.139951) (xy 33.419347 -266.087247)
			(xy 33.435057 -266.036317) (xy 33.458183 -265.988296) (xy 33.488207 -265.944259) (xy 33.524459 -265.905188)
			(xy 33.56613 -265.871957) (xy 33.612288 -265.845308) (xy 33.661902 -265.825836) (xy 33.713864 -265.813976)
			(xy 33.767014 -265.809993) (xy 33.820164 -265.813976) (xy 33.872126 -265.825836) (xy 33.92174 -265.845308)
			(xy 33.967898 -265.871957) (xy 34.009569 -265.905188) (xy 34.045821 -265.944259) (xy 34.075845 -265.988296)
			(xy 34.098971 -266.036317) (xy 34.114681 -266.087247) (xy 34.122624 -266.139951) (xy 34.123122 -266.1666)
			(xy 34.122624 -266.193249) (xy 35.621204 -266.193249) (xy 35.621204 -266.139951) (xy 35.629147 -266.087247)
			(xy 35.644857 -266.036317) (xy 35.667983 -265.988296) (xy 35.698007 -265.944259) (xy 35.734259 -265.905188)
			(xy 35.77593 -265.871957) (xy 35.822088 -265.845308) (xy 35.871702 -265.825836) (xy 35.923664 -265.813976)
			(xy 35.976814 -265.809993) (xy 36.029964 -265.813976) (xy 36.081926 -265.825836) (xy 36.13154 -265.845308)
			(xy 36.177698 -265.871957) (xy 36.219369 -265.905188) (xy 36.255621 -265.944259) (xy 36.285645 -265.988296)
			(xy 36.308771 -266.036317) (xy 36.324481 -266.087247) (xy 36.332424 -266.139951) (xy 36.332922 -266.1666)
			(xy 36.332424 -266.193249) (xy 36.324481 -266.245953) (xy 36.308771 -266.296883) (xy 36.285645 -266.344904)
			(xy 36.255621 -266.388941) (xy 36.219369 -266.428012) (xy 36.177698 -266.461243) (xy 36.13154 -266.487892)
			(xy 36.081926 -266.507364) (xy 36.029964 -266.519224) (xy 35.976814 -266.523208) (xy 35.923664 -266.519224)
			(xy 35.871702 -266.507364) (xy 35.822088 -266.487892) (xy 35.77593 -266.461243) (xy 35.734259 -266.428012)
			(xy 35.698007 -266.388941) (xy 35.667983 -266.344904) (xy 35.644857 -266.296883) (xy 35.629147 -266.245953)
			(xy 35.621204 -266.193249) (xy 34.122624 -266.193249) (xy 34.114681 -266.245953) (xy 34.098971 -266.296883)
			(xy 34.075845 -266.344904) (xy 34.045821 -266.388941) (xy 34.009569 -266.428012) (xy 33.967898 -266.461243)
			(xy 33.92174 -266.487892) (xy 33.872126 -266.507364) (xy 33.820164 -266.519224) (xy 33.767014 -266.523208)
			(xy 33.713864 -266.519224) (xy 33.661902 -266.507364) (xy 33.612288 -266.487892) (xy 33.56613 -266.461243)
			(xy 33.524459 -266.428012) (xy 33.488207 -266.388941) (xy 33.458183 -266.344904) (xy 33.435057 -266.296883)
			(xy 33.419347 -266.245953) (xy 33.411404 -266.193249) (xy 32.391858 -266.193249) (xy 32.391858 -267.221462)
			(xy 34.120836 -267.221462) (xy 34.120836 -266.812522) (xy 34.121282 -266.802352) (xy 34.129059 -266.783558)
			(xy 34.143438 -266.769173) (xy 34.162228 -266.761387) (xy 34.172398 -266.76096) (xy 35.571938 -266.76096)
			(xy 35.579809 -266.761268) (xy 35.594808 -266.766051) (xy 35.601402 -266.770358) (xy 35.613165 -266.777942)
			(xy 35.639601 -266.787089) (xy 35.667527 -266.788728) (xy 35.694852 -266.782738) (xy 35.71953 -266.769566)
			(xy 35.729926 -266.760198) (xy 35.749927 -266.741611) (xy 35.794576 -266.710184) (xy 35.843501 -266.685945)
			(xy 35.895554 -266.669464) (xy 35.949514 -266.661126) (xy 35.976814 -266.66063) (xy 36.003465 -266.661053)
			(xy 36.056173 -266.668999) (xy 36.107107 -266.684712) (xy 36.155131 -266.707841) (xy 36.199171 -266.737868)
			(xy 36.238244 -266.774124) (xy 36.271477 -266.815799) (xy 36.298128 -266.861961) (xy 36.317602 -266.911579)
			(xy 36.329462 -266.963546) (xy 36.333446 -267.0167) (xy 36.331446 -267.043387) (xy 36.855136 -267.043387)
			(xy 36.855136 -266.990089) (xy 36.863079 -266.937385) (xy 36.878789 -266.886455) (xy 36.901915 -266.838434)
			(xy 36.931939 -266.794397) (xy 36.968191 -266.755326) (xy 37.009862 -266.722095) (xy 37.05602 -266.695446)
			(xy 37.105634 -266.675974) (xy 37.157596 -266.664114) (xy 37.210746 -266.660131) (xy 37.263896 -266.664114)
			(xy 37.315858 -266.675974) (xy 37.365472 -266.695446) (xy 37.41163 -266.722095) (xy 37.453301 -266.755326)
			(xy 37.489553 -266.794397) (xy 37.519577 -266.838434) (xy 37.542703 -266.886455) (xy 37.558413 -266.937385)
			(xy 37.566356 -266.990089) (xy 37.566854 -267.016738) (xy 37.566356 -267.043387) (xy 37.558413 -267.096091)
			(xy 37.542703 -267.147021) (xy 37.519577 -267.195042) (xy 37.489553 -267.239079) (xy 37.453301 -267.27815)
			(xy 37.41163 -267.311381) (xy 37.365472 -267.33803) (xy 37.315858 -267.357502) (xy 37.263896 -267.369362)
			(xy 37.210746 -267.373346) (xy 37.157596 -267.369362) (xy 37.105634 -267.357502) (xy 37.05602 -267.33803)
			(xy 37.009862 -267.311381) (xy 36.968191 -267.27815) (xy 36.931939 -267.239079) (xy 36.901915 -267.195042)
			(xy 36.878789 -267.147021) (xy 36.863079 -267.096091) (xy 36.855136 -267.043387) (xy 36.331446 -267.043387)
			(xy 36.329462 -267.069854) (xy 36.317602 -267.121821) (xy 36.298128 -267.171439) (xy 36.271477 -267.217601)
			(xy 36.238244 -267.259276) (xy 36.199171 -267.295532) (xy 36.155131 -267.325559) (xy 36.107107 -267.348688)
			(xy 36.056173 -267.364401) (xy 36.003465 -267.372347) (xy 35.976814 -267.372846) (xy 35.94955 -267.372359)
			(xy 35.895661 -267.364041) (xy 35.843672 -267.347597) (xy 35.794801 -267.323413) (xy 35.750192 -267.292055)
			(xy 35.73018 -267.273532) (xy 35.719775 -267.264113) (xy 35.695027 -267.250891) (xy 35.667614 -267.244914)
			(xy 35.639609 -267.246633) (xy 35.613132 -267.255918) (xy 35.601402 -267.263626) (xy 35.594793 -267.267906)
			(xy 35.579804 -267.272699) (xy 35.571938 -267.273024) (xy 34.172398 -267.273024) (xy 34.162222 -267.272637)
			(xy 34.14342 -267.264844) (xy 34.129033 -267.250447) (xy 34.121255 -267.231639) (xy 34.120836 -267.221462)
			(xy 32.391858 -267.221462) (xy 32.391858 -267.893271) (xy 33.411404 -267.893271) (xy 33.411404 -267.839973)
			(xy 33.419347 -267.787269) (xy 33.435057 -267.736339) (xy 33.458183 -267.688318) (xy 33.488207 -267.644281)
			(xy 33.524459 -267.60521) (xy 33.56613 -267.571979) (xy 33.612288 -267.54533) (xy 33.661902 -267.525858)
			(xy 33.713864 -267.513998) (xy 33.767014 -267.510015) (xy 33.820164 -267.513998) (xy 33.872126 -267.525858)
			(xy 33.92174 -267.54533) (xy 33.967898 -267.571979) (xy 34.009569 -267.60521) (xy 34.045821 -267.644281)
			(xy 34.075845 -267.688318) (xy 34.098971 -267.736339) (xy 34.114681 -267.787269) (xy 34.122624 -267.839973)
			(xy 34.123122 -267.866622) (xy 34.122624 -267.893271) (xy 35.621204 -267.893271) (xy 35.621204 -267.839973)
			(xy 35.629147 -267.787269) (xy 35.644857 -267.736339) (xy 35.667983 -267.688318) (xy 35.698007 -267.644281)
			(xy 35.734259 -267.60521) (xy 35.77593 -267.571979) (xy 35.822088 -267.54533) (xy 35.871702 -267.525858)
			(xy 35.923664 -267.513998) (xy 35.976814 -267.510015) (xy 36.029964 -267.513998) (xy 36.081926 -267.525858)
			(xy 36.13154 -267.54533) (xy 36.177698 -267.571979) (xy 36.219369 -267.60521) (xy 36.255621 -267.644281)
			(xy 36.285645 -267.688318) (xy 36.308771 -267.736339) (xy 36.324481 -267.787269) (xy 36.332424 -267.839973)
			(xy 36.332922 -267.866622) (xy 36.332424 -267.893271) (xy 36.324481 -267.945975) (xy 36.308771 -267.996905)
			(xy 36.285645 -268.044926) (xy 36.255621 -268.088963) (xy 36.219369 -268.128034) (xy 36.177698 -268.161265)
			(xy 36.13154 -268.187914) (xy 36.081926 -268.207386) (xy 36.029964 -268.219246) (xy 35.976814 -268.22323)
			(xy 35.923664 -268.219246) (xy 35.871702 -268.207386) (xy 35.822088 -268.187914) (xy 35.77593 -268.161265)
			(xy 35.734259 -268.128034) (xy 35.698007 -268.088963) (xy 35.667983 -268.044926) (xy 35.644857 -267.996905)
			(xy 35.629147 -267.945975) (xy 35.621204 -267.893271) (xy 34.122624 -267.893271) (xy 34.114681 -267.945975)
			(xy 34.098971 -267.996905) (xy 34.075845 -268.044926) (xy 34.045821 -268.088963) (xy 34.009569 -268.128034)
			(xy 33.967898 -268.161265) (xy 33.92174 -268.187914) (xy 33.872126 -268.207386) (xy 33.820164 -268.219246)
			(xy 33.767014 -268.22323) (xy 33.713864 -268.219246) (xy 33.661902 -268.207386) (xy 33.612288 -268.187914)
			(xy 33.56613 -268.161265) (xy 33.524459 -268.128034) (xy 33.488207 -268.088963) (xy 33.458183 -268.044926)
			(xy 33.435057 -267.996905) (xy 33.419347 -267.945975) (xy 33.411404 -267.893271) (xy 32.391858 -267.893271)
			(xy 32.391858 -268.921484) (xy 34.120836 -268.921484) (xy 34.120836 -268.512544) (xy 34.121258 -268.502388)
			(xy 34.129046 -268.48363) (xy 34.143444 -268.469304) (xy 34.16224 -268.461609) (xy 34.172398 -268.461236)
			(xy 35.571938 -268.461236) (xy 35.579791 -268.461479) (xy 35.594788 -268.466138) (xy 35.601402 -268.47038)
			(xy 35.613166 -268.47796) (xy 35.639602 -268.487105) (xy 35.667527 -268.488744) (xy 35.694851 -268.482755)
			(xy 35.719529 -268.469586) (xy 35.729926 -268.46022) (xy 35.749931 -268.441637) (xy 35.794578 -268.410208)
			(xy 35.843502 -268.385968) (xy 35.895555 -268.369486) (xy 35.949514 -268.361148) (xy 35.976814 -268.360652)
			(xy 36.00346 -268.361231) (xy 36.056155 -268.369176) (xy 36.107078 -268.384885) (xy 36.155092 -268.408009)
			(xy 36.199122 -268.43803) (xy 36.238187 -268.474278) (xy 36.271412 -268.515943) (xy 36.298058 -268.562095)
			(xy 36.317527 -268.611703) (xy 36.329385 -268.663658) (xy 36.333367 -268.7168) (xy 36.331373 -268.743409)
			(xy 36.855136 -268.743409) (xy 36.855136 -268.690111) (xy 36.863079 -268.637407) (xy 36.878789 -268.586477)
			(xy 36.901915 -268.538456) (xy 36.931939 -268.494419) (xy 36.968191 -268.455348) (xy 37.009862 -268.422117)
			(xy 37.05602 -268.395468) (xy 37.105634 -268.375996) (xy 37.157596 -268.364136) (xy 37.210746 -268.360153)
			(xy 37.263896 -268.364136) (xy 37.315858 -268.375996) (xy 37.365472 -268.395468) (xy 37.41163 -268.422117)
			(xy 37.453301 -268.455348) (xy 37.489553 -268.494419) (xy 37.519577 -268.538456) (xy 37.542703 -268.586477)
			(xy 37.558413 -268.637407) (xy 37.566356 -268.690111) (xy 37.566854 -268.71676) (xy 37.566356 -268.743409)
			(xy 37.558413 -268.796113) (xy 37.542703 -268.847043) (xy 37.519577 -268.895064) (xy 37.489553 -268.939101)
			(xy 37.453301 -268.978172) (xy 37.41163 -269.011403) (xy 37.365472 -269.038052) (xy 37.315858 -269.057524)
			(xy 37.263896 -269.069384) (xy 37.210746 -269.073368) (xy 37.157596 -269.069384) (xy 37.105634 -269.057524)
			(xy 37.05602 -269.038052) (xy 37.009862 -269.011403) (xy 36.968191 -268.978172) (xy 36.931939 -268.939101)
			(xy 36.901915 -268.895064) (xy 36.878789 -268.847043) (xy 36.863079 -268.796113) (xy 36.855136 -268.743409)
			(xy 36.331373 -268.743409) (xy 36.329385 -268.769942) (xy 36.317527 -268.821897) (xy 36.298058 -268.871505)
			(xy 36.271412 -268.917657) (xy 36.238187 -268.959322) (xy 36.199122 -268.99557) (xy 36.155092 -269.025591)
			(xy 36.107078 -269.048715) (xy 36.056155 -269.064424) (xy 36.00346 -269.072369) (xy 35.976814 -269.072868)
			(xy 35.94955 -269.072375) (xy 35.895662 -269.064057) (xy 35.843673 -269.047615) (xy 35.794802 -269.023432)
			(xy 35.750192 -268.992076) (xy 35.73018 -268.973554) (xy 35.719774 -268.964135) (xy 35.695028 -268.950911)
			(xy 35.667614 -268.944932) (xy 35.639608 -268.946651) (xy 35.613132 -268.955939) (xy 35.601402 -268.963648)
			(xy 35.59479 -268.967894) (xy 35.579792 -268.972549) (xy 35.571938 -268.972792) (xy 34.172398 -268.972792)
			(xy 34.162275 -268.972276) (xy 34.14356 -268.964553) (xy 34.129205 -268.950277) (xy 34.12138 -268.931604)
			(xy 34.120836 -268.921484) (xy 32.391858 -268.921484) (xy 32.391858 -269.593293) (xy 33.411404 -269.593293)
			(xy 33.411404 -269.539995) (xy 33.419347 -269.487291) (xy 33.435057 -269.436361) (xy 33.458183 -269.38834)
			(xy 33.488207 -269.344303) (xy 33.524459 -269.305232) (xy 33.56613 -269.272001) (xy 33.612288 -269.245352)
			(xy 33.661902 -269.22588) (xy 33.713864 -269.21402) (xy 33.767014 -269.210037) (xy 33.820164 -269.21402)
			(xy 33.872126 -269.22588) (xy 33.92174 -269.245352) (xy 33.967898 -269.272001) (xy 34.009569 -269.305232)
			(xy 34.045821 -269.344303) (xy 34.075845 -269.38834) (xy 34.098971 -269.436361) (xy 34.114681 -269.487291)
			(xy 34.122624 -269.539995) (xy 34.123122 -269.566644) (xy 34.122624 -269.593293) (xy 35.621204 -269.593293)
			(xy 35.621204 -269.539995) (xy 35.629147 -269.487291) (xy 35.644857 -269.436361) (xy 35.667983 -269.38834)
			(xy 35.698007 -269.344303) (xy 35.734259 -269.305232) (xy 35.77593 -269.272001) (xy 35.822088 -269.245352)
			(xy 35.871702 -269.22588) (xy 35.923664 -269.21402) (xy 35.976814 -269.210037) (xy 36.029964 -269.21402)
			(xy 36.081926 -269.22588) (xy 36.13154 -269.245352) (xy 36.177698 -269.272001) (xy 36.219369 -269.305232)
			(xy 36.255621 -269.344303) (xy 36.285645 -269.38834) (xy 36.308771 -269.436361) (xy 36.324481 -269.487291)
			(xy 36.332424 -269.539995) (xy 36.332922 -269.566644) (xy 36.332424 -269.593293) (xy 36.324481 -269.645997)
			(xy 36.308771 -269.696927) (xy 36.285645 -269.744948) (xy 36.255621 -269.788985) (xy 36.219369 -269.828056)
			(xy 36.177698 -269.861287) (xy 36.13154 -269.887936) (xy 36.081926 -269.907408) (xy 36.029964 -269.919268)
			(xy 35.976814 -269.923252) (xy 35.923664 -269.919268) (xy 35.871702 -269.907408) (xy 35.822088 -269.887936)
			(xy 35.77593 -269.861287) (xy 35.734259 -269.828056) (xy 35.698007 -269.788985) (xy 35.667983 -269.744948)
			(xy 35.644857 -269.696927) (xy 35.629147 -269.645997) (xy 35.621204 -269.593293) (xy 34.122624 -269.593293)
			(xy 34.114681 -269.645997) (xy 34.098971 -269.696927) (xy 34.075845 -269.744948) (xy 34.045821 -269.788985)
			(xy 34.009569 -269.828056) (xy 33.967898 -269.861287) (xy 33.92174 -269.887936) (xy 33.872126 -269.907408)
			(xy 33.820164 -269.919268) (xy 33.767014 -269.923252) (xy 33.713864 -269.919268) (xy 33.661902 -269.907408)
			(xy 33.612288 -269.887936) (xy 33.56613 -269.861287) (xy 33.524459 -269.828056) (xy 33.488207 -269.788985)
			(xy 33.458183 -269.744948) (xy 33.435057 -269.696927) (xy 33.419347 -269.645997) (xy 33.411404 -269.593293)
			(xy 32.391858 -269.593293) (xy 32.391858 -270.621506) (xy 34.120836 -270.621506) (xy 34.120836 -270.212566)
			(xy 34.121305 -270.202406) (xy 34.129091 -270.183637) (xy 34.143464 -270.169273) (xy 34.162238 -270.161499)
			(xy 34.172398 -270.161004) (xy 35.571938 -270.161004) (xy 35.579808 -270.161322) (xy 35.594806 -270.166099)
			(xy 35.601402 -270.170402) (xy 35.613161 -270.177994) (xy 35.639598 -270.187147) (xy 35.667527 -270.188788)
			(xy 35.694854 -270.182794) (xy 35.719532 -270.169614) (xy 35.729926 -270.160242) (xy 35.749918 -270.141645)
			(xy 35.794571 -270.110221) (xy 35.843498 -270.085985) (xy 35.895553 -270.069506) (xy 35.949513 -270.061169)
			(xy 35.976814 -270.060674) (xy 36.003461 -270.061209) (xy 36.05616 -270.069154) (xy 36.107087 -270.084865)
			(xy 36.155103 -270.10799) (xy 36.199136 -270.138012) (xy 36.238203 -270.174263) (xy 36.271431 -270.215931)
			(xy 36.298077 -270.262085) (xy 36.317548 -270.311696) (xy 36.329406 -270.363654) (xy 36.333389 -270.4168)
			(xy 36.331393 -270.443431) (xy 36.855136 -270.443431) (xy 36.855136 -270.390133) (xy 36.863079 -270.337429)
			(xy 36.878789 -270.286499) (xy 36.901915 -270.238478) (xy 36.931939 -270.194441) (xy 36.968191 -270.15537)
			(xy 37.009862 -270.122139) (xy 37.05602 -270.09549) (xy 37.105634 -270.076018) (xy 37.157596 -270.064158)
			(xy 37.210746 -270.060175) (xy 37.263896 -270.064158) (xy 37.315858 -270.076018) (xy 37.365472 -270.09549)
			(xy 37.41163 -270.122139) (xy 37.453301 -270.15537) (xy 37.489553 -270.194441) (xy 37.519577 -270.238478)
			(xy 37.542703 -270.286499) (xy 37.558413 -270.337429) (xy 37.566356 -270.390133) (xy 37.566854 -270.416782)
			(xy 37.566356 -270.443431) (xy 37.558413 -270.496135) (xy 37.542703 -270.547065) (xy 37.519577 -270.595086)
			(xy 37.489553 -270.639123) (xy 37.453301 -270.678194) (xy 37.41163 -270.711425) (xy 37.365472 -270.738074)
			(xy 37.315858 -270.757546) (xy 37.263896 -270.769406) (xy 37.210746 -270.77339) (xy 37.157596 -270.769406)
			(xy 37.105634 -270.757546) (xy 37.05602 -270.738074) (xy 37.009862 -270.711425) (xy 36.968191 -270.678194)
			(xy 36.931939 -270.639123) (xy 36.901915 -270.595086) (xy 36.878789 -270.547065) (xy 36.863079 -270.496135)
			(xy 36.855136 -270.443431) (xy 36.331393 -270.443431) (xy 36.329406 -270.469946) (xy 36.317548 -270.521904)
			(xy 36.298077 -270.571515) (xy 36.271431 -270.617669) (xy 36.238203 -270.659337) (xy 36.199136 -270.695588)
			(xy 36.155103 -270.72561) (xy 36.107087 -270.748735) (xy 36.05616 -270.764446) (xy 36.003461 -270.772391)
			(xy 35.976814 -270.77289) (xy 35.949551 -270.772391) (xy 35.895663 -270.764074) (xy 35.843674 -270.747632)
			(xy 35.794803 -270.723451) (xy 35.750193 -270.692097) (xy 35.73018 -270.673576) (xy 35.719774 -270.664157)
			(xy 35.695028 -270.65093) (xy 35.667614 -270.64495) (xy 35.639608 -270.64667) (xy 35.613131 -270.655959)
			(xy 35.601402 -270.66367) (xy 35.59479 -270.667945) (xy 35.579804 -270.672742) (xy 35.571938 -270.673068)
			(xy 34.172398 -270.673068) (xy 34.162241 -270.672568) (xy 34.143473 -270.664794) (xy 34.129108 -270.650431)
			(xy 34.121332 -270.631663) (xy 34.120836 -270.621506) (xy 32.391858 -270.621506) (xy 32.391858 -271.293315)
			(xy 33.411404 -271.293315) (xy 33.411404 -271.240017) (xy 33.419347 -271.187313) (xy 33.435057 -271.136383)
			(xy 33.458183 -271.088362) (xy 33.488207 -271.044325) (xy 33.524459 -271.005254) (xy 33.56613 -270.972023)
			(xy 33.612288 -270.945374) (xy 33.661902 -270.925902) (xy 33.713864 -270.914042) (xy 33.767014 -270.910059)
			(xy 33.820164 -270.914042) (xy 33.872126 -270.925902) (xy 33.92174 -270.945374) (xy 33.967898 -270.972023)
			(xy 34.009569 -271.005254) (xy 34.045821 -271.044325) (xy 34.075845 -271.088362) (xy 34.098971 -271.136383)
			(xy 34.114681 -271.187313) (xy 34.122624 -271.240017) (xy 34.123122 -271.266666) (xy 34.122624 -271.293315)
			(xy 35.621204 -271.293315) (xy 35.621204 -271.240017) (xy 35.629147 -271.187313) (xy 35.644857 -271.136383)
			(xy 35.667983 -271.088362) (xy 35.698007 -271.044325) (xy 35.734259 -271.005254) (xy 35.77593 -270.972023)
			(xy 35.822088 -270.945374) (xy 35.871702 -270.925902) (xy 35.923664 -270.914042) (xy 35.976814 -270.910059)
			(xy 36.029964 -270.914042) (xy 36.081926 -270.925902) (xy 36.13154 -270.945374) (xy 36.177698 -270.972023)
			(xy 36.219369 -271.005254) (xy 36.255621 -271.044325) (xy 36.285645 -271.088362) (xy 36.308771 -271.136383)
			(xy 36.324481 -271.187313) (xy 36.332424 -271.240017) (xy 36.332922 -271.266666) (xy 36.332424 -271.293315)
			(xy 36.324481 -271.346019) (xy 36.308771 -271.396949) (xy 36.285645 -271.44497) (xy 36.267632 -271.47139)
			(xy 37.564568 -271.47139) (xy 37.564568 -271.06245) (xy 37.565005 -271.052278) (xy 37.57278 -271.033479)
			(xy 37.587162 -271.019091) (xy 37.605958 -271.011309) (xy 37.61613 -271.010888) (xy 39.01567 -271.010888)
			(xy 39.025846 -271.01129) (xy 39.044649 -271.019074) (xy 39.059037 -271.033467) (xy 39.066814 -271.052274)
			(xy 39.067232 -271.06245) (xy 39.067232 -271.47139) (xy 39.066827 -271.481565) (xy 39.05904 -271.500365)
			(xy 39.044648 -271.514751) (xy 39.025845 -271.522531) (xy 39.01567 -271.522952) (xy 37.61613 -271.522952)
			(xy 37.605959 -271.522511) (xy 37.587163 -271.514734) (xy 37.572777 -271.500354) (xy 37.564993 -271.481561)
			(xy 37.564568 -271.47139) (xy 36.267632 -271.47139) (xy 36.255621 -271.489007) (xy 36.219369 -271.528078)
			(xy 36.177698 -271.561309) (xy 36.13154 -271.587958) (xy 36.081926 -271.60743) (xy 36.029964 -271.61929)
			(xy 35.976814 -271.623274) (xy 35.923664 -271.61929) (xy 35.871702 -271.60743) (xy 35.822088 -271.587958)
			(xy 35.77593 -271.561309) (xy 35.734259 -271.528078) (xy 35.698007 -271.489007) (xy 35.667983 -271.44497)
			(xy 35.644857 -271.396949) (xy 35.629147 -271.346019) (xy 35.621204 -271.293315) (xy 34.122624 -271.293315)
			(xy 34.114681 -271.346019) (xy 34.098971 -271.396949) (xy 34.075845 -271.44497) (xy 34.045821 -271.489007)
			(xy 34.009569 -271.528078) (xy 33.967898 -271.561309) (xy 33.92174 -271.587958) (xy 33.872126 -271.60743)
			(xy 33.820164 -271.61929) (xy 33.767014 -271.623274) (xy 33.713864 -271.61929) (xy 33.661902 -271.60743)
			(xy 33.612288 -271.587958) (xy 33.56613 -271.561309) (xy 33.524459 -271.528078) (xy 33.488207 -271.489007)
			(xy 33.458183 -271.44497) (xy 33.435057 -271.396949) (xy 33.419347 -271.346019) (xy 33.411404 -271.293315)
			(xy 32.391858 -271.293315) (xy 32.391858 -272.321528) (xy 34.120836 -272.321528) (xy 34.120836 -271.912588)
			(xy 34.121212 -271.902429) (xy 34.129019 -271.883669) (xy 34.14343 -271.869345) (xy 34.162236 -271.861652)
			(xy 34.172398 -271.86128) (xy 35.571938 -271.86128) (xy 35.579792 -271.861516) (xy 35.594789 -271.86618)
			(xy 35.601402 -271.870424) (xy 35.613162 -271.878013) (xy 35.639599 -271.887163) (xy 35.667527 -271.888803)
			(xy 35.694853 -271.882811) (xy 35.719531 -271.869634) (xy 35.729926 -271.860264) (xy 35.749922 -271.841671)
			(xy 35.794573 -271.810246) (xy 35.843499 -271.786009) (xy 35.895553 -271.769528) (xy 35.949514 -271.761191)
			(xy 35.976814 -271.760696) (xy 36.003463 -271.761187) (xy 36.056165 -271.769132) (xy 36.107095 -271.784844)
			(xy 36.155114 -271.80797) (xy 36.19915 -271.837995) (xy 36.238219 -271.874247) (xy 36.271449 -271.915918)
			(xy 36.298098 -271.962076) (xy 36.317569 -272.011689) (xy 36.329429 -272.063651) (xy 36.333412 -272.1168)
			(xy 36.331415 -272.143453) (xy 36.855136 -272.143453) (xy 36.855136 -272.090155) (xy 36.863079 -272.037451)
			(xy 36.878789 -271.986521) (xy 36.901915 -271.9385) (xy 36.931939 -271.894463) (xy 36.968191 -271.855392)
			(xy 37.009862 -271.822161) (xy 37.05602 -271.795512) (xy 37.105634 -271.77604) (xy 37.157596 -271.76418)
			(xy 37.210746 -271.760197) (xy 37.263896 -271.76418) (xy 37.315858 -271.77604) (xy 37.365472 -271.795512)
			(xy 37.41163 -271.822161) (xy 37.453301 -271.855392) (xy 37.489553 -271.894463) (xy 37.519577 -271.9385)
			(xy 37.542703 -271.986521) (xy 37.558413 -272.037451) (xy 37.566356 -272.090155) (xy 37.566854 -272.116804)
			(xy 37.566356 -272.143453) (xy 37.558413 -272.196157) (xy 37.542703 -272.247087) (xy 37.519577 -272.295108)
			(xy 37.489553 -272.339145) (xy 37.453301 -272.378216) (xy 37.41163 -272.411447) (xy 37.365472 -272.438096)
			(xy 37.315858 -272.457568) (xy 37.263896 -272.469428) (xy 37.210746 -272.473412) (xy 37.157596 -272.469428)
			(xy 37.105634 -272.457568) (xy 37.05602 -272.438096) (xy 37.009862 -272.411447) (xy 36.968191 -272.378216)
			(xy 36.931939 -272.339145) (xy 36.901915 -272.295108) (xy 36.878789 -272.247087) (xy 36.863079 -272.196157)
			(xy 36.855136 -272.143453) (xy 36.331415 -272.143453) (xy 36.329429 -272.169949) (xy 36.317569 -272.221911)
			(xy 36.298098 -272.271524) (xy 36.271449 -272.317682) (xy 36.238219 -272.359353) (xy 36.19915 -272.395605)
			(xy 36.155114 -272.42563) (xy 36.107095 -272.448756) (xy 36.056165 -272.464468) (xy 36.003463 -272.472413)
			(xy 35.976814 -272.472912) (xy 35.949551 -272.472407) (xy 35.895663 -272.46409) (xy 35.843675 -272.44765)
			(xy 35.794804 -272.42347) (xy 35.750194 -272.392118) (xy 35.73018 -272.373598) (xy 35.719773 -272.364178)
			(xy 35.695028 -272.350949) (xy 35.667614 -272.344968) (xy 35.639607 -272.346688) (xy 35.61313 -272.35598)
			(xy 35.601402 -272.363692) (xy 35.594787 -272.367933) (xy 35.579791 -272.372592) (xy 35.571938 -272.372836)
			(xy 34.172398 -272.372836) (xy 34.162268 -272.372374) (xy 34.143543 -272.364641) (xy 34.129185 -272.350347)
			(xy 34.121371 -272.331656) (xy 34.120836 -272.321528) (xy 32.391858 -272.321528) (xy 32.391858 -272.993337)
			(xy 33.411404 -272.993337) (xy 33.411404 -272.940039) (xy 33.419347 -272.887335) (xy 33.435057 -272.836405)
			(xy 33.458183 -272.788384) (xy 33.488207 -272.744347) (xy 33.524459 -272.705276) (xy 33.56613 -272.672045)
			(xy 33.612288 -272.645396) (xy 33.661902 -272.625924) (xy 33.713864 -272.614064) (xy 33.767014 -272.610081)
			(xy 33.820164 -272.614064) (xy 33.872126 -272.625924) (xy 33.92174 -272.645396) (xy 33.967898 -272.672045)
			(xy 34.009569 -272.705276) (xy 34.045821 -272.744347) (xy 34.075845 -272.788384) (xy 34.098971 -272.836405)
			(xy 34.114681 -272.887335) (xy 34.122624 -272.940039) (xy 34.123122 -272.966688) (xy 34.122624 -272.993337)
			(xy 35.621204 -272.993337) (xy 35.621204 -272.940039) (xy 35.629147 -272.887335) (xy 35.644857 -272.836405)
			(xy 35.667983 -272.788384) (xy 35.698007 -272.744347) (xy 35.734259 -272.705276) (xy 35.77593 -272.672045)
			(xy 35.822088 -272.645396) (xy 35.871702 -272.625924) (xy 35.923664 -272.614064) (xy 35.976814 -272.610081)
			(xy 36.029964 -272.614064) (xy 36.081926 -272.625924) (xy 36.13154 -272.645396) (xy 36.177698 -272.672045)
			(xy 36.219369 -272.705276) (xy 36.255621 -272.744347) (xy 36.285645 -272.788384) (xy 36.308771 -272.836405)
			(xy 36.324481 -272.887335) (xy 36.332424 -272.940039) (xy 36.332922 -272.966688) (xy 36.332424 -272.993337)
			(xy 36.324481 -273.046041) (xy 36.308771 -273.096971) (xy 36.285645 -273.144992) (xy 36.267632 -273.171412)
			(xy 37.564568 -273.171412) (xy 37.564568 -272.762472) (xy 37.564998 -272.75232) (xy 37.572797 -272.733573)
			(xy 37.58719 -272.719252) (xy 37.605976 -272.711547) (xy 37.61613 -272.711164) (xy 39.01567 -272.711164)
			(xy 39.025798 -272.711652) (xy 39.044523 -272.719374) (xy 39.058881 -272.733661) (xy 39.066697 -272.752347)
			(xy 39.067232 -272.762472) (xy 39.067232 -273.171412) (xy 39.066789 -273.181563) (xy 39.058996 -273.20031)
			(xy 39.044606 -273.214631) (xy 39.025823 -273.222336) (xy 39.01567 -273.22272) (xy 37.61613 -273.22272)
			(xy 37.606 -273.222248) (xy 37.587272 -273.214523) (xy 37.572913 -273.200231) (xy 37.5651 -273.181539)
			(xy 37.564568 -273.171412) (xy 36.267632 -273.171412) (xy 36.255621 -273.189029) (xy 36.219369 -273.2281)
			(xy 36.177698 -273.261331) (xy 36.13154 -273.28798) (xy 36.081926 -273.307452) (xy 36.029964 -273.319312)
			(xy 35.976814 -273.323296) (xy 35.923664 -273.319312) (xy 35.871702 -273.307452) (xy 35.822088 -273.28798)
			(xy 35.77593 -273.261331) (xy 35.734259 -273.2281) (xy 35.698007 -273.189029) (xy 35.667983 -273.144992)
			(xy 35.644857 -273.096971) (xy 35.629147 -273.046041) (xy 35.621204 -272.993337) (xy 34.122624 -272.993337)
			(xy 34.114681 -273.046041) (xy 34.098971 -273.096971) (xy 34.075845 -273.144992) (xy 34.045821 -273.189029)
			(xy 34.009569 -273.2281) (xy 33.967898 -273.261331) (xy 33.92174 -273.28798) (xy 33.872126 -273.307452)
			(xy 33.820164 -273.319312) (xy 33.767014 -273.323296) (xy 33.713864 -273.319312) (xy 33.661902 -273.307452)
			(xy 33.612288 -273.28798) (xy 33.56613 -273.261331) (xy 33.524459 -273.2281) (xy 33.488207 -273.189029)
			(xy 33.458183 -273.144992) (xy 33.435057 -273.096971) (xy 33.419347 -273.046041) (xy 33.411404 -272.993337)
			(xy 32.391858 -272.993337) (xy 32.391858 -274.02155) (xy 34.120836 -274.02155) (xy 34.120836 -273.61261)
			(xy 34.121272 -273.602439) (xy 34.129053 -273.583645) (xy 34.143435 -273.56926) (xy 34.162227 -273.561474)
			(xy 34.172398 -273.561048) (xy 35.571938 -273.561048) (xy 35.579808 -273.561358) (xy 35.594807 -273.566139)
			(xy 35.601402 -273.570446) (xy 35.613129 -273.578052) (xy 35.639547 -273.587152) (xy 35.667444 -273.588732)
			(xy 35.694721 -273.582672) (xy 35.719325 -273.569429) (xy 35.729672 -273.560032) (xy 35.74971 -273.541446)
			(xy 35.794395 -273.509985) (xy 35.843368 -273.48573) (xy 35.895474 -273.469252) (xy 35.949489 -273.46094)
			(xy 35.976814 -273.460464) (xy 36.00346 -273.461019) (xy 36.056158 -273.468964) (xy 36.107083 -273.484674)
			(xy 36.155098 -273.507798) (xy 36.19913 -273.53782) (xy 36.238195 -273.57407) (xy 36.271422 -273.615736)
			(xy 36.298068 -273.66189) (xy 36.317538 -273.711499) (xy 36.329397 -273.763456) (xy 36.333379 -273.8166)
			(xy 36.331384 -273.843221) (xy 36.855136 -273.843221) (xy 36.855136 -273.789923) (xy 36.863079 -273.737219)
			(xy 36.878789 -273.686289) (xy 36.901915 -273.638268) (xy 36.931939 -273.594231) (xy 36.968191 -273.55516)
			(xy 37.009862 -273.521929) (xy 37.05602 -273.49528) (xy 37.105634 -273.475808) (xy 37.157596 -273.463948)
			(xy 37.210746 -273.459965) (xy 37.263896 -273.463948) (xy 37.315858 -273.475808) (xy 37.365472 -273.49528)
			(xy 37.41163 -273.521929) (xy 37.453301 -273.55516) (xy 37.489553 -273.594231) (xy 37.519577 -273.638268)
			(xy 37.542703 -273.686289) (xy 37.558413 -273.737219) (xy 37.566356 -273.789923) (xy 37.566854 -273.816572)
			(xy 37.566356 -273.843221) (xy 37.558413 -273.895925) (xy 37.542703 -273.946855) (xy 37.519577 -273.994876)
			(xy 37.489553 -274.038913) (xy 37.453301 -274.077984) (xy 37.41163 -274.111215) (xy 37.365472 -274.137864)
			(xy 37.315858 -274.157336) (xy 37.263896 -274.169196) (xy 37.210746 -274.17318) (xy 37.157596 -274.169196)
			(xy 37.105634 -274.157336) (xy 37.05602 -274.137864) (xy 37.009862 -274.111215) (xy 36.968191 -274.077984)
			(xy 36.931939 -274.038913) (xy 36.901915 -273.994876) (xy 36.878789 -273.946855) (xy 36.863079 -273.895925)
			(xy 36.855136 -273.843221) (xy 36.331384 -273.843221) (xy 36.329397 -273.869744) (xy 36.317538 -273.921701)
			(xy 36.298068 -273.97131) (xy 36.271422 -274.017464) (xy 36.238195 -274.05913) (xy 36.19913 -274.09538)
			(xy 36.155098 -274.125402) (xy 36.107083 -274.148526) (xy 36.056158 -274.164236) (xy 36.00346 -274.172181)
			(xy 35.976814 -274.17268) (xy 35.949551 -274.172184) (xy 35.895662 -274.163866) (xy 35.843674 -274.147424)
			(xy 35.794802 -274.123243) (xy 35.750193 -274.091888) (xy 35.73018 -274.073366) (xy 35.719729 -274.064018)
			(xy 35.694955 -274.050906) (xy 35.667554 -274.045004) (xy 35.63958 -274.046754) (xy 35.613128 -274.056026)
			(xy 35.601402 -274.063714) (xy 35.594793 -274.067993) (xy 35.579804 -274.072787) (xy 35.571938 -274.073112)
			(xy 34.172398 -274.073112) (xy 34.16222 -274.072737) (xy 34.143416 -274.064942) (xy 34.129029 -274.050541)
			(xy 34.121253 -274.031728) (xy 34.120836 -274.02155) (xy 32.391858 -274.02155) (xy 32.391858 -274.871434)
			(xy 34.120836 -274.871434) (xy 34.120836 -274.462494) (xy 34.121329 -274.452336) (xy 34.129105 -274.433567)
			(xy 34.143471 -274.419202) (xy 34.16224 -274.411428) (xy 34.172398 -274.410932) (xy 35.571938 -274.410932)
			(xy 35.579808 -274.411245) (xy 35.594807 -274.416025) (xy 35.601402 -274.42033) (xy 35.613163 -274.427918)
			(xy 35.639599 -274.437068) (xy 35.667527 -274.438708) (xy 35.694853 -274.432716) (xy 35.719531 -274.41954)
			(xy 35.729926 -274.41017) (xy 35.749923 -274.391578) (xy 35.794573 -274.360152) (xy 35.843499 -274.335915)
			(xy 35.895553 -274.319434) (xy 35.949514 -274.311097) (xy 35.976814 -274.310602) (xy 36.003463 -274.311081)
			(xy 36.056167 -274.319026) (xy 36.107097 -274.334738) (xy 36.155117 -274.357865) (xy 36.199154 -274.38789)
			(xy 36.238224 -274.424143) (xy 36.271454 -274.465815) (xy 36.298103 -274.511973) (xy 36.317575 -274.561588)
			(xy 36.329435 -274.61355) (xy 36.333418 -274.6667) (xy 36.329435 -274.71985) (xy 36.317575 -274.771812)
			(xy 36.298103 -274.821427) (xy 36.271454 -274.867585) (xy 36.268385 -274.871434) (xy 37.564568 -274.871434)
			(xy 37.564568 -274.462494) (xy 37.56496 -274.452318) (xy 37.572752 -274.433518) (xy 37.587148 -274.419132)
			(xy 37.605954 -274.411353) (xy 37.61613 -274.410932) (xy 39.01567 -274.410932) (xy 39.025839 -274.411388)
			(xy 39.044632 -274.419162) (xy 39.059017 -274.433538) (xy 39.066804 -274.452325) (xy 39.067232 -274.462494)
			(xy 39.067232 -274.871434) (xy 39.066794 -274.881598) (xy 39.059003 -274.900373) (xy 39.04462 -274.914738)
			(xy 39.025834 -274.922506) (xy 39.01567 -274.922996) (xy 37.61613 -274.922996) (xy 37.605978 -274.922443)
			(xy 37.587216 -274.914685) (xy 37.572851 -274.900337) (xy 37.565069 -274.881585) (xy 37.564568 -274.871434)
			(xy 36.268385 -274.871434) (xy 36.238224 -274.909257) (xy 36.199154 -274.94551) (xy 36.155117 -274.975535)
			(xy 36.107097 -274.998662) (xy 36.056167 -275.014374) (xy 36.003463 -275.022319) (xy 35.976814 -275.022818)
			(xy 35.949551 -275.022311) (xy 35.895664 -275.013995) (xy 35.843676 -274.997555) (xy 35.794804 -274.973376)
			(xy 35.750194 -274.942024) (xy 35.73018 -274.923504) (xy 35.719773 -274.914084) (xy 35.695028 -274.900854)
			(xy 35.667614 -274.894873) (xy 35.639607 -274.896593) (xy 35.61313 -274.905885) (xy 35.601402 -274.913598)
			(xy 35.594792 -274.917876) (xy 35.579804 -274.92267) (xy 35.571938 -274.922996) (xy 34.172398 -274.922996)
			(xy 34.162244 -274.922469) (xy 34.143482 -274.9147) (xy 34.129118 -274.900345) (xy 34.121337 -274.881587)
			(xy 34.120836 -274.871434) (xy 32.391858 -274.871434) (xy 32.391858 -275.543243) (xy 33.411404 -275.543243)
			(xy 33.411404 -275.489945) (xy 33.419347 -275.437241) (xy 33.435057 -275.386311) (xy 33.458183 -275.33829)
			(xy 33.488207 -275.294253) (xy 33.524459 -275.255182) (xy 33.56613 -275.221951) (xy 33.612288 -275.195302)
			(xy 33.661902 -275.17583) (xy 33.713864 -275.16397) (xy 33.767014 -275.159987) (xy 33.820164 -275.16397)
			(xy 33.872126 -275.17583) (xy 33.92174 -275.195302) (xy 33.967898 -275.221951) (xy 34.009569 -275.255182)
			(xy 34.045821 -275.294253) (xy 34.075845 -275.33829) (xy 34.098971 -275.386311) (xy 34.114681 -275.437241)
			(xy 34.122624 -275.489945) (xy 34.123122 -275.516594) (xy 34.122624 -275.543243) (xy 35.621204 -275.543243)
			(xy 35.621204 -275.489945) (xy 35.629147 -275.437241) (xy 35.644857 -275.386311) (xy 35.667983 -275.33829)
			(xy 35.698007 -275.294253) (xy 35.734259 -275.255182) (xy 35.77593 -275.221951) (xy 35.822088 -275.195302)
			(xy 35.871702 -275.17583) (xy 35.923664 -275.16397) (xy 35.976814 -275.159987) (xy 36.029964 -275.16397)
			(xy 36.081926 -275.17583) (xy 36.13154 -275.195302) (xy 36.177698 -275.221951) (xy 36.219369 -275.255182)
			(xy 36.255621 -275.294253) (xy 36.285645 -275.33829) (xy 36.308771 -275.386311) (xy 36.324481 -275.437241)
			(xy 36.332424 -275.489945) (xy 36.332922 -275.516594) (xy 36.332424 -275.543243) (xy 36.324481 -275.595947)
			(xy 36.308771 -275.646877) (xy 36.285645 -275.694898) (xy 36.267632 -275.721318) (xy 37.564568 -275.721318)
			(xy 37.564568 -275.312378) (xy 37.564947 -275.302201) (xy 37.572745 -275.2834) (xy 37.587144 -275.269015)
			(xy 37.605953 -275.261237) (xy 37.61613 -275.260816) (xy 39.01567 -275.260816) (xy 39.025837 -275.261288)
			(xy 39.044627 -275.269059) (xy 39.059012 -275.28343) (xy 39.066802 -275.302212) (xy 39.067232 -275.312378)
			(xy 39.067232 -275.721318) (xy 39.06685 -275.731494) (xy 39.059053 -275.750295) (xy 39.044655 -275.76468)
			(xy 39.025847 -275.772459) (xy 39.01567 -275.77288) (xy 37.61613 -275.77288) (xy 37.605963 -275.772412)
			(xy 37.587172 -275.76464) (xy 37.572787 -275.750268) (xy 37.564998 -275.731485) (xy 37.564568 -275.721318)
			(xy 36.267632 -275.721318) (xy 36.255621 -275.738935) (xy 36.219369 -275.778006) (xy 36.177698 -275.811237)
			(xy 36.13154 -275.837886) (xy 36.081926 -275.857358) (xy 36.029964 -275.869218) (xy 35.976814 -275.873202)
			(xy 35.923664 -275.869218) (xy 35.871702 -275.857358) (xy 35.822088 -275.837886) (xy 35.77593 -275.811237)
			(xy 35.734259 -275.778006) (xy 35.698007 -275.738935) (xy 35.667983 -275.694898) (xy 35.644857 -275.646877)
			(xy 35.629147 -275.595947) (xy 35.621204 -275.543243) (xy 34.122624 -275.543243) (xy 34.114681 -275.595947)
			(xy 34.098971 -275.646877) (xy 34.075845 -275.694898) (xy 34.045821 -275.738935) (xy 34.009569 -275.778006)
			(xy 33.967898 -275.811237) (xy 33.92174 -275.837886) (xy 33.872126 -275.857358) (xy 33.820164 -275.869218)
			(xy 33.767014 -275.873202) (xy 33.713864 -275.869218) (xy 33.661902 -275.857358) (xy 33.612288 -275.837886)
			(xy 33.56613 -275.811237) (xy 33.524459 -275.778006) (xy 33.488207 -275.738935) (xy 33.458183 -275.694898)
			(xy 33.435057 -275.646877) (xy 33.419347 -275.595947) (xy 33.411404 -275.543243) (xy 32.391858 -275.543243)
			(xy 32.391858 -276.571456) (xy 34.120836 -276.571456) (xy 34.120836 -276.162516) (xy 34.121235 -276.152358)
			(xy 34.129032 -276.133599) (xy 34.143437 -276.119274) (xy 34.162238 -276.11158) (xy 34.172398 -276.111208)
			(xy 35.571938 -276.111208) (xy 35.57979 -276.111456) (xy 35.594787 -276.116112) (xy 35.601402 -276.120352)
			(xy 35.613164 -276.127937) (xy 35.639601 -276.137084) (xy 35.667527 -276.138724) (xy 35.694852 -276.132733)
			(xy 35.71953 -276.11956) (xy 35.729926 -276.110192) (xy 35.749926 -276.091604) (xy 35.794575 -276.060177)
			(xy 35.843501 -276.035939) (xy 35.895554 -276.019457) (xy 35.949514 -276.01112) (xy 35.976814 -276.010624)
			(xy 36.003465 -276.011059) (xy 36.056171 -276.019005) (xy 36.107105 -276.034718) (xy 36.155128 -276.057846)
			(xy 36.199167 -276.087873) (xy 36.23824 -276.124128) (xy 36.271472 -276.165802) (xy 36.298123 -276.211964)
			(xy 36.317596 -276.261581) (xy 36.329456 -276.313547) (xy 36.33344 -276.3667) (xy 36.33144 -276.393381)
			(xy 36.855136 -276.393381) (xy 36.855136 -276.340083) (xy 36.863079 -276.287379) (xy 36.878789 -276.236449)
			(xy 36.901915 -276.188428) (xy 36.931939 -276.144391) (xy 36.968191 -276.10532) (xy 37.009862 -276.072089)
			(xy 37.05602 -276.04544) (xy 37.105634 -276.025968) (xy 37.157596 -276.014108) (xy 37.210746 -276.010125)
			(xy 37.263896 -276.014108) (xy 37.315858 -276.025968) (xy 37.365472 -276.04544) (xy 37.41163 -276.072089)
			(xy 37.453301 -276.10532) (xy 37.489553 -276.144391) (xy 37.519577 -276.188428) (xy 37.542703 -276.236449)
			(xy 37.558413 -276.287379) (xy 37.566356 -276.340083) (xy 37.566854 -276.366732) (xy 37.566356 -276.393381)
			(xy 37.558413 -276.446085) (xy 37.542703 -276.497015) (xy 37.519577 -276.545036) (xy 37.489553 -276.589073)
			(xy 37.453301 -276.628144) (xy 37.41163 -276.661375) (xy 37.365472 -276.688024) (xy 37.315858 -276.707496)
			(xy 37.263896 -276.719356) (xy 37.210746 -276.72334) (xy 37.157596 -276.719356) (xy 37.105634 -276.707496)
			(xy 37.05602 -276.688024) (xy 37.009862 -276.661375) (xy 36.968191 -276.628144) (xy 36.931939 -276.589073)
			(xy 36.901915 -276.545036) (xy 36.878789 -276.497015) (xy 36.863079 -276.446085) (xy 36.855136 -276.393381)
			(xy 36.33144 -276.393381) (xy 36.329456 -276.419853) (xy 36.317596 -276.471819) (xy 36.298123 -276.521436)
			(xy 36.271472 -276.567598) (xy 36.23824 -276.609272) (xy 36.199167 -276.645527) (xy 36.155128 -276.675554)
			(xy 36.107105 -276.698682) (xy 36.056171 -276.714395) (xy 36.003465 -276.722341) (xy 35.976814 -276.72284)
			(xy 35.94955 -276.722355) (xy 35.895661 -276.714036) (xy 35.843671 -276.697592) (xy 35.7948 -276.673408)
			(xy 35.750192 -276.642049) (xy 35.73018 -276.623526) (xy 35.719775 -276.614107) (xy 35.695027 -276.600886)
			(xy 35.667614 -276.594909) (xy 35.639609 -276.596628) (xy 35.613132 -276.605912) (xy 35.601402 -276.61362)
			(xy 35.594789 -276.617863) (xy 35.579791 -276.622521) (xy 35.571938 -276.622764) (xy 34.172398 -276.622764)
			(xy 34.162272 -276.622275) (xy 34.143551 -276.614547) (xy 34.129195 -276.600262) (xy 34.121375 -276.58158)
			(xy 34.120836 -276.571456) (xy 32.391858 -276.571456) (xy 32.391858 -277.243265) (xy 33.411404 -277.243265)
			(xy 33.411404 -277.189967) (xy 33.419347 -277.137263) (xy 33.435057 -277.086333) (xy 33.458183 -277.038312)
			(xy 33.488207 -276.994275) (xy 33.524459 -276.955204) (xy 33.56613 -276.921973) (xy 33.612288 -276.895324)
			(xy 33.661902 -276.875852) (xy 33.713864 -276.863992) (xy 33.767014 -276.860009) (xy 33.820164 -276.863992)
			(xy 33.872126 -276.875852) (xy 33.92174 -276.895324) (xy 33.967898 -276.921973) (xy 34.009569 -276.955204)
			(xy 34.045821 -276.994275) (xy 34.075845 -277.038312) (xy 34.098971 -277.086333) (xy 34.114681 -277.137263)
			(xy 34.122624 -277.189967) (xy 34.123122 -277.216616) (xy 34.122624 -277.243265) (xy 35.621204 -277.243265)
			(xy 35.621204 -277.189967) (xy 35.629147 -277.137263) (xy 35.644857 -277.086333) (xy 35.667983 -277.038312)
			(xy 35.698007 -276.994275) (xy 35.734259 -276.955204) (xy 35.77593 -276.921973) (xy 35.822088 -276.895324)
			(xy 35.871702 -276.875852) (xy 35.923664 -276.863992) (xy 35.976814 -276.860009) (xy 36.029964 -276.863992)
			(xy 36.081926 -276.875852) (xy 36.13154 -276.895324) (xy 36.177698 -276.921973) (xy 36.219369 -276.955204)
			(xy 36.255621 -276.994275) (xy 36.285645 -277.038312) (xy 36.308771 -277.086333) (xy 36.324481 -277.137263)
			(xy 36.332424 -277.189967) (xy 36.332922 -277.216616) (xy 36.332424 -277.243265) (xy 36.324481 -277.295969)
			(xy 36.308771 -277.346899) (xy 36.285645 -277.39492) (xy 36.267632 -277.42134) (xy 37.564568 -277.42134)
			(xy 37.564568 -277.0124) (xy 37.565021 -277.00225) (xy 37.572811 -276.983504) (xy 37.587197 -276.969182)
			(xy 37.605978 -276.961476) (xy 37.61613 -276.961092) (xy 39.01567 -276.961092) (xy 39.025789 -276.96165)
			(xy 39.0445 -276.969359) (xy 39.058856 -276.983623) (xy 39.066685 -277.002284) (xy 39.067232 -277.0124)
			(xy 39.067232 -277.42134) (xy 39.066812 -277.431493) (xy 39.059009 -277.45024) (xy 39.044613 -277.464561)
			(xy 39.025825 -277.472265) (xy 39.01567 -277.472648) (xy 37.61613 -277.472648) (xy 37.606004 -277.472149)
			(xy 37.587281 -277.464429) (xy 37.572923 -277.450146) (xy 37.565105 -277.431464) (xy 37.564568 -277.42134)
			(xy 36.267632 -277.42134) (xy 36.255621 -277.438957) (xy 36.219369 -277.478028) (xy 36.177698 -277.511259)
			(xy 36.13154 -277.537908) (xy 36.081926 -277.55738) (xy 36.029964 -277.56924) (xy 35.976814 -277.573224)
			(xy 35.923664 -277.56924) (xy 35.871702 -277.55738) (xy 35.822088 -277.537908) (xy 35.77593 -277.511259)
			(xy 35.734259 -277.478028) (xy 35.698007 -277.438957) (xy 35.667983 -277.39492) (xy 35.644857 -277.346899)
			(xy 35.629147 -277.295969) (xy 35.621204 -277.243265) (xy 34.122624 -277.243265) (xy 34.114681 -277.295969)
			(xy 34.098971 -277.346899) (xy 34.075845 -277.39492) (xy 34.045821 -277.438957) (xy 34.009569 -277.478028)
			(xy 33.967898 -277.511259) (xy 33.92174 -277.537908) (xy 33.872126 -277.55738) (xy 33.820164 -277.56924)
			(xy 33.767014 -277.573224) (xy 33.713864 -277.56924) (xy 33.661902 -277.55738) (xy 33.612288 -277.537908)
			(xy 33.56613 -277.511259) (xy 33.524459 -277.478028) (xy 33.488207 -277.438957) (xy 33.458183 -277.39492)
			(xy 33.435057 -277.346899) (xy 33.419347 -277.295969) (xy 33.411404 -277.243265) (xy 32.391858 -277.243265)
			(xy 32.391858 -278.271478) (xy 34.120836 -278.271478) (xy 34.120836 -277.862538) (xy 34.121295 -277.852369)
			(xy 34.129067 -277.833576) (xy 34.143442 -277.81919) (xy 34.162229 -277.811403) (xy 34.172398 -277.810976)
			(xy 35.571938 -277.810976) (xy 35.579809 -277.811282) (xy 35.594808 -277.816065) (xy 35.601402 -277.820374)
			(xy 35.613166 -277.827955) (xy 35.639602 -277.8371) (xy 35.667527 -277.83874) (xy 35.694851 -277.83275)
			(xy 35.71953 -277.81958) (xy 35.729926 -277.810214) (xy 35.74993 -277.79163) (xy 35.794577 -277.760202)
			(xy 35.843502 -277.735962) (xy 35.895555 -277.71948) (xy 35.949514 -277.711142) (xy 35.976814 -277.710646)
			(xy 36.003459 -277.711237) (xy 36.056154 -277.719181) (xy 36.107076 -277.734891) (xy 36.155089 -277.758014)
			(xy 36.199118 -277.788034) (xy 36.238182 -277.824282) (xy 36.271408 -277.865946) (xy 36.298052 -277.912098)
			(xy 36.317521 -277.961704) (xy 36.329379 -278.013659) (xy 36.333361 -278.0668) (xy 36.331368 -278.093403)
			(xy 36.855136 -278.093403) (xy 36.855136 -278.040105) (xy 36.863079 -277.987401) (xy 36.878789 -277.936471)
			(xy 36.901915 -277.88845) (xy 36.931939 -277.844413) (xy 36.968191 -277.805342) (xy 37.009862 -277.772111)
			(xy 37.05602 -277.745462) (xy 37.105634 -277.72599) (xy 37.157596 -277.71413) (xy 37.210746 -277.710147)
			(xy 37.263896 -277.71413) (xy 37.315858 -277.72599) (xy 37.365472 -277.745462) (xy 37.41163 -277.772111)
			(xy 37.453301 -277.805342) (xy 37.489553 -277.844413) (xy 37.519577 -277.88845) (xy 37.542703 -277.936471)
			(xy 37.558413 -277.987401) (xy 37.566356 -278.040105) (xy 37.566854 -278.066754) (xy 37.566356 -278.093403)
			(xy 37.558413 -278.146107) (xy 37.542703 -278.197037) (xy 37.519577 -278.245058) (xy 37.489553 -278.289095)
			(xy 37.453301 -278.328166) (xy 37.41163 -278.361397) (xy 37.365472 -278.388046) (xy 37.315858 -278.407518)
			(xy 37.263896 -278.419378) (xy 37.210746 -278.423362) (xy 37.157596 -278.419378) (xy 37.105634 -278.407518)
			(xy 37.05602 -278.388046) (xy 37.009862 -278.361397) (xy 36.968191 -278.328166) (xy 36.931939 -278.289095)
			(xy 36.901915 -278.245058) (xy 36.878789 -278.197037) (xy 36.863079 -278.146107) (xy 36.855136 -278.093403)
			(xy 36.331368 -278.093403) (xy 36.329379 -278.119941) (xy 36.317521 -278.171896) (xy 36.298052 -278.221502)
			(xy 36.271408 -278.267654) (xy 36.238182 -278.309318) (xy 36.199118 -278.345566) (xy 36.155089 -278.375586)
			(xy 36.107076 -278.398709) (xy 36.056154 -278.414419) (xy 36.003459 -278.422363) (xy 35.976814 -278.422862)
			(xy 35.94955 -278.422371) (xy 35.895661 -278.414053) (xy 35.843673 -278.39761) (xy 35.794801 -278.373427)
			(xy 35.750192 -278.34207) (xy 35.73018 -278.323548) (xy 35.719774 -278.314129) (xy 35.695028 -278.300905)
			(xy 35.667614 -278.294927) (xy 35.639608 -278.296646) (xy 35.613132 -278.305933) (xy 35.601402 -278.313642)
			(xy 35.594794 -278.317924) (xy 35.579804 -278.322715) (xy 35.571938 -278.32304) (xy 34.172398 -278.32304)
			(xy 34.162224 -278.322637) (xy 34.143425 -278.314847) (xy 34.129039 -278.300455) (xy 34.121258 -278.281653)
			(xy 34.120836 -278.271478) (xy 32.391858 -278.271478) (xy 32.391858 -278.943287) (xy 33.411404 -278.943287)
			(xy 33.411404 -278.889989) (xy 33.419347 -278.837285) (xy 33.435057 -278.786355) (xy 33.458183 -278.738334)
			(xy 33.488207 -278.694297) (xy 33.524459 -278.655226) (xy 33.56613 -278.621995) (xy 33.612288 -278.595346)
			(xy 33.661902 -278.575874) (xy 33.713864 -278.564014) (xy 33.767014 -278.560031) (xy 33.820164 -278.564014)
			(xy 33.872126 -278.575874) (xy 33.92174 -278.595346) (xy 33.967898 -278.621995) (xy 34.009569 -278.655226)
			(xy 34.045821 -278.694297) (xy 34.075845 -278.738334) (xy 34.098971 -278.786355) (xy 34.114681 -278.837285)
			(xy 34.122624 -278.889989) (xy 34.123122 -278.916638) (xy 34.122624 -278.943287) (xy 35.621204 -278.943287)
			(xy 35.621204 -278.889989) (xy 35.629147 -278.837285) (xy 35.644857 -278.786355) (xy 35.667983 -278.738334)
			(xy 35.698007 -278.694297) (xy 35.734259 -278.655226) (xy 35.77593 -278.621995) (xy 35.822088 -278.595346)
			(xy 35.871702 -278.575874) (xy 35.923664 -278.564014) (xy 35.976814 -278.560031) (xy 36.029964 -278.564014)
			(xy 36.081926 -278.575874) (xy 36.13154 -278.595346) (xy 36.177698 -278.621995) (xy 36.219369 -278.655226)
			(xy 36.255621 -278.694297) (xy 36.285645 -278.738334) (xy 36.308771 -278.786355) (xy 36.324481 -278.837285)
			(xy 36.332424 -278.889989) (xy 36.332922 -278.916638) (xy 36.332424 -278.943287) (xy 36.324481 -278.995991)
			(xy 36.308771 -279.046921) (xy 36.285645 -279.094942) (xy 36.267632 -279.121362) (xy 37.564568 -279.121362)
			(xy 37.564568 -278.712422) (xy 37.564983 -278.702248) (xy 37.572766 -278.683448) (xy 37.587155 -278.669062)
			(xy 37.605956 -278.661281) (xy 37.61613 -278.66086) (xy 39.01567 -278.66086) (xy 39.025842 -278.661289)
			(xy 39.044641 -278.669068) (xy 39.059027 -278.683453) (xy 39.066809 -278.70225) (xy 39.067232 -278.712422)
			(xy 39.067232 -279.121362) (xy 39.066804 -279.131535) (xy 39.059026 -279.150334) (xy 39.044641 -279.164722)
			(xy 39.025843 -279.172503) (xy 39.01567 -279.172924) (xy 37.61613 -279.172924) (xy 37.605956 -279.172511)
			(xy 37.587154 -279.164728) (xy 37.572767 -279.150339) (xy 37.564988 -279.131536) (xy 37.564568 -279.121362)
			(xy 36.267632 -279.121362) (xy 36.255621 -279.138979) (xy 36.219369 -279.17805) (xy 36.177698 -279.211281)
			(xy 36.13154 -279.23793) (xy 36.081926 -279.257402) (xy 36.029964 -279.269262) (xy 35.976814 -279.273246)
			(xy 35.923664 -279.269262) (xy 35.871702 -279.257402) (xy 35.822088 -279.23793) (xy 35.77593 -279.211281)
			(xy 35.734259 -279.17805) (xy 35.698007 -279.138979) (xy 35.667983 -279.094942) (xy 35.644857 -279.046921)
			(xy 35.629147 -278.995991) (xy 35.621204 -278.943287) (xy 34.122624 -278.943287) (xy 34.114681 -278.995991)
			(xy 34.098971 -279.046921) (xy 34.075845 -279.094942) (xy 34.045821 -279.138979) (xy 34.009569 -279.17805)
			(xy 33.967898 -279.211281) (xy 33.92174 -279.23793) (xy 33.872126 -279.257402) (xy 33.820164 -279.269262)
			(xy 33.767014 -279.273246) (xy 33.713864 -279.269262) (xy 33.661902 -279.257402) (xy 33.612288 -279.23793)
			(xy 33.56613 -279.211281) (xy 33.524459 -279.17805) (xy 33.488207 -279.138979) (xy 33.458183 -279.094942)
			(xy 33.435057 -279.046921) (xy 33.419347 -278.995991) (xy 33.411404 -278.943287) (xy 32.391858 -278.943287)
			(xy 32.391858 -279.9715) (xy 34.120836 -279.9715) (xy 34.120836 -279.56256) (xy 34.12119 -279.552399)
			(xy 34.129005 -279.533639) (xy 34.143423 -279.519315) (xy 34.162234 -279.511624) (xy 34.172398 -279.511252)
			(xy 35.571938 -279.511252) (xy 35.579791 -279.511493) (xy 35.594788 -279.516154) (xy 35.601402 -279.520396)
			(xy 35.613167 -279.527974) (xy 35.639603 -279.537117) (xy 35.667526 -279.538756) (xy 35.69485 -279.532768)
			(xy 35.719529 -279.5196) (xy 35.729926 -279.510236) (xy 35.749917 -279.491638) (xy 35.79457 -279.460215)
			(xy 35.843498 -279.435979) (xy 35.895552 -279.4195) (xy 35.949513 -279.411163) (xy 35.976814 -279.410668)
			(xy 36.003461 -279.411215) (xy 36.056159 -279.41916) (xy 36.107084 -279.43487) (xy 36.1551 -279.457995)
			(xy 36.199132 -279.488017) (xy 36.238198 -279.524267) (xy 36.271426 -279.565934) (xy 36.298072 -279.612088)
			(xy 36.317542 -279.661698) (xy 36.3294 -279.713655) (xy 36.333383 -279.7668) (xy 36.331388 -279.793425)
			(xy 36.855136 -279.793425) (xy 36.855136 -279.740127) (xy 36.863079 -279.687423) (xy 36.878789 -279.636493)
			(xy 36.901915 -279.588472) (xy 36.931939 -279.544435) (xy 36.968191 -279.505364) (xy 37.009862 -279.472133)
			(xy 37.05602 -279.445484) (xy 37.105634 -279.426012) (xy 37.157596 -279.414152) (xy 37.210746 -279.410169)
			(xy 37.263896 -279.414152) (xy 37.315858 -279.426012) (xy 37.365472 -279.445484) (xy 37.41163 -279.472133)
			(xy 37.453301 -279.505364) (xy 37.489553 -279.544435) (xy 37.519577 -279.588472) (xy 37.542703 -279.636493)
			(xy 37.558413 -279.687423) (xy 37.566356 -279.740127) (xy 37.566854 -279.766776) (xy 37.566356 -279.793425)
			(xy 37.558413 -279.846129) (xy 37.542703 -279.897059) (xy 37.519577 -279.94508) (xy 37.489553 -279.989117)
			(xy 37.453301 -280.028188) (xy 37.41163 -280.061419) (xy 37.365472 -280.088068) (xy 37.315858 -280.10754)
			(xy 37.263896 -280.1194) (xy 37.210746 -280.123384) (xy 37.157596 -280.1194) (xy 37.105634 -280.10754)
			(xy 37.05602 -280.088068) (xy 37.009862 -280.061419) (xy 36.968191 -280.028188) (xy 36.931939 -279.989117)
			(xy 36.901915 -279.94508) (xy 36.878789 -279.897059) (xy 36.863079 -279.846129) (xy 36.855136 -279.793425)
			(xy 36.331388 -279.793425) (xy 36.3294 -279.819945) (xy 36.317542 -279.871902) (xy 36.298072 -279.921512)
			(xy 36.271426 -279.967666) (xy 36.238198 -280.009333) (xy 36.199132 -280.045583) (xy 36.1551 -280.075605)
			(xy 36.107084 -280.09873) (xy 36.056159 -280.11444) (xy 36.003461 -280.122385) (xy 35.976814 -280.122884)
			(xy 35.949551 -280.122387) (xy 35.895662 -280.114069) (xy 35.843674 -280.097628) (xy 35.794802 -280.073446)
			(xy 35.750193 -280.042091) (xy 35.73018 -280.02357) (xy 35.719774 -280.014151) (xy 35.695028 -280.000925)
			(xy 35.667614 -279.994945) (xy 35.639608 -279.996665) (xy 35.613131 -280.005954) (xy 35.601402 -280.013664)
			(xy 35.594786 -280.017902) (xy 35.579791 -280.022564) (xy 35.571938 -280.022808) (xy 34.172398 -280.022808)
			(xy 34.162277 -280.022276) (xy 34.143565 -280.014557) (xy 34.129211 -280.000285) (xy 34.121383 -279.981618)
			(xy 34.120836 -279.9715) (xy 32.391858 -279.9715) (xy 32.391858 -280.643309) (xy 33.411404 -280.643309)
			(xy 33.411404 -280.590011) (xy 33.419347 -280.537307) (xy 33.435057 -280.486377) (xy 33.458183 -280.438356)
			(xy 33.488207 -280.394319) (xy 33.524459 -280.355248) (xy 33.56613 -280.322017) (xy 33.612288 -280.295368)
			(xy 33.661902 -280.275896) (xy 33.713864 -280.264036) (xy 33.767014 -280.260053) (xy 33.820164 -280.264036)
			(xy 33.872126 -280.275896) (xy 33.92174 -280.295368) (xy 33.967898 -280.322017) (xy 34.009569 -280.355248)
			(xy 34.045821 -280.394319) (xy 34.075845 -280.438356) (xy 34.098971 -280.486377) (xy 34.114681 -280.537307)
			(xy 34.122624 -280.590011) (xy 34.123122 -280.61666) (xy 34.122624 -280.643309) (xy 35.621204 -280.643309)
			(xy 35.621204 -280.590011) (xy 35.629147 -280.537307) (xy 35.644857 -280.486377) (xy 35.667983 -280.438356)
			(xy 35.698007 -280.394319) (xy 35.734259 -280.355248) (xy 35.77593 -280.322017) (xy 35.822088 -280.295368)
			(xy 35.871702 -280.275896) (xy 35.923664 -280.264036) (xy 35.976814 -280.260053) (xy 36.029964 -280.264036)
			(xy 36.081926 -280.275896) (xy 36.13154 -280.295368) (xy 36.177698 -280.322017) (xy 36.219369 -280.355248)
			(xy 36.255621 -280.394319) (xy 36.285645 -280.438356) (xy 36.308771 -280.486377) (xy 36.324481 -280.537307)
			(xy 36.332424 -280.590011) (xy 36.332922 -280.61666) (xy 36.332424 -280.643309) (xy 36.324481 -280.696013)
			(xy 36.308771 -280.746943) (xy 36.285645 -280.794964) (xy 36.267632 -280.821384) (xy 37.564568 -280.821384)
			(xy 37.564568 -280.412444) (xy 37.565057 -280.402297) (xy 37.572832 -280.383551) (xy 37.587208 -280.369228)
			(xy 37.605981 -280.361521) (xy 37.61613 -280.361136) (xy 39.01567 -280.361136) (xy 39.025794 -280.361651)
			(xy 39.044514 -280.369368) (xy 39.058871 -280.383646) (xy 39.066692 -280.402322) (xy 39.067232 -280.412444)
			(xy 39.067232 -280.821384) (xy 39.066766 -280.831533) (xy 39.058982 -280.850279) (xy 39.044599 -280.864602)
			(xy 39.025821 -280.872308) (xy 39.01567 -280.872692) (xy 37.61613 -280.872692) (xy 37.606009 -280.87215)
			(xy 37.587295 -280.864438) (xy 37.572938 -280.850169) (xy 37.565112 -280.831502) (xy 37.564568 -280.821384)
			(xy 36.267632 -280.821384) (xy 36.255621 -280.839001) (xy 36.219369 -280.878072) (xy 36.177698 -280.911303)
			(xy 36.13154 -280.937952) (xy 36.081926 -280.957424) (xy 36.029964 -280.969284) (xy 35.976814 -280.973268)
			(xy 35.923664 -280.969284) (xy 35.871702 -280.957424) (xy 35.822088 -280.937952) (xy 35.77593 -280.911303)
			(xy 35.734259 -280.878072) (xy 35.698007 -280.839001) (xy 35.667983 -280.794964) (xy 35.644857 -280.746943)
			(xy 35.629147 -280.696013) (xy 35.621204 -280.643309) (xy 34.122624 -280.643309) (xy 34.114681 -280.696013)
			(xy 34.098971 -280.746943) (xy 34.075845 -280.794964) (xy 34.045821 -280.839001) (xy 34.009569 -280.878072)
			(xy 33.967898 -280.911303) (xy 33.92174 -280.937952) (xy 33.872126 -280.957424) (xy 33.820164 -280.969284)
			(xy 33.767014 -280.973268) (xy 33.713864 -280.969284) (xy 33.661902 -280.957424) (xy 33.612288 -280.937952)
			(xy 33.56613 -280.911303) (xy 33.524459 -280.878072) (xy 33.488207 -280.839001) (xy 33.458183 -280.794964)
			(xy 33.435057 -280.746943) (xy 33.419347 -280.696013) (xy 33.411404 -280.643309) (xy 32.391858 -280.643309)
			(xy 32.391858 -281.671522) (xy 34.120836 -281.671522) (xy 34.120836 -281.262582) (xy 34.121318 -281.252423)
			(xy 34.129098 -281.233654) (xy 34.143467 -281.219289) (xy 34.162239 -281.211515) (xy 34.172398 -281.21102)
			(xy 35.571938 -281.21102) (xy 35.579808 -281.211335) (xy 35.594807 -281.216113) (xy 35.601402 -281.220418)
			(xy 35.613162 -281.228008) (xy 35.639599 -281.237159) (xy 35.667527 -281.238799) (xy 35.694853 -281.232806)
			(xy 35.719532 -281.219629) (xy 35.729926 -281.210258) (xy 35.749921 -281.191664) (xy 35.794572 -281.160239)
			(xy 35.843499 -281.136002) (xy 35.895553 -281.119522) (xy 35.949514 -281.111185) (xy 35.976814 -281.11069)
			(xy 36.003462 -281.111193) (xy 36.056164 -281.119138) (xy 36.107093 -281.134849) (xy 36.155111 -281.157975)
			(xy 36.199146 -281.188) (xy 36.238215 -281.224252) (xy 36.271444 -281.265921) (xy 36.298092 -281.312078)
			(xy 36.317563 -281.361691) (xy 36.329423 -281.413652) (xy 36.333406 -281.4668) (xy 36.331409 -281.493447)
			(xy 36.855136 -281.493447) (xy 36.855136 -281.440149) (xy 36.863079 -281.387445) (xy 36.878789 -281.336515)
			(xy 36.901915 -281.288494) (xy 36.931939 -281.244457) (xy 36.968191 -281.205386) (xy 37.009862 -281.172155)
			(xy 37.05602 -281.145506) (xy 37.105634 -281.126034) (xy 37.157596 -281.114174) (xy 37.210746 -281.110191)
			(xy 37.263896 -281.114174) (xy 37.315858 -281.126034) (xy 37.365472 -281.145506) (xy 37.41163 -281.172155)
			(xy 37.453301 -281.205386) (xy 37.489553 -281.244457) (xy 37.519577 -281.288494) (xy 37.542703 -281.336515)
			(xy 37.558413 -281.387445) (xy 37.566356 -281.440149) (xy 37.566854 -281.466798) (xy 37.566356 -281.493447)
			(xy 37.558413 -281.546151) (xy 37.542703 -281.597081) (xy 37.519577 -281.645102) (xy 37.489553 -281.689139)
			(xy 37.453301 -281.72821) (xy 37.41163 -281.761441) (xy 37.365472 -281.78809) (xy 37.315858 -281.807562)
			(xy 37.263896 -281.819422) (xy 37.210746 -281.823406) (xy 37.157596 -281.819422) (xy 37.105634 -281.807562)
			(xy 37.05602 -281.78809) (xy 37.009862 -281.761441) (xy 36.968191 -281.72821) (xy 36.931939 -281.689139)
			(xy 36.901915 -281.645102) (xy 36.878789 -281.597081) (xy 36.863079 -281.546151) (xy 36.855136 -281.493447)
			(xy 36.331409 -281.493447) (xy 36.329423 -281.519948) (xy 36.317563 -281.571909) (xy 36.298092 -281.621522)
			(xy 36.271444 -281.667679) (xy 36.238215 -281.709348) (xy 36.199146 -281.7456) (xy 36.155111 -281.775625)
			(xy 36.107093 -281.798751) (xy 36.056164 -281.814462) (xy 36.003462 -281.822407) (xy 35.976814 -281.822906)
			(xy 35.949551 -281.822403) (xy 35.895663 -281.814086) (xy 35.843675 -281.797645) (xy 35.794804 -281.773465)
			(xy 35.750193 -281.742112) (xy 35.73018 -281.723592) (xy 35.719773 -281.714172) (xy 35.695028 -281.700944)
			(xy 35.667614 -281.694963) (xy 35.639607 -281.696683) (xy 35.613131 -281.705974) (xy 35.601402 -281.713686)
			(xy 35.594791 -281.717963) (xy 35.579804 -281.722758) (xy 35.571938 -281.723084) (xy 34.172398 -281.723084)
			(xy 34.162243 -281.722569) (xy 34.143478 -281.714798) (xy 34.129113 -281.700439) (xy 34.121335 -281.681677)
			(xy 34.120836 -281.671522) (xy 32.391858 -281.671522) (xy 32.391858 -282.343331) (xy 33.411404 -282.343331)
			(xy 33.411404 -282.290033) (xy 33.419347 -282.237329) (xy 33.435057 -282.186399) (xy 33.458183 -282.138378)
			(xy 33.488207 -282.094341) (xy 33.524459 -282.05527) (xy 33.56613 -282.022039) (xy 33.612288 -281.99539)
			(xy 33.661902 -281.975918) (xy 33.713864 -281.964058) (xy 33.767014 -281.960075) (xy 33.820164 -281.964058)
			(xy 33.872126 -281.975918) (xy 33.92174 -281.99539) (xy 33.967898 -282.022039) (xy 34.009569 -282.05527)
			(xy 34.045821 -282.094341) (xy 34.075845 -282.138378) (xy 34.098971 -282.186399) (xy 34.114681 -282.237329)
			(xy 34.122624 -282.290033) (xy 34.123122 -282.316682) (xy 34.122624 -282.343331) (xy 35.621204 -282.343331)
			(xy 35.621204 -282.290033) (xy 35.629147 -282.237329) (xy 35.644857 -282.186399) (xy 35.667983 -282.138378)
			(xy 35.698007 -282.094341) (xy 35.734259 -282.05527) (xy 35.77593 -282.022039) (xy 35.822088 -281.99539)
			(xy 35.871702 -281.975918) (xy 35.923664 -281.964058) (xy 35.976814 -281.960075) (xy 36.029964 -281.964058)
			(xy 36.081926 -281.975918) (xy 36.13154 -281.99539) (xy 36.177698 -282.022039) (xy 36.219369 -282.05527)
			(xy 36.255621 -282.094341) (xy 36.285645 -282.138378) (xy 36.308771 -282.186399) (xy 36.324481 -282.237329)
			(xy 36.332424 -282.290033) (xy 36.332922 -282.316682) (xy 36.332424 -282.343331) (xy 36.324481 -282.396035)
			(xy 36.308771 -282.446965) (xy 36.285645 -282.494986) (xy 36.267632 -282.521406) (xy 37.564568 -282.521406)
			(xy 37.564568 -282.112466) (xy 37.565006 -282.102302) (xy 37.572797 -282.083527) (xy 37.58718 -282.069162)
			(xy 37.605966 -282.061394) (xy 37.61613 -282.060904) (xy 39.01567 -282.060904) (xy 39.025822 -282.061457)
			(xy 39.044584 -282.069215) (xy 39.058949 -282.083563) (xy 39.066731 -282.102315) (xy 39.067232 -282.112466)
			(xy 39.067232 -282.521406) (xy 39.06684 -282.531582) (xy 39.059048 -282.550382) (xy 39.044652 -282.564768)
			(xy 39.025846 -282.572547) (xy 39.01567 -282.572968) (xy 37.61613 -282.572968) (xy 37.605961 -282.572512)
			(xy 37.587168 -282.564738) (xy 37.572783 -282.550362) (xy 37.564996 -282.531575) (xy 37.564568 -282.521406)
			(xy 36.267632 -282.521406) (xy 36.255621 -282.539023) (xy 36.219369 -282.578094) (xy 36.177698 -282.611325)
			(xy 36.13154 -282.637974) (xy 36.081926 -282.657446) (xy 36.029964 -282.669306) (xy 35.976814 -282.67329)
			(xy 35.923664 -282.669306) (xy 35.871702 -282.657446) (xy 35.822088 -282.637974) (xy 35.77593 -282.611325)
			(xy 35.734259 -282.578094) (xy 35.698007 -282.539023) (xy 35.667983 -282.494986) (xy 35.644857 -282.446965)
			(xy 35.629147 -282.396035) (xy 35.621204 -282.343331) (xy 34.122624 -282.343331) (xy 34.114681 -282.396035)
			(xy 34.098971 -282.446965) (xy 34.075845 -282.494986) (xy 34.045821 -282.539023) (xy 34.009569 -282.578094)
			(xy 33.967898 -282.611325) (xy 33.92174 -282.637974) (xy 33.872126 -282.657446) (xy 33.820164 -282.669306)
			(xy 33.767014 -282.67329) (xy 33.713864 -282.669306) (xy 33.661902 -282.657446) (xy 33.612288 -282.637974)
			(xy 33.56613 -282.611325) (xy 33.524459 -282.578094) (xy 33.488207 -282.539023) (xy 33.458183 -282.494986)
			(xy 33.435057 -282.446965) (xy 33.419347 -282.396035) (xy 33.411404 -282.343331) (xy 32.391858 -282.343331)
			(xy 32.391858 -283.371544) (xy 34.120836 -283.371544) (xy 34.120836 -282.962604) (xy 34.121226 -282.952446)
			(xy 34.129027 -282.933686) (xy 34.143434 -282.919362) (xy 34.162237 -282.911668) (xy 34.172398 -282.911296)
			(xy 35.571938 -282.911296) (xy 35.579792 -282.91153) (xy 35.59479 -282.916194) (xy 35.601402 -282.92044)
			(xy 35.613129 -282.928047) (xy 35.639547 -282.937148) (xy 35.667444 -282.938727) (xy 35.694721 -282.932668)
			(xy 35.719325 -282.919424) (xy 35.729672 -282.910026) (xy 35.749709 -282.891439) (xy 35.794395 -282.859978)
			(xy 35.843367 -282.835724) (xy 35.895474 -282.819246) (xy 35.949489 -282.810934) (xy 35.976814 -282.810458)
			(xy 36.00346 -282.811025) (xy 36.056157 -282.81897) (xy 36.107081 -282.834679) (xy 36.155095 -282.857803)
			(xy 36.199126 -282.887825) (xy 36.238191 -282.924074) (xy 36.271417 -282.96574) (xy 36.298063 -283.011892)
			(xy 36.317532 -283.061501) (xy 36.329391 -283.113457) (xy 36.333373 -283.1666) (xy 36.331379 -283.193215)
			(xy 36.855136 -283.193215) (xy 36.855136 -283.139917) (xy 36.863079 -283.087213) (xy 36.878789 -283.036283)
			(xy 36.901915 -282.988262) (xy 36.931939 -282.944225) (xy 36.968191 -282.905154) (xy 37.009862 -282.871923)
			(xy 37.05602 -282.845274) (xy 37.105634 -282.825802) (xy 37.157596 -282.813942) (xy 37.210746 -282.809959)
			(xy 37.263896 -282.813942) (xy 37.315858 -282.825802) (xy 37.365472 -282.845274) (xy 37.41163 -282.871923)
			(xy 37.453301 -282.905154) (xy 37.489553 -282.944225) (xy 37.519577 -282.988262) (xy 37.542703 -283.036283)
			(xy 37.558413 -283.087213) (xy 37.566356 -283.139917) (xy 37.566854 -283.166566) (xy 37.566356 -283.193215)
			(xy 37.558413 -283.245919) (xy 37.542703 -283.296849) (xy 37.519577 -283.34487) (xy 37.489553 -283.388907)
			(xy 37.453301 -283.427978) (xy 37.41163 -283.461209) (xy 37.365472 -283.487858) (xy 37.315858 -283.50733)
			(xy 37.263896 -283.51919) (xy 37.210746 -283.523174) (xy 37.157596 -283.51919) (xy 37.105634 -283.50733)
			(xy 37.05602 -283.487858) (xy 37.009862 -283.461209) (xy 36.968191 -283.427978) (xy 36.931939 -283.388907)
			(xy 36.901915 -283.34487) (xy 36.878789 -283.296849) (xy 36.863079 -283.245919) (xy 36.855136 -283.193215)
			(xy 36.331379 -283.193215) (xy 36.329391 -283.219743) (xy 36.317532 -283.271699) (xy 36.298063 -283.321308)
			(xy 36.271417 -283.36746) (xy 36.238191 -283.409126) (xy 36.199126 -283.445375) (xy 36.155095 -283.475397)
			(xy 36.107081 -283.498521) (xy 36.056157 -283.51423) (xy 36.00346 -283.522175) (xy 35.976814 -283.522674)
			(xy 35.949551 -283.522179) (xy 35.895662 -283.513862) (xy 35.843673 -283.49742) (xy 35.794802 -283.473238)
			(xy 35.750193 -283.441882) (xy 35.73018 -283.42336) (xy 35.719729 -283.414012) (xy 35.694955 -283.400901)
			(xy 35.667554 -283.394999) (xy 35.63958 -283.396749) (xy 35.613128 -283.40602) (xy 35.601402 -283.413708)
			(xy 35.594788 -283.41795) (xy 35.579791 -283.422609) (xy 35.571938 -283.422852) (xy 34.172398 -283.422852)
			(xy 34.16227 -283.422375) (xy 34.143548 -283.414645) (xy 34.129191 -283.400356) (xy 34.121373 -283.381669)
			(xy 34.120836 -283.371544) (xy 32.391858 -283.371544) (xy 32.391858 -284.221428) (xy 34.120836 -284.221428)
			(xy 34.120836 -283.812488) (xy 34.121212 -283.802329) (xy 34.129019 -283.783569) (xy 34.14343 -283.769245)
			(xy 34.162236 -283.761552) (xy 34.172398 -283.76118) (xy 35.571938 -283.76118) (xy 35.579792 -283.761416)
			(xy 35.594789 -283.76608) (xy 35.601402 -283.770324) (xy 35.613162 -283.777913) (xy 35.639599 -283.787063)
			(xy 35.667527 -283.788703) (xy 35.694853 -283.782711) (xy 35.719531 -283.769534) (xy 35.729926 -283.760164)
			(xy 35.749922 -283.741571) (xy 35.794573 -283.710146) (xy 35.843499 -283.685909) (xy 35.895553 -283.669428)
			(xy 35.949514 -283.661091) (xy 35.976814 -283.660596) (xy 36.003463 -283.661087) (xy 36.056165 -283.669032)
			(xy 36.107095 -283.684744) (xy 36.155114 -283.70787) (xy 36.19915 -283.737895) (xy 36.238219 -283.774147)
			(xy 36.271449 -283.815818) (xy 36.298098 -283.861976) (xy 36.317569 -283.911589) (xy 36.329429 -283.963551)
			(xy 36.333412 -284.0167) (xy 36.329429 -284.069849) (xy 36.317569 -284.121811) (xy 36.298098 -284.171424)
			(xy 36.271449 -284.217582) (xy 36.268382 -284.221428) (xy 37.564568 -284.221428) (xy 37.564568 -283.812488)
			(xy 37.565011 -283.802337) (xy 37.572804 -283.78359) (xy 37.587194 -283.769269) (xy 37.605977 -283.761564)
			(xy 37.61613 -283.76118) (xy 39.01567 -283.76118) (xy 39.0258 -283.761652) (xy 39.044528 -283.769377)
			(xy 39.058887 -283.783669) (xy 39.0667 -283.802361) (xy 39.067232 -283.812488) (xy 39.067232 -284.221428)
			(xy 39.066802 -284.23158) (xy 39.059003 -284.250327) (xy 39.04461 -284.264648) (xy 39.025824 -284.272353)
			(xy 39.01567 -284.272736) (xy 37.61613 -284.272736) (xy 37.606002 -284.272248) (xy 37.587277 -284.264526)
			(xy 37.572919 -284.250239) (xy 37.565103 -284.231553) (xy 37.564568 -284.221428) (xy 36.268382 -284.221428)
			(xy 36.238219 -284.259253) (xy 36.19915 -284.295505) (xy 36.155114 -284.32553) (xy 36.107095 -284.348656)
			(xy 36.056165 -284.364368) (xy 36.003463 -284.372313) (xy 35.976814 -284.372812) (xy 35.949551 -284.372307)
			(xy 35.895663 -284.36399) (xy 35.843675 -284.34755) (xy 35.794804 -284.32337) (xy 35.750194 -284.292018)
			(xy 35.73018 -284.273498) (xy 35.719773 -284.264078) (xy 35.695028 -284.250849) (xy 35.667614 -284.244868)
			(xy 35.639607 -284.246588) (xy 35.61313 -284.25588) (xy 35.601402 -284.263592) (xy 35.594787 -284.267833)
			(xy 35.579791 -284.272492) (xy 35.571938 -284.272736) (xy 34.172398 -284.272736) (xy 34.162268 -284.272274)
			(xy 34.143543 -284.264541) (xy 34.129185 -284.250247) (xy 34.121371 -284.231556) (xy 34.120836 -284.221428)
			(xy 32.391858 -284.221428) (xy 32.391858 -284.893237) (xy 33.411404 -284.893237) (xy 33.411404 -284.839939)
			(xy 33.419347 -284.787235) (xy 33.435057 -284.736305) (xy 33.458183 -284.688284) (xy 33.488207 -284.644247)
			(xy 33.524459 -284.605176) (xy 33.56613 -284.571945) (xy 33.612288 -284.545296) (xy 33.661902 -284.525824)
			(xy 33.713864 -284.513964) (xy 33.767014 -284.509981) (xy 33.820164 -284.513964) (xy 33.872126 -284.525824)
			(xy 33.92174 -284.545296) (xy 33.967898 -284.571945) (xy 34.009569 -284.605176) (xy 34.045821 -284.644247)
			(xy 34.075845 -284.688284) (xy 34.098971 -284.736305) (xy 34.114681 -284.787235) (xy 34.122624 -284.839939)
			(xy 34.123122 -284.866588) (xy 34.122624 -284.893237) (xy 35.621204 -284.893237) (xy 35.621204 -284.839939)
			(xy 35.629147 -284.787235) (xy 35.644857 -284.736305) (xy 35.667983 -284.688284) (xy 35.698007 -284.644247)
			(xy 35.734259 -284.605176) (xy 35.77593 -284.571945) (xy 35.822088 -284.545296) (xy 35.871702 -284.525824)
			(xy 35.923664 -284.513964) (xy 35.976814 -284.509981) (xy 36.029964 -284.513964) (xy 36.081926 -284.525824)
			(xy 36.13154 -284.545296) (xy 36.177698 -284.571945) (xy 36.219369 -284.605176) (xy 36.255621 -284.644247)
			(xy 36.285645 -284.688284) (xy 36.308771 -284.736305) (xy 36.324481 -284.787235) (xy 36.332424 -284.839939)
			(xy 36.332922 -284.866588) (xy 36.332424 -284.893237) (xy 36.324481 -284.945941) (xy 36.308771 -284.996871)
			(xy 36.285645 -285.044892) (xy 36.267632 -285.071312) (xy 37.564568 -285.071312) (xy 37.564568 -284.662372)
			(xy 37.564998 -284.65222) (xy 37.572797 -284.633473) (xy 37.58719 -284.619152) (xy 37.605976 -284.611447)
			(xy 37.61613 -284.611064) (xy 39.01567 -284.611064) (xy 39.025798 -284.611552) (xy 39.044523 -284.619274)
			(xy 39.058881 -284.633561) (xy 39.066697 -284.652247) (xy 39.067232 -284.662372) (xy 39.067232 -285.071312)
			(xy 39.066789 -285.081463) (xy 39.058996 -285.10021) (xy 39.044606 -285.114531) (xy 39.025823 -285.122236)
			(xy 39.01567 -285.12262) (xy 37.61613 -285.12262) (xy 37.606 -285.122148) (xy 37.587272 -285.114423)
			(xy 37.572913 -285.100131) (xy 37.5651 -285.081439) (xy 37.564568 -285.071312) (xy 36.267632 -285.071312)
			(xy 36.255621 -285.088929) (xy 36.219369 -285.128) (xy 36.177698 -285.161231) (xy 36.13154 -285.18788)
			(xy 36.081926 -285.207352) (xy 36.029964 -285.219212) (xy 35.976814 -285.223196) (xy 35.923664 -285.219212)
			(xy 35.871702 -285.207352) (xy 35.822088 -285.18788) (xy 35.77593 -285.161231) (xy 35.734259 -285.128)
			(xy 35.698007 -285.088929) (xy 35.667983 -285.044892) (xy 35.644857 -284.996871) (xy 35.629147 -284.945941)
			(xy 35.621204 -284.893237) (xy 34.122624 -284.893237) (xy 34.114681 -284.945941) (xy 34.098971 -284.996871)
			(xy 34.075845 -285.044892) (xy 34.045821 -285.088929) (xy 34.009569 -285.128) (xy 33.967898 -285.161231)
			(xy 33.92174 -285.18788) (xy 33.872126 -285.207352) (xy 33.820164 -285.219212) (xy 33.767014 -285.223196)
			(xy 33.713864 -285.219212) (xy 33.661902 -285.207352) (xy 33.612288 -285.18788) (xy 33.56613 -285.161231)
			(xy 33.524459 -285.128) (xy 33.488207 -285.088929) (xy 33.458183 -285.044892) (xy 33.435057 -284.996871)
			(xy 33.419347 -284.945941) (xy 33.411404 -284.893237) (xy 32.391858 -284.893237) (xy 32.391858 -285.92145)
			(xy 34.120836 -285.92145) (xy 34.120836 -285.51251) (xy 34.121272 -285.502339) (xy 34.129053 -285.483545)
			(xy 34.143435 -285.46916) (xy 34.162227 -285.461374) (xy 34.172398 -285.460948) (xy 35.571938 -285.460948)
			(xy 35.579808 -285.461258) (xy 35.594807 -285.466039) (xy 35.601402 -285.470346) (xy 35.613164 -285.477932)
			(xy 35.6396 -285.48708) (xy 35.667527 -285.488719) (xy 35.694852 -285.482728) (xy 35.719531 -285.469555)
			(xy 35.729926 -285.460186) (xy 35.749925 -285.441597) (xy 35.794575 -285.41017) (xy 35.8435 -285.385932)
			(xy 35.895554 -285.369451) (xy 35.949514 -285.361114) (xy 35.976814 -285.360618) (xy 36.003465 -285.361065)
			(xy 36.05617 -285.369011) (xy 36.107103 -285.384723) (xy 36.155125 -285.407851) (xy 36.199164 -285.437878)
			(xy 36.238235 -285.474133) (xy 36.271467 -285.515806) (xy 36.298117 -285.561966) (xy 36.31759 -285.611583)
			(xy 36.32945 -285.663548) (xy 36.333434 -285.7167) (xy 36.331435 -285.743375) (xy 36.855136 -285.743375)
			(xy 36.855136 -285.690077) (xy 36.863079 -285.637373) (xy 36.878789 -285.586443) (xy 36.901915 -285.538422)
			(xy 36.931939 -285.494385) (xy 36.968191 -285.455314) (xy 37.009862 -285.422083) (xy 37.05602 -285.395434)
			(xy 37.105634 -285.375962) (xy 37.157596 -285.364102) (xy 37.210746 -285.360119) (xy 37.263896 -285.364102)
			(xy 37.315858 -285.375962) (xy 37.365472 -285.395434) (xy 37.41163 -285.422083) (xy 37.453301 -285.455314)
			(xy 37.489553 -285.494385) (xy 37.519577 -285.538422) (xy 37.542703 -285.586443) (xy 37.558413 -285.637373)
			(xy 37.566356 -285.690077) (xy 37.566854 -285.716726) (xy 37.566356 -285.743375) (xy 37.558413 -285.796079)
			(xy 37.542703 -285.847009) (xy 37.519577 -285.89503) (xy 37.489553 -285.939067) (xy 37.453301 -285.978138)
			(xy 37.41163 -286.011369) (xy 37.365472 -286.038018) (xy 37.315858 -286.05749) (xy 37.263896 -286.06935)
			(xy 37.210746 -286.073334) (xy 37.157596 -286.06935) (xy 37.105634 -286.05749) (xy 37.05602 -286.038018)
			(xy 37.009862 -286.011369) (xy 36.968191 -285.978138) (xy 36.931939 -285.939067) (xy 36.901915 -285.89503)
			(xy 36.878789 -285.847009) (xy 36.863079 -285.796079) (xy 36.855136 -285.743375) (xy 36.331435 -285.743375)
			(xy 36.32945 -285.769852) (xy 36.31759 -285.821817) (xy 36.298117 -285.871434) (xy 36.271467 -285.917594)
			(xy 36.238235 -285.959267) (xy 36.199164 -285.995522) (xy 36.155125 -286.025549) (xy 36.107103 -286.048677)
			(xy 36.05617 -286.064389) (xy 36.003465 -286.072335) (xy 35.976814 -286.072834) (xy 35.94955 -286.07235)
			(xy 35.89566 -286.064032) (xy 35.843671 -286.047588) (xy 35.7948 -286.023403) (xy 35.750192 -285.992044)
			(xy 35.73018 -285.97352) (xy 35.719775 -285.964101) (xy 35.695027 -285.950881) (xy 35.667614 -285.944904)
			(xy 35.639609 -285.946623) (xy 35.613132 -285.955907) (xy 35.601402 -285.963614) (xy 35.594793 -285.967893)
			(xy 35.579804 -285.972687) (xy 35.571938 -285.973012) (xy 34.172398 -285.973012) (xy 34.16222 -285.972637)
			(xy 34.143416 -285.964842) (xy 34.129029 -285.950441) (xy 34.121253 -285.931628) (xy 34.120836 -285.92145)
			(xy 32.391858 -285.92145) (xy 32.391858 -286.593259) (xy 33.411404 -286.593259) (xy 33.411404 -286.539961)
			(xy 33.419347 -286.487257) (xy 33.435057 -286.436327) (xy 33.458183 -286.388306) (xy 33.488207 -286.344269)
			(xy 33.524459 -286.305198) (xy 33.56613 -286.271967) (xy 33.612288 -286.245318) (xy 33.661902 -286.225846)
			(xy 33.713864 -286.213986) (xy 33.767014 -286.210003) (xy 33.820164 -286.213986) (xy 33.872126 -286.225846)
			(xy 33.92174 -286.245318) (xy 33.967898 -286.271967) (xy 34.009569 -286.305198) (xy 34.045821 -286.344269)
			(xy 34.075845 -286.388306) (xy 34.098971 -286.436327) (xy 34.114681 -286.487257) (xy 34.122624 -286.539961)
			(xy 34.123122 -286.56661) (xy 34.122624 -286.593259) (xy 35.621204 -286.593259) (xy 35.621204 -286.539961)
			(xy 35.629147 -286.487257) (xy 35.644857 -286.436327) (xy 35.667983 -286.388306) (xy 35.698007 -286.344269)
			(xy 35.734259 -286.305198) (xy 35.77593 -286.271967) (xy 35.822088 -286.245318) (xy 35.871702 -286.225846)
			(xy 35.923664 -286.213986) (xy 35.976814 -286.210003) (xy 36.029964 -286.213986) (xy 36.081926 -286.225846)
			(xy 36.13154 -286.245318) (xy 36.177698 -286.271967) (xy 36.219369 -286.305198) (xy 36.255621 -286.344269)
			(xy 36.285645 -286.388306) (xy 36.308771 -286.436327) (xy 36.324481 -286.487257) (xy 36.332424 -286.539961)
			(xy 36.332922 -286.56661) (xy 36.332424 -286.593259) (xy 36.324481 -286.645963) (xy 36.308771 -286.696893)
			(xy 36.285645 -286.744914) (xy 36.267632 -286.771334) (xy 37.564568 -286.771334) (xy 37.564568 -286.362394)
			(xy 37.56496 -286.352218) (xy 37.572752 -286.333418) (xy 37.587148 -286.319032) (xy 37.605954 -286.311253)
			(xy 37.61613 -286.310832) (xy 39.01567 -286.310832) (xy 39.025839 -286.311288) (xy 39.044632 -286.319062)
			(xy 39.059017 -286.333438) (xy 39.066804 -286.352225) (xy 39.067232 -286.362394) (xy 39.067232 -286.771334)
			(xy 39.066794 -286.781498) (xy 39.059003 -286.800273) (xy 39.04462 -286.814638) (xy 39.025834 -286.822406)
			(xy 39.01567 -286.822896) (xy 37.61613 -286.822896) (xy 37.605978 -286.822343) (xy 37.587216 -286.814585)
			(xy 37.572851 -286.800237) (xy 37.565069 -286.781485) (xy 37.564568 -286.771334) (xy 36.267632 -286.771334)
			(xy 36.255621 -286.788951) (xy 36.219369 -286.828022) (xy 36.177698 -286.861253) (xy 36.13154 -286.887902)
			(xy 36.081926 -286.907374) (xy 36.029964 -286.919234) (xy 35.976814 -286.923218) (xy 35.923664 -286.919234)
			(xy 35.871702 -286.907374) (xy 35.822088 -286.887902) (xy 35.77593 -286.861253) (xy 35.734259 -286.828022)
			(xy 35.698007 -286.788951) (xy 35.667983 -286.744914) (xy 35.644857 -286.696893) (xy 35.629147 -286.645963)
			(xy 35.621204 -286.593259) (xy 34.122624 -286.593259) (xy 34.114681 -286.645963) (xy 34.098971 -286.696893)
			(xy 34.075845 -286.744914) (xy 34.045821 -286.788951) (xy 34.009569 -286.828022) (xy 33.967898 -286.861253)
			(xy 33.92174 -286.887902) (xy 33.872126 -286.907374) (xy 33.820164 -286.919234) (xy 33.767014 -286.923218)
			(xy 33.713864 -286.919234) (xy 33.661902 -286.907374) (xy 33.612288 -286.887902) (xy 33.56613 -286.861253)
			(xy 33.524459 -286.828022) (xy 33.488207 -286.788951) (xy 33.458183 -286.744914) (xy 33.435057 -286.696893)
			(xy 33.419347 -286.645963) (xy 33.411404 -286.593259) (xy 32.391858 -286.593259) (xy 32.391858 -287.621472)
			(xy 34.120836 -287.621472) (xy 34.120836 -287.212532) (xy 34.121248 -287.202375) (xy 34.12904 -287.183617)
			(xy 34.14344 -287.169291) (xy 34.162239 -287.161596) (xy 34.172398 -287.161224) (xy 35.571938 -287.161224)
			(xy 35.579791 -287.161469) (xy 35.594788 -287.166127) (xy 35.601402 -287.170368) (xy 35.613165 -287.17795)
			(xy 35.639601 -287.187096) (xy 35.667527 -287.188735) (xy 35.694851 -287.182746) (xy 35.71953 -287.169575)
			(xy 35.729926 -287.160208) (xy 35.749929 -287.141623) (xy 35.794577 -287.110195) (xy 35.843502 -287.085956)
			(xy 35.895554 -287.069474) (xy 35.949514 -287.061136) (xy 35.976814 -287.06064) (xy 36.003466 -287.061043)
			(xy 36.056175 -287.068989) (xy 36.107111 -287.084703) (xy 36.155136 -287.107832) (xy 36.199177 -287.13786)
			(xy 36.238252 -287.174118) (xy 36.271486 -287.215793) (xy 36.298137 -287.261957) (xy 36.317611 -287.311576)
			(xy 36.329472 -287.363545) (xy 36.333456 -287.4167) (xy 36.331455 -287.443397) (xy 36.855136 -287.443397)
			(xy 36.855136 -287.390099) (xy 36.863079 -287.337395) (xy 36.878789 -287.286465) (xy 36.901915 -287.238444)
			(xy 36.931939 -287.194407) (xy 36.968191 -287.155336) (xy 37.009862 -287.122105) (xy 37.05602 -287.095456)
			(xy 37.105634 -287.075984) (xy 37.157596 -287.064124) (xy 37.210746 -287.060141) (xy 37.263896 -287.064124)
			(xy 37.315858 -287.075984) (xy 37.365472 -287.095456) (xy 37.41163 -287.122105) (xy 37.453301 -287.155336)
			(xy 37.489553 -287.194407) (xy 37.519577 -287.238444) (xy 37.542703 -287.286465) (xy 37.558413 -287.337395)
			(xy 37.566356 -287.390099) (xy 37.566854 -287.416748) (xy 37.566356 -287.443397) (xy 37.558413 -287.496101)
			(xy 37.542703 -287.547031) (xy 37.519577 -287.595052) (xy 37.489553 -287.639089) (xy 37.453301 -287.67816)
			(xy 37.41163 -287.711391) (xy 37.365472 -287.73804) (xy 37.315858 -287.757512) (xy 37.263896 -287.769372)
			(xy 37.210746 -287.773356) (xy 37.157596 -287.769372) (xy 37.105634 -287.757512) (xy 37.05602 -287.73804)
			(xy 37.009862 -287.711391) (xy 36.968191 -287.67816) (xy 36.931939 -287.639089) (xy 36.901915 -287.595052)
			(xy 36.878789 -287.547031) (xy 36.863079 -287.496101) (xy 36.855136 -287.443397) (xy 36.331455 -287.443397)
			(xy 36.329472 -287.469855) (xy 36.317611 -287.521824) (xy 36.298137 -287.571443) (xy 36.271486 -287.617607)
			(xy 36.238252 -287.659282) (xy 36.199177 -287.69554) (xy 36.155136 -287.725568) (xy 36.107111 -287.748697)
			(xy 36.056175 -287.764411) (xy 36.003466 -287.772357) (xy 35.976814 -287.772856) (xy 35.94955 -287.772366)
			(xy 35.895661 -287.764048) (xy 35.843672 -287.747605) (xy 35.794801 -287.723422) (xy 35.750192 -287.692065)
			(xy 35.73018 -287.673542) (xy 35.719774 -287.664123) (xy 35.695027 -287.6509) (xy 35.667614 -287.644922)
			(xy 35.639609 -287.646641) (xy 35.613132 -287.655927) (xy 35.601402 -287.663636) (xy 35.59479 -287.667881)
			(xy 35.579792 -287.672537) (xy 35.571938 -287.67278) (xy 34.172398 -287.67278) (xy 34.162274 -287.672276)
			(xy 34.143556 -287.664551) (xy 34.129201 -287.65027) (xy 34.121378 -287.631594) (xy 34.120836 -287.621472)
			(xy 32.391858 -287.621472) (xy 32.391858 -288.293281) (xy 33.411404 -288.293281) (xy 33.411404 -288.239983)
			(xy 33.419347 -288.187279) (xy 33.435057 -288.136349) (xy 33.458183 -288.088328) (xy 33.488207 -288.044291)
			(xy 33.524459 -288.00522) (xy 33.56613 -287.971989) (xy 33.612288 -287.94534) (xy 33.661902 -287.925868)
			(xy 33.713864 -287.914008) (xy 33.767014 -287.910025) (xy 33.820164 -287.914008) (xy 33.872126 -287.925868)
			(xy 33.92174 -287.94534) (xy 33.967898 -287.971989) (xy 34.009569 -288.00522) (xy 34.045821 -288.044291)
			(xy 34.075845 -288.088328) (xy 34.098971 -288.136349) (xy 34.114681 -288.187279) (xy 34.122624 -288.239983)
			(xy 34.123122 -288.266632) (xy 34.122624 -288.293281) (xy 35.621204 -288.293281) (xy 35.621204 -288.239983)
			(xy 35.629147 -288.187279) (xy 35.644857 -288.136349) (xy 35.667983 -288.088328) (xy 35.698007 -288.044291)
			(xy 35.734259 -288.00522) (xy 35.77593 -287.971989) (xy 35.822088 -287.94534) (xy 35.871702 -287.925868)
			(xy 35.923664 -287.914008) (xy 35.976814 -287.910025) (xy 36.029964 -287.914008) (xy 36.081926 -287.925868)
			(xy 36.13154 -287.94534) (xy 36.177698 -287.971989) (xy 36.219369 -288.00522) (xy 36.255621 -288.044291)
			(xy 36.285645 -288.088328) (xy 36.308771 -288.136349) (xy 36.324481 -288.187279) (xy 36.332424 -288.239983)
			(xy 36.332922 -288.266632) (xy 36.332424 -288.293281) (xy 36.324481 -288.345985) (xy 36.308771 -288.396915)
			(xy 36.285645 -288.444936) (xy 36.267632 -288.471356) (xy 37.564568 -288.471356) (xy 37.564568 -288.062416)
			(xy 37.565034 -288.052267) (xy 37.572818 -288.033521) (xy 37.587201 -288.019198) (xy 37.605979 -288.011492)
			(xy 37.61613 -288.011108) (xy 39.01567 -288.011108) (xy 39.025791 -288.01165) (xy 39.044505 -288.019362)
			(xy 39.058862 -288.033631) (xy 39.066688 -288.052298) (xy 39.067232 -288.062416) (xy 39.067232 -288.471356)
			(xy 39.066743 -288.481503) (xy 39.058968 -288.500249) (xy 39.044592 -288.514572) (xy 39.025819 -288.522279)
			(xy 39.01567 -288.522664) (xy 37.61613 -288.522664) (xy 37.606006 -288.522149) (xy 37.587286 -288.514432)
			(xy 37.572929 -288.500154) (xy 37.565108 -288.481478) (xy 37.564568 -288.471356) (xy 36.267632 -288.471356)
			(xy 36.255621 -288.488973) (xy 36.219369 -288.528044) (xy 36.177698 -288.561275) (xy 36.13154 -288.587924)
			(xy 36.081926 -288.607396) (xy 36.029964 -288.619256) (xy 35.976814 -288.62324) (xy 35.923664 -288.619256)
			(xy 35.871702 -288.607396) (xy 35.822088 -288.587924) (xy 35.77593 -288.561275) (xy 35.734259 -288.528044)
			(xy 35.698007 -288.488973) (xy 35.667983 -288.444936) (xy 35.644857 -288.396915) (xy 35.629147 -288.345985)
			(xy 35.621204 -288.293281) (xy 34.122624 -288.293281) (xy 34.114681 -288.345985) (xy 34.098971 -288.396915)
			(xy 34.075845 -288.444936) (xy 34.045821 -288.488973) (xy 34.009569 -288.528044) (xy 33.967898 -288.561275)
			(xy 33.92174 -288.587924) (xy 33.872126 -288.607396) (xy 33.820164 -288.619256) (xy 33.767014 -288.62324)
			(xy 33.713864 -288.619256) (xy 33.661902 -288.607396) (xy 33.612288 -288.587924) (xy 33.56613 -288.561275)
			(xy 33.524459 -288.528044) (xy 33.488207 -288.488973) (xy 33.458183 -288.444936) (xy 33.435057 -288.396915)
			(xy 33.419347 -288.345985) (xy 33.411404 -288.293281) (xy 32.391858 -288.293281) (xy 32.391858 -289.321494)
			(xy 34.120836 -289.321494) (xy 34.120836 -288.912554) (xy 34.121296 -288.902394) (xy 34.129085 -288.883624)
			(xy 34.143461 -288.86926) (xy 34.162237 -288.861487) (xy 34.172398 -288.860992) (xy 35.571938 -288.860992)
			(xy 35.579809 -288.861295) (xy 35.594808 -288.86608) (xy 35.601402 -288.87039) (xy 35.613167 -288.877969)
			(xy 35.639602 -288.887112) (xy 35.667526 -288.888751) (xy 35.69485 -288.882763) (xy 35.719529 -288.869595)
			(xy 35.729926 -288.86023) (xy 35.749917 -288.841631) (xy 35.794569 -288.810208) (xy 35.843497 -288.785973)
			(xy 35.895552 -288.769494) (xy 35.949513 -288.761157) (xy 35.976814 -288.760662) (xy 36.00346 -288.761221)
			(xy 36.056158 -288.769166) (xy 36.107082 -288.784876) (xy 36.155097 -288.808) (xy 36.199128 -288.838022)
			(xy 36.238194 -288.874271) (xy 36.271421 -288.915937) (xy 36.298067 -288.962091) (xy 36.317536 -289.0117)
			(xy 36.329395 -289.063656) (xy 36.333377 -289.1168) (xy 36.331382 -289.143419) (xy 36.855136 -289.143419)
			(xy 36.855136 -289.090121) (xy 36.863079 -289.037417) (xy 36.878789 -288.986487) (xy 36.901915 -288.938466)
			(xy 36.931939 -288.894429) (xy 36.968191 -288.855358) (xy 37.009862 -288.822127) (xy 37.05602 -288.795478)
			(xy 37.105634 -288.776006) (xy 37.157596 -288.764146) (xy 37.210746 -288.760163) (xy 37.263896 -288.764146)
			(xy 37.315858 -288.776006) (xy 37.365472 -288.795478) (xy 37.41163 -288.822127) (xy 37.453301 -288.855358)
			(xy 37.489553 -288.894429) (xy 37.519577 -288.938466) (xy 37.542703 -288.986487) (xy 37.558413 -289.037417)
			(xy 37.566356 -289.090121) (xy 37.566854 -289.11677) (xy 37.566356 -289.143419) (xy 37.558413 -289.196123)
			(xy 37.542703 -289.247053) (xy 37.519577 -289.295074) (xy 37.489553 -289.339111) (xy 37.453301 -289.378182)
			(xy 37.41163 -289.411413) (xy 37.365472 -289.438062) (xy 37.315858 -289.457534) (xy 37.263896 -289.469394)
			(xy 37.210746 -289.473378) (xy 37.157596 -289.469394) (xy 37.105634 -289.457534) (xy 37.05602 -289.438062)
			(xy 37.009862 -289.411413) (xy 36.968191 -289.378182) (xy 36.931939 -289.339111) (xy 36.901915 -289.295074)
			(xy 36.878789 -289.247053) (xy 36.863079 -289.196123) (xy 36.855136 -289.143419) (xy 36.331382 -289.143419)
			(xy 36.329395 -289.169944) (xy 36.317536 -289.2219) (xy 36.298067 -289.271509) (xy 36.271421 -289.317663)
			(xy 36.238194 -289.359329) (xy 36.199128 -289.395578) (xy 36.155097 -289.4256) (xy 36.107082 -289.448724)
			(xy 36.056158 -289.464434) (xy 36.00346 -289.472379) (xy 35.976814 -289.472878) (xy 35.949551 -289.472382)
			(xy 35.895662 -289.464065) (xy 35.843673 -289.447623) (xy 35.794802 -289.423441) (xy 35.750193 -289.392086)
			(xy 35.73018 -289.373564) (xy 35.719774 -289.364145) (xy 35.695028 -289.350919) (xy 35.667614 -289.34494)
			(xy 35.639608 -289.34666) (xy 35.613131 -289.355948) (xy 35.601402 -289.363658) (xy 35.594789 -289.367932)
			(xy 35.579804 -289.372729) (xy 35.571938 -289.373056) (xy 34.172398 -289.373056) (xy 34.162226 -289.372638)
			(xy 34.14343 -289.364851) (xy 34.129045 -289.350464) (xy 34.121261 -289.331667) (xy 34.120836 -289.321494)
			(xy 32.391858 -289.321494) (xy 32.391858 -289.993303) (xy 33.411404 -289.993303) (xy 33.411404 -289.940005)
			(xy 33.419347 -289.887301) (xy 33.435057 -289.836371) (xy 33.458183 -289.78835) (xy 33.488207 -289.744313)
			(xy 33.524459 -289.705242) (xy 33.56613 -289.672011) (xy 33.612288 -289.645362) (xy 33.661902 -289.62589)
			(xy 33.713864 -289.61403) (xy 33.767014 -289.610047) (xy 33.820164 -289.61403) (xy 33.872126 -289.62589)
			(xy 33.92174 -289.645362) (xy 33.967898 -289.672011) (xy 34.009569 -289.705242) (xy 34.045821 -289.744313)
			(xy 34.075845 -289.78835) (xy 34.098971 -289.836371) (xy 34.114681 -289.887301) (xy 34.122624 -289.940005)
			(xy 34.123122 -289.966654) (xy 34.122624 -289.993303) (xy 35.621204 -289.993303) (xy 35.621204 -289.940005)
			(xy 35.629147 -289.887301) (xy 35.644857 -289.836371) (xy 35.667983 -289.78835) (xy 35.698007 -289.744313)
			(xy 35.734259 -289.705242) (xy 35.77593 -289.672011) (xy 35.822088 -289.645362) (xy 35.871702 -289.62589)
			(xy 35.923664 -289.61403) (xy 35.976814 -289.610047) (xy 36.029964 -289.61403) (xy 36.081926 -289.62589)
			(xy 36.13154 -289.645362) (xy 36.177698 -289.672011) (xy 36.219369 -289.705242) (xy 36.255621 -289.744313)
			(xy 36.285645 -289.78835) (xy 36.308771 -289.836371) (xy 36.324481 -289.887301) (xy 36.332424 -289.940005)
			(xy 36.332922 -289.966654) (xy 36.332424 -289.993303) (xy 36.324481 -290.046007) (xy 36.308771 -290.096937)
			(xy 36.285645 -290.144958) (xy 36.267632 -290.171378) (xy 37.564568 -290.171378) (xy 37.564568 -289.762438)
			(xy 37.564996 -289.752265) (xy 37.572774 -289.733466) (xy 37.587159 -289.719078) (xy 37.605957 -289.711297)
			(xy 37.61613 -289.710876) (xy 39.01567 -289.710876) (xy 39.025844 -289.711289) (xy 39.044646 -289.719072)
			(xy 39.059033 -289.733461) (xy 39.066812 -289.752264) (xy 39.067232 -289.762438) (xy 39.067232 -290.171378)
			(xy 39.066817 -290.181552) (xy 39.059034 -290.200352) (xy 39.044645 -290.214738) (xy 39.025844 -290.222519)
			(xy 39.01567 -290.22294) (xy 37.61613 -290.22294) (xy 37.605958 -290.222511) (xy 37.587159 -290.214732)
			(xy 37.572773 -290.200347) (xy 37.564991 -290.18155) (xy 37.564568 -290.171378) (xy 36.267632 -290.171378)
			(xy 36.255621 -290.188995) (xy 36.219369 -290.228066) (xy 36.177698 -290.261297) (xy 36.13154 -290.287946)
			(xy 36.081926 -290.307418) (xy 36.029964 -290.319278) (xy 35.976814 -290.323262) (xy 35.923664 -290.319278)
			(xy 35.871702 -290.307418) (xy 35.822088 -290.287946) (xy 35.77593 -290.261297) (xy 35.734259 -290.228066)
			(xy 35.698007 -290.188995) (xy 35.667983 -290.144958) (xy 35.644857 -290.096937) (xy 35.629147 -290.046007)
			(xy 35.621204 -289.993303) (xy 34.122624 -289.993303) (xy 34.114681 -290.046007) (xy 34.098971 -290.096937)
			(xy 34.075845 -290.144958) (xy 34.045821 -290.188995) (xy 34.009569 -290.228066) (xy 33.967898 -290.261297)
			(xy 33.92174 -290.287946) (xy 33.872126 -290.307418) (xy 33.820164 -290.319278) (xy 33.767014 -290.323262)
			(xy 33.713864 -290.319278) (xy 33.661902 -290.307418) (xy 33.612288 -290.287946) (xy 33.56613 -290.261297)
			(xy 33.524459 -290.228066) (xy 33.488207 -290.188995) (xy 33.458183 -290.144958) (xy 33.435057 -290.096937)
			(xy 33.419347 -290.046007) (xy 33.411404 -289.993303) (xy 32.391858 -289.993303) (xy 32.391858 -291.021516)
			(xy 34.120836 -291.021516) (xy 34.120836 -290.612576) (xy 34.121203 -290.602416) (xy 34.129013 -290.583656)
			(xy 34.143427 -290.569332) (xy 34.162235 -290.56164) (xy 34.172398 -290.561268) (xy 35.571938 -290.561268)
			(xy 35.579791 -290.561506) (xy 35.594789 -290.566168) (xy 35.601402 -290.570412) (xy 35.613161 -290.578003)
			(xy 35.639599 -290.587154) (xy 35.667527 -290.588795) (xy 35.694854 -290.582801) (xy 35.719532 -290.569623)
			(xy 35.729926 -290.560252) (xy 35.74992 -290.541657) (xy 35.794571 -290.510232) (xy 35.843498 -290.485996)
			(xy 35.895553 -290.469516) (xy 35.949514 -290.461179) (xy 35.976814 -290.460684) (xy 36.003462 -290.461199)
			(xy 36.056163 -290.469144) (xy 36.10709 -290.484855) (xy 36.155108 -290.50798) (xy 36.199142 -290.538004)
			(xy 36.23821 -290.574256) (xy 36.271439 -290.615925) (xy 36.298087 -290.662081) (xy 36.317558 -290.711693)
			(xy 36.329417 -290.763653) (xy 36.3334 -290.8168) (xy 36.331403 -290.843441) (xy 36.855136 -290.843441)
			(xy 36.855136 -290.790143) (xy 36.863079 -290.737439) (xy 36.878789 -290.686509) (xy 36.901915 -290.638488)
			(xy 36.931939 -290.594451) (xy 36.968191 -290.55538) (xy 37.009862 -290.522149) (xy 37.05602 -290.4955)
			(xy 37.105634 -290.476028) (xy 37.157596 -290.464168) (xy 37.210746 -290.460185) (xy 37.263896 -290.464168)
			(xy 37.315858 -290.476028) (xy 37.365472 -290.4955) (xy 37.41163 -290.522149) (xy 37.453301 -290.55538)
			(xy 37.489553 -290.594451) (xy 37.519577 -290.638488) (xy 37.542703 -290.686509) (xy 37.558413 -290.737439)
			(xy 37.566356 -290.790143) (xy 37.566854 -290.816792) (xy 37.566356 -290.843441) (xy 37.558413 -290.896145)
			(xy 37.542703 -290.947075) (xy 37.519577 -290.995096) (xy 37.489553 -291.039133) (xy 37.453301 -291.078204)
			(xy 37.41163 -291.111435) (xy 37.365472 -291.138084) (xy 37.315858 -291.157556) (xy 37.263896 -291.169416)
			(xy 37.210746 -291.1734) (xy 37.157596 -291.169416) (xy 37.105634 -291.157556) (xy 37.05602 -291.138084)
			(xy 37.009862 -291.111435) (xy 36.968191 -291.078204) (xy 36.931939 -291.039133) (xy 36.901915 -290.995096)
			(xy 36.878789 -290.947075) (xy 36.863079 -290.896145) (xy 36.855136 -290.843441) (xy 36.331403 -290.843441)
			(xy 36.329417 -290.869947) (xy 36.317558 -290.921907) (xy 36.298087 -290.971519) (xy 36.271439 -291.017675)
			(xy 36.23821 -291.059344) (xy 36.199142 -291.095596) (xy 36.155108 -291.12562) (xy 36.10709 -291.148745)
			(xy 36.056163 -291.164456) (xy 36.003462 -291.172401) (xy 35.976814 -291.1729) (xy 35.949551 -291.172398)
			(xy 35.895663 -291.164081) (xy 35.843675 -291.14764) (xy 35.794803 -291.12346) (xy 35.750193 -291.092107)
			(xy 35.73018 -291.073586) (xy 35.719773 -291.064166) (xy 35.695028 -291.050939) (xy 35.667614 -291.044958)
			(xy 35.639607 -291.046678) (xy 35.613131 -291.055968) (xy 35.601402 -291.06368) (xy 35.594787 -291.06792)
			(xy 35.579791 -291.07258) (xy 35.571938 -291.072824) (xy 34.172398 -291.072824) (xy 34.162267 -291.072374)
			(xy 34.143539 -291.064639) (xy 34.129181 -291.050341) (xy 34.121369 -291.031645) (xy 34.120836 -291.021516)
			(xy 32.391858 -291.021516) (xy 32.391858 -291.693325) (xy 33.411404 -291.693325) (xy 33.411404 -291.640027)
			(xy 33.419347 -291.587323) (xy 33.435057 -291.536393) (xy 33.458183 -291.488372) (xy 33.488207 -291.444335)
			(xy 33.524459 -291.405264) (xy 33.56613 -291.372033) (xy 33.612288 -291.345384) (xy 33.661902 -291.325912)
			(xy 33.713864 -291.314052) (xy 33.767014 -291.310069) (xy 33.820164 -291.314052) (xy 33.872126 -291.325912)
			(xy 33.92174 -291.345384) (xy 33.967898 -291.372033) (xy 34.009569 -291.405264) (xy 34.045821 -291.444335)
			(xy 34.075845 -291.488372) (xy 34.098971 -291.536393) (xy 34.114681 -291.587323) (xy 34.122624 -291.640027)
			(xy 34.123122 -291.666676) (xy 34.122624 -291.693325) (xy 35.621204 -291.693325) (xy 35.621204 -291.640027)
			(xy 35.629147 -291.587323) (xy 35.644857 -291.536393) (xy 35.667983 -291.488372) (xy 35.698007 -291.444335)
			(xy 35.734259 -291.405264) (xy 35.77593 -291.372033) (xy 35.822088 -291.345384) (xy 35.871702 -291.325912)
			(xy 35.923664 -291.314052) (xy 35.976814 -291.310069) (xy 36.029964 -291.314052) (xy 36.081926 -291.325912)
			(xy 36.13154 -291.345384) (xy 36.177698 -291.372033) (xy 36.219369 -291.405264) (xy 36.255621 -291.444335)
			(xy 36.285645 -291.488372) (xy 36.308771 -291.536393) (xy 36.324481 -291.587323) (xy 36.332424 -291.640027)
			(xy 36.332922 -291.666676) (xy 36.332424 -291.693325) (xy 36.324481 -291.746029) (xy 36.308771 -291.796959)
			(xy 36.285645 -291.84498) (xy 36.267632 -291.8714) (xy 37.564568 -291.8714) (xy 37.564568 -291.46246)
			(xy 37.564988 -291.452307) (xy 37.572791 -291.43356) (xy 37.587187 -291.419239) (xy 37.605975 -291.411535)
			(xy 37.61613 -291.411152) (xy 39.01567 -291.411152) (xy 39.025796 -291.411651) (xy 39.044519 -291.419371)
			(xy 39.058877 -291.433654) (xy 39.066695 -291.452336) (xy 39.067232 -291.46246) (xy 39.067232 -291.8714)
			(xy 39.066779 -291.88155) (xy 39.058989 -291.900296) (xy 39.044603 -291.914618) (xy 39.025822 -291.922324)
			(xy 39.01567 -291.922708) (xy 37.61613 -291.922708) (xy 37.606011 -291.92215) (xy 37.5873 -291.914441)
			(xy 37.572944 -291.900177) (xy 37.565115 -291.881516) (xy 37.564568 -291.8714) (xy 36.267632 -291.8714)
			(xy 36.255621 -291.889017) (xy 36.219369 -291.928088) (xy 36.177698 -291.961319) (xy 36.13154 -291.987968)
			(xy 36.081926 -292.00744) (xy 36.029964 -292.0193) (xy 35.976814 -292.023284) (xy 35.923664 -292.0193)
			(xy 35.871702 -292.00744) (xy 35.822088 -291.987968) (xy 35.77593 -291.961319) (xy 35.734259 -291.928088)
			(xy 35.698007 -291.889017) (xy 35.667983 -291.84498) (xy 35.644857 -291.796959) (xy 35.629147 -291.746029)
			(xy 35.621204 -291.693325) (xy 34.122624 -291.693325) (xy 34.114681 -291.746029) (xy 34.098971 -291.796959)
			(xy 34.075845 -291.84498) (xy 34.045821 -291.889017) (xy 34.009569 -291.928088) (xy 33.967898 -291.961319)
			(xy 33.92174 -291.987968) (xy 33.872126 -292.00744) (xy 33.820164 -292.0193) (xy 33.767014 -292.023284)
			(xy 33.713864 -292.0193) (xy 33.661902 -292.00744) (xy 33.612288 -291.987968) (xy 33.56613 -291.961319)
			(xy 33.524459 -291.928088) (xy 33.488207 -291.889017) (xy 33.458183 -291.84498) (xy 33.435057 -291.796959)
			(xy 33.419347 -291.746029) (xy 33.411404 -291.693325) (xy 32.391858 -291.693325) (xy 32.391858 -292.721538)
			(xy 34.120836 -292.721538) (xy 34.120836 -292.312598) (xy 34.121332 -292.30244) (xy 34.129106 -292.283672)
			(xy 34.143472 -292.269306) (xy 34.16224 -292.261532) (xy 34.172398 -292.261036) (xy 35.571938 -292.261036)
			(xy 35.579808 -292.261348) (xy 35.594807 -292.266128) (xy 35.601402 -292.270434) (xy 35.613163 -292.278021)
			(xy 35.6396 -292.287171) (xy 35.667527 -292.288811) (xy 35.694853 -292.282819) (xy 35.719531 -292.269644)
			(xy 35.729926 -292.260274) (xy 35.749924 -292.241683) (xy 35.794574 -292.210257) (xy 35.8435 -292.18602)
			(xy 35.895554 -292.169539) (xy 35.949514 -292.161202) (xy 35.976814 -292.160706) (xy 36.003464 -292.161177)
			(xy 36.056167 -292.169122) (xy 36.107098 -292.184834) (xy 36.155119 -292.207961) (xy 36.199156 -292.237987)
			(xy 36.238227 -292.274241) (xy 36.271458 -292.315912) (xy 36.298107 -292.362071) (xy 36.317579 -292.411687)
			(xy 36.329439 -292.46365) (xy 36.333422 -292.5168) (xy 36.331424 -292.543463) (xy 36.855136 -292.543463)
			(xy 36.855136 -292.490165) (xy 36.863079 -292.437461) (xy 36.878789 -292.386531) (xy 36.901915 -292.33851)
			(xy 36.931939 -292.294473) (xy 36.968191 -292.255402) (xy 37.009862 -292.222171) (xy 37.05602 -292.195522)
			(xy 37.105634 -292.17605) (xy 37.157596 -292.16419) (xy 37.210746 -292.160207) (xy 37.263896 -292.16419)
			(xy 37.315858 -292.17605) (xy 37.365472 -292.195522) (xy 37.41163 -292.222171) (xy 37.453301 -292.255402)
			(xy 37.489553 -292.294473) (xy 37.519577 -292.33851) (xy 37.542703 -292.386531) (xy 37.558413 -292.437461)
			(xy 37.566356 -292.490165) (xy 37.566854 -292.516814) (xy 37.566356 -292.543463) (xy 37.558413 -292.596167)
			(xy 37.542703 -292.647097) (xy 37.519577 -292.695118) (xy 37.489553 -292.739155) (xy 37.453301 -292.778226)
			(xy 37.41163 -292.811457) (xy 37.365472 -292.838106) (xy 37.315858 -292.857578) (xy 37.263896 -292.869438)
			(xy 37.210746 -292.873422) (xy 37.157596 -292.869438) (xy 37.105634 -292.857578) (xy 37.05602 -292.838106)
			(xy 37.009862 -292.811457) (xy 36.968191 -292.778226) (xy 36.931939 -292.739155) (xy 36.901915 -292.695118)
			(xy 36.878789 -292.647097) (xy 36.863079 -292.596167) (xy 36.855136 -292.543463) (xy 36.331424 -292.543463)
			(xy 36.329439 -292.56995) (xy 36.317579 -292.621913) (xy 36.298107 -292.671529) (xy 36.271458 -292.717688)
			(xy 36.238227 -292.759359) (xy 36.199156 -292.795613) (xy 36.155119 -292.825639) (xy 36.107098 -292.848766)
			(xy 36.056167 -292.864478) (xy 36.003464 -292.872423) (xy 35.976814 -292.872922) (xy 35.949551 -292.872414)
			(xy 35.895664 -292.864098) (xy 35.843676 -292.847658) (xy 35.794804 -292.823479) (xy 35.750194 -292.792128)
			(xy 35.73018 -292.773608) (xy 35.719773 -292.764188) (xy 35.695028 -292.750958) (xy 35.667614 -292.744976)
			(xy 35.639607 -292.746697) (xy 35.61313 -292.755989) (xy 35.601402 -292.763702) (xy 35.594792 -292.76798)
			(xy 35.579804 -292.772774) (xy 35.571938 -292.7731) (xy 34.172398 -292.7731) (xy 34.162245 -292.772569)
			(xy 34.143483 -292.764801) (xy 34.129119 -292.750447) (xy 34.121338 -292.731691) (xy 34.120836 -292.721538)
			(xy 32.391858 -292.721538) (xy 32.391858 -293.571422) (xy 34.120836 -293.571422) (xy 34.120836 -293.162482)
			(xy 34.121318 -293.152323) (xy 34.129098 -293.133554) (xy 34.143467 -293.119189) (xy 34.162239 -293.111415)
			(xy 34.172398 -293.11092) (xy 35.571938 -293.11092) (xy 35.579808 -293.111235) (xy 35.594807 -293.116013)
			(xy 35.601402 -293.120318) (xy 35.613162 -293.127908) (xy 35.639599 -293.137059) (xy 35.667527 -293.138699)
			(xy 35.694853 -293.132706) (xy 35.719532 -293.119529) (xy 35.729926 -293.110158) (xy 35.749921 -293.091564)
			(xy 35.794572 -293.060139) (xy 35.843499 -293.035902) (xy 35.895553 -293.019422) (xy 35.949514 -293.011085)
			(xy 35.976814 -293.01059) (xy 36.003462 -293.011093) (xy 36.056164 -293.019038) (xy 36.107093 -293.034749)
			(xy 36.155111 -293.057875) (xy 36.199146 -293.0879) (xy 36.238215 -293.124152) (xy 36.271444 -293.165821)
			(xy 36.298092 -293.211978) (xy 36.317563 -293.261591) (xy 36.329423 -293.313552) (xy 36.333406 -293.3667)
			(xy 36.329423 -293.419848) (xy 36.317563 -293.471809) (xy 36.298092 -293.521422) (xy 36.271444 -293.567579)
			(xy 36.268379 -293.571422) (xy 37.564568 -293.571422) (xy 37.564568 -293.162482) (xy 37.56495 -293.152306)
			(xy 37.572747 -293.133505) (xy 37.587145 -293.11912) (xy 37.605953 -293.111341) (xy 37.61613 -293.11092)
			(xy 39.01567 -293.11092) (xy 39.025837 -293.111388) (xy 39.044628 -293.11916) (xy 39.059013 -293.133532)
			(xy 39.066802 -293.152315) (xy 39.067232 -293.162482) (xy 39.067232 -293.571422) (xy 39.066853 -293.581599)
			(xy 39.059055 -293.6004) (xy 39.044656 -293.614785) (xy 39.025847 -293.622563) (xy 39.01567 -293.622984)
			(xy 37.61613 -293.622984) (xy 37.605963 -293.622512) (xy 37.587173 -293.614741) (xy 37.572788 -293.60037)
			(xy 37.564998 -293.581588) (xy 37.564568 -293.571422) (xy 36.268379 -293.571422) (xy 36.238215 -293.609248)
			(xy 36.199146 -293.6455) (xy 36.155111 -293.675525) (xy 36.107093 -293.698651) (xy 36.056164 -293.714362)
			(xy 36.003462 -293.722307) (xy 35.976814 -293.722806) (xy 35.949551 -293.722303) (xy 35.895663 -293.713986)
			(xy 35.843675 -293.697545) (xy 35.794804 -293.673365) (xy 35.750193 -293.642012) (xy 35.73018 -293.623492)
			(xy 35.719773 -293.614072) (xy 35.695028 -293.600844) (xy 35.667614 -293.594863) (xy 35.639607 -293.596583)
			(xy 35.613131 -293.605874) (xy 35.601402 -293.613586) (xy 35.594791 -293.617863) (xy 35.579804 -293.622658)
			(xy 35.571938 -293.622984) (xy 34.172398 -293.622984) (xy 34.162243 -293.622469) (xy 34.143478 -293.614698)
			(xy 34.129113 -293.600339) (xy 34.121335 -293.581577) (xy 34.120836 -293.571422) (xy 32.391858 -293.571422)
			(xy 32.391858 -294.243231) (xy 33.411404 -294.243231) (xy 33.411404 -294.189933) (xy 33.419347 -294.137229)
			(xy 33.435057 -294.086299) (xy 33.458183 -294.038278) (xy 33.488207 -293.994241) (xy 33.524459 -293.95517)
			(xy 33.56613 -293.921939) (xy 33.612288 -293.89529) (xy 33.661902 -293.875818) (xy 33.713864 -293.863958)
			(xy 33.767014 -293.859975) (xy 33.820164 -293.863958) (xy 33.872126 -293.875818) (xy 33.92174 -293.89529)
			(xy 33.967898 -293.921939) (xy 34.009569 -293.95517) (xy 34.045821 -293.994241) (xy 34.075845 -294.038278)
			(xy 34.098971 -294.086299) (xy 34.114681 -294.137229) (xy 34.122624 -294.189933) (xy 34.123122 -294.216582)
			(xy 34.122624 -294.243231) (xy 35.621204 -294.243231) (xy 35.621204 -294.189933) (xy 35.629147 -294.137229)
			(xy 35.644857 -294.086299) (xy 35.667983 -294.038278) (xy 35.698007 -293.994241) (xy 35.734259 -293.95517)
			(xy 35.77593 -293.921939) (xy 35.822088 -293.89529) (xy 35.871702 -293.875818) (xy 35.923664 -293.863958)
			(xy 35.976814 -293.859975) (xy 36.029964 -293.863958) (xy 36.081926 -293.875818) (xy 36.13154 -293.89529)
			(xy 36.177698 -293.921939) (xy 36.219369 -293.95517) (xy 36.255621 -293.994241) (xy 36.285645 -294.038278)
			(xy 36.308771 -294.086299) (xy 36.324481 -294.137229) (xy 36.332424 -294.189933) (xy 36.332922 -294.216582)
			(xy 36.332424 -294.243231) (xy 36.324481 -294.295935) (xy 36.308771 -294.346865) (xy 36.285645 -294.394886)
			(xy 36.267632 -294.421306) (xy 37.564568 -294.421306) (xy 37.564568 -294.012366) (xy 37.565006 -294.002202)
			(xy 37.572797 -293.983427) (xy 37.58718 -293.969062) (xy 37.605966 -293.961294) (xy 37.61613 -293.960804)
			(xy 39.01567 -293.960804) (xy 39.025822 -293.961357) (xy 39.044584 -293.969115) (xy 39.058949 -293.983463)
			(xy 39.066731 -294.002215) (xy 39.067232 -294.012366) (xy 39.067232 -294.421306) (xy 39.06684 -294.431482)
			(xy 39.059048 -294.450282) (xy 39.044652 -294.464668) (xy 39.025846 -294.472447) (xy 39.01567 -294.472868)
			(xy 37.61613 -294.472868) (xy 37.605961 -294.472412) (xy 37.587168 -294.464638) (xy 37.572783 -294.450262)
			(xy 37.564996 -294.431475) (xy 37.564568 -294.421306) (xy 36.267632 -294.421306) (xy 36.255621 -294.438923)
			(xy 36.219369 -294.477994) (xy 36.177698 -294.511225) (xy 36.13154 -294.537874) (xy 36.081926 -294.557346)
			(xy 36.029964 -294.569206) (xy 35.976814 -294.57319) (xy 35.923664 -294.569206) (xy 35.871702 -294.557346)
			(xy 35.822088 -294.537874) (xy 35.77593 -294.511225) (xy 35.734259 -294.477994) (xy 35.698007 -294.438923)
			(xy 35.667983 -294.394886) (xy 35.644857 -294.346865) (xy 35.629147 -294.295935) (xy 35.621204 -294.243231)
			(xy 34.122624 -294.243231) (xy 34.114681 -294.295935) (xy 34.098971 -294.346865) (xy 34.075845 -294.394886)
			(xy 34.045821 -294.438923) (xy 34.009569 -294.477994) (xy 33.967898 -294.511225) (xy 33.92174 -294.537874)
			(xy 33.872126 -294.557346) (xy 33.820164 -294.569206) (xy 33.767014 -294.57319) (xy 33.713864 -294.569206)
			(xy 33.661902 -294.557346) (xy 33.612288 -294.537874) (xy 33.56613 -294.511225) (xy 33.524459 -294.477994)
			(xy 33.488207 -294.438923) (xy 33.458183 -294.394886) (xy 33.435057 -294.346865) (xy 33.419347 -294.295935)
			(xy 33.411404 -294.243231) (xy 32.391858 -294.243231) (xy 32.391858 -295.271444) (xy 34.120836 -295.271444)
			(xy 34.120836 -294.862504) (xy 34.121226 -294.852346) (xy 34.129027 -294.833586) (xy 34.143434 -294.819262)
			(xy 34.162237 -294.811568) (xy 34.172398 -294.811196) (xy 35.571938 -294.811196) (xy 35.579792 -294.81143)
			(xy 35.59479 -294.816094) (xy 35.601402 -294.82034) (xy 35.613163 -294.827926) (xy 35.6396 -294.837075)
			(xy 35.667527 -294.838715) (xy 35.694852 -294.832723) (xy 35.719531 -294.819549) (xy 35.729926 -294.81018)
			(xy 35.749925 -294.79159) (xy 35.794574 -294.760164) (xy 35.8435 -294.735926) (xy 35.895554 -294.719445)
			(xy 35.949514 -294.711108) (xy 35.976814 -294.710612) (xy 36.003464 -294.711071) (xy 36.056169 -294.719017)
			(xy 36.107101 -294.734729) (xy 36.155122 -294.757856) (xy 36.19916 -294.787882) (xy 36.238231 -294.824137)
			(xy 36.271462 -294.865809) (xy 36.298112 -294.911969) (xy 36.317584 -294.961585) (xy 36.329444 -295.013549)
			(xy 36.333428 -295.0667) (xy 36.331429 -295.093369) (xy 36.855136 -295.093369) (xy 36.855136 -295.040071)
			(xy 36.863079 -294.987367) (xy 36.878789 -294.936437) (xy 36.901915 -294.888416) (xy 36.931939 -294.844379)
			(xy 36.968191 -294.805308) (xy 37.009862 -294.772077) (xy 37.05602 -294.745428) (xy 37.105634 -294.725956)
			(xy 37.157596 -294.714096) (xy 37.210746 -294.710113) (xy 37.263896 -294.714096) (xy 37.315858 -294.725956)
			(xy 37.365472 -294.745428) (xy 37.41163 -294.772077) (xy 37.453301 -294.805308) (xy 37.489553 -294.844379)
			(xy 37.519577 -294.888416) (xy 37.542703 -294.936437) (xy 37.558413 -294.987367) (xy 37.566356 -295.040071)
			(xy 37.566854 -295.06672) (xy 37.566356 -295.093369) (xy 37.558413 -295.146073) (xy 37.542703 -295.197003)
			(xy 37.519577 -295.245024) (xy 37.489553 -295.289061) (xy 37.453301 -295.328132) (xy 37.41163 -295.361363)
			(xy 37.365472 -295.388012) (xy 37.315858 -295.407484) (xy 37.263896 -295.419344) (xy 37.210746 -295.423328)
			(xy 37.157596 -295.419344) (xy 37.105634 -295.407484) (xy 37.05602 -295.388012) (xy 37.009862 -295.361363)
			(xy 36.968191 -295.328132) (xy 36.931939 -295.289061) (xy 36.901915 -295.245024) (xy 36.878789 -295.197003)
			(xy 36.863079 -295.146073) (xy 36.855136 -295.093369) (xy 36.331429 -295.093369) (xy 36.329444 -295.119851)
			(xy 36.317584 -295.171815) (xy 36.298112 -295.221431) (xy 36.271462 -295.267591) (xy 36.238231 -295.309263)
			(xy 36.19916 -295.345518) (xy 36.155122 -295.375544) (xy 36.107101 -295.398671) (xy 36.056169 -295.414383)
			(xy 36.003464 -295.422329) (xy 35.976814 -295.422828) (xy 35.949551 -295.422318) (xy 35.895664 -295.414002)
			(xy 35.843676 -295.397563) (xy 35.794805 -295.373384) (xy 35.750194 -295.342033) (xy 35.73018 -295.323514)
			(xy 35.719775 -295.314094) (xy 35.695027 -295.300875) (xy 35.667614 -295.294899) (xy 35.639609 -295.296617)
			(xy 35.613132 -295.305901) (xy 35.601402 -295.313608) (xy 35.594788 -295.31785) (xy 35.579791 -295.322509)
			(xy 35.571938 -295.322752) (xy 34.172398 -295.322752) (xy 34.16227 -295.322275) (xy 34.143548 -295.314545)
			(xy 34.129191 -295.300256) (xy 34.121373 -295.281569) (xy 34.120836 -295.271444) (xy 32.391858 -295.271444)
			(xy 32.391858 -295.943253) (xy 33.411404 -295.943253) (xy 33.411404 -295.889955) (xy 33.419347 -295.837251)
			(xy 33.435057 -295.786321) (xy 33.458183 -295.7383) (xy 33.488207 -295.694263) (xy 33.524459 -295.655192)
			(xy 33.56613 -295.621961) (xy 33.612288 -295.595312) (xy 33.661902 -295.57584) (xy 33.713864 -295.56398)
			(xy 33.767014 -295.559997) (xy 33.820164 -295.56398) (xy 33.872126 -295.57584) (xy 33.92174 -295.595312)
			(xy 33.967898 -295.621961) (xy 34.009569 -295.655192) (xy 34.045821 -295.694263) (xy 34.075845 -295.7383)
			(xy 34.098971 -295.786321) (xy 34.114681 -295.837251) (xy 34.122624 -295.889955) (xy 34.123122 -295.916604)
			(xy 34.122624 -295.943253) (xy 35.621204 -295.943253) (xy 35.621204 -295.889955) (xy 35.629147 -295.837251)
			(xy 35.644857 -295.786321) (xy 35.667983 -295.7383) (xy 35.698007 -295.694263) (xy 35.734259 -295.655192)
			(xy 35.77593 -295.621961) (xy 35.822088 -295.595312) (xy 35.871702 -295.57584) (xy 35.923664 -295.56398)
			(xy 35.976814 -295.559997) (xy 36.029964 -295.56398) (xy 36.081926 -295.57584) (xy 36.13154 -295.595312)
			(xy 36.177698 -295.621961) (xy 36.219369 -295.655192) (xy 36.255621 -295.694263) (xy 36.285645 -295.7383)
			(xy 36.308771 -295.786321) (xy 36.324481 -295.837251) (xy 36.332424 -295.889955) (xy 36.332922 -295.916604)
			(xy 36.332424 -295.943253) (xy 36.324481 -295.995957) (xy 36.308771 -296.046887) (xy 36.285645 -296.094908)
			(xy 36.267632 -296.121328) (xy 37.564568 -296.121328) (xy 37.564568 -295.712388) (xy 37.565011 -295.702237)
			(xy 37.572804 -295.68349) (xy 37.587194 -295.669169) (xy 37.605977 -295.661464) (xy 37.61613 -295.66108)
			(xy 39.01567 -295.66108) (xy 39.0258 -295.661552) (xy 39.044528 -295.669277) (xy 39.058887 -295.683569)
			(xy 39.0667 -295.702261) (xy 39.067232 -295.712388) (xy 39.067232 -296.121328) (xy 39.066802 -296.13148)
			(xy 39.059003 -296.150227) (xy 39.04461 -296.164548) (xy 39.025824 -296.172253) (xy 39.01567 -296.172636)
			(xy 37.61613 -296.172636) (xy 37.606002 -296.172148) (xy 37.587277 -296.164426) (xy 37.572919 -296.150139)
			(xy 37.565103 -296.131453) (xy 37.564568 -296.121328) (xy 36.267632 -296.121328) (xy 36.255621 -296.138945)
			(xy 36.219369 -296.178016) (xy 36.177698 -296.211247) (xy 36.13154 -296.237896) (xy 36.081926 -296.257368)
			(xy 36.029964 -296.269228) (xy 35.976814 -296.273212) (xy 35.923664 -296.269228) (xy 35.871702 -296.257368)
			(xy 35.822088 -296.237896) (xy 35.77593 -296.211247) (xy 35.734259 -296.178016) (xy 35.698007 -296.138945)
			(xy 35.667983 -296.094908) (xy 35.644857 -296.046887) (xy 35.629147 -295.995957) (xy 35.621204 -295.943253)
			(xy 34.122624 -295.943253) (xy 34.114681 -295.995957) (xy 34.098971 -296.046887) (xy 34.075845 -296.094908)
			(xy 34.045821 -296.138945) (xy 34.009569 -296.178016) (xy 33.967898 -296.211247) (xy 33.92174 -296.237896)
			(xy 33.872126 -296.257368) (xy 33.820164 -296.269228) (xy 33.767014 -296.273212) (xy 33.713864 -296.269228)
			(xy 33.661902 -296.257368) (xy 33.612288 -296.237896) (xy 33.56613 -296.211247) (xy 33.524459 -296.178016)
			(xy 33.488207 -296.138945) (xy 33.458183 -296.094908) (xy 33.435057 -296.046887) (xy 33.419347 -295.995957)
			(xy 33.411404 -295.943253) (xy 32.391858 -295.943253) (xy 32.391858 -296.971466) (xy 34.120836 -296.971466)
			(xy 34.120836 -296.562526) (xy 34.121285 -296.552356) (xy 34.129061 -296.533563) (xy 34.143439 -296.519177)
			(xy 34.162229 -296.511391) (xy 34.172398 -296.510964) (xy 35.571938 -296.510964) (xy 35.579809 -296.511272)
			(xy 35.594808 -296.516054) (xy 35.601402 -296.520362) (xy 35.613165 -296.527945) (xy 35.639601 -296.537091)
			(xy 35.667527 -296.538731) (xy 35.694851 -296.532741) (xy 35.71953 -296.519569) (xy 35.729926 -296.510202)
			(xy 35.749928 -296.491616) (xy 35.794576 -296.460188) (xy 35.843501 -296.435949) (xy 35.895554 -296.419468)
			(xy 35.949514 -296.41113) (xy 35.976814 -296.410634) (xy 36.003466 -296.411049) (xy 36.056174 -296.418995)
			(xy 36.107109 -296.434708) (xy 36.155133 -296.457837) (xy 36.199174 -296.487865) (xy 36.238247 -296.524122)
			(xy 36.271481 -296.565797) (xy 36.298132 -296.611959) (xy 36.317605 -296.661578) (xy 36.329466 -296.713545)
			(xy 36.33345 -296.7667) (xy 36.331449 -296.793391) (xy 36.855136 -296.793391) (xy 36.855136 -296.740093)
			(xy 36.863079 -296.687389) (xy 36.878789 -296.636459) (xy 36.901915 -296.588438) (xy 36.931939 -296.544401)
			(xy 36.968191 -296.50533) (xy 37.009862 -296.472099) (xy 37.05602 -296.44545) (xy 37.105634 -296.425978)
			(xy 37.157596 -296.414118) (xy 37.210746 -296.410135) (xy 37.263896 -296.414118) (xy 37.315858 -296.425978)
			(xy 37.365472 -296.44545) (xy 37.41163 -296.472099) (xy 37.453301 -296.50533) (xy 37.489553 -296.544401)
			(xy 37.519577 -296.588438) (xy 37.542703 -296.636459) (xy 37.558413 -296.687389) (xy 37.566356 -296.740093)
			(xy 37.566854 -296.766742) (xy 37.566356 -296.793391) (xy 37.558413 -296.846095) (xy 37.542703 -296.897025)
			(xy 37.519577 -296.945046) (xy 37.489553 -296.989083) (xy 37.453301 -297.028154) (xy 37.41163 -297.061385)
			(xy 37.365472 -297.088034) (xy 37.315858 -297.107506) (xy 37.263896 -297.119366) (xy 37.210746 -297.12335)
			(xy 37.157596 -297.119366) (xy 37.105634 -297.107506) (xy 37.05602 -297.088034) (xy 37.009862 -297.061385)
			(xy 36.968191 -297.028154) (xy 36.931939 -296.989083) (xy 36.901915 -296.945046) (xy 36.878789 -296.897025)
			(xy 36.863079 -296.846095) (xy 36.855136 -296.793391) (xy 36.331449 -296.793391) (xy 36.329466 -296.819855)
			(xy 36.317605 -296.871822) (xy 36.298132 -296.921441) (xy 36.271481 -296.967603) (xy 36.238247 -297.009278)
			(xy 36.199174 -297.045535) (xy 36.155133 -297.075563) (xy 36.107109 -297.098692) (xy 36.056174 -297.114405)
			(xy 36.003466 -297.122351) (xy 35.976814 -297.12285) (xy 35.94955 -297.122362) (xy 35.895661 -297.114044)
			(xy 35.843672 -297.0976) (xy 35.794801 -297.073417) (xy 35.750192 -297.042059) (xy 35.73018 -297.023536)
			(xy 35.719775 -297.014117) (xy 35.695027 -297.000895) (xy 35.667614 -296.994917) (xy 35.639609 -296.996636)
			(xy 35.613132 -297.005922) (xy 35.601402 -297.01363) (xy 35.594794 -297.017911) (xy 35.579804 -297.022703)
			(xy 35.571938 -297.023028) (xy 34.172398 -297.023028) (xy 34.162222 -297.022637) (xy 34.143421 -297.014845)
			(xy 34.129035 -297.000449) (xy 34.121256 -296.981642) (xy 34.120836 -296.971466) (xy 32.391858 -296.971466)
			(xy 32.391858 -297.643275) (xy 33.411404 -297.643275) (xy 33.411404 -297.589977) (xy 33.419347 -297.537273)
			(xy 33.435057 -297.486343) (xy 33.458183 -297.438322) (xy 33.488207 -297.394285) (xy 33.524459 -297.355214)
			(xy 33.56613 -297.321983) (xy 33.612288 -297.295334) (xy 33.661902 -297.275862) (xy 33.713864 -297.264002)
			(xy 33.767014 -297.260019) (xy 33.820164 -297.264002) (xy 33.872126 -297.275862) (xy 33.92174 -297.295334)
			(xy 33.967898 -297.321983) (xy 34.009569 -297.355214) (xy 34.045821 -297.394285) (xy 34.075845 -297.438322)
			(xy 34.098971 -297.486343) (xy 34.114681 -297.537273) (xy 34.122624 -297.589977) (xy 34.123122 -297.616626)
			(xy 34.122624 -297.643275) (xy 35.621204 -297.643275) (xy 35.621204 -297.589977) (xy 35.629147 -297.537273)
			(xy 35.644857 -297.486343) (xy 35.667983 -297.438322) (xy 35.698007 -297.394285) (xy 35.734259 -297.355214)
			(xy 35.77593 -297.321983) (xy 35.822088 -297.295334) (xy 35.871702 -297.275862) (xy 35.923664 -297.264002)
			(xy 35.976814 -297.260019) (xy 36.029964 -297.264002) (xy 36.081926 -297.275862) (xy 36.13154 -297.295334)
			(xy 36.177698 -297.321983) (xy 36.219369 -297.355214) (xy 36.255621 -297.394285) (xy 36.285645 -297.438322)
			(xy 36.308771 -297.486343) (xy 36.324481 -297.537273) (xy 36.332424 -297.589977) (xy 36.332922 -297.616626)
			(xy 36.332424 -297.643275) (xy 36.324481 -297.695979) (xy 36.308771 -297.746909) (xy 36.285645 -297.79493)
			(xy 36.267632 -297.82135) (xy 37.564568 -297.82135) (xy 37.564568 -297.41241) (xy 37.564973 -297.402235)
			(xy 37.57276 -297.383435) (xy 37.587152 -297.369049) (xy 37.605955 -297.361269) (xy 37.61613 -297.360848)
			(xy 39.01567 -297.360848) (xy 39.025841 -297.361289) (xy 39.044637 -297.369066) (xy 39.059023 -297.383446)
			(xy 39.066807 -297.402239) (xy 39.067232 -297.41241) (xy 39.067232 -297.82135) (xy 39.066795 -297.831522)
			(xy 39.05902 -297.850321) (xy 39.044638 -297.864709) (xy 39.025842 -297.872491) (xy 39.01567 -297.872912)
			(xy 37.61613 -297.872912) (xy 37.605954 -297.87251) (xy 37.587151 -297.864726) (xy 37.572763 -297.850333)
			(xy 37.564986 -297.831526) (xy 37.564568 -297.82135) (xy 36.267632 -297.82135) (xy 36.255621 -297.838967)
			(xy 36.219369 -297.878038) (xy 36.177698 -297.911269) (xy 36.13154 -297.937918) (xy 36.081926 -297.95739)
			(xy 36.029964 -297.96925) (xy 35.976814 -297.973234) (xy 35.923664 -297.96925) (xy 35.871702 -297.95739)
			(xy 35.822088 -297.937918) (xy 35.77593 -297.911269) (xy 35.734259 -297.878038) (xy 35.698007 -297.838967)
			(xy 35.667983 -297.79493) (xy 35.644857 -297.746909) (xy 35.629147 -297.695979) (xy 35.621204 -297.643275)
			(xy 34.122624 -297.643275) (xy 34.114681 -297.695979) (xy 34.098971 -297.746909) (xy 34.075845 -297.79493)
			(xy 34.045821 -297.838967) (xy 34.009569 -297.878038) (xy 33.967898 -297.911269) (xy 33.92174 -297.937918)
			(xy 33.872126 -297.95739) (xy 33.820164 -297.96925) (xy 33.767014 -297.973234) (xy 33.713864 -297.96925)
			(xy 33.661902 -297.95739) (xy 33.612288 -297.937918) (xy 33.56613 -297.911269) (xy 33.524459 -297.878038)
			(xy 33.488207 -297.838967) (xy 33.458183 -297.79493) (xy 33.435057 -297.746909) (xy 33.419347 -297.695979)
			(xy 33.411404 -297.643275) (xy 32.391858 -297.643275) (xy 32.391858 -298.671488) (xy 34.120836 -298.671488)
			(xy 34.120836 -298.262548) (xy 34.121262 -298.252393) (xy 34.129048 -298.233634) (xy 34.143445 -298.219308)
			(xy 34.162241 -298.211613) (xy 34.172398 -298.21124) (xy 35.571938 -298.21124) (xy 35.579791 -298.211482)
			(xy 35.594788 -298.216142) (xy 35.601402 -298.220384) (xy 35.613167 -298.227964) (xy 35.639602 -298.237108)
			(xy 35.667527 -298.238747) (xy 35.69485 -298.232758) (xy 35.719529 -298.219589) (xy 35.729926 -298.210224)
			(xy 35.749916 -298.191624) (xy 35.794569 -298.160201) (xy 35.843497 -298.135966) (xy 35.895552 -298.119487)
			(xy 35.949513 -298.111151) (xy 35.976814 -298.110656) (xy 36.00346 -298.111227) (xy 36.056156 -298.119172)
			(xy 36.10708 -298.134881) (xy 36.155094 -298.158005) (xy 36.199125 -298.188027) (xy 36.23819 -298.224275)
			(xy 36.271416 -298.265941) (xy 36.298061 -298.312093) (xy 36.31753 -298.361701) (xy 36.329389 -298.413657)
			(xy 36.333371 -298.4668) (xy 36.331377 -298.493413) (xy 36.855136 -298.493413) (xy 36.855136 -298.440115)
			(xy 36.863079 -298.387411) (xy 36.878789 -298.336481) (xy 36.901915 -298.28846) (xy 36.931939 -298.244423)
			(xy 36.968191 -298.205352) (xy 37.009862 -298.172121) (xy 37.05602 -298.145472) (xy 37.105634 -298.126)
			(xy 37.157596 -298.11414) (xy 37.210746 -298.110157) (xy 37.263896 -298.11414) (xy 37.315858 -298.126)
			(xy 37.365472 -298.145472) (xy 37.41163 -298.172121) (xy 37.453301 -298.205352) (xy 37.489553 -298.244423)
			(xy 37.519577 -298.28846) (xy 37.542703 -298.336481) (xy 37.558413 -298.387411) (xy 37.566356 -298.440115)
			(xy 37.566854 -298.466764) (xy 37.566356 -298.493413) (xy 37.558413 -298.546117) (xy 37.542703 -298.597047)
			(xy 37.519577 -298.645068) (xy 37.489553 -298.689105) (xy 37.453301 -298.728176) (xy 37.41163 -298.761407)
			(xy 37.365472 -298.788056) (xy 37.315858 -298.807528) (xy 37.263896 -298.819388) (xy 37.210746 -298.823372)
			(xy 37.157596 -298.819388) (xy 37.105634 -298.807528) (xy 37.05602 -298.788056) (xy 37.009862 -298.761407)
			(xy 36.968191 -298.728176) (xy 36.931939 -298.689105) (xy 36.901915 -298.645068) (xy 36.878789 -298.597047)
			(xy 36.863079 -298.546117) (xy 36.855136 -298.493413) (xy 36.331377 -298.493413) (xy 36.329389 -298.519943)
			(xy 36.31753 -298.571899) (xy 36.298061 -298.621507) (xy 36.271416 -298.667659) (xy 36.23819 -298.709325)
			(xy 36.199125 -298.745573) (xy 36.155094 -298.775595) (xy 36.10708 -298.798719) (xy 36.056156 -298.814428)
			(xy 36.00346 -298.822373) (xy 35.976814 -298.822872) (xy 35.949551 -298.822378) (xy 35.895662 -298.81406)
			(xy 35.843673 -298.797618) (xy 35.794802 -298.773436) (xy 35.750193 -298.74208) (xy 35.73018 -298.723558)
			(xy 35.719774 -298.714139) (xy 35.695028 -298.700914) (xy 35.667614 -298.694935) (xy 35.639608 -298.696655)
			(xy 35.613131 -298.705942) (xy 35.601402 -298.713652) (xy 35.594791 -298.717898) (xy 35.579792 -298.722553)
			(xy 35.571938 -298.722796) (xy 34.172398 -298.722796) (xy 34.162276 -298.722276) (xy 34.143561 -298.714554)
			(xy 34.129206 -298.700279) (xy 34.121381 -298.681608) (xy 34.120836 -298.671488) (xy 32.391858 -298.671488)
			(xy 32.391858 -299.343297) (xy 33.411404 -299.343297) (xy 33.411404 -299.289999) (xy 33.419347 -299.237295)
			(xy 33.435057 -299.186365) (xy 33.458183 -299.138344) (xy 33.488207 -299.094307) (xy 33.524459 -299.055236)
			(xy 33.56613 -299.022005) (xy 33.612288 -298.995356) (xy 33.661902 -298.975884) (xy 33.713864 -298.964024)
			(xy 33.767014 -298.960041) (xy 33.820164 -298.964024) (xy 33.872126 -298.975884) (xy 33.92174 -298.995356)
			(xy 33.967898 -299.022005) (xy 34.009569 -299.055236) (xy 34.045821 -299.094307) (xy 34.075845 -299.138344)
			(xy 34.098971 -299.186365) (xy 34.114681 -299.237295) (xy 34.122624 -299.289999) (xy 34.123122 -299.316648)
			(xy 34.122624 -299.343297) (xy 35.621204 -299.343297) (xy 35.621204 -299.289999) (xy 35.629147 -299.237295)
			(xy 35.644857 -299.186365) (xy 35.667983 -299.138344) (xy 35.698007 -299.094307) (xy 35.734259 -299.055236)
			(xy 35.77593 -299.022005) (xy 35.822088 -298.995356) (xy 35.871702 -298.975884) (xy 35.923664 -298.964024)
			(xy 35.976814 -298.960041) (xy 36.029964 -298.964024) (xy 36.081926 -298.975884) (xy 36.13154 -298.995356)
			(xy 36.177698 -299.022005) (xy 36.219369 -299.055236) (xy 36.255621 -299.094307) (xy 36.285645 -299.138344)
			(xy 36.308771 -299.186365) (xy 36.324481 -299.237295) (xy 36.332424 -299.289999) (xy 36.332922 -299.316648)
			(xy 36.332424 -299.343297) (xy 36.324481 -299.396001) (xy 36.308771 -299.446931) (xy 36.285645 -299.494952)
			(xy 36.267632 -299.521372) (xy 37.564568 -299.521372) (xy 37.564568 -299.112432) (xy 37.565047 -299.102284)
			(xy 37.572826 -299.083538) (xy 37.587205 -299.069215) (xy 37.60598 -299.061508) (xy 37.61613 -299.061124)
			(xy 39.01567 -299.061124) (xy 39.025793 -299.06165) (xy 39.04451 -299.069365) (xy 39.058867 -299.08364)
			(xy 39.06669 -299.102312) (xy 39.067232 -299.112432) (xy 39.067232 -299.521372) (xy 39.066756 -299.53152)
			(xy 39.058976 -299.550266) (xy 39.044596 -299.564589) (xy 39.02582 -299.572296) (xy 39.01567 -299.57268)
			(xy 37.61613 -299.57268) (xy 37.606008 -299.57215) (xy 37.587291 -299.564435) (xy 37.572934 -299.550163)
			(xy 37.56511 -299.531491) (xy 37.564568 -299.521372) (xy 36.267632 -299.521372) (xy 36.255621 -299.538989)
			(xy 36.219369 -299.57806) (xy 36.177698 -299.611291) (xy 36.13154 -299.63794) (xy 36.081926 -299.657412)
			(xy 36.029964 -299.669272) (xy 35.976814 -299.673256) (xy 35.923664 -299.669272) (xy 35.871702 -299.657412)
			(xy 35.822088 -299.63794) (xy 35.77593 -299.611291) (xy 35.734259 -299.57806) (xy 35.698007 -299.538989)
			(xy 35.667983 -299.494952) (xy 35.644857 -299.446931) (xy 35.629147 -299.396001) (xy 35.621204 -299.343297)
			(xy 34.122624 -299.343297) (xy 34.114681 -299.396001) (xy 34.098971 -299.446931) (xy 34.075845 -299.494952)
			(xy 34.045821 -299.538989) (xy 34.009569 -299.57806) (xy 33.967898 -299.611291) (xy 33.92174 -299.63794)
			(xy 33.872126 -299.657412) (xy 33.820164 -299.669272) (xy 33.767014 -299.673256) (xy 33.713864 -299.669272)
			(xy 33.661902 -299.657412) (xy 33.612288 -299.63794) (xy 33.56613 -299.611291) (xy 33.524459 -299.57806)
			(xy 33.488207 -299.538989) (xy 33.458183 -299.494952) (xy 33.435057 -299.446931) (xy 33.419347 -299.396001)
			(xy 33.411404 -299.343297) (xy 32.391858 -299.343297) (xy 32.391858 -300.37151) (xy 34.120836 -300.37151)
			(xy 34.120836 -299.96257) (xy 34.121309 -299.952411) (xy 34.129093 -299.933641) (xy 34.143465 -299.919277)
			(xy 34.162238 -299.911503) (xy 34.172398 -299.911008) (xy 35.571938 -299.911008) (xy 35.579808 -299.911325)
			(xy 35.594806 -299.916102) (xy 35.601402 -299.920406) (xy 35.613161 -299.927998) (xy 35.639598 -299.93715)
			(xy 35.667527 -299.93879) (xy 35.694854 -299.932797) (xy 35.719532 -299.919618) (xy 35.729926 -299.910246)
			(xy 35.749919 -299.89165) (xy 35.794571 -299.860226) (xy 35.843498 -299.83599) (xy 35.895553 -299.81951)
			(xy 35.949514 -299.811173) (xy 35.976814 -299.810678) (xy 36.003462 -299.811205) (xy 36.056161 -299.81915)
			(xy 36.107088 -299.83486) (xy 36.155105 -299.857986) (xy 36.199139 -299.888009) (xy 36.238206 -299.92426)
			(xy 36.271434 -299.965928) (xy 36.298081 -300.012083) (xy 36.317552 -300.061695) (xy 36.329411 -300.113654)
			(xy 36.333394 -300.1668) (xy 36.331398 -300.193435) (xy 36.855136 -300.193435) (xy 36.855136 -300.140137)
			(xy 36.863079 -300.087433) (xy 36.878789 -300.036503) (xy 36.901915 -299.988482) (xy 36.931939 -299.944445)
			(xy 36.968191 -299.905374) (xy 37.009862 -299.872143) (xy 37.05602 -299.845494) (xy 37.105634 -299.826022)
			(xy 37.157596 -299.814162) (xy 37.210746 -299.810179) (xy 37.263896 -299.814162) (xy 37.315858 -299.826022)
			(xy 37.365472 -299.845494) (xy 37.41163 -299.872143) (xy 37.453301 -299.905374) (xy 37.489553 -299.944445)
			(xy 37.519577 -299.988482) (xy 37.542703 -300.036503) (xy 37.558413 -300.087433) (xy 37.566356 -300.140137)
			(xy 37.566854 -300.166786) (xy 37.566356 -300.193435) (xy 37.558413 -300.246139) (xy 37.542703 -300.297069)
			(xy 37.519577 -300.34509) (xy 37.489553 -300.389127) (xy 37.453301 -300.428198) (xy 37.41163 -300.461429)
			(xy 37.365472 -300.488078) (xy 37.315858 -300.50755) (xy 37.263896 -300.51941) (xy 37.210746 -300.523394)
			(xy 37.157596 -300.51941) (xy 37.105634 -300.50755) (xy 37.05602 -300.488078) (xy 37.009862 -300.461429)
			(xy 36.968191 -300.428198) (xy 36.931939 -300.389127) (xy 36.901915 -300.34509) (xy 36.878789 -300.297069)
			(xy 36.863079 -300.246139) (xy 36.855136 -300.193435) (xy 36.331398 -300.193435) (xy 36.329411 -300.219946)
			(xy 36.317552 -300.271905) (xy 36.298081 -300.321517) (xy 36.271434 -300.367672) (xy 36.238206 -300.40934)
			(xy 36.199139 -300.445591) (xy 36.155105 -300.475614) (xy 36.107088 -300.49874) (xy 36.056161 -300.51445)
			(xy 36.003462 -300.522395) (xy 35.976814 -300.522894) (xy 35.949551 -300.522394) (xy 35.895663 -300.514077)
			(xy 35.843674 -300.497636) (xy 35.794803 -300.473455) (xy 35.750193 -300.442101) (xy 35.73018 -300.42358)
			(xy 35.719774 -300.41416) (xy 35.695028 -300.400933) (xy 35.667614 -300.394953) (xy 35.639607 -300.396673)
			(xy 35.613131 -300.405963) (xy 35.601402 -300.413674) (xy 35.59479 -300.417949) (xy 35.579804 -300.422746)
			(xy 35.571938 -300.423072) (xy 34.172398 -300.423072) (xy 34.162241 -300.422568) (xy 34.143474 -300.414795)
			(xy 34.129109 -300.400433) (xy 34.121333 -300.381667) (xy 34.120836 -300.37151) (xy 32.391858 -300.37151)
			(xy 32.391858 -301.043319) (xy 33.411404 -301.043319) (xy 33.411404 -300.990021) (xy 33.419347 -300.937317)
			(xy 33.435057 -300.886387) (xy 33.458183 -300.838366) (xy 33.488207 -300.794329) (xy 33.524459 -300.755258)
			(xy 33.56613 -300.722027) (xy 33.612288 -300.695378) (xy 33.661902 -300.675906) (xy 33.713864 -300.664046)
			(xy 33.767014 -300.660063) (xy 33.820164 -300.664046) (xy 33.872126 -300.675906) (xy 33.92174 -300.695378)
			(xy 33.967898 -300.722027) (xy 34.009569 -300.755258) (xy 34.045821 -300.794329) (xy 34.075845 -300.838366)
			(xy 34.098971 -300.886387) (xy 34.114681 -300.937317) (xy 34.122624 -300.990021) (xy 34.123122 -301.01667)
			(xy 34.122624 -301.043319) (xy 35.621204 -301.043319) (xy 35.621204 -300.990021) (xy 35.629147 -300.937317)
			(xy 35.644857 -300.886387) (xy 35.667983 -300.838366) (xy 35.698007 -300.794329) (xy 35.734259 -300.755258)
			(xy 35.77593 -300.722027) (xy 35.822088 -300.695378) (xy 35.871702 -300.675906) (xy 35.923664 -300.664046)
			(xy 35.976814 -300.660063) (xy 36.029964 -300.664046) (xy 36.081926 -300.675906) (xy 36.13154 -300.695378)
			(xy 36.177698 -300.722027) (xy 36.219369 -300.755258) (xy 36.255621 -300.794329) (xy 36.285645 -300.838366)
			(xy 36.308771 -300.886387) (xy 36.324481 -300.937317) (xy 36.332424 -300.990021) (xy 36.332922 -301.01667)
			(xy 36.332424 -301.043319) (xy 36.324481 -301.096023) (xy 36.308771 -301.146953) (xy 36.285645 -301.194974)
			(xy 36.267632 -301.221394) (xy 37.564568 -301.221394) (xy 37.564568 -300.812454) (xy 37.564997 -300.80229)
			(xy 37.572792 -300.783514) (xy 37.587178 -300.769149) (xy 37.605965 -300.761382) (xy 37.61613 -300.760892)
			(xy 39.01567 -300.760892) (xy 39.02582 -300.761457) (xy 39.04458 -300.769213) (xy 39.058945 -300.783556)
			(xy 39.066728 -300.802305) (xy 39.067232 -300.812454) (xy 39.067232 -301.221394) (xy 39.066831 -301.231569)
			(xy 39.059042 -301.250369) (xy 39.044649 -301.264755) (xy 39.025845 -301.272535) (xy 39.01567 -301.272956)
			(xy 37.61613 -301.272956) (xy 37.60596 -301.272511) (xy 37.587164 -301.264735) (xy 37.572778 -301.250356)
			(xy 37.564993 -301.231564) (xy 37.564568 -301.221394) (xy 36.267632 -301.221394) (xy 36.255621 -301.239011)
			(xy 36.219369 -301.278082) (xy 36.177698 -301.311313) (xy 36.13154 -301.337962) (xy 36.081926 -301.357434)
			(xy 36.029964 -301.369294) (xy 35.976814 -301.373278) (xy 35.923664 -301.369294) (xy 35.871702 -301.357434)
			(xy 35.822088 -301.337962) (xy 35.77593 -301.311313) (xy 35.734259 -301.278082) (xy 35.698007 -301.239011)
			(xy 35.667983 -301.194974) (xy 35.644857 -301.146953) (xy 35.629147 -301.096023) (xy 35.621204 -301.043319)
			(xy 34.122624 -301.043319) (xy 34.114681 -301.096023) (xy 34.098971 -301.146953) (xy 34.075845 -301.194974)
			(xy 34.045821 -301.239011) (xy 34.009569 -301.278082) (xy 33.967898 -301.311313) (xy 33.92174 -301.337962)
			(xy 33.872126 -301.357434) (xy 33.820164 -301.369294) (xy 33.767014 -301.373278) (xy 33.713864 -301.369294)
			(xy 33.661902 -301.357434) (xy 33.612288 -301.337962) (xy 33.56613 -301.311313) (xy 33.524459 -301.278082)
			(xy 33.488207 -301.239011) (xy 33.458183 -301.194974) (xy 33.435057 -301.146953) (xy 33.419347 -301.096023)
			(xy 33.411404 -301.043319) (xy 32.391858 -301.043319) (xy 32.391858 -302.071532) (xy 34.120836 -302.071532)
			(xy 34.120836 -301.662592) (xy 34.121216 -301.652433) (xy 34.129021 -301.633673) (xy 34.143431 -301.619349)
			(xy 34.162237 -301.611656) (xy 34.172398 -301.611284) (xy 35.571938 -301.611284) (xy 35.579792 -301.61152)
			(xy 35.594789 -301.616183) (xy 35.601402 -301.620428) (xy 35.613163 -301.628016) (xy 35.639599 -301.637166)
			(xy 35.667527 -301.638806) (xy 35.694853 -301.632814) (xy 35.719531 -301.619638) (xy 35.729926 -301.610268)
			(xy 35.749922 -301.591675) (xy 35.794573 -301.56025) (xy 35.843499 -301.536013) (xy 35.895553 -301.519532)
			(xy 35.949514 -301.511195) (xy 35.976814 -301.5107) (xy 36.003463 -301.511183) (xy 36.056166 -301.519128)
			(xy 36.107096 -301.53484) (xy 36.155116 -301.557967) (xy 36.199152 -301.587992) (xy 36.238222 -301.624245)
			(xy 36.271453 -301.665916) (xy 36.298101 -301.712074) (xy 36.317573 -301.761688) (xy 36.329433 -301.813651)
			(xy 36.333416 -301.8668) (xy 36.331418 -301.893457) (xy 36.855136 -301.893457) (xy 36.855136 -301.840159)
			(xy 36.863079 -301.787455) (xy 36.878789 -301.736525) (xy 36.901915 -301.688504) (xy 36.931939 -301.644467)
			(xy 36.968191 -301.605396) (xy 37.009862 -301.572165) (xy 37.05602 -301.545516) (xy 37.105634 -301.526044)
			(xy 37.157596 -301.514184) (xy 37.210746 -301.510201) (xy 37.263896 -301.514184) (xy 37.315858 -301.526044)
			(xy 37.365472 -301.545516) (xy 37.41163 -301.572165) (xy 37.453301 -301.605396) (xy 37.489553 -301.644467)
			(xy 37.519577 -301.688504) (xy 37.542703 -301.736525) (xy 37.558413 -301.787455) (xy 37.566356 -301.840159)
			(xy 37.566854 -301.866808) (xy 37.566356 -301.893457) (xy 37.558413 -301.946161) (xy 37.542703 -301.997091)
			(xy 37.519577 -302.045112) (xy 37.489553 -302.089149) (xy 37.453301 -302.12822) (xy 37.41163 -302.161451)
			(xy 37.365472 -302.1881) (xy 37.315858 -302.207572) (xy 37.263896 -302.219432) (xy 37.210746 -302.223416)
			(xy 37.157596 -302.219432) (xy 37.105634 -302.207572) (xy 37.05602 -302.1881) (xy 37.009862 -302.161451)
			(xy 36.968191 -302.12822) (xy 36.931939 -302.089149) (xy 36.901915 -302.045112) (xy 36.878789 -301.997091)
			(xy 36.863079 -301.946161) (xy 36.855136 -301.893457) (xy 36.331418 -301.893457) (xy 36.329433 -301.919949)
			(xy 36.317573 -301.971912) (xy 36.298101 -302.021526) (xy 36.271453 -302.067684) (xy 36.238222 -302.109355)
			(xy 36.199152 -302.145608) (xy 36.155116 -302.175633) (xy 36.107096 -302.19876) (xy 36.056166 -302.214472)
			(xy 36.003463 -302.222417) (xy 35.976814 -302.222916) (xy 35.949551 -302.22241) (xy 35.895664 -302.214093)
			(xy 35.843675 -302.197653) (xy 35.794804 -302.173474) (xy 35.750194 -302.142122) (xy 35.73018 -302.123602)
			(xy 35.719773 -302.114182) (xy 35.695028 -302.100953) (xy 35.667614 -302.094971) (xy 35.639607 -302.096692)
			(xy 35.61313 -302.105983) (xy 35.601402 -302.113696) (xy 35.594788 -302.117937) (xy 35.579791 -302.122596)
			(xy 35.571938 -302.12284) (xy 34.172398 -302.12284) (xy 34.162269 -302.122374) (xy 34.143544 -302.114642)
			(xy 34.129187 -302.100349) (xy 34.121371 -302.081659) (xy 34.120836 -302.071532) (xy 32.391858 -302.071532)
			(xy 32.391858 -302.921416) (xy 34.120836 -302.921416) (xy 34.120836 -302.512476) (xy 34.121203 -302.502316)
			(xy 34.129013 -302.483556) (xy 34.143427 -302.469232) (xy 34.162235 -302.46154) (xy 34.172398 -302.461168)
			(xy 35.571938 -302.461168) (xy 35.579791 -302.461406) (xy 35.594789 -302.466068) (xy 35.601402 -302.470312)
			(xy 35.613161 -302.477903) (xy 35.639599 -302.487054) (xy 35.667527 -302.488695) (xy 35.694854 -302.482701)
			(xy 35.719532 -302.469523) (xy 35.729926 -302.460152) (xy 35.74992 -302.441557) (xy 35.794571 -302.410132)
			(xy 35.843498 -302.385896) (xy 35.895553 -302.369416) (xy 35.949514 -302.361079) (xy 35.976814 -302.360584)
			(xy 36.003462 -302.361099) (xy 36.056163 -302.369044) (xy 36.10709 -302.384755) (xy 36.155108 -302.40788)
			(xy 36.199142 -302.437904) (xy 36.23821 -302.474156) (xy 36.271439 -302.515825) (xy 36.298087 -302.561981)
			(xy 36.317558 -302.611593) (xy 36.329417 -302.663553) (xy 36.3334 -302.7167) (xy 36.329417 -302.769847)
			(xy 36.317558 -302.821807) (xy 36.298087 -302.871419) (xy 36.271439 -302.917575) (xy 36.268376 -302.921416)
			(xy 37.564568 -302.921416) (xy 37.564568 -302.512476) (xy 37.565001 -302.502324) (xy 37.572799 -302.483577)
			(xy 37.587191 -302.469256) (xy 37.605976 -302.461551) (xy 37.61613 -302.461168) (xy 39.01567 -302.461168)
			(xy 39.025798 -302.461652) (xy 39.044524 -302.469375) (xy 39.058883 -302.483663) (xy 39.066698 -302.50235)
			(xy 39.067232 -302.512476) (xy 39.067232 -302.921416) (xy 39.066792 -302.931567) (xy 39.058997 -302.950314)
			(xy 39.044607 -302.964636) (xy 39.025823 -302.972341) (xy 39.01567 -302.972724) (xy 37.61613 -302.972724)
			(xy 37.606001 -302.972248) (xy 37.587273 -302.964523) (xy 37.572915 -302.950233) (xy 37.565101 -302.931543)
			(xy 37.564568 -302.921416) (xy 36.268376 -302.921416) (xy 36.23821 -302.959244) (xy 36.199142 -302.995496)
			(xy 36.155108 -303.02552) (xy 36.10709 -303.048645) (xy 36.056163 -303.064356) (xy 36.003462 -303.072301)
			(xy 35.976814 -303.0728) (xy 35.949551 -303.072298) (xy 35.895663 -303.063981) (xy 35.843675 -303.04754)
			(xy 35.794803 -303.02336) (xy 35.750193 -302.992007) (xy 35.73018 -302.973486) (xy 35.719773 -302.964066)
			(xy 35.695028 -302.950839) (xy 35.667614 -302.944858) (xy 35.639607 -302.946578) (xy 35.613131 -302.955868)
			(xy 35.601402 -302.96358) (xy 35.594787 -302.96782) (xy 35.579791 -302.97248) (xy 35.571938 -302.972724)
			(xy 34.172398 -302.972724) (xy 34.162267 -302.972274) (xy 34.143539 -302.964539) (xy 34.129181 -302.950241)
			(xy 34.121369 -302.931545) (xy 34.120836 -302.921416) (xy 32.391858 -302.921416) (xy 32.391858 -303.593225)
			(xy 33.411404 -303.593225) (xy 33.411404 -303.539927) (xy 33.419347 -303.487223) (xy 33.435057 -303.436293)
			(xy 33.458183 -303.388272) (xy 33.488207 -303.344235) (xy 33.524459 -303.305164) (xy 33.56613 -303.271933)
			(xy 33.612288 -303.245284) (xy 33.661902 -303.225812) (xy 33.713864 -303.213952) (xy 33.767014 -303.209969)
			(xy 33.820164 -303.213952) (xy 33.872126 -303.225812) (xy 33.92174 -303.245284) (xy 33.967898 -303.271933)
			(xy 34.009569 -303.305164) (xy 34.045821 -303.344235) (xy 34.075845 -303.388272) (xy 34.098971 -303.436293)
			(xy 34.114681 -303.487223) (xy 34.122624 -303.539927) (xy 34.123122 -303.566576) (xy 34.122624 -303.593225)
			(xy 35.621204 -303.593225) (xy 35.621204 -303.539927) (xy 35.629147 -303.487223) (xy 35.644857 -303.436293)
			(xy 35.667983 -303.388272) (xy 35.698007 -303.344235) (xy 35.734259 -303.305164) (xy 35.77593 -303.271933)
			(xy 35.822088 -303.245284) (xy 35.871702 -303.225812) (xy 35.923664 -303.213952) (xy 35.976814 -303.209969)
			(xy 36.029964 -303.213952) (xy 36.081926 -303.225812) (xy 36.13154 -303.245284) (xy 36.177698 -303.271933)
			(xy 36.219369 -303.305164) (xy 36.255621 -303.344235) (xy 36.285645 -303.388272) (xy 36.308771 -303.436293)
			(xy 36.324481 -303.487223) (xy 36.332424 -303.539927) (xy 36.332922 -303.566576) (xy 36.332424 -303.593225)
			(xy 36.324481 -303.645929) (xy 36.308771 -303.696859) (xy 36.285645 -303.74488) (xy 36.267632 -303.7713)
			(xy 37.564568 -303.7713) (xy 37.564568 -303.36236) (xy 37.564988 -303.352207) (xy 37.572791 -303.33346)
			(xy 37.587187 -303.319139) (xy 37.605975 -303.311435) (xy 37.61613 -303.311052) (xy 39.01567 -303.311052)
			(xy 39.025796 -303.311551) (xy 39.044519 -303.319271) (xy 39.058877 -303.333554) (xy 39.066695 -303.352236)
			(xy 39.067232 -303.36236) (xy 39.067232 -303.7713) (xy 39.066779 -303.78145) (xy 39.058989 -303.800196)
			(xy 39.044603 -303.814518) (xy 39.025822 -303.822224) (xy 39.01567 -303.822608) (xy 37.61613 -303.822608)
			(xy 37.606011 -303.82205) (xy 37.5873 -303.814341) (xy 37.572944 -303.800077) (xy 37.565115 -303.781416)
			(xy 37.564568 -303.7713) (xy 36.267632 -303.7713) (xy 36.255621 -303.788917) (xy 36.219369 -303.827988)
			(xy 36.177698 -303.861219) (xy 36.13154 -303.887868) (xy 36.081926 -303.90734) (xy 36.029964 -303.9192)
			(xy 35.976814 -303.923184) (xy 35.923664 -303.9192) (xy 35.871702 -303.90734) (xy 35.822088 -303.887868)
			(xy 35.77593 -303.861219) (xy 35.734259 -303.827988) (xy 35.698007 -303.788917) (xy 35.667983 -303.74488)
			(xy 35.644857 -303.696859) (xy 35.629147 -303.645929) (xy 35.621204 -303.593225) (xy 34.122624 -303.593225)
			(xy 34.114681 -303.645929) (xy 34.098971 -303.696859) (xy 34.075845 -303.74488) (xy 34.045821 -303.788917)
			(xy 34.009569 -303.827988) (xy 33.967898 -303.861219) (xy 33.92174 -303.887868) (xy 33.872126 -303.90734)
			(xy 33.820164 -303.9192) (xy 33.767014 -303.923184) (xy 33.713864 -303.9192) (xy 33.661902 -303.90734)
			(xy 33.612288 -303.887868) (xy 33.56613 -303.861219) (xy 33.524459 -303.827988) (xy 33.488207 -303.788917)
			(xy 33.458183 -303.74488) (xy 33.435057 -303.696859) (xy 33.419347 -303.645929) (xy 33.411404 -303.593225)
			(xy 32.391858 -303.593225) (xy 32.391858 -304.621438) (xy 34.120836 -304.621438) (xy 34.120836 -304.212498)
			(xy 34.121332 -304.20234) (xy 34.129106 -304.183572) (xy 34.143472 -304.169206) (xy 34.16224 -304.161432)
			(xy 34.172398 -304.160936) (xy 35.571938 -304.160936) (xy 35.579808 -304.161248) (xy 35.594807 -304.166028)
			(xy 35.601402 -304.170334) (xy 35.613163 -304.177921) (xy 35.6396 -304.187071) (xy 35.667527 -304.188711)
			(xy 35.694853 -304.182719) (xy 35.719531 -304.169544) (xy 35.729926 -304.160174) (xy 35.749924 -304.141583)
			(xy 35.794574 -304.110157) (xy 35.8435 -304.08592) (xy 35.895554 -304.069439) (xy 35.949514 -304.061102)
			(xy 35.976814 -304.060606) (xy 36.003464 -304.061077) (xy 36.056167 -304.069022) (xy 36.107098 -304.084734)
			(xy 36.155119 -304.107861) (xy 36.199156 -304.137887) (xy 36.238227 -304.174141) (xy 36.271458 -304.215812)
			(xy 36.298107 -304.261971) (xy 36.317579 -304.311587) (xy 36.329439 -304.36355) (xy 36.333422 -304.4167)
			(xy 36.331424 -304.443363) (xy 36.855136 -304.443363) (xy 36.855136 -304.390065) (xy 36.863079 -304.337361)
			(xy 36.878789 -304.286431) (xy 36.901915 -304.23841) (xy 36.931939 -304.194373) (xy 36.968191 -304.155302)
			(xy 37.009862 -304.122071) (xy 37.05602 -304.095422) (xy 37.105634 -304.07595) (xy 37.157596 -304.06409)
			(xy 37.210746 -304.060107) (xy 37.263896 -304.06409) (xy 37.315858 -304.07595) (xy 37.365472 -304.095422)
			(xy 37.41163 -304.122071) (xy 37.453301 -304.155302) (xy 37.489553 -304.194373) (xy 37.519577 -304.23841)
			(xy 37.542703 -304.286431) (xy 37.558413 -304.337361) (xy 37.566356 -304.390065) (xy 37.566854 -304.416714)
			(xy 37.566356 -304.443363) (xy 37.558413 -304.496067) (xy 37.542703 -304.546997) (xy 37.519577 -304.595018)
			(xy 37.489553 -304.639055) (xy 37.453301 -304.678126) (xy 37.41163 -304.711357) (xy 37.365472 -304.738006)
			(xy 37.315858 -304.757478) (xy 37.263896 -304.769338) (xy 37.210746 -304.773322) (xy 37.157596 -304.769338)
			(xy 37.105634 -304.757478) (xy 37.05602 -304.738006) (xy 37.009862 -304.711357) (xy 36.968191 -304.678126)
			(xy 36.931939 -304.639055) (xy 36.901915 -304.595018) (xy 36.878789 -304.546997) (xy 36.863079 -304.496067)
			(xy 36.855136 -304.443363) (xy 36.331424 -304.443363) (xy 36.329439 -304.46985) (xy 36.317579 -304.521813)
			(xy 36.298107 -304.571429) (xy 36.271458 -304.617588) (xy 36.238227 -304.659259) (xy 36.199156 -304.695513)
			(xy 36.155119 -304.725539) (xy 36.107098 -304.748666) (xy 36.056167 -304.764378) (xy 36.003464 -304.772323)
			(xy 35.976814 -304.772822) (xy 35.949551 -304.772314) (xy 35.895664 -304.763998) (xy 35.843676 -304.747558)
			(xy 35.794804 -304.723379) (xy 35.750194 -304.692028) (xy 35.73018 -304.673508) (xy 35.719773 -304.664088)
			(xy 35.695028 -304.650858) (xy 35.667614 -304.644876) (xy 35.639607 -304.646597) (xy 35.61313 -304.655889)
			(xy 35.601402 -304.663602) (xy 35.594792 -304.66788) (xy 35.579804 -304.672674) (xy 35.571938 -304.673)
			(xy 34.172398 -304.673) (xy 34.162245 -304.672469) (xy 34.143483 -304.664701) (xy 34.129119 -304.650347)
			(xy 34.121338 -304.631591) (xy 34.120836 -304.621438) (xy 32.391858 -304.621438) (xy 32.391858 -305.293247)
			(xy 33.411404 -305.293247) (xy 33.411404 -305.239949) (xy 33.419347 -305.187245) (xy 33.435057 -305.136315)
			(xy 33.458183 -305.088294) (xy 33.488207 -305.044257) (xy 33.524459 -305.005186) (xy 33.56613 -304.971955)
			(xy 33.612288 -304.945306) (xy 33.661902 -304.925834) (xy 33.713864 -304.913974) (xy 33.767014 -304.909991)
			(xy 33.820164 -304.913974) (xy 33.872126 -304.925834) (xy 33.92174 -304.945306) (xy 33.967898 -304.971955)
			(xy 34.009569 -305.005186) (xy 34.045821 -305.044257) (xy 34.075845 -305.088294) (xy 34.098971 -305.136315)
			(xy 34.114681 -305.187245) (xy 34.122624 -305.239949) (xy 34.123122 -305.266598) (xy 34.122624 -305.293247)
			(xy 35.621204 -305.293247) (xy 35.621204 -305.239949) (xy 35.629147 -305.187245) (xy 35.644857 -305.136315)
			(xy 35.667983 -305.088294) (xy 35.698007 -305.044257) (xy 35.734259 -305.005186) (xy 35.77593 -304.971955)
			(xy 35.822088 -304.945306) (xy 35.871702 -304.925834) (xy 35.923664 -304.913974) (xy 35.976814 -304.909991)
			(xy 36.029964 -304.913974) (xy 36.081926 -304.925834) (xy 36.13154 -304.945306) (xy 36.177698 -304.971955)
			(xy 36.219369 -305.005186) (xy 36.255621 -305.044257) (xy 36.285645 -305.088294) (xy 36.308771 -305.136315)
			(xy 36.324481 -305.187245) (xy 36.332424 -305.239949) (xy 36.332922 -305.266598) (xy 36.332424 -305.293247)
			(xy 36.324481 -305.345951) (xy 36.308771 -305.396881) (xy 36.285645 -305.444902) (xy 36.267632 -305.471322)
			(xy 37.564568 -305.471322) (xy 37.564568 -305.062382) (xy 37.56495 -305.052206) (xy 37.572747 -305.033405)
			(xy 37.587145 -305.01902) (xy 37.605953 -305.011241) (xy 37.61613 -305.01082) (xy 39.01567 -305.01082)
			(xy 39.025837 -305.011288) (xy 39.044628 -305.01906) (xy 39.059013 -305.033432) (xy 39.066802 -305.052215)
			(xy 39.067232 -305.062382) (xy 39.067232 -305.471322) (xy 39.066853 -305.481499) (xy 39.059055 -305.5003)
			(xy 39.044656 -305.514685) (xy 39.025847 -305.522463) (xy 39.01567 -305.522884) (xy 37.61613 -305.522884)
			(xy 37.605963 -305.522412) (xy 37.587173 -305.514641) (xy 37.572788 -305.50027) (xy 37.564998 -305.481488)
			(xy 37.564568 -305.471322) (xy 36.267632 -305.471322) (xy 36.255621 -305.488939) (xy 36.219369 -305.52801)
			(xy 36.177698 -305.561241) (xy 36.13154 -305.58789) (xy 36.081926 -305.607362) (xy 36.029964 -305.619222)
			(xy 35.976814 -305.623206) (xy 35.923664 -305.619222) (xy 35.871702 -305.607362) (xy 35.822088 -305.58789)
			(xy 35.77593 -305.561241) (xy 35.734259 -305.52801) (xy 35.698007 -305.488939) (xy 35.667983 -305.444902)
			(xy 35.644857 -305.396881) (xy 35.629147 -305.345951) (xy 35.621204 -305.293247) (xy 34.122624 -305.293247)
			(xy 34.114681 -305.345951) (xy 34.098971 -305.396881) (xy 34.075845 -305.444902) (xy 34.045821 -305.488939)
			(xy 34.009569 -305.52801) (xy 33.967898 -305.561241) (xy 33.92174 -305.58789) (xy 33.872126 -305.607362)
			(xy 33.820164 -305.619222) (xy 33.767014 -305.623206) (xy 33.713864 -305.619222) (xy 33.661902 -305.607362)
			(xy 33.612288 -305.58789) (xy 33.56613 -305.561241) (xy 33.524459 -305.52801) (xy 33.488207 -305.488939)
			(xy 33.458183 -305.444902) (xy 33.435057 -305.396881) (xy 33.419347 -305.345951) (xy 33.411404 -305.293247)
			(xy 32.391858 -305.293247) (xy 32.391858 -306.32146) (xy 34.120836 -306.32146) (xy 34.120836 -305.91252)
			(xy 34.121239 -305.902363) (xy 34.129034 -305.883604) (xy 34.143438 -305.869278) (xy 34.162238 -305.861584)
			(xy 34.172398 -305.861212) (xy 35.571938 -305.861212) (xy 35.579791 -305.861459) (xy 35.594788 -305.866116)
			(xy 35.601402 -305.870356) (xy 35.613165 -305.87794) (xy 35.639601 -305.887087) (xy 35.667527 -305.888727)
			(xy 35.694852 -305.882736) (xy 35.71953 -305.869564) (xy 35.729926 -305.860196) (xy 35.749927 -305.841609)
			(xy 35.794576 -305.810182) (xy 35.843501 -305.785943) (xy 35.895554 -305.769461) (xy 35.949514 -305.761124)
			(xy 35.976814 -305.760628) (xy 36.003465 -305.761055) (xy 36.056172 -305.769001) (xy 36.107106 -305.784714)
			(xy 36.15513 -305.807842) (xy 36.19917 -305.83787) (xy 36.238243 -305.874126) (xy 36.271476 -305.9158)
			(xy 36.298126 -305.961962) (xy 36.3176 -306.01158) (xy 36.32946 -306.063546) (xy 36.333444 -306.1167)
			(xy 36.331444 -306.143385) (xy 36.855136 -306.143385) (xy 36.855136 -306.090087) (xy 36.863079 -306.037383)
			(xy 36.878789 -305.986453) (xy 36.901915 -305.938432) (xy 36.931939 -305.894395) (xy 36.968191 -305.855324)
			(xy 37.009862 -305.822093) (xy 37.05602 -305.795444) (xy 37.105634 -305.775972) (xy 37.157596 -305.764112)
			(xy 37.210746 -305.760129) (xy 37.263896 -305.764112) (xy 37.315858 -305.775972) (xy 37.365472 -305.795444)
			(xy 37.41163 -305.822093) (xy 37.453301 -305.855324) (xy 37.489553 -305.894395) (xy 37.519577 -305.938432)
			(xy 37.542703 -305.986453) (xy 37.558413 -306.037383) (xy 37.566356 -306.090087) (xy 37.566854 -306.116736)
			(xy 37.566356 -306.143385) (xy 37.558413 -306.196089) (xy 37.542703 -306.247019) (xy 37.519577 -306.29504)
			(xy 37.489553 -306.339077) (xy 37.453301 -306.378148) (xy 37.41163 -306.411379) (xy 37.365472 -306.438028)
			(xy 37.315858 -306.4575) (xy 37.263896 -306.46936) (xy 37.210746 -306.473344) (xy 37.157596 -306.46936)
			(xy 37.105634 -306.4575) (xy 37.05602 -306.438028) (xy 37.009862 -306.411379) (xy 36.968191 -306.378148)
			(xy 36.931939 -306.339077) (xy 36.901915 -306.29504) (xy 36.878789 -306.247019) (xy 36.863079 -306.196089)
			(xy 36.855136 -306.143385) (xy 36.331444 -306.143385) (xy 36.32946 -306.169854) (xy 36.3176 -306.22182)
			(xy 36.298126 -306.271438) (xy 36.271476 -306.3176) (xy 36.238243 -306.359274) (xy 36.19917 -306.39553)
			(xy 36.15513 -306.425558) (xy 36.107106 -306.448686) (xy 36.056172 -306.464399) (xy 36.003465 -306.472345)
			(xy 35.976814 -306.472844) (xy 35.94955 -306.472358) (xy 35.895661 -306.464039) (xy 35.843672 -306.447596)
			(xy 35.7948 -306.423411) (xy 35.750192 -306.392053) (xy 35.73018 -306.37353) (xy 35.719775 -306.364111)
			(xy 35.695027 -306.35089) (xy 35.667614 -306.344912) (xy 35.639609 -306.346631) (xy 35.613132 -306.355916)
			(xy 35.601402 -306.363624) (xy 35.594789 -306.367868) (xy 35.579791 -306.372525) (xy 35.571938 -306.372768)
			(xy 34.172398 -306.372768) (xy 34.162272 -306.372275) (xy 34.143553 -306.364548) (xy 34.129197 -306.350264)
			(xy 34.121376 -306.331583) (xy 34.120836 -306.32146) (xy 32.391858 -306.32146) (xy 32.391858 -306.993269)
			(xy 33.411404 -306.993269) (xy 33.411404 -306.939971) (xy 33.419347 -306.887267) (xy 33.435057 -306.836337)
			(xy 33.458183 -306.788316) (xy 33.488207 -306.744279) (xy 33.524459 -306.705208) (xy 33.56613 -306.671977)
			(xy 33.612288 -306.645328) (xy 33.661902 -306.625856) (xy 33.713864 -306.613996) (xy 33.767014 -306.610013)
			(xy 33.820164 -306.613996) (xy 33.872126 -306.625856) (xy 33.92174 -306.645328) (xy 33.967898 -306.671977)
			(xy 34.009569 -306.705208) (xy 34.045821 -306.744279) (xy 34.075845 -306.788316) (xy 34.098971 -306.836337)
			(xy 34.114681 -306.887267) (xy 34.122624 -306.939971) (xy 34.123122 -306.96662) (xy 34.122624 -306.993269)
			(xy 35.621204 -306.993269) (xy 35.621204 -306.939971) (xy 35.629147 -306.887267) (xy 35.644857 -306.836337)
			(xy 35.667983 -306.788316) (xy 35.698007 -306.744279) (xy 35.734259 -306.705208) (xy 35.77593 -306.671977)
			(xy 35.822088 -306.645328) (xy 35.871702 -306.625856) (xy 35.923664 -306.613996) (xy 35.976814 -306.610013)
			(xy 36.029964 -306.613996) (xy 36.081926 -306.625856) (xy 36.13154 -306.645328) (xy 36.177698 -306.671977)
			(xy 36.219369 -306.705208) (xy 36.255621 -306.744279) (xy 36.285645 -306.788316) (xy 36.308771 -306.836337)
			(xy 36.324481 -306.887267) (xy 36.332424 -306.939971) (xy 36.332922 -306.96662) (xy 36.332424 -306.993269)
			(xy 36.324481 -307.045973) (xy 36.308771 -307.096903) (xy 36.285645 -307.144924) (xy 36.267632 -307.171344)
			(xy 37.564568 -307.171344) (xy 37.564568 -306.762404) (xy 37.565024 -306.752254) (xy 37.572813 -306.733508)
			(xy 37.587198 -306.719186) (xy 37.605978 -306.71148) (xy 37.61613 -306.711096) (xy 39.01567 -306.711096)
			(xy 39.025789 -306.71165) (xy 39.044502 -306.719359) (xy 39.058857 -306.733625) (xy 39.066686 -306.752288)
			(xy 39.067232 -306.762404) (xy 39.067232 -307.171344) (xy 39.066815 -307.181497) (xy 39.059011 -307.200244)
			(xy 39.044614 -307.214565) (xy 39.025825 -307.222269) (xy 39.01567 -307.222652) (xy 37.61613 -307.222652)
			(xy 37.606004 -307.222149) (xy 37.587282 -307.214429) (xy 37.572924 -307.200148) (xy 37.565106 -307.181467)
			(xy 37.564568 -307.171344) (xy 36.267632 -307.171344) (xy 36.255621 -307.188961) (xy 36.219369 -307.228032)
			(xy 36.177698 -307.261263) (xy 36.13154 -307.287912) (xy 36.081926 -307.307384) (xy 36.029964 -307.319244)
			(xy 35.976814 -307.323228) (xy 35.923664 -307.319244) (xy 35.871702 -307.307384) (xy 35.822088 -307.287912)
			(xy 35.77593 -307.261263) (xy 35.734259 -307.228032) (xy 35.698007 -307.188961) (xy 35.667983 -307.144924)
			(xy 35.644857 -307.096903) (xy 35.629147 -307.045973) (xy 35.621204 -306.993269) (xy 34.122624 -306.993269)
			(xy 34.114681 -307.045973) (xy 34.098971 -307.096903) (xy 34.075845 -307.144924) (xy 34.045821 -307.188961)
			(xy 34.009569 -307.228032) (xy 33.967898 -307.261263) (xy 33.92174 -307.287912) (xy 33.872126 -307.307384)
			(xy 33.820164 -307.319244) (xy 33.767014 -307.323228) (xy 33.713864 -307.319244) (xy 33.661902 -307.307384)
			(xy 33.612288 -307.287912) (xy 33.56613 -307.261263) (xy 33.524459 -307.228032) (xy 33.488207 -307.188961)
			(xy 33.458183 -307.144924) (xy 33.435057 -307.096903) (xy 33.419347 -307.045973) (xy 33.411404 -306.993269)
			(xy 32.391858 -306.993269) (xy 32.391858 -308.021482) (xy 34.120836 -308.021482) (xy 34.120836 -307.612542)
			(xy 34.121298 -307.602373) (xy 34.129069 -307.58358) (xy 34.143443 -307.569194) (xy 34.16223 -307.561407)
			(xy 34.172398 -307.56098) (xy 35.571938 -307.56098) (xy 35.579809 -307.561285) (xy 35.594808 -307.566069)
			(xy 35.601402 -307.570378) (xy 35.613166 -307.577959) (xy 35.639602 -307.587103) (xy 35.667527 -307.588743)
			(xy 35.694851 -307.582753) (xy 35.719529 -307.569584) (xy 35.729926 -307.560218) (xy 35.74993 -307.541634)
			(xy 35.794578 -307.510206) (xy 35.843502 -307.485966) (xy 35.895555 -307.469484) (xy 35.949514 -307.461146)
			(xy 35.976814 -307.46065) (xy 36.003459 -307.461233) (xy 36.056155 -307.469178) (xy 36.107078 -307.484887)
			(xy 36.155091 -307.50801) (xy 36.199121 -307.538031) (xy 36.238185 -307.574279) (xy 36.271411 -307.615944)
			(xy 36.298056 -307.662096) (xy 36.317525 -307.711703) (xy 36.329383 -307.763658) (xy 36.333365 -307.8168)
			(xy 36.331371 -307.843407) (xy 36.855136 -307.843407) (xy 36.855136 -307.790109) (xy 36.863079 -307.737405)
			(xy 36.878789 -307.686475) (xy 36.901915 -307.638454) (xy 36.931939 -307.594417) (xy 36.968191 -307.555346)
			(xy 37.009862 -307.522115) (xy 37.05602 -307.495466) (xy 37.105634 -307.475994) (xy 37.157596 -307.464134)
			(xy 37.210746 -307.460151) (xy 37.263896 -307.464134) (xy 37.315858 -307.475994) (xy 37.365472 -307.495466)
			(xy 37.41163 -307.522115) (xy 37.453301 -307.555346) (xy 37.489553 -307.594417) (xy 37.519577 -307.638454)
			(xy 37.542703 -307.686475) (xy 37.558413 -307.737405) (xy 37.566356 -307.790109) (xy 37.566854 -307.816758)
			(xy 37.566356 -307.843407) (xy 37.558413 -307.896111) (xy 37.542703 -307.947041) (xy 37.519577 -307.995062)
			(xy 37.489553 -308.039099) (xy 37.453301 -308.07817) (xy 37.41163 -308.111401) (xy 37.365472 -308.13805)
			(xy 37.315858 -308.157522) (xy 37.263896 -308.169382) (xy 37.210746 -308.173366) (xy 37.157596 -308.169382)
			(xy 37.105634 -308.157522) (xy 37.05602 -308.13805) (xy 37.009862 -308.111401) (xy 36.968191 -308.07817)
			(xy 36.931939 -308.039099) (xy 36.901915 -307.995062) (xy 36.878789 -307.947041) (xy 36.863079 -307.896111)
			(xy 36.855136 -307.843407) (xy 36.331371 -307.843407) (xy 36.329383 -307.869942) (xy 36.317525 -307.921897)
			(xy 36.298056 -307.971504) (xy 36.271411 -308.017656) (xy 36.238185 -308.059321) (xy 36.199121 -308.095569)
			(xy 36.155091 -308.12559) (xy 36.107078 -308.148713) (xy 36.056155 -308.164422) (xy 36.003459 -308.172367)
			(xy 35.976814 -308.172866) (xy 35.94955 -308.172374) (xy 35.895662 -308.164056) (xy 35.843673 -308.147613)
			(xy 35.794802 -308.123431) (xy 35.750192 -308.092074) (xy 35.73018 -308.073552) (xy 35.719774 -308.064133)
			(xy 35.695028 -308.050909) (xy 35.667614 -308.04493) (xy 35.639608 -308.04665) (xy 35.613132 -308.055937)
			(xy 35.601402 -308.063646) (xy 35.594794 -308.067928) (xy 35.579804 -308.072719) (xy 35.571938 -308.073044)
			(xy 34.172398 -308.073044) (xy 34.162224 -308.072637) (xy 34.143426 -308.064848) (xy 34.12904 -308.050457)
			(xy 34.121259 -308.031656) (xy 34.120836 -308.021482) (xy 32.391858 -308.021482) (xy 32.391858 -308.693291)
			(xy 33.411404 -308.693291) (xy 33.411404 -308.639993) (xy 33.419347 -308.587289) (xy 33.435057 -308.536359)
			(xy 33.458183 -308.488338) (xy 33.488207 -308.444301) (xy 33.524459 -308.40523) (xy 33.56613 -308.371999)
			(xy 33.612288 -308.34535) (xy 33.661902 -308.325878) (xy 33.713864 -308.314018) (xy 33.767014 -308.310035)
			(xy 33.820164 -308.314018) (xy 33.872126 -308.325878) (xy 33.92174 -308.34535) (xy 33.967898 -308.371999)
			(xy 34.009569 -308.40523) (xy 34.045821 -308.444301) (xy 34.075845 -308.488338) (xy 34.098971 -308.536359)
			(xy 34.114681 -308.587289) (xy 34.122624 -308.639993) (xy 34.123122 -308.666642) (xy 34.122624 -308.693291)
			(xy 35.621204 -308.693291) (xy 35.621204 -308.639993) (xy 35.629147 -308.587289) (xy 35.644857 -308.536359)
			(xy 35.667983 -308.488338) (xy 35.698007 -308.444301) (xy 35.734259 -308.40523) (xy 35.77593 -308.371999)
			(xy 35.822088 -308.34535) (xy 35.871702 -308.325878) (xy 35.923664 -308.314018) (xy 35.976814 -308.310035)
			(xy 36.029964 -308.314018) (xy 36.081926 -308.325878) (xy 36.13154 -308.34535) (xy 36.177698 -308.371999)
			(xy 36.219369 -308.40523) (xy 36.255621 -308.444301) (xy 36.285645 -308.488338) (xy 36.308771 -308.536359)
			(xy 36.324481 -308.587289) (xy 36.332424 -308.639993) (xy 36.332922 -308.666642) (xy 36.332424 -308.693291)
			(xy 36.324481 -308.745995) (xy 36.308771 -308.796925) (xy 36.285645 -308.844946) (xy 36.267632 -308.871366)
			(xy 37.564568 -308.871366) (xy 37.564568 -308.462426) (xy 37.564986 -308.452252) (xy 37.572768 -308.433453)
			(xy 37.587156 -308.419066) (xy 37.605956 -308.411285) (xy 37.61613 -308.410864) (xy 39.01567 -308.410864)
			(xy 39.025843 -308.411289) (xy 39.044642 -308.419069) (xy 39.059029 -308.433455) (xy 39.06681 -308.452253)
			(xy 39.067232 -308.462426) (xy 39.067232 -308.871366) (xy 39.066807 -308.881539) (xy 39.059028 -308.900339)
			(xy 39.044642 -308.914726) (xy 39.025843 -308.922507) (xy 39.01567 -308.922928) (xy 37.61613 -308.922928)
			(xy 37.605956 -308.922511) (xy 37.587156 -308.914729) (xy 37.572769 -308.900341) (xy 37.564989 -308.88154)
			(xy 37.564568 -308.871366) (xy 36.267632 -308.871366) (xy 36.255621 -308.888983) (xy 36.219369 -308.928054)
			(xy 36.177698 -308.961285) (xy 36.13154 -308.987934) (xy 36.081926 -309.007406) (xy 36.029964 -309.019266)
			(xy 35.976814 -309.02325) (xy 35.923664 -309.019266) (xy 35.871702 -309.007406) (xy 35.822088 -308.987934)
			(xy 35.77593 -308.961285) (xy 35.734259 -308.928054) (xy 35.698007 -308.888983) (xy 35.667983 -308.844946)
			(xy 35.644857 -308.796925) (xy 35.629147 -308.745995) (xy 35.621204 -308.693291) (xy 34.122624 -308.693291)
			(xy 34.114681 -308.745995) (xy 34.098971 -308.796925) (xy 34.075845 -308.844946) (xy 34.045821 -308.888983)
			(xy 34.009569 -308.928054) (xy 33.967898 -308.961285) (xy 33.92174 -308.987934) (xy 33.872126 -309.007406)
			(xy 33.820164 -309.019266) (xy 33.767014 -309.02325) (xy 33.713864 -309.019266) (xy 33.661902 -309.007406)
			(xy 33.612288 -308.987934) (xy 33.56613 -308.961285) (xy 33.524459 -308.928054) (xy 33.488207 -308.888983)
			(xy 33.458183 -308.844946) (xy 33.435057 -308.796925) (xy 33.419347 -308.745995) (xy 33.411404 -308.693291)
			(xy 32.391858 -308.693291) (xy 32.391858 -309.721504) (xy 34.120836 -309.721504) (xy 34.120836 -309.312564)
			(xy 34.121193 -309.302403) (xy 34.129007 -309.283643) (xy 34.143424 -309.26932) (xy 34.162234 -309.261628)
			(xy 34.172398 -309.261256) (xy 35.571938 -309.261256) (xy 35.579791 -309.261496) (xy 35.594788 -309.266157)
			(xy 35.601402 -309.2704) (xy 35.613161 -309.277993) (xy 35.639598 -309.287145) (xy 35.667527 -309.288786)
			(xy 35.694854 -309.282792) (xy 35.719532 -309.269612) (xy 35.729926 -309.26024) (xy 35.749918 -309.241643)
			(xy 35.79457 -309.210219) (xy 35.843498 -309.185983) (xy 35.895553 -309.169504) (xy 35.949513 -309.161167)
			(xy 35.976814 -309.160672) (xy 36.003461 -309.161211) (xy 36.05616 -309.169156) (xy 36.107086 -309.184866)
			(xy 36.155102 -309.207991) (xy 36.199135 -309.238014) (xy 36.238201 -309.274264) (xy 36.271429 -309.315932)
			(xy 36.298076 -309.362086) (xy 36.317546 -309.411697) (xy 36.329404 -309.463655) (xy 36.333387 -309.5168)
			(xy 36.331391 -309.543429) (xy 36.855136 -309.543429) (xy 36.855136 -309.490131) (xy 36.863079 -309.437427)
			(xy 36.878789 -309.386497) (xy 36.901915 -309.338476) (xy 36.931939 -309.294439) (xy 36.968191 -309.255368)
			(xy 37.009862 -309.222137) (xy 37.05602 -309.195488) (xy 37.105634 -309.176016) (xy 37.157596 -309.164156)
			(xy 37.210746 -309.160173) (xy 37.263896 -309.164156) (xy 37.315858 -309.176016) (xy 37.365472 -309.195488)
			(xy 37.41163 -309.222137) (xy 37.453301 -309.255368) (xy 37.489553 -309.294439) (xy 37.519577 -309.338476)
			(xy 37.542703 -309.386497) (xy 37.558413 -309.437427) (xy 37.566356 -309.490131) (xy 37.566854 -309.51678)
			(xy 37.566356 -309.543429) (xy 37.558413 -309.596133) (xy 37.542703 -309.647063) (xy 37.519577 -309.695084)
			(xy 37.489553 -309.739121) (xy 37.453301 -309.778192) (xy 37.41163 -309.811423) (xy 37.365472 -309.838072)
			(xy 37.315858 -309.857544) (xy 37.263896 -309.869404) (xy 37.210746 -309.873388) (xy 37.157596 -309.869404)
			(xy 37.105634 -309.857544) (xy 37.05602 -309.838072) (xy 37.009862 -309.811423) (xy 36.968191 -309.778192)
			(xy 36.931939 -309.739121) (xy 36.901915 -309.695084) (xy 36.878789 -309.647063) (xy 36.863079 -309.596133)
			(xy 36.855136 -309.543429) (xy 36.331391 -309.543429) (xy 36.329404 -309.569945) (xy 36.317546 -309.621903)
			(xy 36.298076 -309.671514) (xy 36.271429 -309.717668) (xy 36.238201 -309.759336) (xy 36.199135 -309.795586)
			(xy 36.155102 -309.825609) (xy 36.107086 -309.848734) (xy 36.05616 -309.864444) (xy 36.003461 -309.872389)
			(xy 35.976814 -309.872888) (xy 35.949551 -309.872389) (xy 35.895662 -309.864072) (xy 35.843674 -309.847631)
			(xy 35.794803 -309.82345) (xy 35.750193 -309.792095) (xy 35.73018 -309.773574) (xy 35.719774 -309.764155)
			(xy 35.695028 -309.750928) (xy 35.667614 -309.744948) (xy 35.639608 -309.746668) (xy 35.613131 -309.755957)
			(xy 35.601402 -309.763668) (xy 35.594786 -309.767906) (xy 35.579791 -309.772568) (xy 35.571938 -309.772812)
			(xy 34.172398 -309.772812) (xy 34.162278 -309.772277) (xy 34.143566 -309.764558) (xy 34.129212 -309.750287)
			(xy 34.121384 -309.731621) (xy 34.120836 -309.721504) (xy 32.391858 -309.721504) (xy 32.391858 -310.393313)
			(xy 33.411404 -310.393313) (xy 33.411404 -310.340015) (xy 33.419347 -310.287311) (xy 33.435057 -310.236381)
			(xy 33.458183 -310.18836) (xy 33.488207 -310.144323) (xy 33.524459 -310.105252) (xy 33.56613 -310.072021)
			(xy 33.612288 -310.045372) (xy 33.661902 -310.0259) (xy 33.713864 -310.01404) (xy 33.767014 -310.010057)
			(xy 33.820164 -310.01404) (xy 33.872126 -310.0259) (xy 33.92174 -310.045372) (xy 33.967898 -310.072021)
			(xy 34.009569 -310.105252) (xy 34.045821 -310.144323) (xy 34.075845 -310.18836) (xy 34.098971 -310.236381)
			(xy 34.114681 -310.287311) (xy 34.122624 -310.340015) (xy 34.123122 -310.366664) (xy 34.122624 -310.393313)
			(xy 35.621204 -310.393313) (xy 35.621204 -310.340015) (xy 35.629147 -310.287311) (xy 35.644857 -310.236381)
			(xy 35.667983 -310.18836) (xy 35.698007 -310.144323) (xy 35.734259 -310.105252) (xy 35.77593 -310.072021)
			(xy 35.822088 -310.045372) (xy 35.871702 -310.0259) (xy 35.923664 -310.01404) (xy 35.976814 -310.010057)
			(xy 36.029964 -310.01404) (xy 36.081926 -310.0259) (xy 36.13154 -310.045372) (xy 36.177698 -310.072021)
			(xy 36.219369 -310.105252) (xy 36.255621 -310.144323) (xy 36.285645 -310.18836) (xy 36.308771 -310.236381)
			(xy 36.324481 -310.287311) (xy 36.332424 -310.340015) (xy 36.332922 -310.366664) (xy 36.332424 -310.393313)
			(xy 36.324481 -310.446017) (xy 36.308771 -310.496947) (xy 36.285645 -310.544968) (xy 36.267632 -310.571388)
			(xy 37.564568 -310.571388) (xy 37.564568 -310.162448) (xy 37.56506 -310.152301) (xy 37.572834 -310.133556)
			(xy 37.587209 -310.119232) (xy 37.605982 -310.111525) (xy 37.61613 -310.11114) (xy 39.01567 -310.11114)
			(xy 39.025795 -310.111651) (xy 39.044515 -310.119369) (xy 39.058873 -310.133648) (xy 39.066693 -310.152326)
			(xy 39.067232 -310.162448) (xy 39.067232 -310.571388) (xy 39.066769 -310.581537) (xy 39.058984 -310.600283)
			(xy 39.0446 -310.614606) (xy 39.025821 -310.622312) (xy 39.01567 -310.622696) (xy 37.61613 -310.622696)
			(xy 37.60601 -310.62215) (xy 37.587296 -310.614439) (xy 37.57294 -310.600171) (xy 37.565113 -310.581505)
			(xy 37.564568 -310.571388) (xy 36.267632 -310.571388) (xy 36.255621 -310.589005) (xy 36.219369 -310.628076)
			(xy 36.177698 -310.661307) (xy 36.13154 -310.687956) (xy 36.081926 -310.707428) (xy 36.029964 -310.719288)
			(xy 35.976814 -310.723272) (xy 35.923664 -310.719288) (xy 35.871702 -310.707428) (xy 35.822088 -310.687956)
			(xy 35.77593 -310.661307) (xy 35.734259 -310.628076) (xy 35.698007 -310.589005) (xy 35.667983 -310.544968)
			(xy 35.644857 -310.496947) (xy 35.629147 -310.446017) (xy 35.621204 -310.393313) (xy 34.122624 -310.393313)
			(xy 34.114681 -310.446017) (xy 34.098971 -310.496947) (xy 34.075845 -310.544968) (xy 34.045821 -310.589005)
			(xy 34.009569 -310.628076) (xy 33.967898 -310.661307) (xy 33.92174 -310.687956) (xy 33.872126 -310.707428)
			(xy 33.820164 -310.719288) (xy 33.767014 -310.723272) (xy 33.713864 -310.719288) (xy 33.661902 -310.707428)
			(xy 33.612288 -310.687956) (xy 33.56613 -310.661307) (xy 33.524459 -310.628076) (xy 33.488207 -310.589005)
			(xy 33.458183 -310.544968) (xy 33.435057 -310.496947) (xy 33.419347 -310.446017) (xy 33.411404 -310.393313)
			(xy 32.391858 -310.393313) (xy 32.391858 -311.421526) (xy 34.120836 -311.421526) (xy 34.120836 -311.012586)
			(xy 34.121322 -311.002428) (xy 34.129101 -310.983659) (xy 34.143469 -310.969294) (xy 34.16224 -310.96152)
			(xy 34.172398 -310.961024) (xy 35.571938 -310.961024) (xy 35.579808 -310.961338) (xy 35.594807 -310.966117)
			(xy 35.601402 -310.970422) (xy 35.613162 -310.978011) (xy 35.639599 -310.987162) (xy 35.667527 -310.988802)
			(xy 35.694853 -310.982809) (xy 35.719531 -310.969633) (xy 35.729926 -310.960262) (xy 35.749921 -310.941668)
			(xy 35.794572 -310.910243) (xy 35.843499 -310.886006) (xy 35.895553 -310.869526) (xy 35.949514 -310.861189)
			(xy 35.976814 -310.860694) (xy 36.003463 -310.861189) (xy 36.056165 -310.869134) (xy 36.107094 -310.884845)
			(xy 36.155113 -310.907972) (xy 36.199149 -310.937996) (xy 36.238218 -310.974249) (xy 36.271448 -311.015919)
			(xy 36.298096 -311.062077) (xy 36.317567 -311.11169) (xy 36.329427 -311.163651) (xy 36.33341 -311.2168)
			(xy 36.331413 -311.243451) (xy 36.855136 -311.243451) (xy 36.855136 -311.190153) (xy 36.863079 -311.137449)
			(xy 36.878789 -311.086519) (xy 36.901915 -311.038498) (xy 36.931939 -310.994461) (xy 36.968191 -310.95539)
			(xy 37.009862 -310.922159) (xy 37.05602 -310.89551) (xy 37.105634 -310.876038) (xy 37.157596 -310.864178)
			(xy 37.210746 -310.860195) (xy 37.263896 -310.864178) (xy 37.315858 -310.876038) (xy 37.365472 -310.89551)
			(xy 37.41163 -310.922159) (xy 37.453301 -310.95539) (xy 37.489553 -310.994461) (xy 37.519577 -311.038498)
			(xy 37.542703 -311.086519) (xy 37.558413 -311.137449) (xy 37.566356 -311.190153) (xy 37.566854 -311.216802)
			(xy 37.566356 -311.243451) (xy 37.558413 -311.296155) (xy 37.542703 -311.347085) (xy 37.519577 -311.395106)
			(xy 37.489553 -311.439143) (xy 37.453301 -311.478214) (xy 37.41163 -311.511445) (xy 37.365472 -311.538094)
			(xy 37.315858 -311.557566) (xy 37.263896 -311.569426) (xy 37.210746 -311.57341) (xy 37.157596 -311.569426)
			(xy 37.105634 -311.557566) (xy 37.05602 -311.538094) (xy 37.009862 -311.511445) (xy 36.968191 -311.478214)
			(xy 36.931939 -311.439143) (xy 36.901915 -311.395106) (xy 36.878789 -311.347085) (xy 36.863079 -311.296155)
			(xy 36.855136 -311.243451) (xy 36.331413 -311.243451) (xy 36.329427 -311.269949) (xy 36.317567 -311.32191)
			(xy 36.298096 -311.371523) (xy 36.271448 -311.417681) (xy 36.238218 -311.459351) (xy 36.199149 -311.495604)
			(xy 36.155113 -311.525628) (xy 36.107094 -311.548755) (xy 36.056165 -311.564466) (xy 36.003463 -311.572411)
			(xy 35.976814 -311.57291) (xy 35.949551 -311.572405) (xy 35.895663 -311.564089) (xy 35.843675 -311.547648)
			(xy 35.794804 -311.523469) (xy 35.750193 -311.492116) (xy 35.73018 -311.473596) (xy 35.719773 -311.464176)
			(xy 35.695028 -311.450947) (xy 35.667614 -311.444966) (xy 35.639607 -311.446687) (xy 35.61313 -311.455978)
			(xy 35.601402 -311.46369) (xy 35.594791 -311.467967) (xy 35.579804 -311.472762) (xy 35.571938 -311.473088)
			(xy 34.172398 -311.473088) (xy 34.162243 -311.472569) (xy 34.143479 -311.464799) (xy 34.129115 -311.450441)
			(xy 34.121336 -311.43168) (xy 34.120836 -311.421526) (xy 32.391858 -311.421526) (xy 32.391858 -312.27141)
			(xy 34.120836 -312.27141) (xy 34.120836 -311.86247) (xy 34.121309 -311.852311) (xy 34.129093 -311.833541)
			(xy 34.143465 -311.819177) (xy 34.162238 -311.811403) (xy 34.172398 -311.810908) (xy 35.571938 -311.810908)
			(xy 35.579808 -311.811225) (xy 35.594806 -311.816002) (xy 35.601402 -311.820306) (xy 35.613161 -311.827898)
			(xy 35.639598 -311.83705) (xy 35.667527 -311.83869) (xy 35.694854 -311.832697) (xy 35.719532 -311.819518)
			(xy 35.729926 -311.810146) (xy 35.749919 -311.79155) (xy 35.794571 -311.760126) (xy 35.843498 -311.73589)
			(xy 35.895553 -311.71941) (xy 35.949514 -311.711073) (xy 35.976814 -311.710578) (xy 36.003462 -311.711105)
			(xy 36.056161 -311.71905) (xy 36.107088 -311.73476) (xy 36.155105 -311.757886) (xy 36.199139 -311.787909)
			(xy 36.238206 -311.82416) (xy 36.271434 -311.865828) (xy 36.298081 -311.911983) (xy 36.317552 -311.961595)
			(xy 36.329411 -312.013554) (xy 36.333394 -312.0667) (xy 36.329411 -312.119846) (xy 36.317552 -312.171805)
			(xy 36.298081 -312.221417) (xy 36.271434 -312.267572) (xy 36.268373 -312.27141) (xy 37.564568 -312.27141)
			(xy 37.564568 -311.86247) (xy 37.565009 -311.852307) (xy 37.572799 -311.833531) (xy 37.587181 -311.819166)
			(xy 37.605966 -311.811398) (xy 37.61613 -311.810908) (xy 39.01567 -311.810908) (xy 39.025822 -311.811457)
			(xy 39.044585 -311.819216) (xy 39.05895 -311.833565) (xy 39.066731 -311.852318) (xy 39.067232 -311.86247)
			(xy 39.067232 -312.27141) (xy 39.066844 -312.281586) (xy 39.05905 -312.300387) (xy 39.044653 -312.314772)
			(xy 39.025846 -312.322551) (xy 39.01567 -312.322972) (xy 37.61613 -312.322972) (xy 37.605962 -312.322512)
			(xy 37.58717 -312.314738) (xy 37.572784 -312.300364) (xy 37.564996 -312.281578) (xy 37.564568 -312.27141)
			(xy 36.268373 -312.27141) (xy 36.238206 -312.30924) (xy 36.199139 -312.345491) (xy 36.155105 -312.375514)
			(xy 36.107088 -312.39864) (xy 36.056161 -312.41435) (xy 36.003462 -312.422295) (xy 35.976814 -312.422794)
			(xy 35.949551 -312.422294) (xy 35.895663 -312.413977) (xy 35.843674 -312.397536) (xy 35.794803 -312.373355)
			(xy 35.750193 -312.342001) (xy 35.73018 -312.32348) (xy 35.719774 -312.31406) (xy 35.695028 -312.300833)
			(xy 35.667614 -312.294853) (xy 35.639607 -312.296573) (xy 35.613131 -312.305863) (xy 35.601402 -312.313574)
			(xy 35.59479 -312.317849) (xy 35.579804 -312.322646) (xy 35.571938 -312.322972) (xy 34.172398 -312.322972)
			(xy 34.162241 -312.322468) (xy 34.143474 -312.314695) (xy 34.129109 -312.300333) (xy 34.121333 -312.281567)
			(xy 34.120836 -312.27141) (xy 32.391858 -312.27141) (xy 32.391858 -312.943219) (xy 33.411404 -312.943219)
			(xy 33.411404 -312.889921) (xy 33.419347 -312.837217) (xy 33.435057 -312.786287) (xy 33.458183 -312.738266)
			(xy 33.488207 -312.694229) (xy 33.524459 -312.655158) (xy 33.56613 -312.621927) (xy 33.612288 -312.595278)
			(xy 33.661902 -312.575806) (xy 33.713864 -312.563946) (xy 33.767014 -312.559963) (xy 33.820164 -312.563946)
			(xy 33.872126 -312.575806) (xy 33.92174 -312.595278) (xy 33.967898 -312.621927) (xy 34.009569 -312.655158)
			(xy 34.045821 -312.694229) (xy 34.075845 -312.738266) (xy 34.098971 -312.786287) (xy 34.114681 -312.837217)
			(xy 34.122624 -312.889921) (xy 34.123122 -312.91657) (xy 34.122624 -312.943219) (xy 35.621204 -312.943219)
			(xy 35.621204 -312.889921) (xy 35.629147 -312.837217) (xy 35.644857 -312.786287) (xy 35.667983 -312.738266)
			(xy 35.698007 -312.694229) (xy 35.734259 -312.655158) (xy 35.77593 -312.621927) (xy 35.822088 -312.595278)
			(xy 35.871702 -312.575806) (xy 35.923664 -312.563946) (xy 35.976814 -312.559963) (xy 36.029964 -312.563946)
			(xy 36.081926 -312.575806) (xy 36.13154 -312.595278) (xy 36.177698 -312.621927) (xy 36.219369 -312.655158)
			(xy 36.255621 -312.694229) (xy 36.285645 -312.738266) (xy 36.308771 -312.786287) (xy 36.324481 -312.837217)
			(xy 36.332424 -312.889921) (xy 36.332922 -312.91657) (xy 36.332424 -312.943219) (xy 36.324481 -312.995923)
			(xy 36.308771 -313.046853) (xy 36.285645 -313.094874) (xy 36.267632 -313.121294) (xy 37.564568 -313.121294)
			(xy 37.564568 -312.712354) (xy 37.564997 -312.70219) (xy 37.572792 -312.683414) (xy 37.587178 -312.669049)
			(xy 37.605965 -312.661282) (xy 37.61613 -312.660792) (xy 39.01567 -312.660792) (xy 39.02582 -312.661357)
			(xy 39.04458 -312.669113) (xy 39.058945 -312.683456) (xy 39.066728 -312.702205) (xy 39.067232 -312.712354)
			(xy 39.067232 -313.121294) (xy 39.066831 -313.131469) (xy 39.059042 -313.150269) (xy 39.044649 -313.164655)
			(xy 39.025845 -313.172435) (xy 39.01567 -313.172856) (xy 37.61613 -313.172856) (xy 37.60596 -313.172411)
			(xy 37.587164 -313.164635) (xy 37.572778 -313.150256) (xy 37.564993 -313.131464) (xy 37.564568 -313.121294)
			(xy 36.267632 -313.121294) (xy 36.255621 -313.138911) (xy 36.219369 -313.177982) (xy 36.177698 -313.211213)
			(xy 36.13154 -313.237862) (xy 36.081926 -313.257334) (xy 36.029964 -313.269194) (xy 35.976814 -313.273178)
			(xy 35.923664 -313.269194) (xy 35.871702 -313.257334) (xy 35.822088 -313.237862) (xy 35.77593 -313.211213)
			(xy 35.734259 -313.177982) (xy 35.698007 -313.138911) (xy 35.667983 -313.094874) (xy 35.644857 -313.046853)
			(xy 35.629147 -312.995923) (xy 35.621204 -312.943219) (xy 34.122624 -312.943219) (xy 34.114681 -312.995923)
			(xy 34.098971 -313.046853) (xy 34.075845 -313.094874) (xy 34.045821 -313.138911) (xy 34.009569 -313.177982)
			(xy 33.967898 -313.211213) (xy 33.92174 -313.237862) (xy 33.872126 -313.257334) (xy 33.820164 -313.269194)
			(xy 33.767014 -313.273178) (xy 33.713864 -313.269194) (xy 33.661902 -313.257334) (xy 33.612288 -313.237862)
			(xy 33.56613 -313.211213) (xy 33.524459 -313.177982) (xy 33.488207 -313.138911) (xy 33.458183 -313.094874)
			(xy 33.435057 -313.046853) (xy 33.419347 -312.995923) (xy 33.411404 -312.943219) (xy 32.391858 -312.943219)
			(xy 32.391858 -313.971432) (xy 34.120836 -313.971432) (xy 34.120836 -313.562492) (xy 34.121216 -313.552333)
			(xy 34.129021 -313.533573) (xy 34.143431 -313.519249) (xy 34.162237 -313.511556) (xy 34.172398 -313.511184)
			(xy 35.571938 -313.511184) (xy 35.579792 -313.51142) (xy 35.594789 -313.516083) (xy 35.601402 -313.520328)
			(xy 35.613163 -313.527916) (xy 35.639599 -313.537066) (xy 35.667527 -313.538706) (xy 35.694853 -313.532714)
			(xy 35.719531 -313.519538) (xy 35.729926 -313.510168) (xy 35.749922 -313.491575) (xy 35.794573 -313.46015)
			(xy 35.843499 -313.435913) (xy 35.895553 -313.419432) (xy 35.949514 -313.411095) (xy 35.976814 -313.4106)
			(xy 36.003463 -313.411083) (xy 36.056166 -313.419028) (xy 36.107096 -313.43474) (xy 36.155116 -313.457867)
			(xy 36.199152 -313.487892) (xy 36.238222 -313.524145) (xy 36.271453 -313.565816) (xy 36.298101 -313.611974)
			(xy 36.317573 -313.661588) (xy 36.329433 -313.713551) (xy 36.333416 -313.7667) (xy 36.331418 -313.793357)
			(xy 36.855136 -313.793357) (xy 36.855136 -313.740059) (xy 36.863079 -313.687355) (xy 36.878789 -313.636425)
			(xy 36.901915 -313.588404) (xy 36.931939 -313.544367) (xy 36.968191 -313.505296) (xy 37.009862 -313.472065)
			(xy 37.05602 -313.445416) (xy 37.105634 -313.425944) (xy 37.157596 -313.414084) (xy 37.210746 -313.410101)
			(xy 37.263896 -313.414084) (xy 37.315858 -313.425944) (xy 37.365472 -313.445416) (xy 37.41163 -313.472065)
			(xy 37.453301 -313.505296) (xy 37.489553 -313.544367) (xy 37.519577 -313.588404) (xy 37.542703 -313.636425)
			(xy 37.558413 -313.687355) (xy 37.566356 -313.740059) (xy 37.566854 -313.766708) (xy 37.566356 -313.793357)
			(xy 37.558413 -313.846061) (xy 37.542703 -313.896991) (xy 37.519577 -313.945012) (xy 37.489553 -313.989049)
			(xy 37.453301 -314.02812) (xy 37.41163 -314.061351) (xy 37.365472 -314.088) (xy 37.315858 -314.107472)
			(xy 37.263896 -314.119332) (xy 37.210746 -314.123316) (xy 37.157596 -314.119332) (xy 37.105634 -314.107472)
			(xy 37.05602 -314.088) (xy 37.009862 -314.061351) (xy 36.968191 -314.02812) (xy 36.931939 -313.989049)
			(xy 36.901915 -313.945012) (xy 36.878789 -313.896991) (xy 36.863079 -313.846061) (xy 36.855136 -313.793357)
			(xy 36.331418 -313.793357) (xy 36.329433 -313.819849) (xy 36.317573 -313.871812) (xy 36.298101 -313.921426)
			(xy 36.271453 -313.967584) (xy 36.238222 -314.009255) (xy 36.199152 -314.045508) (xy 36.155116 -314.075533)
			(xy 36.107096 -314.09866) (xy 36.056166 -314.114372) (xy 36.003463 -314.122317) (xy 35.976814 -314.122816)
			(xy 35.949551 -314.12231) (xy 35.895664 -314.113993) (xy 35.843675 -314.097553) (xy 35.794804 -314.073374)
			(xy 35.750194 -314.042022) (xy 35.73018 -314.023502) (xy 35.719773 -314.014082) (xy 35.695028 -314.000853)
			(xy 35.667614 -313.994871) (xy 35.639607 -313.996592) (xy 35.61313 -314.005883) (xy 35.601402 -314.013596)
			(xy 35.594788 -314.017837) (xy 35.579791 -314.022496) (xy 35.571938 -314.02274) (xy 34.172398 -314.02274)
			(xy 34.162269 -314.022274) (xy 34.143544 -314.014542) (xy 34.129187 -314.000249) (xy 34.121371 -313.981559)
			(xy 34.120836 -313.971432) (xy 32.391858 -313.971432) (xy 32.391858 -314.5691) (xy 32.646386 -314.5691)
			(xy 32.650369 -314.515951) (xy 32.662229 -314.46399) (xy 32.6817 -314.414376) (xy 32.708348 -314.368218)
			(xy 32.741578 -314.326548) (xy 32.780647 -314.290295) (xy 32.824683 -314.26027) (xy 32.872702 -314.237143)
			(xy 32.923631 -314.221431) (xy 32.976333 -314.213485) (xy 33.002982 -314.212986) (xy 33.029761 -314.213521)
			(xy 33.082714 -314.221546) (xy 33.13387 -314.237402) (xy 33.182079 -314.260733) (xy 33.226255 -314.291013)
			(xy 33.265404 -314.327562) (xy 33.298644 -314.369556) (xy 33.312354 -314.392564) (xy 33.319931 -314.404825)
			(xy 33.340615 -314.424876) (xy 33.366073 -314.438358) (xy 33.394282 -314.444201) (xy 33.423001 -314.44194)
			(xy 33.449948 -314.431755) (xy 33.472983 -314.414454) (xy 33.482026 -314.403232) (xy 33.498944 -314.381475)
			(xy 33.538357 -314.342952) (xy 33.583237 -314.310967) (xy 33.632513 -314.286285) (xy 33.685005 -314.269495)
			(xy 33.739458 -314.261) (xy 33.767014 -314.260484) (xy 33.793662 -314.260999) (xy 33.846363 -314.268944)
			(xy 33.89729 -314.284655) (xy 33.945308 -314.30778) (xy 33.989342 -314.337804) (xy 34.02841 -314.374056)
			(xy 34.061639 -314.415725) (xy 34.088287 -314.461881) (xy 34.107758 -314.511493) (xy 34.119617 -314.563453)
			(xy 34.1236 -314.6166) (xy 34.121603 -314.643241) (xy 35.621204 -314.643241) (xy 35.621204 -314.589943)
			(xy 35.629147 -314.537239) (xy 35.644857 -314.486309) (xy 35.667983 -314.438288) (xy 35.698007 -314.394251)
			(xy 35.734259 -314.35518) (xy 35.77593 -314.321949) (xy 35.822088 -314.2953) (xy 35.871702 -314.275828)
			(xy 35.923664 -314.263968) (xy 35.976814 -314.259985) (xy 36.029964 -314.263968) (xy 36.081926 -314.275828)
			(xy 36.13154 -314.2953) (xy 36.177698 -314.321949) (xy 36.219369 -314.35518) (xy 36.255621 -314.394251)
			(xy 36.285645 -314.438288) (xy 36.308771 -314.486309) (xy 36.324481 -314.537239) (xy 36.332424 -314.589943)
			(xy 36.332922 -314.616592) (xy 36.332424 -314.643241) (xy 36.324481 -314.695945) (xy 36.308771 -314.746875)
			(xy 36.285645 -314.794896) (xy 36.267632 -314.821316) (xy 37.564568 -314.821316) (xy 37.564568 -314.412376)
			(xy 37.565001 -314.402224) (xy 37.572799 -314.383477) (xy 37.587191 -314.369156) (xy 37.605976 -314.361451)
			(xy 37.61613 -314.361068) (xy 39.01567 -314.361068) (xy 39.025798 -314.361552) (xy 39.044524 -314.369275)
			(xy 39.058883 -314.383563) (xy 39.066698 -314.40225) (xy 39.067232 -314.412376) (xy 39.067232 -314.821316)
			(xy 39.066792 -314.831467) (xy 39.058997 -314.850214) (xy 39.044607 -314.864536) (xy 39.025823 -314.872241)
			(xy 39.01567 -314.872624) (xy 37.61613 -314.872624) (xy 37.606001 -314.872148) (xy 37.587273 -314.864423)
			(xy 37.572915 -314.850133) (xy 37.565101 -314.831443) (xy 37.564568 -314.821316) (xy 36.267632 -314.821316)
			(xy 36.255621 -314.838933) (xy 36.219369 -314.878004) (xy 36.177698 -314.911235) (xy 36.13154 -314.937884)
			(xy 36.081926 -314.957356) (xy 36.029964 -314.969216) (xy 35.976814 -314.9732) (xy 35.923664 -314.969216)
			(xy 35.871702 -314.957356) (xy 35.822088 -314.937884) (xy 35.77593 -314.911235) (xy 35.734259 -314.878004)
			(xy 35.698007 -314.838933) (xy 35.667983 -314.794896) (xy 35.644857 -314.746875) (xy 35.629147 -314.695945)
			(xy 35.621204 -314.643241) (xy 34.121603 -314.643241) (xy 34.119617 -314.669747) (xy 34.107758 -314.721707)
			(xy 34.088287 -314.771319) (xy 34.061639 -314.817475) (xy 34.02841 -314.859144) (xy 33.989342 -314.895396)
			(xy 33.945308 -314.92542) (xy 33.89729 -314.948545) (xy 33.846363 -314.964256) (xy 33.793662 -314.972201)
			(xy 33.767014 -314.9727) (xy 33.740235 -314.972175) (xy 33.687281 -314.964149) (xy 33.636124 -314.948292)
			(xy 33.587915 -314.92496) (xy 33.543739 -314.894677) (xy 33.504591 -314.858127) (xy 33.471351 -314.816131)
			(xy 33.457642 -314.793122) (xy 33.45007 -314.780858) (xy 33.429384 -314.760809) (xy 33.403925 -314.747329)
			(xy 33.375716 -314.741487) (xy 33.346997 -314.743748) (xy 33.320049 -314.753933) (xy 33.297014 -314.771233)
			(xy 33.28797 -314.782454) (xy 33.271077 -314.804232) (xy 33.231657 -314.842749) (xy 33.18677 -314.874729)
			(xy 33.13749 -314.899407) (xy 33.084995 -314.916194) (xy 33.030539 -314.924687) (xy 33.002982 -314.925202)
			(xy 32.976333 -314.924715) (xy 32.923631 -314.916769) (xy 32.872702 -314.901057) (xy 32.824683 -314.87793)
			(xy 32.780647 -314.847905) (xy 32.741578 -314.811652) (xy 32.708348 -314.769982) (xy 32.6817 -314.723824)
			(xy 32.662229 -314.67421) (xy 32.650369 -314.622249) (xy 32.646386 -314.5691) (xy 32.391858 -314.5691)
			(xy 32.391858 -315.671454) (xy 34.120836 -315.671454) (xy 34.120836 -315.262514) (xy 34.121275 -315.252344)
			(xy 34.129055 -315.233549) (xy 34.143436 -315.219164) (xy 34.162228 -315.211378) (xy 34.172398 -315.210952)
			(xy 35.571938 -315.210952) (xy 35.579809 -315.211262) (xy 35.594807 -315.216043) (xy 35.601402 -315.22035)
			(xy 35.613164 -315.227935) (xy 35.6396 -315.237083) (xy 35.667527 -315.238722) (xy 35.694852 -315.232731)
			(xy 35.71953 -315.219558) (xy 35.729926 -315.21019) (xy 35.749926 -315.191602) (xy 35.794575 -315.160175)
			(xy 35.843501 -315.135937) (xy 35.895554 -315.119455) (xy 35.949514 -315.111118) (xy 35.976814 -315.110622)
			(xy 36.003465 -315.111061) (xy 36.056171 -315.119007) (xy 36.107104 -315.134719) (xy 36.155127 -315.157848)
			(xy 36.199166 -315.187875) (xy 36.238238 -315.22413) (xy 36.271471 -315.265803) (xy 36.298121 -315.311964)
			(xy 36.317594 -315.361582) (xy 36.329454 -315.413547) (xy 36.333438 -315.4667) (xy 36.331438 -315.493379)
			(xy 36.855136 -315.493379) (xy 36.855136 -315.440081) (xy 36.863079 -315.387377) (xy 36.878789 -315.336447)
			(xy 36.901915 -315.288426) (xy 36.931939 -315.244389) (xy 36.968191 -315.205318) (xy 37.009862 -315.172087)
			(xy 37.05602 -315.145438) (xy 37.105634 -315.125966) (xy 37.157596 -315.114106) (xy 37.210746 -315.110123)
			(xy 37.263896 -315.114106) (xy 37.315858 -315.125966) (xy 37.365472 -315.145438) (xy 37.41163 -315.172087)
			(xy 37.453301 -315.205318) (xy 37.489553 -315.244389) (xy 37.519577 -315.288426) (xy 37.542703 -315.336447)
			(xy 37.558413 -315.387377) (xy 37.566356 -315.440081) (xy 37.566854 -315.46673) (xy 37.566356 -315.493379)
			(xy 37.558413 -315.546083) (xy 37.542703 -315.597013) (xy 37.519577 -315.645034) (xy 37.489553 -315.689071)
			(xy 37.453301 -315.728142) (xy 37.41163 -315.761373) (xy 37.365472 -315.788022) (xy 37.315858 -315.807494)
			(xy 37.263896 -315.819354) (xy 37.210746 -315.823338) (xy 37.157596 -315.819354) (xy 37.105634 -315.807494)
			(xy 37.05602 -315.788022) (xy 37.009862 -315.761373) (xy 36.968191 -315.728142) (xy 36.931939 -315.689071)
			(xy 36.901915 -315.645034) (xy 36.878789 -315.597013) (xy 36.863079 -315.546083) (xy 36.855136 -315.493379)
			(xy 36.331438 -315.493379) (xy 36.329454 -315.519853) (xy 36.317594 -315.571818) (xy 36.298121 -315.621436)
			(xy 36.271471 -315.667597) (xy 36.238238 -315.70927) (xy 36.199166 -315.745525) (xy 36.155127 -315.775552)
			(xy 36.107104 -315.798681) (xy 36.056171 -315.814393) (xy 36.003465 -315.822339) (xy 35.976814 -315.822838)
			(xy 35.94955 -315.822353) (xy 35.89566 -315.814035) (xy 35.843671 -315.797591) (xy 35.7948 -315.773406)
			(xy 35.750192 -315.742048) (xy 35.73018 -315.723524) (xy 35.719775 -315.714105) (xy 35.695027 -315.700884)
			(xy 35.667614 -315.694907) (xy 35.639609 -315.696626) (xy 35.613132 -315.705911) (xy 35.601402 -315.713618)
			(xy 35.594793 -315.717898) (xy 35.579804 -315.722691) (xy 35.571938 -315.723016) (xy 34.172398 -315.723016)
			(xy 34.162221 -315.722637) (xy 34.143417 -315.714842) (xy 34.129031 -315.700443) (xy 34.121254 -315.681632)
			(xy 34.120836 -315.671454) (xy 32.391858 -315.671454) (xy 32.391858 -316.343263) (xy 33.411404 -316.343263)
			(xy 33.411404 -316.289965) (xy 33.419347 -316.237261) (xy 33.435057 -316.186331) (xy 33.458183 -316.13831)
			(xy 33.488207 -316.094273) (xy 33.524459 -316.055202) (xy 33.56613 -316.021971) (xy 33.612288 -315.995322)
			(xy 33.661902 -315.97585) (xy 33.713864 -315.96399) (xy 33.767014 -315.960007) (xy 33.820164 -315.96399)
			(xy 33.872126 -315.97585) (xy 33.92174 -315.995322) (xy 33.967898 -316.021971) (xy 34.009569 -316.055202)
			(xy 34.045821 -316.094273) (xy 34.075845 -316.13831) (xy 34.098971 -316.186331) (xy 34.114681 -316.237261)
			(xy 34.122624 -316.289965) (xy 34.123122 -316.316614) (xy 34.122624 -316.343263) (xy 35.621204 -316.343263)
			(xy 35.621204 -316.289965) (xy 35.629147 -316.237261) (xy 35.644857 -316.186331) (xy 35.667983 -316.13831)
			(xy 35.698007 -316.094273) (xy 35.734259 -316.055202) (xy 35.77593 -316.021971) (xy 35.822088 -315.995322)
			(xy 35.871702 -315.97585) (xy 35.923664 -315.96399) (xy 35.976814 -315.960007) (xy 36.029964 -315.96399)
			(xy 36.081926 -315.97585) (xy 36.13154 -315.995322) (xy 36.177698 -316.021971) (xy 36.219369 -316.055202)
			(xy 36.255621 -316.094273) (xy 36.285645 -316.13831) (xy 36.308771 -316.186331) (xy 36.324481 -316.237261)
			(xy 36.332424 -316.289965) (xy 36.332922 -316.316614) (xy 36.332424 -316.343263) (xy 36.324481 -316.395967)
			(xy 36.308771 -316.446897) (xy 36.285645 -316.494918) (xy 36.267632 -316.521338) (xy 37.564568 -316.521338)
			(xy 37.564568 -316.112398) (xy 37.564963 -316.102223) (xy 37.572754 -316.083422) (xy 37.587149 -316.069036)
			(xy 37.605954 -316.061257) (xy 37.61613 -316.060836) (xy 39.01567 -316.060836) (xy 39.025839 -316.061289)
			(xy 39.044633 -316.069063) (xy 39.059019 -316.08344) (xy 39.066805 -316.102229) (xy 39.067232 -316.112398)
			(xy 39.067232 -316.521338) (xy 39.066797 -316.531502) (xy 39.059004 -316.550278) (xy 39.044621 -316.564643)
			(xy 39.025835 -316.57241) (xy 39.01567 -316.5729) (xy 37.61613 -316.5729) (xy 37.605979 -316.572343)
			(xy 37.587217 -316.564586) (xy 37.572852 -316.55024) (xy 37.56507 -316.531489) (xy 37.564568 -316.521338)
			(xy 36.267632 -316.521338) (xy 36.255621 -316.538955) (xy 36.219369 -316.578026) (xy 36.177698 -316.611257)
			(xy 36.13154 -316.637906) (xy 36.081926 -316.657378) (xy 36.029964 -316.669238) (xy 35.976814 -316.673222)
			(xy 35.923664 -316.669238) (xy 35.871702 -316.657378) (xy 35.822088 -316.637906) (xy 35.77593 -316.611257)
			(xy 35.734259 -316.578026) (xy 35.698007 -316.538955) (xy 35.667983 -316.494918) (xy 35.644857 -316.446897)
			(xy 35.629147 -316.395967) (xy 35.621204 -316.343263) (xy 34.122624 -316.343263) (xy 34.114681 -316.395967)
			(xy 34.098971 -316.446897) (xy 34.075845 -316.494918) (xy 34.045821 -316.538955) (xy 34.009569 -316.578026)
			(xy 33.967898 -316.611257) (xy 33.92174 -316.637906) (xy 33.872126 -316.657378) (xy 33.820164 -316.669238)
			(xy 33.767014 -316.673222) (xy 33.713864 -316.669238) (xy 33.661902 -316.657378) (xy 33.612288 -316.637906)
			(xy 33.56613 -316.611257) (xy 33.524459 -316.578026) (xy 33.488207 -316.538955) (xy 33.458183 -316.494918)
			(xy 33.435057 -316.446897) (xy 33.419347 -316.395967) (xy 33.411404 -316.343263) (xy 32.391858 -316.343263)
			(xy 32.391858 -317.193401) (xy 35.621204 -317.193401) (xy 35.621204 -317.140103) (xy 35.629147 -317.087399)
			(xy 35.644857 -317.036469) (xy 35.667983 -316.988448) (xy 35.698007 -316.944411) (xy 35.734259 -316.90534)
			(xy 35.77593 -316.872109) (xy 35.822088 -316.84546) (xy 35.871702 -316.825988) (xy 35.923664 -316.814128)
			(xy 35.976814 -316.810145) (xy 36.029964 -316.814128) (xy 36.081926 -316.825988) (xy 36.13154 -316.84546)
			(xy 36.177698 -316.872109) (xy 36.219369 -316.90534) (xy 36.255621 -316.944411) (xy 36.285645 -316.988448)
			(xy 36.308771 -317.036469) (xy 36.324481 -317.087399) (xy 36.332424 -317.140103) (xy 36.332922 -317.166752)
			(xy 36.332424 -317.193401) (xy 36.855136 -317.193401) (xy 36.855136 -317.140103) (xy 36.863079 -317.087399)
			(xy 36.878789 -317.036469) (xy 36.901915 -316.988448) (xy 36.931939 -316.944411) (xy 36.968191 -316.90534)
			(xy 37.009862 -316.872109) (xy 37.05602 -316.84546) (xy 37.105634 -316.825988) (xy 37.157596 -316.814128)
			(xy 37.210746 -316.810145) (xy 37.263896 -316.814128) (xy 37.315858 -316.825988) (xy 37.365472 -316.84546)
			(xy 37.41163 -316.872109) (xy 37.453301 -316.90534) (xy 37.489553 -316.944411) (xy 37.519577 -316.988448)
			(xy 37.542703 -317.036469) (xy 37.558413 -317.087399) (xy 37.566356 -317.140103) (xy 37.566854 -317.166752)
			(xy 37.566356 -317.193401) (xy 37.558413 -317.246105) (xy 37.542703 -317.297035) (xy 37.519577 -317.345056)
			(xy 37.489553 -317.389093) (xy 37.453301 -317.428164) (xy 37.41163 -317.461395) (xy 37.365472 -317.488044)
			(xy 37.315858 -317.507516) (xy 37.263896 -317.519376) (xy 37.210746 -317.52336) (xy 37.157596 -317.519376)
			(xy 37.105634 -317.507516) (xy 37.05602 -317.488044) (xy 37.009862 -317.461395) (xy 36.968191 -317.428164)
			(xy 36.931939 -317.389093) (xy 36.901915 -317.345056) (xy 36.878789 -317.297035) (xy 36.863079 -317.246105)
			(xy 36.855136 -317.193401) (xy 36.332424 -317.193401) (xy 36.324481 -317.246105) (xy 36.308771 -317.297035)
			(xy 36.285645 -317.345056) (xy 36.255621 -317.389093) (xy 36.219369 -317.428164) (xy 36.177698 -317.461395)
			(xy 36.13154 -317.488044) (xy 36.081926 -317.507516) (xy 36.029964 -317.519376) (xy 35.976814 -317.52336)
			(xy 35.923664 -317.519376) (xy 35.871702 -317.507516) (xy 35.822088 -317.488044) (xy 35.77593 -317.461395)
			(xy 35.734259 -317.428164) (xy 35.698007 -317.389093) (xy 35.667983 -317.345056) (xy 35.644857 -317.297035)
			(xy 35.629147 -317.246105) (xy 35.621204 -317.193401) (xy 32.391858 -317.193401) (xy 32.391858 -317.932308)
			(xy 32.280881 -318.043285) (xy 33.411404 -318.043285) (xy 33.411404 -317.989987) (xy 33.419347 -317.937283)
			(xy 33.435057 -317.886353) (xy 33.458183 -317.838332) (xy 33.488207 -317.794295) (xy 33.524459 -317.755224)
			(xy 33.56613 -317.721993) (xy 33.612288 -317.695344) (xy 33.661902 -317.675872) (xy 33.713864 -317.664012)
			(xy 33.767014 -317.660029) (xy 33.820164 -317.664012) (xy 33.872126 -317.675872) (xy 33.92174 -317.695344)
			(xy 33.967898 -317.721993) (xy 34.009569 -317.755224) (xy 34.045821 -317.794295) (xy 34.075845 -317.838332)
			(xy 34.098971 -317.886353) (xy 34.114681 -317.937283) (xy 34.122624 -317.989987) (xy 34.123122 -318.016636)
			(xy 34.122624 -318.043285) (xy 34.114681 -318.095989) (xy 34.098971 -318.146919) (xy 34.075845 -318.19494)
			(xy 34.045821 -318.238977) (xy 34.009569 -318.278048) (xy 33.967898 -318.311279) (xy 33.92174 -318.337928)
			(xy 33.872126 -318.3574) (xy 33.820164 -318.36926) (xy 33.767014 -318.373244) (xy 33.713864 -318.36926)
			(xy 33.661902 -318.3574) (xy 33.612288 -318.337928) (xy 33.56613 -318.311279) (xy 33.524459 -318.278048)
			(xy 33.488207 -318.238977) (xy 33.458183 -318.19494) (xy 33.435057 -318.146919) (xy 33.419347 -318.095989)
			(xy 33.411404 -318.043285) (xy 32.280881 -318.043285) (xy 31.764478 -318.559688) (xy 29.51988 -318.559688)
			(xy 29.357066 -318.722502) (xy 29.354018 -318.737742) (xy 29.347932 -318.765929) (xy 29.327887 -318.819995)
			(xy 29.299403 -318.87013) (xy 29.280633 -318.893423) (xy 33.411404 -318.893423) (xy 33.411404 -318.840125)
			(xy 33.419347 -318.787421) (xy 33.435057 -318.736491) (xy 33.458183 -318.68847) (xy 33.488207 -318.644433)
			(xy 33.524459 -318.605362) (xy 33.56613 -318.572131) (xy 33.612288 -318.545482) (xy 33.661902 -318.52601)
			(xy 33.713864 -318.51415) (xy 33.767014 -318.510167) (xy 33.820164 -318.51415) (xy 33.872126 -318.52601)
			(xy 33.92174 -318.545482) (xy 33.967898 -318.572131) (xy 34.009569 -318.605362) (xy 34.045821 -318.644433)
			(xy 34.075845 -318.68847) (xy 34.098971 -318.736491) (xy 34.114681 -318.787421) (xy 34.122624 -318.840125)
			(xy 34.123122 -318.866774) (xy 34.122624 -318.893423) (xy 34.115504 -318.940667) (xy 36.13784 -318.940667)
			(xy 36.13784 -318.887369) (xy 36.145783 -318.834665) (xy 36.161493 -318.783735) (xy 36.184619 -318.735714)
			(xy 36.214643 -318.691677) (xy 36.250895 -318.652606) (xy 36.292566 -318.619375) (xy 36.338724 -318.592726)
			(xy 36.388338 -318.573254) (xy 36.4403 -318.561394) (xy 36.49345 -318.557411) (xy 36.5466 -318.561394)
			(xy 36.598562 -318.573254) (xy 36.648176 -318.592726) (xy 36.694334 -318.619375) (xy 36.736005 -318.652606)
			(xy 36.772257 -318.691677) (xy 36.802281 -318.735714) (xy 36.825407 -318.783735) (xy 36.841117 -318.834665)
			(xy 36.84906 -318.887369) (xy 36.849558 -318.914018) (xy 36.84906 -318.940667) (xy 36.841117 -318.993371)
			(xy 36.825407 -319.044301) (xy 36.802281 -319.092322) (xy 36.772257 -319.136359) (xy 36.736005 -319.17543)
			(xy 36.694334 -319.208661) (xy 36.648176 -319.23531) (xy 36.598562 -319.254782) (xy 36.5466 -319.266642)
			(xy 36.49345 -319.270626) (xy 36.4403 -319.266642) (xy 36.388338 -319.254782) (xy 36.338724 -319.23531)
			(xy 36.292566 -319.208661) (xy 36.250895 -319.17543) (xy 36.214643 -319.136359) (xy 36.184619 -319.092322)
			(xy 36.161493 -319.044301) (xy 36.145783 -318.993371) (xy 36.13784 -318.940667) (xy 34.115504 -318.940667)
			(xy 34.114681 -318.946127) (xy 34.098971 -318.997057) (xy 34.075845 -319.045078) (xy 34.045821 -319.089115)
			(xy 34.009569 -319.128186) (xy 33.967898 -319.161417) (xy 33.92174 -319.188066) (xy 33.872126 -319.207538)
			(xy 33.820164 -319.219398) (xy 33.767014 -319.223382) (xy 33.713864 -319.219398) (xy 33.661902 -319.207538)
			(xy 33.612288 -319.188066) (xy 33.56613 -319.161417) (xy 33.524459 -319.128186) (xy 33.488207 -319.089115)
			(xy 33.458183 -319.045078) (xy 33.435057 -318.997057) (xy 33.419347 -318.946127) (xy 33.411404 -318.893423)
			(xy 29.280633 -318.893423) (xy 29.263223 -318.915029) (xy 29.22029 -318.953522) (xy 29.171722 -318.984604)
			(xy 29.145484 -318.996568) (xy 29.11475 -319.009776) (xy 29.11475 -319.330557) (xy 31.499038 -319.330557)
			(xy 31.499038 -319.277259) (xy 31.506981 -319.224555) (xy 31.522691 -319.173625) (xy 31.545817 -319.125604)
			(xy 31.575841 -319.081567) (xy 31.612093 -319.042496) (xy 31.653764 -319.009265) (xy 31.699922 -318.982616)
			(xy 31.749536 -318.963144) (xy 31.801498 -318.951284) (xy 31.854648 -318.947301) (xy 31.907798 -318.951284)
			(xy 31.95976 -318.963144) (xy 32.009374 -318.982616) (xy 32.055532 -319.009265) (xy 32.097203 -319.042496)
			(xy 32.133455 -319.081567) (xy 32.163479 -319.125604) (xy 32.186605 -319.173625) (xy 32.202315 -319.224555)
			(xy 32.210258 -319.277259) (xy 32.210756 -319.303908) (xy 32.210258 -319.330557) (xy 32.209033 -319.338685)
			(xy 39.04868 -319.338685) (xy 39.04868 -319.285387) (xy 39.056623 -319.232683) (xy 39.072333 -319.181753)
			(xy 39.095459 -319.133732) (xy 39.125483 -319.089695) (xy 39.161735 -319.050624) (xy 39.203406 -319.017393)
			(xy 39.249564 -318.990744) (xy 39.299178 -318.971272) (xy 39.35114 -318.959412) (xy 39.40429 -318.955429)
			(xy 39.45744 -318.959412) (xy 39.509402 -318.971272) (xy 39.559016 -318.990744) (xy 39.605174 -319.017393)
			(xy 39.646845 -319.050624) (xy 39.683097 -319.089695) (xy 39.713121 -319.133732) (xy 39.736247 -319.181753)
			(xy 39.751957 -319.232683) (xy 39.7599 -319.285387) (xy 39.760398 -319.312036) (xy 39.7599 -319.338685)
			(xy 39.751957 -319.391389) (xy 39.736247 -319.442319) (xy 39.713121 -319.49034) (xy 39.683097 -319.534377)
			(xy 39.646845 -319.573448) (xy 39.605174 -319.606679) (xy 39.559016 -319.633328) (xy 39.509402 -319.6528)
			(xy 39.45744 -319.66466) (xy 39.40429 -319.668644) (xy 39.35114 -319.66466) (xy 39.299178 -319.6528)
			(xy 39.249564 -319.633328) (xy 39.203406 -319.606679) (xy 39.161735 -319.573448) (xy 39.125483 -319.534377)
			(xy 39.095459 -319.49034) (xy 39.072333 -319.442319) (xy 39.056623 -319.391389) (xy 39.04868 -319.338685)
			(xy 32.209033 -319.338685) (xy 32.202315 -319.383261) (xy 32.186605 -319.434191) (xy 32.163479 -319.482212)
			(xy 32.133455 -319.526249) (xy 32.097203 -319.56532) (xy 32.055532 -319.598551) (xy 32.009374 -319.6252)
			(xy 31.95976 -319.644672) (xy 31.907798 -319.656532) (xy 31.854648 -319.660516) (xy 31.801498 -319.656532)
			(xy 31.749536 -319.644672) (xy 31.699922 -319.6252) (xy 31.653764 -319.598551) (xy 31.612093 -319.56532)
			(xy 31.575841 -319.526249) (xy 31.545817 -319.482212) (xy 31.522691 -319.434191) (xy 31.506981 -319.383261)
			(xy 31.499038 -319.330557) (xy 29.11475 -319.330557) (xy 29.11475 -319.743307) (xy 33.411404 -319.743307)
			(xy 33.411404 -319.690009) (xy 33.419347 -319.637305) (xy 33.435057 -319.586375) (xy 33.458183 -319.538354)
			(xy 33.488207 -319.494317) (xy 33.524459 -319.455246) (xy 33.56613 -319.422015) (xy 33.612288 -319.395366)
			(xy 33.661902 -319.375894) (xy 33.713864 -319.364034) (xy 33.767014 -319.360051) (xy 33.820164 -319.364034)
			(xy 33.872126 -319.375894) (xy 33.92174 -319.395366) (xy 33.967898 -319.422015) (xy 34.009569 -319.455246)
			(xy 34.045821 -319.494317) (xy 34.075845 -319.538354) (xy 34.098971 -319.586375) (xy 34.114681 -319.637305)
			(xy 34.122624 -319.690009) (xy 34.123122 -319.716658) (xy 34.122624 -319.743307) (xy 40.955204 -319.743307)
			(xy 40.955204 -319.690009) (xy 40.963147 -319.637305) (xy 40.978857 -319.586375) (xy 41.001983 -319.538354)
			(xy 41.032007 -319.494317) (xy 41.068259 -319.455246) (xy 41.10993 -319.422015) (xy 41.156088 -319.395366)
			(xy 41.205702 -319.375894) (xy 41.257664 -319.364034) (xy 41.310814 -319.360051) (xy 41.363964 -319.364034)
			(xy 41.415926 -319.375894) (xy 41.46554 -319.395366) (xy 41.511698 -319.422015) (xy 41.553369 -319.455246)
			(xy 41.589621 -319.494317) (xy 41.619645 -319.538354) (xy 41.642771 -319.586375) (xy 41.658481 -319.637305)
			(xy 41.666424 -319.690009) (xy 41.666922 -319.716658) (xy 41.666424 -319.743307) (xy 41.658481 -319.796011)
			(xy 41.642771 -319.846941) (xy 41.619645 -319.894962) (xy 41.589621 -319.938999) (xy 41.553369 -319.97807)
			(xy 41.511698 -320.011301) (xy 41.46554 -320.03795) (xy 41.415926 -320.057422) (xy 41.363964 -320.069282)
			(xy 41.310814 -320.073266) (xy 41.257664 -320.069282) (xy 41.205702 -320.057422) (xy 41.156088 -320.03795)
			(xy 41.10993 -320.011301) (xy 41.068259 -319.97807) (xy 41.032007 -319.938999) (xy 41.001983 -319.894962)
			(xy 40.978857 -319.846941) (xy 40.963147 -319.796011) (xy 40.955204 -319.743307) (xy 34.122624 -319.743307)
			(xy 34.114681 -319.796011) (xy 34.098971 -319.846941) (xy 34.075845 -319.894962) (xy 34.045821 -319.938999)
			(xy 34.009569 -319.97807) (xy 33.967898 -320.011301) (xy 33.92174 -320.03795) (xy 33.872126 -320.057422)
			(xy 33.820164 -320.069282) (xy 33.767014 -320.073266) (xy 33.713864 -320.069282) (xy 33.661902 -320.057422)
			(xy 33.612288 -320.03795) (xy 33.56613 -320.011301) (xy 33.524459 -319.97807) (xy 33.488207 -319.938999)
			(xy 33.458183 -319.894962) (xy 33.435057 -319.846941) (xy 33.419347 -319.796011) (xy 33.411404 -319.743307)
			(xy 29.11475 -319.743307) (xy 29.11475 -320.165) (xy 55.436936 -320.165) (xy 55.44092 -320.111838)
			(xy 55.452784 -320.059864) (xy 55.472262 -320.010239) (xy 55.498919 -319.964071) (xy 55.53216 -319.922393)
			(xy 55.571242 -319.886135) (xy 55.615291 -319.856107) (xy 55.663324 -319.83298) (xy 55.714268 -319.817271)
			(xy 55.766985 -319.80933) (xy 55.79364 -319.80886) (xy 55.820407 -319.809353) (xy 55.873341 -319.817344)
			(xy 55.924482 -319.833171) (xy 55.972677 -319.856477) (xy 56.016839 -319.886736) (xy 56.055973 -319.923265)
			(xy 56.089196 -319.965243) (xy 56.11576 -320.011721) (xy 56.135065 -320.061653) (xy 56.146677 -320.113912)
			(xy 56.148986 -320.140584) (xy 56.150362 -320.153815) (xy 56.159003 -320.178962) (xy 56.173845 -320.201025)
			(xy 56.193881 -320.218505) (xy 56.217753 -320.230218) (xy 56.243839 -320.235369) (xy 56.270371 -320.233607)
			(xy 56.283098 -320.229738) (xy 56.311079 -320.220784) (xy 56.36904 -320.211211) (xy 56.398414 -320.210688)
			(xy 56.425062 -320.211195) (xy 56.477763 -320.21914) (xy 56.528692 -320.234851) (xy 56.57671 -320.257977)
			(xy 56.620745 -320.288001) (xy 56.659813 -320.324253) (xy 56.693043 -320.365923) (xy 56.71969 -320.412079)
			(xy 56.739161 -320.461692) (xy 56.751021 -320.513652) (xy 56.755004 -320.5668) (xy 56.753007 -320.593445)
			(xy 59.486536 -320.593445) (xy 59.486536 -320.540147) (xy 59.494479 -320.487443) (xy 59.510189 -320.436513)
			(xy 59.533315 -320.388492) (xy 59.563339 -320.344455) (xy 59.599591 -320.305384) (xy 59.641262 -320.272153)
			(xy 59.68742 -320.245504) (xy 59.737034 -320.226032) (xy 59.788996 -320.214172) (xy 59.842146 -320.210189)
			(xy 59.895296 -320.214172) (xy 59.947258 -320.226032) (xy 59.996872 -320.245504) (xy 60.04303 -320.272153)
			(xy 60.084701 -320.305384) (xy 60.120953 -320.344455) (xy 60.150977 -320.388492) (xy 60.174103 -320.436513)
			(xy 60.189813 -320.487443) (xy 60.197756 -320.540147) (xy 60.198254 -320.566796) (xy 60.197756 -320.593445)
			(xy 60.189813 -320.646149) (xy 60.174103 -320.697079) (xy 60.150977 -320.7451) (xy 60.120953 -320.789137)
			(xy 60.084701 -320.828208) (xy 60.04303 -320.861439) (xy 59.996872 -320.888088) (xy 59.947258 -320.90756)
			(xy 59.895296 -320.91942) (xy 59.842146 -320.923404) (xy 59.788996 -320.91942) (xy 59.737034 -320.90756)
			(xy 59.68742 -320.888088) (xy 59.641262 -320.861439) (xy 59.599591 -320.828208) (xy 59.563339 -320.789137)
			(xy 59.533315 -320.7451) (xy 59.510189 -320.697079) (xy 59.494479 -320.646149) (xy 59.486536 -320.593445)
			(xy 56.753007 -320.593445) (xy 56.751021 -320.619948) (xy 56.739161 -320.671908) (xy 56.71969 -320.721521)
			(xy 56.693043 -320.767677) (xy 56.659813 -320.809347) (xy 56.620745 -320.845599) (xy 56.57671 -320.875623)
			(xy 56.528692 -320.898749) (xy 56.477763 -320.91446) (xy 56.425062 -320.922405) (xy 56.398414 -320.922904)
			(xy 56.371644 -320.922487) (xy 56.318705 -320.914488) (xy 56.267561 -320.898653) (xy 56.219364 -320.875339)
			(xy 56.1752 -320.845071) (xy 56.136067 -320.808533) (xy 56.102845 -320.766547) (xy 56.076284 -320.720061)
			(xy 56.056982 -320.670121) (xy 56.045375 -320.617855) (xy 56.043068 -320.59118) (xy 56.041703 -320.577945)
			(xy 56.033071 -320.552789) (xy 56.018231 -320.530718) (xy 55.998192 -320.513232) (xy 55.974314 -320.501519)
			(xy 55.94822 -320.496375) (xy 55.921684 -320.498149) (xy 55.908956 -320.502026) (xy 55.880971 -320.510966)
			(xy 55.823013 -320.520548) (xy 55.79364 -320.521076) (xy 55.766985 -320.52067) (xy 55.714268 -320.512729)
			(xy 55.663324 -320.49702) (xy 55.615291 -320.473893) (xy 55.571242 -320.443865) (xy 55.53216 -320.407607)
			(xy 55.498919 -320.365929) (xy 55.472262 -320.319761) (xy 55.452784 -320.270136) (xy 55.44092 -320.218162)
			(xy 55.436936 -320.165) (xy 29.11475 -320.165) (xy 29.11475 -320.593445) (xy 29.311336 -320.593445)
			(xy 29.311336 -320.540147) (xy 29.319279 -320.487443) (xy 29.334989 -320.436513) (xy 29.358115 -320.388492)
			(xy 29.388139 -320.344455) (xy 29.424391 -320.305384) (xy 29.466062 -320.272153) (xy 29.51222 -320.245504)
			(xy 29.561834 -320.226032) (xy 29.613796 -320.214172) (xy 29.666946 -320.210189) (xy 29.720096 -320.214172)
			(xy 29.772058 -320.226032) (xy 29.821672 -320.245504) (xy 29.86783 -320.272153) (xy 29.909501 -320.305384)
			(xy 29.945753 -320.344455) (xy 29.975777 -320.388492) (xy 29.998903 -320.436513) (xy 30.014613 -320.487443)
			(xy 30.022556 -320.540147) (xy 30.023054 -320.566796) (xy 30.022556 -320.593445) (xy 33.411404 -320.593445)
			(xy 33.411404 -320.540147) (xy 33.419347 -320.487443) (xy 33.435057 -320.436513) (xy 33.458183 -320.388492)
			(xy 33.488207 -320.344455) (xy 33.524459 -320.305384) (xy 33.56613 -320.272153) (xy 33.612288 -320.245504)
			(xy 33.661902 -320.226032) (xy 33.713864 -320.214172) (xy 33.767014 -320.210189) (xy 33.820164 -320.214172)
			(xy 33.872126 -320.226032) (xy 33.92174 -320.245504) (xy 33.967898 -320.272153) (xy 34.009569 -320.305384)
			(xy 34.045821 -320.344455) (xy 34.075845 -320.388492) (xy 34.098971 -320.436513) (xy 34.114681 -320.487443)
			(xy 34.122624 -320.540147) (xy 34.123122 -320.566796) (xy 34.122624 -320.593445) (xy 36.855136 -320.593445)
			(xy 36.855136 -320.540147) (xy 36.863079 -320.487443) (xy 36.878789 -320.436513) (xy 36.901915 -320.388492)
			(xy 36.931939 -320.344455) (xy 36.968191 -320.305384) (xy 37.009862 -320.272153) (xy 37.05602 -320.245504)
			(xy 37.105634 -320.226032) (xy 37.157596 -320.214172) (xy 37.210746 -320.210189) (xy 37.263896 -320.214172)
			(xy 37.315858 -320.226032) (xy 37.365472 -320.245504) (xy 37.41163 -320.272153) (xy 37.453301 -320.305384)
			(xy 37.489553 -320.344455) (xy 37.519577 -320.388492) (xy 37.542703 -320.436513) (xy 37.558413 -320.487443)
			(xy 37.566356 -320.540147) (xy 37.566854 -320.566796) (xy 37.566356 -320.593445) (xy 40.955204 -320.593445)
			(xy 40.955204 -320.540147) (xy 40.963147 -320.487443) (xy 40.978857 -320.436513) (xy 41.001983 -320.388492)
			(xy 41.032007 -320.344455) (xy 41.068259 -320.305384) (xy 41.10993 -320.272153) (xy 41.156088 -320.245504)
			(xy 41.205702 -320.226032) (xy 41.257664 -320.214172) (xy 41.310814 -320.210189) (xy 41.363964 -320.214172)
			(xy 41.415926 -320.226032) (xy 41.46554 -320.245504) (xy 41.511698 -320.272153) (xy 41.553369 -320.305384)
			(xy 41.589621 -320.344455) (xy 41.619645 -320.388492) (xy 41.642771 -320.436513) (xy 41.658481 -320.487443)
			(xy 41.666424 -320.540147) (xy 41.666922 -320.566796) (xy 41.666424 -320.593445) (xy 44.398936 -320.593445)
			(xy 44.398936 -320.540147) (xy 44.406879 -320.487443) (xy 44.422589 -320.436513) (xy 44.445715 -320.388492)
			(xy 44.475739 -320.344455) (xy 44.511991 -320.305384) (xy 44.553662 -320.272153) (xy 44.59982 -320.245504)
			(xy 44.649434 -320.226032) (xy 44.701396 -320.214172) (xy 44.754546 -320.210189) (xy 44.807696 -320.214172)
			(xy 44.859658 -320.226032) (xy 44.909272 -320.245504) (xy 44.95543 -320.272153) (xy 44.997101 -320.305384)
			(xy 45.033353 -320.344455) (xy 45.063377 -320.388492) (xy 45.086503 -320.436513) (xy 45.102213 -320.487443)
			(xy 45.110156 -320.540147) (xy 45.110654 -320.566796) (xy 45.110156 -320.593445) (xy 48.499004 -320.593445)
			(xy 48.499004 -320.540147) (xy 48.506947 -320.487443) (xy 48.522657 -320.436513) (xy 48.545783 -320.388492)
			(xy 48.575807 -320.344455) (xy 48.612059 -320.305384) (xy 48.65373 -320.272153) (xy 48.699888 -320.245504)
			(xy 48.749502 -320.226032) (xy 48.801464 -320.214172) (xy 48.854614 -320.210189) (xy 48.907764 -320.214172)
			(xy 48.959726 -320.226032) (xy 49.00934 -320.245504) (xy 49.055498 -320.272153) (xy 49.097169 -320.305384)
			(xy 49.133421 -320.344455) (xy 49.163445 -320.388492) (xy 49.186571 -320.436513) (xy 49.202281 -320.487443)
			(xy 49.210224 -320.540147) (xy 49.210722 -320.566796) (xy 49.210224 -320.593445) (xy 51.942736 -320.593445)
			(xy 51.942736 -320.540147) (xy 51.950679 -320.487443) (xy 51.966389 -320.436513) (xy 51.989515 -320.388492)
			(xy 52.019539 -320.344455) (xy 52.055791 -320.305384) (xy 52.097462 -320.272153) (xy 52.14362 -320.245504)
			(xy 52.193234 -320.226032) (xy 52.245196 -320.214172) (xy 52.298346 -320.210189) (xy 52.351496 -320.214172)
			(xy 52.403458 -320.226032) (xy 52.453072 -320.245504) (xy 52.49923 -320.272153) (xy 52.540901 -320.305384)
			(xy 52.577153 -320.344455) (xy 52.607177 -320.388492) (xy 52.630303 -320.436513) (xy 52.646013 -320.487443)
			(xy 52.653956 -320.540147) (xy 52.654454 -320.566796) (xy 52.653956 -320.593445) (xy 52.646013 -320.646149)
			(xy 52.630303 -320.697079) (xy 52.607177 -320.7451) (xy 52.577153 -320.789137) (xy 52.540901 -320.828208)
			(xy 52.49923 -320.861439) (xy 52.453072 -320.888088) (xy 52.403458 -320.90756) (xy 52.351496 -320.91942)
			(xy 52.298346 -320.923404) (xy 52.245196 -320.91942) (xy 52.193234 -320.90756) (xy 52.14362 -320.888088)
			(xy 52.097462 -320.861439) (xy 52.055791 -320.828208) (xy 52.019539 -320.789137) (xy 51.989515 -320.7451)
			(xy 51.966389 -320.697079) (xy 51.950679 -320.646149) (xy 51.942736 -320.593445) (xy 49.210224 -320.593445)
			(xy 49.202281 -320.646149) (xy 49.186571 -320.697079) (xy 49.163445 -320.7451) (xy 49.133421 -320.789137)
			(xy 49.097169 -320.828208) (xy 49.055498 -320.861439) (xy 49.00934 -320.888088) (xy 48.959726 -320.90756)
			(xy 48.907764 -320.91942) (xy 48.854614 -320.923404) (xy 48.801464 -320.91942) (xy 48.749502 -320.90756)
			(xy 48.699888 -320.888088) (xy 48.65373 -320.861439) (xy 48.612059 -320.828208) (xy 48.575807 -320.789137)
			(xy 48.545783 -320.7451) (xy 48.522657 -320.697079) (xy 48.506947 -320.646149) (xy 48.499004 -320.593445)
			(xy 45.110156 -320.593445) (xy 45.102213 -320.646149) (xy 45.086503 -320.697079) (xy 45.063377 -320.7451)
			(xy 45.033353 -320.789137) (xy 44.997101 -320.828208) (xy 44.95543 -320.861439) (xy 44.909272 -320.888088)
			(xy 44.859658 -320.90756) (xy 44.807696 -320.91942) (xy 44.754546 -320.923404) (xy 44.701396 -320.91942)
			(xy 44.649434 -320.90756) (xy 44.59982 -320.888088) (xy 44.553662 -320.861439) (xy 44.511991 -320.828208)
			(xy 44.475739 -320.789137) (xy 44.445715 -320.7451) (xy 44.422589 -320.697079) (xy 44.406879 -320.646149)
			(xy 44.398936 -320.593445) (xy 41.666424 -320.593445) (xy 41.658481 -320.646149) (xy 41.642771 -320.697079)
			(xy 41.619645 -320.7451) (xy 41.589621 -320.789137) (xy 41.553369 -320.828208) (xy 41.511698 -320.861439)
			(xy 41.46554 -320.888088) (xy 41.415926 -320.90756) (xy 41.363964 -320.91942) (xy 41.310814 -320.923404)
			(xy 41.257664 -320.91942) (xy 41.205702 -320.90756) (xy 41.156088 -320.888088) (xy 41.10993 -320.861439)
			(xy 41.068259 -320.828208) (xy 41.032007 -320.789137) (xy 41.001983 -320.7451) (xy 40.978857 -320.697079)
			(xy 40.963147 -320.646149) (xy 40.955204 -320.593445) (xy 37.566356 -320.593445) (xy 37.558413 -320.646149)
			(xy 37.542703 -320.697079) (xy 37.519577 -320.7451) (xy 37.489553 -320.789137) (xy 37.453301 -320.828208)
			(xy 37.41163 -320.861439) (xy 37.365472 -320.888088) (xy 37.315858 -320.90756) (xy 37.263896 -320.91942)
			(xy 37.210746 -320.923404) (xy 37.157596 -320.91942) (xy 37.105634 -320.90756) (xy 37.05602 -320.888088)
			(xy 37.009862 -320.861439) (xy 36.968191 -320.828208) (xy 36.931939 -320.789137) (xy 36.901915 -320.7451)
			(xy 36.878789 -320.697079) (xy 36.863079 -320.646149) (xy 36.855136 -320.593445) (xy 34.122624 -320.593445)
			(xy 34.114681 -320.646149) (xy 34.098971 -320.697079) (xy 34.075845 -320.7451) (xy 34.045821 -320.789137)
			(xy 34.009569 -320.828208) (xy 33.967898 -320.861439) (xy 33.92174 -320.888088) (xy 33.872126 -320.90756)
			(xy 33.820164 -320.91942) (xy 33.767014 -320.923404) (xy 33.713864 -320.91942) (xy 33.661902 -320.90756)
			(xy 33.612288 -320.888088) (xy 33.56613 -320.861439) (xy 33.524459 -320.828208) (xy 33.488207 -320.789137)
			(xy 33.458183 -320.7451) (xy 33.435057 -320.697079) (xy 33.419347 -320.646149) (xy 33.411404 -320.593445)
			(xy 30.022556 -320.593445) (xy 30.014613 -320.646149) (xy 29.998903 -320.697079) (xy 29.975777 -320.7451)
			(xy 29.945753 -320.789137) (xy 29.909501 -320.828208) (xy 29.86783 -320.861439) (xy 29.821672 -320.888088)
			(xy 29.772058 -320.90756) (xy 29.720096 -320.91942) (xy 29.666946 -320.923404) (xy 29.613796 -320.91942)
			(xy 29.561834 -320.90756) (xy 29.51222 -320.888088) (xy 29.466062 -320.861439) (xy 29.424391 -320.828208)
			(xy 29.388139 -320.789137) (xy 29.358115 -320.7451) (xy 29.334989 -320.697079) (xy 29.319279 -320.646149)
			(xy 29.311336 -320.593445) (xy 29.11475 -320.593445) (xy 29.11475 -321.443329) (xy 29.311336 -321.443329)
			(xy 29.311336 -321.390031) (xy 29.319279 -321.337327) (xy 29.334989 -321.286397) (xy 29.358115 -321.238376)
			(xy 29.388139 -321.194339) (xy 29.424391 -321.155268) (xy 29.466062 -321.122037) (xy 29.51222 -321.095388)
			(xy 29.561834 -321.075916) (xy 29.613796 -321.064056) (xy 29.666946 -321.060073) (xy 29.720096 -321.064056)
			(xy 29.772058 -321.075916) (xy 29.821672 -321.095388) (xy 29.86783 -321.122037) (xy 29.909501 -321.155268)
			(xy 29.945753 -321.194339) (xy 29.975777 -321.238376) (xy 29.998903 -321.286397) (xy 30.014613 -321.337327)
			(xy 30.022556 -321.390031) (xy 30.023054 -321.41668) (xy 30.022556 -321.443329) (xy 33.411404 -321.443329)
			(xy 33.411404 -321.390031) (xy 33.419347 -321.337327) (xy 33.435057 -321.286397) (xy 33.458183 -321.238376)
			(xy 33.488207 -321.194339) (xy 33.524459 -321.155268) (xy 33.56613 -321.122037) (xy 33.612288 -321.095388)
			(xy 33.661902 -321.075916) (xy 33.713864 -321.064056) (xy 33.767014 -321.060073) (xy 33.820164 -321.064056)
			(xy 33.872126 -321.075916) (xy 33.92174 -321.095388) (xy 33.967898 -321.122037) (xy 34.009569 -321.155268)
			(xy 34.045821 -321.194339) (xy 34.075845 -321.238376) (xy 34.098971 -321.286397) (xy 34.114681 -321.337327)
			(xy 34.122624 -321.390031) (xy 34.123122 -321.41668) (xy 34.122624 -321.443329) (xy 36.855136 -321.443329)
			(xy 36.855136 -321.390031) (xy 36.863079 -321.337327) (xy 36.878789 -321.286397) (xy 36.901915 -321.238376)
			(xy 36.931939 -321.194339) (xy 36.968191 -321.155268) (xy 37.009862 -321.122037) (xy 37.05602 -321.095388)
			(xy 37.105634 -321.075916) (xy 37.157596 -321.064056) (xy 37.210746 -321.060073) (xy 37.263896 -321.064056)
			(xy 37.315858 -321.075916) (xy 37.365472 -321.095388) (xy 37.41163 -321.122037) (xy 37.453301 -321.155268)
			(xy 37.489553 -321.194339) (xy 37.519577 -321.238376) (xy 37.542703 -321.286397) (xy 37.558413 -321.337327)
			(xy 37.566356 -321.390031) (xy 37.566854 -321.41668) (xy 37.566356 -321.443329) (xy 40.955204 -321.443329)
			(xy 40.955204 -321.390031) (xy 40.963147 -321.337327) (xy 40.978857 -321.286397) (xy 41.001983 -321.238376)
			(xy 41.032007 -321.194339) (xy 41.068259 -321.155268) (xy 41.10993 -321.122037) (xy 41.156088 -321.095388)
			(xy 41.205702 -321.075916) (xy 41.257664 -321.064056) (xy 41.310814 -321.060073) (xy 41.363964 -321.064056)
			(xy 41.415926 -321.075916) (xy 41.46554 -321.095388) (xy 41.511698 -321.122037) (xy 41.553369 -321.155268)
			(xy 41.589621 -321.194339) (xy 41.619645 -321.238376) (xy 41.642771 -321.286397) (xy 41.658481 -321.337327)
			(xy 41.666424 -321.390031) (xy 41.666922 -321.41668) (xy 41.666424 -321.443329) (xy 44.398936 -321.443329)
			(xy 44.398936 -321.390031) (xy 44.406879 -321.337327) (xy 44.422589 -321.286397) (xy 44.445715 -321.238376)
			(xy 44.475739 -321.194339) (xy 44.511991 -321.155268) (xy 44.553662 -321.122037) (xy 44.59982 -321.095388)
			(xy 44.649434 -321.075916) (xy 44.701396 -321.064056) (xy 44.754546 -321.060073) (xy 44.807696 -321.064056)
			(xy 44.859658 -321.075916) (xy 44.909272 -321.095388) (xy 44.95543 -321.122037) (xy 44.997101 -321.155268)
			(xy 45.033353 -321.194339) (xy 45.063377 -321.238376) (xy 45.086503 -321.286397) (xy 45.102213 -321.337327)
			(xy 45.110156 -321.390031) (xy 45.110654 -321.41668) (xy 45.110156 -321.443329) (xy 48.499004 -321.443329)
			(xy 48.499004 -321.390031) (xy 48.506947 -321.337327) (xy 48.522657 -321.286397) (xy 48.545783 -321.238376)
			(xy 48.575807 -321.194339) (xy 48.612059 -321.155268) (xy 48.65373 -321.122037) (xy 48.699888 -321.095388)
			(xy 48.749502 -321.075916) (xy 48.801464 -321.064056) (xy 48.854614 -321.060073) (xy 48.907764 -321.064056)
			(xy 48.959726 -321.075916) (xy 49.00934 -321.095388) (xy 49.055498 -321.122037) (xy 49.097169 -321.155268)
			(xy 49.133421 -321.194339) (xy 49.163445 -321.238376) (xy 49.186571 -321.286397) (xy 49.202281 -321.337327)
			(xy 49.210224 -321.390031) (xy 49.210722 -321.41668) (xy 49.210224 -321.443329) (xy 51.942736 -321.443329)
			(xy 51.942736 -321.390031) (xy 51.950679 -321.337327) (xy 51.966389 -321.286397) (xy 51.989515 -321.238376)
			(xy 52.019539 -321.194339) (xy 52.055791 -321.155268) (xy 52.097462 -321.122037) (xy 52.14362 -321.095388)
			(xy 52.193234 -321.075916) (xy 52.245196 -321.064056) (xy 52.298346 -321.060073) (xy 52.351496 -321.064056)
			(xy 52.403458 -321.075916) (xy 52.453072 -321.095388) (xy 52.49923 -321.122037) (xy 52.540901 -321.155268)
			(xy 52.577153 -321.194339) (xy 52.607177 -321.238376) (xy 52.630303 -321.286397) (xy 52.646013 -321.337327)
			(xy 52.653956 -321.390031) (xy 52.654454 -321.41668) (xy 52.653956 -321.443329) (xy 56.042804 -321.443329)
			(xy 56.042804 -321.390031) (xy 56.050747 -321.337327) (xy 56.066457 -321.286397) (xy 56.089583 -321.238376)
			(xy 56.119607 -321.194339) (xy 56.155859 -321.155268) (xy 56.19753 -321.122037) (xy 56.243688 -321.095388)
			(xy 56.293302 -321.075916) (xy 56.345264 -321.064056) (xy 56.398414 -321.060073) (xy 56.451564 -321.064056)
			(xy 56.503526 -321.075916) (xy 56.55314 -321.095388) (xy 56.599298 -321.122037) (xy 56.640969 -321.155268)
			(xy 56.677221 -321.194339) (xy 56.707245 -321.238376) (xy 56.730371 -321.286397) (xy 56.746081 -321.337327)
			(xy 56.754024 -321.390031) (xy 56.754522 -321.41668) (xy 56.754024 -321.443329) (xy 56.746081 -321.496033)
			(xy 56.730371 -321.546963) (xy 56.707245 -321.594984) (xy 56.677221 -321.639021) (xy 56.640969 -321.678092)
			(xy 56.599298 -321.711323) (xy 56.55314 -321.737972) (xy 56.503526 -321.757444) (xy 56.451564 -321.769304)
			(xy 56.398414 -321.773288) (xy 56.345264 -321.769304) (xy 56.293302 -321.757444) (xy 56.243688 -321.737972)
			(xy 56.19753 -321.711323) (xy 56.155859 -321.678092) (xy 56.119607 -321.639021) (xy 56.089583 -321.594984)
			(xy 56.066457 -321.546963) (xy 56.050747 -321.496033) (xy 56.042804 -321.443329) (xy 52.653956 -321.443329)
			(xy 52.646013 -321.496033) (xy 52.630303 -321.546963) (xy 52.607177 -321.594984) (xy 52.577153 -321.639021)
			(xy 52.540901 -321.678092) (xy 52.49923 -321.711323) (xy 52.453072 -321.737972) (xy 52.403458 -321.757444)
			(xy 52.351496 -321.769304) (xy 52.298346 -321.773288) (xy 52.245196 -321.769304) (xy 52.193234 -321.757444)
			(xy 52.14362 -321.737972) (xy 52.097462 -321.711323) (xy 52.055791 -321.678092) (xy 52.019539 -321.639021)
			(xy 51.989515 -321.594984) (xy 51.966389 -321.546963) (xy 51.950679 -321.496033) (xy 51.942736 -321.443329)
			(xy 49.210224 -321.443329) (xy 49.202281 -321.496033) (xy 49.186571 -321.546963) (xy 49.163445 -321.594984)
			(xy 49.133421 -321.639021) (xy 49.097169 -321.678092) (xy 49.055498 -321.711323) (xy 49.00934 -321.737972)
			(xy 48.959726 -321.757444) (xy 48.907764 -321.769304) (xy 48.854614 -321.773288) (xy 48.801464 -321.769304)
			(xy 48.749502 -321.757444) (xy 48.699888 -321.737972) (xy 48.65373 -321.711323) (xy 48.612059 -321.678092)
			(xy 48.575807 -321.639021) (xy 48.545783 -321.594984) (xy 48.522657 -321.546963) (xy 48.506947 -321.496033)
			(xy 48.499004 -321.443329) (xy 45.110156 -321.443329) (xy 45.102213 -321.496033) (xy 45.086503 -321.546963)
			(xy 45.063377 -321.594984) (xy 45.033353 -321.639021) (xy 44.997101 -321.678092) (xy 44.95543 -321.711323)
			(xy 44.909272 -321.737972) (xy 44.859658 -321.757444) (xy 44.807696 -321.769304) (xy 44.754546 -321.773288)
			(xy 44.701396 -321.769304) (xy 44.649434 -321.757444) (xy 44.59982 -321.737972) (xy 44.553662 -321.711323)
			(xy 44.511991 -321.678092) (xy 44.475739 -321.639021) (xy 44.445715 -321.594984) (xy 44.422589 -321.546963)
			(xy 44.406879 -321.496033) (xy 44.398936 -321.443329) (xy 41.666424 -321.443329) (xy 41.658481 -321.496033)
			(xy 41.642771 -321.546963) (xy 41.619645 -321.594984) (xy 41.589621 -321.639021) (xy 41.553369 -321.678092)
			(xy 41.511698 -321.711323) (xy 41.46554 -321.737972) (xy 41.415926 -321.757444) (xy 41.363964 -321.769304)
			(xy 41.310814 -321.773288) (xy 41.257664 -321.769304) (xy 41.205702 -321.757444) (xy 41.156088 -321.737972)
			(xy 41.10993 -321.711323) (xy 41.068259 -321.678092) (xy 41.032007 -321.639021) (xy 41.001983 -321.594984)
			(xy 40.978857 -321.546963) (xy 40.963147 -321.496033) (xy 40.955204 -321.443329) (xy 37.566356 -321.443329)
			(xy 37.558413 -321.496033) (xy 37.542703 -321.546963) (xy 37.519577 -321.594984) (xy 37.489553 -321.639021)
			(xy 37.453301 -321.678092) (xy 37.41163 -321.711323) (xy 37.365472 -321.737972) (xy 37.315858 -321.757444)
			(xy 37.263896 -321.769304) (xy 37.210746 -321.773288) (xy 37.157596 -321.769304) (xy 37.105634 -321.757444)
			(xy 37.05602 -321.737972) (xy 37.009862 -321.711323) (xy 36.968191 -321.678092) (xy 36.931939 -321.639021)
			(xy 36.901915 -321.594984) (xy 36.878789 -321.546963) (xy 36.863079 -321.496033) (xy 36.855136 -321.443329)
			(xy 34.122624 -321.443329) (xy 34.114681 -321.496033) (xy 34.098971 -321.546963) (xy 34.075845 -321.594984)
			(xy 34.045821 -321.639021) (xy 34.009569 -321.678092) (xy 33.967898 -321.711323) (xy 33.92174 -321.737972)
			(xy 33.872126 -321.757444) (xy 33.820164 -321.769304) (xy 33.767014 -321.773288) (xy 33.713864 -321.769304)
			(xy 33.661902 -321.757444) (xy 33.612288 -321.737972) (xy 33.56613 -321.711323) (xy 33.524459 -321.678092)
			(xy 33.488207 -321.639021) (xy 33.458183 -321.594984) (xy 33.435057 -321.546963) (xy 33.419347 -321.496033)
			(xy 33.411404 -321.443329) (xy 30.022556 -321.443329) (xy 30.014613 -321.496033) (xy 29.998903 -321.546963)
			(xy 29.975777 -321.594984) (xy 29.945753 -321.639021) (xy 29.909501 -321.678092) (xy 29.86783 -321.711323)
			(xy 29.821672 -321.737972) (xy 29.772058 -321.757444) (xy 29.720096 -321.769304) (xy 29.666946 -321.773288)
			(xy 29.613796 -321.769304) (xy 29.561834 -321.757444) (xy 29.51222 -321.737972) (xy 29.466062 -321.711323)
			(xy 29.424391 -321.678092) (xy 29.388139 -321.639021) (xy 29.358115 -321.594984) (xy 29.334989 -321.546963)
			(xy 29.319279 -321.496033) (xy 29.311336 -321.443329) (xy 29.11475 -321.443329) (xy 29.11475 -322.893182)
			(xy 29.122116 -322.900548) (xy 48.562768 -322.900548) (xy 48.563283 -322.873249) (xy 48.571616 -322.81929)
			(xy 48.588094 -322.767238) (xy 48.61233 -322.718314) (xy 48.643756 -322.673666) (xy 48.662336 -322.65366)
			(xy 48.672736 -322.6421) (xy 48.68654 -322.61425) (xy 48.691357 -322.583543) (xy 48.686745 -322.552804)
			(xy 48.673128 -322.524863) (xy 48.662844 -322.513198) (xy 48.644678 -322.493248) (xy 48.613962 -322.448891)
			(xy 48.590287 -322.400409) (xy 48.574197 -322.34891) (xy 48.566059 -322.295573) (xy 48.565562 -322.268596)
			(xy 48.56606 -322.241947) (xy 48.574003 -322.189243) (xy 48.589713 -322.138313) (xy 48.612839 -322.090292)
			(xy 48.642863 -322.046255) (xy 48.679115 -322.007184) (xy 48.720786 -321.973953) (xy 48.766944 -321.947304)
			(xy 48.816558 -321.927832) (xy 48.86852 -321.915972) (xy 48.92167 -321.911989) (xy 48.97482 -321.915972)
			(xy 49.026782 -321.927832) (xy 49.076396 -321.947304) (xy 49.122554 -321.973953) (xy 49.164225 -322.007184)
			(xy 49.200477 -322.046255) (xy 49.230501 -322.090292) (xy 49.253627 -322.138313) (xy 49.269337 -322.189243)
			(xy 49.27728 -322.241947) (xy 49.277778 -322.268596) (xy 49.277305 -322.295897) (xy 49.268964 -322.349858)
			(xy 49.252477 -322.401911) (xy 49.228231 -322.450835) (xy 49.196795 -322.49548) (xy 49.17821 -322.515484)
			(xy 49.167862 -322.527087) (xy 49.154046 -322.55492) (xy 49.149215 -322.585616) (xy 49.153815 -322.616347)
			(xy 49.167422 -322.644283) (xy 49.177702 -322.655946) (xy 49.195849 -322.675912) (xy 49.226566 -322.720266)
			(xy 49.250243 -322.768744) (xy 49.266338 -322.820239) (xy 49.274483 -322.873572) (xy 49.274984 -322.900548)
			(xy 49.274576 -322.922392) (xy 52.035964 -322.922392) (xy 52.036376 -322.897333) (xy 52.043387 -322.847707)
			(xy 52.057286 -322.799554) (xy 52.077796 -322.753824) (xy 52.104513 -322.71142) (xy 52.136909 -322.67318)
			(xy 52.155344 -322.6562) (xy 52.16539 -322.646655) (xy 52.180316 -322.623317) (xy 52.188429 -322.596829)
			(xy 52.189135 -322.569135) (xy 52.182382 -322.542268) (xy 52.168664 -322.518199) (xy 52.159154 -322.508118)
			(xy 52.139503 -322.487907) (xy 52.106178 -322.442445) (xy 52.080429 -322.392302) (xy 52.062898 -322.338729)
			(xy 52.054024 -322.283064) (xy 52.05349 -322.25488) (xy 52.053988 -322.228231) (xy 52.061931 -322.175527)
			(xy 52.077641 -322.124597) (xy 52.100767 -322.076576) (xy 52.130791 -322.032539) (xy 52.167043 -321.993468)
			(xy 52.208714 -321.960237) (xy 52.254872 -321.933588) (xy 52.304486 -321.914116) (xy 52.356448 -321.902256)
			(xy 52.409598 -321.898273) (xy 52.462748 -321.902256) (xy 52.51471 -321.914116) (xy 52.564324 -321.933588)
			(xy 52.610482 -321.960237) (xy 52.652153 -321.993468) (xy 52.688405 -322.032539) (xy 52.718429 -322.076576)
			(xy 52.741555 -322.124597) (xy 52.757265 -322.175527) (xy 52.765208 -322.228231) (xy 52.765706 -322.25488)
			(xy 52.765285 -322.279939) (xy 52.758277 -322.329565) (xy 52.744381 -322.377718) (xy 52.723873 -322.423448)
			(xy 52.697157 -322.465852) (xy 52.664761 -322.504093) (xy 52.646326 -322.521072) (xy 52.636309 -322.530644)
			(xy 52.621386 -322.553976) (xy 52.613272 -322.580456) (xy 52.612561 -322.608143) (xy 52.619306 -322.635005)
			(xy 52.633012 -322.659072) (xy 52.642516 -322.669154) (xy 52.662148 -322.689382) (xy 52.695477 -322.734839)
			(xy 52.72123 -322.784978) (xy 52.738765 -322.838547) (xy 52.747644 -322.894209) (xy 52.74818 -322.922392)
			(xy 52.747682 -322.949041) (xy 52.739739 -323.001745) (xy 52.724029 -323.052675) (xy 52.700903 -323.100696)
			(xy 52.670879 -323.144733) (xy 52.634627 -323.183804) (xy 52.592956 -323.217035) (xy 52.546798 -323.243684)
			(xy 52.497184 -323.263156) (xy 52.445222 -323.275016) (xy 52.392072 -323.279) (xy 52.338922 -323.275016)
			(xy 52.28696 -323.263156) (xy 52.237346 -323.243684) (xy 52.191188 -323.217035) (xy 52.149517 -323.183804)
			(xy 52.113265 -323.144733) (xy 52.083241 -323.100696) (xy 52.060115 -323.052675) (xy 52.044405 -323.001745)
			(xy 52.036462 -322.949041) (xy 52.035964 -322.922392) (xy 49.274576 -322.922392) (xy 49.274486 -322.927197)
			(xy 49.266543 -322.979901) (xy 49.250833 -323.030831) (xy 49.227707 -323.078852) (xy 49.197683 -323.122889)
			(xy 49.161431 -323.16196) (xy 49.11976 -323.195191) (xy 49.073602 -323.22184) (xy 49.023988 -323.241312)
			(xy 48.972026 -323.253172) (xy 48.918876 -323.257156) (xy 48.865726 -323.253172) (xy 48.813764 -323.241312)
			(xy 48.76415 -323.22184) (xy 48.717992 -323.195191) (xy 48.676321 -323.16196) (xy 48.640069 -323.122889)
			(xy 48.610045 -323.078852) (xy 48.586919 -323.030831) (xy 48.571209 -322.979901) (xy 48.563266 -322.927197)
			(xy 48.562768 -322.900548) (xy 29.122116 -322.900548) (xy 29.656068 -323.4345) (xy 30.084248 -323.4345)
			(xy 30.088232 -323.381345) (xy 30.100093 -323.329378) (xy 30.119566 -323.279759) (xy 30.146217 -323.233596)
			(xy 30.179451 -323.191921) (xy 30.218524 -323.155664) (xy 30.262565 -323.125636) (xy 30.310589 -323.102507)
			(xy 30.361524 -323.086794) (xy 30.414232 -323.078847) (xy 30.440884 -323.078348) (xy 30.467292 -323.078855)
			(xy 30.519528 -323.086653) (xy 30.57004 -323.10208) (xy 30.617719 -323.124798) (xy 30.661521 -323.15431)
			(xy 30.700483 -323.189966) (xy 30.71749 -323.210174) (xy 30.727427 -323.221567) (xy 30.75248 -323.238458)
			(xy 30.781376 -323.247289) (xy 30.811592 -323.247289) (xy 30.840488 -323.238458) (xy 30.865541 -323.221567)
			(xy 30.875478 -323.210174) (xy 30.892482 -323.189962) (xy 30.931444 -323.154302) (xy 30.975245 -323.124786)
			(xy 31.022925 -323.102064) (xy 31.073437 -323.086632) (xy 31.125675 -323.078829) (xy 31.152084 -323.078348)
			(xy 31.178733 -323.078908) (xy 31.231435 -323.086849) (xy 31.282365 -323.102557) (xy 31.330385 -323.12568)
			(xy 31.374422 -323.155703) (xy 31.413492 -323.191953) (xy 31.446723 -323.233622) (xy 31.473373 -323.279778)
			(xy 31.492845 -323.329391) (xy 31.504705 -323.381352) (xy 31.508688 -323.4345) (xy 34.148248 -323.4345)
			(xy 34.152232 -323.381345) (xy 34.164093 -323.329378) (xy 34.183566 -323.279759) (xy 34.210217 -323.233596)
			(xy 34.243451 -323.191921) (xy 34.282524 -323.155664) (xy 34.326565 -323.125636) (xy 34.374589 -323.102507)
			(xy 34.425524 -323.086794) (xy 34.478232 -323.078847) (xy 34.504884 -323.078348) (xy 34.531292 -323.078855)
			(xy 34.583528 -323.086653) (xy 34.63404 -323.10208) (xy 34.681719 -323.124798) (xy 34.725521 -323.15431)
			(xy 34.764483 -323.189966) (xy 34.78149 -323.210174) (xy 34.791427 -323.221567) (xy 34.81648 -323.238458)
			(xy 34.845376 -323.247289) (xy 34.875592 -323.247289) (xy 34.904488 -323.238458) (xy 34.929541 -323.221567)
			(xy 34.939478 -323.210174) (xy 34.956482 -323.189962) (xy 34.995444 -323.154302) (xy 35.039245 -323.124786)
			(xy 35.086925 -323.102064) (xy 35.137437 -323.086632) (xy 35.189675 -323.078829) (xy 35.216084 -323.078348)
			(xy 35.242733 -323.078908) (xy 35.295435 -323.086849) (xy 35.346365 -323.102557) (xy 35.394385 -323.12568)
			(xy 35.438422 -323.155703) (xy 35.477492 -323.191953) (xy 35.510723 -323.233622) (xy 35.537373 -323.279778)
			(xy 35.556845 -323.329391) (xy 35.568705 -323.381352) (xy 35.572688 -323.4345) (xy 37.628048 -323.4345)
			(xy 37.632032 -323.381345) (xy 37.643893 -323.329378) (xy 37.663366 -323.279759) (xy 37.690017 -323.233596)
			(xy 37.723251 -323.191921) (xy 37.762324 -323.155664) (xy 37.806365 -323.125636) (xy 37.854389 -323.102507)
			(xy 37.905324 -323.086794) (xy 37.958032 -323.078847) (xy 37.984684 -323.078348) (xy 38.011092 -323.078855)
			(xy 38.063328 -323.086653) (xy 38.11384 -323.10208) (xy 38.161519 -323.124798) (xy 38.205321 -323.15431)
			(xy 38.244283 -323.189966) (xy 38.26129 -323.210174) (xy 38.271227 -323.221567) (xy 38.29628 -323.238458)
			(xy 38.325176 -323.247289) (xy 38.355392 -323.247289) (xy 38.384288 -323.238458) (xy 38.409341 -323.221567)
			(xy 38.419278 -323.210174) (xy 38.436282 -323.189962) (xy 38.475244 -323.154302) (xy 38.519045 -323.124786)
			(xy 38.566725 -323.102064) (xy 38.617237 -323.086632) (xy 38.669475 -323.078829) (xy 38.695884 -323.078348)
			(xy 38.722533 -323.078908) (xy 38.775235 -323.086849) (xy 38.826165 -323.102557) (xy 38.874185 -323.12568)
			(xy 38.918222 -323.155703) (xy 38.957292 -323.191953) (xy 38.990523 -323.233622) (xy 39.017173 -323.279778)
			(xy 39.036645 -323.329391) (xy 39.048505 -323.381352) (xy 39.052488 -323.4345) (xy 41.692048 -323.4345)
			(xy 41.696032 -323.381345) (xy 41.707893 -323.329378) (xy 41.727366 -323.279759) (xy 41.754017 -323.233596)
			(xy 41.787251 -323.191921) (xy 41.826324 -323.155664) (xy 41.870365 -323.125636) (xy 41.918389 -323.102507)
			(xy 41.969324 -323.086794) (xy 42.022032 -323.078847) (xy 42.048684 -323.078348) (xy 42.075092 -323.078855)
			(xy 42.127328 -323.086653) (xy 42.17784 -323.10208) (xy 42.225519 -323.124798) (xy 42.269321 -323.15431)
			(xy 42.308283 -323.189966) (xy 42.32529 -323.210174) (xy 42.335227 -323.221567) (xy 42.36028 -323.238458)
			(xy 42.389176 -323.247289) (xy 42.419392 -323.247289) (xy 42.448288 -323.238458) (xy 42.473341 -323.221567)
			(xy 42.483278 -323.210174) (xy 42.500282 -323.189962) (xy 42.539244 -323.154302) (xy 42.583045 -323.124786)
			(xy 42.630725 -323.102064) (xy 42.681237 -323.086632) (xy 42.733475 -323.078829) (xy 42.759884 -323.078348)
			(xy 42.786533 -323.078908) (xy 42.839235 -323.086849) (xy 42.890165 -323.102557) (xy 42.938185 -323.12568)
			(xy 42.982222 -323.155703) (xy 43.021292 -323.191953) (xy 43.054523 -323.233622) (xy 43.081173 -323.279778)
			(xy 43.100645 -323.329391) (xy 43.112505 -323.381352) (xy 43.116488 -323.4345) (xy 45.171848 -323.4345)
			(xy 45.175832 -323.381345) (xy 45.187693 -323.329378) (xy 45.207166 -323.279759) (xy 45.233817 -323.233596)
			(xy 45.267051 -323.191921) (xy 45.306124 -323.155664) (xy 45.350165 -323.125636) (xy 45.398189 -323.102507)
			(xy 45.449124 -323.086794) (xy 45.501832 -323.078847) (xy 45.528484 -323.078348) (xy 45.554892 -323.078855)
			(xy 45.607128 -323.086653) (xy 45.65764 -323.10208) (xy 45.705319 -323.124798) (xy 45.749121 -323.15431)
			(xy 45.788083 -323.189966) (xy 45.80509 -323.210174) (xy 45.815027 -323.221567) (xy 45.84008 -323.238458)
			(xy 45.868976 -323.247289) (xy 45.899192 -323.247289) (xy 45.928088 -323.238458) (xy 45.953141 -323.221567)
			(xy 45.963078 -323.210174) (xy 45.980082 -323.189962) (xy 46.019044 -323.154302) (xy 46.062845 -323.124786)
			(xy 46.110525 -323.102064) (xy 46.161037 -323.086632) (xy 46.213275 -323.078829) (xy 46.239684 -323.078348)
			(xy 46.266333 -323.078908) (xy 46.319035 -323.086849) (xy 46.369965 -323.102557) (xy 46.417985 -323.12568)
			(xy 46.462022 -323.155703) (xy 46.501092 -323.191953) (xy 46.534323 -323.233622) (xy 46.560973 -323.279778)
			(xy 46.580445 -323.329391) (xy 46.592305 -323.381352) (xy 46.596288 -323.4345) (xy 46.592305 -323.487648)
			(xy 46.580445 -323.539609) (xy 46.560973 -323.589222) (xy 46.534323 -323.635378) (xy 46.501092 -323.677047)
			(xy 46.462022 -323.713297) (xy 46.417985 -323.74332) (xy 46.369965 -323.766443) (xy 46.319035 -323.782151)
			(xy 46.266333 -323.790092) (xy 46.239684 -323.790564) (xy 46.213274 -323.790112) (xy 46.161034 -323.782307)
			(xy 46.110519 -323.766871) (xy 46.062839 -323.744143) (xy 46.01904 -323.71462) (xy 45.980082 -323.678952)
			(xy 45.963078 -323.658738) (xy 45.953141 -323.647345) (xy 45.928088 -323.630454) (xy 45.899192 -323.621623)
			(xy 45.868976 -323.621623) (xy 45.84008 -323.630454) (xy 45.815027 -323.647345) (xy 45.80509 -323.658738)
			(xy 45.788106 -323.678968) (xy 45.74914 -323.714626) (xy 45.705335 -323.744139) (xy 45.657651 -323.766859)
			(xy 45.607135 -323.782287) (xy 45.554894 -323.790086) (xy 45.528484 -323.790564) (xy 45.501832 -323.790153)
			(xy 45.449124 -323.782206) (xy 45.398189 -323.766493) (xy 45.350165 -323.743364) (xy 45.306124 -323.713336)
			(xy 45.267051 -323.677079) (xy 45.233817 -323.635404) (xy 45.207166 -323.589241) (xy 45.187693 -323.539622)
			(xy 45.175832 -323.487655) (xy 45.171848 -323.4345) (xy 43.116488 -323.4345) (xy 43.112505 -323.487648)
			(xy 43.100645 -323.539609) (xy 43.081173 -323.589222) (xy 43.054523 -323.635378) (xy 43.021292 -323.677047)
			(xy 42.982222 -323.713297) (xy 42.938185 -323.74332) (xy 42.890165 -323.766443) (xy 42.839235 -323.782151)
			(xy 42.786533 -323.790092) (xy 42.759884 -323.790564) (xy 42.733474 -323.790112) (xy 42.681234 -323.782307)
			(xy 42.630719 -323.766871) (xy 42.583039 -323.744143) (xy 42.53924 -323.71462) (xy 42.500282 -323.678952)
			(xy 42.483278 -323.658738) (xy 42.473341 -323.647345) (xy 42.448288 -323.630454) (xy 42.419392 -323.621623)
			(xy 42.389176 -323.621623) (xy 42.36028 -323.630454) (xy 42.335227 -323.647345) (xy 42.32529 -323.658738)
			(xy 42.308306 -323.678968) (xy 42.26934 -323.714626) (xy 42.225535 -323.744139) (xy 42.177851 -323.766859)
			(xy 42.127335 -323.782287) (xy 42.075094 -323.790086) (xy 42.048684 -323.790564) (xy 42.022032 -323.790153)
			(xy 41.969324 -323.782206) (xy 41.918389 -323.766493) (xy 41.870365 -323.743364) (xy 41.826324 -323.713336)
			(xy 41.787251 -323.677079) (xy 41.754017 -323.635404) (xy 41.727366 -323.589241) (xy 41.707893 -323.539622)
			(xy 41.696032 -323.487655) (xy 41.692048 -323.4345) (xy 39.052488 -323.4345) (xy 39.048505 -323.487648)
			(xy 39.036645 -323.539609) (xy 39.017173 -323.589222) (xy 38.990523 -323.635378) (xy 38.957292 -323.677047)
			(xy 38.918222 -323.713297) (xy 38.874185 -323.74332) (xy 38.826165 -323.766443) (xy 38.775235 -323.782151)
			(xy 38.722533 -323.790092) (xy 38.695884 -323.790564) (xy 38.669474 -323.790112) (xy 38.617234 -323.782307)
			(xy 38.566719 -323.766871) (xy 38.519039 -323.744143) (xy 38.47524 -323.71462) (xy 38.436282 -323.678952)
			(xy 38.419278 -323.658738) (xy 38.409341 -323.647345) (xy 38.384288 -323.630454) (xy 38.355392 -323.621623)
			(xy 38.325176 -323.621623) (xy 38.29628 -323.630454) (xy 38.271227 -323.647345) (xy 38.26129 -323.658738)
			(xy 38.244306 -323.678968) (xy 38.20534 -323.714626) (xy 38.161535 -323.744139) (xy 38.113851 -323.766859)
			(xy 38.063335 -323.782287) (xy 38.011094 -323.790086) (xy 37.984684 -323.790564) (xy 37.958032 -323.790153)
			(xy 37.905324 -323.782206) (xy 37.854389 -323.766493) (xy 37.806365 -323.743364) (xy 37.762324 -323.713336)
			(xy 37.723251 -323.677079) (xy 37.690017 -323.635404) (xy 37.663366 -323.589241) (xy 37.643893 -323.539622)
			(xy 37.632032 -323.487655) (xy 37.628048 -323.4345) (xy 35.572688 -323.4345) (xy 35.568705 -323.487648)
			(xy 35.556845 -323.539609) (xy 35.537373 -323.589222) (xy 35.510723 -323.635378) (xy 35.477492 -323.677047)
			(xy 35.438422 -323.713297) (xy 35.394385 -323.74332) (xy 35.346365 -323.766443) (xy 35.295435 -323.782151)
			(xy 35.242733 -323.790092) (xy 35.216084 -323.790564) (xy 35.189674 -323.790112) (xy 35.137434 -323.782307)
			(xy 35.086919 -323.766871) (xy 35.039239 -323.744143) (xy 34.99544 -323.71462) (xy 34.956482 -323.678952)
			(xy 34.939478 -323.658738) (xy 34.929541 -323.647345) (xy 34.904488 -323.630454) (xy 34.875592 -323.621623)
			(xy 34.845376 -323.621623) (xy 34.81648 -323.630454) (xy 34.791427 -323.647345) (xy 34.78149 -323.658738)
			(xy 34.764506 -323.678968) (xy 34.72554 -323.714626) (xy 34.681735 -323.744139) (xy 34.634051 -323.766859)
			(xy 34.583535 -323.782287) (xy 34.531294 -323.790086) (xy 34.504884 -323.790564) (xy 34.478232 -323.790153)
			(xy 34.425524 -323.782206) (xy 34.374589 -323.766493) (xy 34.326565 -323.743364) (xy 34.282524 -323.713336)
			(xy 34.243451 -323.677079) (xy 34.210217 -323.635404) (xy 34.183566 -323.589241) (xy 34.164093 -323.539622)
			(xy 34.152232 -323.487655) (xy 34.148248 -323.4345) (xy 31.508688 -323.4345) (xy 31.504705 -323.487648)
			(xy 31.492845 -323.539609) (xy 31.473373 -323.589222) (xy 31.446723 -323.635378) (xy 31.413492 -323.677047)
			(xy 31.374422 -323.713297) (xy 31.330385 -323.74332) (xy 31.282365 -323.766443) (xy 31.231435 -323.782151)
			(xy 31.178733 -323.790092) (xy 31.152084 -323.790564) (xy 31.125674 -323.790112) (xy 31.073434 -323.782307)
			(xy 31.022919 -323.766871) (xy 30.975239 -323.744143) (xy 30.93144 -323.71462) (xy 30.892482 -323.678952)
			(xy 30.875478 -323.658738) (xy 30.865541 -323.647345) (xy 30.840488 -323.630454) (xy 30.811592 -323.621623)
			(xy 30.781376 -323.621623) (xy 30.75248 -323.630454) (xy 30.727427 -323.647345) (xy 30.71749 -323.658738)
			(xy 30.700506 -323.678968) (xy 30.66154 -323.714626) (xy 30.617735 -323.744139) (xy 30.570051 -323.766859)
			(xy 30.519535 -323.782287) (xy 30.467294 -323.790086) (xy 30.440884 -323.790564) (xy 30.414232 -323.790153)
			(xy 30.361524 -323.782206) (xy 30.310589 -323.766493) (xy 30.262565 -323.743364) (xy 30.218524 -323.713336)
			(xy 30.179451 -323.677079) (xy 30.146217 -323.635404) (xy 30.119566 -323.589241) (xy 30.100093 -323.539622)
			(xy 30.088232 -323.487655) (xy 30.084248 -323.4345) (xy 29.656068 -323.4345) (xy 30.339538 -324.11797)
		)
		(stroke
			(width 0)
			(type solid)
		)
		(fill yes)
		(layer "In2.Cu")
		(net "P3V3_AUX")
	)
	(gr_poly
		(pts
			(xy 335.067148 -288.891726) (xy 335.071155 -288.891644) (xy 335.079064 -288.890361) (xy 335.082896 -288.889186)
			(xy 335.107788 -288.880042) (xy 335.114392 -288.874708) (xy 335.11617 -288.87293) (xy 335.124298 -288.86658)
			(xy 335.143094 -288.830004) (xy 335.143856 -288.819336) (xy 335.146254 -288.785102) (xy 335.153751 -288.716877)
			(xy 335.158842 -288.682938) (xy 335.165144 -288.643856) (xy 335.181279 -288.566347) (xy 335.1911 -288.527998)
			(xy 335.192878 -288.515552) (xy 335.192726 -288.509623) (xy 335.190035 -288.498075) (xy 335.187544 -288.492692)
			(xy 335.182464 -288.482532) (xy 335.160366 -288.439352) (xy 335.158465 -288.436149) (xy 335.15387 -288.430288)
			(xy 335.151222 -288.427668) (xy 335.132172 -288.410142) (xy 335.124298 -288.406586) (xy 335.099264 -288.395205)
			(xy 335.053062 -288.365387) (xy 335.012436 -288.32833) (xy 334.978507 -288.285058) (xy 334.952211 -288.236764)
			(xy 334.934274 -288.184784) (xy 334.925193 -288.13055) (xy 334.924654 -288.103056) (xy 334.925167 -288.07707)
			(xy 334.933303 -288.025739) (xy 334.949367 -287.976311) (xy 334.972965 -287.930005) (xy 335.003514 -287.88796)
			(xy 335.040265 -287.851211) (xy 335.08231 -287.820661) (xy 335.128617 -287.797065) (xy 335.178044 -287.781001)
			(xy 335.229376 -287.772866) (xy 335.255362 -287.772348) (xy 335.255616 -287.772348) (xy 335.282149 -287.77287)
			(xy 335.334535 -287.781342) (xy 335.384891 -287.798082) (xy 335.431923 -287.822659) (xy 335.453482 -287.838134)
			(xy 335.460086 -287.84296) (xy 335.4832 -287.850834) (xy 335.496916 -287.852612) (xy 335.527904 -287.850834)
			(xy 335.55051 -287.849564) (xy 335.555027 -287.849258) (xy 335.563842 -287.847206) (xy 335.568036 -287.8455)
			(xy 335.591404 -287.834832) (xy 335.598008 -287.828482) (xy 335.598262 -287.828228) (xy 335.631028 -287.796986)
			(xy 335.633822 -287.794446) (xy 335.64068 -287.78581) (xy 335.647284 -287.770062) (xy 335.659984 -287.717484)
			(xy 335.660746 -287.714436) (xy 335.661762 -287.706816) (xy 335.662334 -287.699554) (xy 335.65976 -287.685224)
			(xy 335.656682 -287.678622) (xy 335.640426 -287.645602) (xy 335.631282 -287.627568) (xy 335.629156 -287.623751)
			(xy 335.623784 -287.61686) (xy 335.620614 -287.613852) (xy 335.610454 -287.604454) (xy 335.601818 -287.596326)
			(xy 335.59369 -287.59277) (xy 335.568715 -287.581332) (xy 335.522637 -287.551432) (xy 335.482125 -287.514338)
			(xy 335.448291 -287.471067) (xy 335.422062 -287.422805) (xy 335.404158 -287.370876) (xy 335.39507 -287.316704)
			(xy 335.394554 -287.28924) (xy 335.395034 -287.263248) (xy 335.40316 -287.211902) (xy 335.419218 -287.16246)
			(xy 335.442813 -287.116138) (xy 335.473364 -287.074078) (xy 335.510119 -287.037315) (xy 335.552172 -287.006754)
			(xy 335.598487 -286.983148) (xy 335.647926 -286.967078) (xy 335.69927 -286.95894) (xy 335.725262 -286.958532)
			(xy 335.752109 -286.959081) (xy 335.805094 -286.967794) (xy 335.855981 -286.984933) (xy 335.90344 -287.010051)
			(xy 335.92516 -287.025842) (xy 335.929224 -287.028636) (xy 335.959704 -287.039304) (xy 335.963006 -287.039304)
			(xy 336.019648 -287.035748) (xy 336.024173 -287.035366) (xy 336.032992 -287.0332) (xy 336.037174 -287.03143)
			(xy 336.061304 -287.020762) (xy 336.067654 -287.014412) (xy 336.070448 -287.011872) (xy 336.070702 -287.011618)
			(xy 336.072226 -287.010094) (xy 336.096864 -286.986472) (xy 336.099658 -286.983932) (xy 336.102706 -286.981138)
			(xy 336.117438 -286.955484) (xy 336.119216 -286.948118) (xy 336.130138 -286.90316) (xy 336.130392 -286.90189)
			(xy 336.1309 -286.900366) (xy 336.131916 -286.893508) (xy 336.132586 -286.886139) (xy 336.130123 -286.871556)
			(xy 336.12709 -286.864806) (xy 336.114136 -286.841946) (xy 336.112133 -286.838935) (xy 336.107418 -286.833452)
			(xy 336.104738 -286.831024) (xy 336.099658 -286.82696) (xy 336.083402 -286.813752) (xy 336.075274 -286.810704)
			(xy 336.057592 -286.804109) (xy 336.023609 -286.787696) (xy 336.007456 -286.777938) (xy 335.986104 -286.764207)
			(xy 335.947155 -286.731647) (xy 335.913226 -286.693886) (xy 335.898744 -286.673036) (xy 335.520284 -286.673036)
			(xy 335.504565 -286.693275) (xy 335.467934 -286.729108) (xy 335.426216 -286.758866) (xy 335.38041 -286.781837)
			(xy 335.33161 -286.797472) (xy 335.280983 -286.805396) (xy 335.255362 -286.805878) (xy 335.229395 -286.805366)
			(xy 335.178101 -286.797236) (xy 335.12871 -286.781183) (xy 335.082438 -286.757602) (xy 335.040424 -286.727072)
			(xy 335.003703 -286.690347) (xy 334.973179 -286.64833) (xy 334.949602 -286.602055) (xy 334.933555 -286.552662)
			(xy 334.925431 -286.501367) (xy 334.925431 -286.449433) (xy 334.933555 -286.398138) (xy 334.949602 -286.348745)
			(xy 334.973179 -286.30247) (xy 335.003703 -286.260453) (xy 335.040424 -286.223728) (xy 335.082438 -286.193198)
			(xy 335.12871 -286.169617) (xy 335.178101 -286.153564) (xy 335.229395 -286.145434) (xy 335.255362 -286.14497)
			(xy 335.280985 -286.145449) (xy 335.331616 -286.153355) (xy 335.380421 -286.168982) (xy 335.426227 -286.191957)
			(xy 335.467938 -286.221728) (xy 335.504552 -286.257581) (xy 335.520284 -286.277812) (xy 335.898744 -286.277812)
			(xy 335.914619 -286.254967) (xy 335.952297 -286.214043) (xy 335.99588 -286.179475) (xy 336.044307 -286.152102)
			(xy 336.0964 -286.13259) (xy 336.150894 -286.121414) (xy 336.178652 -286.11957) (xy 336.188304 -286.119316)
			(xy 336.195162 -286.119062) (xy 336.22023 -286.119481) (xy 336.269873 -286.126501) (xy 336.318037 -286.140422)
			(xy 336.363771 -286.160968) (xy 336.406166 -286.187731) (xy 336.42554 -286.203644) (xy 336.432144 -286.209232)
			(xy 336.465164 -286.221932) (xy 336.495898 -286.221678) (xy 336.530696 -286.2072) (xy 336.54619 -286.192214)
			(xy 336.56397 -286.17545) (xy 336.564224 -286.17545) (xy 336.566256 -286.173418) (xy 336.571844 -286.168084)
			(xy 336.586576 -286.142684) (xy 336.587592 -286.138366) (xy 336.588354 -286.13481) (xy 336.59953 -286.089598)
			(xy 336.600292 -286.08655) (xy 336.601308 -286.07893) (xy 336.60182 -286.071876) (xy 336.599372 -286.057953)
			(xy 336.596482 -286.051498) (xy 336.569558 -285.997396) (xy 336.562954 -285.988506) (xy 336.543396 -285.969964)
			(xy 336.541364 -285.968186) (xy 336.53349 -285.96463) (xy 336.508509 -285.953229) (xy 336.462414 -285.923392)
			(xy 336.421886 -285.886346) (xy 336.388039 -285.84311) (xy 336.361806 -285.794873) (xy 336.343909 -285.742963)
			(xy 336.334839 -285.688808) (xy 336.334354 -285.661354) (xy 336.334824 -285.635819) (xy 336.342665 -285.585356)
			(xy 336.35817 -285.536698) (xy 336.38097 -285.491001) (xy 336.410523 -285.449352) (xy 336.446126 -285.41274)
			(xy 336.486934 -285.382036) (xy 336.531977 -285.357969) (xy 336.580183 -285.341112) (xy 336.630408 -285.331864)
			(xy 336.655918 -285.330646) (xy 336.670904 -285.330138) (xy 336.703924 -285.307786) (xy 336.721958 -285.286196)
			(xy 336.725006 -285.279338) (xy 336.73562 -285.255355) (xy 336.759127 -285.208465) (xy 336.771996 -285.185612)
			(xy 336.789027 -285.156341) (xy 336.826654 -285.100026) (xy 336.84718 -285.07309) (xy 336.857848 -285.04261)
			(xy 336.857848 -285.042102) (xy 336.850736 -285.016956) (xy 336.848704 -285.0134) (xy 336.83479 -284.988035)
			(xy 336.814992 -284.933679) (xy 336.804907 -284.876716) (xy 336.804254 -284.847792) (xy 336.804254 -284.847538)
			(xy 336.804761 -284.821548) (xy 336.812886 -284.770206) (xy 336.828943 -284.720768) (xy 336.852537 -284.674451)
			(xy 336.883085 -284.632394) (xy 336.919837 -284.595635) (xy 336.961886 -284.565076) (xy 337.008198 -284.541473)
			(xy 337.057632 -284.525404) (xy 337.108972 -284.517267) (xy 337.134962 -284.51683) (xy 337.158949 -284.517255)
			(xy 337.206421 -284.524183) (xy 337.252394 -284.537897) (xy 337.295902 -284.558112) (xy 337.336032 -284.584401)
			(xy 337.371942 -284.616214) (xy 337.402878 -284.652882) (xy 337.415886 -284.67304) (xy 337.417664 -284.675834)
			(xy 337.434936 -284.692598) (xy 337.45297 -284.703266) (xy 337.458823 -284.706468) (xy 337.4717 -284.709936)
			(xy 337.47837 -284.710124) (xy 337.484466 -284.709616) (xy 337.48599 -284.709362) (xy 337.503262 -284.707584)
			(xy 337.557364 -284.703266) (xy 337.604862 -284.701996) (xy 337.65236 -284.703266) (xy 337.706462 -284.707584)
			(xy 337.723734 -284.709362) (xy 337.725258 -284.709616) (xy 337.731354 -284.710124) (xy 337.738015 -284.709888)
			(xy 337.750875 -284.706408) (xy 337.756754 -284.703266) (xy 337.774788 -284.692598) (xy 337.79206 -284.675834)
			(xy 337.793838 -284.67304) (xy 337.808558 -284.650359) (xy 337.844177 -284.609684) (xy 337.885942 -284.575349)
			(xy 337.932739 -284.54827) (xy 337.983319 -284.529169) (xy 338.036333 -284.518555) (xy 338.063332 -284.517084)
			(xy 338.069936 -284.516576) (xy 338.1121 -284.491938) (xy 338.183728 -284.367986) (xy 338.199361 -284.341457)
			(xy 338.233552 -284.290238) (xy 338.252054 -284.265624) (xy 338.25688 -284.259274) (xy 338.263484 -284.23997)
			(xy 338.264931 -284.233772) (xy 338.26506 -284.22105) (xy 338.263738 -284.214824) (xy 338.260436 -284.20314)
			(xy 338.257388 -284.197552) (xy 338.257134 -284.197298) (xy 338.24357 -284.172236) (xy 338.224321 -284.118605)
			(xy 338.214562 -284.062467) (xy 338.213954 -284.033976) (xy 338.213954 -284.033722) (xy 338.214462 -284.007733)
			(xy 338.222589 -283.956393) (xy 338.238648 -283.906957) (xy 338.262242 -283.860642) (xy 338.292791 -283.818588)
			(xy 338.329542 -283.78183) (xy 338.371591 -283.751274) (xy 338.417902 -283.727671) (xy 338.467335 -283.711603)
			(xy 338.518673 -283.703467) (xy 338.544662 -283.703014) (xy 338.56865 -283.703439) (xy 338.616122 -283.710366)
			(xy 338.662095 -283.72408) (xy 338.705604 -283.744294) (xy 338.745735 -283.770582) (xy 338.781647 -283.802394)
			(xy 338.812584 -283.839062) (xy 338.825586 -283.859224) (xy 338.827364 -283.862018) (xy 338.844636 -283.878782)
			(xy 338.86267 -283.88945) (xy 338.868524 -283.892647) (xy 338.881401 -283.896109) (xy 338.88807 -283.896308)
			(xy 338.894166 -283.8958) (xy 338.89569 -283.895546) (xy 338.912962 -283.893768) (xy 338.967064 -283.88945)
			(xy 339.014562 -283.88818) (xy 339.06206 -283.88945) (xy 339.116162 -283.893768) (xy 339.133434 -283.895546)
			(xy 339.134958 -283.8958) (xy 339.141054 -283.896308) (xy 339.147715 -283.896072) (xy 339.160575 -283.892591)
			(xy 339.166454 -283.88945) (xy 339.184488 -283.878782) (xy 339.20176 -283.862018) (xy 339.203538 -283.859224)
			(xy 339.216556 -283.839071) (xy 339.247489 -283.802399) (xy 339.283396 -283.770581) (xy 339.323524 -283.744285)
			(xy 339.36703 -283.724063) (xy 339.413002 -283.710339) (xy 339.460474 -283.703401) (xy 339.484462 -283.703014)
			(xy 339.510453 -283.703494) (xy 339.561794 -283.711621) (xy 339.611233 -283.72768) (xy 339.65755 -283.751276)
			(xy 339.699604 -283.781828) (xy 339.736361 -283.818583) (xy 339.766915 -283.860637) (xy 339.790514 -283.906953)
			(xy 339.806575 -283.95639) (xy 339.814704 -284.007731) (xy 339.81517 -284.033722) (xy 339.81517 -284.033976)
			(xy 339.814581 -284.062907) (xy 339.804525 -284.119888) (xy 339.784698 -284.174247) (xy 339.77072 -284.199584)
			(xy 339.768688 -284.20314) (xy 339.761576 -284.228286) (xy 339.761576 -284.228794) (xy 339.772244 -284.25902)
			(xy 339.7758 -284.263846) (xy 339.79879 -284.294418) (xy 339.840367 -284.358631) (xy 339.858858 -284.392116)
			(xy 339.876384 -284.410912) (xy 339.896704 -284.423612) (xy 339.902529 -284.426935) (xy 339.915405 -284.430668)
			(xy 339.922104 -284.430978) (xy 339.996272 -284.432756) (xy 340.004987 -284.432564) (xy 340.021485 -284.426978)
			(xy 340.0351 -284.416116) (xy 340.03996 -284.40888) (xy 340.063582 -284.367986) (xy 340.08022 -284.339732)
			(xy 340.116829 -284.285329) (xy 340.136734 -284.259274) (xy 340.147148 -284.228794) (xy 340.147148 -284.22854)
			(xy 340.140036 -284.203394) (xy 340.138004 -284.199838) (xy 340.124094 -284.174471) (xy 340.104307 -284.120115)
			(xy 340.094233 -284.063152) (xy 340.093554 -284.03423) (xy 340.093554 -284.033722) (xy 340.094062 -284.007733)
			(xy 340.102189 -283.956393) (xy 340.118248 -283.906957) (xy 340.141842 -283.860642) (xy 340.172391 -283.818588)
			(xy 340.209142 -283.78183) (xy 340.251191 -283.751274) (xy 340.297502 -283.727671) (xy 340.346935 -283.711603)
			(xy 340.398273 -283.703467) (xy 340.424262 -283.703014) (xy 340.44825 -283.703439) (xy 340.495722 -283.710366)
			(xy 340.541695 -283.72408) (xy 340.585204 -283.744294) (xy 340.625335 -283.770582) (xy 340.661247 -283.802394)
			(xy 340.692184 -283.839062) (xy 340.705186 -283.859224) (xy 340.706964 -283.862018) (xy 340.724236 -283.878782)
			(xy 340.74227 -283.88945) (xy 340.748124 -283.892647) (xy 340.761001 -283.896109) (xy 340.76767 -283.896308)
			(xy 340.773766 -283.8958) (xy 340.77529 -283.895546) (xy 340.833202 -283.890212) (xy 340.894416 -283.88818)
			(xy 340.928706 -283.888942) (xy 340.952074 -283.889958) (xy 340.967668 -283.890909) (xy 340.99879 -283.893702)
			(xy 341.014304 -283.895546) (xy 341.027512 -283.897324) (xy 341.03183 -283.897578) (xy 341.07501 -283.872178)
			(xy 341.079582 -283.865066) (xy 341.092445 -283.844239) (xy 341.123345 -283.806273) (xy 341.159505 -283.773278)
			(xy 341.200134 -283.745975) (xy 341.244344 -283.72496) (xy 341.291169 -283.710693) (xy 341.339587 -283.703485)
			(xy 341.364062 -283.703014) (xy 341.390053 -283.703494) (xy 341.441394 -283.711621) (xy 341.490833 -283.72768)
			(xy 341.53715 -283.751276) (xy 341.579204 -283.781828) (xy 341.615961 -283.818583) (xy 341.646515 -283.860637)
			(xy 341.670114 -283.906953) (xy 341.686175 -283.95639) (xy 341.694304 -284.007731) (xy 341.69477 -284.033722)
			(xy 341.69477 -284.033976) (xy 341.694177 -284.062411) (xy 341.684458 -284.118444) (xy 341.665319 -284.171997)
			(xy 341.651844 -284.197044) (xy 341.65159 -284.197298) (xy 341.648542 -284.202886) (xy 341.645494 -284.213808)
			(xy 341.644006 -284.220273) (xy 341.644142 -284.233533) (xy 341.645748 -284.23997) (xy 341.651844 -284.258766)
			(xy 341.656924 -284.26537) (xy 341.674311 -284.28857) (xy 341.70659 -284.336736) (xy 341.72144 -284.361636)
			(xy 341.738458 -284.391608) (xy 341.738712 -284.391862) (xy 341.741962 -284.397503) (xy 341.75084 -284.407018)
			(xy 341.756238 -284.410658) (xy 341.776558 -284.423358) (xy 341.782383 -284.426684) (xy 341.795258 -284.430426)
			(xy 341.801958 -284.430724) (xy 341.875872 -284.432502) (xy 341.884588 -284.43231) (xy 341.90109 -284.426728)
			(xy 341.914713 -284.415871) (xy 341.91956 -284.408626) (xy 341.943182 -284.367986) (xy 341.95982 -284.339732)
			(xy 341.996429 -284.285329) (xy 342.016334 -284.259274) (xy 342.026748 -284.228794) (xy 342.026748 -284.22854)
			(xy 342.019636 -284.203394) (xy 342.017604 -284.199838) (xy 342.003694 -284.174471) (xy 341.983907 -284.120115)
			(xy 341.973833 -284.063152) (xy 341.973154 -284.03423) (xy 341.973154 -284.033722) (xy 341.973662 -284.007733)
			(xy 341.981789 -283.956393) (xy 341.997848 -283.906957) (xy 342.021442 -283.860642) (xy 342.051991 -283.818588)
			(xy 342.088742 -283.78183) (xy 342.130791 -283.751274) (xy 342.177102 -283.727671) (xy 342.226535 -283.711603)
			(xy 342.277873 -283.703467) (xy 342.303862 -283.703014) (xy 342.32785 -283.703439) (xy 342.375322 -283.710366)
			(xy 342.421295 -283.72408) (xy 342.464804 -283.744294) (xy 342.504935 -283.770582) (xy 342.540847 -283.802394)
			(xy 342.571784 -283.839062) (xy 342.584786 -283.859224) (xy 342.586564 -283.862018) (xy 342.603836 -283.878782)
			(xy 342.62187 -283.88945) (xy 342.627724 -283.892647) (xy 342.640601 -283.896109) (xy 342.64727 -283.896308)
			(xy 342.653366 -283.8958) (xy 342.65489 -283.895546) (xy 342.712802 -283.890212) (xy 342.774016 -283.88818)
			(xy 342.808306 -283.888942) (xy 342.831674 -283.889958) (xy 342.847268 -283.890909) (xy 342.87839 -283.893702)
			(xy 342.893904 -283.895546) (xy 342.907112 -283.897324) (xy 342.91143 -283.897578) (xy 342.95461 -283.872178)
			(xy 342.959182 -283.865066) (xy 342.972045 -283.844239) (xy 343.002945 -283.806273) (xy 343.039105 -283.773278)
			(xy 343.079734 -283.745975) (xy 343.123944 -283.72496) (xy 343.170769 -283.710693) (xy 343.219187 -283.703485)
			(xy 343.243662 -283.703014) (xy 343.269653 -283.703494) (xy 343.320994 -283.711621) (xy 343.370433 -283.72768)
			(xy 343.41675 -283.751276) (xy 343.458804 -283.781828) (xy 343.495561 -283.818583) (xy 343.526115 -283.860637)
			(xy 343.549714 -283.906953) (xy 343.565775 -283.95639) (xy 343.573904 -284.007731) (xy 343.57437 -284.033722)
			(xy 343.57437 -284.033976) (xy 343.573777 -284.062411) (xy 343.564058 -284.118444) (xy 343.544919 -284.171997)
			(xy 343.531444 -284.197044) (xy 343.53119 -284.197298) (xy 343.528142 -284.202886) (xy 343.525094 -284.213808)
			(xy 343.523606 -284.220273) (xy 343.523742 -284.233533) (xy 343.525348 -284.23997) (xy 343.531444 -284.258766)
			(xy 343.536524 -284.26537) (xy 343.553911 -284.28857) (xy 343.58619 -284.336736) (xy 343.60104 -284.361636)
			(xy 343.618058 -284.391608) (xy 343.618312 -284.391862) (xy 343.621562 -284.397503) (xy 343.63044 -284.407018)
			(xy 343.635838 -284.410658) (xy 343.656158 -284.423358) (xy 343.661983 -284.426684) (xy 343.674858 -284.430426)
			(xy 343.681558 -284.430724) (xy 343.755472 -284.432502) (xy 343.764188 -284.43231) (xy 343.78069 -284.426728)
			(xy 343.794313 -284.415871) (xy 343.79916 -284.408626) (xy 343.822782 -284.367986) (xy 343.83942 -284.339732)
			(xy 343.876029 -284.285329) (xy 343.895934 -284.259274) (xy 343.906348 -284.228794) (xy 343.906348 -284.22854)
			(xy 343.899236 -284.203394) (xy 343.897204 -284.199838) (xy 343.883294 -284.174471) (xy 343.863507 -284.120115)
			(xy 343.853433 -284.063152) (xy 343.852754 -284.03423) (xy 343.852754 -284.033722) (xy 343.853262 -284.007733)
			(xy 343.861389 -283.956393) (xy 343.877448 -283.906957) (xy 343.901042 -283.860642) (xy 343.931591 -283.818588)
			(xy 343.968342 -283.78183) (xy 344.010391 -283.751274) (xy 344.056702 -283.727671) (xy 344.106135 -283.711603)
			(xy 344.157473 -283.703467) (xy 344.183462 -283.703014) (xy 344.20745 -283.703439) (xy 344.254922 -283.710366)
			(xy 344.300895 -283.72408) (xy 344.344404 -283.744294) (xy 344.384535 -283.770582) (xy 344.420447 -283.802394)
			(xy 344.451384 -283.839062) (xy 344.464386 -283.859224) (xy 344.466164 -283.862018) (xy 344.483436 -283.878782)
			(xy 344.50147 -283.88945) (xy 344.507324 -283.892647) (xy 344.520201 -283.896109) (xy 344.52687 -283.896308)
			(xy 344.532966 -283.8958) (xy 344.53449 -283.895546) (xy 344.592402 -283.890212) (xy 344.653616 -283.88818)
			(xy 344.687906 -283.888942) (xy 344.711274 -283.889958) (xy 344.726868 -283.890909) (xy 344.75799 -283.893702)
			(xy 344.773504 -283.895546) (xy 344.786712 -283.897324) (xy 344.79103 -283.897578) (xy 344.83421 -283.872178)
			(xy 344.838782 -283.865066) (xy 344.851645 -283.844239) (xy 344.882545 -283.806273) (xy 344.918705 -283.773278)
			(xy 344.959334 -283.745975) (xy 345.003544 -283.72496) (xy 345.050369 -283.710693) (xy 345.098787 -283.703485)
			(xy 345.123262 -283.703014) (xy 345.149253 -283.703494) (xy 345.200594 -283.711621) (xy 345.250033 -283.72768)
			(xy 345.29635 -283.751276) (xy 345.338404 -283.781828) (xy 345.375161 -283.818583) (xy 345.405715 -283.860637)
			(xy 345.429314 -283.906953) (xy 345.445375 -283.95639) (xy 345.453504 -284.007731) (xy 345.45397 -284.033722)
			(xy 345.45397 -284.033976) (xy 345.453377 -284.062411) (xy 345.443658 -284.118444) (xy 345.424519 -284.171997)
			(xy 345.411044 -284.197044) (xy 345.41079 -284.197298) (xy 345.407742 -284.202886) (xy 345.404694 -284.213808)
			(xy 345.403206 -284.220273) (xy 345.403342 -284.233533) (xy 345.404948 -284.23997) (xy 345.411044 -284.258766)
			(xy 345.416124 -284.26537) (xy 345.433511 -284.28857) (xy 345.46579 -284.336736) (xy 345.48064 -284.361636)
			(xy 345.497658 -284.391608) (xy 345.497912 -284.391862) (xy 345.501162 -284.397503) (xy 345.51004 -284.407018)
			(xy 345.515438 -284.410658) (xy 345.535758 -284.423358) (xy 345.541583 -284.426684) (xy 345.554458 -284.430426)
			(xy 345.561158 -284.430724) (xy 345.635072 -284.432502) (xy 345.643788 -284.43231) (xy 345.66029 -284.426728)
			(xy 345.673913 -284.415871) (xy 345.67876 -284.408626) (xy 345.702382 -284.367986) (xy 345.71902 -284.339732)
			(xy 345.755629 -284.285329) (xy 345.775534 -284.259274) (xy 345.785948 -284.228794) (xy 345.785948 -284.22854)
			(xy 345.778836 -284.203394) (xy 345.776804 -284.199838) (xy 345.762894 -284.174471) (xy 345.743107 -284.120115)
			(xy 345.733033 -284.063152) (xy 345.732354 -284.03423) (xy 345.732354 -284.033722) (xy 345.732862 -284.007733)
			(xy 345.740989 -283.956393) (xy 345.757048 -283.906957) (xy 345.780642 -283.860642) (xy 345.811191 -283.818588)
			(xy 345.847942 -283.78183) (xy 345.889991 -283.751274) (xy 345.936302 -283.727671) (xy 345.985735 -283.711603)
			(xy 346.037073 -283.703467) (xy 346.063062 -283.703014) (xy 346.08705 -283.703439) (xy 346.134522 -283.710366)
			(xy 346.180495 -283.72408) (xy 346.224004 -283.744294) (xy 346.264135 -283.770582) (xy 346.300047 -283.802394)
			(xy 346.330984 -283.839062) (xy 346.343986 -283.859224) (xy 346.345764 -283.862018) (xy 346.363036 -283.878782)
			(xy 346.38107 -283.88945) (xy 346.386924 -283.892647) (xy 346.399801 -283.896109) (xy 346.40647 -283.896308)
			(xy 346.412566 -283.8958) (xy 346.41409 -283.895546) (xy 346.472002 -283.890212) (xy 346.533216 -283.88818)
			(xy 346.567506 -283.888942) (xy 346.590874 -283.889958) (xy 346.606468 -283.890909) (xy 346.63759 -283.893702)
			(xy 346.653104 -283.895546) (xy 346.666312 -283.897324) (xy 346.67063 -283.897578) (xy 346.71381 -283.872178)
			(xy 346.718382 -283.865066) (xy 346.731245 -283.844239) (xy 346.762145 -283.806273) (xy 346.798305 -283.773278)
			(xy 346.838934 -283.745975) (xy 346.883144 -283.72496) (xy 346.929969 -283.710693) (xy 346.978387 -283.703485)
			(xy 347.002862 -283.703014) (xy 347.028853 -283.703494) (xy 347.080194 -283.711621) (xy 347.129633 -283.72768)
			(xy 347.17595 -283.751276) (xy 347.218004 -283.781828) (xy 347.254761 -283.818583) (xy 347.285315 -283.860637)
			(xy 347.308914 -283.906953) (xy 347.324975 -283.95639) (xy 347.333104 -284.007731) (xy 347.33357 -284.033722)
			(xy 347.33357 -284.033976) (xy 347.332977 -284.062411) (xy 347.323258 -284.118444) (xy 347.304119 -284.171997)
			(xy 347.290644 -284.197044) (xy 347.29039 -284.197298) (xy 347.287342 -284.202886) (xy 347.284294 -284.213808)
			(xy 347.282806 -284.220273) (xy 347.282942 -284.233533) (xy 347.284548 -284.23997) (xy 347.290644 -284.258766)
			(xy 347.295724 -284.26537) (xy 347.313111 -284.28857) (xy 347.34539 -284.336736) (xy 347.36024 -284.361636)
			(xy 347.377258 -284.391608) (xy 347.377512 -284.391862) (xy 347.380762 -284.397503) (xy 347.38964 -284.407018)
			(xy 347.395038 -284.410658) (xy 347.415358 -284.423358) (xy 347.421183 -284.426684) (xy 347.434058 -284.430426)
			(xy 347.440758 -284.430724) (xy 347.514672 -284.432502) (xy 347.523388 -284.43231) (xy 347.53989 -284.426728)
			(xy 347.553513 -284.415871) (xy 347.55836 -284.408626) (xy 347.581982 -284.367986) (xy 347.59862 -284.339732)
			(xy 347.635229 -284.285329) (xy 347.655134 -284.259274) (xy 347.665548 -284.228794) (xy 347.665548 -284.22854)
			(xy 347.658436 -284.203394) (xy 347.656404 -284.199838) (xy 347.642494 -284.174471) (xy 347.622707 -284.120115)
			(xy 347.612633 -284.063152) (xy 347.611954 -284.03423) (xy 347.611954 -284.033722) (xy 347.612462 -284.007733)
			(xy 347.620589 -283.956393) (xy 347.636648 -283.906957) (xy 347.660242 -283.860642) (xy 347.690791 -283.818588)
			(xy 347.727542 -283.78183) (xy 347.769591 -283.751274) (xy 347.815902 -283.727671) (xy 347.865335 -283.711603)
			(xy 347.916673 -283.703467) (xy 347.942662 -283.703014) (xy 347.96665 -283.703439) (xy 348.014122 -283.710366)
			(xy 348.060095 -283.72408) (xy 348.103604 -283.744294) (xy 348.143735 -283.770582) (xy 348.179647 -283.802394)
			(xy 348.210584 -283.839062) (xy 348.223586 -283.859224) (xy 348.225364 -283.862018) (xy 348.242636 -283.878782)
			(xy 348.26067 -283.88945) (xy 348.266524 -283.892647) (xy 348.279401 -283.896109) (xy 348.28607 -283.896308)
			(xy 348.292166 -283.8958) (xy 348.29369 -283.895546) (xy 348.351602 -283.890212) (xy 348.412816 -283.88818)
			(xy 348.447106 -283.888942) (xy 348.470474 -283.889958) (xy 348.486068 -283.890909) (xy 348.51719 -283.893702)
			(xy 348.532704 -283.895546) (xy 348.545912 -283.897324) (xy 348.55023 -283.897578) (xy 348.59341 -283.872178)
			(xy 348.597982 -283.865066) (xy 348.610845 -283.844239) (xy 348.641745 -283.806273) (xy 348.677905 -283.773278)
			(xy 348.718534 -283.745975) (xy 348.762744 -283.72496) (xy 348.809569 -283.710693) (xy 348.857987 -283.703485)
			(xy 348.882462 -283.703014) (xy 348.908453 -283.703494) (xy 348.959794 -283.711621) (xy 349.009233 -283.72768)
			(xy 349.05555 -283.751276) (xy 349.097604 -283.781828) (xy 349.134361 -283.818583) (xy 349.164915 -283.860637)
			(xy 349.188514 -283.906953) (xy 349.204575 -283.95639) (xy 349.212704 -284.007731) (xy 349.21317 -284.033722)
			(xy 349.21317 -284.033976) (xy 349.212577 -284.062411) (xy 349.202858 -284.118444) (xy 349.183719 -284.171997)
			(xy 349.170244 -284.197044) (xy 349.16999 -284.197298) (xy 349.166942 -284.202886) (xy 349.163894 -284.213808)
			(xy 349.162406 -284.220273) (xy 349.162542 -284.233533) (xy 349.164148 -284.23997) (xy 349.170244 -284.258766)
			(xy 349.17507 -284.265116) (xy 349.207066 -284.308216) (xy 349.262317 -284.400252) (xy 349.285306 -284.448758)
			(xy 349.30334 -284.46984) (xy 349.3262 -284.484572) (xy 349.331992 -284.487757) (xy 349.344739 -284.491243)
			(xy 349.351346 -284.49143) (xy 349.374206 -284.49143) (xy 349.38589 -284.484826) (xy 349.391325 -284.48159)
			(xy 349.400462 -284.472848) (xy 349.403924 -284.467554) (xy 349.461582 -284.367986) (xy 349.47822 -284.339732)
			(xy 349.514829 -284.285329) (xy 349.534734 -284.259274) (xy 349.545148 -284.228794) (xy 349.545148 -284.22854)
			(xy 349.538036 -284.203394) (xy 349.536004 -284.199838) (xy 349.522094 -284.174471) (xy 349.502307 -284.120115)
			(xy 349.492233 -284.063152) (xy 349.491554 -284.03423) (xy 349.491554 -284.033722) (xy 349.492062 -284.007733)
			(xy 349.500189 -283.956393) (xy 349.516248 -283.906957) (xy 349.539842 -283.860642) (xy 349.570391 -283.818588)
			(xy 349.607142 -283.78183) (xy 349.649191 -283.751274) (xy 349.695502 -283.727671) (xy 349.744935 -283.711603)
			(xy 349.796273 -283.703467) (xy 349.822262 -283.703014) (xy 349.84625 -283.703439) (xy 349.893722 -283.710366)
			(xy 349.939695 -283.72408) (xy 349.983204 -283.744294) (xy 350.023335 -283.770582) (xy 350.059247 -283.802394)
			(xy 350.090184 -283.839062) (xy 350.103186 -283.859224) (xy 350.104964 -283.862018) (xy 350.122236 -283.878782)
			(xy 350.14027 -283.88945) (xy 350.146124 -283.892647) (xy 350.159001 -283.896109) (xy 350.16567 -283.896308)
			(xy 350.171766 -283.8958) (xy 350.17329 -283.895546) (xy 350.231202 -283.890212) (xy 350.292416 -283.88818)
			(xy 350.326706 -283.888942) (xy 350.350074 -283.889958) (xy 350.365668 -283.890909) (xy 350.39679 -283.893702)
			(xy 350.412304 -283.895546) (xy 350.425512 -283.897324) (xy 350.42983 -283.897578) (xy 350.47301 -283.872178)
			(xy 350.477582 -283.865066) (xy 350.490445 -283.844239) (xy 350.521345 -283.806273) (xy 350.557505 -283.773278)
			(xy 350.598134 -283.745975) (xy 350.642344 -283.72496) (xy 350.689169 -283.710693) (xy 350.737587 -283.703485)
			(xy 350.762062 -283.703014) (xy 350.788053 -283.703494) (xy 350.839394 -283.711621) (xy 350.888833 -283.72768)
			(xy 350.93515 -283.751276) (xy 350.977204 -283.781828) (xy 351.013961 -283.818583) (xy 351.044515 -283.860637)
			(xy 351.068114 -283.906953) (xy 351.084175 -283.95639) (xy 351.092304 -284.007731) (xy 351.09277 -284.033722)
			(xy 351.09277 -284.033976) (xy 351.092177 -284.062411) (xy 351.082458 -284.118444) (xy 351.063319 -284.171997)
			(xy 351.049844 -284.197044) (xy 351.04959 -284.197298) (xy 351.046542 -284.202886) (xy 351.043494 -284.213808)
			(xy 351.042006 -284.220273) (xy 351.042142 -284.233533) (xy 351.043748 -284.23997) (xy 351.049844 -284.258766)
			(xy 351.05467 -284.265116) (xy 351.086666 -284.308216) (xy 351.141917 -284.400252) (xy 351.164906 -284.448758)
			(xy 351.18294 -284.46984) (xy 351.2058 -284.484572) (xy 351.211592 -284.487757) (xy 351.224339 -284.491243)
			(xy 351.230946 -284.49143) (xy 351.253806 -284.49143) (xy 351.26549 -284.484826) (xy 351.270925 -284.48159)
			(xy 351.280062 -284.472848) (xy 351.283524 -284.467554) (xy 351.341182 -284.367986) (xy 351.35782 -284.339732)
			(xy 351.394429 -284.285329) (xy 351.414334 -284.259274) (xy 351.424748 -284.228794) (xy 351.424748 -284.22854)
			(xy 351.417636 -284.203394) (xy 351.415604 -284.199838) (xy 351.401694 -284.174471) (xy 351.381907 -284.120115)
			(xy 351.371833 -284.063152) (xy 351.371154 -284.03423) (xy 351.371154 -284.033722) (xy 351.371662 -284.007733)
			(xy 351.379789 -283.956393) (xy 351.395848 -283.906957) (xy 351.419442 -283.860642) (xy 351.449991 -283.818588)
			(xy 351.486742 -283.78183) (xy 351.528791 -283.751274) (xy 351.575102 -283.727671) (xy 351.624535 -283.711603)
			(xy 351.675873 -283.703467) (xy 351.701862 -283.703014) (xy 351.72585 -283.703439) (xy 351.773322 -283.710366)
			(xy 351.819295 -283.72408) (xy 351.862804 -283.744294) (xy 351.902935 -283.770582) (xy 351.938847 -283.802394)
			(xy 351.969784 -283.839062) (xy 351.982786 -283.859224) (xy 351.984564 -283.862018) (xy 352.001836 -283.878782)
			(xy 352.01987 -283.88945) (xy 352.025724 -283.892647) (xy 352.038601 -283.896109) (xy 352.04527 -283.896308)
			(xy 352.051366 -283.8958) (xy 352.05289 -283.895546) (xy 352.110802 -283.890212) (xy 352.172016 -283.88818)
			(xy 352.206306 -283.888942) (xy 352.229674 -283.889958) (xy 352.245268 -283.890909) (xy 352.27639 -283.893702)
			(xy 352.291904 -283.895546) (xy 352.305112 -283.897324) (xy 352.30943 -283.897578) (xy 352.35261 -283.872178)
			(xy 352.357182 -283.865066) (xy 352.370045 -283.844239) (xy 352.400945 -283.806273) (xy 352.437105 -283.773278)
			(xy 352.477734 -283.745975) (xy 352.521944 -283.72496) (xy 352.568769 -283.710693) (xy 352.617187 -283.703485)
			(xy 352.641662 -283.703014) (xy 352.652806 -283.703055) (xy 352.67505 -283.704452) (xy 352.686112 -283.705808)
			(xy 352.690176 -283.706316) (xy 352.699352 -283.706423) (xy 352.716806 -283.700813) (xy 352.724212 -283.695394)
			(xy 352.765614 -283.659326) (xy 352.782632 -283.644594) (xy 352.790455 -283.637151) (xy 352.799422 -283.617534)
			(xy 352.799904 -283.606748) (xy 352.799904 -283.403802) (xy 352.79457 -283.381704) (xy 352.79203 -283.376624)
			(xy 352.780572 -283.352105) (xy 352.764382 -283.300463) (xy 352.7562 -283.246966) (xy 352.755708 -283.219906)
			(xy 352.755708 -283.219652) (xy 352.756209 -283.192949) (xy 352.764222 -283.140148) (xy 352.780019 -283.089131)
			(xy 352.803244 -283.04104) (xy 352.817938 -283.018738) (xy 352.818192 -283.018484) (xy 352.822256 -283.012388)
			(xy 352.829368 -282.991052) (xy 352.830412 -282.987522) (xy 352.831568 -282.980253) (xy 352.831654 -282.976574)
			(xy 352.831654 -282.85313) (xy 352.831177 -282.842531) (xy 352.822489 -282.823197) (xy 352.81489 -282.815792)
			(xy 352.750882 -282.763468) (xy 352.744078 -282.759028) (xy 352.728526 -282.754359) (xy 352.720402 -282.754324)
			(xy 352.71202 -282.755086) (xy 352.70948 -282.755594) (xy 352.693066 -282.758552) (xy 352.659863 -282.761737)
			(xy 352.643186 -282.761944) (xy 352.638614 -282.761944) (xy 352.613819 -282.761327) (xy 352.564754 -282.754066)
			(xy 352.517174 -282.740061) (xy 352.472 -282.719581) (xy 352.43011 -282.693026) (xy 352.392314 -282.660908)
			(xy 352.359346 -282.623852) (xy 352.345244 -282.603448) (xy 351.966784 -282.603448) (xy 351.951064 -282.623686)
			(xy 351.914433 -282.659518) (xy 351.872715 -282.689275) (xy 351.826909 -282.712245) (xy 351.77811 -282.727879)
			(xy 351.727483 -282.735804) (xy 351.701862 -282.73629) (xy 351.675894 -282.735778) (xy 351.624598 -282.727648)
			(xy 351.575205 -282.711594) (xy 351.528931 -282.688012) (xy 351.486916 -282.657482) (xy 351.450194 -282.620755)
			(xy 351.419668 -282.578736) (xy 351.396091 -282.53246) (xy 351.380043 -282.483065) (xy 351.371919 -282.431768)
			(xy 351.371919 -282.379832) (xy 351.380043 -282.328535) (xy 351.396091 -282.27914) (xy 351.419668 -282.232864)
			(xy 351.450194 -282.190845) (xy 351.486916 -282.154118) (xy 351.528931 -282.123588) (xy 351.575205 -282.100006)
			(xy 351.624598 -282.083952) (xy 351.675894 -282.075822) (xy 351.701862 -282.075382) (xy 351.727486 -282.075861)
			(xy 351.77812 -282.083765) (xy 351.826927 -282.09939) (xy 351.872737 -282.12236) (xy 351.914454 -282.152126)
			(xy 351.951076 -282.187974) (xy 351.966784 -282.208224) (xy 352.345244 -282.208224) (xy 352.359482 -282.187652)
			(xy 352.392802 -282.150332) (xy 352.431015 -282.118041) (xy 352.47337 -282.091412) (xy 352.519034 -282.070971)
			(xy 352.567108 -282.05712) (xy 352.616647 -282.050129) (xy 352.641662 -282.049728) (xy 352.66725 -282.050175)
			(xy 352.717898 -282.057508) (xy 352.766976 -282.072015) (xy 352.813471 -282.093397) (xy 352.856428 -282.121213)
			(xy 352.894962 -282.15489) (xy 352.928279 -282.193736) (xy 352.942398 -282.215082) (xy 352.94824 -282.22448)
			(xy 352.984816 -282.248356) (xy 353.064826 -282.258516) (xy 353.075963 -282.258995) (xy 353.096924 -282.25149)
			(xy 353.105212 -282.244038) (xy 353.682554 -281.666696) (xy 353.689335 -281.65935) (xy 353.696928 -281.640874)
			(xy 353.697286 -281.630882) (xy 353.697032 -281.626564) (xy 353.695508 -281.59202) (xy 353.696027 -281.564034)
			(xy 353.70478 -281.508751) (xy 353.722075 -281.455518) (xy 353.747484 -281.405646) (xy 353.780383 -281.360364)
			(xy 353.819961 -281.320785) (xy 353.865243 -281.287886) (xy 353.915114 -281.262476) (xy 353.968347 -281.245181)
			(xy 354.02363 -281.236427) (xy 354.051616 -281.235912) (xy 354.08616 -281.237436) (xy 354.090478 -281.23769)
			(xy 354.100458 -281.237293) (xy 354.118909 -281.229687) (xy 354.126292 -281.222958) (xy 354.24491 -281.10434)
			(xy 354.251353 -281.09725) (xy 354.258789 -281.079612) (xy 354.259388 -281.07005) (xy 354.259896 -281.047444)
			(xy 354.259896 -281.039062) (xy 354.248212 -281.007058) (xy 354.245418 -281.003502) (xy 354.235766 -280.991056)
			(xy 354.224844 -280.975816) (xy 353.846384 -280.975816) (xy 353.830665 -280.996056) (xy 353.794035 -281.031891)
			(xy 353.752318 -281.061651) (xy 353.706512 -281.084623) (xy 353.657711 -281.100259) (xy 353.607084 -281.108184)
			(xy 353.581462 -281.108658) (xy 353.555496 -281.108146) (xy 353.504205 -281.100017) (xy 353.454817 -281.083965)
			(xy 353.408548 -281.060385) (xy 353.366537 -281.029857) (xy 353.329818 -280.993134) (xy 353.299296 -280.951119)
			(xy 353.275721 -280.904848) (xy 353.259674 -280.855458) (xy 353.251551 -280.804166) (xy 353.251551 -280.752234)
			(xy 353.259674 -280.700942) (xy 353.275721 -280.651552) (xy 353.299296 -280.605281) (xy 353.329818 -280.563266)
			(xy 353.366537 -280.526543) (xy 353.408548 -280.496015) (xy 353.454817 -280.472435) (xy 353.504205 -280.456383)
			(xy 353.555496 -280.448254) (xy 353.581462 -280.44775) (xy 353.607085 -280.448229) (xy 353.657717 -280.456135)
			(xy 353.706522 -280.471761) (xy 353.75233 -280.494735) (xy 353.794041 -280.524505) (xy 353.830658 -280.560357)
			(xy 353.846384 -280.580592) (xy 354.224844 -280.580592) (xy 354.239083 -280.560021) (xy 354.272404 -280.522705)
			(xy 354.310618 -280.490416) (xy 354.352973 -280.46379) (xy 354.398636 -280.443351) (xy 354.44671 -280.429501)
			(xy 354.496248 -280.422511) (xy 354.521262 -280.422096) (xy 354.547932 -280.422569) (xy 354.600676 -280.430526)
			(xy 354.651641 -280.446267) (xy 354.699685 -280.469439) (xy 354.743732 -280.499524) (xy 354.763578 -280.517346)
			(xy 354.763832 -280.517346) (xy 354.77117 -280.52357) (xy 354.789128 -280.530431) (xy 354.808348 -280.530066)
			(xy 354.826033 -280.522529) (xy 354.833174 -280.516076) (xy 356.067868 -279.281382) (xy 356.072414 -279.276512)
			(xy 356.078979 -279.264924) (xy 356.080822 -279.258522) (xy 356.080822 -279.23363) (xy 356.079298 -279.227788)
			(xy 356.075033 -279.208833) (xy 356.070445 -279.170252) (xy 356.070154 -279.150826) (xy 356.070154 -279.150318)
			(xy 356.070662 -279.124329) (xy 356.07879 -279.07299) (xy 356.094849 -279.023555) (xy 356.118443 -278.97724)
			(xy 356.148992 -278.935186) (xy 356.185743 -278.898429) (xy 356.227792 -278.867873) (xy 356.274103 -278.844271)
			(xy 356.323535 -278.828203) (xy 356.374873 -278.820067) (xy 356.400862 -278.81961) (xy 356.42186 -278.819954)
			(xy 356.463515 -278.825307) (xy 356.48392 -278.830278) (xy 356.484174 -278.830278) (xy 356.492638 -278.832074)
			(xy 356.509853 -278.83046) (xy 356.525516 -278.823137) (xy 356.531926 -278.817324) (xy 356.636828 -278.712422)
			(xy 356.643545 -278.705185) (xy 356.651149 -278.68698) (xy 356.65156 -278.677116) (xy 356.65156 -278.605742)
			(xy 356.637082 -278.57069) (xy 356.630478 -278.564086) (xy 356.613575 -278.545557) (xy 356.584994 -278.504345)
			(xy 356.562973 -278.459285) (xy 356.548017 -278.411415) (xy 356.540471 -278.361833) (xy 356.540054 -278.336756)
			(xy 356.540054 -278.336502) (xy 356.540517 -278.311341) (xy 356.54813 -278.261598) (xy 356.563194 -278.213584)
			(xy 356.585362 -278.168407) (xy 356.614121 -278.127113) (xy 356.648807 -278.090655) (xy 356.688619 -278.059876)
			(xy 356.732635 -278.035488) (xy 356.779841 -278.018052) (xy 356.829143 -278.007974) (xy 356.854252 -278.006302)
			(xy 356.854506 -278.006302) (xy 356.862888 -278.005794) (xy 356.870762 -278.005794) (xy 356.895836 -278.006254)
			(xy 356.945411 -278.013813) (xy 356.993278 -278.028763) (xy 357.038342 -278.050763) (xy 357.079573 -278.079309)
			(xy 357.098092 -278.096218) (xy 357.0986 -278.096726) (xy 357.10495 -278.102568) (xy 357.129588 -278.112982)
			(xy 357.131366 -278.113744) (xy 357.135821 -278.115404) (xy 357.145155 -278.117201) (xy 357.149908 -278.1173)
			(xy 357.211376 -278.1173) (xy 357.221213 -278.116763) (xy 357.239372 -278.109174) (xy 357.246682 -278.102568)
			(xy 357.329232 -278.020018) (xy 357.335948 -278.012781) (xy 357.34355 -277.994576) (xy 357.343964 -277.984712)
			(xy 357.343964 -277.925784) (xy 357.34329 -277.914157) (xy 357.332792 -277.893397) (xy 357.314143 -277.879492)
			(xy 357.302816 -277.876762) (xy 357.299006 -277.876254) (xy 357.273523 -277.872803) (xy 357.223846 -277.859516)
			(xy 357.176596 -277.839224) (xy 357.132755 -277.812348) (xy 357.093234 -277.779447) (xy 357.058856 -277.741205)
			(xy 357.044244 -277.720044) (xy 356.665784 -277.720044) (xy 356.650064 -277.740282) (xy 356.613433 -277.776115)
			(xy 356.571716 -277.805872) (xy 356.525909 -277.828842) (xy 356.47711 -277.844477) (xy 356.426483 -277.852401)
			(xy 356.400862 -277.852886) (xy 356.374894 -277.852374) (xy 356.323599 -277.844244) (xy 356.274207 -277.82819)
			(xy 356.227933 -277.804608) (xy 356.185919 -277.774079) (xy 356.149197 -277.737352) (xy 356.118672 -277.695334)
			(xy 356.095095 -277.649058) (xy 356.079047 -277.599664) (xy 356.070923 -277.548368) (xy 356.070923 -277.496432)
			(xy 356.079047 -277.445136) (xy 356.095095 -277.395742) (xy 356.118672 -277.349466) (xy 356.149197 -277.307448)
			(xy 356.185919 -277.270722) (xy 356.227933 -277.240192) (xy 356.274207 -277.21661) (xy 356.323599 -277.200556)
			(xy 356.374894 -277.192426) (xy 356.400862 -277.191978) (xy 356.426486 -277.192457) (xy 356.47712 -277.200361)
			(xy 356.525927 -277.215986) (xy 356.571738 -277.238956) (xy 356.613454 -277.268722) (xy 356.650077 -277.304569)
			(xy 356.665784 -277.32482) (xy 357.044244 -277.32482) (xy 357.058882 -277.30368) (xy 357.093261 -277.265445)
			(xy 357.132779 -277.232548) (xy 357.176615 -277.205673) (xy 357.223858 -277.185378) (xy 357.273528 -277.172084)
			(xy 357.299006 -277.16861) (xy 357.302816 -277.168102) (xy 357.314174 -277.16545) (xy 357.332851 -277.151527)
			(xy 357.343336 -277.130725) (xy 357.343964 -277.11908) (xy 357.343964 -276.473158) (xy 357.343577 -276.46362)
			(xy 357.336624 -276.445858) (xy 357.323658 -276.431868) (xy 357.306475 -276.423587) (xy 357.287454 -276.422162)
			(xy 357.269229 -276.427789) (xy 357.254322 -276.43969) (xy 357.249222 -276.447758) (xy 357.1748 -276.57679)
			(xy 357.18242 -276.598888) (xy 357.191212 -276.625463) (xy 357.200658 -276.68063) (xy 357.201216 -276.708616)
			(xy 357.200707 -276.734583) (xy 357.192582 -276.785878) (xy 357.176534 -276.835271) (xy 357.152956 -276.881545)
			(xy 357.12243 -276.923561) (xy 357.085707 -276.960284) (xy 357.043691 -276.99081) (xy 356.997417 -277.014388)
			(xy 356.948024 -277.030436) (xy 356.896729 -277.038561) (xy 356.844795 -277.038561) (xy 356.7935 -277.030436)
			(xy 356.744107 -277.014388) (xy 356.697833 -276.99081) (xy 356.655817 -276.960284) (xy 356.619094 -276.923561)
			(xy 356.588568 -276.881545) (xy 356.56499 -276.835271) (xy 356.548942 -276.785878) (xy 356.540817 -276.734583)
			(xy 356.540308 -276.708616) (xy 356.540783 -276.68317) (xy 356.548594 -276.632882) (xy 356.564021 -276.584385)
			(xy 356.586697 -276.538825) (xy 356.616087 -276.497278) (xy 356.651497 -276.460725) (xy 356.69209 -276.430031)
			(xy 356.736908 -276.405921) (xy 356.784891 -276.388963) (xy 356.809802 -276.38375) (xy 356.832916 -276.379432)
			(xy 357.020876 -276.053804) (xy 357.011224 -276.03069) (xy 357.002706 -276.009058) (xy 356.990715 -275.964141)
			(xy 356.984669 -275.918045) (xy 356.9843 -275.8948) (xy 356.984821 -275.866815) (xy 356.993576 -275.811534)
			(xy 357.010872 -275.758303) (xy 357.036283 -275.708433) (xy 357.069182 -275.663153) (xy 357.108759 -275.623576)
			(xy 357.15404 -275.590678) (xy 357.20391 -275.565269) (xy 357.257142 -275.547974) (xy 357.312423 -275.53922)
			(xy 357.340408 -275.538692) (xy 357.355081 -275.538843) (xy 357.384328 -275.541261) (xy 357.398828 -275.543518)
			(xy 357.399844 -275.543772) (xy 357.401876 -275.544026) (xy 357.406448 -275.544534) (xy 357.416348 -275.544972)
			(xy 357.435208 -275.538943) (xy 357.443024 -275.53285) (xy 357.487728 -275.495258) (xy 357.502714 -275.482812)
			(xy 357.510302 -275.475402) (xy 357.518974 -275.456068) (xy 357.519478 -275.445474) (xy 357.519478 -275.255736)
			(xy 357.518208 -275.244814) (xy 357.514144 -275.227542) (xy 357.511858 -275.222716) (xy 357.501756 -275.200424)
			(xy 357.487494 -275.153607) (xy 357.480282 -275.1052) (xy 357.479854 -275.08073) (xy 357.479854 -275.072094)
			(xy 357.481052 -275.045765) (xy 357.490763 -274.993966) (xy 357.508568 -274.944362) (xy 357.534015 -274.898211)
			(xy 357.566461 -274.856681) (xy 357.605084 -274.820823) (xy 357.648905 -274.791546) (xy 357.696816 -274.76959)
			(xy 357.747603 -274.755512) (xy 357.773732 -274.752054) (xy 357.790242 -274.749768) (xy 357.810562 -274.749768)
			(xy 357.8358 -274.750264) (xy 357.885686 -274.757971) (xy 357.933822 -274.773168) (xy 357.979091 -274.7955)
			(xy 358.020442 -274.82445) (xy 358.056915 -274.859346) (xy 358.07269 -274.879054) (xy 358.074722 -274.88134)
			(xy 358.091486 -274.895564) (xy 358.111806 -274.905978) (xy 358.116968 -274.908301) (xy 358.127992 -274.910862)
			(xy 358.13365 -274.911058) (xy 358.396286 -274.911058) (xy 358.402093 -274.910907) (xy 358.413387 -274.908208)
			(xy 358.418638 -274.905724) (xy 358.439974 -274.89404) (xy 358.456992 -274.878546) (xy 358.460294 -274.873974)
			(xy 358.475822 -274.852981) (xy 358.512013 -274.815342) (xy 358.553306 -274.783384) (xy 358.598819 -274.75779)
			(xy 358.647578 -274.739107) (xy 358.69854 -274.727735) (xy 358.750616 -274.723917) (xy 358.802692 -274.727735)
			(xy 358.853654 -274.739107) (xy 358.902413 -274.75779) (xy 358.947926 -274.783384) (xy 358.989219 -274.815342)
			(xy 359.02541 -274.852981) (xy 359.040938 -274.873974) (xy 359.04424 -274.878546) (xy 359.061258 -274.89404)
			(xy 359.082594 -274.905724) (xy 359.087859 -274.908165) (xy 359.099146 -274.910854) (xy 359.104946 -274.911058)
			(xy 359.335832 -274.911058) (xy 359.34164 -274.910914) (xy 359.352941 -274.908226) (xy 359.358184 -274.905724)
			(xy 359.37952 -274.89404) (xy 359.396538 -274.878546) (xy 359.39984 -274.873974) (xy 359.415368 -274.852981)
			(xy 359.451559 -274.815342) (xy 359.492852 -274.783384) (xy 359.538365 -274.75779) (xy 359.587124 -274.739107)
			(xy 359.638086 -274.727735) (xy 359.690162 -274.723917) (xy 359.742238 -274.727735) (xy 359.7932 -274.739107)
			(xy 359.841959 -274.75779) (xy 359.887472 -274.783384) (xy 359.928765 -274.815342) (xy 359.964956 -274.852981)
			(xy 359.980484 -274.873974) (xy 359.983786 -274.878546) (xy 360.000804 -274.89404) (xy 360.02214 -274.905724)
			(xy 360.027404 -274.908171) (xy 360.038691 -274.910872) (xy 360.044492 -274.911058) (xy 360.275632 -274.911058)
			(xy 360.28144 -274.910914) (xy 360.292741 -274.908226) (xy 360.297984 -274.905724) (xy 360.31932 -274.89404)
			(xy 360.336338 -274.878546) (xy 360.33964 -274.873974) (xy 360.355168 -274.852981) (xy 360.391359 -274.815342)
			(xy 360.432652 -274.783384) (xy 360.478165 -274.75779) (xy 360.526924 -274.739107) (xy 360.577886 -274.727735)
			(xy 360.629962 -274.723917) (xy 360.682038 -274.727735) (xy 360.733 -274.739107) (xy 360.781759 -274.75779)
			(xy 360.827272 -274.783384) (xy 360.868565 -274.815342) (xy 360.904756 -274.852981) (xy 360.920284 -274.873974)
			(xy 360.923586 -274.878546) (xy 360.940604 -274.89404) (xy 360.96194 -274.905724) (xy 360.967204 -274.908171)
			(xy 360.978491 -274.910872) (xy 360.984292 -274.911058) (xy 361.246674 -274.911058) (xy 361.252625 -274.910908)
			(xy 361.264185 -274.908083) (xy 361.269534 -274.90547) (xy 361.289092 -274.89531) (xy 361.305602 -274.881086)
			(xy 361.308904 -274.877022) (xy 361.324712 -274.857603) (xy 361.361183 -274.823295) (xy 361.402398 -274.794861)
			(xy 361.44742 -274.772948) (xy 361.495225 -274.758055) (xy 361.544726 -274.75052) (xy 361.569762 -274.750022)
			(xy 361.595752 -274.750502) (xy 361.647094 -274.758629) (xy 361.696531 -274.774688) (xy 361.742848 -274.798285)
			(xy 361.784902 -274.828837) (xy 361.821658 -274.865592) (xy 361.852211 -274.907645) (xy 361.875809 -274.953961)
			(xy 361.891869 -275.003398) (xy 361.899997 -275.05474) (xy 361.90047 -275.08073) (xy 361.899964 -275.106625)
			(xy 361.899953 -275.106697) (xy 362.179363 -275.106697) (xy 362.179363 -275.054763) (xy 362.187488 -275.003468)
			(xy 362.203536 -274.954075) (xy 362.227114 -274.907801) (xy 362.25764 -274.865785) (xy 362.294363 -274.829062)
			(xy 362.336379 -274.798536) (xy 362.382653 -274.774958) (xy 362.432046 -274.75891) (xy 362.483341 -274.750785)
			(xy 362.535275 -274.750785) (xy 362.58657 -274.75891) (xy 362.635963 -274.774958) (xy 362.682237 -274.798536)
			(xy 362.724253 -274.829062) (xy 362.760976 -274.865785) (xy 362.791502 -274.907801) (xy 362.81508 -274.954075)
			(xy 362.831128 -275.003468) (xy 362.839253 -275.054763) (xy 362.839762 -275.08073) (xy 362.839253 -275.106697)
			(xy 363.119163 -275.106697) (xy 363.119163 -275.054763) (xy 363.127288 -275.003468) (xy 363.143336 -274.954075)
			(xy 363.166914 -274.907801) (xy 363.19744 -274.865785) (xy 363.234163 -274.829062) (xy 363.276179 -274.798536)
			(xy 363.322453 -274.774958) (xy 363.371846 -274.75891) (xy 363.423141 -274.750785) (xy 363.475075 -274.750785)
			(xy 363.52637 -274.75891) (xy 363.575763 -274.774958) (xy 363.622037 -274.798536) (xy 363.664053 -274.829062)
			(xy 363.700776 -274.865785) (xy 363.731302 -274.907801) (xy 363.75488 -274.954075) (xy 363.770928 -275.003468)
			(xy 363.779053 -275.054763) (xy 363.779562 -275.08073) (xy 363.779053 -275.106697) (xy 364.059217 -275.106697)
			(xy 364.059217 -275.054763) (xy 364.067342 -275.003468) (xy 364.08339 -274.954075) (xy 364.106968 -274.907801)
			(xy 364.137494 -274.865785) (xy 364.174217 -274.829062) (xy 364.216233 -274.798536) (xy 364.262507 -274.774958)
			(xy 364.3119 -274.75891) (xy 364.363195 -274.750785) (xy 364.415129 -274.750785) (xy 364.466424 -274.75891)
			(xy 364.515817 -274.774958) (xy 364.562091 -274.798536) (xy 364.604107 -274.829062) (xy 364.64083 -274.865785)
			(xy 364.671356 -274.907801) (xy 364.694934 -274.954075) (xy 364.710982 -275.003468) (xy 364.719107 -275.054763)
			(xy 364.719616 -275.08073) (xy 364.719107 -275.106697) (xy 367.818671 -275.106697) (xy 367.818671 -275.054763)
			(xy 367.826796 -275.003468) (xy 367.842844 -274.954075) (xy 367.866422 -274.907801) (xy 367.896948 -274.865785)
			(xy 367.933671 -274.829062) (xy 367.975687 -274.798536) (xy 368.021961 -274.774958) (xy 368.071354 -274.75891)
			(xy 368.122649 -274.750785) (xy 368.174583 -274.750785) (xy 368.225878 -274.75891) (xy 368.275271 -274.774958)
			(xy 368.321545 -274.798536) (xy 368.363561 -274.829062) (xy 368.400284 -274.865785) (xy 368.43081 -274.907801)
			(xy 368.454388 -274.954075) (xy 368.470436 -275.003468) (xy 368.478561 -275.054763) (xy 368.47907 -275.08073)
			(xy 368.478566 -275.106443) (xy 368.758217 -275.106443) (xy 368.758217 -275.054509) (xy 368.766342 -275.003214)
			(xy 368.78239 -274.953821) (xy 368.805968 -274.907547) (xy 368.836494 -274.865531) (xy 368.873217 -274.828808)
			(xy 368.915233 -274.798282) (xy 368.961507 -274.774704) (xy 369.0109 -274.758656) (xy 369.062195 -274.750531)
			(xy 369.114129 -274.750531) (xy 369.165424 -274.758656) (xy 369.214817 -274.774704) (xy 369.261091 -274.798282)
			(xy 369.303107 -274.828808) (xy 369.33983 -274.865531) (xy 369.370356 -274.907547) (xy 369.393934 -274.953821)
			(xy 369.409982 -275.003214) (xy 369.418107 -275.054509) (xy 369.418616 -275.080476) (xy 369.418107 -275.106443)
			(xy 369.418067 -275.106697) (xy 369.698271 -275.106697) (xy 369.698271 -275.054763) (xy 369.706396 -275.003468)
			(xy 369.722444 -274.954075) (xy 369.746022 -274.907801) (xy 369.776548 -274.865785) (xy 369.813271 -274.829062)
			(xy 369.855287 -274.798536) (xy 369.901561 -274.774958) (xy 369.950954 -274.75891) (xy 370.002249 -274.750785)
			(xy 370.054183 -274.750785) (xy 370.105478 -274.75891) (xy 370.154871 -274.774958) (xy 370.201145 -274.798536)
			(xy 370.243161 -274.829062) (xy 370.279884 -274.865785) (xy 370.31041 -274.907801) (xy 370.333988 -274.954075)
			(xy 370.350036 -275.003468) (xy 370.358161 -275.054763) (xy 370.35867 -275.08073) (xy 370.358161 -275.106697)
			(xy 370.638071 -275.106697) (xy 370.638071 -275.054763) (xy 370.646196 -275.003468) (xy 370.662244 -274.954075)
			(xy 370.685822 -274.907801) (xy 370.716348 -274.865785) (xy 370.753071 -274.829062) (xy 370.795087 -274.798536)
			(xy 370.841361 -274.774958) (xy 370.890754 -274.75891) (xy 370.942049 -274.750785) (xy 370.993983 -274.750785)
			(xy 371.045278 -274.75891) (xy 371.094671 -274.774958) (xy 371.140945 -274.798536) (xy 371.182961 -274.829062)
			(xy 371.219684 -274.865785) (xy 371.25021 -274.907801) (xy 371.273788 -274.954075) (xy 371.289836 -275.003468)
			(xy 371.297961 -275.054763) (xy 371.29847 -275.08073) (xy 371.297961 -275.106697) (xy 371.577871 -275.106697)
			(xy 371.577871 -275.054763) (xy 371.585996 -275.003468) (xy 371.602044 -274.954075) (xy 371.625622 -274.907801)
			(xy 371.656148 -274.865785) (xy 371.692871 -274.829062) (xy 371.734887 -274.798536) (xy 371.781161 -274.774958)
			(xy 371.830554 -274.75891) (xy 371.881849 -274.750785) (xy 371.933783 -274.750785) (xy 371.985078 -274.75891)
			(xy 372.034471 -274.774958) (xy 372.080745 -274.798536) (xy 372.122761 -274.829062) (xy 372.159484 -274.865785)
			(xy 372.19001 -274.907801) (xy 372.213588 -274.954075) (xy 372.229636 -275.003468) (xy 372.237761 -275.054763)
			(xy 372.23827 -275.08073) (xy 372.237761 -275.106697) (xy 372.517671 -275.106697) (xy 372.517671 -275.054763)
			(xy 372.525796 -275.003468) (xy 372.541844 -274.954075) (xy 372.565422 -274.907801) (xy 372.595948 -274.865785)
			(xy 372.632671 -274.829062) (xy 372.674687 -274.798536) (xy 372.720961 -274.774958) (xy 372.770354 -274.75891)
			(xy 372.821649 -274.750785) (xy 372.873583 -274.750785) (xy 372.924878 -274.75891) (xy 372.974271 -274.774958)
			(xy 373.020545 -274.798536) (xy 373.062561 -274.829062) (xy 373.099284 -274.865785) (xy 373.12981 -274.907801)
			(xy 373.153388 -274.954075) (xy 373.169436 -275.003468) (xy 373.177561 -275.054763) (xy 373.17807 -275.08073)
			(xy 373.177561 -275.106697) (xy 373.457471 -275.106697) (xy 373.457471 -275.054763) (xy 373.465596 -275.003468)
			(xy 373.481644 -274.954075) (xy 373.505222 -274.907801) (xy 373.535748 -274.865785) (xy 373.572471 -274.829062)
			(xy 373.614487 -274.798536) (xy 373.660761 -274.774958) (xy 373.710154 -274.75891) (xy 373.761449 -274.750785)
			(xy 373.813383 -274.750785) (xy 373.864678 -274.75891) (xy 373.914071 -274.774958) (xy 373.960345 -274.798536)
			(xy 374.002361 -274.829062) (xy 374.039084 -274.865785) (xy 374.06961 -274.907801) (xy 374.093188 -274.954075)
			(xy 374.109236 -275.003468) (xy 374.117361 -275.054763) (xy 374.11787 -275.08073) (xy 374.117361 -275.106697)
			(xy 374.397017 -275.106697) (xy 374.397017 -275.054763) (xy 374.405142 -275.003468) (xy 374.42119 -274.954075)
			(xy 374.444768 -274.907801) (xy 374.475294 -274.865785) (xy 374.512017 -274.829062) (xy 374.554033 -274.798536)
			(xy 374.600307 -274.774958) (xy 374.6497 -274.75891) (xy 374.700995 -274.750785) (xy 374.752929 -274.750785)
			(xy 374.804224 -274.75891) (xy 374.853617 -274.774958) (xy 374.899891 -274.798536) (xy 374.941907 -274.829062)
			(xy 374.97863 -274.865785) (xy 375.009156 -274.907801) (xy 375.032734 -274.954075) (xy 375.048782 -275.003468)
			(xy 375.056907 -275.054763) (xy 375.057416 -275.08073) (xy 375.056907 -275.106697) (xy 375.337071 -275.106697)
			(xy 375.337071 -275.054763) (xy 375.345196 -275.003468) (xy 375.361244 -274.954075) (xy 375.384822 -274.907801)
			(xy 375.415348 -274.865785) (xy 375.452071 -274.829062) (xy 375.494087 -274.798536) (xy 375.540361 -274.774958)
			(xy 375.589754 -274.75891) (xy 375.641049 -274.750785) (xy 375.692983 -274.750785) (xy 375.744278 -274.75891)
			(xy 375.793671 -274.774958) (xy 375.839945 -274.798536) (xy 375.881961 -274.829062) (xy 375.918684 -274.865785)
			(xy 375.94921 -274.907801) (xy 375.972788 -274.954075) (xy 375.988836 -275.003468) (xy 375.996961 -275.054763)
			(xy 375.99747 -275.08073) (xy 375.996961 -275.106697) (xy 376.276871 -275.106697) (xy 376.276871 -275.054763)
			(xy 376.284996 -275.003468) (xy 376.301044 -274.954075) (xy 376.324622 -274.907801) (xy 376.355148 -274.865785)
			(xy 376.391871 -274.829062) (xy 376.433887 -274.798536) (xy 376.480161 -274.774958) (xy 376.529554 -274.75891)
			(xy 376.580849 -274.750785) (xy 376.632783 -274.750785) (xy 376.684078 -274.75891) (xy 376.733471 -274.774958)
			(xy 376.779745 -274.798536) (xy 376.821761 -274.829062) (xy 376.858484 -274.865785) (xy 376.88901 -274.907801)
			(xy 376.912588 -274.954075) (xy 376.928636 -275.003468) (xy 376.936761 -275.054763) (xy 376.93727 -275.08073)
			(xy 376.936761 -275.106697) (xy 377.216671 -275.106697) (xy 377.216671 -275.054763) (xy 377.224796 -275.003468)
			(xy 377.240844 -274.954075) (xy 377.264422 -274.907801) (xy 377.294948 -274.865785) (xy 377.331671 -274.829062)
			(xy 377.373687 -274.798536) (xy 377.419961 -274.774958) (xy 377.469354 -274.75891) (xy 377.520649 -274.750785)
			(xy 377.572583 -274.750785) (xy 377.623878 -274.75891) (xy 377.673271 -274.774958) (xy 377.719545 -274.798536)
			(xy 377.761561 -274.829062) (xy 377.798284 -274.865785) (xy 377.82881 -274.907801) (xy 377.852388 -274.954075)
			(xy 377.868436 -275.003468) (xy 377.876561 -275.054763) (xy 377.87707 -275.08073) (xy 377.876561 -275.106697)
			(xy 378.156471 -275.106697) (xy 378.156471 -275.054763) (xy 378.164596 -275.003468) (xy 378.180644 -274.954075)
			(xy 378.204222 -274.907801) (xy 378.234748 -274.865785) (xy 378.271471 -274.829062) (xy 378.313487 -274.798536)
			(xy 378.359761 -274.774958) (xy 378.409154 -274.75891) (xy 378.460449 -274.750785) (xy 378.512383 -274.750785)
			(xy 378.563678 -274.75891) (xy 378.613071 -274.774958) (xy 378.659345 -274.798536) (xy 378.701361 -274.829062)
			(xy 378.738084 -274.865785) (xy 378.76861 -274.907801) (xy 378.792188 -274.954075) (xy 378.808236 -275.003468)
			(xy 378.816361 -275.054763) (xy 378.81687 -275.08073) (xy 378.816361 -275.106697) (xy 378.808236 -275.157992)
			(xy 378.792188 -275.207385) (xy 378.76861 -275.253659) (xy 378.738084 -275.295675) (xy 378.701361 -275.332398)
			(xy 378.659345 -275.362924) (xy 378.613071 -275.386502) (xy 378.563678 -275.40255) (xy 378.512383 -275.410675)
			(xy 378.460449 -275.410675) (xy 378.409154 -275.40255) (xy 378.359761 -275.386502) (xy 378.313487 -275.362924)
			(xy 378.271471 -275.332398) (xy 378.234748 -275.295675) (xy 378.204222 -275.253659) (xy 378.180644 -275.207385)
			(xy 378.164596 -275.157992) (xy 378.156471 -275.106697) (xy 377.876561 -275.106697) (xy 377.868436 -275.157992)
			(xy 377.852388 -275.207385) (xy 377.82881 -275.253659) (xy 377.798284 -275.295675) (xy 377.761561 -275.332398)
			(xy 377.719545 -275.362924) (xy 377.673271 -275.386502) (xy 377.623878 -275.40255) (xy 377.572583 -275.410675)
			(xy 377.520649 -275.410675) (xy 377.469354 -275.40255) (xy 377.419961 -275.386502) (xy 377.373687 -275.362924)
			(xy 377.331671 -275.332398) (xy 377.294948 -275.295675) (xy 377.264422 -275.253659) (xy 377.240844 -275.207385)
			(xy 377.224796 -275.157992) (xy 377.216671 -275.106697) (xy 376.936761 -275.106697) (xy 376.928636 -275.157992)
			(xy 376.912588 -275.207385) (xy 376.88901 -275.253659) (xy 376.858484 -275.295675) (xy 376.821761 -275.332398)
			(xy 376.779745 -275.362924) (xy 376.733471 -275.386502) (xy 376.684078 -275.40255) (xy 376.632783 -275.410675)
			(xy 376.580849 -275.410675) (xy 376.529554 -275.40255) (xy 376.480161 -275.386502) (xy 376.433887 -275.362924)
			(xy 376.391871 -275.332398) (xy 376.355148 -275.295675) (xy 376.324622 -275.253659) (xy 376.301044 -275.207385)
			(xy 376.284996 -275.157992) (xy 376.276871 -275.106697) (xy 375.996961 -275.106697) (xy 375.988836 -275.157992)
			(xy 375.972788 -275.207385) (xy 375.94921 -275.253659) (xy 375.918684 -275.295675) (xy 375.881961 -275.332398)
			(xy 375.839945 -275.362924) (xy 375.793671 -275.386502) (xy 375.744278 -275.40255) (xy 375.692983 -275.410675)
			(xy 375.641049 -275.410675) (xy 375.589754 -275.40255) (xy 375.540361 -275.386502) (xy 375.494087 -275.362924)
			(xy 375.452071 -275.332398) (xy 375.415348 -275.295675) (xy 375.384822 -275.253659) (xy 375.361244 -275.207385)
			(xy 375.345196 -275.157992) (xy 375.337071 -275.106697) (xy 375.056907 -275.106697) (xy 375.048782 -275.157992)
			(xy 375.032734 -275.207385) (xy 375.009156 -275.253659) (xy 374.97863 -275.295675) (xy 374.941907 -275.332398)
			(xy 374.899891 -275.362924) (xy 374.853617 -275.386502) (xy 374.804224 -275.40255) (xy 374.752929 -275.410675)
			(xy 374.700995 -275.410675) (xy 374.6497 -275.40255) (xy 374.600307 -275.386502) (xy 374.554033 -275.362924)
			(xy 374.512017 -275.332398) (xy 374.475294 -275.295675) (xy 374.444768 -275.253659) (xy 374.42119 -275.207385)
			(xy 374.405142 -275.157992) (xy 374.397017 -275.106697) (xy 374.117361 -275.106697) (xy 374.109236 -275.157992)
			(xy 374.093188 -275.207385) (xy 374.06961 -275.253659) (xy 374.039084 -275.295675) (xy 374.002361 -275.332398)
			(xy 373.960345 -275.362924) (xy 373.914071 -275.386502) (xy 373.864678 -275.40255) (xy 373.813383 -275.410675)
			(xy 373.761449 -275.410675) (xy 373.710154 -275.40255) (xy 373.660761 -275.386502) (xy 373.614487 -275.362924)
			(xy 373.572471 -275.332398) (xy 373.535748 -275.295675) (xy 373.505222 -275.253659) (xy 373.481644 -275.207385)
			(xy 373.465596 -275.157992) (xy 373.457471 -275.106697) (xy 373.177561 -275.106697) (xy 373.169436 -275.157992)
			(xy 373.153388 -275.207385) (xy 373.12981 -275.253659) (xy 373.099284 -275.295675) (xy 373.062561 -275.332398)
			(xy 373.020545 -275.362924) (xy 372.974271 -275.386502) (xy 372.924878 -275.40255) (xy 372.873583 -275.410675)
			(xy 372.821649 -275.410675) (xy 372.770354 -275.40255) (xy 372.720961 -275.386502) (xy 372.674687 -275.362924)
			(xy 372.632671 -275.332398) (xy 372.595948 -275.295675) (xy 372.565422 -275.253659) (xy 372.541844 -275.207385)
			(xy 372.525796 -275.157992) (xy 372.517671 -275.106697) (xy 372.237761 -275.106697) (xy 372.229636 -275.157992)
			(xy 372.213588 -275.207385) (xy 372.19001 -275.253659) (xy 372.159484 -275.295675) (xy 372.122761 -275.332398)
			(xy 372.080745 -275.362924) (xy 372.034471 -275.386502) (xy 371.985078 -275.40255) (xy 371.933783 -275.410675)
			(xy 371.881849 -275.410675) (xy 371.830554 -275.40255) (xy 371.781161 -275.386502) (xy 371.734887 -275.362924)
			(xy 371.692871 -275.332398) (xy 371.656148 -275.295675) (xy 371.625622 -275.253659) (xy 371.602044 -275.207385)
			(xy 371.585996 -275.157992) (xy 371.577871 -275.106697) (xy 371.297961 -275.106697) (xy 371.289836 -275.157992)
			(xy 371.273788 -275.207385) (xy 371.25021 -275.253659) (xy 371.219684 -275.295675) (xy 371.182961 -275.332398)
			(xy 371.140945 -275.362924) (xy 371.094671 -275.386502) (xy 371.045278 -275.40255) (xy 370.993983 -275.410675)
			(xy 370.942049 -275.410675) (xy 370.890754 -275.40255) (xy 370.841361 -275.386502) (xy 370.795087 -275.362924)
			(xy 370.753071 -275.332398) (xy 370.716348 -275.295675) (xy 370.685822 -275.253659) (xy 370.662244 -275.207385)
			(xy 370.646196 -275.157992) (xy 370.638071 -275.106697) (xy 370.358161 -275.106697) (xy 370.350036 -275.157992)
			(xy 370.333988 -275.207385) (xy 370.31041 -275.253659) (xy 370.279884 -275.295675) (xy 370.243161 -275.332398)
			(xy 370.201145 -275.362924) (xy 370.154871 -275.386502) (xy 370.105478 -275.40255) (xy 370.054183 -275.410675)
			(xy 370.002249 -275.410675) (xy 369.950954 -275.40255) (xy 369.901561 -275.386502) (xy 369.855287 -275.362924)
			(xy 369.813271 -275.332398) (xy 369.776548 -275.295675) (xy 369.746022 -275.253659) (xy 369.722444 -275.207385)
			(xy 369.706396 -275.157992) (xy 369.698271 -275.106697) (xy 369.418067 -275.106697) (xy 369.409982 -275.157738)
			(xy 369.393934 -275.207131) (xy 369.370356 -275.253405) (xy 369.33983 -275.295421) (xy 369.303107 -275.332144)
			(xy 369.261091 -275.36267) (xy 369.214817 -275.386248) (xy 369.165424 -275.402296) (xy 369.114129 -275.410421)
			(xy 369.062195 -275.410421) (xy 369.0109 -275.402296) (xy 368.961507 -275.386248) (xy 368.915233 -275.36267)
			(xy 368.873217 -275.332144) (xy 368.836494 -275.295421) (xy 368.805968 -275.253405) (xy 368.78239 -275.207131)
			(xy 368.766342 -275.157738) (xy 368.758217 -275.106443) (xy 368.478566 -275.106443) (xy 368.478561 -275.106697)
			(xy 368.470436 -275.157992) (xy 368.454388 -275.207385) (xy 368.43081 -275.253659) (xy 368.400284 -275.295675)
			(xy 368.363561 -275.332398) (xy 368.321545 -275.362924) (xy 368.275271 -275.386502) (xy 368.225878 -275.40255)
			(xy 368.174583 -275.410675) (xy 368.122649 -275.410675) (xy 368.071354 -275.40255) (xy 368.021961 -275.386502)
			(xy 367.975687 -275.362924) (xy 367.933671 -275.332398) (xy 367.896948 -275.295675) (xy 367.866422 -275.253659)
			(xy 367.842844 -275.207385) (xy 367.826796 -275.157992) (xy 367.818671 -275.106697) (xy 364.719107 -275.106697)
			(xy 364.710982 -275.157992) (xy 364.694934 -275.207385) (xy 364.671356 -275.253659) (xy 364.64083 -275.295675)
			(xy 364.604107 -275.332398) (xy 364.562091 -275.362924) (xy 364.515817 -275.386502) (xy 364.466424 -275.40255)
			(xy 364.415129 -275.410675) (xy 364.363195 -275.410675) (xy 364.3119 -275.40255) (xy 364.262507 -275.386502)
			(xy 364.216233 -275.362924) (xy 364.174217 -275.332398) (xy 364.137494 -275.295675) (xy 364.106968 -275.253659)
			(xy 364.08339 -275.207385) (xy 364.067342 -275.157992) (xy 364.059217 -275.106697) (xy 363.779053 -275.106697)
			(xy 363.770928 -275.157992) (xy 363.75488 -275.207385) (xy 363.731302 -275.253659) (xy 363.700776 -275.295675)
			(xy 363.664053 -275.332398) (xy 363.622037 -275.362924) (xy 363.575763 -275.386502) (xy 363.52637 -275.40255)
			(xy 363.475075 -275.410675) (xy 363.423141 -275.410675) (xy 363.371846 -275.40255) (xy 363.322453 -275.386502)
			(xy 363.276179 -275.362924) (xy 363.234163 -275.332398) (xy 363.19744 -275.295675) (xy 363.166914 -275.253659)
			(xy 363.143336 -275.207385) (xy 363.127288 -275.157992) (xy 363.119163 -275.106697) (xy 362.839253 -275.106697)
			(xy 362.831128 -275.157992) (xy 362.81508 -275.207385) (xy 362.791502 -275.253659) (xy 362.760976 -275.295675)
			(xy 362.724253 -275.332398) (xy 362.682237 -275.362924) (xy 362.635963 -275.386502) (xy 362.58657 -275.40255)
			(xy 362.535275 -275.410675) (xy 362.483341 -275.410675) (xy 362.432046 -275.40255) (xy 362.382653 -275.386502)
			(xy 362.336379 -275.362924) (xy 362.294363 -275.332398) (xy 362.25764 -275.295675) (xy 362.227114 -275.253659)
			(xy 362.203536 -275.207385) (xy 362.187488 -275.157992) (xy 362.179363 -275.106697) (xy 361.899953 -275.106697)
			(xy 361.891883 -275.157782) (xy 361.875922 -275.207053) (xy 361.852473 -275.253231) (xy 361.82211 -275.295188)
			(xy 361.804204 -275.313902) (xy 361.80395 -275.314156) (xy 361.789726 -275.349208) (xy 361.789726 -275.350224)
			(xy 361.78998 -275.420074) (xy 361.790498 -275.429823) (xy 361.797951 -275.447847) (xy 361.804458 -275.455126)
			(xy 361.910122 -275.56079) (xy 361.918027 -275.567996) (xy 361.938036 -275.575499) (xy 361.94873 -275.575268)
			(xy 361.957874 -275.574252) (xy 361.960922 -275.57349) (xy 361.980369 -275.569064) (xy 362.019973 -275.564352)
			(xy 362.039916 -275.564092) (xy 362.047536 -275.564092) (xy 362.072749 -275.56515) (xy 362.122434 -275.573963)
			(xy 362.170204 -275.59022) (xy 362.214952 -275.613544) (xy 362.255637 -275.643393) (xy 362.291318 -275.679075)
			(xy 362.321165 -275.719762) (xy 362.344486 -275.764511) (xy 362.360741 -275.812282) (xy 362.369552 -275.861968)
			(xy 362.370624 -275.88718) (xy 362.370624 -275.8948) (xy 362.370383 -275.914744) (xy 362.369666 -275.920767)
			(xy 363.589317 -275.920767) (xy 363.589317 -275.868833) (xy 363.597442 -275.817538) (xy 363.61349 -275.768145)
			(xy 363.637068 -275.721871) (xy 363.667594 -275.679855) (xy 363.704317 -275.643132) (xy 363.746333 -275.612606)
			(xy 363.792607 -275.589028) (xy 363.842 -275.57298) (xy 363.893295 -275.564855) (xy 363.945229 -275.564855)
			(xy 363.996524 -275.57298) (xy 364.045917 -275.589028) (xy 364.092191 -275.612606) (xy 364.134207 -275.643132)
			(xy 364.17093 -275.679855) (xy 364.201456 -275.721871) (xy 364.225034 -275.768145) (xy 364.241082 -275.817538)
			(xy 364.249207 -275.868833) (xy 364.249716 -275.8948) (xy 364.249212 -275.920513) (xy 364.529371 -275.920513)
			(xy 364.529371 -275.868579) (xy 364.537496 -275.817284) (xy 364.553544 -275.767891) (xy 364.577122 -275.721617)
			(xy 364.607648 -275.679601) (xy 364.644371 -275.642878) (xy 364.686387 -275.612352) (xy 364.732661 -275.588774)
			(xy 364.782054 -275.572726) (xy 364.833349 -275.564601) (xy 364.885283 -275.564601) (xy 364.936578 -275.572726)
			(xy 364.985971 -275.588774) (xy 365.032245 -275.612352) (xy 365.074261 -275.642878) (xy 365.110984 -275.679601)
			(xy 365.14151 -275.721617) (xy 365.165088 -275.767891) (xy 365.181136 -275.817284) (xy 365.189261 -275.868579)
			(xy 365.18977 -275.894546) (xy 365.189261 -275.920513) (xy 365.189221 -275.920767) (xy 365.468917 -275.920767)
			(xy 365.468917 -275.868833) (xy 365.477042 -275.817538) (xy 365.49309 -275.768145) (xy 365.516668 -275.721871)
			(xy 365.547194 -275.679855) (xy 365.583917 -275.643132) (xy 365.625933 -275.612606) (xy 365.672207 -275.589028)
			(xy 365.7216 -275.57298) (xy 365.772895 -275.564855) (xy 365.824829 -275.564855) (xy 365.876124 -275.57298)
			(xy 365.925517 -275.589028) (xy 365.971791 -275.612606) (xy 366.013807 -275.643132) (xy 366.05053 -275.679855)
			(xy 366.081056 -275.721871) (xy 366.104634 -275.768145) (xy 366.120682 -275.817538) (xy 366.128807 -275.868833)
			(xy 366.129316 -275.8948) (xy 366.128807 -275.920767) (xy 366.408971 -275.920767) (xy 366.408971 -275.868833)
			(xy 366.417096 -275.817538) (xy 366.433144 -275.768145) (xy 366.456722 -275.721871) (xy 366.487248 -275.679855)
			(xy 366.523971 -275.643132) (xy 366.565987 -275.612606) (xy 366.612261 -275.589028) (xy 366.661654 -275.57298)
			(xy 366.712949 -275.564855) (xy 366.764883 -275.564855) (xy 366.816178 -275.57298) (xy 366.865571 -275.589028)
			(xy 366.911845 -275.612606) (xy 366.953861 -275.643132) (xy 366.990584 -275.679855) (xy 367.02111 -275.721871)
			(xy 367.044688 -275.768145) (xy 367.060736 -275.817538) (xy 367.068861 -275.868833) (xy 367.06937 -275.8948)
			(xy 367.068866 -275.920513) (xy 367.348771 -275.920513) (xy 367.348771 -275.868579) (xy 367.356896 -275.817284)
			(xy 367.372944 -275.767891) (xy 367.396522 -275.721617) (xy 367.427048 -275.679601) (xy 367.463771 -275.642878)
			(xy 367.505787 -275.612352) (xy 367.552061 -275.588774) (xy 367.601454 -275.572726) (xy 367.652749 -275.564601)
			(xy 367.704683 -275.564601) (xy 367.755978 -275.572726) (xy 367.805371 -275.588774) (xy 367.851645 -275.612352)
			(xy 367.893661 -275.642878) (xy 367.930384 -275.679601) (xy 367.96091 -275.721617) (xy 367.984488 -275.767891)
			(xy 368.000536 -275.817284) (xy 368.008661 -275.868579) (xy 368.00917 -275.894546) (xy 368.008661 -275.920513)
			(xy 368.288571 -275.920513) (xy 368.288571 -275.868579) (xy 368.296696 -275.817284) (xy 368.312744 -275.767891)
			(xy 368.336322 -275.721617) (xy 368.366848 -275.679601) (xy 368.403571 -275.642878) (xy 368.445587 -275.612352)
			(xy 368.491861 -275.588774) (xy 368.541254 -275.572726) (xy 368.592549 -275.564601) (xy 368.644483 -275.564601)
			(xy 368.695778 -275.572726) (xy 368.745171 -275.588774) (xy 368.791445 -275.612352) (xy 368.833461 -275.642878)
			(xy 368.870184 -275.679601) (xy 368.90071 -275.721617) (xy 368.924288 -275.767891) (xy 368.940336 -275.817284)
			(xy 368.948461 -275.868579) (xy 368.94897 -275.894546) (xy 368.948461 -275.920513) (xy 369.228371 -275.920513)
			(xy 369.228371 -275.868579) (xy 369.236496 -275.817284) (xy 369.252544 -275.767891) (xy 369.276122 -275.721617)
			(xy 369.306648 -275.679601) (xy 369.343371 -275.642878) (xy 369.385387 -275.612352) (xy 369.431661 -275.588774)
			(xy 369.481054 -275.572726) (xy 369.532349 -275.564601) (xy 369.584283 -275.564601) (xy 369.635578 -275.572726)
			(xy 369.684971 -275.588774) (xy 369.731245 -275.612352) (xy 369.773261 -275.642878) (xy 369.809984 -275.679601)
			(xy 369.84051 -275.721617) (xy 369.864088 -275.767891) (xy 369.880136 -275.817284) (xy 369.888261 -275.868579)
			(xy 369.88877 -275.894546) (xy 369.888261 -275.920513) (xy 369.888221 -275.920767) (xy 370.168171 -275.920767)
			(xy 370.168171 -275.868833) (xy 370.176296 -275.817538) (xy 370.192344 -275.768145) (xy 370.215922 -275.721871)
			(xy 370.246448 -275.679855) (xy 370.283171 -275.643132) (xy 370.325187 -275.612606) (xy 370.371461 -275.589028)
			(xy 370.420854 -275.57298) (xy 370.472149 -275.564855) (xy 370.524083 -275.564855) (xy 370.575378 -275.57298)
			(xy 370.624771 -275.589028) (xy 370.671045 -275.612606) (xy 370.713061 -275.643132) (xy 370.749784 -275.679855)
			(xy 370.78031 -275.721871) (xy 370.803888 -275.768145) (xy 370.819936 -275.817538) (xy 370.828061 -275.868833)
			(xy 370.82857 -275.8948) (xy 370.828061 -275.920767) (xy 371.107717 -275.920767) (xy 371.107717 -275.868833)
			(xy 371.115842 -275.817538) (xy 371.13189 -275.768145) (xy 371.155468 -275.721871) (xy 371.185994 -275.679855)
			(xy 371.222717 -275.643132) (xy 371.264733 -275.612606) (xy 371.311007 -275.589028) (xy 371.3604 -275.57298)
			(xy 371.411695 -275.564855) (xy 371.463629 -275.564855) (xy 371.514924 -275.57298) (xy 371.564317 -275.589028)
			(xy 371.610591 -275.612606) (xy 371.652607 -275.643132) (xy 371.68933 -275.679855) (xy 371.719856 -275.721871)
			(xy 371.743434 -275.768145) (xy 371.759482 -275.817538) (xy 371.767607 -275.868833) (xy 371.768116 -275.8948)
			(xy 371.767607 -275.920767) (xy 372.047517 -275.920767) (xy 372.047517 -275.868833) (xy 372.055642 -275.817538)
			(xy 372.07169 -275.768145) (xy 372.095268 -275.721871) (xy 372.125794 -275.679855) (xy 372.162517 -275.643132)
			(xy 372.204533 -275.612606) (xy 372.250807 -275.589028) (xy 372.3002 -275.57298) (xy 372.351495 -275.564855)
			(xy 372.403429 -275.564855) (xy 372.454724 -275.57298) (xy 372.504117 -275.589028) (xy 372.550391 -275.612606)
			(xy 372.592407 -275.643132) (xy 372.62913 -275.679855) (xy 372.659656 -275.721871) (xy 372.683234 -275.768145)
			(xy 372.699282 -275.817538) (xy 372.707407 -275.868833) (xy 372.707916 -275.8948) (xy 372.707407 -275.920767)
			(xy 372.987317 -275.920767) (xy 372.987317 -275.868833) (xy 372.995442 -275.817538) (xy 373.01149 -275.768145)
			(xy 373.035068 -275.721871) (xy 373.065594 -275.679855) (xy 373.102317 -275.643132) (xy 373.144333 -275.612606)
			(xy 373.190607 -275.589028) (xy 373.24 -275.57298) (xy 373.291295 -275.564855) (xy 373.343229 -275.564855)
			(xy 373.394524 -275.57298) (xy 373.443917 -275.589028) (xy 373.490191 -275.612606) (xy 373.532207 -275.643132)
			(xy 373.56893 -275.679855) (xy 373.599456 -275.721871) (xy 373.623034 -275.768145) (xy 373.639082 -275.817538)
			(xy 373.647207 -275.868833) (xy 373.647716 -275.8948) (xy 373.647207 -275.920767) (xy 373.927117 -275.920767)
			(xy 373.927117 -275.868833) (xy 373.935242 -275.817538) (xy 373.95129 -275.768145) (xy 373.974868 -275.721871)
			(xy 374.005394 -275.679855) (xy 374.042117 -275.643132) (xy 374.084133 -275.612606) (xy 374.130407 -275.589028)
			(xy 374.1798 -275.57298) (xy 374.231095 -275.564855) (xy 374.283029 -275.564855) (xy 374.334324 -275.57298)
			(xy 374.383717 -275.589028) (xy 374.429991 -275.612606) (xy 374.472007 -275.643132) (xy 374.50873 -275.679855)
			(xy 374.539256 -275.721871) (xy 374.562834 -275.768145) (xy 374.578882 -275.817538) (xy 374.587007 -275.868833)
			(xy 374.587516 -275.8948) (xy 374.587007 -275.920767) (xy 374.866917 -275.920767) (xy 374.866917 -275.868833)
			(xy 374.875042 -275.817538) (xy 374.89109 -275.768145) (xy 374.914668 -275.721871) (xy 374.945194 -275.679855)
			(xy 374.981917 -275.643132) (xy 375.023933 -275.612606) (xy 375.070207 -275.589028) (xy 375.1196 -275.57298)
			(xy 375.170895 -275.564855) (xy 375.222829 -275.564855) (xy 375.274124 -275.57298) (xy 375.323517 -275.589028)
			(xy 375.369791 -275.612606) (xy 375.411807 -275.643132) (xy 375.44853 -275.679855) (xy 375.479056 -275.721871)
			(xy 375.502634 -275.768145) (xy 375.518682 -275.817538) (xy 375.526807 -275.868833) (xy 375.527316 -275.8948)
			(xy 375.526807 -275.920767) (xy 375.806717 -275.920767) (xy 375.806717 -275.868833) (xy 375.814842 -275.817538)
			(xy 375.83089 -275.768145) (xy 375.854468 -275.721871) (xy 375.884994 -275.679855) (xy 375.921717 -275.643132)
			(xy 375.963733 -275.612606) (xy 376.010007 -275.589028) (xy 376.0594 -275.57298) (xy 376.110695 -275.564855)
			(xy 376.162629 -275.564855) (xy 376.213924 -275.57298) (xy 376.263317 -275.589028) (xy 376.309591 -275.612606)
			(xy 376.351607 -275.643132) (xy 376.38833 -275.679855) (xy 376.418856 -275.721871) (xy 376.442434 -275.768145)
			(xy 376.458482 -275.817538) (xy 376.466607 -275.868833) (xy 376.467116 -275.8948) (xy 376.466607 -275.920767)
			(xy 376.746771 -275.920767) (xy 376.746771 -275.868833) (xy 376.754896 -275.817538) (xy 376.770944 -275.768145)
			(xy 376.794522 -275.721871) (xy 376.825048 -275.679855) (xy 376.861771 -275.643132) (xy 376.903787 -275.612606)
			(xy 376.950061 -275.589028) (xy 376.999454 -275.57298) (xy 377.050749 -275.564855) (xy 377.102683 -275.564855)
			(xy 377.153978 -275.57298) (xy 377.203371 -275.589028) (xy 377.249645 -275.612606) (xy 377.291661 -275.643132)
			(xy 377.328384 -275.679855) (xy 377.35891 -275.721871) (xy 377.382488 -275.768145) (xy 377.398536 -275.817538)
			(xy 377.406661 -275.868833) (xy 377.40717 -275.8948) (xy 377.406661 -275.920767) (xy 377.686317 -275.920767)
			(xy 377.686317 -275.868833) (xy 377.694442 -275.817538) (xy 377.71049 -275.768145) (xy 377.734068 -275.721871)
			(xy 377.764594 -275.679855) (xy 377.801317 -275.643132) (xy 377.843333 -275.612606) (xy 377.889607 -275.589028)
			(xy 377.939 -275.57298) (xy 377.990295 -275.564855) (xy 378.042229 -275.564855) (xy 378.093524 -275.57298)
			(xy 378.142917 -275.589028) (xy 378.189191 -275.612606) (xy 378.231207 -275.643132) (xy 378.26793 -275.679855)
			(xy 378.298456 -275.721871) (xy 378.322034 -275.768145) (xy 378.338082 -275.817538) (xy 378.346207 -275.868833)
			(xy 378.346716 -275.8948) (xy 378.346207 -275.920767) (xy 378.626117 -275.920767) (xy 378.626117 -275.868833)
			(xy 378.634242 -275.817538) (xy 378.65029 -275.768145) (xy 378.673868 -275.721871) (xy 378.704394 -275.679855)
			(xy 378.741117 -275.643132) (xy 378.783133 -275.612606) (xy 378.829407 -275.589028) (xy 378.8788 -275.57298)
			(xy 378.930095 -275.564855) (xy 378.982029 -275.564855) (xy 379.033324 -275.57298) (xy 379.082717 -275.589028)
			(xy 379.128991 -275.612606) (xy 379.171007 -275.643132) (xy 379.20773 -275.679855) (xy 379.238256 -275.721871)
			(xy 379.261834 -275.768145) (xy 379.277882 -275.817538) (xy 379.286007 -275.868833) (xy 379.286516 -275.8948)
			(xy 379.286007 -275.920767) (xy 379.277882 -275.972062) (xy 379.261834 -276.021455) (xy 379.238256 -276.067729)
			(xy 379.20773 -276.109745) (xy 379.171007 -276.146468) (xy 379.128991 -276.176994) (xy 379.082717 -276.200572)
			(xy 379.033324 -276.21662) (xy 378.982029 -276.224745) (xy 378.930095 -276.224745) (xy 378.8788 -276.21662)
			(xy 378.829407 -276.200572) (xy 378.783133 -276.176994) (xy 378.741117 -276.146468) (xy 378.704394 -276.109745)
			(xy 378.673868 -276.067729) (xy 378.65029 -276.021455) (xy 378.634242 -275.972062) (xy 378.626117 -275.920767)
			(xy 378.346207 -275.920767) (xy 378.338082 -275.972062) (xy 378.322034 -276.021455) (xy 378.298456 -276.067729)
			(xy 378.26793 -276.109745) (xy 378.231207 -276.146468) (xy 378.189191 -276.176994) (xy 378.142917 -276.200572)
			(xy 378.093524 -276.21662) (xy 378.042229 -276.224745) (xy 377.990295 -276.224745) (xy 377.939 -276.21662)
			(xy 377.889607 -276.200572) (xy 377.843333 -276.176994) (xy 377.801317 -276.146468) (xy 377.764594 -276.109745)
			(xy 377.734068 -276.067729) (xy 377.71049 -276.021455) (xy 377.694442 -275.972062) (xy 377.686317 -275.920767)
			(xy 377.406661 -275.920767) (xy 377.398536 -275.972062) (xy 377.382488 -276.021455) (xy 377.35891 -276.067729)
			(xy 377.328384 -276.109745) (xy 377.291661 -276.146468) (xy 377.249645 -276.176994) (xy 377.203371 -276.200572)
			(xy 377.153978 -276.21662) (xy 377.102683 -276.224745) (xy 377.050749 -276.224745) (xy 376.999454 -276.21662)
			(xy 376.950061 -276.200572) (xy 376.903787 -276.176994) (xy 376.861771 -276.146468) (xy 376.825048 -276.109745)
			(xy 376.794522 -276.067729) (xy 376.770944 -276.021455) (xy 376.754896 -275.972062) (xy 376.746771 -275.920767)
			(xy 376.466607 -275.920767) (xy 376.458482 -275.972062) (xy 376.442434 -276.021455) (xy 376.418856 -276.067729)
			(xy 376.38833 -276.109745) (xy 376.351607 -276.146468) (xy 376.309591 -276.176994) (xy 376.263317 -276.200572)
			(xy 376.213924 -276.21662) (xy 376.162629 -276.224745) (xy 376.110695 -276.224745) (xy 376.0594 -276.21662)
			(xy 376.010007 -276.200572) (xy 375.963733 -276.176994) (xy 375.921717 -276.146468) (xy 375.884994 -276.109745)
			(xy 375.854468 -276.067729) (xy 375.83089 -276.021455) (xy 375.814842 -275.972062) (xy 375.806717 -275.920767)
			(xy 375.526807 -275.920767) (xy 375.518682 -275.972062) (xy 375.502634 -276.021455) (xy 375.479056 -276.067729)
			(xy 375.44853 -276.109745) (xy 375.411807 -276.146468) (xy 375.369791 -276.176994) (xy 375.323517 -276.200572)
			(xy 375.274124 -276.21662) (xy 375.222829 -276.224745) (xy 375.170895 -276.224745) (xy 375.1196 -276.21662)
			(xy 375.070207 -276.200572) (xy 375.023933 -276.176994) (xy 374.981917 -276.146468) (xy 374.945194 -276.109745)
			(xy 374.914668 -276.067729) (xy 374.89109 -276.021455) (xy 374.875042 -275.972062) (xy 374.866917 -275.920767)
			(xy 374.587007 -275.920767) (xy 374.578882 -275.972062) (xy 374.562834 -276.021455) (xy 374.539256 -276.067729)
			(xy 374.50873 -276.109745) (xy 374.472007 -276.146468) (xy 374.429991 -276.176994) (xy 374.383717 -276.200572)
			(xy 374.334324 -276.21662) (xy 374.283029 -276.224745) (xy 374.231095 -276.224745) (xy 374.1798 -276.21662)
			(xy 374.130407 -276.200572) (xy 374.084133 -276.176994) (xy 374.042117 -276.146468) (xy 374.005394 -276.109745)
			(xy 373.974868 -276.067729) (xy 373.95129 -276.021455) (xy 373.935242 -275.972062) (xy 373.927117 -275.920767)
			(xy 373.647207 -275.920767) (xy 373.639082 -275.972062) (xy 373.623034 -276.021455) (xy 373.599456 -276.067729)
			(xy 373.56893 -276.109745) (xy 373.532207 -276.146468) (xy 373.490191 -276.176994) (xy 373.443917 -276.200572)
			(xy 373.394524 -276.21662) (xy 373.343229 -276.224745) (xy 373.291295 -276.224745) (xy 373.24 -276.21662)
			(xy 373.190607 -276.200572) (xy 373.144333 -276.176994) (xy 373.102317 -276.146468) (xy 373.065594 -276.109745)
			(xy 373.035068 -276.067729) (xy 373.01149 -276.021455) (xy 372.995442 -275.972062) (xy 372.987317 -275.920767)
			(xy 372.707407 -275.920767) (xy 372.699282 -275.972062) (xy 372.683234 -276.021455) (xy 372.659656 -276.067729)
			(xy 372.62913 -276.109745) (xy 372.592407 -276.146468) (xy 372.550391 -276.176994) (xy 372.504117 -276.200572)
			(xy 372.454724 -276.21662) (xy 372.403429 -276.224745) (xy 372.351495 -276.224745) (xy 372.3002 -276.21662)
			(xy 372.250807 -276.200572) (xy 372.204533 -276.176994) (xy 372.162517 -276.146468) (xy 372.125794 -276.109745)
			(xy 372.095268 -276.067729) (xy 372.07169 -276.021455) (xy 372.055642 -275.972062) (xy 372.047517 -275.920767)
			(xy 371.767607 -275.920767) (xy 371.759482 -275.972062) (xy 371.743434 -276.021455) (xy 371.719856 -276.067729)
			(xy 371.68933 -276.109745) (xy 371.652607 -276.146468) (xy 371.610591 -276.176994) (xy 371.564317 -276.200572)
			(xy 371.514924 -276.21662) (xy 371.463629 -276.224745) (xy 371.411695 -276.224745) (xy 371.3604 -276.21662)
			(xy 371.311007 -276.200572) (xy 371.264733 -276.176994) (xy 371.222717 -276.146468) (xy 371.185994 -276.109745)
			(xy 371.155468 -276.067729) (xy 371.13189 -276.021455) (xy 371.115842 -275.972062) (xy 371.107717 -275.920767)
			(xy 370.828061 -275.920767) (xy 370.819936 -275.972062) (xy 370.803888 -276.021455) (xy 370.78031 -276.067729)
			(xy 370.749784 -276.109745) (xy 370.713061 -276.146468) (xy 370.671045 -276.176994) (xy 370.624771 -276.200572)
			(xy 370.575378 -276.21662) (xy 370.524083 -276.224745) (xy 370.472149 -276.224745) (xy 370.420854 -276.21662)
			(xy 370.371461 -276.200572) (xy 370.325187 -276.176994) (xy 370.283171 -276.146468) (xy 370.246448 -276.109745)
			(xy 370.215922 -276.067729) (xy 370.192344 -276.021455) (xy 370.176296 -275.972062) (xy 370.168171 -275.920767)
			(xy 369.888221 -275.920767) (xy 369.880136 -275.971808) (xy 369.864088 -276.021201) (xy 369.84051 -276.067475)
			(xy 369.809984 -276.109491) (xy 369.773261 -276.146214) (xy 369.731245 -276.17674) (xy 369.684971 -276.200318)
			(xy 369.635578 -276.216366) (xy 369.584283 -276.224491) (xy 369.532349 -276.224491) (xy 369.481054 -276.216366)
			(xy 369.431661 -276.200318) (xy 369.385387 -276.17674) (xy 369.343371 -276.146214) (xy 369.306648 -276.109491)
			(xy 369.276122 -276.067475) (xy 369.252544 -276.021201) (xy 369.236496 -275.971808) (xy 369.228371 -275.920513)
			(xy 368.948461 -275.920513) (xy 368.940336 -275.971808) (xy 368.924288 -276.021201) (xy 368.90071 -276.067475)
			(xy 368.870184 -276.109491) (xy 368.833461 -276.146214) (xy 368.791445 -276.17674) (xy 368.745171 -276.200318)
			(xy 368.695778 -276.216366) (xy 368.644483 -276.224491) (xy 368.592549 -276.224491) (xy 368.541254 -276.216366)
			(xy 368.491861 -276.200318) (xy 368.445587 -276.17674) (xy 368.403571 -276.146214) (xy 368.366848 -276.109491)
			(xy 368.336322 -276.067475) (xy 368.312744 -276.021201) (xy 368.296696 -275.971808) (xy 368.288571 -275.920513)
			(xy 368.008661 -275.920513) (xy 368.000536 -275.971808) (xy 367.984488 -276.021201) (xy 367.96091 -276.067475)
			(xy 367.930384 -276.109491) (xy 367.893661 -276.146214) (xy 367.851645 -276.17674) (xy 367.805371 -276.200318)
			(xy 367.755978 -276.216366) (xy 367.704683 -276.224491) (xy 367.652749 -276.224491) (xy 367.601454 -276.216366)
			(xy 367.552061 -276.200318) (xy 367.505787 -276.17674) (xy 367.463771 -276.146214) (xy 367.427048 -276.109491)
			(xy 367.396522 -276.067475) (xy 367.372944 -276.021201) (xy 367.356896 -275.971808) (xy 367.348771 -275.920513)
			(xy 367.068866 -275.920513) (xy 367.068861 -275.920767) (xy 367.060736 -275.972062) (xy 367.044688 -276.021455)
			(xy 367.02111 -276.067729) (xy 366.990584 -276.109745) (xy 366.953861 -276.146468) (xy 366.911845 -276.176994)
			(xy 366.865571 -276.200572) (xy 366.816178 -276.21662) (xy 366.764883 -276.224745) (xy 366.712949 -276.224745)
			(xy 366.661654 -276.21662) (xy 366.612261 -276.200572) (xy 366.565987 -276.176994) (xy 366.523971 -276.146468)
			(xy 366.487248 -276.109745) (xy 366.456722 -276.067729) (xy 366.433144 -276.021455) (xy 366.417096 -275.972062)
			(xy 366.408971 -275.920767) (xy 366.128807 -275.920767) (xy 366.120682 -275.972062) (xy 366.104634 -276.021455)
			(xy 366.081056 -276.067729) (xy 366.05053 -276.109745) (xy 366.013807 -276.146468) (xy 365.971791 -276.176994)
			(xy 365.925517 -276.200572) (xy 365.876124 -276.21662) (xy 365.824829 -276.224745) (xy 365.772895 -276.224745)
			(xy 365.7216 -276.21662) (xy 365.672207 -276.200572) (xy 365.625933 -276.176994) (xy 365.583917 -276.146468)
			(xy 365.547194 -276.109745) (xy 365.516668 -276.067729) (xy 365.49309 -276.021455) (xy 365.477042 -275.972062)
			(xy 365.468917 -275.920767) (xy 365.189221 -275.920767) (xy 365.181136 -275.971808) (xy 365.165088 -276.021201)
			(xy 365.14151 -276.067475) (xy 365.110984 -276.109491) (xy 365.074261 -276.146214) (xy 365.032245 -276.17674)
			(xy 364.985971 -276.200318) (xy 364.936578 -276.216366) (xy 364.885283 -276.224491) (xy 364.833349 -276.224491)
			(xy 364.782054 -276.216366) (xy 364.732661 -276.200318) (xy 364.686387 -276.17674) (xy 364.644371 -276.146214)
			(xy 364.607648 -276.109491) (xy 364.577122 -276.067475) (xy 364.553544 -276.021201) (xy 364.537496 -275.971808)
			(xy 364.529371 -275.920513) (xy 364.249212 -275.920513) (xy 364.249207 -275.920767) (xy 364.241082 -275.972062)
			(xy 364.225034 -276.021455) (xy 364.201456 -276.067729) (xy 364.17093 -276.109745) (xy 364.134207 -276.146468)
			(xy 364.092191 -276.176994) (xy 364.045917 -276.200572) (xy 363.996524 -276.21662) (xy 363.945229 -276.224745)
			(xy 363.893295 -276.224745) (xy 363.842 -276.21662) (xy 363.792607 -276.200572) (xy 363.746333 -276.176994)
			(xy 363.704317 -276.146468) (xy 363.667594 -276.109745) (xy 363.637068 -276.067729) (xy 363.61349 -276.021455)
			(xy 363.597442 -275.972062) (xy 363.589317 -275.920767) (xy 362.369666 -275.920767) (xy 362.365669 -275.95435)
			(xy 362.361226 -275.973794) (xy 362.360464 -275.976842) (xy 362.359448 -275.985986) (xy 362.359234 -275.996678)
			(xy 362.366727 -276.016687) (xy 362.373926 -276.024594) (xy 362.956094 -276.606762) (xy 362.96532 -276.615054)
			(xy 362.989029 -276.622246) (xy 363.001306 -276.620478) (xy 363.083348 -276.604222) (xy 363.11967 -276.57425)
			(xy 363.122718 -276.567646) (xy 363.13339 -276.544033) (xy 363.160565 -276.499913) (xy 363.193852 -276.460201)
			(xy 363.232548 -276.425739) (xy 363.275834 -276.397255) (xy 363.322794 -276.375352) (xy 363.372436 -276.360493)
			(xy 363.423707 -276.352992) (xy 363.449616 -276.352508) (xy 363.477598 -276.353058) (xy 363.532872 -276.361815)
			(xy 363.586096 -276.379111) (xy 363.635959 -276.404521) (xy 363.681233 -276.437417) (xy 363.720803 -276.476991)
			(xy 363.753696 -276.522268) (xy 363.779101 -276.572134) (xy 363.796392 -276.625359) (xy 363.805144 -276.680634)
			(xy 363.805724 -276.708616) (xy 363.80526 -276.734329) (xy 364.059217 -276.734329) (xy 364.059217 -276.682395)
			(xy 364.067342 -276.6311) (xy 364.08339 -276.581707) (xy 364.106968 -276.535433) (xy 364.137494 -276.493417)
			(xy 364.174217 -276.456694) (xy 364.216233 -276.426168) (xy 364.262507 -276.40259) (xy 364.3119 -276.386542)
			(xy 364.363195 -276.378417) (xy 364.415129 -276.378417) (xy 364.466424 -276.386542) (xy 364.515817 -276.40259)
			(xy 364.562091 -276.426168) (xy 364.604107 -276.456694) (xy 364.64083 -276.493417) (xy 364.671356 -276.535433)
			(xy 364.694934 -276.581707) (xy 364.710982 -276.6311) (xy 364.719107 -276.682395) (xy 364.719616 -276.708362)
			(xy 364.719107 -276.734329) (xy 364.999017 -276.734329) (xy 364.999017 -276.682395) (xy 365.007142 -276.6311)
			(xy 365.02319 -276.581707) (xy 365.046768 -276.535433) (xy 365.077294 -276.493417) (xy 365.114017 -276.456694)
			(xy 365.156033 -276.426168) (xy 365.202307 -276.40259) (xy 365.2517 -276.386542) (xy 365.302995 -276.378417)
			(xy 365.354929 -276.378417) (xy 365.406224 -276.386542) (xy 365.455617 -276.40259) (xy 365.501891 -276.426168)
			(xy 365.543907 -276.456694) (xy 365.58063 -276.493417) (xy 365.611156 -276.535433) (xy 365.634734 -276.581707)
			(xy 365.650782 -276.6311) (xy 365.658907 -276.682395) (xy 365.659416 -276.708362) (xy 365.658907 -276.734329)
			(xy 365.938817 -276.734329) (xy 365.938817 -276.682395) (xy 365.946942 -276.6311) (xy 365.96299 -276.581707)
			(xy 365.986568 -276.535433) (xy 366.017094 -276.493417) (xy 366.053817 -276.456694) (xy 366.095833 -276.426168)
			(xy 366.142107 -276.40259) (xy 366.1915 -276.386542) (xy 366.242795 -276.378417) (xy 366.294729 -276.378417)
			(xy 366.346024 -276.386542) (xy 366.395417 -276.40259) (xy 366.441691 -276.426168) (xy 366.483707 -276.456694)
			(xy 366.52043 -276.493417) (xy 366.550956 -276.535433) (xy 366.574534 -276.581707) (xy 366.590582 -276.6311)
			(xy 366.598707 -276.682395) (xy 366.599216 -276.708362) (xy 366.598707 -276.734329) (xy 366.598667 -276.734583)
			(xy 366.878617 -276.734583) (xy 366.878617 -276.682649) (xy 366.886742 -276.631354) (xy 366.90279 -276.581961)
			(xy 366.926368 -276.535687) (xy 366.956894 -276.493671) (xy 366.993617 -276.456948) (xy 367.035633 -276.426422)
			(xy 367.081907 -276.402844) (xy 367.1313 -276.386796) (xy 367.182595 -276.378671) (xy 367.234529 -276.378671)
			(xy 367.285824 -276.386796) (xy 367.335217 -276.402844) (xy 367.381491 -276.426422) (xy 367.423507 -276.456948)
			(xy 367.46023 -276.493671) (xy 367.490756 -276.535687) (xy 367.514334 -276.581961) (xy 367.530382 -276.631354)
			(xy 367.538507 -276.682649) (xy 367.539016 -276.708616) (xy 367.538512 -276.734329) (xy 367.818417 -276.734329)
			(xy 367.818417 -276.682395) (xy 367.826542 -276.6311) (xy 367.84259 -276.581707) (xy 367.866168 -276.535433)
			(xy 367.896694 -276.493417) (xy 367.933417 -276.456694) (xy 367.975433 -276.426168) (xy 368.021707 -276.40259)
			(xy 368.0711 -276.386542) (xy 368.122395 -276.378417) (xy 368.174329 -276.378417) (xy 368.225624 -276.386542)
			(xy 368.275017 -276.40259) (xy 368.321291 -276.426168) (xy 368.363307 -276.456694) (xy 368.40003 -276.493417)
			(xy 368.430556 -276.535433) (xy 368.454134 -276.581707) (xy 368.470182 -276.6311) (xy 368.478307 -276.682395)
			(xy 368.478816 -276.708362) (xy 368.478307 -276.734329) (xy 368.478267 -276.734583) (xy 368.758471 -276.734583)
			(xy 368.758471 -276.682649) (xy 368.766596 -276.631354) (xy 368.782644 -276.581961) (xy 368.806222 -276.535687)
			(xy 368.836748 -276.493671) (xy 368.873471 -276.456948) (xy 368.915487 -276.426422) (xy 368.961761 -276.402844)
			(xy 369.011154 -276.386796) (xy 369.062449 -276.378671) (xy 369.114383 -276.378671) (xy 369.165678 -276.386796)
			(xy 369.215071 -276.402844) (xy 369.261345 -276.426422) (xy 369.303361 -276.456948) (xy 369.340084 -276.493671)
			(xy 369.37061 -276.535687) (xy 369.394188 -276.581961) (xy 369.410236 -276.631354) (xy 369.418361 -276.682649)
			(xy 369.41887 -276.708616) (xy 369.418361 -276.734583) (xy 370.638071 -276.734583) (xy 370.638071 -276.682649)
			(xy 370.646196 -276.631354) (xy 370.662244 -276.581961) (xy 370.685822 -276.535687) (xy 370.716348 -276.493671)
			(xy 370.753071 -276.456948) (xy 370.795087 -276.426422) (xy 370.841361 -276.402844) (xy 370.890754 -276.386796)
			(xy 370.942049 -276.378671) (xy 370.993983 -276.378671) (xy 371.045278 -276.386796) (xy 371.094671 -276.402844)
			(xy 371.140945 -276.426422) (xy 371.182961 -276.456948) (xy 371.219684 -276.493671) (xy 371.25021 -276.535687)
			(xy 371.273788 -276.581961) (xy 371.289836 -276.631354) (xy 371.297961 -276.682649) (xy 371.29847 -276.708616)
			(xy 371.297961 -276.734583) (xy 371.577871 -276.734583) (xy 371.577871 -276.682649) (xy 371.585996 -276.631354)
			(xy 371.602044 -276.581961) (xy 371.625622 -276.535687) (xy 371.656148 -276.493671) (xy 371.692871 -276.456948)
			(xy 371.734887 -276.426422) (xy 371.781161 -276.402844) (xy 371.830554 -276.386796) (xy 371.881849 -276.378671)
			(xy 371.933783 -276.378671) (xy 371.985078 -276.386796) (xy 372.034471 -276.402844) (xy 372.080745 -276.426422)
			(xy 372.122761 -276.456948) (xy 372.159484 -276.493671) (xy 372.19001 -276.535687) (xy 372.213588 -276.581961)
			(xy 372.229636 -276.631354) (xy 372.237761 -276.682649) (xy 372.23827 -276.708616) (xy 372.237761 -276.734583)
			(xy 372.517671 -276.734583) (xy 372.517671 -276.682649) (xy 372.525796 -276.631354) (xy 372.541844 -276.581961)
			(xy 372.565422 -276.535687) (xy 372.595948 -276.493671) (xy 372.632671 -276.456948) (xy 372.674687 -276.426422)
			(xy 372.720961 -276.402844) (xy 372.770354 -276.386796) (xy 372.821649 -276.378671) (xy 372.873583 -276.378671)
			(xy 372.924878 -276.386796) (xy 372.974271 -276.402844) (xy 373.020545 -276.426422) (xy 373.062561 -276.456948)
			(xy 373.099284 -276.493671) (xy 373.12981 -276.535687) (xy 373.153388 -276.581961) (xy 373.169436 -276.631354)
			(xy 373.177561 -276.682649) (xy 373.17807 -276.708616) (xy 373.177561 -276.734583) (xy 373.457217 -276.734583)
			(xy 373.457217 -276.682649) (xy 373.465342 -276.631354) (xy 373.48139 -276.581961) (xy 373.504968 -276.535687)
			(xy 373.535494 -276.493671) (xy 373.572217 -276.456948) (xy 373.614233 -276.426422) (xy 373.660507 -276.402844)
			(xy 373.7099 -276.386796) (xy 373.761195 -276.378671) (xy 373.813129 -276.378671) (xy 373.864424 -276.386796)
			(xy 373.913817 -276.402844) (xy 373.960091 -276.426422) (xy 374.002107 -276.456948) (xy 374.03883 -276.493671)
			(xy 374.069356 -276.535687) (xy 374.092934 -276.581961) (xy 374.108982 -276.631354) (xy 374.117107 -276.682649)
			(xy 374.117616 -276.708616) (xy 374.117107 -276.734583) (xy 374.397271 -276.734583) (xy 374.397271 -276.682649)
			(xy 374.405396 -276.631354) (xy 374.421444 -276.581961) (xy 374.445022 -276.535687) (xy 374.475548 -276.493671)
			(xy 374.512271 -276.456948) (xy 374.554287 -276.426422) (xy 374.600561 -276.402844) (xy 374.649954 -276.386796)
			(xy 374.701249 -276.378671) (xy 374.753183 -276.378671) (xy 374.804478 -276.386796) (xy 374.853871 -276.402844)
			(xy 374.900145 -276.426422) (xy 374.942161 -276.456948) (xy 374.978884 -276.493671) (xy 375.00941 -276.535687)
			(xy 375.032988 -276.581961) (xy 375.049036 -276.631354) (xy 375.057161 -276.682649) (xy 375.05767 -276.708616)
			(xy 375.057161 -276.734583) (xy 375.337071 -276.734583) (xy 375.337071 -276.682649) (xy 375.345196 -276.631354)
			(xy 375.361244 -276.581961) (xy 375.384822 -276.535687) (xy 375.415348 -276.493671) (xy 375.452071 -276.456948)
			(xy 375.494087 -276.426422) (xy 375.540361 -276.402844) (xy 375.589754 -276.386796) (xy 375.641049 -276.378671)
			(xy 375.692983 -276.378671) (xy 375.744278 -276.386796) (xy 375.793671 -276.402844) (xy 375.839945 -276.426422)
			(xy 375.881961 -276.456948) (xy 375.918684 -276.493671) (xy 375.94921 -276.535687) (xy 375.972788 -276.581961)
			(xy 375.988836 -276.631354) (xy 375.996961 -276.682649) (xy 375.99747 -276.708616) (xy 375.996961 -276.734583)
			(xy 376.276871 -276.734583) (xy 376.276871 -276.682649) (xy 376.284996 -276.631354) (xy 376.301044 -276.581961)
			(xy 376.324622 -276.535687) (xy 376.355148 -276.493671) (xy 376.391871 -276.456948) (xy 376.433887 -276.426422)
			(xy 376.480161 -276.402844) (xy 376.529554 -276.386796) (xy 376.580849 -276.378671) (xy 376.632783 -276.378671)
			(xy 376.684078 -276.386796) (xy 376.733471 -276.402844) (xy 376.779745 -276.426422) (xy 376.821761 -276.456948)
			(xy 376.858484 -276.493671) (xy 376.88901 -276.535687) (xy 376.912588 -276.581961) (xy 376.928636 -276.631354)
			(xy 376.936761 -276.682649) (xy 376.93727 -276.708616) (xy 376.936761 -276.734583) (xy 377.216671 -276.734583)
			(xy 377.216671 -276.682649) (xy 377.224796 -276.631354) (xy 377.240844 -276.581961) (xy 377.264422 -276.535687)
			(xy 377.294948 -276.493671) (xy 377.331671 -276.456948) (xy 377.373687 -276.426422) (xy 377.419961 -276.402844)
			(xy 377.469354 -276.386796) (xy 377.520649 -276.378671) (xy 377.572583 -276.378671) (xy 377.623878 -276.386796)
			(xy 377.673271 -276.402844) (xy 377.719545 -276.426422) (xy 377.761561 -276.456948) (xy 377.798284 -276.493671)
			(xy 377.82881 -276.535687) (xy 377.852388 -276.581961) (xy 377.868436 -276.631354) (xy 377.876561 -276.682649)
			(xy 377.87707 -276.708616) (xy 377.876561 -276.734583) (xy 378.156471 -276.734583) (xy 378.156471 -276.682649)
			(xy 378.164596 -276.631354) (xy 378.180644 -276.581961) (xy 378.204222 -276.535687) (xy 378.234748 -276.493671)
			(xy 378.271471 -276.456948) (xy 378.313487 -276.426422) (xy 378.359761 -276.402844) (xy 378.409154 -276.386796)
			(xy 378.460449 -276.378671) (xy 378.512383 -276.378671) (xy 378.563678 -276.386796) (xy 378.613071 -276.402844)
			(xy 378.659345 -276.426422) (xy 378.701361 -276.456948) (xy 378.738084 -276.493671) (xy 378.76861 -276.535687)
			(xy 378.792188 -276.581961) (xy 378.808236 -276.631354) (xy 378.816361 -276.682649) (xy 378.81687 -276.708616)
			(xy 378.816361 -276.734583) (xy 378.808236 -276.785878) (xy 378.792188 -276.835271) (xy 378.76861 -276.881545)
			(xy 378.738084 -276.923561) (xy 378.701361 -276.960284) (xy 378.659345 -276.99081) (xy 378.613071 -277.014388)
			(xy 378.563678 -277.030436) (xy 378.512383 -277.038561) (xy 378.460449 -277.038561) (xy 378.409154 -277.030436)
			(xy 378.359761 -277.014388) (xy 378.313487 -276.99081) (xy 378.271471 -276.960284) (xy 378.234748 -276.923561)
			(xy 378.204222 -276.881545) (xy 378.180644 -276.835271) (xy 378.164596 -276.785878) (xy 378.156471 -276.734583)
			(xy 377.876561 -276.734583) (xy 377.868436 -276.785878) (xy 377.852388 -276.835271) (xy 377.82881 -276.881545)
			(xy 377.798284 -276.923561) (xy 377.761561 -276.960284) (xy 377.719545 -276.99081) (xy 377.673271 -277.014388)
			(xy 377.623878 -277.030436) (xy 377.572583 -277.038561) (xy 377.520649 -277.038561) (xy 377.469354 -277.030436)
			(xy 377.419961 -277.014388) (xy 377.373687 -276.99081) (xy 377.331671 -276.960284) (xy 377.294948 -276.923561)
			(xy 377.264422 -276.881545) (xy 377.240844 -276.835271) (xy 377.224796 -276.785878) (xy 377.216671 -276.734583)
			(xy 376.936761 -276.734583) (xy 376.928636 -276.785878) (xy 376.912588 -276.835271) (xy 376.88901 -276.881545)
			(xy 376.858484 -276.923561) (xy 376.821761 -276.960284) (xy 376.779745 -276.99081) (xy 376.733471 -277.014388)
			(xy 376.684078 -277.030436) (xy 376.632783 -277.038561) (xy 376.580849 -277.038561) (xy 376.529554 -277.030436)
			(xy 376.480161 -277.014388) (xy 376.433887 -276.99081) (xy 376.391871 -276.960284) (xy 376.355148 -276.923561)
			(xy 376.324622 -276.881545) (xy 376.301044 -276.835271) (xy 376.284996 -276.785878) (xy 376.276871 -276.734583)
			(xy 375.996961 -276.734583) (xy 375.988836 -276.785878) (xy 375.972788 -276.835271) (xy 375.94921 -276.881545)
			(xy 375.918684 -276.923561) (xy 375.881961 -276.960284) (xy 375.839945 -276.99081) (xy 375.793671 -277.014388)
			(xy 375.744278 -277.030436) (xy 375.692983 -277.038561) (xy 375.641049 -277.038561) (xy 375.589754 -277.030436)
			(xy 375.540361 -277.014388) (xy 375.494087 -276.99081) (xy 375.452071 -276.960284) (xy 375.415348 -276.923561)
			(xy 375.384822 -276.881545) (xy 375.361244 -276.835271) (xy 375.345196 -276.785878) (xy 375.337071 -276.734583)
			(xy 375.057161 -276.734583) (xy 375.049036 -276.785878) (xy 375.032988 -276.835271) (xy 375.00941 -276.881545)
			(xy 374.978884 -276.923561) (xy 374.942161 -276.960284) (xy 374.900145 -276.99081) (xy 374.853871 -277.014388)
			(xy 374.804478 -277.030436) (xy 374.753183 -277.038561) (xy 374.701249 -277.038561) (xy 374.649954 -277.030436)
			(xy 374.600561 -277.014388) (xy 374.554287 -276.99081) (xy 374.512271 -276.960284) (xy 374.475548 -276.923561)
			(xy 374.445022 -276.881545) (xy 374.421444 -276.835271) (xy 374.405396 -276.785878) (xy 374.397271 -276.734583)
			(xy 374.117107 -276.734583) (xy 374.108982 -276.785878) (xy 374.092934 -276.835271) (xy 374.069356 -276.881545)
			(xy 374.03883 -276.923561) (xy 374.002107 -276.960284) (xy 373.960091 -276.99081) (xy 373.913817 -277.014388)
			(xy 373.864424 -277.030436) (xy 373.813129 -277.038561) (xy 373.761195 -277.038561) (xy 373.7099 -277.030436)
			(xy 373.660507 -277.014388) (xy 373.614233 -276.99081) (xy 373.572217 -276.960284) (xy 373.535494 -276.923561)
			(xy 373.504968 -276.881545) (xy 373.48139 -276.835271) (xy 373.465342 -276.785878) (xy 373.457217 -276.734583)
			(xy 373.177561 -276.734583) (xy 373.169436 -276.785878) (xy 373.153388 -276.835271) (xy 373.12981 -276.881545)
			(xy 373.099284 -276.923561) (xy 373.062561 -276.960284) (xy 373.020545 -276.99081) (xy 372.974271 -277.014388)
			(xy 372.924878 -277.030436) (xy 372.873583 -277.038561) (xy 372.821649 -277.038561) (xy 372.770354 -277.030436)
			(xy 372.720961 -277.014388) (xy 372.674687 -276.99081) (xy 372.632671 -276.960284) (xy 372.595948 -276.923561)
			(xy 372.565422 -276.881545) (xy 372.541844 -276.835271) (xy 372.525796 -276.785878) (xy 372.517671 -276.734583)
			(xy 372.237761 -276.734583) (xy 372.229636 -276.785878) (xy 372.213588 -276.835271) (xy 372.19001 -276.881545)
			(xy 372.159484 -276.923561) (xy 372.122761 -276.960284) (xy 372.080745 -276.99081) (xy 372.034471 -277.014388)
			(xy 371.985078 -277.030436) (xy 371.933783 -277.038561) (xy 371.881849 -277.038561) (xy 371.830554 -277.030436)
			(xy 371.781161 -277.014388) (xy 371.734887 -276.99081) (xy 371.692871 -276.960284) (xy 371.656148 -276.923561)
			(xy 371.625622 -276.881545) (xy 371.602044 -276.835271) (xy 371.585996 -276.785878) (xy 371.577871 -276.734583)
			(xy 371.297961 -276.734583) (xy 371.289836 -276.785878) (xy 371.273788 -276.835271) (xy 371.25021 -276.881545)
			(xy 371.219684 -276.923561) (xy 371.182961 -276.960284) (xy 371.140945 -276.99081) (xy 371.094671 -277.014388)
			(xy 371.045278 -277.030436) (xy 370.993983 -277.038561) (xy 370.942049 -277.038561) (xy 370.890754 -277.030436)
			(xy 370.841361 -277.014388) (xy 370.795087 -276.99081) (xy 370.753071 -276.960284) (xy 370.716348 -276.923561)
			(xy 370.685822 -276.881545) (xy 370.662244 -276.835271) (xy 370.646196 -276.785878) (xy 370.638071 -276.734583)
			(xy 369.418361 -276.734583) (xy 369.410236 -276.785878) (xy 369.394188 -276.835271) (xy 369.37061 -276.881545)
			(xy 369.340084 -276.923561) (xy 369.303361 -276.960284) (xy 369.261345 -276.99081) (xy 369.215071 -277.014388)
			(xy 369.165678 -277.030436) (xy 369.114383 -277.038561) (xy 369.062449 -277.038561) (xy 369.011154 -277.030436)
			(xy 368.961761 -277.014388) (xy 368.915487 -276.99081) (xy 368.873471 -276.960284) (xy 368.836748 -276.923561)
			(xy 368.806222 -276.881545) (xy 368.782644 -276.835271) (xy 368.766596 -276.785878) (xy 368.758471 -276.734583)
			(xy 368.478267 -276.734583) (xy 368.470182 -276.785624) (xy 368.454134 -276.835017) (xy 368.430556 -276.881291)
			(xy 368.40003 -276.923307) (xy 368.363307 -276.96003) (xy 368.321291 -276.990556) (xy 368.275017 -277.014134)
			(xy 368.225624 -277.030182) (xy 368.174329 -277.038307) (xy 368.122395 -277.038307) (xy 368.0711 -277.030182)
			(xy 368.021707 -277.014134) (xy 367.975433 -276.990556) (xy 367.933417 -276.96003) (xy 367.896694 -276.923307)
			(xy 367.866168 -276.881291) (xy 367.84259 -276.835017) (xy 367.826542 -276.785624) (xy 367.818417 -276.734329)
			(xy 367.538512 -276.734329) (xy 367.538507 -276.734583) (xy 367.530382 -276.785878) (xy 367.514334 -276.835271)
			(xy 367.490756 -276.881545) (xy 367.46023 -276.923561) (xy 367.423507 -276.960284) (xy 367.381491 -276.99081)
			(xy 367.335217 -277.014388) (xy 367.285824 -277.030436) (xy 367.234529 -277.038561) (xy 367.182595 -277.038561)
			(xy 367.1313 -277.030436) (xy 367.081907 -277.014388) (xy 367.035633 -276.99081) (xy 366.993617 -276.960284)
			(xy 366.956894 -276.923561) (xy 366.926368 -276.881545) (xy 366.90279 -276.835271) (xy 366.886742 -276.785878)
			(xy 366.878617 -276.734583) (xy 366.598667 -276.734583) (xy 366.590582 -276.785624) (xy 366.574534 -276.835017)
			(xy 366.550956 -276.881291) (xy 366.52043 -276.923307) (xy 366.483707 -276.96003) (xy 366.441691 -276.990556)
			(xy 366.395417 -277.014134) (xy 366.346024 -277.030182) (xy 366.294729 -277.038307) (xy 366.242795 -277.038307)
			(xy 366.1915 -277.030182) (xy 366.142107 -277.014134) (xy 366.095833 -276.990556) (xy 366.053817 -276.96003)
			(xy 366.017094 -276.923307) (xy 365.986568 -276.881291) (xy 365.96299 -276.835017) (xy 365.946942 -276.785624)
			(xy 365.938817 -276.734329) (xy 365.658907 -276.734329) (xy 365.650782 -276.785624) (xy 365.634734 -276.835017)
			(xy 365.611156 -276.881291) (xy 365.58063 -276.923307) (xy 365.543907 -276.96003) (xy 365.501891 -276.990556)
			(xy 365.455617 -277.014134) (xy 365.406224 -277.030182) (xy 365.354929 -277.038307) (xy 365.302995 -277.038307)
			(xy 365.2517 -277.030182) (xy 365.202307 -277.014134) (xy 365.156033 -276.990556) (xy 365.114017 -276.96003)
			(xy 365.077294 -276.923307) (xy 365.046768 -276.881291) (xy 365.02319 -276.835017) (xy 365.007142 -276.785624)
			(xy 364.999017 -276.734329) (xy 364.719107 -276.734329) (xy 364.710982 -276.785624) (xy 364.694934 -276.835017)
			(xy 364.671356 -276.881291) (xy 364.64083 -276.923307) (xy 364.604107 -276.96003) (xy 364.562091 -276.990556)
			(xy 364.515817 -277.014134) (xy 364.466424 -277.030182) (xy 364.415129 -277.038307) (xy 364.363195 -277.038307)
			(xy 364.3119 -277.030182) (xy 364.262507 -277.014134) (xy 364.216233 -276.990556) (xy 364.174217 -276.96003)
			(xy 364.137494 -276.923307) (xy 364.106968 -276.881291) (xy 364.08339 -276.835017) (xy 364.067342 -276.785624)
			(xy 364.059217 -276.734329) (xy 363.80526 -276.734329) (xy 363.805256 -276.734525) (xy 363.797742 -276.785795)
			(xy 363.782874 -276.835435) (xy 363.760968 -276.882395) (xy 363.732485 -276.925683) (xy 363.698028 -276.964384)
			(xy 363.658324 -276.997682) (xy 363.614212 -277.024872) (xy 363.590586 -277.035514) (xy 363.583982 -277.038562)
			(xy 363.55401 -277.074884) (xy 363.5375 -277.156672) (xy 363.535676 -277.168924) (xy 363.542715 -277.192645)
			(xy 363.550962 -277.201884) (xy 363.60862 -277.259542) (xy 363.615256 -277.265619) (xy 363.631639 -277.273028)
			(xy 363.64958 -277.27422) (xy 363.666799 -277.269044) (xy 363.674152 -277.26386) (xy 363.677962 -277.260304)
			(xy 363.69777 -277.242746) (xy 363.741604 -277.213078) (xy 363.789347 -277.190226) (xy 363.839947 -277.174693)
			(xy 363.892289 -277.166822) (xy 363.918754 -277.166324) (xy 363.919262 -277.166324) (xy 363.947248 -277.166842)
			(xy 364.002533 -277.175593) (xy 364.055767 -277.192886) (xy 364.10564 -277.218295) (xy 364.150924 -277.251193)
			(xy 364.190503 -277.290771) (xy 364.223402 -277.336055) (xy 364.248812 -277.385927) (xy 364.266106 -277.439161)
			(xy 364.274858 -277.494446) (xy 364.27537 -277.522432) (xy 364.27537 -277.52294) (xy 364.274885 -277.548399)
			(xy 364.529117 -277.548399) (xy 364.529117 -277.496465) (xy 364.537242 -277.44517) (xy 364.55329 -277.395777)
			(xy 364.576868 -277.349503) (xy 364.607394 -277.307487) (xy 364.644117 -277.270764) (xy 364.686133 -277.240238)
			(xy 364.732407 -277.21666) (xy 364.7818 -277.200612) (xy 364.833095 -277.192487) (xy 364.885029 -277.192487)
			(xy 364.936324 -277.200612) (xy 364.985717 -277.21666) (xy 365.031991 -277.240238) (xy 365.074007 -277.270764)
			(xy 365.11073 -277.307487) (xy 365.141256 -277.349503) (xy 365.164834 -277.395777) (xy 365.180882 -277.44517)
			(xy 365.189007 -277.496465) (xy 365.189516 -277.522432) (xy 365.189012 -277.548145) (xy 365.469171 -277.548145)
			(xy 365.469171 -277.496211) (xy 365.477296 -277.444916) (xy 365.493344 -277.395523) (xy 365.516922 -277.349249)
			(xy 365.547448 -277.307233) (xy 365.584171 -277.27051) (xy 365.626187 -277.239984) (xy 365.672461 -277.216406)
			(xy 365.721854 -277.200358) (xy 365.773149 -277.192233) (xy 365.825083 -277.192233) (xy 365.876378 -277.200358)
			(xy 365.925771 -277.216406) (xy 365.972045 -277.239984) (xy 366.014061 -277.27051) (xy 366.050784 -277.307233)
			(xy 366.08131 -277.349249) (xy 366.104888 -277.395523) (xy 366.120936 -277.444916) (xy 366.129061 -277.496211)
			(xy 366.12957 -277.522178) (xy 366.129061 -277.548145) (xy 366.129021 -277.548399) (xy 366.408971 -277.548399)
			(xy 366.408971 -277.496465) (xy 366.417096 -277.44517) (xy 366.433144 -277.395777) (xy 366.456722 -277.349503)
			(xy 366.487248 -277.307487) (xy 366.523971 -277.270764) (xy 366.565987 -277.240238) (xy 366.612261 -277.21666)
			(xy 366.661654 -277.200612) (xy 366.712949 -277.192487) (xy 366.764883 -277.192487) (xy 366.816178 -277.200612)
			(xy 366.865571 -277.21666) (xy 366.911845 -277.240238) (xy 366.953861 -277.270764) (xy 366.990584 -277.307487)
			(xy 367.02111 -277.349503) (xy 367.044688 -277.395777) (xy 367.060736 -277.44517) (xy 367.068861 -277.496465)
			(xy 367.06937 -277.522432) (xy 367.068866 -277.548145) (xy 367.348771 -277.548145) (xy 367.348771 -277.496211)
			(xy 367.356896 -277.444916) (xy 367.372944 -277.395523) (xy 367.396522 -277.349249) (xy 367.427048 -277.307233)
			(xy 367.463771 -277.27051) (xy 367.505787 -277.239984) (xy 367.552061 -277.216406) (xy 367.601454 -277.200358)
			(xy 367.652749 -277.192233) (xy 367.704683 -277.192233) (xy 367.755978 -277.200358) (xy 367.805371 -277.216406)
			(xy 367.851645 -277.239984) (xy 367.893661 -277.27051) (xy 367.930384 -277.307233) (xy 367.96091 -277.349249)
			(xy 367.984488 -277.395523) (xy 368.000536 -277.444916) (xy 368.008661 -277.496211) (xy 368.00917 -277.522178)
			(xy 368.008661 -277.548145) (xy 368.288571 -277.548145) (xy 368.288571 -277.496211) (xy 368.296696 -277.444916)
			(xy 368.312744 -277.395523) (xy 368.336322 -277.349249) (xy 368.366848 -277.307233) (xy 368.403571 -277.27051)
			(xy 368.445587 -277.239984) (xy 368.491861 -277.216406) (xy 368.541254 -277.200358) (xy 368.592549 -277.192233)
			(xy 368.644483 -277.192233) (xy 368.695778 -277.200358) (xy 368.745171 -277.216406) (xy 368.791445 -277.239984)
			(xy 368.833461 -277.27051) (xy 368.870184 -277.307233) (xy 368.90071 -277.349249) (xy 368.924288 -277.395523)
			(xy 368.940336 -277.444916) (xy 368.948461 -277.496211) (xy 368.94897 -277.522178) (xy 368.948461 -277.548145)
			(xy 369.228371 -277.548145) (xy 369.228371 -277.496211) (xy 369.236496 -277.444916) (xy 369.252544 -277.395523)
			(xy 369.276122 -277.349249) (xy 369.306648 -277.307233) (xy 369.343371 -277.27051) (xy 369.385387 -277.239984)
			(xy 369.431661 -277.216406) (xy 369.481054 -277.200358) (xy 369.532349 -277.192233) (xy 369.584283 -277.192233)
			(xy 369.635578 -277.200358) (xy 369.684971 -277.216406) (xy 369.731245 -277.239984) (xy 369.773261 -277.27051)
			(xy 369.809984 -277.307233) (xy 369.84051 -277.349249) (xy 369.864088 -277.395523) (xy 369.880136 -277.444916)
			(xy 369.888261 -277.496211) (xy 369.88877 -277.522178) (xy 369.888261 -277.548145) (xy 370.168171 -277.548145)
			(xy 370.168171 -277.496211) (xy 370.176296 -277.444916) (xy 370.192344 -277.395523) (xy 370.215922 -277.349249)
			(xy 370.246448 -277.307233) (xy 370.283171 -277.27051) (xy 370.325187 -277.239984) (xy 370.371461 -277.216406)
			(xy 370.420854 -277.200358) (xy 370.472149 -277.192233) (xy 370.524083 -277.192233) (xy 370.575378 -277.200358)
			(xy 370.624771 -277.216406) (xy 370.671045 -277.239984) (xy 370.713061 -277.27051) (xy 370.749784 -277.307233)
			(xy 370.78031 -277.349249) (xy 370.803888 -277.395523) (xy 370.819936 -277.444916) (xy 370.828061 -277.496211)
			(xy 370.82857 -277.522178) (xy 370.828061 -277.548145) (xy 370.828021 -277.548399) (xy 371.107717 -277.548399)
			(xy 371.107717 -277.496465) (xy 371.115842 -277.44517) (xy 371.13189 -277.395777) (xy 371.155468 -277.349503)
			(xy 371.185994 -277.307487) (xy 371.222717 -277.270764) (xy 371.264733 -277.240238) (xy 371.311007 -277.21666)
			(xy 371.3604 -277.200612) (xy 371.411695 -277.192487) (xy 371.463629 -277.192487) (xy 371.514924 -277.200612)
			(xy 371.564317 -277.21666) (xy 371.610591 -277.240238) (xy 371.652607 -277.270764) (xy 371.68933 -277.307487)
			(xy 371.719856 -277.349503) (xy 371.743434 -277.395777) (xy 371.759482 -277.44517) (xy 371.767607 -277.496465)
			(xy 371.768116 -277.522432) (xy 371.767607 -277.548399) (xy 372.047517 -277.548399) (xy 372.047517 -277.496465)
			(xy 372.055642 -277.44517) (xy 372.07169 -277.395777) (xy 372.095268 -277.349503) (xy 372.125794 -277.307487)
			(xy 372.162517 -277.270764) (xy 372.204533 -277.240238) (xy 372.250807 -277.21666) (xy 372.3002 -277.200612)
			(xy 372.351495 -277.192487) (xy 372.403429 -277.192487) (xy 372.454724 -277.200612) (xy 372.504117 -277.21666)
			(xy 372.550391 -277.240238) (xy 372.592407 -277.270764) (xy 372.62913 -277.307487) (xy 372.659656 -277.349503)
			(xy 372.683234 -277.395777) (xy 372.699282 -277.44517) (xy 372.707407 -277.496465) (xy 372.707916 -277.522432)
			(xy 372.707407 -277.548399) (xy 372.987571 -277.548399) (xy 372.987571 -277.496465) (xy 372.995696 -277.44517)
			(xy 373.011744 -277.395777) (xy 373.035322 -277.349503) (xy 373.065848 -277.307487) (xy 373.102571 -277.270764)
			(xy 373.144587 -277.240238) (xy 373.190861 -277.21666) (xy 373.240254 -277.200612) (xy 373.291549 -277.192487)
			(xy 373.343483 -277.192487) (xy 373.394778 -277.200612) (xy 373.444171 -277.21666) (xy 373.490445 -277.240238)
			(xy 373.532461 -277.270764) (xy 373.569184 -277.307487) (xy 373.59971 -277.349503) (xy 373.623288 -277.395777)
			(xy 373.639336 -277.44517) (xy 373.647461 -277.496465) (xy 373.64797 -277.522432) (xy 373.647461 -277.548399)
			(xy 373.927117 -277.548399) (xy 373.927117 -277.496465) (xy 373.935242 -277.44517) (xy 373.95129 -277.395777)
			(xy 373.974868 -277.349503) (xy 374.005394 -277.307487) (xy 374.042117 -277.270764) (xy 374.084133 -277.240238)
			(xy 374.130407 -277.21666) (xy 374.1798 -277.200612) (xy 374.231095 -277.192487) (xy 374.283029 -277.192487)
			(xy 374.334324 -277.200612) (xy 374.383717 -277.21666) (xy 374.429991 -277.240238) (xy 374.472007 -277.270764)
			(xy 374.50873 -277.307487) (xy 374.539256 -277.349503) (xy 374.562834 -277.395777) (xy 374.578882 -277.44517)
			(xy 374.587007 -277.496465) (xy 374.587516 -277.522432) (xy 374.587007 -277.548399) (xy 374.866917 -277.548399)
			(xy 374.866917 -277.496465) (xy 374.875042 -277.44517) (xy 374.89109 -277.395777) (xy 374.914668 -277.349503)
			(xy 374.945194 -277.307487) (xy 374.981917 -277.270764) (xy 375.023933 -277.240238) (xy 375.070207 -277.21666)
			(xy 375.1196 -277.200612) (xy 375.170895 -277.192487) (xy 375.222829 -277.192487) (xy 375.274124 -277.200612)
			(xy 375.323517 -277.21666) (xy 375.369791 -277.240238) (xy 375.411807 -277.270764) (xy 375.44853 -277.307487)
			(xy 375.479056 -277.349503) (xy 375.502634 -277.395777) (xy 375.518682 -277.44517) (xy 375.526807 -277.496465)
			(xy 375.527316 -277.522432) (xy 375.526807 -277.548399) (xy 375.806717 -277.548399) (xy 375.806717 -277.496465)
			(xy 375.814842 -277.44517) (xy 375.83089 -277.395777) (xy 375.854468 -277.349503) (xy 375.884994 -277.307487)
			(xy 375.921717 -277.270764) (xy 375.963733 -277.240238) (xy 376.010007 -277.21666) (xy 376.0594 -277.200612)
			(xy 376.110695 -277.192487) (xy 376.162629 -277.192487) (xy 376.213924 -277.200612) (xy 376.263317 -277.21666)
			(xy 376.309591 -277.240238) (xy 376.351607 -277.270764) (xy 376.38833 -277.307487) (xy 376.418856 -277.349503)
			(xy 376.442434 -277.395777) (xy 376.458482 -277.44517) (xy 376.466607 -277.496465) (xy 376.467116 -277.522432)
			(xy 376.466607 -277.548399) (xy 376.746517 -277.548399) (xy 376.746517 -277.496465) (xy 376.754642 -277.44517)
			(xy 376.77069 -277.395777) (xy 376.794268 -277.349503) (xy 376.824794 -277.307487) (xy 376.861517 -277.270764)
			(xy 376.903533 -277.240238) (xy 376.949807 -277.21666) (xy 376.9992 -277.200612) (xy 377.050495 -277.192487)
			(xy 377.102429 -277.192487) (xy 377.153724 -277.200612) (xy 377.203117 -277.21666) (xy 377.249391 -277.240238)
			(xy 377.291407 -277.270764) (xy 377.32813 -277.307487) (xy 377.358656 -277.349503) (xy 377.382234 -277.395777)
			(xy 377.398282 -277.44517) (xy 377.406407 -277.496465) (xy 377.406916 -277.522432) (xy 377.406407 -277.548399)
			(xy 377.686571 -277.548399) (xy 377.686571 -277.496465) (xy 377.694696 -277.44517) (xy 377.710744 -277.395777)
			(xy 377.734322 -277.349503) (xy 377.764848 -277.307487) (xy 377.801571 -277.270764) (xy 377.843587 -277.240238)
			(xy 377.889861 -277.21666) (xy 377.939254 -277.200612) (xy 377.990549 -277.192487) (xy 378.042483 -277.192487)
			(xy 378.093778 -277.200612) (xy 378.143171 -277.21666) (xy 378.189445 -277.240238) (xy 378.231461 -277.270764)
			(xy 378.268184 -277.307487) (xy 378.29871 -277.349503) (xy 378.322288 -277.395777) (xy 378.338336 -277.44517)
			(xy 378.346461 -277.496465) (xy 378.34697 -277.522432) (xy 378.346461 -277.548399) (xy 378.626371 -277.548399)
			(xy 378.626371 -277.496465) (xy 378.634496 -277.44517) (xy 378.650544 -277.395777) (xy 378.674122 -277.349503)
			(xy 378.704648 -277.307487) (xy 378.741371 -277.270764) (xy 378.783387 -277.240238) (xy 378.829661 -277.21666)
			(xy 378.879054 -277.200612) (xy 378.930349 -277.192487) (xy 378.982283 -277.192487) (xy 379.033578 -277.200612)
			(xy 379.082971 -277.21666) (xy 379.129245 -277.240238) (xy 379.171261 -277.270764) (xy 379.207984 -277.307487)
			(xy 379.23851 -277.349503) (xy 379.262088 -277.395777) (xy 379.278136 -277.44517) (xy 379.286261 -277.496465)
			(xy 379.28677 -277.522432) (xy 379.286261 -277.548399) (xy 379.278136 -277.599694) (xy 379.262088 -277.649087)
			(xy 379.23851 -277.695361) (xy 379.207984 -277.737377) (xy 379.171261 -277.7741) (xy 379.129245 -277.804626)
			(xy 379.082971 -277.828204) (xy 379.033578 -277.844252) (xy 378.982283 -277.852377) (xy 378.930349 -277.852377)
			(xy 378.879054 -277.844252) (xy 378.829661 -277.828204) (xy 378.783387 -277.804626) (xy 378.741371 -277.7741)
			(xy 378.704648 -277.737377) (xy 378.674122 -277.695361) (xy 378.650544 -277.649087) (xy 378.634496 -277.599694)
			(xy 378.626371 -277.548399) (xy 378.346461 -277.548399) (xy 378.338336 -277.599694) (xy 378.322288 -277.649087)
			(xy 378.29871 -277.695361) (xy 378.268184 -277.737377) (xy 378.231461 -277.7741) (xy 378.189445 -277.804626)
			(xy 378.143171 -277.828204) (xy 378.093778 -277.844252) (xy 378.042483 -277.852377) (xy 377.990549 -277.852377)
			(xy 377.939254 -277.844252) (xy 377.889861 -277.828204) (xy 377.843587 -277.804626) (xy 377.801571 -277.7741)
			(xy 377.764848 -277.737377) (xy 377.734322 -277.695361) (xy 377.710744 -277.649087) (xy 377.694696 -277.599694)
			(xy 377.686571 -277.548399) (xy 377.406407 -277.548399) (xy 377.398282 -277.599694) (xy 377.382234 -277.649087)
			(xy 377.358656 -277.695361) (xy 377.32813 -277.737377) (xy 377.291407 -277.7741) (xy 377.249391 -277.804626)
			(xy 377.203117 -277.828204) (xy 377.153724 -277.844252) (xy 377.102429 -277.852377) (xy 377.050495 -277.852377)
			(xy 376.9992 -277.844252) (xy 376.949807 -277.828204) (xy 376.903533 -277.804626) (xy 376.861517 -277.7741)
			(xy 376.824794 -277.737377) (xy 376.794268 -277.695361) (xy 376.77069 -277.649087) (xy 376.754642 -277.599694)
			(xy 376.746517 -277.548399) (xy 376.466607 -277.548399) (xy 376.458482 -277.599694) (xy 376.442434 -277.649087)
			(xy 376.418856 -277.695361) (xy 376.38833 -277.737377) (xy 376.351607 -277.7741) (xy 376.309591 -277.804626)
			(xy 376.263317 -277.828204) (xy 376.213924 -277.844252) (xy 376.162629 -277.852377) (xy 376.110695 -277.852377)
			(xy 376.0594 -277.844252) (xy 376.010007 -277.828204) (xy 375.963733 -277.804626) (xy 375.921717 -277.7741)
			(xy 375.884994 -277.737377) (xy 375.854468 -277.695361) (xy 375.83089 -277.649087) (xy 375.814842 -277.599694)
			(xy 375.806717 -277.548399) (xy 375.526807 -277.548399) (xy 375.518682 -277.599694) (xy 375.502634 -277.649087)
			(xy 375.479056 -277.695361) (xy 375.44853 -277.737377) (xy 375.411807 -277.7741) (xy 375.369791 -277.804626)
			(xy 375.323517 -277.828204) (xy 375.274124 -277.844252) (xy 375.222829 -277.852377) (xy 375.170895 -277.852377)
			(xy 375.1196 -277.844252) (xy 375.070207 -277.828204) (xy 375.023933 -277.804626) (xy 374.981917 -277.7741)
			(xy 374.945194 -277.737377) (xy 374.914668 -277.695361) (xy 374.89109 -277.649087) (xy 374.875042 -277.599694)
			(xy 374.866917 -277.548399) (xy 374.587007 -277.548399) (xy 374.578882 -277.599694) (xy 374.562834 -277.649087)
			(xy 374.539256 -277.695361) (xy 374.50873 -277.737377) (xy 374.472007 -277.7741) (xy 374.429991 -277.804626)
			(xy 374.383717 -277.828204) (xy 374.334324 -277.844252) (xy 374.283029 -277.852377) (xy 374.231095 -277.852377)
			(xy 374.1798 -277.844252) (xy 374.130407 -277.828204) (xy 374.084133 -277.804626) (xy 374.042117 -277.7741)
			(xy 374.005394 -277.737377) (xy 373.974868 -277.695361) (xy 373.95129 -277.649087) (xy 373.935242 -277.599694)
			(xy 373.927117 -277.548399) (xy 373.647461 -277.548399) (xy 373.639336 -277.599694) (xy 373.623288 -277.649087)
			(xy 373.59971 -277.695361) (xy 373.569184 -277.737377) (xy 373.532461 -277.7741) (xy 373.490445 -277.804626)
			(xy 373.444171 -277.828204) (xy 373.394778 -277.844252) (xy 373.343483 -277.852377) (xy 373.291549 -277.852377)
			(xy 373.240254 -277.844252) (xy 373.190861 -277.828204) (xy 373.144587 -277.804626) (xy 373.102571 -277.7741)
			(xy 373.065848 -277.737377) (xy 373.035322 -277.695361) (xy 373.011744 -277.649087) (xy 372.995696 -277.599694)
			(xy 372.987571 -277.548399) (xy 372.707407 -277.548399) (xy 372.699282 -277.599694) (xy 372.683234 -277.649087)
			(xy 372.659656 -277.695361) (xy 372.62913 -277.737377) (xy 372.592407 -277.7741) (xy 372.550391 -277.804626)
			(xy 372.504117 -277.828204) (xy 372.454724 -277.844252) (xy 372.403429 -277.852377) (xy 372.351495 -277.852377)
			(xy 372.3002 -277.844252) (xy 372.250807 -277.828204) (xy 372.204533 -277.804626) (xy 372.162517 -277.7741)
			(xy 372.125794 -277.737377) (xy 372.095268 -277.695361) (xy 372.07169 -277.649087) (xy 372.055642 -277.599694)
			(xy 372.047517 -277.548399) (xy 371.767607 -277.548399) (xy 371.759482 -277.599694) (xy 371.743434 -277.649087)
			(xy 371.719856 -277.695361) (xy 371.68933 -277.737377) (xy 371.652607 -277.7741) (xy 371.610591 -277.804626)
			(xy 371.564317 -277.828204) (xy 371.514924 -277.844252) (xy 371.463629 -277.852377) (xy 371.411695 -277.852377)
			(xy 371.3604 -277.844252) (xy 371.311007 -277.828204) (xy 371.264733 -277.804626) (xy 371.222717 -277.7741)
			(xy 371.185994 -277.737377) (xy 371.155468 -277.695361) (xy 371.13189 -277.649087) (xy 371.115842 -277.599694)
			(xy 371.107717 -277.548399) (xy 370.828021 -277.548399) (xy 370.819936 -277.59944) (xy 370.803888 -277.648833)
			(xy 370.78031 -277.695107) (xy 370.749784 -277.737123) (xy 370.713061 -277.773846) (xy 370.671045 -277.804372)
			(xy 370.624771 -277.82795) (xy 370.575378 -277.843998) (xy 370.524083 -277.852123) (xy 370.472149 -277.852123)
			(xy 370.420854 -277.843998) (xy 370.371461 -277.82795) (xy 370.325187 -277.804372) (xy 370.283171 -277.773846)
			(xy 370.246448 -277.737123) (xy 370.215922 -277.695107) (xy 370.192344 -277.648833) (xy 370.176296 -277.59944)
			(xy 370.168171 -277.548145) (xy 369.888261 -277.548145) (xy 369.880136 -277.59944) (xy 369.864088 -277.648833)
			(xy 369.84051 -277.695107) (xy 369.809984 -277.737123) (xy 369.773261 -277.773846) (xy 369.731245 -277.804372)
			(xy 369.684971 -277.82795) (xy 369.635578 -277.843998) (xy 369.584283 -277.852123) (xy 369.532349 -277.852123)
			(xy 369.481054 -277.843998) (xy 369.431661 -277.82795) (xy 369.385387 -277.804372) (xy 369.343371 -277.773846)
			(xy 369.306648 -277.737123) (xy 369.276122 -277.695107) (xy 369.252544 -277.648833) (xy 369.236496 -277.59944)
			(xy 369.228371 -277.548145) (xy 368.948461 -277.548145) (xy 368.940336 -277.59944) (xy 368.924288 -277.648833)
			(xy 368.90071 -277.695107) (xy 368.870184 -277.737123) (xy 368.833461 -277.773846) (xy 368.791445 -277.804372)
			(xy 368.745171 -277.82795) (xy 368.695778 -277.843998) (xy 368.644483 -277.852123) (xy 368.592549 -277.852123)
			(xy 368.541254 -277.843998) (xy 368.491861 -277.82795) (xy 368.445587 -277.804372) (xy 368.403571 -277.773846)
			(xy 368.366848 -277.737123) (xy 368.336322 -277.695107) (xy 368.312744 -277.648833) (xy 368.296696 -277.59944)
			(xy 368.288571 -277.548145) (xy 368.008661 -277.548145) (xy 368.000536 -277.59944) (xy 367.984488 -277.648833)
			(xy 367.96091 -277.695107) (xy 367.930384 -277.737123) (xy 367.893661 -277.773846) (xy 367.851645 -277.804372)
			(xy 367.805371 -277.82795) (xy 367.755978 -277.843998) (xy 367.704683 -277.852123) (xy 367.652749 -277.852123)
			(xy 367.601454 -277.843998) (xy 367.552061 -277.82795) (xy 367.505787 -277.804372) (xy 367.463771 -277.773846)
			(xy 367.427048 -277.737123) (xy 367.396522 -277.695107) (xy 367.372944 -277.648833) (xy 367.356896 -277.59944)
			(xy 367.348771 -277.548145) (xy 367.068866 -277.548145) (xy 367.068861 -277.548399) (xy 367.060736 -277.599694)
			(xy 367.044688 -277.649087) (xy 367.02111 -277.695361) (xy 366.990584 -277.737377) (xy 366.953861 -277.7741)
			(xy 366.911845 -277.804626) (xy 366.865571 -277.828204) (xy 366.816178 -277.844252) (xy 366.764883 -277.852377)
			(xy 366.712949 -277.852377) (xy 366.661654 -277.844252) (xy 366.612261 -277.828204) (xy 366.565987 -277.804626)
			(xy 366.523971 -277.7741) (xy 366.487248 -277.737377) (xy 366.456722 -277.695361) (xy 366.433144 -277.649087)
			(xy 366.417096 -277.599694) (xy 366.408971 -277.548399) (xy 366.129021 -277.548399) (xy 366.120936 -277.59944)
			(xy 366.104888 -277.648833) (xy 366.08131 -277.695107) (xy 366.050784 -277.737123) (xy 366.014061 -277.773846)
			(xy 365.972045 -277.804372) (xy 365.925771 -277.82795) (xy 365.876378 -277.843998) (xy 365.825083 -277.852123)
			(xy 365.773149 -277.852123) (xy 365.721854 -277.843998) (xy 365.672461 -277.82795) (xy 365.626187 -277.804372)
			(xy 365.584171 -277.773846) (xy 365.547448 -277.737123) (xy 365.516922 -277.695107) (xy 365.493344 -277.648833)
			(xy 365.477296 -277.59944) (xy 365.469171 -277.548145) (xy 365.189012 -277.548145) (xy 365.189007 -277.548399)
			(xy 365.180882 -277.599694) (xy 365.164834 -277.649087) (xy 365.141256 -277.695361) (xy 365.11073 -277.737377)
			(xy 365.074007 -277.7741) (xy 365.031991 -277.804626) (xy 364.985717 -277.828204) (xy 364.936324 -277.844252)
			(xy 364.885029 -277.852377) (xy 364.833095 -277.852377) (xy 364.7818 -277.844252) (xy 364.732407 -277.828204)
			(xy 364.686133 -277.804626) (xy 364.644117 -277.7741) (xy 364.607394 -277.737377) (xy 364.576868 -277.695361)
			(xy 364.55329 -277.649087) (xy 364.537242 -277.599694) (xy 364.529117 -277.548399) (xy 364.274885 -277.548399)
			(xy 364.274865 -277.54944) (xy 364.266971 -277.601849) (xy 364.251394 -277.652508) (xy 364.228478 -277.700298)
			(xy 364.198729 -277.744162) (xy 364.181136 -277.763986) (xy 364.181136 -277.917656) (xy 364.181725 -277.933086)
			(xy 364.191024 -277.962514) (xy 364.208669 -277.987836) (xy 364.233057 -278.00675) (xy 364.261973 -278.017538)
			(xy 364.292791 -278.01922) (xy 364.307882 -278.015954) (xy 364.327865 -278.011199) (xy 364.368624 -278.006099)
			(xy 364.389162 -278.005794) (xy 364.415129 -278.006274) (xy 364.466426 -278.014393) (xy 364.51582 -278.030437)
			(xy 364.562096 -278.054011) (xy 364.604115 -278.084535) (xy 364.64084 -278.121256) (xy 364.671369 -278.163271)
			(xy 364.694948 -278.209545) (xy 364.710998 -278.258937) (xy 364.719123 -278.310233) (xy 364.719123 -278.362167)
			(xy 364.719115 -278.362215) (xy 364.999017 -278.362215) (xy 364.999017 -278.310281) (xy 365.007142 -278.258986)
			(xy 365.02319 -278.209593) (xy 365.046768 -278.163319) (xy 365.077294 -278.121303) (xy 365.114017 -278.08458)
			(xy 365.156033 -278.054054) (xy 365.202307 -278.030476) (xy 365.2517 -278.014428) (xy 365.302995 -278.006303)
			(xy 365.354929 -278.006303) (xy 365.406224 -278.014428) (xy 365.455617 -278.030476) (xy 365.501891 -278.054054)
			(xy 365.543907 -278.08458) (xy 365.58063 -278.121303) (xy 365.611156 -278.163319) (xy 365.634734 -278.209593)
			(xy 365.650782 -278.258986) (xy 365.658907 -278.310281) (xy 365.659416 -278.336248) (xy 365.658907 -278.362215)
			(xy 365.938817 -278.362215) (xy 365.938817 -278.310281) (xy 365.946942 -278.258986) (xy 365.96299 -278.209593)
			(xy 365.986568 -278.163319) (xy 366.017094 -278.121303) (xy 366.053817 -278.08458) (xy 366.095833 -278.054054)
			(xy 366.142107 -278.030476) (xy 366.1915 -278.014428) (xy 366.242795 -278.006303) (xy 366.294729 -278.006303)
			(xy 366.346024 -278.014428) (xy 366.395417 -278.030476) (xy 366.441691 -278.054054) (xy 366.483707 -278.08458)
			(xy 366.52043 -278.121303) (xy 366.550956 -278.163319) (xy 366.574534 -278.209593) (xy 366.590582 -278.258986)
			(xy 366.598707 -278.310281) (xy 366.599216 -278.336248) (xy 366.598707 -278.362215) (xy 366.598667 -278.362469)
			(xy 366.878871 -278.362469) (xy 366.878871 -278.310535) (xy 366.886996 -278.25924) (xy 366.903044 -278.209847)
			(xy 366.926622 -278.163573) (xy 366.957148 -278.121557) (xy 366.993871 -278.084834) (xy 367.035887 -278.054308)
			(xy 367.082161 -278.03073) (xy 367.131554 -278.014682) (xy 367.182849 -278.006557) (xy 367.234783 -278.006557)
			(xy 367.286078 -278.014682) (xy 367.335471 -278.03073) (xy 367.381745 -278.054308) (xy 367.423761 -278.084834)
			(xy 367.460484 -278.121557) (xy 367.49101 -278.163573) (xy 367.514588 -278.209847) (xy 367.530636 -278.25924)
			(xy 367.538761 -278.310535) (xy 367.53927 -278.336502) (xy 367.538766 -278.362215) (xy 368.758217 -278.362215)
			(xy 368.758217 -278.310281) (xy 368.766342 -278.258986) (xy 368.78239 -278.209593) (xy 368.805968 -278.163319)
			(xy 368.836494 -278.121303) (xy 368.873217 -278.08458) (xy 368.915233 -278.054054) (xy 368.961507 -278.030476)
			(xy 369.0109 -278.014428) (xy 369.062195 -278.006303) (xy 369.114129 -278.006303) (xy 369.165424 -278.014428)
			(xy 369.214817 -278.030476) (xy 369.261091 -278.054054) (xy 369.303107 -278.08458) (xy 369.33983 -278.121303)
			(xy 369.370356 -278.163319) (xy 369.393934 -278.209593) (xy 369.409982 -278.258986) (xy 369.418107 -278.310281)
			(xy 369.418616 -278.336248) (xy 369.418107 -278.362215) (xy 369.418067 -278.362469) (xy 369.698017 -278.362469)
			(xy 369.698017 -278.310535) (xy 369.706142 -278.25924) (xy 369.72219 -278.209847) (xy 369.745768 -278.163573)
			(xy 369.776294 -278.121557) (xy 369.813017 -278.084834) (xy 369.855033 -278.054308) (xy 369.901307 -278.03073)
			(xy 369.9507 -278.014682) (xy 370.001995 -278.006557) (xy 370.053929 -278.006557) (xy 370.105224 -278.014682)
			(xy 370.154617 -278.03073) (xy 370.200891 -278.054308) (xy 370.242907 -278.084834) (xy 370.27963 -278.121557)
			(xy 370.310156 -278.163573) (xy 370.333734 -278.209847) (xy 370.349782 -278.25924) (xy 370.357907 -278.310535)
			(xy 370.358416 -278.336502) (xy 370.357907 -278.362469) (xy 370.638071 -278.362469) (xy 370.638071 -278.310535)
			(xy 370.646196 -278.25924) (xy 370.662244 -278.209847) (xy 370.685822 -278.163573) (xy 370.716348 -278.121557)
			(xy 370.753071 -278.084834) (xy 370.795087 -278.054308) (xy 370.841361 -278.03073) (xy 370.890754 -278.014682)
			(xy 370.942049 -278.006557) (xy 370.993983 -278.006557) (xy 371.045278 -278.014682) (xy 371.094671 -278.03073)
			(xy 371.140945 -278.054308) (xy 371.182961 -278.084834) (xy 371.219684 -278.121557) (xy 371.25021 -278.163573)
			(xy 371.273788 -278.209847) (xy 371.289836 -278.25924) (xy 371.297961 -278.310535) (xy 371.29847 -278.336502)
			(xy 371.297961 -278.362469) (xy 372.517671 -278.362469) (xy 372.517671 -278.310535) (xy 372.525796 -278.25924)
			(xy 372.541844 -278.209847) (xy 372.565422 -278.163573) (xy 372.595948 -278.121557) (xy 372.632671 -278.084834)
			(xy 372.674687 -278.054308) (xy 372.720961 -278.03073) (xy 372.770354 -278.014682) (xy 372.821649 -278.006557)
			(xy 372.873583 -278.006557) (xy 372.924878 -278.014682) (xy 372.974271 -278.03073) (xy 373.020545 -278.054308)
			(xy 373.062561 -278.084834) (xy 373.099284 -278.121557) (xy 373.12981 -278.163573) (xy 373.153388 -278.209847)
			(xy 373.169436 -278.25924) (xy 373.177561 -278.310535) (xy 373.17807 -278.336502) (xy 373.177561 -278.362469)
			(xy 373.457471 -278.362469) (xy 373.457471 -278.310535) (xy 373.465596 -278.25924) (xy 373.481644 -278.209847)
			(xy 373.505222 -278.163573) (xy 373.535748 -278.121557) (xy 373.572471 -278.084834) (xy 373.614487 -278.054308)
			(xy 373.660761 -278.03073) (xy 373.710154 -278.014682) (xy 373.761449 -278.006557) (xy 373.813383 -278.006557)
			(xy 373.864678 -278.014682) (xy 373.914071 -278.03073) (xy 373.960345 -278.054308) (xy 374.002361 -278.084834)
			(xy 374.039084 -278.121557) (xy 374.06961 -278.163573) (xy 374.093188 -278.209847) (xy 374.109236 -278.25924)
			(xy 374.117361 -278.310535) (xy 374.11787 -278.336502) (xy 374.117361 -278.362469) (xy 374.397271 -278.362469)
			(xy 374.397271 -278.310535) (xy 374.405396 -278.25924) (xy 374.421444 -278.209847) (xy 374.445022 -278.163573)
			(xy 374.475548 -278.121557) (xy 374.512271 -278.084834) (xy 374.554287 -278.054308) (xy 374.600561 -278.03073)
			(xy 374.649954 -278.014682) (xy 374.701249 -278.006557) (xy 374.753183 -278.006557) (xy 374.804478 -278.014682)
			(xy 374.853871 -278.03073) (xy 374.900145 -278.054308) (xy 374.942161 -278.084834) (xy 374.978884 -278.121557)
			(xy 375.00941 -278.163573) (xy 375.032988 -278.209847) (xy 375.049036 -278.25924) (xy 375.057161 -278.310535)
			(xy 375.05767 -278.336502) (xy 375.057161 -278.362469) (xy 375.337071 -278.362469) (xy 375.337071 -278.310535)
			(xy 375.345196 -278.25924) (xy 375.361244 -278.209847) (xy 375.384822 -278.163573) (xy 375.415348 -278.121557)
			(xy 375.452071 -278.084834) (xy 375.494087 -278.054308) (xy 375.540361 -278.03073) (xy 375.589754 -278.014682)
			(xy 375.641049 -278.006557) (xy 375.692983 -278.006557) (xy 375.744278 -278.014682) (xy 375.793671 -278.03073)
			(xy 375.839945 -278.054308) (xy 375.881961 -278.084834) (xy 375.918684 -278.121557) (xy 375.94921 -278.163573)
			(xy 375.972788 -278.209847) (xy 375.988836 -278.25924) (xy 375.996961 -278.310535) (xy 375.99747 -278.336502)
			(xy 375.996961 -278.362469) (xy 376.276617 -278.362469) (xy 376.276617 -278.310535) (xy 376.284742 -278.25924)
			(xy 376.30079 -278.209847) (xy 376.324368 -278.163573) (xy 376.354894 -278.121557) (xy 376.391617 -278.084834)
			(xy 376.433633 -278.054308) (xy 376.479907 -278.03073) (xy 376.5293 -278.014682) (xy 376.580595 -278.006557)
			(xy 376.632529 -278.006557) (xy 376.683824 -278.014682) (xy 376.733217 -278.03073) (xy 376.779491 -278.054308)
			(xy 376.821507 -278.084834) (xy 376.85823 -278.121557) (xy 376.888756 -278.163573) (xy 376.912334 -278.209847)
			(xy 376.928382 -278.25924) (xy 376.936507 -278.310535) (xy 376.937016 -278.336502) (xy 376.936507 -278.362469)
			(xy 377.216671 -278.362469) (xy 377.216671 -278.310535) (xy 377.224796 -278.25924) (xy 377.240844 -278.209847)
			(xy 377.264422 -278.163573) (xy 377.294948 -278.121557) (xy 377.331671 -278.084834) (xy 377.373687 -278.054308)
			(xy 377.419961 -278.03073) (xy 377.469354 -278.014682) (xy 377.520649 -278.006557) (xy 377.572583 -278.006557)
			(xy 377.623878 -278.014682) (xy 377.673271 -278.03073) (xy 377.719545 -278.054308) (xy 377.761561 -278.084834)
			(xy 377.798284 -278.121557) (xy 377.82881 -278.163573) (xy 377.852388 -278.209847) (xy 377.868436 -278.25924)
			(xy 377.876561 -278.310535) (xy 377.87707 -278.336502) (xy 377.876561 -278.362469) (xy 378.156217 -278.362469)
			(xy 378.156217 -278.310535) (xy 378.164342 -278.25924) (xy 378.18039 -278.209847) (xy 378.203968 -278.163573)
			(xy 378.234494 -278.121557) (xy 378.271217 -278.084834) (xy 378.313233 -278.054308) (xy 378.359507 -278.03073)
			(xy 378.4089 -278.014682) (xy 378.460195 -278.006557) (xy 378.512129 -278.006557) (xy 378.563424 -278.014682)
			(xy 378.612817 -278.03073) (xy 378.659091 -278.054308) (xy 378.701107 -278.084834) (xy 378.73783 -278.121557)
			(xy 378.768356 -278.163573) (xy 378.791934 -278.209847) (xy 378.807982 -278.25924) (xy 378.816107 -278.310535)
			(xy 378.816616 -278.336502) (xy 378.816107 -278.362469) (xy 378.807982 -278.413764) (xy 378.791934 -278.463157)
			(xy 378.768356 -278.509431) (xy 378.73783 -278.551447) (xy 378.701107 -278.58817) (xy 378.659091 -278.618696)
			(xy 378.612817 -278.642274) (xy 378.563424 -278.658322) (xy 378.512129 -278.666447) (xy 378.460195 -278.666447)
			(xy 378.4089 -278.658322) (xy 378.359507 -278.642274) (xy 378.313233 -278.618696) (xy 378.271217 -278.58817)
			(xy 378.234494 -278.551447) (xy 378.203968 -278.509431) (xy 378.18039 -278.463157) (xy 378.164342 -278.413764)
			(xy 378.156217 -278.362469) (xy 377.876561 -278.362469) (xy 377.868436 -278.413764) (xy 377.852388 -278.463157)
			(xy 377.82881 -278.509431) (xy 377.798284 -278.551447) (xy 377.761561 -278.58817) (xy 377.719545 -278.618696)
			(xy 377.673271 -278.642274) (xy 377.623878 -278.658322) (xy 377.572583 -278.666447) (xy 377.520649 -278.666447)
			(xy 377.469354 -278.658322) (xy 377.419961 -278.642274) (xy 377.373687 -278.618696) (xy 377.331671 -278.58817)
			(xy 377.294948 -278.551447) (xy 377.264422 -278.509431) (xy 377.240844 -278.463157) (xy 377.224796 -278.413764)
			(xy 377.216671 -278.362469) (xy 376.936507 -278.362469) (xy 376.928382 -278.413764) (xy 376.912334 -278.463157)
			(xy 376.888756 -278.509431) (xy 376.85823 -278.551447) (xy 376.821507 -278.58817) (xy 376.779491 -278.618696)
			(xy 376.733217 -278.642274) (xy 376.683824 -278.658322) (xy 376.632529 -278.666447) (xy 376.580595 -278.666447)
			(xy 376.5293 -278.658322) (xy 376.479907 -278.642274) (xy 376.433633 -278.618696) (xy 376.391617 -278.58817)
			(xy 376.354894 -278.551447) (xy 376.324368 -278.509431) (xy 376.30079 -278.463157) (xy 376.284742 -278.413764)
			(xy 376.276617 -278.362469) (xy 375.996961 -278.362469) (xy 375.988836 -278.413764) (xy 375.972788 -278.463157)
			(xy 375.94921 -278.509431) (xy 375.918684 -278.551447) (xy 375.881961 -278.58817) (xy 375.839945 -278.618696)
			(xy 375.793671 -278.642274) (xy 375.744278 -278.658322) (xy 375.692983 -278.666447) (xy 375.641049 -278.666447)
			(xy 375.589754 -278.658322) (xy 375.540361 -278.642274) (xy 375.494087 -278.618696) (xy 375.452071 -278.58817)
			(xy 375.415348 -278.551447) (xy 375.384822 -278.509431) (xy 375.361244 -278.463157) (xy 375.345196 -278.413764)
			(xy 375.337071 -278.362469) (xy 375.057161 -278.362469) (xy 375.049036 -278.413764) (xy 375.032988 -278.463157)
			(xy 375.00941 -278.509431) (xy 374.978884 -278.551447) (xy 374.942161 -278.58817) (xy 374.900145 -278.618696)
			(xy 374.853871 -278.642274) (xy 374.804478 -278.658322) (xy 374.753183 -278.666447) (xy 374.701249 -278.666447)
			(xy 374.649954 -278.658322) (xy 374.600561 -278.642274) (xy 374.554287 -278.618696) (xy 374.512271 -278.58817)
			(xy 374.475548 -278.551447) (xy 374.445022 -278.509431) (xy 374.421444 -278.463157) (xy 374.405396 -278.413764)
			(xy 374.397271 -278.362469) (xy 374.117361 -278.362469) (xy 374.109236 -278.413764) (xy 374.093188 -278.463157)
			(xy 374.06961 -278.509431) (xy 374.039084 -278.551447) (xy 374.002361 -278.58817) (xy 373.960345 -278.618696)
			(xy 373.914071 -278.642274) (xy 373.864678 -278.658322) (xy 373.813383 -278.666447) (xy 373.761449 -278.666447)
			(xy 373.710154 -278.658322) (xy 373.660761 -278.642274) (xy 373.614487 -278.618696) (xy 373.572471 -278.58817)
			(xy 373.535748 -278.551447) (xy 373.505222 -278.509431) (xy 373.481644 -278.463157) (xy 373.465596 -278.413764)
			(xy 373.457471 -278.362469) (xy 373.177561 -278.362469) (xy 373.169436 -278.413764) (xy 373.153388 -278.463157)
			(xy 373.12981 -278.509431) (xy 373.099284 -278.551447) (xy 373.062561 -278.58817) (xy 373.020545 -278.618696)
			(xy 372.974271 -278.642274) (xy 372.924878 -278.658322) (xy 372.873583 -278.666447) (xy 372.821649 -278.666447)
			(xy 372.770354 -278.658322) (xy 372.720961 -278.642274) (xy 372.674687 -278.618696) (xy 372.632671 -278.58817)
			(xy 372.595948 -278.551447) (xy 372.565422 -278.509431) (xy 372.541844 -278.463157) (xy 372.525796 -278.413764)
			(xy 372.517671 -278.362469) (xy 371.297961 -278.362469) (xy 371.289836 -278.413764) (xy 371.273788 -278.463157)
			(xy 371.25021 -278.509431) (xy 371.219684 -278.551447) (xy 371.182961 -278.58817) (xy 371.140945 -278.618696)
			(xy 371.094671 -278.642274) (xy 371.045278 -278.658322) (xy 370.993983 -278.666447) (xy 370.942049 -278.666447)
			(xy 370.890754 -278.658322) (xy 370.841361 -278.642274) (xy 370.795087 -278.618696) (xy 370.753071 -278.58817)
			(xy 370.716348 -278.551447) (xy 370.685822 -278.509431) (xy 370.662244 -278.463157) (xy 370.646196 -278.413764)
			(xy 370.638071 -278.362469) (xy 370.357907 -278.362469) (xy 370.349782 -278.413764) (xy 370.333734 -278.463157)
			(xy 370.310156 -278.509431) (xy 370.27963 -278.551447) (xy 370.242907 -278.58817) (xy 370.200891 -278.618696)
			(xy 370.154617 -278.642274) (xy 370.105224 -278.658322) (xy 370.053929 -278.666447) (xy 370.001995 -278.666447)
			(xy 369.9507 -278.658322) (xy 369.901307 -278.642274) (xy 369.855033 -278.618696) (xy 369.813017 -278.58817)
			(xy 369.776294 -278.551447) (xy 369.745768 -278.509431) (xy 369.72219 -278.463157) (xy 369.706142 -278.413764)
			(xy 369.698017 -278.362469) (xy 369.418067 -278.362469) (xy 369.409982 -278.41351) (xy 369.393934 -278.462903)
			(xy 369.370356 -278.509177) (xy 369.33983 -278.551193) (xy 369.303107 -278.587916) (xy 369.261091 -278.618442)
			(xy 369.214817 -278.64202) (xy 369.165424 -278.658068) (xy 369.114129 -278.666193) (xy 369.062195 -278.666193)
			(xy 369.0109 -278.658068) (xy 368.961507 -278.64202) (xy 368.915233 -278.618442) (xy 368.873217 -278.587916)
			(xy 368.836494 -278.551193) (xy 368.805968 -278.509177) (xy 368.78239 -278.462903) (xy 368.766342 -278.41351)
			(xy 368.758217 -278.362215) (xy 367.538766 -278.362215) (xy 367.538761 -278.362469) (xy 367.530636 -278.413764)
			(xy 367.514588 -278.463157) (xy 367.49101 -278.509431) (xy 367.460484 -278.551447) (xy 367.423761 -278.58817)
			(xy 367.381745 -278.618696) (xy 367.335471 -278.642274) (xy 367.286078 -278.658322) (xy 367.234783 -278.666447)
			(xy 367.182849 -278.666447) (xy 367.131554 -278.658322) (xy 367.082161 -278.642274) (xy 367.035887 -278.618696)
			(xy 366.993871 -278.58817) (xy 366.957148 -278.551447) (xy 366.926622 -278.509431) (xy 366.903044 -278.463157)
			(xy 366.886996 -278.413764) (xy 366.878871 -278.362469) (xy 366.598667 -278.362469) (xy 366.590582 -278.41351)
			(xy 366.574534 -278.462903) (xy 366.550956 -278.509177) (xy 366.52043 -278.551193) (xy 366.483707 -278.587916)
			(xy 366.441691 -278.618442) (xy 366.395417 -278.64202) (xy 366.346024 -278.658068) (xy 366.294729 -278.666193)
			(xy 366.242795 -278.666193) (xy 366.1915 -278.658068) (xy 366.142107 -278.64202) (xy 366.095833 -278.618442)
			(xy 366.053817 -278.587916) (xy 366.017094 -278.551193) (xy 365.986568 -278.509177) (xy 365.96299 -278.462903)
			(xy 365.946942 -278.41351) (xy 365.938817 -278.362215) (xy 365.658907 -278.362215) (xy 365.650782 -278.41351)
			(xy 365.634734 -278.462903) (xy 365.611156 -278.509177) (xy 365.58063 -278.551193) (xy 365.543907 -278.587916)
			(xy 365.501891 -278.618442) (xy 365.455617 -278.64202) (xy 365.406224 -278.658068) (xy 365.354929 -278.666193)
			(xy 365.302995 -278.666193) (xy 365.2517 -278.658068) (xy 365.202307 -278.64202) (xy 365.156033 -278.618442)
			(xy 365.114017 -278.587916) (xy 365.077294 -278.551193) (xy 365.046768 -278.509177) (xy 365.02319 -278.462903)
			(xy 365.007142 -278.41351) (xy 364.999017 -278.362215) (xy 364.719115 -278.362215) (xy 364.710998 -278.413463)
			(xy 364.694948 -278.462855) (xy 364.671369 -278.509129) (xy 364.64084 -278.551144) (xy 364.604115 -278.587865)
			(xy 364.562096 -278.618389) (xy 364.51582 -278.641963) (xy 364.466426 -278.658007) (xy 364.415129 -278.666126)
			(xy 364.389162 -278.666702) (xy 364.368624 -278.666387) (xy 364.327866 -278.661288) (xy 364.307882 -278.656542)
			(xy 364.292788 -278.653236) (xy 364.261946 -278.654867) (xy 364.233 -278.66564) (xy 364.208597 -278.684571)
			(xy 364.190967 -278.709929) (xy 364.18172 -278.739398) (xy 364.181136 -278.75484) (xy 364.181136 -278.948896)
			(xy 364.197219 -278.970707) (xy 364.222808 -279.018474) (xy 364.240277 -279.069769) (xy 364.249162 -279.123224)
			(xy 364.249716 -279.150318) (xy 364.249202 -279.176031) (xy 364.529371 -279.176031) (xy 364.529371 -279.124097)
			(xy 364.537496 -279.072802) (xy 364.553544 -279.023409) (xy 364.577122 -278.977135) (xy 364.607648 -278.935119)
			(xy 364.644371 -278.898396) (xy 364.686387 -278.86787) (xy 364.732661 -278.844292) (xy 364.782054 -278.828244)
			(xy 364.833349 -278.820119) (xy 364.885283 -278.820119) (xy 364.936578 -278.828244) (xy 364.985971 -278.844292)
			(xy 365.032245 -278.86787) (xy 365.074261 -278.898396) (xy 365.110984 -278.935119) (xy 365.14151 -278.977135)
			(xy 365.165088 -279.023409) (xy 365.181136 -279.072802) (xy 365.189261 -279.124097) (xy 365.18977 -279.150064)
			(xy 365.189261 -279.176031) (xy 365.189221 -279.176285) (xy 365.469171 -279.176285) (xy 365.469171 -279.124351)
			(xy 365.477296 -279.073056) (xy 365.493344 -279.023663) (xy 365.516922 -278.977389) (xy 365.547448 -278.935373)
			(xy 365.584171 -278.89865) (xy 365.626187 -278.868124) (xy 365.672461 -278.844546) (xy 365.721854 -278.828498)
			(xy 365.773149 -278.820373) (xy 365.825083 -278.820373) (xy 365.876378 -278.828498) (xy 365.925771 -278.844546)
			(xy 365.972045 -278.868124) (xy 366.014061 -278.89865) (xy 366.050784 -278.935373) (xy 366.08131 -278.977389)
			(xy 366.104888 -279.023663) (xy 366.120936 -279.073056) (xy 366.129061 -279.124351) (xy 366.12957 -279.150318)
			(xy 366.129061 -279.176285) (xy 367.348517 -279.176285) (xy 367.348517 -279.124351) (xy 367.356642 -279.073056)
			(xy 367.37269 -279.023663) (xy 367.396268 -278.977389) (xy 367.426794 -278.935373) (xy 367.463517 -278.89865)
			(xy 367.505533 -278.868124) (xy 367.551807 -278.844546) (xy 367.6012 -278.828498) (xy 367.652495 -278.820373)
			(xy 367.704429 -278.820373) (xy 367.755724 -278.828498) (xy 367.805117 -278.844546) (xy 367.851391 -278.868124)
			(xy 367.893407 -278.89865) (xy 367.93013 -278.935373) (xy 367.960656 -278.977389) (xy 367.984234 -279.023663)
			(xy 368.000282 -279.073056) (xy 368.008407 -279.124351) (xy 368.008916 -279.150318) (xy 368.008407 -279.176285)
			(xy 368.288571 -279.176285) (xy 368.288571 -279.124351) (xy 368.296696 -279.073056) (xy 368.312744 -279.023663)
			(xy 368.336322 -278.977389) (xy 368.366848 -278.935373) (xy 368.403571 -278.89865) (xy 368.445587 -278.868124)
			(xy 368.491861 -278.844546) (xy 368.541254 -278.828498) (xy 368.592549 -278.820373) (xy 368.644483 -278.820373)
			(xy 368.695778 -278.828498) (xy 368.745171 -278.844546) (xy 368.791445 -278.868124) (xy 368.833461 -278.89865)
			(xy 368.870184 -278.935373) (xy 368.90071 -278.977389) (xy 368.924288 -279.023663) (xy 368.940336 -279.073056)
			(xy 368.948461 -279.124351) (xy 368.94897 -279.150318) (xy 368.948461 -279.176285) (xy 369.228117 -279.176285)
			(xy 369.228117 -279.124351) (xy 369.236242 -279.073056) (xy 369.25229 -279.023663) (xy 369.275868 -278.977389)
			(xy 369.306394 -278.935373) (xy 369.343117 -278.89865) (xy 369.385133 -278.868124) (xy 369.431407 -278.844546)
			(xy 369.4808 -278.828498) (xy 369.532095 -278.820373) (xy 369.584029 -278.820373) (xy 369.635324 -278.828498)
			(xy 369.684717 -278.844546) (xy 369.730991 -278.868124) (xy 369.773007 -278.89865) (xy 369.80973 -278.935373)
			(xy 369.840256 -278.977389) (xy 369.863834 -279.023663) (xy 369.879882 -279.073056) (xy 369.888007 -279.124351)
			(xy 369.888516 -279.150318) (xy 369.888007 -279.176285) (xy 370.167917 -279.176285) (xy 370.167917 -279.124351)
			(xy 370.176042 -279.073056) (xy 370.19209 -279.023663) (xy 370.215668 -278.977389) (xy 370.246194 -278.935373)
			(xy 370.282917 -278.89865) (xy 370.324933 -278.868124) (xy 370.371207 -278.844546) (xy 370.4206 -278.828498)
			(xy 370.471895 -278.820373) (xy 370.523829 -278.820373) (xy 370.575124 -278.828498) (xy 370.624517 -278.844546)
			(xy 370.670791 -278.868124) (xy 370.712807 -278.89865) (xy 370.74953 -278.935373) (xy 370.780056 -278.977389)
			(xy 370.803634 -279.023663) (xy 370.819682 -279.073056) (xy 370.827807 -279.124351) (xy 370.828316 -279.150318)
			(xy 370.827807 -279.176285) (xy 371.107971 -279.176285) (xy 371.107971 -279.124351) (xy 371.116096 -279.073056)
			(xy 371.132144 -279.023663) (xy 371.155722 -278.977389) (xy 371.186248 -278.935373) (xy 371.222971 -278.89865)
			(xy 371.264987 -278.868124) (xy 371.311261 -278.844546) (xy 371.360654 -278.828498) (xy 371.411949 -278.820373)
			(xy 371.463883 -278.820373) (xy 371.515178 -278.828498) (xy 371.564571 -278.844546) (xy 371.610845 -278.868124)
			(xy 371.652861 -278.89865) (xy 371.689584 -278.935373) (xy 371.72011 -278.977389) (xy 371.743688 -279.023663)
			(xy 371.759736 -279.073056) (xy 371.767861 -279.124351) (xy 371.76837 -279.150318) (xy 371.767861 -279.176285)
			(xy 372.047517 -279.176285) (xy 372.047517 -279.124351) (xy 372.055642 -279.073056) (xy 372.07169 -279.023663)
			(xy 372.095268 -278.977389) (xy 372.125794 -278.935373) (xy 372.162517 -278.89865) (xy 372.204533 -278.868124)
			(xy 372.250807 -278.844546) (xy 372.3002 -278.828498) (xy 372.351495 -278.820373) (xy 372.403429 -278.820373)
			(xy 372.454724 -278.828498) (xy 372.504117 -278.844546) (xy 372.550391 -278.868124) (xy 372.592407 -278.89865)
			(xy 372.62913 -278.935373) (xy 372.659656 -278.977389) (xy 372.683234 -279.023663) (xy 372.699282 -279.073056)
			(xy 372.707407 -279.124351) (xy 372.707916 -279.150318) (xy 372.707407 -279.176285) (xy 372.987317 -279.176285)
			(xy 372.987317 -279.124351) (xy 372.995442 -279.073056) (xy 373.01149 -279.023663) (xy 373.035068 -278.977389)
			(xy 373.065594 -278.935373) (xy 373.102317 -278.89865) (xy 373.144333 -278.868124) (xy 373.190607 -278.844546)
			(xy 373.24 -278.828498) (xy 373.291295 -278.820373) (xy 373.343229 -278.820373) (xy 373.394524 -278.828498)
			(xy 373.443917 -278.844546) (xy 373.490191 -278.868124) (xy 373.532207 -278.89865) (xy 373.56893 -278.935373)
			(xy 373.599456 -278.977389) (xy 373.623034 -279.023663) (xy 373.639082 -279.073056) (xy 373.647207 -279.124351)
			(xy 373.647716 -279.150318) (xy 373.647207 -279.176285) (xy 373.927117 -279.176285) (xy 373.927117 -279.124351)
			(xy 373.935242 -279.073056) (xy 373.95129 -279.023663) (xy 373.974868 -278.977389) (xy 374.005394 -278.935373)
			(xy 374.042117 -278.89865) (xy 374.084133 -278.868124) (xy 374.130407 -278.844546) (xy 374.1798 -278.828498)
			(xy 374.231095 -278.820373) (xy 374.283029 -278.820373) (xy 374.334324 -278.828498) (xy 374.383717 -278.844546)
			(xy 374.429991 -278.868124) (xy 374.472007 -278.89865) (xy 374.50873 -278.935373) (xy 374.539256 -278.977389)
			(xy 374.562834 -279.023663) (xy 374.578882 -279.073056) (xy 374.587007 -279.124351) (xy 374.587516 -279.150318)
			(xy 374.587007 -279.176285) (xy 374.866917 -279.176285) (xy 374.866917 -279.124351) (xy 374.875042 -279.073056)
			(xy 374.89109 -279.023663) (xy 374.914668 -278.977389) (xy 374.945194 -278.935373) (xy 374.981917 -278.89865)
			(xy 375.023933 -278.868124) (xy 375.070207 -278.844546) (xy 375.1196 -278.828498) (xy 375.170895 -278.820373)
			(xy 375.222829 -278.820373) (xy 375.274124 -278.828498) (xy 375.323517 -278.844546) (xy 375.369791 -278.868124)
			(xy 375.411807 -278.89865) (xy 375.44853 -278.935373) (xy 375.479056 -278.977389) (xy 375.502634 -279.023663)
			(xy 375.518682 -279.073056) (xy 375.526807 -279.124351) (xy 375.527316 -279.150318) (xy 375.526807 -279.176285)
			(xy 375.806717 -279.176285) (xy 375.806717 -279.124351) (xy 375.814842 -279.073056) (xy 375.83089 -279.023663)
			(xy 375.854468 -278.977389) (xy 375.884994 -278.935373) (xy 375.921717 -278.89865) (xy 375.963733 -278.868124)
			(xy 376.010007 -278.844546) (xy 376.0594 -278.828498) (xy 376.110695 -278.820373) (xy 376.162629 -278.820373)
			(xy 376.213924 -278.828498) (xy 376.263317 -278.844546) (xy 376.309591 -278.868124) (xy 376.351607 -278.89865)
			(xy 376.38833 -278.935373) (xy 376.418856 -278.977389) (xy 376.442434 -279.023663) (xy 376.458482 -279.073056)
			(xy 376.466607 -279.124351) (xy 376.467116 -279.150318) (xy 376.466607 -279.176285) (xy 376.746517 -279.176285)
			(xy 376.746517 -279.124351) (xy 376.754642 -279.073056) (xy 376.77069 -279.023663) (xy 376.794268 -278.977389)
			(xy 376.824794 -278.935373) (xy 376.861517 -278.89865) (xy 376.903533 -278.868124) (xy 376.949807 -278.844546)
			(xy 376.9992 -278.828498) (xy 377.050495 -278.820373) (xy 377.102429 -278.820373) (xy 377.153724 -278.828498)
			(xy 377.203117 -278.844546) (xy 377.249391 -278.868124) (xy 377.291407 -278.89865) (xy 377.32813 -278.935373)
			(xy 377.358656 -278.977389) (xy 377.382234 -279.023663) (xy 377.398282 -279.073056) (xy 377.406407 -279.124351)
			(xy 377.406916 -279.150318) (xy 377.406407 -279.176285) (xy 377.686571 -279.176285) (xy 377.686571 -279.124351)
			(xy 377.694696 -279.073056) (xy 377.710744 -279.023663) (xy 377.734322 -278.977389) (xy 377.764848 -278.935373)
			(xy 377.801571 -278.89865) (xy 377.843587 -278.868124) (xy 377.889861 -278.844546) (xy 377.939254 -278.828498)
			(xy 377.990549 -278.820373) (xy 378.042483 -278.820373) (xy 378.093778 -278.828498) (xy 378.143171 -278.844546)
			(xy 378.189445 -278.868124) (xy 378.231461 -278.89865) (xy 378.268184 -278.935373) (xy 378.29871 -278.977389)
			(xy 378.322288 -279.023663) (xy 378.338336 -279.073056) (xy 378.346461 -279.124351) (xy 378.34697 -279.150318)
			(xy 378.346461 -279.176285) (xy 378.626117 -279.176285) (xy 378.626117 -279.124351) (xy 378.634242 -279.073056)
			(xy 378.65029 -279.023663) (xy 378.673868 -278.977389) (xy 378.704394 -278.935373) (xy 378.741117 -278.89865)
			(xy 378.783133 -278.868124) (xy 378.829407 -278.844546) (xy 378.8788 -278.828498) (xy 378.930095 -278.820373)
			(xy 378.982029 -278.820373) (xy 379.033324 -278.828498) (xy 379.082717 -278.844546) (xy 379.128991 -278.868124)
			(xy 379.171007 -278.89865) (xy 379.20773 -278.935373) (xy 379.238256 -278.977389) (xy 379.261834 -279.023663)
			(xy 379.277882 -279.073056) (xy 379.286007 -279.124351) (xy 379.286516 -279.150318) (xy 379.286007 -279.176285)
			(xy 379.277882 -279.22758) (xy 379.261834 -279.276973) (xy 379.238256 -279.323247) (xy 379.20773 -279.365263)
			(xy 379.171007 -279.401986) (xy 379.128991 -279.432512) (xy 379.082717 -279.45609) (xy 379.033324 -279.472138)
			(xy 378.982029 -279.480263) (xy 378.930095 -279.480263) (xy 378.8788 -279.472138) (xy 378.829407 -279.45609)
			(xy 378.783133 -279.432512) (xy 378.741117 -279.401986) (xy 378.704394 -279.365263) (xy 378.673868 -279.323247)
			(xy 378.65029 -279.276973) (xy 378.634242 -279.22758) (xy 378.626117 -279.176285) (xy 378.346461 -279.176285)
			(xy 378.338336 -279.22758) (xy 378.322288 -279.276973) (xy 378.29871 -279.323247) (xy 378.268184 -279.365263)
			(xy 378.231461 -279.401986) (xy 378.189445 -279.432512) (xy 378.143171 -279.45609) (xy 378.093778 -279.472138)
			(xy 378.042483 -279.480263) (xy 377.990549 -279.480263) (xy 377.939254 -279.472138) (xy 377.889861 -279.45609)
			(xy 377.843587 -279.432512) (xy 377.801571 -279.401986) (xy 377.764848 -279.365263) (xy 377.734322 -279.323247)
			(xy 377.710744 -279.276973) (xy 377.694696 -279.22758) (xy 377.686571 -279.176285) (xy 377.406407 -279.176285)
			(xy 377.398282 -279.22758) (xy 377.382234 -279.276973) (xy 377.358656 -279.323247) (xy 377.32813 -279.365263)
			(xy 377.291407 -279.401986) (xy 377.249391 -279.432512) (xy 377.203117 -279.45609) (xy 377.153724 -279.472138)
			(xy 377.102429 -279.480263) (xy 377.050495 -279.480263) (xy 376.9992 -279.472138) (xy 376.949807 -279.45609)
			(xy 376.903533 -279.432512) (xy 376.861517 -279.401986) (xy 376.824794 -279.365263) (xy 376.794268 -279.323247)
			(xy 376.77069 -279.276973) (xy 376.754642 -279.22758) (xy 376.746517 -279.176285) (xy 376.466607 -279.176285)
			(xy 376.458482 -279.22758) (xy 376.442434 -279.276973) (xy 376.418856 -279.323247) (xy 376.38833 -279.365263)
			(xy 376.351607 -279.401986) (xy 376.309591 -279.432512) (xy 376.263317 -279.45609) (xy 376.213924 -279.472138)
			(xy 376.162629 -279.480263) (xy 376.110695 -279.480263) (xy 376.0594 -279.472138) (xy 376.010007 -279.45609)
			(xy 375.963733 -279.432512) (xy 375.921717 -279.401986) (xy 375.884994 -279.365263) (xy 375.854468 -279.323247)
			(xy 375.83089 -279.276973) (xy 375.814842 -279.22758) (xy 375.806717 -279.176285) (xy 375.526807 -279.176285)
			(xy 375.518682 -279.22758) (xy 375.502634 -279.276973) (xy 375.479056 -279.323247) (xy 375.44853 -279.365263)
			(xy 375.411807 -279.401986) (xy 375.369791 -279.432512) (xy 375.323517 -279.45609) (xy 375.274124 -279.472138)
			(xy 375.222829 -279.480263) (xy 375.170895 -279.480263) (xy 375.1196 -279.472138) (xy 375.070207 -279.45609)
			(xy 375.023933 -279.432512) (xy 374.981917 -279.401986) (xy 374.945194 -279.365263) (xy 374.914668 -279.323247)
			(xy 374.89109 -279.276973) (xy 374.875042 -279.22758) (xy 374.866917 -279.176285) (xy 374.587007 -279.176285)
			(xy 374.578882 -279.22758) (xy 374.562834 -279.276973) (xy 374.539256 -279.323247) (xy 374.50873 -279.365263)
			(xy 374.472007 -279.401986) (xy 374.429991 -279.432512) (xy 374.383717 -279.45609) (xy 374.334324 -279.472138)
			(xy 374.283029 -279.480263) (xy 374.231095 -279.480263) (xy 374.1798 -279.472138) (xy 374.130407 -279.45609)
			(xy 374.084133 -279.432512) (xy 374.042117 -279.401986) (xy 374.005394 -279.365263) (xy 373.974868 -279.323247)
			(xy 373.95129 -279.276973) (xy 373.935242 -279.22758) (xy 373.927117 -279.176285) (xy 373.647207 -279.176285)
			(xy 373.639082 -279.22758) (xy 373.623034 -279.276973) (xy 373.599456 -279.323247) (xy 373.56893 -279.365263)
			(xy 373.532207 -279.401986) (xy 373.490191 -279.432512) (xy 373.443917 -279.45609) (xy 373.394524 -279.472138)
			(xy 373.343229 -279.480263) (xy 373.291295 -279.480263) (xy 373.24 -279.472138) (xy 373.190607 -279.45609)
			(xy 373.144333 -279.432512) (xy 373.102317 -279.401986) (xy 373.065594 -279.365263) (xy 373.035068 -279.323247)
			(xy 373.01149 -279.276973) (xy 372.995442 -279.22758) (xy 372.987317 -279.176285) (xy 372.707407 -279.176285)
			(xy 372.699282 -279.22758) (xy 372.683234 -279.276973) (xy 372.659656 -279.323247) (xy 372.62913 -279.365263)
			(xy 372.592407 -279.401986) (xy 372.550391 -279.432512) (xy 372.504117 -279.45609) (xy 372.454724 -279.472138)
			(xy 372.403429 -279.480263) (xy 372.351495 -279.480263) (xy 372.3002 -279.472138) (xy 372.250807 -279.45609)
			(xy 372.204533 -279.432512) (xy 372.162517 -279.401986) (xy 372.125794 -279.365263) (xy 372.095268 -279.323247)
			(xy 372.07169 -279.276973) (xy 372.055642 -279.22758) (xy 372.047517 -279.176285) (xy 371.767861 -279.176285)
			(xy 371.759736 -279.22758) (xy 371.743688 -279.276973) (xy 371.72011 -279.323247) (xy 371.689584 -279.365263)
			(xy 371.652861 -279.401986) (xy 371.610845 -279.432512) (xy 371.564571 -279.45609) (xy 371.515178 -279.472138)
			(xy 371.463883 -279.480263) (xy 371.411949 -279.480263) (xy 371.360654 -279.472138) (xy 371.311261 -279.45609)
			(xy 371.264987 -279.432512) (xy 371.222971 -279.401986) (xy 371.186248 -279.365263) (xy 371.155722 -279.323247)
			(xy 371.132144 -279.276973) (xy 371.116096 -279.22758) (xy 371.107971 -279.176285) (xy 370.827807 -279.176285)
			(xy 370.819682 -279.22758) (xy 370.803634 -279.276973) (xy 370.780056 -279.323247) (xy 370.74953 -279.365263)
			(xy 370.712807 -279.401986) (xy 370.670791 -279.432512) (xy 370.624517 -279.45609) (xy 370.575124 -279.472138)
			(xy 370.523829 -279.480263) (xy 370.471895 -279.480263) (xy 370.4206 -279.472138) (xy 370.371207 -279.45609)
			(xy 370.324933 -279.432512) (xy 370.282917 -279.401986) (xy 370.246194 -279.365263) (xy 370.215668 -279.323247)
			(xy 370.19209 -279.276973) (xy 370.176042 -279.22758) (xy 370.167917 -279.176285) (xy 369.888007 -279.176285)
			(xy 369.879882 -279.22758) (xy 369.863834 -279.276973) (xy 369.840256 -279.323247) (xy 369.80973 -279.365263)
			(xy 369.773007 -279.401986) (xy 369.730991 -279.432512) (xy 369.684717 -279.45609) (xy 369.635324 -279.472138)
			(xy 369.584029 -279.480263) (xy 369.532095 -279.480263) (xy 369.4808 -279.472138) (xy 369.431407 -279.45609)
			(xy 369.385133 -279.432512) (xy 369.343117 -279.401986) (xy 369.306394 -279.365263) (xy 369.275868 -279.323247)
			(xy 369.25229 -279.276973) (xy 369.236242 -279.22758) (xy 369.228117 -279.176285) (xy 368.948461 -279.176285)
			(xy 368.940336 -279.22758) (xy 368.924288 -279.276973) (xy 368.90071 -279.323247) (xy 368.870184 -279.365263)
			(xy 368.833461 -279.401986) (xy 368.791445 -279.432512) (xy 368.745171 -279.45609) (xy 368.695778 -279.472138)
			(xy 368.644483 -279.480263) (xy 368.592549 -279.480263) (xy 368.541254 -279.472138) (xy 368.491861 -279.45609)
			(xy 368.445587 -279.432512) (xy 368.403571 -279.401986) (xy 368.366848 -279.365263) (xy 368.336322 -279.323247)
			(xy 368.312744 -279.276973) (xy 368.296696 -279.22758) (xy 368.288571 -279.176285) (xy 368.008407 -279.176285)
			(xy 368.000282 -279.22758) (xy 367.984234 -279.276973) (xy 367.960656 -279.323247) (xy 367.93013 -279.365263)
			(xy 367.893407 -279.401986) (xy 367.851391 -279.432512) (xy 367.805117 -279.45609) (xy 367.755724 -279.472138)
			(xy 367.704429 -279.480263) (xy 367.652495 -279.480263) (xy 367.6012 -279.472138) (xy 367.551807 -279.45609)
			(xy 367.505533 -279.432512) (xy 367.463517 -279.401986) (xy 367.426794 -279.365263) (xy 367.396268 -279.323247)
			(xy 367.37269 -279.276973) (xy 367.356642 -279.22758) (xy 367.348517 -279.176285) (xy 366.129061 -279.176285)
			(xy 366.120936 -279.22758) (xy 366.104888 -279.276973) (xy 366.08131 -279.323247) (xy 366.050784 -279.365263)
			(xy 366.014061 -279.401986) (xy 365.972045 -279.432512) (xy 365.925771 -279.45609) (xy 365.876378 -279.472138)
			(xy 365.825083 -279.480263) (xy 365.773149 -279.480263) (xy 365.721854 -279.472138) (xy 365.672461 -279.45609)
			(xy 365.626187 -279.432512) (xy 365.584171 -279.401986) (xy 365.547448 -279.365263) (xy 365.516922 -279.323247)
			(xy 365.493344 -279.276973) (xy 365.477296 -279.22758) (xy 365.469171 -279.176285) (xy 365.189221 -279.176285)
			(xy 365.181136 -279.227326) (xy 365.165088 -279.276719) (xy 365.14151 -279.322993) (xy 365.110984 -279.365009)
			(xy 365.074261 -279.401732) (xy 365.032245 -279.432258) (xy 364.985971 -279.455836) (xy 364.936578 -279.471884)
			(xy 364.885283 -279.480009) (xy 364.833349 -279.480009) (xy 364.782054 -279.471884) (xy 364.732661 -279.455836)
			(xy 364.686387 -279.432258) (xy 364.644371 -279.401732) (xy 364.607648 -279.365009) (xy 364.577122 -279.322993)
			(xy 364.553544 -279.276719) (xy 364.537496 -279.227326) (xy 364.529371 -279.176031) (xy 364.249202 -279.176031)
			(xy 364.249174 -279.177415) (xy 364.240326 -279.23088) (xy 364.222853 -279.282179) (xy 364.197226 -279.32993)
			(xy 364.181136 -279.35174) (xy 364.181136 -279.545542) (xy 364.181671 -279.560995) (xy 364.190902 -279.59049)
			(xy 364.208535 -279.615871) (xy 364.232955 -279.634813) (xy 364.261924 -279.645581) (xy 364.292787 -279.647187)
			(xy 364.307882 -279.64384) (xy 364.327803 -279.6391) (xy 364.368434 -279.633999) (xy 364.388908 -279.63368)
			(xy 364.389416 -279.63368) (xy 364.41538 -279.63419) (xy 364.466668 -279.642316) (xy 364.516053 -279.658364)
			(xy 364.56232 -279.68194) (xy 364.604329 -279.712464) (xy 364.641047 -279.749183) (xy 364.671568 -279.791194)
			(xy 364.695142 -279.837462) (xy 364.711188 -279.886848) (xy 364.719311 -279.938136) (xy 364.719311 -279.990064)
			(xy 364.719305 -279.990101) (xy 365.938817 -279.990101) (xy 365.938817 -279.938167) (xy 365.946942 -279.886872)
			(xy 365.96299 -279.837479) (xy 365.986568 -279.791205) (xy 366.017094 -279.749189) (xy 366.053817 -279.712466)
			(xy 366.095833 -279.68194) (xy 366.142107 -279.658362) (xy 366.1915 -279.642314) (xy 366.242795 -279.634189)
			(xy 366.294729 -279.634189) (xy 366.346024 -279.642314) (xy 366.395417 -279.658362) (xy 366.441691 -279.68194)
			(xy 366.483707 -279.712466) (xy 366.52043 -279.749189) (xy 366.550956 -279.791205) (xy 366.574534 -279.837479)
			(xy 366.590582 -279.886872) (xy 366.598707 -279.938167) (xy 366.599216 -279.964134) (xy 366.598707 -279.990101)
			(xy 366.878871 -279.990101) (xy 366.878871 -279.938167) (xy 366.886996 -279.886872) (xy 366.903044 -279.837479)
			(xy 366.926622 -279.791205) (xy 366.957148 -279.749189) (xy 366.993871 -279.712466) (xy 367.035887 -279.68194)
			(xy 367.082161 -279.658362) (xy 367.131554 -279.642314) (xy 367.182849 -279.634189) (xy 367.234783 -279.634189)
			(xy 367.286078 -279.642314) (xy 367.335471 -279.658362) (xy 367.381745 -279.68194) (xy 367.423761 -279.712466)
			(xy 367.460484 -279.749189) (xy 367.49101 -279.791205) (xy 367.514588 -279.837479) (xy 367.530636 -279.886872)
			(xy 367.538761 -279.938167) (xy 367.53927 -279.964134) (xy 367.538761 -279.990101) (xy 367.818671 -279.990101)
			(xy 367.818671 -279.938167) (xy 367.826796 -279.886872) (xy 367.842844 -279.837479) (xy 367.866422 -279.791205)
			(xy 367.896948 -279.749189) (xy 367.933671 -279.712466) (xy 367.975687 -279.68194) (xy 368.021961 -279.658362)
			(xy 368.071354 -279.642314) (xy 368.122649 -279.634189) (xy 368.174583 -279.634189) (xy 368.225878 -279.642314)
			(xy 368.275271 -279.658362) (xy 368.321545 -279.68194) (xy 368.363561 -279.712466) (xy 368.400284 -279.749189)
			(xy 368.43081 -279.791205) (xy 368.454388 -279.837479) (xy 368.470436 -279.886872) (xy 368.478561 -279.938167)
			(xy 368.47907 -279.964134) (xy 368.478561 -279.990101) (xy 368.758471 -279.990101) (xy 368.758471 -279.938167)
			(xy 368.766596 -279.886872) (xy 368.782644 -279.837479) (xy 368.806222 -279.791205) (xy 368.836748 -279.749189)
			(xy 368.873471 -279.712466) (xy 368.915487 -279.68194) (xy 368.961761 -279.658362) (xy 369.011154 -279.642314)
			(xy 369.062449 -279.634189) (xy 369.114383 -279.634189) (xy 369.165678 -279.642314) (xy 369.215071 -279.658362)
			(xy 369.261345 -279.68194) (xy 369.303361 -279.712466) (xy 369.340084 -279.749189) (xy 369.37061 -279.791205)
			(xy 369.394188 -279.837479) (xy 369.410236 -279.886872) (xy 369.418361 -279.938167) (xy 369.41887 -279.964134)
			(xy 369.418361 -279.990101) (xy 370.638071 -279.990101) (xy 370.638071 -279.938167) (xy 370.646196 -279.886872)
			(xy 370.662244 -279.837479) (xy 370.685822 -279.791205) (xy 370.716348 -279.749189) (xy 370.753071 -279.712466)
			(xy 370.795087 -279.68194) (xy 370.841361 -279.658362) (xy 370.890754 -279.642314) (xy 370.942049 -279.634189)
			(xy 370.993983 -279.634189) (xy 371.045278 -279.642314) (xy 371.094671 -279.658362) (xy 371.140945 -279.68194)
			(xy 371.182961 -279.712466) (xy 371.219684 -279.749189) (xy 371.25021 -279.791205) (xy 371.273788 -279.837479)
			(xy 371.289836 -279.886872) (xy 371.297961 -279.938167) (xy 371.29847 -279.964134) (xy 371.297961 -279.990101)
			(xy 371.577617 -279.990101) (xy 371.577617 -279.938167) (xy 371.585742 -279.886872) (xy 371.60179 -279.837479)
			(xy 371.625368 -279.791205) (xy 371.655894 -279.749189) (xy 371.692617 -279.712466) (xy 371.734633 -279.68194)
			(xy 371.780907 -279.658362) (xy 371.8303 -279.642314) (xy 371.881595 -279.634189) (xy 371.933529 -279.634189)
			(xy 371.984824 -279.642314) (xy 372.034217 -279.658362) (xy 372.080491 -279.68194) (xy 372.122507 -279.712466)
			(xy 372.15923 -279.749189) (xy 372.189756 -279.791205) (xy 372.213334 -279.837479) (xy 372.229382 -279.886872)
			(xy 372.237507 -279.938167) (xy 372.238016 -279.964134) (xy 372.237507 -279.990101) (xy 372.517671 -279.990101)
			(xy 372.517671 -279.938167) (xy 372.525796 -279.886872) (xy 372.541844 -279.837479) (xy 372.565422 -279.791205)
			(xy 372.595948 -279.749189) (xy 372.632671 -279.712466) (xy 372.674687 -279.68194) (xy 372.720961 -279.658362)
			(xy 372.770354 -279.642314) (xy 372.821649 -279.634189) (xy 372.873583 -279.634189) (xy 372.924878 -279.642314)
			(xy 372.974271 -279.658362) (xy 373.020545 -279.68194) (xy 373.062561 -279.712466) (xy 373.099284 -279.749189)
			(xy 373.12981 -279.791205) (xy 373.153388 -279.837479) (xy 373.169436 -279.886872) (xy 373.177561 -279.938167)
			(xy 373.17807 -279.964134) (xy 373.177561 -279.990101) (xy 373.457471 -279.990101) (xy 373.457471 -279.938167)
			(xy 373.465596 -279.886872) (xy 373.481644 -279.837479) (xy 373.505222 -279.791205) (xy 373.535748 -279.749189)
			(xy 373.572471 -279.712466) (xy 373.614487 -279.68194) (xy 373.660761 -279.658362) (xy 373.710154 -279.642314)
			(xy 373.761449 -279.634189) (xy 373.813383 -279.634189) (xy 373.864678 -279.642314) (xy 373.914071 -279.658362)
			(xy 373.960345 -279.68194) (xy 374.002361 -279.712466) (xy 374.039084 -279.749189) (xy 374.06961 -279.791205)
			(xy 374.093188 -279.837479) (xy 374.109236 -279.886872) (xy 374.117361 -279.938167) (xy 374.11787 -279.964134)
			(xy 374.117361 -279.990101) (xy 374.397017 -279.990101) (xy 374.397017 -279.938167) (xy 374.405142 -279.886872)
			(xy 374.42119 -279.837479) (xy 374.444768 -279.791205) (xy 374.475294 -279.749189) (xy 374.512017 -279.712466)
			(xy 374.554033 -279.68194) (xy 374.600307 -279.658362) (xy 374.6497 -279.642314) (xy 374.700995 -279.634189)
			(xy 374.752929 -279.634189) (xy 374.804224 -279.642314) (xy 374.853617 -279.658362) (xy 374.899891 -279.68194)
			(xy 374.941907 -279.712466) (xy 374.97863 -279.749189) (xy 375.009156 -279.791205) (xy 375.032734 -279.837479)
			(xy 375.048782 -279.886872) (xy 375.056907 -279.938167) (xy 375.057416 -279.964134) (xy 375.056907 -279.990101)
			(xy 375.337071 -279.990101) (xy 375.337071 -279.938167) (xy 375.345196 -279.886872) (xy 375.361244 -279.837479)
			(xy 375.384822 -279.791205) (xy 375.415348 -279.749189) (xy 375.452071 -279.712466) (xy 375.494087 -279.68194)
			(xy 375.540361 -279.658362) (xy 375.589754 -279.642314) (xy 375.641049 -279.634189) (xy 375.692983 -279.634189)
			(xy 375.744278 -279.642314) (xy 375.793671 -279.658362) (xy 375.839945 -279.68194) (xy 375.881961 -279.712466)
			(xy 375.918684 -279.749189) (xy 375.94921 -279.791205) (xy 375.972788 -279.837479) (xy 375.988836 -279.886872)
			(xy 375.996961 -279.938167) (xy 375.99747 -279.964134) (xy 375.996966 -279.989847) (xy 376.276617 -279.989847)
			(xy 376.276617 -279.937913) (xy 376.284742 -279.886618) (xy 376.30079 -279.837225) (xy 376.324368 -279.790951)
			(xy 376.354894 -279.748935) (xy 376.391617 -279.712212) (xy 376.433633 -279.681686) (xy 376.479907 -279.658108)
			(xy 376.5293 -279.64206) (xy 376.580595 -279.633935) (xy 376.632529 -279.633935) (xy 376.683824 -279.64206)
			(xy 376.733217 -279.658108) (xy 376.779491 -279.681686) (xy 376.821507 -279.712212) (xy 376.85823 -279.748935)
			(xy 376.888756 -279.790951) (xy 376.912334 -279.837225) (xy 376.928382 -279.886618) (xy 376.936507 -279.937913)
			(xy 376.937016 -279.96388) (xy 376.936507 -279.989847) (xy 376.936467 -279.990101) (xy 378.156471 -279.990101)
			(xy 378.156471 -279.938167) (xy 378.164596 -279.886872) (xy 378.180644 -279.837479) (xy 378.204222 -279.791205)
			(xy 378.234748 -279.749189) (xy 378.271471 -279.712466) (xy 378.313487 -279.68194) (xy 378.359761 -279.658362)
			(xy 378.409154 -279.642314) (xy 378.460449 -279.634189) (xy 378.512383 -279.634189) (xy 378.563678 -279.642314)
			(xy 378.613071 -279.658362) (xy 378.659345 -279.68194) (xy 378.701361 -279.712466) (xy 378.738084 -279.749189)
			(xy 378.76861 -279.791205) (xy 378.792188 -279.837479) (xy 378.808236 -279.886872) (xy 378.816361 -279.938167)
			(xy 378.81687 -279.964134) (xy 378.816361 -279.990101) (xy 379.096271 -279.990101) (xy 379.096271 -279.938167)
			(xy 379.104396 -279.886872) (xy 379.120444 -279.837479) (xy 379.144022 -279.791205) (xy 379.174548 -279.749189)
			(xy 379.211271 -279.712466) (xy 379.253287 -279.68194) (xy 379.299561 -279.658362) (xy 379.348954 -279.642314)
			(xy 379.400249 -279.634189) (xy 379.452183 -279.634189) (xy 379.503478 -279.642314) (xy 379.552871 -279.658362)
			(xy 379.599145 -279.68194) (xy 379.641161 -279.712466) (xy 379.677884 -279.749189) (xy 379.70841 -279.791205)
			(xy 379.731988 -279.837479) (xy 379.748036 -279.886872) (xy 379.756161 -279.938167) (xy 379.75667 -279.964134)
			(xy 379.756161 -279.990101) (xy 379.748036 -280.041396) (xy 379.731988 -280.090789) (xy 379.70841 -280.137063)
			(xy 379.677884 -280.179079) (xy 379.641161 -280.215802) (xy 379.599145 -280.246328) (xy 379.552871 -280.269906)
			(xy 379.503478 -280.285954) (xy 379.452183 -280.294079) (xy 379.400249 -280.294079) (xy 379.348954 -280.285954)
			(xy 379.299561 -280.269906) (xy 379.253287 -280.246328) (xy 379.211271 -280.215802) (xy 379.174548 -280.179079)
			(xy 379.144022 -280.137063) (xy 379.120444 -280.090789) (xy 379.104396 -280.041396) (xy 379.096271 -279.990101)
			(xy 378.816361 -279.990101) (xy 378.808236 -280.041396) (xy 378.792188 -280.090789) (xy 378.76861 -280.137063)
			(xy 378.738084 -280.179079) (xy 378.701361 -280.215802) (xy 378.659345 -280.246328) (xy 378.613071 -280.269906)
			(xy 378.563678 -280.285954) (xy 378.512383 -280.294079) (xy 378.460449 -280.294079) (xy 378.409154 -280.285954)
			(xy 378.359761 -280.269906) (xy 378.313487 -280.246328) (xy 378.271471 -280.215802) (xy 378.234748 -280.179079)
			(xy 378.204222 -280.137063) (xy 378.180644 -280.090789) (xy 378.164596 -280.041396) (xy 378.156471 -279.990101)
			(xy 376.936467 -279.990101) (xy 376.928382 -280.041142) (xy 376.912334 -280.090535) (xy 376.888756 -280.136809)
			(xy 376.85823 -280.178825) (xy 376.821507 -280.215548) (xy 376.779491 -280.246074) (xy 376.733217 -280.269652)
			(xy 376.683824 -280.2857) (xy 376.632529 -280.293825) (xy 376.580595 -280.293825) (xy 376.5293 -280.2857)
			(xy 376.479907 -280.269652) (xy 376.433633 -280.246074) (xy 376.391617 -280.215548) (xy 376.354894 -280.178825)
			(xy 376.324368 -280.136809) (xy 376.30079 -280.090535) (xy 376.284742 -280.041142) (xy 376.276617 -279.989847)
			(xy 375.996966 -279.989847) (xy 375.996961 -279.990101) (xy 375.988836 -280.041396) (xy 375.972788 -280.090789)
			(xy 375.94921 -280.137063) (xy 375.918684 -280.179079) (xy 375.881961 -280.215802) (xy 375.839945 -280.246328)
			(xy 375.793671 -280.269906) (xy 375.744278 -280.285954) (xy 375.692983 -280.294079) (xy 375.641049 -280.294079)
			(xy 375.589754 -280.285954) (xy 375.540361 -280.269906) (xy 375.494087 -280.246328) (xy 375.452071 -280.215802)
			(xy 375.415348 -280.179079) (xy 375.384822 -280.137063) (xy 375.361244 -280.090789) (xy 375.345196 -280.041396)
			(xy 375.337071 -279.990101) (xy 375.056907 -279.990101) (xy 375.048782 -280.041396) (xy 375.032734 -280.090789)
			(xy 375.009156 -280.137063) (xy 374.97863 -280.179079) (xy 374.941907 -280.215802) (xy 374.899891 -280.246328)
			(xy 374.853617 -280.269906) (xy 374.804224 -280.285954) (xy 374.752929 -280.294079) (xy 374.700995 -280.294079)
			(xy 374.6497 -280.285954) (xy 374.600307 -280.269906) (xy 374.554033 -280.246328) (xy 374.512017 -280.215802)
			(xy 374.475294 -280.179079) (xy 374.444768 -280.137063) (xy 374.42119 -280.090789) (xy 374.405142 -280.041396)
			(xy 374.397017 -279.990101) (xy 374.117361 -279.990101) (xy 374.109236 -280.041396) (xy 374.093188 -280.090789)
			(xy 374.06961 -280.137063) (xy 374.039084 -280.179079) (xy 374.002361 -280.215802) (xy 373.960345 -280.246328)
			(xy 373.914071 -280.269906) (xy 373.864678 -280.285954) (xy 373.813383 -280.294079) (xy 373.761449 -280.294079)
			(xy 373.710154 -280.285954) (xy 373.660761 -280.269906) (xy 373.614487 -280.246328) (xy 373.572471 -280.215802)
			(xy 373.535748 -280.179079) (xy 373.505222 -280.137063) (xy 373.481644 -280.090789) (xy 373.465596 -280.041396)
			(xy 373.457471 -279.990101) (xy 373.177561 -279.990101) (xy 373.169436 -280.041396) (xy 373.153388 -280.090789)
			(xy 373.12981 -280.137063) (xy 373.099284 -280.179079) (xy 373.062561 -280.215802) (xy 373.020545 -280.246328)
			(xy 372.974271 -280.269906) (xy 372.924878 -280.285954) (xy 372.873583 -280.294079) (xy 372.821649 -280.294079)
			(xy 372.770354 -280.285954) (xy 372.720961 -280.269906) (xy 372.674687 -280.246328) (xy 372.632671 -280.215802)
			(xy 372.595948 -280.179079) (xy 372.565422 -280.137063) (xy 372.541844 -280.090789) (xy 372.525796 -280.041396)
			(xy 372.517671 -279.990101) (xy 372.237507 -279.990101) (xy 372.229382 -280.041396) (xy 372.213334 -280.090789)
			(xy 372.189756 -280.137063) (xy 372.15923 -280.179079) (xy 372.122507 -280.215802) (xy 372.080491 -280.246328)
			(xy 372.034217 -280.269906) (xy 371.984824 -280.285954) (xy 371.933529 -280.294079) (xy 371.881595 -280.294079)
			(xy 371.8303 -280.285954) (xy 371.780907 -280.269906) (xy 371.734633 -280.246328) (xy 371.692617 -280.215802)
			(xy 371.655894 -280.179079) (xy 371.625368 -280.137063) (xy 371.60179 -280.090789) (xy 371.585742 -280.041396)
			(xy 371.577617 -279.990101) (xy 371.297961 -279.990101) (xy 371.289836 -280.041396) (xy 371.273788 -280.090789)
			(xy 371.25021 -280.137063) (xy 371.219684 -280.179079) (xy 371.182961 -280.215802) (xy 371.140945 -280.246328)
			(xy 371.094671 -280.269906) (xy 371.045278 -280.285954) (xy 370.993983 -280.294079) (xy 370.942049 -280.294079)
			(xy 370.890754 -280.285954) (xy 370.841361 -280.269906) (xy 370.795087 -280.246328) (xy 370.753071 -280.215802)
			(xy 370.716348 -280.179079) (xy 370.685822 -280.137063) (xy 370.662244 -280.090789) (xy 370.646196 -280.041396)
			(xy 370.638071 -279.990101) (xy 369.418361 -279.990101) (xy 369.410236 -280.041396) (xy 369.394188 -280.090789)
			(xy 369.37061 -280.137063) (xy 369.340084 -280.179079) (xy 369.303361 -280.215802) (xy 369.261345 -280.246328)
			(xy 369.215071 -280.269906) (xy 369.165678 -280.285954) (xy 369.114383 -280.294079) (xy 369.062449 -280.294079)
			(xy 369.011154 -280.285954) (xy 368.961761 -280.269906) (xy 368.915487 -280.246328) (xy 368.873471 -280.215802)
			(xy 368.836748 -280.179079) (xy 368.806222 -280.137063) (xy 368.782644 -280.090789) (xy 368.766596 -280.041396)
			(xy 368.758471 -279.990101) (xy 368.478561 -279.990101) (xy 368.470436 -280.041396) (xy 368.454388 -280.090789)
			(xy 368.43081 -280.137063) (xy 368.400284 -280.179079) (xy 368.363561 -280.215802) (xy 368.321545 -280.246328)
			(xy 368.275271 -280.269906) (xy 368.225878 -280.285954) (xy 368.174583 -280.294079) (xy 368.122649 -280.294079)
			(xy 368.071354 -280.285954) (xy 368.021961 -280.269906) (xy 367.975687 -280.246328) (xy 367.933671 -280.215802)
			(xy 367.896948 -280.179079) (xy 367.866422 -280.137063) (xy 367.842844 -280.090789) (xy 367.826796 -280.041396)
			(xy 367.818671 -279.990101) (xy 367.538761 -279.990101) (xy 367.530636 -280.041396) (xy 367.514588 -280.090789)
			(xy 367.49101 -280.137063) (xy 367.460484 -280.179079) (xy 367.423761 -280.215802) (xy 367.381745 -280.246328)
			(xy 367.335471 -280.269906) (xy 367.286078 -280.285954) (xy 367.234783 -280.294079) (xy 367.182849 -280.294079)
			(xy 367.131554 -280.285954) (xy 367.082161 -280.269906) (xy 367.035887 -280.246328) (xy 366.993871 -280.215802)
			(xy 366.957148 -280.179079) (xy 366.926622 -280.137063) (xy 366.903044 -280.090789) (xy 366.886996 -280.041396)
			(xy 366.878871 -279.990101) (xy 366.598707 -279.990101) (xy 366.590582 -280.041396) (xy 366.574534 -280.090789)
			(xy 366.550956 -280.137063) (xy 366.52043 -280.179079) (xy 366.483707 -280.215802) (xy 366.441691 -280.246328)
			(xy 366.395417 -280.269906) (xy 366.346024 -280.285954) (xy 366.294729 -280.294079) (xy 366.242795 -280.294079)
			(xy 366.1915 -280.285954) (xy 366.142107 -280.269906) (xy 366.095833 -280.246328) (xy 366.053817 -280.215802)
			(xy 366.017094 -280.179079) (xy 365.986568 -280.137063) (xy 365.96299 -280.090789) (xy 365.946942 -280.041396)
			(xy 365.938817 -279.990101) (xy 364.719305 -279.990101) (xy 364.711188 -280.041352) (xy 364.695142 -280.090738)
			(xy 364.671568 -280.137006) (xy 364.641047 -280.179017) (xy 364.604329 -280.215736) (xy 364.56232 -280.24626)
			(xy 364.516053 -280.269836) (xy 364.466668 -280.285884) (xy 364.41538 -280.29401) (xy 364.389416 -280.294588)
			(xy 364.388908 -280.294588) (xy 364.368433 -280.294267) (xy 364.327801 -280.289176) (xy 364.307882 -280.284428)
			(xy 364.292791 -280.28114) (xy 364.261964 -280.282796) (xy 364.233036 -280.293577) (xy 364.208645 -280.312501)
			(xy 364.191013 -280.337843) (xy 364.181749 -280.367291) (xy 364.181136 -280.382726) (xy 364.181136 -280.576274)
			(xy 364.19493 -280.594795) (xy 364.217761 -280.634939) (xy 364.234778 -280.677871) (xy 364.240572 -280.700226)
			(xy 364.243874 -280.713942) (xy 364.356142 -280.82621) (xy 364.366832 -280.836238) (xy 364.392566 -280.850245)
			(xy 364.421218 -280.856366) (xy 364.450429 -280.854097) (xy 364.477793 -280.843625) (xy 364.501055 -280.825813)
			(xy 364.518301 -280.802127) (xy 364.528109 -280.774519) (xy 364.52937 -280.759916) (xy 364.531219 -280.734929)
			(xy 364.541512 -280.685895) (xy 364.55909 -280.638976) (xy 364.583549 -280.59525) (xy 364.614329 -280.555717)
			(xy 364.650725 -280.521284) (xy 364.691902 -280.49274) (xy 364.736916 -280.47074) (xy 364.784736 -280.455788)
			(xy 364.834265 -280.448226) (xy 364.859316 -280.44775) (xy 364.885282 -280.44826) (xy 364.936575 -280.456387)
			(xy 364.985965 -280.472437) (xy 365.032237 -280.496016) (xy 365.07425 -280.526542) (xy 365.110971 -280.563265)
			(xy 365.141495 -280.60528) (xy 365.165071 -280.651553) (xy 365.181118 -280.700944) (xy 365.189241 -280.752238)
			(xy 365.18977 -280.778204) (xy 365.189307 -280.803256) (xy 365.189167 -280.804171) (xy 365.469171 -280.804171)
			(xy 365.469171 -280.752237) (xy 365.477296 -280.700942) (xy 365.493344 -280.651549) (xy 365.516922 -280.605275)
			(xy 365.547448 -280.563259) (xy 365.584171 -280.526536) (xy 365.626187 -280.49601) (xy 365.672461 -280.472432)
			(xy 365.721854 -280.456384) (xy 365.773149 -280.448259) (xy 365.825083 -280.448259) (xy 365.876378 -280.456384)
			(xy 365.925771 -280.472432) (xy 365.972045 -280.49601) (xy 366.014061 -280.526536) (xy 366.050784 -280.563259)
			(xy 366.08131 -280.605275) (xy 366.104888 -280.651549) (xy 366.120936 -280.700942) (xy 366.129061 -280.752237)
			(xy 366.12957 -280.778204) (xy 366.129061 -280.804171) (xy 366.408717 -280.804171) (xy 366.408717 -280.752237)
			(xy 366.416842 -280.700942) (xy 366.43289 -280.651549) (xy 366.456468 -280.605275) (xy 366.486994 -280.563259)
			(xy 366.523717 -280.526536) (xy 366.565733 -280.49601) (xy 366.612007 -280.472432) (xy 366.6614 -280.456384)
			(xy 366.712695 -280.448259) (xy 366.764629 -280.448259) (xy 366.815924 -280.456384) (xy 366.865317 -280.472432)
			(xy 366.911591 -280.49601) (xy 366.953607 -280.526536) (xy 366.99033 -280.563259) (xy 367.020856 -280.605275)
			(xy 367.044434 -280.651549) (xy 367.060482 -280.700942) (xy 367.068607 -280.752237) (xy 367.069116 -280.778204)
			(xy 367.068607 -280.804171) (xy 367.348517 -280.804171) (xy 367.348517 -280.752237) (xy 367.356642 -280.700942)
			(xy 367.37269 -280.651549) (xy 367.396268 -280.605275) (xy 367.426794 -280.563259) (xy 367.463517 -280.526536)
			(xy 367.505533 -280.49601) (xy 367.551807 -280.472432) (xy 367.6012 -280.456384) (xy 367.652495 -280.448259)
			(xy 367.704429 -280.448259) (xy 367.755724 -280.456384) (xy 367.805117 -280.472432) (xy 367.851391 -280.49601)
			(xy 367.893407 -280.526536) (xy 367.93013 -280.563259) (xy 367.960656 -280.605275) (xy 367.984234 -280.651549)
			(xy 368.000282 -280.700942) (xy 368.008407 -280.752237) (xy 368.008916 -280.778204) (xy 368.008407 -280.804171)
			(xy 368.288317 -280.804171) (xy 368.288317 -280.752237) (xy 368.296442 -280.700942) (xy 368.31249 -280.651549)
			(xy 368.336068 -280.605275) (xy 368.366594 -280.563259) (xy 368.403317 -280.526536) (xy 368.445333 -280.49601)
			(xy 368.491607 -280.472432) (xy 368.541 -280.456384) (xy 368.592295 -280.448259) (xy 368.644229 -280.448259)
			(xy 368.695524 -280.456384) (xy 368.744917 -280.472432) (xy 368.791191 -280.49601) (xy 368.833207 -280.526536)
			(xy 368.86993 -280.563259) (xy 368.900456 -280.605275) (xy 368.924034 -280.651549) (xy 368.940082 -280.700942)
			(xy 368.948207 -280.752237) (xy 368.948716 -280.778204) (xy 368.948207 -280.804171) (xy 369.228117 -280.804171)
			(xy 369.228117 -280.752237) (xy 369.236242 -280.700942) (xy 369.25229 -280.651549) (xy 369.275868 -280.605275)
			(xy 369.306394 -280.563259) (xy 369.343117 -280.526536) (xy 369.385133 -280.49601) (xy 369.431407 -280.472432)
			(xy 369.4808 -280.456384) (xy 369.532095 -280.448259) (xy 369.584029 -280.448259) (xy 369.635324 -280.456384)
			(xy 369.684717 -280.472432) (xy 369.730991 -280.49601) (xy 369.773007 -280.526536) (xy 369.80973 -280.563259)
			(xy 369.840256 -280.605275) (xy 369.863834 -280.651549) (xy 369.879882 -280.700942) (xy 369.888007 -280.752237)
			(xy 369.888516 -280.778204) (xy 369.888007 -280.804171) (xy 370.167917 -280.804171) (xy 370.167917 -280.752237)
			(xy 370.176042 -280.700942) (xy 370.19209 -280.651549) (xy 370.215668 -280.605275) (xy 370.246194 -280.563259)
			(xy 370.282917 -280.526536) (xy 370.324933 -280.49601) (xy 370.371207 -280.472432) (xy 370.4206 -280.456384)
			(xy 370.471895 -280.448259) (xy 370.523829 -280.448259) (xy 370.575124 -280.456384) (xy 370.624517 -280.472432)
			(xy 370.670791 -280.49601) (xy 370.712807 -280.526536) (xy 370.74953 -280.563259) (xy 370.780056 -280.605275)
			(xy 370.803634 -280.651549) (xy 370.819682 -280.700942) (xy 370.827807 -280.752237) (xy 370.828316 -280.778204)
			(xy 370.827807 -280.804171) (xy 371.107717 -280.804171) (xy 371.107717 -280.752237) (xy 371.115842 -280.700942)
			(xy 371.13189 -280.651549) (xy 371.155468 -280.605275) (xy 371.185994 -280.563259) (xy 371.222717 -280.526536)
			(xy 371.264733 -280.49601) (xy 371.311007 -280.472432) (xy 371.3604 -280.456384) (xy 371.411695 -280.448259)
			(xy 371.463629 -280.448259) (xy 371.514924 -280.456384) (xy 371.564317 -280.472432) (xy 371.610591 -280.49601)
			(xy 371.652607 -280.526536) (xy 371.68933 -280.563259) (xy 371.719856 -280.605275) (xy 371.743434 -280.651549)
			(xy 371.759482 -280.700942) (xy 371.767607 -280.752237) (xy 371.768116 -280.778204) (xy 371.767607 -280.804171)
			(xy 372.047517 -280.804171) (xy 372.047517 -280.752237) (xy 372.055642 -280.700942) (xy 372.07169 -280.651549)
			(xy 372.095268 -280.605275) (xy 372.125794 -280.563259) (xy 372.162517 -280.526536) (xy 372.204533 -280.49601)
			(xy 372.250807 -280.472432) (xy 372.3002 -280.456384) (xy 372.351495 -280.448259) (xy 372.403429 -280.448259)
			(xy 372.454724 -280.456384) (xy 372.504117 -280.472432) (xy 372.550391 -280.49601) (xy 372.592407 -280.526536)
			(xy 372.62913 -280.563259) (xy 372.659656 -280.605275) (xy 372.683234 -280.651549) (xy 372.699282 -280.700942)
			(xy 372.707407 -280.752237) (xy 372.707916 -280.778204) (xy 372.707407 -280.804171) (xy 372.987317 -280.804171)
			(xy 372.987317 -280.752237) (xy 372.995442 -280.700942) (xy 373.01149 -280.651549) (xy 373.035068 -280.605275)
			(xy 373.065594 -280.563259) (xy 373.102317 -280.526536) (xy 373.144333 -280.49601) (xy 373.190607 -280.472432)
			(xy 373.24 -280.456384) (xy 373.291295 -280.448259) (xy 373.343229 -280.448259) (xy 373.394524 -280.456384)
			(xy 373.443917 -280.472432) (xy 373.490191 -280.49601) (xy 373.532207 -280.526536) (xy 373.56893 -280.563259)
			(xy 373.599456 -280.605275) (xy 373.623034 -280.651549) (xy 373.639082 -280.700942) (xy 373.647207 -280.752237)
			(xy 373.647716 -280.778204) (xy 373.647207 -280.804171) (xy 373.927371 -280.804171) (xy 373.927371 -280.752237)
			(xy 373.935496 -280.700942) (xy 373.951544 -280.651549) (xy 373.975122 -280.605275) (xy 374.005648 -280.563259)
			(xy 374.042371 -280.526536) (xy 374.084387 -280.49601) (xy 374.130661 -280.472432) (xy 374.180054 -280.456384)
			(xy 374.231349 -280.448259) (xy 374.283283 -280.448259) (xy 374.334578 -280.456384) (xy 374.383971 -280.472432)
			(xy 374.430245 -280.49601) (xy 374.472261 -280.526536) (xy 374.508984 -280.563259) (xy 374.53951 -280.605275)
			(xy 374.563088 -280.651549) (xy 374.579136 -280.700942) (xy 374.587261 -280.752237) (xy 374.58777 -280.778204)
			(xy 374.587261 -280.804171) (xy 374.867171 -280.804171) (xy 374.867171 -280.752237) (xy 374.875296 -280.700942)
			(xy 374.891344 -280.651549) (xy 374.914922 -280.605275) (xy 374.945448 -280.563259) (xy 374.982171 -280.526536)
			(xy 375.024187 -280.49601) (xy 375.070461 -280.472432) (xy 375.119854 -280.456384) (xy 375.171149 -280.448259)
			(xy 375.223083 -280.448259) (xy 375.274378 -280.456384) (xy 375.323771 -280.472432) (xy 375.370045 -280.49601)
			(xy 375.412061 -280.526536) (xy 375.448784 -280.563259) (xy 375.47931 -280.605275) (xy 375.502888 -280.651549)
			(xy 375.518936 -280.700942) (xy 375.527061 -280.752237) (xy 375.52757 -280.778204) (xy 375.527061 -280.804171)
			(xy 375.806971 -280.804171) (xy 375.806971 -280.752237) (xy 375.815096 -280.700942) (xy 375.831144 -280.651549)
			(xy 375.854722 -280.605275) (xy 375.885248 -280.563259) (xy 375.921971 -280.526536) (xy 375.963987 -280.49601)
			(xy 376.010261 -280.472432) (xy 376.059654 -280.456384) (xy 376.110949 -280.448259) (xy 376.162883 -280.448259)
			(xy 376.214178 -280.456384) (xy 376.263571 -280.472432) (xy 376.309845 -280.49601) (xy 376.351861 -280.526536)
			(xy 376.388584 -280.563259) (xy 376.41911 -280.605275) (xy 376.442688 -280.651549) (xy 376.458736 -280.700942)
			(xy 376.466861 -280.752237) (xy 376.46737 -280.778204) (xy 376.466861 -280.804171) (xy 376.746771 -280.804171)
			(xy 376.746771 -280.752237) (xy 376.754896 -280.700942) (xy 376.770944 -280.651549) (xy 376.794522 -280.605275)
			(xy 376.825048 -280.563259) (xy 376.861771 -280.526536) (xy 376.903787 -280.49601) (xy 376.950061 -280.472432)
			(xy 376.999454 -280.456384) (xy 377.050749 -280.448259) (xy 377.102683 -280.448259) (xy 377.153978 -280.456384)
			(xy 377.203371 -280.472432) (xy 377.249645 -280.49601) (xy 377.291661 -280.526536) (xy 377.328384 -280.563259)
			(xy 377.35891 -280.605275) (xy 377.382488 -280.651549) (xy 377.398536 -280.700942) (xy 377.406661 -280.752237)
			(xy 377.40717 -280.778204) (xy 377.406661 -280.804171) (xy 377.686571 -280.804171) (xy 377.686571 -280.752237)
			(xy 377.694696 -280.700942) (xy 377.710744 -280.651549) (xy 377.734322 -280.605275) (xy 377.764848 -280.563259)
			(xy 377.801571 -280.526536) (xy 377.843587 -280.49601) (xy 377.889861 -280.472432) (xy 377.939254 -280.456384)
			(xy 377.990549 -280.448259) (xy 378.042483 -280.448259) (xy 378.093778 -280.456384) (xy 378.143171 -280.472432)
			(xy 378.189445 -280.49601) (xy 378.231461 -280.526536) (xy 378.268184 -280.563259) (xy 378.29871 -280.605275)
			(xy 378.322288 -280.651549) (xy 378.338336 -280.700942) (xy 378.346461 -280.752237) (xy 378.34697 -280.778204)
			(xy 378.346461 -280.804171) (xy 378.626117 -280.804171) (xy 378.626117 -280.752237) (xy 378.634242 -280.700942)
			(xy 378.65029 -280.651549) (xy 378.673868 -280.605275) (xy 378.704394 -280.563259) (xy 378.741117 -280.526536)
			(xy 378.783133 -280.49601) (xy 378.829407 -280.472432) (xy 378.8788 -280.456384) (xy 378.930095 -280.448259)
			(xy 378.982029 -280.448259) (xy 379.033324 -280.456384) (xy 379.082717 -280.472432) (xy 379.128991 -280.49601)
			(xy 379.171007 -280.526536) (xy 379.20773 -280.563259) (xy 379.238256 -280.605275) (xy 379.261834 -280.651549)
			(xy 379.277882 -280.700942) (xy 379.286007 -280.752237) (xy 379.286516 -280.778204) (xy 379.286007 -280.804171)
			(xy 379.565917 -280.804171) (xy 379.565917 -280.752237) (xy 379.574042 -280.700942) (xy 379.59009 -280.651549)
			(xy 379.613668 -280.605275) (xy 379.644194 -280.563259) (xy 379.680917 -280.526536) (xy 379.722933 -280.49601)
			(xy 379.769207 -280.472432) (xy 379.8186 -280.456384) (xy 379.869895 -280.448259) (xy 379.921829 -280.448259)
			(xy 379.973124 -280.456384) (xy 380.022517 -280.472432) (xy 380.068791 -280.49601) (xy 380.110807 -280.526536)
			(xy 380.14753 -280.563259) (xy 380.178056 -280.605275) (xy 380.201634 -280.651549) (xy 380.217682 -280.700942)
			(xy 380.225807 -280.752237) (xy 380.226316 -280.778204) (xy 380.225807 -280.804171) (xy 380.217682 -280.855466)
			(xy 380.201634 -280.904859) (xy 380.178056 -280.951133) (xy 380.14753 -280.993149) (xy 380.110807 -281.029872)
			(xy 380.068791 -281.060398) (xy 380.022517 -281.083976) (xy 379.973124 -281.100024) (xy 379.921829 -281.108149)
			(xy 379.869895 -281.108149) (xy 379.8186 -281.100024) (xy 379.769207 -281.083976) (xy 379.722933 -281.060398)
			(xy 379.680917 -281.029872) (xy 379.644194 -280.993149) (xy 379.613668 -280.951133) (xy 379.59009 -280.904859)
			(xy 379.574042 -280.855466) (xy 379.565917 -280.804171) (xy 379.286007 -280.804171) (xy 379.277882 -280.855466)
			(xy 379.261834 -280.904859) (xy 379.238256 -280.951133) (xy 379.20773 -280.993149) (xy 379.171007 -281.029872)
			(xy 379.128991 -281.060398) (xy 379.082717 -281.083976) (xy 379.033324 -281.100024) (xy 378.982029 -281.108149)
			(xy 378.930095 -281.108149) (xy 378.8788 -281.100024) (xy 378.829407 -281.083976) (xy 378.783133 -281.060398)
			(xy 378.741117 -281.029872) (xy 378.704394 -280.993149) (xy 378.673868 -280.951133) (xy 378.65029 -280.904859)
			(xy 378.634242 -280.855466) (xy 378.626117 -280.804171) (xy 378.346461 -280.804171) (xy 378.338336 -280.855466)
			(xy 378.322288 -280.904859) (xy 378.29871 -280.951133) (xy 378.268184 -280.993149) (xy 378.231461 -281.029872)
			(xy 378.189445 -281.060398) (xy 378.143171 -281.083976) (xy 378.093778 -281.100024) (xy 378.042483 -281.108149)
			(xy 377.990549 -281.108149) (xy 377.939254 -281.100024) (xy 377.889861 -281.083976) (xy 377.843587 -281.060398)
			(xy 377.801571 -281.029872) (xy 377.764848 -280.993149) (xy 377.734322 -280.951133) (xy 377.710744 -280.904859)
			(xy 377.694696 -280.855466) (xy 377.686571 -280.804171) (xy 377.406661 -280.804171) (xy 377.398536 -280.855466)
			(xy 377.382488 -280.904859) (xy 377.35891 -280.951133) (xy 377.328384 -280.993149) (xy 377.291661 -281.029872)
			(xy 377.249645 -281.060398) (xy 377.203371 -281.083976) (xy 377.153978 -281.100024) (xy 377.102683 -281.108149)
			(xy 377.050749 -281.108149) (xy 376.999454 -281.100024) (xy 376.950061 -281.083976) (xy 376.903787 -281.060398)
			(xy 376.861771 -281.029872) (xy 376.825048 -280.993149) (xy 376.794522 -280.951133) (xy 376.770944 -280.904859)
			(xy 376.754896 -280.855466) (xy 376.746771 -280.804171) (xy 376.466861 -280.804171) (xy 376.458736 -280.855466)
			(xy 376.442688 -280.904859) (xy 376.41911 -280.951133) (xy 376.388584 -280.993149) (xy 376.351861 -281.029872)
			(xy 376.309845 -281.060398) (xy 376.263571 -281.083976) (xy 376.214178 -281.100024) (xy 376.162883 -281.108149)
			(xy 376.110949 -281.108149) (xy 376.059654 -281.100024) (xy 376.010261 -281.083976) (xy 375.963987 -281.060398)
			(xy 375.921971 -281.029872) (xy 375.885248 -280.993149) (xy 375.854722 -280.951133) (xy 375.831144 -280.904859)
			(xy 375.815096 -280.855466) (xy 375.806971 -280.804171) (xy 375.527061 -280.804171) (xy 375.518936 -280.855466)
			(xy 375.502888 -280.904859) (xy 375.47931 -280.951133) (xy 375.448784 -280.993149) (xy 375.412061 -281.029872)
			(xy 375.370045 -281.060398) (xy 375.323771 -281.083976) (xy 375.274378 -281.100024) (xy 375.223083 -281.108149)
			(xy 375.171149 -281.108149) (xy 375.119854 -281.100024) (xy 375.070461 -281.083976) (xy 375.024187 -281.060398)
			(xy 374.982171 -281.029872) (xy 374.945448 -280.993149) (xy 374.914922 -280.951133) (xy 374.891344 -280.904859)
			(xy 374.875296 -280.855466) (xy 374.867171 -280.804171) (xy 374.587261 -280.804171) (xy 374.579136 -280.855466)
			(xy 374.563088 -280.904859) (xy 374.53951 -280.951133) (xy 374.508984 -280.993149) (xy 374.472261 -281.029872)
			(xy 374.430245 -281.060398) (xy 374.383971 -281.083976) (xy 374.334578 -281.100024) (xy 374.283283 -281.108149)
			(xy 374.231349 -281.108149) (xy 374.180054 -281.100024) (xy 374.130661 -281.083976) (xy 374.084387 -281.060398)
			(xy 374.042371 -281.029872) (xy 374.005648 -280.993149) (xy 373.975122 -280.951133) (xy 373.951544 -280.904859)
			(xy 373.935496 -280.855466) (xy 373.927371 -280.804171) (xy 373.647207 -280.804171) (xy 373.639082 -280.855466)
			(xy 373.623034 -280.904859) (xy 373.599456 -280.951133) (xy 373.56893 -280.993149) (xy 373.532207 -281.029872)
			(xy 373.490191 -281.060398) (xy 373.443917 -281.083976) (xy 373.394524 -281.100024) (xy 373.343229 -281.108149)
			(xy 373.291295 -281.108149) (xy 373.24 -281.100024) (xy 373.190607 -281.083976) (xy 373.144333 -281.060398)
			(xy 373.102317 -281.029872) (xy 373.065594 -280.993149) (xy 373.035068 -280.951133) (xy 373.01149 -280.904859)
			(xy 372.995442 -280.855466) (xy 372.987317 -280.804171) (xy 372.707407 -280.804171) (xy 372.699282 -280.855466)
			(xy 372.683234 -280.904859) (xy 372.659656 -280.951133) (xy 372.62913 -280.993149) (xy 372.592407 -281.029872)
			(xy 372.550391 -281.060398) (xy 372.504117 -281.083976) (xy 372.454724 -281.100024) (xy 372.403429 -281.108149)
			(xy 372.351495 -281.108149) (xy 372.3002 -281.100024) (xy 372.250807 -281.083976) (xy 372.204533 -281.060398)
			(xy 372.162517 -281.029872) (xy 372.125794 -280.993149) (xy 372.095268 -280.951133) (xy 372.07169 -280.904859)
			(xy 372.055642 -280.855466) (xy 372.047517 -280.804171) (xy 371.767607 -280.804171) (xy 371.759482 -280.855466)
			(xy 371.743434 -280.904859) (xy 371.719856 -280.951133) (xy 371.68933 -280.993149) (xy 371.652607 -281.029872)
			(xy 371.610591 -281.060398) (xy 371.564317 -281.083976) (xy 371.514924 -281.100024) (xy 371.463629 -281.108149)
			(xy 371.411695 -281.108149) (xy 371.3604 -281.100024) (xy 371.311007 -281.083976) (xy 371.264733 -281.060398)
			(xy 371.222717 -281.029872) (xy 371.185994 -280.993149) (xy 371.155468 -280.951133) (xy 371.13189 -280.904859)
			(xy 371.115842 -280.855466) (xy 371.107717 -280.804171) (xy 370.827807 -280.804171) (xy 370.819682 -280.855466)
			(xy 370.803634 -280.904859) (xy 370.780056 -280.951133) (xy 370.74953 -280.993149) (xy 370.712807 -281.029872)
			(xy 370.670791 -281.060398) (xy 370.624517 -281.083976) (xy 370.575124 -281.100024) (xy 370.523829 -281.108149)
			(xy 370.471895 -281.108149) (xy 370.4206 -281.100024) (xy 370.371207 -281.083976) (xy 370.324933 -281.060398)
			(xy 370.282917 -281.029872) (xy 370.246194 -280.993149) (xy 370.215668 -280.951133) (xy 370.19209 -280.904859)
			(xy 370.176042 -280.855466) (xy 370.167917 -280.804171) (xy 369.888007 -280.804171) (xy 369.879882 -280.855466)
			(xy 369.863834 -280.904859) (xy 369.840256 -280.951133) (xy 369.80973 -280.993149) (xy 369.773007 -281.029872)
			(xy 369.730991 -281.060398) (xy 369.684717 -281.083976) (xy 369.635324 -281.100024) (xy 369.584029 -281.108149)
			(xy 369.532095 -281.108149) (xy 369.4808 -281.100024) (xy 369.431407 -281.083976) (xy 369.385133 -281.060398)
			(xy 369.343117 -281.029872) (xy 369.306394 -280.993149) (xy 369.275868 -280.951133) (xy 369.25229 -280.904859)
			(xy 369.236242 -280.855466) (xy 369.228117 -280.804171) (xy 368.948207 -280.804171) (xy 368.940082 -280.855466)
			(xy 368.924034 -280.904859) (xy 368.900456 -280.951133) (xy 368.86993 -280.993149) (xy 368.833207 -281.029872)
			(xy 368.791191 -281.060398) (xy 368.744917 -281.083976) (xy 368.695524 -281.100024) (xy 368.644229 -281.108149)
			(xy 368.592295 -281.108149) (xy 368.541 -281.100024) (xy 368.491607 -281.083976) (xy 368.445333 -281.060398)
			(xy 368.403317 -281.029872) (xy 368.366594 -280.993149) (xy 368.336068 -280.951133) (xy 368.31249 -280.904859)
			(xy 368.296442 -280.855466) (xy 368.288317 -280.804171) (xy 368.008407 -280.804171) (xy 368.000282 -280.855466)
			(xy 367.984234 -280.904859) (xy 367.960656 -280.951133) (xy 367.93013 -280.993149) (xy 367.893407 -281.029872)
			(xy 367.851391 -281.060398) (xy 367.805117 -281.083976) (xy 367.755724 -281.100024) (xy 367.704429 -281.108149)
			(xy 367.652495 -281.108149) (xy 367.6012 -281.100024) (xy 367.551807 -281.083976) (xy 367.505533 -281.060398)
			(xy 367.463517 -281.029872) (xy 367.426794 -280.993149) (xy 367.396268 -280.951133) (xy 367.37269 -280.904859)
			(xy 367.356642 -280.855466) (xy 367.348517 -280.804171) (xy 367.068607 -280.804171) (xy 367.060482 -280.855466)
			(xy 367.044434 -280.904859) (xy 367.020856 -280.951133) (xy 366.99033 -280.993149) (xy 366.953607 -281.029872)
			(xy 366.911591 -281.060398) (xy 366.865317 -281.083976) (xy 366.815924 -281.100024) (xy 366.764629 -281.108149)
			(xy 366.712695 -281.108149) (xy 366.6614 -281.100024) (xy 366.612007 -281.083976) (xy 366.565733 -281.060398)
			(xy 366.523717 -281.029872) (xy 366.486994 -280.993149) (xy 366.456468 -280.951133) (xy 366.43289 -280.904859)
			(xy 366.416842 -280.855466) (xy 366.408717 -280.804171) (xy 366.129061 -280.804171) (xy 366.120936 -280.855466)
			(xy 366.104888 -280.904859) (xy 366.08131 -280.951133) (xy 366.050784 -280.993149) (xy 366.014061 -281.029872)
			(xy 365.972045 -281.060398) (xy 365.925771 -281.083976) (xy 365.876378 -281.100024) (xy 365.825083 -281.108149)
			(xy 365.773149 -281.108149) (xy 365.721854 -281.100024) (xy 365.672461 -281.083976) (xy 365.626187 -281.060398)
			(xy 365.584171 -281.029872) (xy 365.547448 -280.993149) (xy 365.516922 -280.951133) (xy 365.493344 -280.904859)
			(xy 365.477296 -280.855466) (xy 365.469171 -280.804171) (xy 365.189167 -280.804171) (xy 365.181742 -280.852786)
			(xy 365.166788 -280.900606) (xy 365.144786 -280.945621) (xy 365.116241 -280.986799) (xy 365.081807 -281.023195)
			(xy 365.042274 -281.053977) (xy 364.998546 -281.078438) (xy 364.951628 -281.096017) (xy 364.902593 -281.106313)
			(xy 364.877604 -281.10815) (xy 364.863024 -281.109448) (xy 364.835473 -281.1193) (xy 364.811843 -281.136556)
			(xy 364.794073 -281.1598) (xy 364.783618 -281.187128) (xy 364.781336 -281.216299) (xy 364.787414 -281.24492)
			(xy 364.801355 -281.270645) (xy 364.81131 -281.281378) (xy 364.9218 -281.391868) (xy 364.932163 -281.401593)
			(xy 364.956992 -281.415395) (xy 364.984667 -281.421805) (xy 365.013036 -281.420327) (xy 365.039894 -281.411074)
			(xy 365.063155 -281.394767) (xy 365.072422 -281.383994) (xy 365.088203 -281.365222) (xy 365.124364 -281.332097)
			(xy 365.165025 -281.304682) (xy 365.209292 -281.283581) (xy 365.256193 -281.269256) (xy 365.304696 -281.262023)
			(xy 365.329216 -281.261566) (xy 365.355184 -281.26205) (xy 365.40648 -281.270177) (xy 365.455873 -281.286229)
			(xy 365.502147 -281.30981) (xy 365.544162 -281.340339) (xy 365.580885 -281.377065) (xy 365.611409 -281.419084)
			(xy 365.634985 -281.46536) (xy 365.651031 -281.514755) (xy 365.659153 -281.566052) (xy 365.65967 -281.59202)
			(xy 365.659223 -281.616539) (xy 365.659007 -281.617987) (xy 365.938817 -281.617987) (xy 365.938817 -281.566053)
			(xy 365.946942 -281.514758) (xy 365.96299 -281.465365) (xy 365.986568 -281.419091) (xy 366.017094 -281.377075)
			(xy 366.053817 -281.340352) (xy 366.095833 -281.309826) (xy 366.142107 -281.286248) (xy 366.1915 -281.2702)
			(xy 366.242795 -281.262075) (xy 366.294729 -281.262075) (xy 366.346024 -281.2702) (xy 366.395417 -281.286248)
			(xy 366.441691 -281.309826) (xy 366.483707 -281.340352) (xy 366.52043 -281.377075) (xy 366.550956 -281.419091)
			(xy 366.574534 -281.465365) (xy 366.590582 -281.514758) (xy 366.598707 -281.566053) (xy 366.599216 -281.59202)
			(xy 366.598707 -281.617987) (xy 366.878871 -281.617987) (xy 366.878871 -281.566053) (xy 366.886996 -281.514758)
			(xy 366.903044 -281.465365) (xy 366.926622 -281.419091) (xy 366.957148 -281.377075) (xy 366.993871 -281.340352)
			(xy 367.035887 -281.309826) (xy 367.082161 -281.286248) (xy 367.131554 -281.2702) (xy 367.182849 -281.262075)
			(xy 367.234783 -281.262075) (xy 367.286078 -281.2702) (xy 367.335471 -281.286248) (xy 367.381745 -281.309826)
			(xy 367.423761 -281.340352) (xy 367.460484 -281.377075) (xy 367.49101 -281.419091) (xy 367.514588 -281.465365)
			(xy 367.530636 -281.514758) (xy 367.538761 -281.566053) (xy 367.53927 -281.59202) (xy 367.538761 -281.617987)
			(xy 367.818671 -281.617987) (xy 367.818671 -281.566053) (xy 367.826796 -281.514758) (xy 367.842844 -281.465365)
			(xy 367.866422 -281.419091) (xy 367.896948 -281.377075) (xy 367.933671 -281.340352) (xy 367.975687 -281.309826)
			(xy 368.021961 -281.286248) (xy 368.071354 -281.2702) (xy 368.122649 -281.262075) (xy 368.174583 -281.262075)
			(xy 368.225878 -281.2702) (xy 368.275271 -281.286248) (xy 368.321545 -281.309826) (xy 368.363561 -281.340352)
			(xy 368.400284 -281.377075) (xy 368.43081 -281.419091) (xy 368.454388 -281.465365) (xy 368.470436 -281.514758)
			(xy 368.478561 -281.566053) (xy 368.47907 -281.59202) (xy 368.478561 -281.617987) (xy 368.758471 -281.617987)
			(xy 368.758471 -281.566053) (xy 368.766596 -281.514758) (xy 368.782644 -281.465365) (xy 368.806222 -281.419091)
			(xy 368.836748 -281.377075) (xy 368.873471 -281.340352) (xy 368.915487 -281.309826) (xy 368.961761 -281.286248)
			(xy 369.011154 -281.2702) (xy 369.062449 -281.262075) (xy 369.114383 -281.262075) (xy 369.165678 -281.2702)
			(xy 369.215071 -281.286248) (xy 369.261345 -281.309826) (xy 369.303361 -281.340352) (xy 369.340084 -281.377075)
			(xy 369.37061 -281.419091) (xy 369.394188 -281.465365) (xy 369.410236 -281.514758) (xy 369.418361 -281.566053)
			(xy 369.41887 -281.59202) (xy 369.418361 -281.617987) (xy 369.698271 -281.617987) (xy 369.698271 -281.566053)
			(xy 369.706396 -281.514758) (xy 369.722444 -281.465365) (xy 369.746022 -281.419091) (xy 369.776548 -281.377075)
			(xy 369.813271 -281.340352) (xy 369.855287 -281.309826) (xy 369.901561 -281.286248) (xy 369.950954 -281.2702)
			(xy 370.002249 -281.262075) (xy 370.054183 -281.262075) (xy 370.105478 -281.2702) (xy 370.154871 -281.286248)
			(xy 370.201145 -281.309826) (xy 370.243161 -281.340352) (xy 370.279884 -281.377075) (xy 370.31041 -281.419091)
			(xy 370.333988 -281.465365) (xy 370.350036 -281.514758) (xy 370.358161 -281.566053) (xy 370.35867 -281.59202)
			(xy 370.358161 -281.617987) (xy 370.638071 -281.617987) (xy 370.638071 -281.566053) (xy 370.646196 -281.514758)
			(xy 370.662244 -281.465365) (xy 370.685822 -281.419091) (xy 370.716348 -281.377075) (xy 370.753071 -281.340352)
			(xy 370.795087 -281.309826) (xy 370.841361 -281.286248) (xy 370.890754 -281.2702) (xy 370.942049 -281.262075)
			(xy 370.993983 -281.262075) (xy 371.045278 -281.2702) (xy 371.094671 -281.286248) (xy 371.140945 -281.309826)
			(xy 371.182961 -281.340352) (xy 371.219684 -281.377075) (xy 371.25021 -281.419091) (xy 371.273788 -281.465365)
			(xy 371.289836 -281.514758) (xy 371.297961 -281.566053) (xy 371.29847 -281.59202) (xy 371.297961 -281.617987)
			(xy 371.577871 -281.617987) (xy 371.577871 -281.566053) (xy 371.585996 -281.514758) (xy 371.602044 -281.465365)
			(xy 371.625622 -281.419091) (xy 371.656148 -281.377075) (xy 371.692871 -281.340352) (xy 371.734887 -281.309826)
			(xy 371.781161 -281.286248) (xy 371.830554 -281.2702) (xy 371.881849 -281.262075) (xy 371.933783 -281.262075)
			(xy 371.985078 -281.2702) (xy 372.034471 -281.286248) (xy 372.080745 -281.309826) (xy 372.122761 -281.340352)
			(xy 372.159484 -281.377075) (xy 372.19001 -281.419091) (xy 372.213588 -281.465365) (xy 372.229636 -281.514758)
			(xy 372.237761 -281.566053) (xy 372.23827 -281.59202) (xy 372.237761 -281.617987) (xy 372.517671 -281.617987)
			(xy 372.517671 -281.566053) (xy 372.525796 -281.514758) (xy 372.541844 -281.465365) (xy 372.565422 -281.419091)
			(xy 372.595948 -281.377075) (xy 372.632671 -281.340352) (xy 372.674687 -281.309826) (xy 372.720961 -281.286248)
			(xy 372.770354 -281.2702) (xy 372.821649 -281.262075) (xy 372.873583 -281.262075) (xy 372.924878 -281.2702)
			(xy 372.974271 -281.286248) (xy 373.020545 -281.309826) (xy 373.062561 -281.340352) (xy 373.099284 -281.377075)
			(xy 373.12981 -281.419091) (xy 373.153388 -281.465365) (xy 373.169436 -281.514758) (xy 373.177561 -281.566053)
			(xy 373.17807 -281.59202) (xy 373.177561 -281.617987) (xy 373.457471 -281.617987) (xy 373.457471 -281.566053)
			(xy 373.465596 -281.514758) (xy 373.481644 -281.465365) (xy 373.505222 -281.419091) (xy 373.535748 -281.377075)
			(xy 373.572471 -281.340352) (xy 373.614487 -281.309826) (xy 373.660761 -281.286248) (xy 373.710154 -281.2702)
			(xy 373.761449 -281.262075) (xy 373.813383 -281.262075) (xy 373.864678 -281.2702) (xy 373.914071 -281.286248)
			(xy 373.960345 -281.309826) (xy 374.002361 -281.340352) (xy 374.039084 -281.377075) (xy 374.06961 -281.419091)
			(xy 374.093188 -281.465365) (xy 374.109236 -281.514758) (xy 374.117361 -281.566053) (xy 374.11787 -281.59202)
			(xy 374.117361 -281.617987) (xy 374.397017 -281.617987) (xy 374.397017 -281.566053) (xy 374.405142 -281.514758)
			(xy 374.42119 -281.465365) (xy 374.444768 -281.419091) (xy 374.475294 -281.377075) (xy 374.512017 -281.340352)
			(xy 374.554033 -281.309826) (xy 374.600307 -281.286248) (xy 374.6497 -281.2702) (xy 374.700995 -281.262075)
			(xy 374.752929 -281.262075) (xy 374.804224 -281.2702) (xy 374.853617 -281.286248) (xy 374.899891 -281.309826)
			(xy 374.941907 -281.340352) (xy 374.97863 -281.377075) (xy 375.009156 -281.419091) (xy 375.032734 -281.465365)
			(xy 375.048782 -281.514758) (xy 375.056907 -281.566053) (xy 375.057416 -281.59202) (xy 375.056912 -281.617733)
			(xy 375.336817 -281.617733) (xy 375.336817 -281.565799) (xy 375.344942 -281.514504) (xy 375.36099 -281.465111)
			(xy 375.384568 -281.418837) (xy 375.415094 -281.376821) (xy 375.451817 -281.340098) (xy 375.493833 -281.309572)
			(xy 375.540107 -281.285994) (xy 375.5895 -281.269946) (xy 375.640795 -281.261821) (xy 375.692729 -281.261821)
			(xy 375.744024 -281.269946) (xy 375.793417 -281.285994) (xy 375.839691 -281.309572) (xy 375.881707 -281.340098)
			(xy 375.91843 -281.376821) (xy 375.948956 -281.418837) (xy 375.972534 -281.465111) (xy 375.988582 -281.514504)
			(xy 375.996707 -281.565799) (xy 375.997216 -281.591766) (xy 375.996707 -281.617733) (xy 375.996667 -281.617987)
			(xy 376.276871 -281.617987) (xy 376.276871 -281.566053) (xy 376.284996 -281.514758) (xy 376.301044 -281.465365)
			(xy 376.324622 -281.419091) (xy 376.355148 -281.377075) (xy 376.391871 -281.340352) (xy 376.433887 -281.309826)
			(xy 376.480161 -281.286248) (xy 376.529554 -281.2702) (xy 376.580849 -281.262075) (xy 376.632783 -281.262075)
			(xy 376.684078 -281.2702) (xy 376.733471 -281.286248) (xy 376.779745 -281.309826) (xy 376.821761 -281.340352)
			(xy 376.858484 -281.377075) (xy 376.88901 -281.419091) (xy 376.912588 -281.465365) (xy 376.928636 -281.514758)
			(xy 376.936761 -281.566053) (xy 376.93727 -281.59202) (xy 376.936761 -281.617987) (xy 377.216417 -281.617987)
			(xy 377.216417 -281.566053) (xy 377.224542 -281.514758) (xy 377.24059 -281.465365) (xy 377.264168 -281.419091)
			(xy 377.294694 -281.377075) (xy 377.331417 -281.340352) (xy 377.373433 -281.309826) (xy 377.419707 -281.286248)
			(xy 377.4691 -281.2702) (xy 377.520395 -281.262075) (xy 377.572329 -281.262075) (xy 377.623624 -281.2702)
			(xy 377.673017 -281.286248) (xy 377.719291 -281.309826) (xy 377.761307 -281.340352) (xy 377.79803 -281.377075)
			(xy 377.828556 -281.419091) (xy 377.852134 -281.465365) (xy 377.868182 -281.514758) (xy 377.876307 -281.566053)
			(xy 377.876816 -281.59202) (xy 377.876307 -281.617987) (xy 378.156471 -281.617987) (xy 378.156471 -281.566053)
			(xy 378.164596 -281.514758) (xy 378.180644 -281.465365) (xy 378.204222 -281.419091) (xy 378.234748 -281.377075)
			(xy 378.271471 -281.340352) (xy 378.313487 -281.309826) (xy 378.359761 -281.286248) (xy 378.409154 -281.2702)
			(xy 378.460449 -281.262075) (xy 378.512383 -281.262075) (xy 378.563678 -281.2702) (xy 378.613071 -281.286248)
			(xy 378.659345 -281.309826) (xy 378.701361 -281.340352) (xy 378.738084 -281.377075) (xy 378.76861 -281.419091)
			(xy 378.792188 -281.465365) (xy 378.808236 -281.514758) (xy 378.816361 -281.566053) (xy 378.81687 -281.59202)
			(xy 378.816361 -281.617987) (xy 379.096271 -281.617987) (xy 379.096271 -281.566053) (xy 379.104396 -281.514758)
			(xy 379.120444 -281.465365) (xy 379.144022 -281.419091) (xy 379.174548 -281.377075) (xy 379.211271 -281.340352)
			(xy 379.253287 -281.309826) (xy 379.299561 -281.286248) (xy 379.348954 -281.2702) (xy 379.400249 -281.262075)
			(xy 379.452183 -281.262075) (xy 379.503478 -281.2702) (xy 379.552871 -281.286248) (xy 379.599145 -281.309826)
			(xy 379.641161 -281.340352) (xy 379.677884 -281.377075) (xy 379.70841 -281.419091) (xy 379.731988 -281.465365)
			(xy 379.748036 -281.514758) (xy 379.756161 -281.566053) (xy 379.75667 -281.59202) (xy 379.756161 -281.617987)
			(xy 380.036071 -281.617987) (xy 380.036071 -281.566053) (xy 380.044196 -281.514758) (xy 380.060244 -281.465365)
			(xy 380.083822 -281.419091) (xy 380.114348 -281.377075) (xy 380.151071 -281.340352) (xy 380.193087 -281.309826)
			(xy 380.239361 -281.286248) (xy 380.288754 -281.2702) (xy 380.340049 -281.262075) (xy 380.391983 -281.262075)
			(xy 380.443278 -281.2702) (xy 380.492671 -281.286248) (xy 380.538945 -281.309826) (xy 380.580961 -281.340352)
			(xy 380.617684 -281.377075) (xy 380.64821 -281.419091) (xy 380.671788 -281.465365) (xy 380.687836 -281.514758)
			(xy 380.695961 -281.566053) (xy 380.69647 -281.59202) (xy 380.695961 -281.617987) (xy 380.975871 -281.617987)
			(xy 380.975871 -281.566053) (xy 380.983996 -281.514758) (xy 381.000044 -281.465365) (xy 381.023622 -281.419091)
			(xy 381.054148 -281.377075) (xy 381.090871 -281.340352) (xy 381.132887 -281.309826) (xy 381.179161 -281.286248)
			(xy 381.228554 -281.2702) (xy 381.279849 -281.262075) (xy 381.331783 -281.262075) (xy 381.383078 -281.2702)
			(xy 381.432471 -281.286248) (xy 381.478745 -281.309826) (xy 381.520761 -281.340352) (xy 381.557484 -281.377075)
			(xy 381.58801 -281.419091) (xy 381.611588 -281.465365) (xy 381.627636 -281.514758) (xy 381.635761 -281.566053)
			(xy 381.63627 -281.59202) (xy 381.635761 -281.617987) (xy 381.915671 -281.617987) (xy 381.915671 -281.566053)
			(xy 381.923796 -281.514758) (xy 381.939844 -281.465365) (xy 381.963422 -281.419091) (xy 381.993948 -281.377075)
			(xy 382.030671 -281.340352) (xy 382.072687 -281.309826) (xy 382.118961 -281.286248) (xy 382.168354 -281.2702)
			(xy 382.219649 -281.262075) (xy 382.271583 -281.262075) (xy 382.322878 -281.2702) (xy 382.372271 -281.286248)
			(xy 382.418545 -281.309826) (xy 382.460561 -281.340352) (xy 382.497284 -281.377075) (xy 382.52781 -281.419091)
			(xy 382.551388 -281.465365) (xy 382.567436 -281.514758) (xy 382.575561 -281.566053) (xy 382.57607 -281.59202)
			(xy 382.575561 -281.617987) (xy 382.855217 -281.617987) (xy 382.855217 -281.566053) (xy 382.863342 -281.514758)
			(xy 382.87939 -281.465365) (xy 382.902968 -281.419091) (xy 382.933494 -281.377075) (xy 382.970217 -281.340352)
			(xy 383.012233 -281.309826) (xy 383.058507 -281.286248) (xy 383.1079 -281.2702) (xy 383.159195 -281.262075)
			(xy 383.211129 -281.262075) (xy 383.262424 -281.2702) (xy 383.311817 -281.286248) (xy 383.358091 -281.309826)
			(xy 383.400107 -281.340352) (xy 383.43683 -281.377075) (xy 383.467356 -281.419091) (xy 383.490934 -281.465365)
			(xy 383.506982 -281.514758) (xy 383.515107 -281.566053) (xy 383.515616 -281.59202) (xy 383.515107 -281.617987)
			(xy 383.795017 -281.617987) (xy 383.795017 -281.566053) (xy 383.803142 -281.514758) (xy 383.81919 -281.465365)
			(xy 383.842768 -281.419091) (xy 383.873294 -281.377075) (xy 383.910017 -281.340352) (xy 383.952033 -281.309826)
			(xy 383.998307 -281.286248) (xy 384.0477 -281.2702) (xy 384.098995 -281.262075) (xy 384.150929 -281.262075)
			(xy 384.202224 -281.2702) (xy 384.251617 -281.286248) (xy 384.297891 -281.309826) (xy 384.339907 -281.340352)
			(xy 384.37663 -281.377075) (xy 384.407156 -281.419091) (xy 384.430734 -281.465365) (xy 384.446782 -281.514758)
			(xy 384.454907 -281.566053) (xy 384.455416 -281.59202) (xy 384.454907 -281.617987) (xy 384.734817 -281.617987)
			(xy 384.734817 -281.566053) (xy 384.742942 -281.514758) (xy 384.75899 -281.465365) (xy 384.782568 -281.419091)
			(xy 384.813094 -281.377075) (xy 384.849817 -281.340352) (xy 384.891833 -281.309826) (xy 384.938107 -281.286248)
			(xy 384.9875 -281.2702) (xy 385.038795 -281.262075) (xy 385.090729 -281.262075) (xy 385.142024 -281.2702)
			(xy 385.191417 -281.286248) (xy 385.237691 -281.309826) (xy 385.279707 -281.340352) (xy 385.31643 -281.377075)
			(xy 385.346956 -281.419091) (xy 385.370534 -281.465365) (xy 385.386582 -281.514758) (xy 385.394707 -281.566053)
			(xy 385.395216 -281.59202) (xy 385.394707 -281.617987) (xy 385.386582 -281.669282) (xy 385.370534 -281.718675)
			(xy 385.346956 -281.764949) (xy 385.31643 -281.806965) (xy 385.279707 -281.843688) (xy 385.237691 -281.874214)
			(xy 385.191417 -281.897792) (xy 385.142024 -281.91384) (xy 385.090729 -281.921965) (xy 385.038795 -281.921965)
			(xy 384.9875 -281.91384) (xy 384.938107 -281.897792) (xy 384.891833 -281.874214) (xy 384.849817 -281.843688)
			(xy 384.813094 -281.806965) (xy 384.782568 -281.764949) (xy 384.75899 -281.718675) (xy 384.742942 -281.669282)
			(xy 384.734817 -281.617987) (xy 384.454907 -281.617987) (xy 384.446782 -281.669282) (xy 384.430734 -281.718675)
			(xy 384.407156 -281.764949) (xy 384.37663 -281.806965) (xy 384.339907 -281.843688) (xy 384.297891 -281.874214)
			(xy 384.251617 -281.897792) (xy 384.202224 -281.91384) (xy 384.150929 -281.921965) (xy 384.098995 -281.921965)
			(xy 384.0477 -281.91384) (xy 383.998307 -281.897792) (xy 383.952033 -281.874214) (xy 383.910017 -281.843688)
			(xy 383.873294 -281.806965) (xy 383.842768 -281.764949) (xy 383.81919 -281.718675) (xy 383.803142 -281.669282)
			(xy 383.795017 -281.617987) (xy 383.515107 -281.617987) (xy 383.506982 -281.669282) (xy 383.490934 -281.718675)
			(xy 383.467356 -281.764949) (xy 383.43683 -281.806965) (xy 383.400107 -281.843688) (xy 383.358091 -281.874214)
			(xy 383.311817 -281.897792) (xy 383.262424 -281.91384) (xy 383.211129 -281.921965) (xy 383.159195 -281.921965)
			(xy 383.1079 -281.91384) (xy 383.058507 -281.897792) (xy 383.012233 -281.874214) (xy 382.970217 -281.843688)
			(xy 382.933494 -281.806965) (xy 382.902968 -281.764949) (xy 382.87939 -281.718675) (xy 382.863342 -281.669282)
			(xy 382.855217 -281.617987) (xy 382.575561 -281.617987) (xy 382.567436 -281.669282) (xy 382.551388 -281.718675)
			(xy 382.52781 -281.764949) (xy 382.497284 -281.806965) (xy 382.460561 -281.843688) (xy 382.418545 -281.874214)
			(xy 382.372271 -281.897792) (xy 382.322878 -281.91384) (xy 382.271583 -281.921965) (xy 382.219649 -281.921965)
			(xy 382.168354 -281.91384) (xy 382.118961 -281.897792) (xy 382.072687 -281.874214) (xy 382.030671 -281.843688)
			(xy 381.993948 -281.806965) (xy 381.963422 -281.764949) (xy 381.939844 -281.718675) (xy 381.923796 -281.669282)
			(xy 381.915671 -281.617987) (xy 381.635761 -281.617987) (xy 381.627636 -281.669282) (xy 381.611588 -281.718675)
			(xy 381.58801 -281.764949) (xy 381.557484 -281.806965) (xy 381.520761 -281.843688) (xy 381.478745 -281.874214)
			(xy 381.432471 -281.897792) (xy 381.383078 -281.91384) (xy 381.331783 -281.921965) (xy 381.279849 -281.921965)
			(xy 381.228554 -281.91384) (xy 381.179161 -281.897792) (xy 381.132887 -281.874214) (xy 381.090871 -281.843688)
			(xy 381.054148 -281.806965) (xy 381.023622 -281.764949) (xy 381.000044 -281.718675) (xy 380.983996 -281.669282)
			(xy 380.975871 -281.617987) (xy 380.695961 -281.617987) (xy 380.687836 -281.669282) (xy 380.671788 -281.718675)
			(xy 380.64821 -281.764949) (xy 380.617684 -281.806965) (xy 380.580961 -281.843688) (xy 380.538945 -281.874214)
			(xy 380.492671 -281.897792) (xy 380.443278 -281.91384) (xy 380.391983 -281.921965) (xy 380.340049 -281.921965)
			(xy 380.288754 -281.91384) (xy 380.239361 -281.897792) (xy 380.193087 -281.874214) (xy 380.151071 -281.843688)
			(xy 380.114348 -281.806965) (xy 380.083822 -281.764949) (xy 380.060244 -281.718675) (xy 380.044196 -281.669282)
			(xy 380.036071 -281.617987) (xy 379.756161 -281.617987) (xy 379.748036 -281.669282) (xy 379.731988 -281.718675)
			(xy 379.70841 -281.764949) (xy 379.677884 -281.806965) (xy 379.641161 -281.843688) (xy 379.599145 -281.874214)
			(xy 379.552871 -281.897792) (xy 379.503478 -281.91384) (xy 379.452183 -281.921965) (xy 379.400249 -281.921965)
			(xy 379.348954 -281.91384) (xy 379.299561 -281.897792) (xy 379.253287 -281.874214) (xy 379.211271 -281.843688)
			(xy 379.174548 -281.806965) (xy 379.144022 -281.764949) (xy 379.120444 -281.718675) (xy 379.104396 -281.669282)
			(xy 379.096271 -281.617987) (xy 378.816361 -281.617987) (xy 378.808236 -281.669282) (xy 378.792188 -281.718675)
			(xy 378.76861 -281.764949) (xy 378.738084 -281.806965) (xy 378.701361 -281.843688) (xy 378.659345 -281.874214)
			(xy 378.613071 -281.897792) (xy 378.563678 -281.91384) (xy 378.512383 -281.921965) (xy 378.460449 -281.921965)
			(xy 378.409154 -281.91384) (xy 378.359761 -281.897792) (xy 378.313487 -281.874214) (xy 378.271471 -281.843688)
			(xy 378.234748 -281.806965) (xy 378.204222 -281.764949) (xy 378.180644 -281.718675) (xy 378.164596 -281.669282)
			(xy 378.156471 -281.617987) (xy 377.876307 -281.617987) (xy 377.868182 -281.669282) (xy 377.852134 -281.718675)
			(xy 377.828556 -281.764949) (xy 377.79803 -281.806965) (xy 377.761307 -281.843688) (xy 377.719291 -281.874214)
			(xy 377.673017 -281.897792) (xy 377.623624 -281.91384) (xy 377.572329 -281.921965) (xy 377.520395 -281.921965)
			(xy 377.4691 -281.91384) (xy 377.419707 -281.897792) (xy 377.373433 -281.874214) (xy 377.331417 -281.843688)
			(xy 377.294694 -281.806965) (xy 377.264168 -281.764949) (xy 377.24059 -281.718675) (xy 377.224542 -281.669282)
			(xy 377.216417 -281.617987) (xy 376.936761 -281.617987) (xy 376.928636 -281.669282) (xy 376.912588 -281.718675)
			(xy 376.88901 -281.764949) (xy 376.858484 -281.806965) (xy 376.821761 -281.843688) (xy 376.779745 -281.874214)
			(xy 376.733471 -281.897792) (xy 376.684078 -281.91384) (xy 376.632783 -281.921965) (xy 376.580849 -281.921965)
			(xy 376.529554 -281.91384) (xy 376.480161 -281.897792) (xy 376.433887 -281.874214) (xy 376.391871 -281.843688)
			(xy 376.355148 -281.806965) (xy 376.324622 -281.764949) (xy 376.301044 -281.718675) (xy 376.284996 -281.669282)
			(xy 376.276871 -281.617987) (xy 375.996667 -281.617987) (xy 375.988582 -281.669028) (xy 375.972534 -281.718421)
			(xy 375.948956 -281.764695) (xy 375.91843 -281.806711) (xy 375.881707 -281.843434) (xy 375.839691 -281.87396)
			(xy 375.793417 -281.897538) (xy 375.744024 -281.913586) (xy 375.692729 -281.921711) (xy 375.640795 -281.921711)
			(xy 375.5895 -281.913586) (xy 375.540107 -281.897538) (xy 375.493833 -281.87396) (xy 375.451817 -281.843434)
			(xy 375.415094 -281.806711) (xy 375.384568 -281.764695) (xy 375.36099 -281.718421) (xy 375.344942 -281.669028)
			(xy 375.336817 -281.617733) (xy 375.056912 -281.617733) (xy 375.056907 -281.617987) (xy 375.048782 -281.669282)
			(xy 375.032734 -281.718675) (xy 375.009156 -281.764949) (xy 374.97863 -281.806965) (xy 374.941907 -281.843688)
			(xy 374.899891 -281.874214) (xy 374.853617 -281.897792) (xy 374.804224 -281.91384) (xy 374.752929 -281.921965)
			(xy 374.700995 -281.921965) (xy 374.6497 -281.91384) (xy 374.600307 -281.897792) (xy 374.554033 -281.874214)
			(xy 374.512017 -281.843688) (xy 374.475294 -281.806965) (xy 374.444768 -281.764949) (xy 374.42119 -281.718675)
			(xy 374.405142 -281.669282) (xy 374.397017 -281.617987) (xy 374.117361 -281.617987) (xy 374.109236 -281.669282)
			(xy 374.093188 -281.718675) (xy 374.06961 -281.764949) (xy 374.039084 -281.806965) (xy 374.002361 -281.843688)
			(xy 373.960345 -281.874214) (xy 373.914071 -281.897792) (xy 373.864678 -281.91384) (xy 373.813383 -281.921965)
			(xy 373.761449 -281.921965) (xy 373.710154 -281.91384) (xy 373.660761 -281.897792) (xy 373.614487 -281.874214)
			(xy 373.572471 -281.843688) (xy 373.535748 -281.806965) (xy 373.505222 -281.764949) (xy 373.481644 -281.718675)
			(xy 373.465596 -281.669282) (xy 373.457471 -281.617987) (xy 373.177561 -281.617987) (xy 373.169436 -281.669282)
			(xy 373.153388 -281.718675) (xy 373.12981 -281.764949) (xy 373.099284 -281.806965) (xy 373.062561 -281.843688)
			(xy 373.020545 -281.874214) (xy 372.974271 -281.897792) (xy 372.924878 -281.91384) (xy 372.873583 -281.921965)
			(xy 372.821649 -281.921965) (xy 372.770354 -281.91384) (xy 372.720961 -281.897792) (xy 372.674687 -281.874214)
			(xy 372.632671 -281.843688) (xy 372.595948 -281.806965) (xy 372.565422 -281.764949) (xy 372.541844 -281.718675)
			(xy 372.525796 -281.669282) (xy 372.517671 -281.617987) (xy 372.237761 -281.617987) (xy 372.229636 -281.669282)
			(xy 372.213588 -281.718675) (xy 372.19001 -281.764949) (xy 372.159484 -281.806965) (xy 372.122761 -281.843688)
			(xy 372.080745 -281.874214) (xy 372.034471 -281.897792) (xy 371.985078 -281.91384) (xy 371.933783 -281.921965)
			(xy 371.881849 -281.921965) (xy 371.830554 -281.91384) (xy 371.781161 -281.897792) (xy 371.734887 -281.874214)
			(xy 371.692871 -281.843688) (xy 371.656148 -281.806965) (xy 371.625622 -281.764949) (xy 371.602044 -281.718675)
			(xy 371.585996 -281.669282) (xy 371.577871 -281.617987) (xy 371.297961 -281.617987) (xy 371.289836 -281.669282)
			(xy 371.273788 -281.718675) (xy 371.25021 -281.764949) (xy 371.219684 -281.806965) (xy 371.182961 -281.843688)
			(xy 371.140945 -281.874214) (xy 371.094671 -281.897792) (xy 371.045278 -281.91384) (xy 370.993983 -281.921965)
			(xy 370.942049 -281.921965) (xy 370.890754 -281.91384) (xy 370.841361 -281.897792) (xy 370.795087 -281.874214)
			(xy 370.753071 -281.843688) (xy 370.716348 -281.806965) (xy 370.685822 -281.764949) (xy 370.662244 -281.718675)
			(xy 370.646196 -281.669282) (xy 370.638071 -281.617987) (xy 370.358161 -281.617987) (xy 370.350036 -281.669282)
			(xy 370.333988 -281.718675) (xy 370.31041 -281.764949) (xy 370.279884 -281.806965) (xy 370.243161 -281.843688)
			(xy 370.201145 -281.874214) (xy 370.154871 -281.897792) (xy 370.105478 -281.91384) (xy 370.054183 -281.921965)
			(xy 370.002249 -281.921965) (xy 369.950954 -281.91384) (xy 369.901561 -281.897792) (xy 369.855287 -281.874214)
			(xy 369.813271 -281.843688) (xy 369.776548 -281.806965) (xy 369.746022 -281.764949) (xy 369.722444 -281.718675)
			(xy 369.706396 -281.669282) (xy 369.698271 -281.617987) (xy 369.418361 -281.617987) (xy 369.410236 -281.669282)
			(xy 369.394188 -281.718675) (xy 369.37061 -281.764949) (xy 369.340084 -281.806965) (xy 369.303361 -281.843688)
			(xy 369.261345 -281.874214) (xy 369.215071 -281.897792) (xy 369.165678 -281.91384) (xy 369.114383 -281.921965)
			(xy 369.062449 -281.921965) (xy 369.011154 -281.91384) (xy 368.961761 -281.897792) (xy 368.915487 -281.874214)
			(xy 368.873471 -281.843688) (xy 368.836748 -281.806965) (xy 368.806222 -281.764949) (xy 368.782644 -281.718675)
			(xy 368.766596 -281.669282) (xy 368.758471 -281.617987) (xy 368.478561 -281.617987) (xy 368.470436 -281.669282)
			(xy 368.454388 -281.718675) (xy 368.43081 -281.764949) (xy 368.400284 -281.806965) (xy 368.363561 -281.843688)
			(xy 368.321545 -281.874214) (xy 368.275271 -281.897792) (xy 368.225878 -281.91384) (xy 368.174583 -281.921965)
			(xy 368.122649 -281.921965) (xy 368.071354 -281.91384) (xy 368.021961 -281.897792) (xy 367.975687 -281.874214)
			(xy 367.933671 -281.843688) (xy 367.896948 -281.806965) (xy 367.866422 -281.764949) (xy 367.842844 -281.718675)
			(xy 367.826796 -281.669282) (xy 367.818671 -281.617987) (xy 367.538761 -281.617987) (xy 367.530636 -281.669282)
			(xy 367.514588 -281.718675) (xy 367.49101 -281.764949) (xy 367.460484 -281.806965) (xy 367.423761 -281.843688)
			(xy 367.381745 -281.874214) (xy 367.335471 -281.897792) (xy 367.286078 -281.91384) (xy 367.234783 -281.921965)
			(xy 367.182849 -281.921965) (xy 367.131554 -281.91384) (xy 367.082161 -281.897792) (xy 367.035887 -281.874214)
			(xy 366.993871 -281.843688) (xy 366.957148 -281.806965) (xy 366.926622 -281.764949) (xy 366.903044 -281.718675)
			(xy 366.886996 -281.669282) (xy 366.878871 -281.617987) (xy 366.598707 -281.617987) (xy 366.590582 -281.669282)
			(xy 366.574534 -281.718675) (xy 366.550956 -281.764949) (xy 366.52043 -281.806965) (xy 366.483707 -281.843688)
			(xy 366.441691 -281.874214) (xy 366.395417 -281.897792) (xy 366.346024 -281.91384) (xy 366.294729 -281.921965)
			(xy 366.242795 -281.921965) (xy 366.1915 -281.91384) (xy 366.142107 -281.897792) (xy 366.095833 -281.874214)
			(xy 366.053817 -281.843688) (xy 366.017094 -281.806965) (xy 365.986568 -281.764949) (xy 365.96299 -281.718675)
			(xy 365.946942 -281.669282) (xy 365.938817 -281.617987) (xy 365.659007 -281.617987) (xy 365.651975 -281.665039)
			(xy 365.637643 -281.711936) (xy 365.616539 -281.756201) (xy 365.589127 -281.796863) (xy 365.55601 -281.833029)
			(xy 365.537242 -281.848814) (xy 365.526538 -281.858134) (xy 365.51031 -281.881406) (xy 365.5011 -281.90824)
			(xy 365.499617 -281.936572) (xy 365.505975 -281.964221) (xy 365.519685 -281.98906) (xy 365.529368 -281.999436)
			(xy 365.642652 -282.11272) (xy 365.673894 -282.10002) (xy 365.703921 -282.088547) (xy 365.766981 -282.076134)
			(xy 365.799116 -282.075382) (xy 365.825083 -282.075866) (xy 365.876379 -282.083993) (xy 365.925771 -282.100045)
			(xy 365.972043 -282.123626) (xy 366.014057 -282.154156) (xy 366.050778 -282.190882) (xy 366.081301 -282.232901)
			(xy 366.104875 -282.279177) (xy 366.120919 -282.328572) (xy 366.129038 -282.379868) (xy 366.12957 -282.405836)
			(xy 366.128951 -282.431803) (xy 366.408717 -282.431803) (xy 366.408717 -282.379869) (xy 366.416842 -282.328574)
			(xy 366.43289 -282.279181) (xy 366.456468 -282.232907) (xy 366.486994 -282.190891) (xy 366.523717 -282.154168)
			(xy 366.565733 -282.123642) (xy 366.612007 -282.100064) (xy 366.6614 -282.084016) (xy 366.712695 -282.075891)
			(xy 366.764629 -282.075891) (xy 366.815924 -282.084016) (xy 366.865317 -282.100064) (xy 366.911591 -282.123642)
			(xy 366.953607 -282.154168) (xy 366.99033 -282.190891) (xy 367.020856 -282.232907) (xy 367.044434 -282.279181)
			(xy 367.060482 -282.328574) (xy 367.068607 -282.379869) (xy 367.069116 -282.405836) (xy 367.068607 -282.431803)
			(xy 367.348517 -282.431803) (xy 367.348517 -282.379869) (xy 367.356642 -282.328574) (xy 367.37269 -282.279181)
			(xy 367.396268 -282.232907) (xy 367.426794 -282.190891) (xy 367.463517 -282.154168) (xy 367.505533 -282.123642)
			(xy 367.551807 -282.100064) (xy 367.6012 -282.084016) (xy 367.652495 -282.075891) (xy 367.704429 -282.075891)
			(xy 367.755724 -282.084016) (xy 367.805117 -282.100064) (xy 367.851391 -282.123642) (xy 367.893407 -282.154168)
			(xy 367.93013 -282.190891) (xy 367.960656 -282.232907) (xy 367.984234 -282.279181) (xy 368.000282 -282.328574)
			(xy 368.008407 -282.379869) (xy 368.008916 -282.405836) (xy 368.008407 -282.431803) (xy 368.288317 -282.431803)
			(xy 368.288317 -282.379869) (xy 368.296442 -282.328574) (xy 368.31249 -282.279181) (xy 368.336068 -282.232907)
			(xy 368.366594 -282.190891) (xy 368.403317 -282.154168) (xy 368.445333 -282.123642) (xy 368.491607 -282.100064)
			(xy 368.541 -282.084016) (xy 368.592295 -282.075891) (xy 368.644229 -282.075891) (xy 368.695524 -282.084016)
			(xy 368.744917 -282.100064) (xy 368.791191 -282.123642) (xy 368.833207 -282.154168) (xy 368.86993 -282.190891)
			(xy 368.900456 -282.232907) (xy 368.924034 -282.279181) (xy 368.940082 -282.328574) (xy 368.948207 -282.379869)
			(xy 368.948716 -282.405836) (xy 368.948207 -282.431803) (xy 369.228117 -282.431803) (xy 369.228117 -282.379869)
			(xy 369.236242 -282.328574) (xy 369.25229 -282.279181) (xy 369.275868 -282.232907) (xy 369.306394 -282.190891)
			(xy 369.343117 -282.154168) (xy 369.385133 -282.123642) (xy 369.431407 -282.100064) (xy 369.4808 -282.084016)
			(xy 369.532095 -282.075891) (xy 369.584029 -282.075891) (xy 369.635324 -282.084016) (xy 369.684717 -282.100064)
			(xy 369.730991 -282.123642) (xy 369.773007 -282.154168) (xy 369.80973 -282.190891) (xy 369.840256 -282.232907)
			(xy 369.863834 -282.279181) (xy 369.879882 -282.328574) (xy 369.888007 -282.379869) (xy 369.888516 -282.405836)
			(xy 369.888007 -282.431803) (xy 370.167917 -282.431803) (xy 370.167917 -282.379869) (xy 370.176042 -282.328574)
			(xy 370.19209 -282.279181) (xy 370.215668 -282.232907) (xy 370.246194 -282.190891) (xy 370.282917 -282.154168)
			(xy 370.324933 -282.123642) (xy 370.371207 -282.100064) (xy 370.4206 -282.084016) (xy 370.471895 -282.075891)
			(xy 370.523829 -282.075891) (xy 370.575124 -282.084016) (xy 370.624517 -282.100064) (xy 370.670791 -282.123642)
			(xy 370.712807 -282.154168) (xy 370.74953 -282.190891) (xy 370.780056 -282.232907) (xy 370.803634 -282.279181)
			(xy 370.819682 -282.328574) (xy 370.827807 -282.379869) (xy 370.828316 -282.405836) (xy 370.827807 -282.431803)
			(xy 371.107717 -282.431803) (xy 371.107717 -282.379869) (xy 371.115842 -282.328574) (xy 371.13189 -282.279181)
			(xy 371.155468 -282.232907) (xy 371.185994 -282.190891) (xy 371.222717 -282.154168) (xy 371.264733 -282.123642)
			(xy 371.311007 -282.100064) (xy 371.3604 -282.084016) (xy 371.411695 -282.075891) (xy 371.463629 -282.075891)
			(xy 371.514924 -282.084016) (xy 371.564317 -282.100064) (xy 371.610591 -282.123642) (xy 371.652607 -282.154168)
			(xy 371.68933 -282.190891) (xy 371.719856 -282.232907) (xy 371.743434 -282.279181) (xy 371.759482 -282.328574)
			(xy 371.767607 -282.379869) (xy 371.768116 -282.405836) (xy 371.767607 -282.431803) (xy 372.047517 -282.431803)
			(xy 372.047517 -282.379869) (xy 372.055642 -282.328574) (xy 372.07169 -282.279181) (xy 372.095268 -282.232907)
			(xy 372.125794 -282.190891) (xy 372.162517 -282.154168) (xy 372.204533 -282.123642) (xy 372.250807 -282.100064)
			(xy 372.3002 -282.084016) (xy 372.351495 -282.075891) (xy 372.403429 -282.075891) (xy 372.454724 -282.084016)
			(xy 372.504117 -282.100064) (xy 372.550391 -282.123642) (xy 372.592407 -282.154168) (xy 372.62913 -282.190891)
			(xy 372.659656 -282.232907) (xy 372.683234 -282.279181) (xy 372.699282 -282.328574) (xy 372.707407 -282.379869)
			(xy 372.707916 -282.405836) (xy 372.707407 -282.431803) (xy 372.987317 -282.431803) (xy 372.987317 -282.379869)
			(xy 372.995442 -282.328574) (xy 373.01149 -282.279181) (xy 373.035068 -282.232907) (xy 373.065594 -282.190891)
			(xy 373.102317 -282.154168) (xy 373.144333 -282.123642) (xy 373.190607 -282.100064) (xy 373.24 -282.084016)
			(xy 373.291295 -282.075891) (xy 373.343229 -282.075891) (xy 373.394524 -282.084016) (xy 373.443917 -282.100064)
			(xy 373.490191 -282.123642) (xy 373.532207 -282.154168) (xy 373.56893 -282.190891) (xy 373.599456 -282.232907)
			(xy 373.623034 -282.279181) (xy 373.639082 -282.328574) (xy 373.647207 -282.379869) (xy 373.647716 -282.405836)
			(xy 373.647207 -282.431803) (xy 373.927371 -282.431803) (xy 373.927371 -282.379869) (xy 373.935496 -282.328574)
			(xy 373.951544 -282.279181) (xy 373.975122 -282.232907) (xy 374.005648 -282.190891) (xy 374.042371 -282.154168)
			(xy 374.084387 -282.123642) (xy 374.130661 -282.100064) (xy 374.180054 -282.084016) (xy 374.231349 -282.075891)
			(xy 374.283283 -282.075891) (xy 374.334578 -282.084016) (xy 374.383971 -282.100064) (xy 374.430245 -282.123642)
			(xy 374.472261 -282.154168) (xy 374.508984 -282.190891) (xy 374.53951 -282.232907) (xy 374.563088 -282.279181)
			(xy 374.579136 -282.328574) (xy 374.587261 -282.379869) (xy 374.58777 -282.405836) (xy 374.587266 -282.431549)
			(xy 374.867171 -282.431549) (xy 374.867171 -282.379615) (xy 374.875296 -282.32832) (xy 374.891344 -282.278927)
			(xy 374.914922 -282.232653) (xy 374.945448 -282.190637) (xy 374.982171 -282.153914) (xy 375.024187 -282.123388)
			(xy 375.070461 -282.09981) (xy 375.119854 -282.083762) (xy 375.171149 -282.075637) (xy 375.223083 -282.075637)
			(xy 375.274378 -282.083762) (xy 375.323771 -282.09981) (xy 375.370045 -282.123388) (xy 375.412061 -282.153914)
			(xy 375.448784 -282.190637) (xy 375.47931 -282.232653) (xy 375.502888 -282.278927) (xy 375.518936 -282.32832)
			(xy 375.527061 -282.379615) (xy 375.52757 -282.405582) (xy 375.527061 -282.431549) (xy 375.806971 -282.431549)
			(xy 375.806971 -282.379615) (xy 375.815096 -282.32832) (xy 375.831144 -282.278927) (xy 375.854722 -282.232653)
			(xy 375.885248 -282.190637) (xy 375.921971 -282.153914) (xy 375.963987 -282.123388) (xy 376.010261 -282.09981)
			(xy 376.059654 -282.083762) (xy 376.110949 -282.075637) (xy 376.162883 -282.075637) (xy 376.214178 -282.083762)
			(xy 376.263571 -282.09981) (xy 376.309845 -282.123388) (xy 376.351861 -282.153914) (xy 376.388584 -282.190637)
			(xy 376.41911 -282.232653) (xy 376.442688 -282.278927) (xy 376.458736 -282.32832) (xy 376.466861 -282.379615)
			(xy 376.46737 -282.405582) (xy 376.466861 -282.431549) (xy 376.746771 -282.431549) (xy 376.746771 -282.379615)
			(xy 376.754896 -282.32832) (xy 376.770944 -282.278927) (xy 376.794522 -282.232653) (xy 376.825048 -282.190637)
			(xy 376.861771 -282.153914) (xy 376.903787 -282.123388) (xy 376.950061 -282.09981) (xy 376.999454 -282.083762)
			(xy 377.050749 -282.075637) (xy 377.102683 -282.075637) (xy 377.153978 -282.083762) (xy 377.203371 -282.09981)
			(xy 377.249645 -282.123388) (xy 377.291661 -282.153914) (xy 377.328384 -282.190637) (xy 377.35891 -282.232653)
			(xy 377.382488 -282.278927) (xy 377.398536 -282.32832) (xy 377.406661 -282.379615) (xy 377.40717 -282.405582)
			(xy 377.406661 -282.431549) (xy 377.686571 -282.431549) (xy 377.686571 -282.379615) (xy 377.694696 -282.32832)
			(xy 377.710744 -282.278927) (xy 377.734322 -282.232653) (xy 377.764848 -282.190637) (xy 377.801571 -282.153914)
			(xy 377.843587 -282.123388) (xy 377.889861 -282.09981) (xy 377.939254 -282.083762) (xy 377.990549 -282.075637)
			(xy 378.042483 -282.075637) (xy 378.093778 -282.083762) (xy 378.143171 -282.09981) (xy 378.189445 -282.123388)
			(xy 378.231461 -282.153914) (xy 378.268184 -282.190637) (xy 378.29871 -282.232653) (xy 378.322288 -282.278927)
			(xy 378.338336 -282.32832) (xy 378.346461 -282.379615) (xy 378.34697 -282.405582) (xy 378.346461 -282.431549)
			(xy 378.346421 -282.431803) (xy 378.626117 -282.431803) (xy 378.626117 -282.379869) (xy 378.634242 -282.328574)
			(xy 378.65029 -282.279181) (xy 378.673868 -282.232907) (xy 378.704394 -282.190891) (xy 378.741117 -282.154168)
			(xy 378.783133 -282.123642) (xy 378.829407 -282.100064) (xy 378.8788 -282.084016) (xy 378.930095 -282.075891)
			(xy 378.982029 -282.075891) (xy 379.033324 -282.084016) (xy 379.082717 -282.100064) (xy 379.128991 -282.123642)
			(xy 379.171007 -282.154168) (xy 379.20773 -282.190891) (xy 379.238256 -282.232907) (xy 379.261834 -282.279181)
			(xy 379.277882 -282.328574) (xy 379.286007 -282.379869) (xy 379.286516 -282.405836) (xy 379.286007 -282.431803)
			(xy 379.565917 -282.431803) (xy 379.565917 -282.379869) (xy 379.574042 -282.328574) (xy 379.59009 -282.279181)
			(xy 379.613668 -282.232907) (xy 379.644194 -282.190891) (xy 379.680917 -282.154168) (xy 379.722933 -282.123642)
			(xy 379.769207 -282.100064) (xy 379.8186 -282.084016) (xy 379.869895 -282.075891) (xy 379.921829 -282.075891)
			(xy 379.973124 -282.084016) (xy 380.022517 -282.100064) (xy 380.068791 -282.123642) (xy 380.110807 -282.154168)
			(xy 380.14753 -282.190891) (xy 380.178056 -282.232907) (xy 380.201634 -282.279181) (xy 380.217682 -282.328574)
			(xy 380.225807 -282.379869) (xy 380.226316 -282.405836) (xy 380.225807 -282.431803) (xy 380.505717 -282.431803)
			(xy 380.505717 -282.379869) (xy 380.513842 -282.328574) (xy 380.52989 -282.279181) (xy 380.553468 -282.232907)
			(xy 380.583994 -282.190891) (xy 380.620717 -282.154168) (xy 380.662733 -282.123642) (xy 380.709007 -282.100064)
			(xy 380.7584 -282.084016) (xy 380.809695 -282.075891) (xy 380.861629 -282.075891) (xy 380.912924 -282.084016)
			(xy 380.962317 -282.100064) (xy 381.008591 -282.123642) (xy 381.050607 -282.154168) (xy 381.08733 -282.190891)
			(xy 381.117856 -282.232907) (xy 381.141434 -282.279181) (xy 381.157482 -282.328574) (xy 381.165607 -282.379869)
			(xy 381.166116 -282.405836) (xy 381.165607 -282.431803) (xy 381.445517 -282.431803) (xy 381.445517 -282.379869)
			(xy 381.453642 -282.328574) (xy 381.46969 -282.279181) (xy 381.493268 -282.232907) (xy 381.523794 -282.190891)
			(xy 381.560517 -282.154168) (xy 381.602533 -282.123642) (xy 381.648807 -282.100064) (xy 381.6982 -282.084016)
			(xy 381.749495 -282.075891) (xy 381.801429 -282.075891) (xy 381.852724 -282.084016) (xy 381.902117 -282.100064)
			(xy 381.948391 -282.123642) (xy 381.990407 -282.154168) (xy 382.02713 -282.190891) (xy 382.057656 -282.232907)
			(xy 382.081234 -282.279181) (xy 382.097282 -282.328574) (xy 382.105407 -282.379869) (xy 382.105916 -282.405836)
			(xy 382.105407 -282.431803) (xy 382.385571 -282.431803) (xy 382.385571 -282.379869) (xy 382.393696 -282.328574)
			(xy 382.409744 -282.279181) (xy 382.433322 -282.232907) (xy 382.463848 -282.190891) (xy 382.500571 -282.154168)
			(xy 382.542587 -282.123642) (xy 382.588861 -282.100064) (xy 382.638254 -282.084016) (xy 382.689549 -282.075891)
			(xy 382.741483 -282.075891) (xy 382.792778 -282.084016) (xy 382.842171 -282.100064) (xy 382.888445 -282.123642)
			(xy 382.930461 -282.154168) (xy 382.967184 -282.190891) (xy 382.99771 -282.232907) (xy 383.021288 -282.279181)
			(xy 383.037336 -282.328574) (xy 383.045461 -282.379869) (xy 383.04597 -282.405836) (xy 383.045461 -282.431803)
			(xy 383.325117 -282.431803) (xy 383.325117 -282.379869) (xy 383.333242 -282.328574) (xy 383.34929 -282.279181)
			(xy 383.372868 -282.232907) (xy 383.403394 -282.190891) (xy 383.440117 -282.154168) (xy 383.482133 -282.123642)
			(xy 383.528407 -282.100064) (xy 383.5778 -282.084016) (xy 383.629095 -282.075891) (xy 383.681029 -282.075891)
			(xy 383.732324 -282.084016) (xy 383.781717 -282.100064) (xy 383.827991 -282.123642) (xy 383.870007 -282.154168)
			(xy 383.90673 -282.190891) (xy 383.937256 -282.232907) (xy 383.960834 -282.279181) (xy 383.976882 -282.328574)
			(xy 383.985007 -282.379869) (xy 383.985516 -282.405836) (xy 383.985007 -282.431803) (xy 384.264917 -282.431803)
			(xy 384.264917 -282.379869) (xy 384.273042 -282.328574) (xy 384.28909 -282.279181) (xy 384.312668 -282.232907)
			(xy 384.343194 -282.190891) (xy 384.379917 -282.154168) (xy 384.421933 -282.123642) (xy 384.468207 -282.100064)
			(xy 384.5176 -282.084016) (xy 384.568895 -282.075891) (xy 384.620829 -282.075891) (xy 384.672124 -282.084016)
			(xy 384.721517 -282.100064) (xy 384.767791 -282.123642) (xy 384.809807 -282.154168) (xy 384.84653 -282.190891)
			(xy 384.877056 -282.232907) (xy 384.900634 -282.279181) (xy 384.916682 -282.328574) (xy 384.924807 -282.379869)
			(xy 384.925316 -282.405836) (xy 384.924807 -282.431803) (xy 385.204717 -282.431803) (xy 385.204717 -282.379869)
			(xy 385.212842 -282.328574) (xy 385.22889 -282.279181) (xy 385.252468 -282.232907) (xy 385.282994 -282.190891)
			(xy 385.319717 -282.154168) (xy 385.361733 -282.123642) (xy 385.408007 -282.100064) (xy 385.4574 -282.084016)
			(xy 385.508695 -282.075891) (xy 385.560629 -282.075891) (xy 385.611924 -282.084016) (xy 385.661317 -282.100064)
			(xy 385.707591 -282.123642) (xy 385.749607 -282.154168) (xy 385.78633 -282.190891) (xy 385.816856 -282.232907)
			(xy 385.840434 -282.279181) (xy 385.856482 -282.328574) (xy 385.864607 -282.379869) (xy 385.865116 -282.405836)
			(xy 385.864607 -282.431803) (xy 385.856482 -282.483098) (xy 385.840434 -282.532491) (xy 385.816856 -282.578765)
			(xy 385.78633 -282.620781) (xy 385.749607 -282.657504) (xy 385.707591 -282.68803) (xy 385.661317 -282.711608)
			(xy 385.611924 -282.727656) (xy 385.560629 -282.735781) (xy 385.508695 -282.735781) (xy 385.4574 -282.727656)
			(xy 385.408007 -282.711608) (xy 385.361733 -282.68803) (xy 385.319717 -282.657504) (xy 385.282994 -282.620781)
			(xy 385.252468 -282.578765) (xy 385.22889 -282.532491) (xy 385.212842 -282.483098) (xy 385.204717 -282.431803)
			(xy 384.924807 -282.431803) (xy 384.916682 -282.483098) (xy 384.900634 -282.532491) (xy 384.877056 -282.578765)
			(xy 384.84653 -282.620781) (xy 384.809807 -282.657504) (xy 384.767791 -282.68803) (xy 384.721517 -282.711608)
			(xy 384.672124 -282.727656) (xy 384.620829 -282.735781) (xy 384.568895 -282.735781) (xy 384.5176 -282.727656)
			(xy 384.468207 -282.711608) (xy 384.421933 -282.68803) (xy 384.379917 -282.657504) (xy 384.343194 -282.620781)
			(xy 384.312668 -282.578765) (xy 384.28909 -282.532491) (xy 384.273042 -282.483098) (xy 384.264917 -282.431803)
			(xy 383.985007 -282.431803) (xy 383.976882 -282.483098) (xy 383.960834 -282.532491) (xy 383.937256 -282.578765)
			(xy 383.90673 -282.620781) (xy 383.870007 -282.657504) (xy 383.827991 -282.68803) (xy 383.781717 -282.711608)
			(xy 383.732324 -282.727656) (xy 383.681029 -282.735781) (xy 383.629095 -282.735781) (xy 383.5778 -282.727656)
			(xy 383.528407 -282.711608) (xy 383.482133 -282.68803) (xy 383.440117 -282.657504) (xy 383.403394 -282.620781)
			(xy 383.372868 -282.578765) (xy 383.34929 -282.532491) (xy 383.333242 -282.483098) (xy 383.325117 -282.431803)
			(xy 383.045461 -282.431803) (xy 383.037336 -282.483098) (xy 383.021288 -282.532491) (xy 382.99771 -282.578765)
			(xy 382.967184 -282.620781) (xy 382.930461 -282.657504) (xy 382.888445 -282.68803) (xy 382.842171 -282.711608)
			(xy 382.792778 -282.727656) (xy 382.741483 -282.735781) (xy 382.689549 -282.735781) (xy 382.638254 -282.727656)
			(xy 382.588861 -282.711608) (xy 382.542587 -282.68803) (xy 382.500571 -282.657504) (xy 382.463848 -282.620781)
			(xy 382.433322 -282.578765) (xy 382.409744 -282.532491) (xy 382.393696 -282.483098) (xy 382.385571 -282.431803)
			(xy 382.105407 -282.431803) (xy 382.097282 -282.483098) (xy 382.081234 -282.532491) (xy 382.057656 -282.578765)
			(xy 382.02713 -282.620781) (xy 381.990407 -282.657504) (xy 381.948391 -282.68803) (xy 381.902117 -282.711608)
			(xy 381.852724 -282.727656) (xy 381.801429 -282.735781) (xy 381.749495 -282.735781) (xy 381.6982 -282.727656)
			(xy 381.648807 -282.711608) (xy 381.602533 -282.68803) (xy 381.560517 -282.657504) (xy 381.523794 -282.620781)
			(xy 381.493268 -282.578765) (xy 381.46969 -282.532491) (xy 381.453642 -282.483098) (xy 381.445517 -282.431803)
			(xy 381.165607 -282.431803) (xy 381.157482 -282.483098) (xy 381.141434 -282.532491) (xy 381.117856 -282.578765)
			(xy 381.08733 -282.620781) (xy 381.050607 -282.657504) (xy 381.008591 -282.68803) (xy 380.962317 -282.711608)
			(xy 380.912924 -282.727656) (xy 380.861629 -282.735781) (xy 380.809695 -282.735781) (xy 380.7584 -282.727656)
			(xy 380.709007 -282.711608) (xy 380.662733 -282.68803) (xy 380.620717 -282.657504) (xy 380.583994 -282.620781)
			(xy 380.553468 -282.578765) (xy 380.52989 -282.532491) (xy 380.513842 -282.483098) (xy 380.505717 -282.431803)
			(xy 380.225807 -282.431803) (xy 380.217682 -282.483098) (xy 380.201634 -282.532491) (xy 380.178056 -282.578765)
			(xy 380.14753 -282.620781) (xy 380.110807 -282.657504) (xy 380.068791 -282.68803) (xy 380.022517 -282.711608)
			(xy 379.973124 -282.727656) (xy 379.921829 -282.735781) (xy 379.869895 -282.735781) (xy 379.8186 -282.727656)
			(xy 379.769207 -282.711608) (xy 379.722933 -282.68803) (xy 379.680917 -282.657504) (xy 379.644194 -282.620781)
			(xy 379.613668 -282.578765) (xy 379.59009 -282.532491) (xy 379.574042 -282.483098) (xy 379.565917 -282.431803)
			(xy 379.286007 -282.431803) (xy 379.277882 -282.483098) (xy 379.261834 -282.532491) (xy 379.238256 -282.578765)
			(xy 379.20773 -282.620781) (xy 379.171007 -282.657504) (xy 379.128991 -282.68803) (xy 379.082717 -282.711608)
			(xy 379.033324 -282.727656) (xy 378.982029 -282.735781) (xy 378.930095 -282.735781) (xy 378.8788 -282.727656)
			(xy 378.829407 -282.711608) (xy 378.783133 -282.68803) (xy 378.741117 -282.657504) (xy 378.704394 -282.620781)
			(xy 378.673868 -282.578765) (xy 378.65029 -282.532491) (xy 378.634242 -282.483098) (xy 378.626117 -282.431803)
			(xy 378.346421 -282.431803) (xy 378.338336 -282.482844) (xy 378.322288 -282.532237) (xy 378.29871 -282.578511)
			(xy 378.268184 -282.620527) (xy 378.231461 -282.65725) (xy 378.189445 -282.687776) (xy 378.143171 -282.711354)
			(xy 378.093778 -282.727402) (xy 378.042483 -282.735527) (xy 377.990549 -282.735527) (xy 377.939254 -282.727402)
			(xy 377.889861 -282.711354) (xy 377.843587 -282.687776) (xy 377.801571 -282.65725) (xy 377.764848 -282.620527)
			(xy 377.734322 -282.578511) (xy 377.710744 -282.532237) (xy 377.694696 -282.482844) (xy 377.686571 -282.431549)
			(xy 377.406661 -282.431549) (xy 377.398536 -282.482844) (xy 377.382488 -282.532237) (xy 377.35891 -282.578511)
			(xy 377.328384 -282.620527) (xy 377.291661 -282.65725) (xy 377.249645 -282.687776) (xy 377.203371 -282.711354)
			(xy 377.153978 -282.727402) (xy 377.102683 -282.735527) (xy 377.050749 -282.735527) (xy 376.999454 -282.727402)
			(xy 376.950061 -282.711354) (xy 376.903787 -282.687776) (xy 376.861771 -282.65725) (xy 376.825048 -282.620527)
			(xy 376.794522 -282.578511) (xy 376.770944 -282.532237) (xy 376.754896 -282.482844) (xy 376.746771 -282.431549)
			(xy 376.466861 -282.431549) (xy 376.458736 -282.482844) (xy 376.442688 -282.532237) (xy 376.41911 -282.578511)
			(xy 376.388584 -282.620527) (xy 376.351861 -282.65725) (xy 376.309845 -282.687776) (xy 376.263571 -282.711354)
			(xy 376.214178 -282.727402) (xy 376.162883 -282.735527) (xy 376.110949 -282.735527) (xy 376.059654 -282.727402)
			(xy 376.010261 -282.711354) (xy 375.963987 -282.687776) (xy 375.921971 -282.65725) (xy 375.885248 -282.620527)
			(xy 375.854722 -282.578511) (xy 375.831144 -282.532237) (xy 375.815096 -282.482844) (xy 375.806971 -282.431549)
			(xy 375.527061 -282.431549) (xy 375.518936 -282.482844) (xy 375.502888 -282.532237) (xy 375.47931 -282.578511)
			(xy 375.448784 -282.620527) (xy 375.412061 -282.65725) (xy 375.370045 -282.687776) (xy 375.323771 -282.711354)
			(xy 375.274378 -282.727402) (xy 375.223083 -282.735527) (xy 375.171149 -282.735527) (xy 375.119854 -282.727402)
			(xy 375.070461 -282.711354) (xy 375.024187 -282.687776) (xy 374.982171 -282.65725) (xy 374.945448 -282.620527)
			(xy 374.914922 -282.578511) (xy 374.891344 -282.532237) (xy 374.875296 -282.482844) (xy 374.867171 -282.431549)
			(xy 374.587266 -282.431549) (xy 374.587261 -282.431803) (xy 374.579136 -282.483098) (xy 374.563088 -282.532491)
			(xy 374.53951 -282.578765) (xy 374.508984 -282.620781) (xy 374.472261 -282.657504) (xy 374.430245 -282.68803)
			(xy 374.383971 -282.711608) (xy 374.334578 -282.727656) (xy 374.283283 -282.735781) (xy 374.231349 -282.735781)
			(xy 374.180054 -282.727656) (xy 374.130661 -282.711608) (xy 374.084387 -282.68803) (xy 374.042371 -282.657504)
			(xy 374.005648 -282.620781) (xy 373.975122 -282.578765) (xy 373.951544 -282.532491) (xy 373.935496 -282.483098)
			(xy 373.927371 -282.431803) (xy 373.647207 -282.431803) (xy 373.639082 -282.483098) (xy 373.623034 -282.532491)
			(xy 373.599456 -282.578765) (xy 373.56893 -282.620781) (xy 373.532207 -282.657504) (xy 373.490191 -282.68803)
			(xy 373.443917 -282.711608) (xy 373.394524 -282.727656) (xy 373.343229 -282.735781) (xy 373.291295 -282.735781)
			(xy 373.24 -282.727656) (xy 373.190607 -282.711608) (xy 373.144333 -282.68803) (xy 373.102317 -282.657504)
			(xy 373.065594 -282.620781) (xy 373.035068 -282.578765) (xy 373.01149 -282.532491) (xy 372.995442 -282.483098)
			(xy 372.987317 -282.431803) (xy 372.707407 -282.431803) (xy 372.699282 -282.483098) (xy 372.683234 -282.532491)
			(xy 372.659656 -282.578765) (xy 372.62913 -282.620781) (xy 372.592407 -282.657504) (xy 372.550391 -282.68803)
			(xy 372.504117 -282.711608) (xy 372.454724 -282.727656) (xy 372.403429 -282.735781) (xy 372.351495 -282.735781)
			(xy 372.3002 -282.727656) (xy 372.250807 -282.711608) (xy 372.204533 -282.68803) (xy 372.162517 -282.657504)
			(xy 372.125794 -282.620781) (xy 372.095268 -282.578765) (xy 372.07169 -282.532491) (xy 372.055642 -282.483098)
			(xy 372.047517 -282.431803) (xy 371.767607 -282.431803) (xy 371.759482 -282.483098) (xy 371.743434 -282.532491)
			(xy 371.719856 -282.578765) (xy 371.68933 -282.620781) (xy 371.652607 -282.657504) (xy 371.610591 -282.68803)
			(xy 371.564317 -282.711608) (xy 371.514924 -282.727656) (xy 371.463629 -282.735781) (xy 371.411695 -282.735781)
			(xy 371.3604 -282.727656) (xy 371.311007 -282.711608) (xy 371.264733 -282.68803) (xy 371.222717 -282.657504)
			(xy 371.185994 -282.620781) (xy 371.155468 -282.578765) (xy 371.13189 -282.532491) (xy 371.115842 -282.483098)
			(xy 371.107717 -282.431803) (xy 370.827807 -282.431803) (xy 370.819682 -282.483098) (xy 370.803634 -282.532491)
			(xy 370.780056 -282.578765) (xy 370.74953 -282.620781) (xy 370.712807 -282.657504) (xy 370.670791 -282.68803)
			(xy 370.624517 -282.711608) (xy 370.575124 -282.727656) (xy 370.523829 -282.735781) (xy 370.471895 -282.735781)
			(xy 370.4206 -282.727656) (xy 370.371207 -282.711608) (xy 370.324933 -282.68803) (xy 370.282917 -282.657504)
			(xy 370.246194 -282.620781) (xy 370.215668 -282.578765) (xy 370.19209 -282.532491) (xy 370.176042 -282.483098)
			(xy 370.167917 -282.431803) (xy 369.888007 -282.431803) (xy 369.879882 -282.483098) (xy 369.863834 -282.532491)
			(xy 369.840256 -282.578765) (xy 369.80973 -282.620781) (xy 369.773007 -282.657504) (xy 369.730991 -282.68803)
			(xy 369.684717 -282.711608) (xy 369.635324 -282.727656) (xy 369.584029 -282.735781) (xy 369.532095 -282.735781)
			(xy 369.4808 -282.727656) (xy 369.431407 -282.711608) (xy 369.385133 -282.68803) (xy 369.343117 -282.657504)
			(xy 369.306394 -282.620781) (xy 369.275868 -282.578765) (xy 369.25229 -282.532491) (xy 369.236242 -282.483098)
			(xy 369.228117 -282.431803) (xy 368.948207 -282.431803) (xy 368.940082 -282.483098) (xy 368.924034 -282.532491)
			(xy 368.900456 -282.578765) (xy 368.86993 -282.620781) (xy 368.833207 -282.657504) (xy 368.791191 -282.68803)
			(xy 368.744917 -282.711608) (xy 368.695524 -282.727656) (xy 368.644229 -282.735781) (xy 368.592295 -282.735781)
			(xy 368.541 -282.727656) (xy 368.491607 -282.711608) (xy 368.445333 -282.68803) (xy 368.403317 -282.657504)
			(xy 368.366594 -282.620781) (xy 368.336068 -282.578765) (xy 368.31249 -282.532491) (xy 368.296442 -282.483098)
			(xy 368.288317 -282.431803) (xy 368.008407 -282.431803) (xy 368.000282 -282.483098) (xy 367.984234 -282.532491)
			(xy 367.960656 -282.578765) (xy 367.93013 -282.620781) (xy 367.893407 -282.657504) (xy 367.851391 -282.68803)
			(xy 367.805117 -282.711608) (xy 367.755724 -282.727656) (xy 367.704429 -282.735781) (xy 367.652495 -282.735781)
			(xy 367.6012 -282.727656) (xy 367.551807 -282.711608) (xy 367.505533 -282.68803) (xy 367.463517 -282.657504)
			(xy 367.426794 -282.620781) (xy 367.396268 -282.578765) (xy 367.37269 -282.532491) (xy 367.356642 -282.483098)
			(xy 367.348517 -282.431803) (xy 367.068607 -282.431803) (xy 367.060482 -282.483098) (xy 367.044434 -282.532491)
			(xy 367.020856 -282.578765) (xy 366.99033 -282.620781) (xy 366.953607 -282.657504) (xy 366.911591 -282.68803)
			(xy 366.865317 -282.711608) (xy 366.815924 -282.727656) (xy 366.764629 -282.735781) (xy 366.712695 -282.735781)
			(xy 366.6614 -282.727656) (xy 366.612007 -282.711608) (xy 366.565733 -282.68803) (xy 366.523717 -282.657504)
			(xy 366.486994 -282.620781) (xy 366.456468 -282.578765) (xy 366.43289 -282.532491) (xy 366.416842 -282.483098)
			(xy 366.408717 -282.431803) (xy 366.128951 -282.431803) (xy 366.128804 -282.43797) (xy 366.116392 -282.501027)
			(xy 366.104932 -282.531058) (xy 366.092232 -282.5623) (xy 366.71758 -283.187648) (xy 366.727377 -283.196823)
			(xy 366.750673 -283.210139) (xy 366.776635 -283.216918) (xy 366.803467 -283.216692) (xy 366.829311 -283.209477)
			(xy 366.85238 -283.195771) (xy 366.871075 -283.176523) (xy 366.884104 -283.153066) (xy 366.88776 -283.14015)
			(xy 366.894087 -283.116607) (xy 366.912712 -283.071556) (xy 366.937747 -283.029727) (xy 366.96865 -282.992025)
			(xy 367.004751 -282.959266) (xy 367.045269 -282.932161) (xy 367.089327 -282.911295) (xy 367.13597 -282.897122)
			(xy 367.184188 -282.889947) (xy 367.208562 -282.889452) (xy 367.234533 -282.889932) (xy 367.285836 -282.898052)
			(xy 367.335238 -282.914099) (xy 367.38152 -282.937677) (xy 367.423544 -282.968205) (xy 367.460274 -283.004932)
			(xy 367.490807 -283.046953) (xy 367.514389 -283.093233) (xy 367.53044 -283.142632) (xy 367.538565 -283.193935)
			(xy 367.539016 -283.219906) (xy 367.538587 -283.244287) (xy 367.538352 -283.245873) (xy 367.818671 -283.245873)
			(xy 367.818671 -283.193939) (xy 367.826796 -283.142644) (xy 367.842844 -283.093251) (xy 367.866422 -283.046977)
			(xy 367.896948 -283.004961) (xy 367.933671 -282.968238) (xy 367.975687 -282.937712) (xy 368.021961 -282.914134)
			(xy 368.071354 -282.898086) (xy 368.122649 -282.889961) (xy 368.174583 -282.889961) (xy 368.225878 -282.898086)
			(xy 368.275271 -282.914134) (xy 368.321545 -282.937712) (xy 368.363561 -282.968238) (xy 368.400284 -283.004961)
			(xy 368.43081 -283.046977) (xy 368.454388 -283.093251) (xy 368.470436 -283.142644) (xy 368.478561 -283.193939)
			(xy 368.47907 -283.219906) (xy 368.478561 -283.245873) (xy 368.758217 -283.245873) (xy 368.758217 -283.193939)
			(xy 368.766342 -283.142644) (xy 368.78239 -283.093251) (xy 368.805968 -283.046977) (xy 368.836494 -283.004961)
			(xy 368.873217 -282.968238) (xy 368.915233 -282.937712) (xy 368.961507 -282.914134) (xy 369.0109 -282.898086)
			(xy 369.062195 -282.889961) (xy 369.114129 -282.889961) (xy 369.165424 -282.898086) (xy 369.214817 -282.914134)
			(xy 369.261091 -282.937712) (xy 369.303107 -282.968238) (xy 369.33983 -283.004961) (xy 369.370356 -283.046977)
			(xy 369.393934 -283.093251) (xy 369.409982 -283.142644) (xy 369.418107 -283.193939) (xy 369.418616 -283.219906)
			(xy 369.418107 -283.245873) (xy 369.698017 -283.245873) (xy 369.698017 -283.193939) (xy 369.706142 -283.142644)
			(xy 369.72219 -283.093251) (xy 369.745768 -283.046977) (xy 369.776294 -283.004961) (xy 369.813017 -282.968238)
			(xy 369.855033 -282.937712) (xy 369.901307 -282.914134) (xy 369.9507 -282.898086) (xy 370.001995 -282.889961)
			(xy 370.053929 -282.889961) (xy 370.105224 -282.898086) (xy 370.154617 -282.914134) (xy 370.200891 -282.937712)
			(xy 370.242907 -282.968238) (xy 370.27963 -283.004961) (xy 370.310156 -283.046977) (xy 370.333734 -283.093251)
			(xy 370.349782 -283.142644) (xy 370.357907 -283.193939) (xy 370.358416 -283.219906) (xy 370.357907 -283.245873)
			(xy 370.638071 -283.245873) (xy 370.638071 -283.193939) (xy 370.646196 -283.142644) (xy 370.662244 -283.093251)
			(xy 370.685822 -283.046977) (xy 370.716348 -283.004961) (xy 370.753071 -282.968238) (xy 370.795087 -282.937712)
			(xy 370.841361 -282.914134) (xy 370.890754 -282.898086) (xy 370.942049 -282.889961) (xy 370.993983 -282.889961)
			(xy 371.045278 -282.898086) (xy 371.094671 -282.914134) (xy 371.140945 -282.937712) (xy 371.182961 -282.968238)
			(xy 371.219684 -283.004961) (xy 371.25021 -283.046977) (xy 371.273788 -283.093251) (xy 371.289836 -283.142644)
			(xy 371.297961 -283.193939) (xy 371.29847 -283.219906) (xy 371.297961 -283.245873) (xy 372.517671 -283.245873)
			(xy 372.517671 -283.193939) (xy 372.525796 -283.142644) (xy 372.541844 -283.093251) (xy 372.565422 -283.046977)
			(xy 372.595948 -283.004961) (xy 372.632671 -282.968238) (xy 372.674687 -282.937712) (xy 372.720961 -282.914134)
			(xy 372.770354 -282.898086) (xy 372.821649 -282.889961) (xy 372.873583 -282.889961) (xy 372.924878 -282.898086)
			(xy 372.974271 -282.914134) (xy 373.020545 -282.937712) (xy 373.062561 -282.968238) (xy 373.099284 -283.004961)
			(xy 373.12981 -283.046977) (xy 373.153388 -283.093251) (xy 373.169436 -283.142644) (xy 373.177561 -283.193939)
			(xy 373.17807 -283.219906) (xy 373.177561 -283.245873) (xy 373.457471 -283.245873) (xy 373.457471 -283.193939)
			(xy 373.465596 -283.142644) (xy 373.481644 -283.093251) (xy 373.505222 -283.046977) (xy 373.535748 -283.004961)
			(xy 373.572471 -282.968238) (xy 373.614487 -282.937712) (xy 373.660761 -282.914134) (xy 373.710154 -282.898086)
			(xy 373.761449 -282.889961) (xy 373.813383 -282.889961) (xy 373.864678 -282.898086) (xy 373.914071 -282.914134)
			(xy 373.960345 -282.937712) (xy 374.002361 -282.968238) (xy 374.039084 -283.004961) (xy 374.06961 -283.046977)
			(xy 374.093188 -283.093251) (xy 374.109236 -283.142644) (xy 374.117361 -283.193939) (xy 374.11787 -283.219906)
			(xy 374.117361 -283.245873) (xy 374.397017 -283.245873) (xy 374.397017 -283.193939) (xy 374.405142 -283.142644)
			(xy 374.42119 -283.093251) (xy 374.444768 -283.046977) (xy 374.475294 -283.004961) (xy 374.512017 -282.968238)
			(xy 374.554033 -282.937712) (xy 374.600307 -282.914134) (xy 374.6497 -282.898086) (xy 374.700995 -282.889961)
			(xy 374.752929 -282.889961) (xy 374.804224 -282.898086) (xy 374.853617 -282.914134) (xy 374.899891 -282.937712)
			(xy 374.941907 -282.968238) (xy 374.97863 -283.004961) (xy 375.009156 -283.046977) (xy 375.032734 -283.093251)
			(xy 375.048782 -283.142644) (xy 375.056907 -283.193939) (xy 375.057416 -283.219906) (xy 375.056912 -283.245619)
			(xy 376.276617 -283.245619) (xy 376.276617 -283.193685) (xy 376.284742 -283.14239) (xy 376.30079 -283.092997)
			(xy 376.324368 -283.046723) (xy 376.354894 -283.004707) (xy 376.391617 -282.967984) (xy 376.433633 -282.937458)
			(xy 376.479907 -282.91388) (xy 376.5293 -282.897832) (xy 376.580595 -282.889707) (xy 376.632529 -282.889707)
			(xy 376.683824 -282.897832) (xy 376.733217 -282.91388) (xy 376.779491 -282.937458) (xy 376.821507 -282.967984)
			(xy 376.85823 -283.004707) (xy 376.888756 -283.046723) (xy 376.912334 -283.092997) (xy 376.928382 -283.14239)
			(xy 376.936507 -283.193685) (xy 376.937016 -283.219652) (xy 376.936507 -283.245619) (xy 376.936467 -283.245873)
			(xy 377.216417 -283.245873) (xy 377.216417 -283.193939) (xy 377.224542 -283.142644) (xy 377.24059 -283.093251)
			(xy 377.264168 -283.046977) (xy 377.294694 -283.004961) (xy 377.331417 -282.968238) (xy 377.373433 -282.937712)
			(xy 377.419707 -282.914134) (xy 377.4691 -282.898086) (xy 377.520395 -282.889961) (xy 377.572329 -282.889961)
			(xy 377.623624 -282.898086) (xy 377.673017 -282.914134) (xy 377.719291 -282.937712) (xy 377.761307 -282.968238)
			(xy 377.79803 -283.004961) (xy 377.828556 -283.046977) (xy 377.852134 -283.093251) (xy 377.868182 -283.142644)
			(xy 377.876307 -283.193939) (xy 377.876816 -283.219906) (xy 377.876307 -283.245873) (xy 378.156217 -283.245873)
			(xy 378.156217 -283.193939) (xy 378.164342 -283.142644) (xy 378.18039 -283.093251) (xy 378.203968 -283.046977)
			(xy 378.234494 -283.004961) (xy 378.271217 -282.968238) (xy 378.313233 -282.937712) (xy 378.359507 -282.914134)
			(xy 378.4089 -282.898086) (xy 378.460195 -282.889961) (xy 378.512129 -282.889961) (xy 378.563424 -282.898086)
			(xy 378.612817 -282.914134) (xy 378.659091 -282.937712) (xy 378.701107 -282.968238) (xy 378.73783 -283.004961)
			(xy 378.768356 -283.046977) (xy 378.791934 -283.093251) (xy 378.807982 -283.142644) (xy 378.816107 -283.193939)
			(xy 378.816616 -283.219906) (xy 378.816107 -283.245873) (xy 379.096271 -283.245873) (xy 379.096271 -283.193939)
			(xy 379.104396 -283.142644) (xy 379.120444 -283.093251) (xy 379.144022 -283.046977) (xy 379.174548 -283.004961)
			(xy 379.211271 -282.968238) (xy 379.253287 -282.937712) (xy 379.299561 -282.914134) (xy 379.348954 -282.898086)
			(xy 379.400249 -282.889961) (xy 379.452183 -282.889961) (xy 379.503478 -282.898086) (xy 379.552871 -282.914134)
			(xy 379.599145 -282.937712) (xy 379.641161 -282.968238) (xy 379.677884 -283.004961) (xy 379.70841 -283.046977)
			(xy 379.731988 -283.093251) (xy 379.748036 -283.142644) (xy 379.756161 -283.193939) (xy 379.75667 -283.219906)
			(xy 379.756161 -283.245873) (xy 380.035817 -283.245873) (xy 380.035817 -283.193939) (xy 380.043942 -283.142644)
			(xy 380.05999 -283.093251) (xy 380.083568 -283.046977) (xy 380.114094 -283.004961) (xy 380.150817 -282.968238)
			(xy 380.192833 -282.937712) (xy 380.239107 -282.914134) (xy 380.2885 -282.898086) (xy 380.339795 -282.889961)
			(xy 380.391729 -282.889961) (xy 380.443024 -282.898086) (xy 380.492417 -282.914134) (xy 380.538691 -282.937712)
			(xy 380.580707 -282.968238) (xy 380.61743 -283.004961) (xy 380.647956 -283.046977) (xy 380.671534 -283.093251)
			(xy 380.687582 -283.142644) (xy 380.695707 -283.193939) (xy 380.696216 -283.219906) (xy 380.695707 -283.245873)
			(xy 380.975871 -283.245873) (xy 380.975871 -283.193939) (xy 380.983996 -283.142644) (xy 381.000044 -283.093251)
			(xy 381.023622 -283.046977) (xy 381.054148 -283.004961) (xy 381.090871 -282.968238) (xy 381.132887 -282.937712)
			(xy 381.179161 -282.914134) (xy 381.228554 -282.898086) (xy 381.279849 -282.889961) (xy 381.331783 -282.889961)
			(xy 381.383078 -282.898086) (xy 381.432471 -282.914134) (xy 381.478745 -282.937712) (xy 381.520761 -282.968238)
			(xy 381.557484 -283.004961) (xy 381.58801 -283.046977) (xy 381.611588 -283.093251) (xy 381.627636 -283.142644)
			(xy 381.635761 -283.193939) (xy 381.63627 -283.219906) (xy 381.635761 -283.245873) (xy 381.915671 -283.245873)
			(xy 381.915671 -283.193939) (xy 381.923796 -283.142644) (xy 381.939844 -283.093251) (xy 381.963422 -283.046977)
			(xy 381.993948 -283.004961) (xy 382.030671 -282.968238) (xy 382.072687 -282.937712) (xy 382.118961 -282.914134)
			(xy 382.168354 -282.898086) (xy 382.219649 -282.889961) (xy 382.271583 -282.889961) (xy 382.322878 -282.898086)
			(xy 382.372271 -282.914134) (xy 382.418545 -282.937712) (xy 382.460561 -282.968238) (xy 382.497284 -283.004961)
			(xy 382.52781 -283.046977) (xy 382.551388 -283.093251) (xy 382.567436 -283.142644) (xy 382.575561 -283.193939)
			(xy 382.57607 -283.219906) (xy 382.575561 -283.245873) (xy 382.855217 -283.245873) (xy 382.855217 -283.193939)
			(xy 382.863342 -283.142644) (xy 382.87939 -283.093251) (xy 382.902968 -283.046977) (xy 382.933494 -283.004961)
			(xy 382.970217 -282.968238) (xy 383.012233 -282.937712) (xy 383.058507 -282.914134) (xy 383.1079 -282.898086)
			(xy 383.159195 -282.889961) (xy 383.211129 -282.889961) (xy 383.262424 -282.898086) (xy 383.311817 -282.914134)
			(xy 383.358091 -282.937712) (xy 383.400107 -282.968238) (xy 383.43683 -283.004961) (xy 383.467356 -283.046977)
			(xy 383.490934 -283.093251) (xy 383.506982 -283.142644) (xy 383.515107 -283.193939) (xy 383.515616 -283.219906)
			(xy 383.515107 -283.245873) (xy 383.795017 -283.245873) (xy 383.795017 -283.193939) (xy 383.803142 -283.142644)
			(xy 383.81919 -283.093251) (xy 383.842768 -283.046977) (xy 383.873294 -283.004961) (xy 383.910017 -282.968238)
			(xy 383.952033 -282.937712) (xy 383.998307 -282.914134) (xy 384.0477 -282.898086) (xy 384.098995 -282.889961)
			(xy 384.150929 -282.889961) (xy 384.202224 -282.898086) (xy 384.251617 -282.914134) (xy 384.297891 -282.937712)
			(xy 384.339907 -282.968238) (xy 384.37663 -283.004961) (xy 384.407156 -283.046977) (xy 384.430734 -283.093251)
			(xy 384.446782 -283.142644) (xy 384.454907 -283.193939) (xy 384.455416 -283.219906) (xy 384.454907 -283.245873)
			(xy 384.735071 -283.245873) (xy 384.735071 -283.193939) (xy 384.743196 -283.142644) (xy 384.759244 -283.093251)
			(xy 384.782822 -283.046977) (xy 384.813348 -283.004961) (xy 384.850071 -282.968238) (xy 384.892087 -282.937712)
			(xy 384.938361 -282.914134) (xy 384.987754 -282.898086) (xy 385.039049 -282.889961) (xy 385.090983 -282.889961)
			(xy 385.142278 -282.898086) (xy 385.191671 -282.914134) (xy 385.237945 -282.937712) (xy 385.279961 -282.968238)
			(xy 385.316684 -283.004961) (xy 385.34721 -283.046977) (xy 385.370788 -283.093251) (xy 385.386836 -283.142644)
			(xy 385.394961 -283.193939) (xy 385.39547 -283.219906) (xy 385.394961 -283.245873) (xy 385.386836 -283.297168)
			(xy 385.370788 -283.346561) (xy 385.34721 -283.392835) (xy 385.316684 -283.434851) (xy 385.279961 -283.471574)
			(xy 385.237945 -283.5021) (xy 385.191671 -283.525678) (xy 385.142278 -283.541726) (xy 385.090983 -283.549851)
			(xy 385.039049 -283.549851) (xy 384.987754 -283.541726) (xy 384.938361 -283.525678) (xy 384.892087 -283.5021)
			(xy 384.850071 -283.471574) (xy 384.813348 -283.434851) (xy 384.782822 -283.392835) (xy 384.759244 -283.346561)
			(xy 384.743196 -283.297168) (xy 384.735071 -283.245873) (xy 384.454907 -283.245873) (xy 384.446782 -283.297168)
			(xy 384.430734 -283.346561) (xy 384.407156 -283.392835) (xy 384.37663 -283.434851) (xy 384.339907 -283.471574)
			(xy 384.297891 -283.5021) (xy 384.251617 -283.525678) (xy 384.202224 -283.541726) (xy 384.150929 -283.549851)
			(xy 384.098995 -283.549851) (xy 384.0477 -283.541726) (xy 383.998307 -283.525678) (xy 383.952033 -283.5021)
			(xy 383.910017 -283.471574) (xy 383.873294 -283.434851) (xy 383.842768 -283.392835) (xy 383.81919 -283.346561)
			(xy 383.803142 -283.297168) (xy 383.795017 -283.245873) (xy 383.515107 -283.245873) (xy 383.506982 -283.297168)
			(xy 383.490934 -283.346561) (xy 383.467356 -283.392835) (xy 383.43683 -283.434851) (xy 383.400107 -283.471574)
			(xy 383.358091 -283.5021) (xy 383.311817 -283.525678) (xy 383.262424 -283.541726) (xy 383.211129 -283.549851)
			(xy 383.159195 -283.549851) (xy 383.1079 -283.541726) (xy 383.058507 -283.525678) (xy 383.012233 -283.5021)
			(xy 382.970217 -283.471574) (xy 382.933494 -283.434851) (xy 382.902968 -283.392835) (xy 382.87939 -283.346561)
			(xy 382.863342 -283.297168) (xy 382.855217 -283.245873) (xy 382.575561 -283.245873) (xy 382.567436 -283.297168)
			(xy 382.551388 -283.346561) (xy 382.52781 -283.392835) (xy 382.497284 -283.434851) (xy 382.460561 -283.471574)
			(xy 382.418545 -283.5021) (xy 382.372271 -283.525678) (xy 382.322878 -283.541726) (xy 382.271583 -283.549851)
			(xy 382.219649 -283.549851) (xy 382.168354 -283.541726) (xy 382.118961 -283.525678) (xy 382.072687 -283.5021)
			(xy 382.030671 -283.471574) (xy 381.993948 -283.434851) (xy 381.963422 -283.392835) (xy 381.939844 -283.346561)
			(xy 381.923796 -283.297168) (xy 381.915671 -283.245873) (xy 381.635761 -283.245873) (xy 381.627636 -283.297168)
			(xy 381.611588 -283.346561) (xy 381.58801 -283.392835) (xy 381.557484 -283.434851) (xy 381.520761 -283.471574)
			(xy 381.478745 -283.5021) (xy 381.432471 -283.525678) (xy 381.383078 -283.541726) (xy 381.331783 -283.549851)
			(xy 381.279849 -283.549851) (xy 381.228554 -283.541726) (xy 381.179161 -283.525678) (xy 381.132887 -283.5021)
			(xy 381.090871 -283.471574) (xy 381.054148 -283.434851) (xy 381.023622 -283.392835) (xy 381.000044 -283.346561)
			(xy 380.983996 -283.297168) (xy 380.975871 -283.245873) (xy 380.695707 -283.245873) (xy 380.687582 -283.297168)
			(xy 380.671534 -283.346561) (xy 380.647956 -283.392835) (xy 380.61743 -283.434851) (xy 380.580707 -283.471574)
			(xy 380.538691 -283.5021) (xy 380.492417 -283.525678) (xy 380.443024 -283.541726) (xy 380.391729 -283.549851)
			(xy 380.339795 -283.549851) (xy 380.2885 -283.541726) (xy 380.239107 -283.525678) (xy 380.192833 -283.5021)
			(xy 380.150817 -283.471574) (xy 380.114094 -283.434851) (xy 380.083568 -283.392835) (xy 380.05999 -283.346561)
			(xy 380.043942 -283.297168) (xy 380.035817 -283.245873) (xy 379.756161 -283.245873) (xy 379.748036 -283.297168)
			(xy 379.731988 -283.346561) (xy 379.70841 -283.392835) (xy 379.677884 -283.434851) (xy 379.641161 -283.471574)
			(xy 379.599145 -283.5021) (xy 379.552871 -283.525678) (xy 379.503478 -283.541726) (xy 379.452183 -283.549851)
			(xy 379.400249 -283.549851) (xy 379.348954 -283.541726) (xy 379.299561 -283.525678) (xy 379.253287 -283.5021)
			(xy 379.211271 -283.471574) (xy 379.174548 -283.434851) (xy 379.144022 -283.392835) (xy 379.120444 -283.346561)
			(xy 379.104396 -283.297168) (xy 379.096271 -283.245873) (xy 378.816107 -283.245873) (xy 378.807982 -283.297168)
			(xy 378.791934 -283.346561) (xy 378.768356 -283.392835) (xy 378.73783 -283.434851) (xy 378.701107 -283.471574)
			(xy 378.659091 -283.5021) (xy 378.612817 -283.525678) (xy 378.563424 -283.541726) (xy 378.512129 -283.549851)
			(xy 378.460195 -283.549851) (xy 378.4089 -283.541726) (xy 378.359507 -283.525678) (xy 378.313233 -283.5021)
			(xy 378.271217 -283.471574) (xy 378.234494 -283.434851) (xy 378.203968 -283.392835) (xy 378.18039 -283.346561)
			(xy 378.164342 -283.297168) (xy 378.156217 -283.245873) (xy 377.876307 -283.245873) (xy 377.868182 -283.297168)
			(xy 377.852134 -283.346561) (xy 377.828556 -283.392835) (xy 377.79803 -283.434851) (xy 377.761307 -283.471574)
			(xy 377.719291 -283.5021) (xy 377.673017 -283.525678) (xy 377.623624 -283.541726) (xy 377.572329 -283.549851)
			(xy 377.520395 -283.549851) (xy 377.4691 -283.541726) (xy 377.419707 -283.525678) (xy 377.373433 -283.5021)
			(xy 377.331417 -283.471574) (xy 377.294694 -283.434851) (xy 377.264168 -283.392835) (xy 377.24059 -283.346561)
			(xy 377.224542 -283.297168) (xy 377.216417 -283.245873) (xy 376.936467 -283.245873) (xy 376.928382 -283.296914)
			(xy 376.912334 -283.346307) (xy 376.888756 -283.392581) (xy 376.85823 -283.434597) (xy 376.821507 -283.47132)
			(xy 376.779491 -283.501846) (xy 376.733217 -283.525424) (xy 376.683824 -283.541472) (xy 376.632529 -283.549597)
			(xy 376.580595 -283.549597) (xy 376.5293 -283.541472) (xy 376.479907 -283.525424) (xy 376.433633 -283.501846)
			(xy 376.391617 -283.47132) (xy 376.354894 -283.434597) (xy 376.324368 -283.392581) (xy 376.30079 -283.346307)
			(xy 376.284742 -283.296914) (xy 376.276617 -283.245619) (xy 375.056912 -283.245619) (xy 375.056907 -283.245873)
			(xy 375.048782 -283.297168) (xy 375.032734 -283.346561) (xy 375.009156 -283.392835) (xy 374.97863 -283.434851)
			(xy 374.941907 -283.471574) (xy 374.899891 -283.5021) (xy 374.853617 -283.525678) (xy 374.804224 -283.541726)
			(xy 374.752929 -283.549851) (xy 374.700995 -283.549851) (xy 374.6497 -283.541726) (xy 374.600307 -283.525678)
			(xy 374.554033 -283.5021) (xy 374.512017 -283.471574) (xy 374.475294 -283.434851) (xy 374.444768 -283.392835)
			(xy 374.42119 -283.346561) (xy 374.405142 -283.297168) (xy 374.397017 -283.245873) (xy 374.117361 -283.245873)
			(xy 374.109236 -283.297168) (xy 374.093188 -283.346561) (xy 374.06961 -283.392835) (xy 374.039084 -283.434851)
			(xy 374.002361 -283.471574) (xy 373.960345 -283.5021) (xy 373.914071 -283.525678) (xy 373.864678 -283.541726)
			(xy 373.813383 -283.549851) (xy 373.761449 -283.549851) (xy 373.710154 -283.541726) (xy 373.660761 -283.525678)
			(xy 373.614487 -283.5021) (xy 373.572471 -283.471574) (xy 373.535748 -283.434851) (xy 373.505222 -283.392835)
			(xy 373.481644 -283.346561) (xy 373.465596 -283.297168) (xy 373.457471 -283.245873) (xy 373.177561 -283.245873)
			(xy 373.169436 -283.297168) (xy 373.153388 -283.346561) (xy 373.12981 -283.392835) (xy 373.099284 -283.434851)
			(xy 373.062561 -283.471574) (xy 373.020545 -283.5021) (xy 372.974271 -283.525678) (xy 372.924878 -283.541726)
			(xy 372.873583 -283.549851) (xy 372.821649 -283.549851) (xy 372.770354 -283.541726) (xy 372.720961 -283.525678)
			(xy 372.674687 -283.5021) (xy 372.632671 -283.471574) (xy 372.595948 -283.434851) (xy 372.565422 -283.392835)
			(xy 372.541844 -283.346561) (xy 372.525796 -283.297168) (xy 372.517671 -283.245873) (xy 371.297961 -283.245873)
			(xy 371.289836 -283.297168) (xy 371.273788 -283.346561) (xy 371.25021 -283.392835) (xy 371.219684 -283.434851)
			(xy 371.182961 -283.471574) (xy 371.140945 -283.5021) (xy 371.094671 -283.525678) (xy 371.045278 -283.541726)
			(xy 370.993983 -283.549851) (xy 370.942049 -283.549851) (xy 370.890754 -283.541726) (xy 370.841361 -283.525678)
			(xy 370.795087 -283.5021) (xy 370.753071 -283.471574) (xy 370.716348 -283.434851) (xy 370.685822 -283.392835)
			(xy 370.662244 -283.346561) (xy 370.646196 -283.297168) (xy 370.638071 -283.245873) (xy 370.357907 -283.245873)
			(xy 370.349782 -283.297168) (xy 370.333734 -283.346561) (xy 370.310156 -283.392835) (xy 370.27963 -283.434851)
			(xy 370.242907 -283.471574) (xy 370.200891 -283.5021) (xy 370.154617 -283.525678) (xy 370.105224 -283.541726)
			(xy 370.053929 -283.549851) (xy 370.001995 -283.549851) (xy 369.9507 -283.541726) (xy 369.901307 -283.525678)
			(xy 369.855033 -283.5021) (xy 369.813017 -283.471574) (xy 369.776294 -283.434851) (xy 369.745768 -283.392835)
			(xy 369.72219 -283.346561) (xy 369.706142 -283.297168) (xy 369.698017 -283.245873) (xy 369.418107 -283.245873)
			(xy 369.409982 -283.297168) (xy 369.393934 -283.346561) (xy 369.370356 -283.392835) (xy 369.33983 -283.434851)
			(xy 369.303107 -283.471574) (xy 369.261091 -283.5021) (xy 369.214817 -283.525678) (xy 369.165424 -283.541726)
			(xy 369.114129 -283.549851) (xy 369.062195 -283.549851) (xy 369.0109 -283.541726) (xy 368.961507 -283.525678)
			(xy 368.915233 -283.5021) (xy 368.873217 -283.471574) (xy 368.836494 -283.434851) (xy 368.805968 -283.392835)
			(xy 368.78239 -283.346561) (xy 368.766342 -283.297168) (xy 368.758217 -283.245873) (xy 368.478561 -283.245873)
			(xy 368.470436 -283.297168) (xy 368.454388 -283.346561) (xy 368.43081 -283.392835) (xy 368.400284 -283.434851)
			(xy 368.363561 -283.471574) (xy 368.321545 -283.5021) (xy 368.275271 -283.525678) (xy 368.225878 -283.541726)
			(xy 368.174583 -283.549851) (xy 368.122649 -283.549851) (xy 368.071354 -283.541726) (xy 368.021961 -283.525678)
			(xy 367.975687 -283.5021) (xy 367.933671 -283.471574) (xy 367.896948 -283.434851) (xy 367.866422 -283.392835)
			(xy 367.842844 -283.346561) (xy 367.826796 -283.297168) (xy 367.818671 -283.245873) (xy 367.538352 -283.245873)
			(xy 367.531436 -283.292523) (xy 367.517276 -283.339184) (xy 367.496413 -283.383258) (xy 367.469301 -283.423789)
			(xy 367.436529 -283.459897) (xy 367.398806 -283.490797) (xy 367.356954 -283.515819) (xy 367.311878 -283.534421)
			(xy 367.288318 -283.540708) (xy 367.275391 -283.54433) (xy 367.251926 -283.557354) (xy 367.232673 -283.57605)
			(xy 367.218966 -283.599123) (xy 367.211756 -283.624973) (xy 367.211541 -283.651809) (xy 367.218337 -283.677771)
			(xy 367.231672 -283.70106) (xy 367.24082 -283.710888) (xy 367.316004 -283.786072) (xy 367.327362 -283.796653)
			(xy 367.354873 -283.810998) (xy 367.385422 -283.816423) (xy 367.41619 -283.812426) (xy 367.444339 -283.799377)
			(xy 367.456212 -283.789374) (xy 367.474545 -283.773273) (xy 367.515061 -283.746087) (xy 367.559135 -283.725157)
			(xy 367.605809 -283.710939) (xy 367.654066 -283.703741) (xy 367.678462 -283.703268) (xy 367.704433 -283.703748)
			(xy 367.755735 -283.711868) (xy 367.805135 -283.727915) (xy 367.851417 -283.751493) (xy 367.893439 -283.782022)
			(xy 367.930168 -283.818749) (xy 367.960698 -283.86077) (xy 367.984279 -283.90705) (xy 368.000328 -283.956449)
			(xy 368.008451 -284.007751) (xy 368.008916 -284.033722) (xy 368.008395 -284.060138) (xy 367.999979 -284.112296)
			(xy 367.983366 -284.162448) (xy 367.95898 -284.209315) (xy 367.943638 -284.230826) (xy 367.965728 -284.257636)
			(xy 368.006409 -284.313952) (xy 368.024918 -284.343348) (xy 368.272314 -284.343348) (xy 368.290784 -284.314094)
			(xy 368.331338 -284.258033) (xy 368.35334 -284.231334) (xy 368.337929 -284.209782) (xy 368.313445 -284.162799)
			(xy 368.296765 -284.112514) (xy 368.288315 -284.060212) (xy 368.287808 -284.033722) (xy 368.288316 -284.007753)
			(xy 368.296437 -283.956453) (xy 368.312483 -283.907055) (xy 368.336059 -283.860775) (xy 368.366584 -283.818753)
			(xy 368.403307 -283.782023) (xy 368.445324 -283.751491) (xy 368.491599 -283.727906) (xy 368.540994 -283.711851)
			(xy 368.592293 -283.70372) (xy 368.618262 -283.703268) (xy 368.645753 -283.703818) (xy 368.699975 -283.712924)
			(xy 368.751944 -283.730873) (xy 368.800228 -283.757171) (xy 368.843496 -283.791094) (xy 368.880557 -283.831707)
			(xy 368.910389 -283.877892) (xy 368.921792 -283.902912) (xy 368.963108 -283.896055) (xy 369.046538 -283.888677)
			(xy 369.088416 -283.88818) (xy 369.130167 -283.888688) (xy 369.213343 -283.896068) (xy 369.254532 -283.902912)
			(xy 369.265912 -283.877878) (xy 369.29573 -283.831676) (xy 369.332787 -283.79105) (xy 369.37606 -283.757122)
			(xy 369.424353 -283.730827) (xy 369.476334 -283.712892) (xy 369.530568 -283.703813) (xy 369.558062 -283.703268)
			(xy 369.584033 -283.703748) (xy 369.635335 -283.711868) (xy 369.684735 -283.727915) (xy 369.731017 -283.751493)
			(xy 369.773039 -283.782022) (xy 369.809768 -283.818749) (xy 369.840298 -283.86077) (xy 369.863879 -283.90705)
			(xy 369.879928 -283.956449) (xy 369.888051 -284.007751) (xy 369.888516 -284.033722) (xy 369.887995 -284.060138)
			(xy 369.879579 -284.112296) (xy 369.862966 -284.162448) (xy 369.83858 -284.209315) (xy 369.823238 -284.230826)
			(xy 369.845328 -284.257636) (xy 369.886009 -284.313952) (xy 369.904518 -284.343348) (xy 370.151914 -284.343348)
			(xy 370.170384 -284.314094) (xy 370.210938 -284.258033) (xy 370.23294 -284.231334) (xy 370.217529 -284.209782)
			(xy 370.193045 -284.162799) (xy 370.176365 -284.112514) (xy 370.167915 -284.060212) (xy 370.167408 -284.033722)
			(xy 370.167916 -284.007753) (xy 370.176037 -283.956453) (xy 370.192083 -283.907055) (xy 370.215659 -283.860775)
			(xy 370.246184 -283.818753) (xy 370.282907 -283.782023) (xy 370.324924 -283.751491) (xy 370.371199 -283.727906)
			(xy 370.420594 -283.711851) (xy 370.471893 -283.70372) (xy 370.497862 -283.703268) (xy 370.525353 -283.703818)
			(xy 370.579575 -283.712924) (xy 370.631544 -283.730873) (xy 370.679828 -283.757171) (xy 370.723096 -283.791094)
			(xy 370.760157 -283.831707) (xy 370.789989 -283.877892) (xy 370.801392 -283.902912) (xy 370.842708 -283.896055)
			(xy 370.926138 -283.888677) (xy 370.968016 -283.88818) (xy 371.009767 -283.888688) (xy 371.092943 -283.896068)
			(xy 371.134132 -283.902912) (xy 371.145512 -283.877878) (xy 371.17533 -283.831676) (xy 371.212387 -283.79105)
			(xy 371.25566 -283.757122) (xy 371.303953 -283.730827) (xy 371.355934 -283.712892) (xy 371.410168 -283.703813)
			(xy 371.437662 -283.703268) (xy 371.463633 -283.703748) (xy 371.514935 -283.711868) (xy 371.564335 -283.727915)
			(xy 371.610617 -283.751493) (xy 371.652639 -283.782022) (xy 371.689368 -283.818749) (xy 371.719898 -283.86077)
			(xy 371.743479 -283.90705) (xy 371.759528 -283.956449) (xy 371.767651 -284.007751) (xy 371.768116 -284.033722)
			(xy 371.767595 -284.060138) (xy 371.759179 -284.112296) (xy 371.742566 -284.162448) (xy 371.71818 -284.209315)
			(xy 371.702838 -284.230826) (xy 371.724928 -284.257636) (xy 371.765609 -284.313952) (xy 371.784118 -284.343348)
			(xy 372.031514 -284.343348) (xy 372.049984 -284.314094) (xy 372.090538 -284.258033) (xy 372.11254 -284.231334)
			(xy 372.097129 -284.209782) (xy 372.072645 -284.162799) (xy 372.055965 -284.112514) (xy 372.047515 -284.060212)
			(xy 372.047008 -284.033722) (xy 372.047516 -284.007753) (xy 372.055637 -283.956453) (xy 372.071683 -283.907055)
			(xy 372.095259 -283.860775) (xy 372.125784 -283.818753) (xy 372.162507 -283.782023) (xy 372.204524 -283.751491)
			(xy 372.250799 -283.727906) (xy 372.300194 -283.711851) (xy 372.351493 -283.70372) (xy 372.377462 -283.703268)
			(xy 372.404953 -283.703818) (xy 372.459175 -283.712924) (xy 372.511144 -283.730873) (xy 372.559428 -283.757171)
			(xy 372.602696 -283.791094) (xy 372.639757 -283.831707) (xy 372.669589 -283.877892) (xy 372.680992 -283.902912)
			(xy 372.722308 -283.896055) (xy 372.805738 -283.888677) (xy 372.847616 -283.88818) (xy 372.889431 -283.888664)
			(xy 372.972736 -283.896041) (xy 373.013986 -283.902912) (xy 373.025365 -283.877876) (xy 373.055182 -283.83167)
			(xy 373.092238 -283.791038) (xy 373.13551 -283.757104) (xy 373.183803 -283.730803) (xy 373.235785 -283.712861)
			(xy 373.29002 -283.703775) (xy 373.317516 -283.703268) (xy 373.343484 -283.703752) (xy 373.39478 -283.711879)
			(xy 373.444173 -283.727931) (xy 373.490447 -283.751512) (xy 373.532462 -283.782041) (xy 373.569184 -283.818767)
			(xy 373.599708 -283.860786) (xy 373.623284 -283.907062) (xy 373.63933 -283.956457) (xy 373.647451 -284.007754)
			(xy 373.64797 -284.033722) (xy 373.647425 -284.060179) (xy 373.638955 -284.112411) (xy 373.622283 -284.16263)
			(xy 373.597832 -284.209557) (xy 373.582438 -284.23108) (xy 373.60452 -284.257829) (xy 373.645197 -284.31402)
			(xy 373.663718 -284.343348) (xy 373.911114 -284.343348) (xy 373.929584 -284.314094) (xy 373.970138 -284.258033)
			(xy 373.99214 -284.231334) (xy 373.976729 -284.209782) (xy 373.952245 -284.162799) (xy 373.935565 -284.112514)
			(xy 373.927115 -284.060212) (xy 373.926608 -284.033722) (xy 373.927116 -284.007753) (xy 373.935237 -283.956453)
			(xy 373.951283 -283.907055) (xy 373.974859 -283.860775) (xy 374.005384 -283.818753) (xy 374.042107 -283.782023)
			(xy 374.084124 -283.751491) (xy 374.130399 -283.727906) (xy 374.179794 -283.711851) (xy 374.231093 -283.70372)
			(xy 374.257062 -283.703268) (xy 374.284553 -283.703818) (xy 374.338775 -283.712924) (xy 374.390744 -283.730873)
			(xy 374.439028 -283.757171) (xy 374.482296 -283.791094) (xy 374.519357 -283.831707) (xy 374.549189 -283.877892)
			(xy 374.560592 -283.902912) (xy 374.601908 -283.896055) (xy 374.685338 -283.888677) (xy 374.727216 -283.88818)
			(xy 374.768967 -283.888688) (xy 374.852143 -283.896068) (xy 374.893332 -283.902912) (xy 374.904712 -283.877878)
			(xy 374.93453 -283.831676) (xy 374.971587 -283.79105) (xy 375.01486 -283.757122) (xy 375.063153 -283.730827)
			(xy 375.115134 -283.712892) (xy 375.169368 -283.703813) (xy 375.196862 -283.703268) (xy 375.222833 -283.703748)
			(xy 375.274135 -283.711868) (xy 375.323535 -283.727915) (xy 375.369817 -283.751493) (xy 375.411839 -283.782022)
			(xy 375.448568 -283.818749) (xy 375.479098 -283.86077) (xy 375.502679 -283.90705) (xy 375.518728 -283.956449)
			(xy 375.526851 -284.007751) (xy 375.527316 -284.033722) (xy 375.526795 -284.060138) (xy 375.518379 -284.112296)
			(xy 375.501766 -284.162448) (xy 375.47738 -284.209315) (xy 375.462038 -284.230826) (xy 375.484128 -284.257636)
			(xy 375.524809 -284.313952) (xy 375.543318 -284.343348) (xy 375.790714 -284.343348) (xy 375.809184 -284.314094)
			(xy 375.849738 -284.258033) (xy 375.87174 -284.231334) (xy 375.856329 -284.209782) (xy 375.831845 -284.162799)
			(xy 375.815165 -284.112514) (xy 375.806715 -284.060212) (xy 375.806208 -284.033722) (xy 375.806716 -284.007753)
			(xy 375.814837 -283.956453) (xy 375.830883 -283.907055) (xy 375.854459 -283.860775) (xy 375.884984 -283.818753)
			(xy 375.921707 -283.782023) (xy 375.963724 -283.751491) (xy 376.009999 -283.727906) (xy 376.059394 -283.711851)
			(xy 376.110693 -283.70372) (xy 376.136662 -283.703268) (xy 376.164153 -283.703818) (xy 376.218375 -283.712924)
			(xy 376.270344 -283.730873) (xy 376.318628 -283.757171) (xy 376.361896 -283.791094) (xy 376.398957 -283.831707)
			(xy 376.428789 -283.877892) (xy 376.440192 -283.902912) (xy 376.481508 -283.896055) (xy 376.564938 -283.888677)
			(xy 376.606816 -283.88818) (xy 376.648567 -283.888688) (xy 376.731743 -283.896068) (xy 376.772932 -283.902912)
			(xy 376.784312 -283.877878) (xy 376.81413 -283.831676) (xy 376.851187 -283.79105) (xy 376.89446 -283.757122)
			(xy 376.942753 -283.730827) (xy 376.994734 -283.712892) (xy 377.048968 -283.703813) (xy 377.076462 -283.703268)
			(xy 377.102433 -283.703748) (xy 377.153735 -283.711868) (xy 377.203135 -283.727915) (xy 377.249417 -283.751493)
			(xy 377.291439 -283.782022) (xy 377.328168 -283.818749) (xy 377.358698 -283.86077) (xy 377.382279 -283.90705)
			(xy 377.398328 -283.956449) (xy 377.406451 -284.007751) (xy 377.406916 -284.033722) (xy 377.406395 -284.060138)
			(xy 377.397979 -284.112296) (xy 377.381366 -284.162448) (xy 377.35698 -284.209315) (xy 377.341638 -284.230826)
			(xy 377.363728 -284.257636) (xy 377.404409 -284.313952) (xy 377.422918 -284.343348) (xy 377.670314 -284.343348)
			(xy 377.688784 -284.314094) (xy 377.729338 -284.258033) (xy 377.75134 -284.231334) (xy 377.735929 -284.209782)
			(xy 377.711445 -284.162799) (xy 377.694765 -284.112514) (xy 377.686315 -284.060212) (xy 377.685808 -284.033722)
			(xy 377.686316 -284.007753) (xy 377.694437 -283.956453) (xy 377.710483 -283.907055) (xy 377.734059 -283.860775)
			(xy 377.764584 -283.818753) (xy 377.801307 -283.782023) (xy 377.843324 -283.751491) (xy 377.889599 -283.727906)
			(xy 377.938994 -283.711851) (xy 377.990293 -283.70372) (xy 378.016262 -283.703268) (xy 378.043753 -283.703818)
			(xy 378.097975 -283.712924) (xy 378.149944 -283.730873) (xy 378.198228 -283.757171) (xy 378.241496 -283.791094)
			(xy 378.278557 -283.831707) (xy 378.308389 -283.877892) (xy 378.319792 -283.902912) (xy 378.361108 -283.896055)
			(xy 378.444538 -283.888677) (xy 378.486416 -283.88818) (xy 378.528167 -283.888688) (xy 378.611343 -283.896068)
			(xy 378.652532 -283.902912) (xy 378.663912 -283.877878) (xy 378.69373 -283.831676) (xy 378.730787 -283.79105)
			(xy 378.77406 -283.757122) (xy 378.822353 -283.730827) (xy 378.874334 -283.712892) (xy 378.928568 -283.703813)
			(xy 378.956062 -283.703268) (xy 378.982033 -283.703748) (xy 379.033335 -283.711868) (xy 379.082735 -283.727915)
			(xy 379.129017 -283.751493) (xy 379.171039 -283.782022) (xy 379.207768 -283.818749) (xy 379.238298 -283.86077)
			(xy 379.261879 -283.90705) (xy 379.277928 -283.956449) (xy 379.286051 -284.007751) (xy 379.286516 -284.033722)
			(xy 379.285995 -284.060138) (xy 379.277579 -284.112296) (xy 379.260966 -284.162448) (xy 379.23658 -284.209315)
			(xy 379.221238 -284.230826) (xy 379.243328 -284.257636) (xy 379.284009 -284.313952) (xy 379.302518 -284.343348)
			(xy 379.549914 -284.343348) (xy 379.568384 -284.314094) (xy 379.608938 -284.258033) (xy 379.63094 -284.231334)
			(xy 379.615529 -284.209782) (xy 379.591045 -284.162799) (xy 379.574365 -284.112514) (xy 379.565915 -284.060212)
			(xy 379.565408 -284.033722) (xy 379.565916 -284.007753) (xy 379.574037 -283.956453) (xy 379.590083 -283.907055)
			(xy 379.613659 -283.860775) (xy 379.644184 -283.818753) (xy 379.680907 -283.782023) (xy 379.722924 -283.751491)
			(xy 379.769199 -283.727906) (xy 379.818594 -283.711851) (xy 379.869893 -283.70372) (xy 379.895862 -283.703268)
			(xy 379.923353 -283.703818) (xy 379.977575 -283.712924) (xy 380.029544 -283.730873) (xy 380.077828 -283.757171)
			(xy 380.121096 -283.791094) (xy 380.158157 -283.831707) (xy 380.187989 -283.877892) (xy 380.199392 -283.902912)
			(xy 380.240708 -283.896055) (xy 380.324138 -283.888677) (xy 380.366016 -283.88818) (xy 380.407767 -283.888688)
			(xy 380.490943 -283.896068) (xy 380.532132 -283.902912) (xy 380.543512 -283.877878) (xy 380.57333 -283.831676)
			(xy 380.610387 -283.79105) (xy 380.65366 -283.757122) (xy 380.701953 -283.730827) (xy 380.753934 -283.712892)
			(xy 380.808168 -283.703813) (xy 380.835662 -283.703268) (xy 380.861633 -283.703748) (xy 380.912935 -283.711868)
			(xy 380.962335 -283.727915) (xy 381.008617 -283.751493) (xy 381.050639 -283.782022) (xy 381.087368 -283.818749)
			(xy 381.117898 -283.86077) (xy 381.141479 -283.90705) (xy 381.157528 -283.956449) (xy 381.165651 -284.007751)
			(xy 381.166116 -284.033722) (xy 381.165595 -284.060138) (xy 381.157179 -284.112296) (xy 381.140566 -284.162448)
			(xy 381.11618 -284.209315) (xy 381.100838 -284.230826) (xy 381.122928 -284.257636) (xy 381.163609 -284.313952)
			(xy 381.182118 -284.343348) (xy 382.336802 -284.343348) (xy 382.351868 -284.342762) (xy 382.380669 -284.333899)
			(xy 382.40564 -284.31703) (xy 382.424614 -284.293619) (xy 382.435945 -284.265696) (xy 382.438652 -284.235683)
			(xy 382.432498 -284.206183) (xy 382.425702 -284.192726) (xy 382.412855 -284.168211) (xy 382.394632 -284.115955)
			(xy 382.385372 -284.061393) (xy 382.384808 -284.033722) (xy 382.385317 -284.007755) (xy 382.393442 -283.95646)
			(xy 382.40949 -283.907067) (xy 382.433068 -283.860793) (xy 382.463594 -283.818777) (xy 382.500317 -283.782054)
			(xy 382.542333 -283.751528) (xy 382.588607 -283.72795) (xy 382.638 -283.711902) (xy 382.689295 -283.703777)
			(xy 382.741229 -283.703777) (xy 382.792524 -283.711902) (xy 382.841917 -283.72795) (xy 382.888191 -283.751528)
			(xy 382.930207 -283.782054) (xy 382.96693 -283.818777) (xy 382.997456 -283.860793) (xy 383.021034 -283.907067)
			(xy 383.037082 -283.95646) (xy 383.045207 -284.007755) (xy 383.045716 -284.033722) (xy 383.045129 -284.06139)
			(xy 383.035862 -284.115947) (xy 383.017642 -284.168199) (xy 383.004822 -284.192726) (xy 382.998015 -284.206197)
			(xy 382.991794 -284.235715) (xy 382.994462 -284.265764) (xy 383.005787 -284.293724) (xy 383.024783 -284.317159)
			(xy 383.049793 -284.334027) (xy 383.078639 -284.342857) (xy 383.093722 -284.343348) (xy 385.769612 -284.343348)
			(xy 385.96697 -284.14599) (xy 385.96697 -283.550614) (xy 385.928108 -283.541216) (xy 385.902933 -283.534724)
			(xy 385.854869 -283.51491) (xy 385.810503 -283.487812) (xy 385.770929 -283.454097) (xy 385.737126 -283.4146)
			(xy 385.709928 -283.370295) (xy 385.690006 -283.322275) (xy 385.677852 -283.271728) (xy 385.673767 -283.219901)
			(xy 385.677852 -283.168074) (xy 385.690005 -283.117527) (xy 385.709926 -283.069508) (xy 385.737124 -283.025202)
			(xy 385.770927 -282.985705) (xy 385.810501 -282.95199) (xy 385.854867 -282.924891) (xy 385.902931 -282.905077)
			(xy 385.928108 -282.898596) (xy 385.96697 -282.889198) (xy 385.96697 -281.922728) (xy 385.927854 -281.913584)
			(xy 385.904082 -281.907431) (xy 385.858545 -281.88906) (xy 385.816224 -281.86416) (xy 385.77805 -281.833277)
			(xy 385.744859 -281.79709) (xy 385.717384 -281.756394) (xy 385.696226 -281.712083) (xy 385.681851 -281.665132)
			(xy 385.674574 -281.616571) (xy 385.674108 -281.59202) (xy 385.674734 -281.563177) (xy 385.684742 -281.506367)
			(xy 385.704457 -281.452155) (xy 385.733282 -281.402188) (xy 385.751324 -281.379676) (xy 385.7606 -281.367782)
			(xy 385.772399 -281.340039) (xy 385.775579 -281.310059) (xy 385.769863 -281.280459) (xy 385.755749 -281.253819)
			(xy 385.745482 -281.24277) (xy 385.605528 -281.102816) (xy 385.599432 -281.102816) (xy 385.579874 -281.10561)
			(xy 385.568626 -281.107045) (xy 385.546001 -281.108567) (xy 385.534662 -281.108658) (xy 385.52017 -281.108503)
			(xy 385.491299 -281.10596) (xy 385.477004 -281.103578) (xy 385.472686 -281.102816) (xy 384.656838 -281.102816)
			(xy 384.65252 -281.103578) (xy 384.638224 -281.105951) (xy 384.609353 -281.108491) (xy 384.594862 -281.108658)
			(xy 384.58037 -281.108503) (xy 384.551499 -281.10596) (xy 384.537204 -281.103578) (xy 384.532886 -281.102816)
			(xy 383.717038 -281.102816) (xy 383.71272 -281.103578) (xy 383.698424 -281.105951) (xy 383.669553 -281.108491)
			(xy 383.655062 -281.108658) (xy 383.64057 -281.108503) (xy 383.611699 -281.10596) (xy 383.597404 -281.103578)
			(xy 383.593086 -281.102816) (xy 382.778508 -281.102816) (xy 382.77419 -281.103578) (xy 382.759585 -281.106067)
			(xy 382.730076 -281.108736) (xy 382.715262 -281.108912) (xy 382.700447 -281.108737) (xy 382.670938 -281.10607)
			(xy 382.656334 -281.103578) (xy 382.652016 -281.102816) (xy 381.837438 -281.102816) (xy 381.83312 -281.103578)
			(xy 381.818824 -281.105951) (xy 381.789953 -281.108491) (xy 381.775462 -281.108658) (xy 381.76097 -281.108503)
			(xy 381.732099 -281.10596) (xy 381.717804 -281.103578) (xy 381.713486 -281.102816) (xy 381.558546 -281.102816)
			(xy 381.31242 -280.85669) (xy 381.301765 -280.84682) (xy 381.276253 -280.83297) (xy 381.247873 -280.826861)
			(xy 381.218921 -280.828988) (xy 381.191739 -280.839178) (xy 381.168524 -280.856608) (xy 381.151154 -280.879867)
			(xy 381.145542 -280.893266) (xy 381.136341 -280.916636) (xy 381.111901 -280.960511) (xy 381.08111 -281.000188)
			(xy 381.044676 -281.034756) (xy 381.003436 -281.06342) (xy 380.958337 -281.085521) (xy 380.910416 -281.100552)
			(xy 380.860773 -281.108167) (xy 380.835662 -281.108658) (xy 380.809697 -281.108146) (xy 380.758406 -281.100017)
			(xy 380.709018 -281.083965) (xy 380.662749 -281.060385) (xy 380.620738 -281.029858) (xy 380.58402 -280.993136)
			(xy 380.553497 -280.951122) (xy 380.529922 -280.90485) (xy 380.513875 -280.855461) (xy 380.505751 -280.804169)
			(xy 380.505208 -280.778204) (xy 380.505668 -280.753087) (xy 380.513255 -280.703429) (xy 380.528269 -280.655491)
			(xy 380.550365 -280.610378) (xy 380.579034 -280.569128) (xy 380.613615 -280.532692) (xy 380.653312 -280.501909)
			(xy 380.69721 -280.477488) (xy 380.7206 -280.468324) (xy 380.734068 -280.462841) (xy 380.757377 -280.445474)
			(xy 380.77484 -280.422237) (xy 380.78504 -280.395018) (xy 380.787148 -280.366027) (xy 380.780994 -280.337619)
			(xy 380.767076 -280.3121) (xy 380.757176 -280.301446) (xy 380.627382 -280.171652) (xy 380.591568 -280.205434)
			(xy 380.573102 -280.222106) (xy 380.532099 -280.250277) (xy 380.487335 -280.271981) (xy 380.439823 -280.286726)
			(xy 380.390636 -280.294181) (xy 380.365762 -280.294588) (xy 380.339796 -280.294076) (xy 380.288503 -280.285947)
			(xy 380.239114 -280.269896) (xy 380.192843 -280.246316) (xy 380.150829 -280.21579) (xy 380.114107 -280.179068)
			(xy 380.083582 -280.137054) (xy 380.060003 -280.090783) (xy 380.043952 -280.041393) (xy 380.035824 -279.9901)
			(xy 380.035308 -279.964134) (xy 380.035762 -279.939264) (xy 380.043224 -279.890086) (xy 380.057969 -279.842581)
			(xy 380.079664 -279.797821) (xy 380.10782 -279.756816) (xy 380.124462 -279.738328) (xy 380.138178 -279.70353)
			(xy 380.137691 -279.693569) (xy 380.1301 -279.675147) (xy 380.123446 -279.667716) (xy 379.934978 -279.479248)
			(xy 379.912372 -279.480264) (xy 379.896116 -279.480772) (xy 379.870147 -279.480264) (xy 379.818849 -279.472142)
			(xy 379.769454 -279.456095) (xy 379.723176 -279.432518) (xy 379.681157 -279.401992) (xy 379.64443 -279.365269)
			(xy 379.6139 -279.323253) (xy 379.590318 -279.276978) (xy 379.574266 -279.227584) (xy 379.566139 -279.176287)
			(xy 379.565662 -279.150318) (xy 379.56617 -279.134062) (xy 379.567186 -279.111456) (xy 379.490478 -279.034748)
			(xy 379.490478 -278.765762) (xy 379.4901 -278.756444) (xy 379.483306 -278.73909) (xy 379.47727 -278.73198)
			(xy 379.431042 -278.681942) (xy 379.398784 -278.666194) (xy 379.389894 -278.665178) (xy 379.364661 -278.661921)
			(xy 379.315545 -278.648656) (xy 379.269041 -278.628025) (xy 379.226245 -278.600515) (xy 379.188167 -278.566774)
			(xy 379.155707 -278.5276) (xy 379.129629 -278.483916) (xy 379.11055 -278.436754) (xy 379.098919 -278.387225)
			(xy 379.095011 -278.3365) (xy 379.098919 -278.285775) (xy 379.11055 -278.236247) (xy 379.129629 -278.189084)
			(xy 379.155706 -278.1454) (xy 379.188167 -278.106226) (xy 379.226244 -278.072485) (xy 379.26904 -278.044975)
			(xy 379.315545 -278.024344) (xy 379.364661 -278.011079) (xy 379.389894 -278.007826) (xy 379.398784 -278.00681)
			(xy 379.431042 -277.991062) (xy 379.47727 -277.941024) (xy 379.483231 -277.933871) (xy 379.489999 -277.916542)
			(xy 379.490478 -277.907242) (xy 379.490478 -277.137876) (xy 379.490103 -277.128557) (xy 379.483312 -277.1112)
			(xy 379.47727 -277.104094) (xy 379.431042 -277.054056) (xy 379.398784 -277.038308) (xy 379.389894 -277.037292)
			(xy 379.36466 -277.034035) (xy 379.315542 -277.02077) (xy 379.269036 -277.000138) (xy 379.226238 -276.972627)
			(xy 379.188158 -276.938885) (xy 379.155696 -276.899709) (xy 379.129617 -276.856024) (xy 379.110537 -276.808859)
			(xy 379.098906 -276.759329) (xy 379.094997 -276.708602) (xy 379.098905 -276.657874) (xy 379.110536 -276.608344)
			(xy 379.129616 -276.561179) (xy 379.155694 -276.517494) (xy 379.188156 -276.478317) (xy 379.226235 -276.444575)
			(xy 379.269033 -276.417064) (xy 379.315539 -276.396431) (xy 379.364657 -276.383166) (xy 379.389894 -276.37994)
			(xy 379.398784 -276.378924) (xy 379.431042 -276.363176) (xy 379.47727 -276.313138) (xy 379.483233 -276.305986)
			(xy 379.490006 -276.288657) (xy 379.490478 -276.279356) (xy 379.490478 -275.50999) (xy 379.490105 -275.500669)
			(xy 379.483318 -275.483309) (xy 379.47727 -275.476208) (xy 379.431042 -275.42617) (xy 379.398784 -275.410422)
			(xy 379.389894 -275.409406) (xy 379.364659 -275.406149) (xy 379.315539 -275.392883) (xy 379.26903 -275.372251)
			(xy 379.22623 -275.344739) (xy 379.188149 -275.310996) (xy 379.155686 -275.271819) (xy 379.129605 -275.228131)
			(xy 379.110524 -275.180965) (xy 379.098892 -275.131433) (xy 379.094984 -275.080703) (xy 379.098891 -275.029974)
			(xy 379.110522 -274.980441) (xy 379.129603 -274.933275) (xy 379.155682 -274.889587) (xy 379.188145 -274.850409)
			(xy 379.226225 -274.816665) (xy 379.269025 -274.789152) (xy 379.315533 -274.768519) (xy 379.364653 -274.755252)
			(xy 379.389894 -274.752054) (xy 379.398784 -274.751038) (xy 379.431042 -274.73529) (xy 379.47727 -274.685252)
			(xy 379.483235 -274.6781) (xy 379.490013 -274.660771) (xy 379.490478 -274.65147) (xy 379.490478 -273.882358)
			(xy 379.4901 -273.87304) (xy 379.483304 -273.855688) (xy 379.47727 -273.848576) (xy 379.431042 -273.798538)
			(xy 379.398784 -273.78279) (xy 379.389894 -273.781774) (xy 379.364662 -273.778517) (xy 379.315546 -273.765252)
			(xy 379.269042 -273.744621) (xy 379.226247 -273.717111) (xy 379.18817 -273.683371) (xy 379.15571 -273.644197)
			(xy 379.129632 -273.600514) (xy 379.110553 -273.553352) (xy 379.098923 -273.503824) (xy 379.095015 -273.4531)
			(xy 379.098923 -273.402375) (xy 379.110554 -273.352848) (xy 379.129633 -273.305686) (xy 379.15571 -273.262002)
			(xy 379.18817 -273.222828) (xy 379.226247 -273.189088) (xy 379.269043 -273.161578) (xy 379.315547 -273.140948)
			(xy 379.364662 -273.127683) (xy 379.389894 -273.124422) (xy 379.398784 -273.123406) (xy 379.431042 -273.107658)
			(xy 379.47727 -273.05762) (xy 379.483231 -273.050467) (xy 379.489997 -273.033138) (xy 379.490478 -273.023838)
			(xy 379.490478 -272.254472) (xy 379.490102 -272.245153) (xy 379.48331 -272.227797) (xy 379.47727 -272.22069)
			(xy 379.431042 -272.170652) (xy 379.398784 -272.154904) (xy 379.389894 -272.153888) (xy 379.364661 -272.150631)
			(xy 379.315543 -272.137366) (xy 379.269037 -272.116734) (xy 379.22624 -272.089223) (xy 379.188161 -272.055482)
			(xy 379.155699 -272.016307) (xy 379.129621 -271.972622) (xy 379.110541 -271.925458) (xy 379.098909 -271.875928)
			(xy 379.095001 -271.825201) (xy 379.098909 -271.774475) (xy 379.11054 -271.724945) (xy 379.129619 -271.677781)
			(xy 379.155698 -271.634095) (xy 379.188159 -271.59492) (xy 379.226238 -271.561178) (xy 379.269035 -271.533667)
			(xy 379.315541 -271.513035) (xy 379.364658 -271.499769) (xy 379.389894 -271.496536) (xy 379.398784 -271.49552)
			(xy 379.431042 -271.479772) (xy 379.47727 -271.429734) (xy 379.483233 -271.422581) (xy 379.490004 -271.405252)
			(xy 379.490478 -271.395952) (xy 379.490478 -270.62684) (xy 379.490097 -270.617523) (xy 379.483297 -270.600175)
			(xy 379.47727 -270.593058) (xy 379.431042 -270.54302) (xy 379.398784 -270.527272) (xy 379.389894 -270.526256)
			(xy 379.364663 -270.522999) (xy 379.315551 -270.509734) (xy 379.269049 -270.489104) (xy 379.226256 -270.461596)
			(xy 379.188182 -270.427857) (xy 379.155723 -270.388685) (xy 379.129648 -270.345004) (xy 379.11057 -270.297845)
			(xy 379.098941 -270.24832) (xy 379.095034 -270.197598) (xy 379.098941 -270.146876) (xy 379.110572 -270.097351)
			(xy 379.12965 -270.050192) (xy 379.155726 -270.006511) (xy 379.188185 -269.96734) (xy 379.22626 -269.933602)
			(xy 379.269053 -269.906094) (xy 379.315555 -269.885464) (xy 379.364667 -269.872201) (xy 379.389894 -269.868904)
			(xy 379.398784 -269.867888) (xy 379.431042 -269.85214) (xy 379.47727 -269.802102) (xy 379.483228 -269.794948)
			(xy 379.489989 -269.777619) (xy 379.490478 -269.76832) (xy 379.490478 -268.998954) (xy 379.490099 -268.989636)
			(xy 379.483303 -268.972285) (xy 379.47727 -268.965172) (xy 379.431042 -268.915134) (xy 379.398784 -268.899386)
			(xy 379.389894 -268.89837) (xy 379.364662 -268.895113) (xy 379.315547 -268.881848) (xy 379.269044 -268.861217)
			(xy 379.226249 -268.833708) (xy 379.188173 -268.799968) (xy 379.155713 -268.760794) (xy 379.129636 -268.717112)
			(xy 379.110558 -268.66995) (xy 379.098927 -268.620423) (xy 379.09502 -268.569699) (xy 379.098927 -268.518975)
			(xy 379.110558 -268.469448) (xy 379.129637 -268.422287) (xy 379.155714 -268.378604) (xy 379.188174 -268.339431)
			(xy 379.22625 -268.305692) (xy 379.269045 -268.278182) (xy 379.315549 -268.257552) (xy 379.364663 -268.244287)
			(xy 379.389894 -268.241018) (xy 379.398784 -268.240002) (xy 379.431042 -268.224254) (xy 379.47727 -268.174216)
			(xy 379.48323 -268.167063) (xy 379.489995 -268.149733) (xy 379.490478 -268.140434) (xy 379.490478 -267.371068)
			(xy 379.490101 -267.361749) (xy 379.483309 -267.344394) (xy 379.47727 -267.337286) (xy 379.431042 -267.287248)
			(xy 379.398784 -267.2715) (xy 379.389894 -267.270484) (xy 379.364661 -267.267227) (xy 379.315544 -267.253962)
			(xy 379.269039 -267.233331) (xy 379.226242 -267.20582) (xy 379.188163 -267.172079) (xy 379.155702 -267.132904)
			(xy 379.129624 -267.089219) (xy 379.110544 -267.042056) (xy 379.098913 -266.992527) (xy 379.095005 -266.941801)
			(xy 379.098913 -266.891075) (xy 379.110544 -266.841546) (xy 379.129623 -266.794382) (xy 379.155701 -266.750697)
			(xy 379.188162 -266.711522) (xy 379.22624 -266.677781) (xy 379.269037 -266.65027) (xy 379.315542 -266.629639)
			(xy 379.364659 -266.616373) (xy 379.389894 -266.613132) (xy 379.398784 -266.612116) (xy 379.431042 -266.596368)
			(xy 379.47727 -266.54633) (xy 379.483232 -266.539177) (xy 379.490002 -266.521848) (xy 379.490478 -266.512548)
			(xy 379.490478 -265.743436) (xy 379.490096 -265.734119) (xy 379.483295 -265.716773) (xy 379.47727 -265.709654)
			(xy 379.431042 -265.659616) (xy 379.398784 -265.643868) (xy 379.389894 -265.642852) (xy 379.364663 -265.639595)
			(xy 379.315552 -265.62633) (xy 379.269051 -265.605701) (xy 379.226258 -265.578192) (xy 379.188184 -265.544454)
			(xy 379.155726 -265.505283) (xy 379.129651 -265.461602) (xy 379.110574 -265.414443) (xy 379.098945 -265.364919)
			(xy 379.095038 -265.314197) (xy 379.098945 -265.263476) (xy 379.110576 -265.213952) (xy 379.129654 -265.166793)
			(xy 379.15573 -265.123113) (xy 379.188188 -265.083942) (xy 379.226263 -265.050205) (xy 379.269055 -265.022697)
			(xy 379.315557 -265.002068) (xy 379.364669 -264.988804) (xy 379.389894 -264.9855) (xy 379.398784 -264.984484)
			(xy 379.431042 -264.968736) (xy 379.47727 -264.918698) (xy 379.483227 -264.911544) (xy 379.489987 -264.894214)
			(xy 379.490478 -264.884916) (xy 379.490478 -264.115804) (xy 379.490108 -264.106482) (xy 379.483324 -264.089119)
			(xy 379.47727 -264.082022) (xy 379.431042 -264.031984) (xy 379.398784 -264.016236) (xy 379.389894 -264.01522)
			(xy 379.364658 -264.011963) (xy 379.315536 -263.998697) (xy 379.269025 -263.978064) (xy 379.226223 -263.950551)
			(xy 379.18814 -263.916807) (xy 379.155675 -263.877628) (xy 379.129594 -263.833939) (xy 379.110511 -263.786771)
			(xy 379.098878 -263.737236) (xy 379.09497 -263.686505) (xy 379.098877 -263.635773) (xy 379.110508 -263.586238)
			(xy 379.129589 -263.53907) (xy 379.15567 -263.49538) (xy 379.188134 -263.4562) (xy 379.226216 -263.422455)
			(xy 379.269017 -263.394941) (xy 379.315527 -263.374306) (xy 379.364649 -263.361039) (xy 379.389894 -263.357868)
			(xy 379.398784 -263.356852) (xy 379.431042 -263.341104) (xy 379.47727 -263.291066) (xy 379.483238 -263.283915)
			(xy 379.49002 -263.266586) (xy 379.490478 -263.257284) (xy 379.490478 -262.922258) (xy 379.515878 -262.896858)
			(xy 379.515878 -262.490458) (xy 379.515263 -262.474764) (xy 379.505675 -262.444874) (xy 379.487476 -262.419297)
			(xy 379.462378 -262.400442) (xy 379.432746 -262.390083) (xy 379.417072 -262.389112) (xy 379.391592 -262.387912)
			(xy 379.341434 -262.378642) (xy 379.293295 -262.361777) (xy 379.248319 -262.337717) (xy 379.207572 -262.307034)
			(xy 379.172022 -262.270455) (xy 379.142514 -262.22885) (xy 379.119747 -262.183205) (xy 379.104262 -262.134605)
			(xy 379.096426 -262.084203) (xy 379.096426 -262.033195) (xy 379.104262 -261.982793) (xy 379.119748 -261.934193)
			(xy 379.142515 -261.888548) (xy 379.172024 -261.846943) (xy 379.207574 -261.810365) (xy 379.248321 -261.779682)
			(xy 379.293297 -261.755622) (xy 379.341436 -261.738757) (xy 379.391594 -261.729488) (xy 379.417072 -261.728204)
			(xy 379.432743 -261.727197) (xy 379.462376 -261.716858) (xy 379.487473 -261.698012) (xy 379.505666 -261.672439)
			(xy 379.515238 -261.642549) (xy 379.515878 -261.626858) (xy 379.515878 -261.066026) (xy 378.962158 -260.512306)
			(xy 378.951549 -260.502412) (xy 378.926116 -260.488488) (xy 378.897794 -260.482276) (xy 378.868868 -260.484275)
			(xy 378.84167 -260.494325) (xy 378.818394 -260.511616) (xy 378.800918 -260.534753) (xy 378.79528 -260.54812)
			(xy 378.78599 -260.571284) (xy 378.761449 -260.614741) (xy 378.730653 -260.654015) (xy 378.694303 -260.688212)
			(xy 378.653226 -260.716556) (xy 378.608354 -260.738403) (xy 378.560707 -260.753255) (xy 378.51137 -260.760775)
			(xy 378.486416 -260.761226) (xy 378.460447 -260.760744) (xy 378.409147 -260.752621) (xy 378.35975 -260.736572)
			(xy 378.313473 -260.712993) (xy 378.271454 -260.682464) (xy 378.234728 -260.645737) (xy 378.204201 -260.603717)
			(xy 378.180623 -260.557439) (xy 378.164576 -260.508041) (xy 378.156455 -260.456741) (xy 378.155962 -260.430772)
			(xy 378.156413 -260.405815) (xy 378.163912 -260.356467) (xy 378.17875 -260.308809) (xy 378.200589 -260.263926)
			(xy 378.228932 -260.222839) (xy 378.263133 -260.186485) (xy 378.302415 -260.155689) (xy 378.345883 -260.131154)
			(xy 378.369068 -260.121908) (xy 378.382437 -260.116286) (xy 378.405557 -260.098798) (xy 378.422833 -260.07552)
			(xy 378.432874 -260.048326) (xy 378.434871 -260.019406) (xy 378.428664 -259.99109) (xy 378.414752 -259.965658)
			(xy 378.404882 -259.95503) (xy 378.276358 -259.826506) (xy 378.240544 -259.85978) (xy 378.222129 -259.876146)
			(xy 378.181362 -259.903805) (xy 378.136946 -259.925115) (xy 378.089861 -259.939605) (xy 378.041148 -259.946955)
			(xy 378.016516 -259.94741) (xy 378.016262 -259.94741) (xy 377.990296 -259.946924) (xy 377.939004 -259.938794)
			(xy 377.889615 -259.92274) (xy 377.843346 -259.899158) (xy 377.801336 -259.868628) (xy 377.764619 -259.831902)
			(xy 377.734099 -259.789884) (xy 377.710528 -259.743609) (xy 377.694487 -259.694216) (xy 377.686369 -259.642922)
			(xy 377.685808 -259.616956) (xy 377.685808 -259.616702) (xy 377.686258 -259.592067) (xy 377.69357 -259.543344)
			(xy 377.708048 -259.496249) (xy 377.729369 -259.451832) (xy 377.757058 -259.41108) (xy 377.773438 -259.392674)
			(xy 377.7869 -259.35813) (xy 377.786413 -259.348168) (xy 377.778824 -259.329745) (xy 377.772168 -259.322316)
			(xy 377.582176 -259.132324) (xy 377.560078 -259.13334) (xy 377.546362 -259.133594) (xy 377.520396 -259.133082)
			(xy 377.469103 -259.124953) (xy 377.419713 -259.108902) (xy 377.373441 -259.085323) (xy 377.331427 -259.054796)
			(xy 377.294705 -259.018074) (xy 377.264178 -258.97606) (xy 377.240599 -258.929789) (xy 377.224547 -258.880399)
			(xy 377.216418 -258.829106) (xy 377.215908 -258.80314) (xy 377.216162 -258.789424) (xy 377.217178 -258.767326)
			(xy 376.582686 -258.132834) (xy 376.572941 -258.123752) (xy 376.54985 -258.110494) (xy 376.524115 -258.103659)
			(xy 376.497488 -258.103711) (xy 376.471781 -258.110647) (xy 376.448741 -258.123995) (xy 376.429937 -258.142848)
			(xy 376.42292 -258.15417) (xy 376.410178 -258.175383) (xy 376.379341 -258.214082) (xy 376.343077 -258.24775)
			(xy 376.302198 -258.275634) (xy 376.257618 -258.29711) (xy 376.210334 -258.311698) (xy 376.161404 -258.319071)
			(xy 376.136662 -258.319524) (xy 376.110698 -258.319012) (xy 376.059409 -258.310883) (xy 376.010023 -258.29483)
			(xy 375.963757 -258.27125) (xy 375.921749 -258.240723) (xy 375.885033 -258.204) (xy 375.854514 -258.161985)
			(xy 375.830944 -258.115714) (xy 375.814901 -258.066325) (xy 375.806783 -258.015035) (xy 375.806208 -257.98907)
			(xy 375.80665 -257.964329) (xy 375.814031 -257.9154) (xy 375.828625 -257.868119) (xy 375.850104 -257.823541)
			(xy 375.87799 -257.782664) (xy 375.911657 -257.746401) (xy 375.950355 -257.715563) (xy 375.971562 -257.702812)
			(xy 375.982932 -257.695846) (xy 376.001843 -257.677058) (xy 376.015232 -257.654008) (xy 376.022184 -257.628273)
			(xy 376.022222 -257.601616) (xy 376.015344 -257.575862) (xy 376.002021 -257.552773) (xy 375.992898 -257.543046)
			(xy 375.880376 -257.430524) (xy 375.846086 -257.452876) (xy 375.82595 -257.465387) (xy 375.782857 -257.485142)
			(xy 375.737385 -257.49854) (xy 375.690465 -257.505305) (xy 375.666762 -257.505708) (xy 375.640796 -257.505222)
			(xy 375.589504 -257.497092) (xy 375.540116 -257.481038) (xy 375.493847 -257.457456) (xy 375.451836 -257.426926)
			(xy 375.415119 -257.3902) (xy 375.3846 -257.348182) (xy 375.361029 -257.301907) (xy 375.344988 -257.252514)
			(xy 375.336871 -257.20122) (xy 375.336308 -257.175254) (xy 375.336718 -257.151553) (xy 375.343491 -257.104636)
			(xy 375.356892 -257.059166) (xy 375.376646 -257.016075) (xy 375.38914 -256.99593) (xy 375.411492 -256.96164)
			(xy 375.187464 -256.737612) (xy 375.187464 -256.737358) (xy 375.186761 -256.726033) (xy 375.176808 -256.705676)
			(xy 375.159022 -256.691638) (xy 375.148094 -256.68859) (xy 375.144792 -256.688082) (xy 375.119221 -256.683489)
			(xy 375.06983 -256.667387) (xy 375.023562 -256.643763) (xy 374.981556 -256.613198) (xy 374.944844 -256.576442)
			(xy 374.914329 -256.534399) (xy 374.89076 -256.488103) (xy 374.874718 -256.438692) (xy 374.866597 -256.387381)
			(xy 374.866596 -256.335431) (xy 374.874716 -256.28412) (xy 374.890756 -256.234708) (xy 374.914323 -256.188411)
			(xy 374.944836 -256.146368) (xy 374.981547 -256.10961) (xy 375.023552 -256.079043) (xy 375.069819 -256.055417)
			(xy 375.11921 -256.039314) (xy 375.144792 -256.034794) (xy 375.148094 -256.034286) (xy 375.159095 -256.031361)
			(xy 375.176994 -256.017333) (xy 375.186951 -255.996888) (xy 375.187464 -255.985518) (xy 375.187464 -255.835404)
			(xy 375.181368 -255.811782) (xy 375.17959 -255.80848) (xy 375.17324 -255.79578) (xy 375.165874 -255.781048)
			(xy 375.16054 -255.769364) (xy 375.12117 -255.740154) (xy 375.035318 -255.729486) (xy 375.026654 -255.728789)
			(xy 375.009725 -255.732667) (xy 374.995139 -255.742093) (xy 374.989598 -255.74879) (xy 374.989344 -255.74879)
			(xy 374.973597 -255.768564) (xy 374.937111 -255.803548) (xy 374.895723 -255.832566) (xy 374.850399 -255.854943)
			(xy 374.802194 -255.870155) (xy 374.752236 -255.877848) (xy 374.726962 -255.87833) (xy 374.700975 -255.877818)
			(xy 374.649642 -255.869682) (xy 374.600213 -255.853616) (xy 374.553906 -255.830017) (xy 374.51186 -255.799464)
			(xy 374.475111 -255.762711) (xy 374.444563 -255.720662) (xy 374.420969 -255.674352) (xy 374.404909 -255.624921)
			(xy 374.396779 -255.573587) (xy 374.396779 -255.521613) (xy 374.404909 -255.470279) (xy 374.420969 -255.420848)
			(xy 374.444563 -255.374538) (xy 374.475111 -255.332489) (xy 374.51186 -255.295736) (xy 374.553906 -255.265183)
			(xy 374.600213 -255.241584) (xy 374.649642 -255.225518) (xy 374.700975 -255.217382) (xy 374.726962 -255.216914)
			(xy 374.752233 -255.217398) (xy 374.802185 -255.225104) (xy 374.850382 -255.240325) (xy 374.895698 -255.262707)
			(xy 374.937079 -255.291729) (xy 374.973558 -255.326713) (xy 374.989344 -255.346454) (xy 374.989598 -255.346454)
			(xy 374.99516 -255.353124) (xy 375.00975 -255.362523) (xy 375.026659 -255.366428) (xy 375.035318 -255.365758)
			(xy 375.12117 -255.35509) (xy 375.16054 -255.32588) (xy 375.165874 -255.314196) (xy 375.17324 -255.299464)
			(xy 375.17959 -255.286764) (xy 375.181368 -255.283462) (xy 375.187464 -255.25984) (xy 375.187464 -255.109472)
			(xy 375.186763 -255.098145) (xy 375.176814 -255.077783) (xy 375.159026 -255.06374) (xy 375.148094 -255.060704)
			(xy 375.144792 -255.060196) (xy 375.119611 -255.055697) (xy 375.070941 -255.039962) (xy 375.025274 -255.016923)
			(xy 374.983696 -254.98713) (xy 374.947199 -254.951292) (xy 374.916653 -254.910265) (xy 374.892786 -254.865024)
			(xy 374.876166 -254.816649) (xy 374.86719 -254.766293) (xy 374.866071 -254.715155) (xy 374.872837 -254.664454)
			(xy 374.887326 -254.615399) (xy 374.909192 -254.569158) (xy 374.937915 -254.526834) (xy 374.97281 -254.489435)
			(xy 375.013045 -254.457852) (xy 375.057662 -254.432839) (xy 375.105597 -254.414991) (xy 375.130568 -254.409448)
			(xy 375.145554 -254.4064) (xy 375.416572 -254.135382) (xy 375.401557 -254.117296) (xy 375.376253 -254.077682)
			(xy 375.356811 -254.034886) (xy 375.343621 -253.989769) (xy 375.336949 -253.943239) (xy 375.336562 -253.919736)
			(xy 375.337042 -253.893765) (xy 375.345163 -253.842463) (xy 375.36121 -253.793062) (xy 375.384788 -253.746781)
			(xy 375.415316 -253.704758) (xy 375.452043 -253.668029) (xy 375.494064 -253.637498) (xy 375.540344 -253.613917)
			(xy 375.589743 -253.597867) (xy 375.641045 -253.589744) (xy 375.667016 -253.589282) (xy 375.66727 -253.589282)
			(xy 375.691474 -253.589698) (xy 375.739365 -253.596755) (xy 375.785709 -253.610736) (xy 375.829513 -253.631342)
			(xy 375.849896 -253.6444) (xy 375.88444 -253.667514) (xy 379.55347 -249.998484) (xy 379.562636 -249.988754)
			(xy 379.575986 -249.965604) (xy 379.582873 -249.939784) (xy 379.582826 -249.913061) (xy 379.575848 -249.887265)
			(xy 379.562418 -249.864162) (xy 379.553216 -249.854466) (xy 379.53506 -249.835739) (xy 379.50429 -249.793625)
			(xy 379.480521 -249.747199) (xy 379.464344 -249.697614) (xy 379.456159 -249.646103) (xy 379.45568 -249.620024)
			(xy 379.456161 -249.594054) (xy 379.464283 -249.542754) (xy 379.480331 -249.493357) (xy 379.50391 -249.447078)
			(xy 379.534439 -249.405059) (xy 379.571166 -249.368333) (xy 379.613187 -249.337805) (xy 379.659466 -249.314228)
			(xy 379.708864 -249.298181) (xy 379.760164 -249.29006) (xy 379.786134 -249.28957) (xy 379.796257 -249.289663)
			(xy 379.816464 -249.290936) (xy 379.82652 -249.29211) (xy 379.840839 -249.293385) (xy 379.869211 -249.28883)
			(xy 379.89519 -249.27655) (xy 379.916719 -249.257517) (xy 379.932091 -249.233239) (xy 379.94009 -249.20564)
			(xy 379.940566 -249.191272) (xy 379.940566 -248.90476) (xy 379.938534 -248.897902) (xy 379.932461 -248.875467)
			(xy 379.925953 -248.829447) (xy 379.92558 -248.806208) (xy 379.925977 -248.782971) (xy 379.932481 -248.736953)
			(xy 379.938534 -248.714514) (xy 379.940566 -248.707656) (xy 379.940566 -248.42089) (xy 379.940071 -248.406528)
			(xy 379.932067 -248.378942) (xy 379.916695 -248.354677) (xy 379.895171 -248.335655) (xy 379.869201 -248.323382)
			(xy 379.84084 -248.318829) (xy 379.82652 -248.320052) (xy 379.816402 -248.321238) (xy 379.796067 -248.322511)
			(xy 379.78588 -248.322592) (xy 379.759911 -248.322081) (xy 379.708612 -248.313953) (xy 379.659217 -248.297901)
			(xy 379.61294 -248.27432) (xy 379.570922 -248.24379) (xy 379.534197 -248.207062) (xy 379.50367 -248.165043)
			(xy 379.480091 -248.118765) (xy 379.464042 -248.069368) (xy 379.455917 -248.018069) (xy 379.455917 -247.966131)
			(xy 379.464042 -247.914832) (xy 379.480091 -247.865435) (xy 379.50367 -247.819157) (xy 379.534197 -247.777138)
			(xy 379.570922 -247.740411) (xy 379.61294 -247.70988) (xy 379.659217 -247.686299) (xy 379.708612 -247.670247)
			(xy 379.759911 -247.662119) (xy 379.78588 -247.661684) (xy 379.796067 -247.66177) (xy 379.816401 -247.663043)
			(xy 379.82652 -247.664224) (xy 379.84084 -247.665499) (xy 379.869213 -247.660944) (xy 379.895194 -247.648664)
			(xy 379.916724 -247.629632) (xy 379.9321 -247.605354) (xy 379.940102 -247.577754) (xy 379.940566 -247.563386)
			(xy 379.940566 -247.276874) (xy 379.938534 -247.270016) (xy 379.932467 -247.24758) (xy 379.925971 -247.20156)
			(xy 379.92558 -247.178322) (xy 379.925976 -247.155084) (xy 379.932478 -247.109066) (xy 379.938534 -247.086628)
			(xy 379.940566 -247.07977) (xy 379.940566 -246.793258) (xy 379.940067 -246.778899) (xy 379.932057 -246.75132)
			(xy 379.916684 -246.727064) (xy 379.895162 -246.708049) (xy 379.869196 -246.69578) (xy 379.840841 -246.691229)
			(xy 379.82652 -246.69242) (xy 379.816402 -246.693606) (xy 379.796067 -246.694879) (xy 379.78588 -246.69496)
			(xy 379.759913 -246.694449) (xy 379.70862 -246.686322) (xy 379.659229 -246.670272) (xy 379.612957 -246.646692)
			(xy 379.570943 -246.616165) (xy 379.534222 -246.579442) (xy 379.503697 -246.537426) (xy 379.480121 -246.491152)
			(xy 379.464073 -246.441761) (xy 379.455949 -246.390467) (xy 379.455949 -246.338533) (xy 379.464073 -246.287239)
			(xy 379.480121 -246.237848) (xy 379.503697 -246.191574) (xy 379.534222 -246.149558) (xy 379.570943 -246.112835)
			(xy 379.612957 -246.082308) (xy 379.659229 -246.058728) (xy 379.70862 -246.042678) (xy 379.759913 -246.034551)
			(xy 379.78588 -246.034052) (xy 379.796067 -246.034138) (xy 379.816401 -246.035411) (xy 379.82652 -246.036592)
			(xy 379.840839 -246.037867) (xy 379.869209 -246.033312) (xy 379.895185 -246.021031) (xy 379.916711 -246.001998)
			(xy 379.93208 -245.97772) (xy 379.940074 -245.950121) (xy 379.940566 -245.935754) (xy 379.940566 -245.650258)
			(xy 379.938534 -245.643146) (xy 379.932366 -245.620531) (xy 379.925737 -245.574128) (xy 379.925739 -245.527253)
			(xy 379.93237 -245.48085) (xy 379.938534 -245.458234) (xy 379.940566 -245.451122) (xy 379.940566 -245.165372)
			(xy 379.940069 -245.151012) (xy 379.932062 -245.12343) (xy 379.916688 -245.09917) (xy 379.895166 -245.080151)
			(xy 379.869199 -245.067881) (xy 379.840841 -245.063329) (xy 379.82652 -245.064534) (xy 379.816465 -245.065712)
			(xy 379.796258 -245.066985) (xy 379.786134 -245.067074) (xy 379.760161 -245.066594) (xy 379.708855 -245.058472)
			(xy 379.659451 -245.042425) (xy 379.613166 -245.018845) (xy 379.571139 -244.988315) (xy 379.534407 -244.951586)
			(xy 379.503873 -244.909563) (xy 379.480289 -244.86328) (xy 379.464236 -244.813878) (xy 379.456109 -244.762573)
			(xy 379.456109 -244.710627) (xy 379.464236 -244.659322) (xy 379.480289 -244.60992) (xy 379.503873 -244.563637)
			(xy 379.534407 -244.521614) (xy 379.571139 -244.484885) (xy 379.613166 -244.454355) (xy 379.659451 -244.430775)
			(xy 379.708855 -244.414728) (xy 379.760161 -244.406606) (xy 379.786134 -244.406166) (xy 379.796257 -244.406259)
			(xy 379.816464 -244.407532) (xy 379.82652 -244.408706) (xy 379.840839 -244.409982) (xy 379.869211 -244.405426)
			(xy 379.895189 -244.393146) (xy 379.916717 -244.374113) (xy 379.932089 -244.349835) (xy 379.940087 -244.322236)
			(xy 379.940566 -244.307868) (xy 379.940566 -244.021356) (xy 379.938534 -244.014498) (xy 379.932461 -243.992063)
			(xy 379.925954 -243.946043) (xy 379.92558 -243.922804) (xy 379.925978 -243.899567) (xy 379.932482 -243.853549)
			(xy 379.938534 -243.83111) (xy 379.940566 -243.824252) (xy 379.940566 -243.53774) (xy 379.940078 -243.523373)
			(xy 379.932082 -243.495774) (xy 379.916712 -243.471497) (xy 379.895186 -243.452464) (xy 379.869209 -243.440184)
			(xy 379.840839 -243.435629) (xy 379.82652 -243.436902) (xy 379.816402 -243.438088) (xy 379.796067 -243.439361)
			(xy 379.78588 -243.439442) (xy 379.759915 -243.438931) (xy 379.708624 -243.430805) (xy 379.659236 -243.414755)
			(xy 379.612966 -243.391177) (xy 379.570955 -243.360651) (xy 379.534236 -243.32393) (xy 379.503713 -243.281916)
			(xy 379.480137 -243.235646) (xy 379.464091 -243.186257) (xy 379.455967 -243.134965) (xy 379.455967 -243.083035)
			(xy 379.464091 -243.031743) (xy 379.480137 -242.982354) (xy 379.503713 -242.936084) (xy 379.534236 -242.89407)
			(xy 379.570955 -242.857349) (xy 379.612966 -242.826823) (xy 379.659236 -242.803245) (xy 379.708624 -242.787195)
			(xy 379.759915 -242.779069) (xy 379.78588 -242.778534) (xy 379.796067 -242.77862) (xy 379.816401 -242.779893)
			(xy 379.82652 -242.781074) (xy 379.840842 -242.782349) (xy 379.86922 -242.777794) (xy 379.895207 -242.765515)
			(xy 379.916745 -242.746484) (xy 379.93213 -242.722208) (xy 379.940145 -242.694606) (xy 379.940566 -242.680236)
			(xy 379.940566 -242.39347) (xy 379.938534 -242.386612) (xy 379.932467 -242.364176) (xy 379.925972 -242.318156)
			(xy 379.92558 -242.294918) (xy 379.925977 -242.27168) (xy 379.932479 -242.225662) (xy 379.938534 -242.203224)
			(xy 379.940566 -242.196366) (xy 379.940566 -241.909854) (xy 379.940067 -241.895495) (xy 379.932056 -241.867918)
			(xy 379.916682 -241.843662) (xy 379.895161 -241.824648) (xy 379.869196 -241.81238) (xy 379.840841 -241.807829)
			(xy 379.82652 -241.809016) (xy 379.816402 -241.810202) (xy 379.796067 -241.811475) (xy 379.78588 -241.811556)
			(xy 379.759914 -241.811045) (xy 379.708621 -241.802918) (xy 379.659231 -241.786868) (xy 379.612959 -241.763289)
			(xy 379.570946 -241.732762) (xy 379.534225 -241.696039) (xy 379.503701 -241.654024) (xy 379.480124 -241.607751)
			(xy 379.464077 -241.55836) (xy 379.455953 -241.507066) (xy 379.455953 -241.455134) (xy 379.464077 -241.40384)
			(xy 379.480124 -241.354449) (xy 379.503701 -241.308176) (xy 379.534225 -241.266161) (xy 379.570946 -241.229438)
			(xy 379.612959 -241.198911) (xy 379.659231 -241.175332) (xy 379.708621 -241.159282) (xy 379.759914 -241.151155)
			(xy 379.78588 -241.150648) (xy 379.796067 -241.150734) (xy 379.816401 -241.152007) (xy 379.82652 -241.153188)
			(xy 379.840838 -241.154463) (xy 379.869208 -241.149908) (xy 379.895184 -241.137627) (xy 379.916709 -241.118593)
			(xy 379.932077 -241.094316) (xy 379.940071 -241.066717) (xy 379.940566 -241.05235) (xy 379.940566 -240.766854)
			(xy 379.938534 -240.759742) (xy 379.932366 -240.737127) (xy 379.925738 -240.690724) (xy 379.92574 -240.643849)
			(xy 379.932372 -240.597446) (xy 379.938534 -240.57483) (xy 379.940566 -240.567718) (xy 379.940566 -240.281968)
			(xy 379.940068 -240.267608) (xy 379.93206 -240.240027) (xy 379.916687 -240.215768) (xy 379.895165 -240.196751)
			(xy 379.869198 -240.184481) (xy 379.840841 -240.179929) (xy 379.82652 -240.18113) (xy 379.816465 -240.182308)
			(xy 379.796258 -240.183581) (xy 379.786134 -240.18367) (xy 379.760162 -240.18319) (xy 379.708856 -240.175068)
			(xy 379.659453 -240.159021) (xy 379.613168 -240.135442) (xy 379.571142 -240.104912) (xy 379.53441 -240.068184)
			(xy 379.503876 -240.026161) (xy 379.480292 -239.979879) (xy 379.464239 -239.930477) (xy 379.456113 -239.879172)
			(xy 379.456113 -239.827228) (xy 379.464239 -239.775923) (xy 379.480292 -239.726521) (xy 379.503876 -239.680239)
			(xy 379.53441 -239.638216) (xy 379.571142 -239.601488) (xy 379.613168 -239.570958) (xy 379.659453 -239.547379)
			(xy 379.708856 -239.531332) (xy 379.760162 -239.52321) (xy 379.786134 -239.522762) (xy 379.796257 -239.522855)
			(xy 379.816464 -239.524128) (xy 379.82652 -239.525302) (xy 379.840839 -239.526577) (xy 379.86921 -239.522022)
			(xy 379.895188 -239.509741) (xy 379.916715 -239.490708) (xy 379.932086 -239.46643) (xy 379.940083 -239.438831)
			(xy 379.940566 -239.424464) (xy 379.940566 -239.137952) (xy 379.938534 -239.131094) (xy 379.932461 -239.108659)
			(xy 379.925955 -239.062639) (xy 379.92558 -239.0394) (xy 379.925978 -239.016163) (xy 379.932483 -238.970145)
			(xy 379.938534 -238.947706) (xy 379.940566 -238.940848) (xy 379.940566 -238.654336) (xy 379.940077 -238.639969)
			(xy 379.932081 -238.612372) (xy 379.916711 -238.588096) (xy 379.895185 -238.569064) (xy 379.869208 -238.556784)
			(xy 379.840839 -238.552229) (xy 379.82652 -238.553498) (xy 379.816402 -238.554684) (xy 379.796067 -238.555957)
			(xy 379.78588 -238.556038) (xy 379.759915 -238.555527) (xy 379.708625 -238.547401) (xy 379.659237 -238.531351)
			(xy 379.612969 -238.507774) (xy 379.570957 -238.477248) (xy 379.534239 -238.440527) (xy 379.503716 -238.398514)
			(xy 379.480141 -238.352244) (xy 379.464094 -238.302856) (xy 379.455971 -238.251565) (xy 379.455971 -238.199635)
			(xy 379.464094 -238.148344) (xy 379.480141 -238.098956) (xy 379.503716 -238.052686) (xy 379.534239 -238.010673)
			(xy 379.570957 -237.973952) (xy 379.612969 -237.943426) (xy 379.659237 -237.919849) (xy 379.708625 -237.903799)
			(xy 379.759915 -237.895673) (xy 379.78588 -237.89513) (xy 379.796067 -237.895216) (xy 379.816401 -237.896489)
			(xy 379.82652 -237.89767) (xy 379.840842 -237.898945) (xy 379.86922 -237.89439) (xy 379.895206 -237.882111)
			(xy 379.916743 -237.86308) (xy 379.932127 -237.838803) (xy 379.940141 -237.811202) (xy 379.940566 -237.796832)
			(xy 379.940566 -237.510066) (xy 379.938534 -237.503208) (xy 379.932461 -237.480773) (xy 379.925952 -237.434753)
			(xy 379.92558 -237.411514) (xy 379.925977 -237.388277) (xy 379.93248 -237.342259) (xy 379.938534 -237.31982)
			(xy 379.940566 -237.312962) (xy 379.940566 -237.026704) (xy 379.940073 -237.012341) (xy 379.932071 -236.984751)
			(xy 379.916699 -236.960483) (xy 379.895176 -236.941458) (xy 379.869203 -236.929182) (xy 379.84084 -236.924629)
			(xy 379.82652 -236.925866) (xy 379.816402 -236.927052) (xy 379.796067 -236.928325) (xy 379.78588 -236.928406)
			(xy 379.759918 -236.927895) (xy 379.708632 -236.91977) (xy 379.65925 -236.903722) (xy 379.612985 -236.880146)
			(xy 379.570978 -236.849624) (xy 379.534263 -236.812907) (xy 379.503743 -236.770898) (xy 379.480171 -236.724632)
			(xy 379.464126 -236.675248) (xy 379.456003 -236.623962) (xy 379.456003 -236.572038) (xy 379.464126 -236.520752)
			(xy 379.480171 -236.471368) (xy 379.503743 -236.425102) (xy 379.534263 -236.383093) (xy 379.570978 -236.346376)
			(xy 379.612985 -236.315854) (xy 379.65925 -236.292278) (xy 379.708632 -236.27623) (xy 379.759918 -236.268105)
			(xy 379.78588 -236.267498) (xy 379.796067 -236.267584) (xy 379.816401 -236.268857) (xy 379.82652 -236.270038)
			(xy 379.840841 -236.271313) (xy 379.869215 -236.266758) (xy 379.895197 -236.254478) (xy 379.91673 -236.235446)
			(xy 379.932108 -236.211169) (xy 379.940114 -236.183569) (xy 379.940566 -236.1692) (xy 379.940566 -235.88345)
			(xy 379.938534 -235.876338) (xy 379.932366 -235.853723) (xy 379.925739 -235.80732) (xy 379.925742 -235.760446)
			(xy 379.932374 -235.714043) (xy 379.938534 -235.691426) (xy 379.940566 -235.684314) (xy 379.940566 -235.398818)
			(xy 379.940075 -235.384453) (xy 379.932075 -235.35686) (xy 379.916704 -235.332588) (xy 379.89518 -235.31356)
			(xy 379.869206 -235.301283) (xy 379.840839 -235.296729) (xy 379.82652 -235.29798) (xy 379.816465 -235.299158)
			(xy 379.796258 -235.300431) (xy 379.786134 -235.30052) (xy 379.760166 -235.30004) (xy 379.708868 -235.29192)
			(xy 379.659472 -235.275875) (xy 379.613194 -235.252299) (xy 379.571175 -235.221774) (xy 379.534448 -235.185051)
			(xy 379.503919 -235.143035) (xy 379.480338 -235.09676) (xy 379.464288 -235.047365) (xy 379.456163 -234.996068)
			(xy 379.456163 -234.944132) (xy 379.464288 -234.892835) (xy 379.480338 -234.84344) (xy 379.503919 -234.797165)
			(xy 379.534448 -234.755149) (xy 379.571175 -234.718426) (xy 379.613194 -234.687901) (xy 379.659472 -234.664325)
			(xy 379.708868 -234.64828) (xy 379.760166 -234.64016) (xy 379.786134 -234.639612) (xy 379.796257 -234.639705)
			(xy 379.816464 -234.640978) (xy 379.82652 -234.642152) (xy 379.840841 -234.643427) (xy 379.869217 -234.638872)
			(xy 379.895201 -234.626592) (xy 379.916736 -234.607561) (xy 379.932117 -234.583284) (xy 379.940126 -234.555684)
			(xy 379.940566 -234.541314) (xy 379.940566 -234.354624) (xy 379.94729 -234.34739) (xy 379.954904 -234.329185)
			(xy 379.955298 -234.319318) (xy 379.955298 -234.294426) (xy 379.951234 -234.285028) (xy 379.943047 -234.264645)
			(xy 379.931515 -234.222259) (xy 379.925687 -234.178721) (xy 379.925326 -234.156758) (xy 379.925326 -234.15625)
			(xy 379.925805 -234.130259) (xy 379.933931 -234.078917) (xy 379.949989 -234.029477) (xy 379.973585 -233.98316)
			(xy 380.004136 -233.941104) (xy 380.040892 -233.904347) (xy 380.082946 -233.873793) (xy 380.129263 -233.850195)
			(xy 380.178701 -233.834134) (xy 380.230043 -233.826007) (xy 380.256034 -233.825542) (xy 380.256288 -233.825542)
			(xy 380.279826 -233.825953) (xy 380.326427 -233.832635) (xy 380.371602 -233.845877) (xy 380.393194 -233.85526)
			(xy 380.394718 -233.856022) (xy 380.40406 -233.859586) (xy 380.424038 -233.859769) (xy 380.44251 -233.852158)
			(xy 380.449836 -233.845354) (xy 380.537974 -233.757216) (xy 380.545252 -233.749201) (xy 380.552767 -233.728921)
			(xy 380.552452 -233.7181) (xy 380.547626 -233.653584) (xy 380.547118 -233.648627) (xy 380.544437 -233.639031)
			(xy 380.542292 -233.634534) (xy 380.527306 -233.606848) (xy 380.519432 -233.600498) (xy 380.500413 -233.584706)
			(xy 380.466825 -233.548437) (xy 380.43901 -233.507572) (xy 380.417589 -233.463022) (xy 380.403038 -233.415779)
			(xy 380.395682 -233.366896) (xy 380.395226 -233.34218) (xy 380.395226 -233.341926) (xy 380.395315 -233.330714)
			(xy 380.396838 -233.308342) (xy 380.398274 -233.297222) (xy 380.398782 -233.293666) (xy 380.398782 -233.292142)
			(xy 380.402909 -233.268063) (xy 380.417318 -233.221383) (xy 380.438433 -233.17733) (xy 380.465796 -233.136859)
			(xy 380.498811 -233.10085) (xy 380.536761 -233.070087) (xy 380.578821 -233.045237) (xy 380.624077 -233.026841)
			(xy 380.647702 -233.020616) (xy 380.651512 -233.0196) (xy 380.661456 -233.015975) (xy 380.677278 -233.001943)
			(xy 380.68599 -232.982674) (xy 380.686564 -232.972102) (xy 380.686564 -232.805224) (xy 380.686075 -232.794985)
			(xy 380.677941 -232.776192) (xy 380.663005 -232.762184) (xy 380.653544 -232.758234) (xy 380.616968 -232.745026)
			(xy 380.606046 -232.740962) (xy 380.509272 -232.740962) (xy 380.493486 -232.759116) (xy 380.457558 -232.791108)
			(xy 380.417371 -232.817551) (xy 380.373773 -232.837887) (xy 380.327687 -232.851684) (xy 380.280088 -232.858652)
			(xy 380.256034 -232.859072) (xy 380.230046 -232.858592) (xy 380.178709 -232.850465) (xy 380.129275 -232.834408)
			(xy 380.082962 -232.810815) (xy 380.040911 -232.780266) (xy 380.004156 -232.743515) (xy 379.973603 -232.701467)
			(xy 379.950005 -232.655156) (xy 379.933943 -232.605724) (xy 379.925811 -232.554388) (xy 379.925811 -232.502412)
			(xy 379.933943 -232.451076) (xy 379.950005 -232.401644) (xy 379.973603 -232.355333) (xy 380.004156 -232.313285)
			(xy 380.040911 -232.276534) (xy 380.082962 -232.245985) (xy 380.129275 -232.222392) (xy 380.178709 -232.206335)
			(xy 380.230046 -232.198208) (xy 380.256034 -232.197656) (xy 380.280086 -232.198091) (xy 380.327683 -232.205067)
			(xy 380.373765 -232.218866) (xy 380.417362 -232.239198) (xy 380.457553 -232.265632) (xy 380.493489 -232.297612)
			(xy 380.509272 -232.315766) (xy 380.509526 -232.315766) (xy 380.516202 -232.323113) (xy 380.533795 -232.332273)
			(xy 380.55356 -232.333929) (xy 380.56312 -232.33126) (xy 380.609094 -232.31475) (xy 380.653544 -232.298494)
			(xy 380.662992 -232.29454) (xy 380.677883 -232.280509) (xy 380.686013 -232.261733) (xy 380.686564 -232.251504)
			(xy 380.686564 -232.084626) (xy 380.648718 -232.03662) (xy 380.634748 -232.032556) (xy 380.610688 -232.025187)
			(xy 380.564964 -232.004186) (xy 380.522947 -231.976503) (xy 380.485607 -231.942776) (xy 380.453806 -231.903783)
			(xy 380.428277 -231.860424) (xy 380.409608 -231.813698) (xy 380.398231 -231.764685) (xy 380.394408 -231.714513)
			(xy 380.398227 -231.664342) (xy 380.4096 -231.615327) (xy 380.428265 -231.5686) (xy 380.453791 -231.525239)
			(xy 380.485589 -231.486243) (xy 380.522926 -231.452513) (xy 380.564941 -231.424826) (xy 380.610664 -231.403822)
			(xy 380.634748 -231.39654) (xy 380.648718 -231.392476) (xy 380.686564 -231.34447) (xy 380.686564 -231.115362)
			(xy 380.683008 -231.106472) (xy 380.674372 -231.083104) (xy 380.671832 -231.0765) (xy 380.666244 -231.058974)
			(xy 380.658624 -231.03078) (xy 380.655671 -231.021158) (xy 380.643505 -231.005142) (xy 380.62612 -230.995029)
			(xy 380.606184 -230.992371) (xy 380.586757 -230.997577) (xy 380.57082 -231.009846) (xy 380.565406 -231.018334)
			(xy 380.563628 -231.02189) (xy 380.562866 -231.023414) (xy 380.553303 -231.046098) (xy 380.528442 -231.088587)
			(xy 380.497556 -231.12692) (xy 380.461327 -231.160249) (xy 380.420558 -231.187838) (xy 380.376148 -231.209078)
			(xy 380.32908 -231.223498) (xy 380.280394 -231.230779) (xy 380.25578 -231.231186) (xy 380.229792 -231.230701)
			(xy 380.178458 -231.222568) (xy 380.129027 -231.206503) (xy 380.082718 -231.182904) (xy 380.040671 -231.152351)
			(xy 380.003922 -231.115597) (xy 379.973374 -231.073546) (xy 379.949781 -231.027234) (xy 379.933723 -230.977802)
			(xy 379.925595 -230.926466) (xy 379.925072 -230.900478) (xy 379.9256 -230.874037) (xy 379.934028 -230.821832)
			(xy 379.950652 -230.771632) (xy 379.975048 -230.724714) (xy 380.006595 -230.682272) (xy 380.044489 -230.645388)
			(xy 380.087767 -230.614999) (xy 380.135327 -230.59188) (xy 380.185958 -230.576618) (xy 380.212092 -230.572564)
			(xy 380.21514 -230.572056) (xy 380.22719 -230.569173) (xy 380.246514 -230.553716) (xy 380.25197 -230.542592)
			(xy 380.254764 -230.535734) (xy 380.287276 -230.460042) (xy 380.288567 -230.456102) (xy 380.289972 -230.447931)
			(xy 380.29007 -230.443786) (xy 380.280418 -230.414322) (xy 380.275846 -230.407972) (xy 380.261368 -230.386382)
			(xy 380.25018 -230.368653) (xy 380.23022 -230.331782) (xy 380.22149 -230.312722) (xy 380.219458 -230.308658)
			(xy 380.179834 -230.279448) (xy 380.09449 -230.269034) (xy 380.08317 -230.268229) (xy 380.06174 -230.275626)
			(xy 380.053342 -230.283258) (xy 380.048262 -230.288338) (xy 380.046484 -230.290624) (xy 380.030712 -230.310012)
			(xy 379.99432 -230.344267) (xy 379.953187 -230.372655) (xy 379.90825 -230.394529) (xy 379.860533 -230.409391)
			(xy 379.811123 -230.416902) (xy 379.786134 -230.41737) (xy 379.760146 -230.41689) (xy 379.708809 -230.408763)
			(xy 379.659376 -230.392706) (xy 379.613063 -230.369113) (xy 379.571012 -230.338565) (xy 379.534257 -230.301814)
			(xy 379.503705 -230.259766) (xy 379.480107 -230.213456) (xy 379.464044 -230.164024) (xy 379.455913 -230.112688)
			(xy 379.455913 -230.060712) (xy 379.464044 -230.009376) (xy 379.480107 -229.959944) (xy 379.503705 -229.913634)
			(xy 379.534257 -229.871586) (xy 379.571012 -229.834835) (xy 379.613063 -229.804287) (xy 379.659376 -229.780694)
			(xy 379.708809 -229.764637) (xy 379.760146 -229.75651) (xy 379.786134 -229.755954) (xy 379.798693 -229.756072)
			(xy 379.823739 -229.757982) (xy 379.836172 -229.759764) (xy 379.860812 -229.764002) (xy 379.908529 -229.778918)
			(xy 379.953462 -229.800838) (xy 379.994589 -229.829263) (xy 380.030976 -229.863547) (xy 380.046738 -229.882954)
			(xy 380.048516 -229.88524) (xy 380.053342 -229.890066) (xy 380.061813 -229.897581) (xy 380.083186 -229.904968)
			(xy 380.09449 -229.90429) (xy 380.179834 -229.893876) (xy 380.219458 -229.864666) (xy 380.22149 -229.860602)
			(xy 380.23023 -229.841547) (xy 380.250192 -229.804679) (xy 380.261368 -229.786942) (xy 380.275846 -229.765352)
			(xy 380.280418 -229.759002) (xy 380.29007 -229.729538) (xy 380.28998 -229.72533) (xy 380.288568 -229.717034)
			(xy 380.287276 -229.713028) (xy 380.251462 -229.628954) (xy 380.245758 -229.618533) (xy 380.226935 -229.60409)
			(xy 380.215394 -229.601268) (xy 380.212346 -229.60076) (xy 380.186194 -229.59676) (xy 380.135533 -229.581531)
			(xy 380.087943 -229.558429) (xy 380.044638 -229.528045) (xy 380.006723 -229.491153) (xy 379.975167 -229.448695)
			(xy 379.950773 -229.401753) (xy 379.934165 -229.351527) (xy 379.925767 -229.299297) (xy 379.925326 -229.272846)
			(xy 379.925806 -229.246855) (xy 379.933931 -229.195513) (xy 379.94999 -229.146075) (xy 379.973586 -229.099758)
			(xy 380.004138 -229.057703) (xy 380.040893 -229.020946) (xy 380.082947 -228.990392) (xy 380.129264 -228.966795)
			(xy 380.178702 -228.950734) (xy 380.230043 -228.942607) (xy 380.256034 -228.942138) (xy 380.283193 -228.942689)
			(xy 380.336779 -228.951569) (xy 380.388195 -228.969085) (xy 380.436057 -228.994766) (xy 380.479081 -229.027923)
			(xy 380.516109 -229.067663) (xy 380.546147 -229.112919) (xy 380.557786 -229.137464) (xy 380.563628 -229.150418)
			(xy 380.609856 -229.181914) (xy 380.65837 -229.14356) (xy 380.662688 -229.127304) (xy 380.667768 -229.109778)
			(xy 380.683008 -229.066852) (xy 380.686564 -229.057962) (xy 380.686564 -228.829108) (xy 380.648718 -228.781102)
			(xy 380.63297 -228.77653) (xy 380.607603 -228.768524) (xy 380.559625 -228.745563) (xy 380.515936 -228.715226)
			(xy 380.477658 -228.678294) (xy 380.445779 -228.635716) (xy 380.421117 -228.58859) (xy 380.404307 -228.538126)
			(xy 380.395782 -228.485625) (xy 380.395226 -228.45903) (xy 380.395707 -228.43304) (xy 380.403835 -228.3817)
			(xy 380.419895 -228.332264) (xy 380.443491 -228.285949) (xy 380.474044 -228.243896) (xy 380.510799 -228.207141)
			(xy 380.552852 -228.176589) (xy 380.599167 -228.152993) (xy 380.648604 -228.136934) (xy 380.699944 -228.128807)
			(xy 380.725934 -228.128322) (xy 380.740158 -228.128576) (xy 380.74219 -228.128576) (xy 380.752005 -228.128099)
			(xy 380.770168 -228.120646) (xy 380.777496 -228.114098) (xy 380.938024 -227.95357) (xy 380.94447 -227.946481)
			(xy 380.951915 -227.928844) (xy 380.952502 -227.91928) (xy 380.952756 -227.898198) (xy 380.95301 -227.888038)
			(xy 380.94158 -227.856542) (xy 380.938278 -227.852478) (xy 380.921155 -227.830286) (xy 380.893856 -227.781336)
			(xy 380.875209 -227.728481) (xy 380.865749 -227.673238) (xy 380.865126 -227.645214) (xy 380.865126 -227.64496)
			(xy 380.865639 -227.618976) (xy 380.873774 -227.567648) (xy 380.889839 -227.518225) (xy 380.913438 -227.471924)
			(xy 380.943989 -227.429884) (xy 380.98074 -227.393141) (xy 381.022787 -227.362599) (xy 381.069094 -227.339011)
			(xy 381.11852 -227.322957) (xy 381.16985 -227.314833) (xy 381.195834 -227.314252) (xy 381.219735 -227.314675)
			(xy 381.267039 -227.321557) (xy 381.312861 -227.335174) (xy 381.356247 -227.355241) (xy 381.396295 -227.381341)
			(xy 381.414528 -227.396802) (xy 381.421132 -227.402644) (xy 381.455168 -227.415852) (xy 381.464918 -227.415336)
			(xy 381.482947 -227.407888) (xy 381.49022 -227.401374) (xy 381.585724 -227.30587) (xy 381.594127 -227.296481)
			(xy 381.601196 -227.272335) (xy 381.599186 -227.259896) (xy 381.581406 -227.177346) (xy 381.550164 -227.141278)
			(xy 381.545846 -227.1395) (xy 381.522881 -227.130077) (xy 381.479839 -227.105352) (xy 381.440971 -227.074477)
			(xy 381.40715 -227.038143) (xy 381.379134 -226.997167) (xy 381.357552 -226.952466) (xy 381.342886 -226.905044)
			(xy 381.335467 -226.855963) (xy 381.335026 -226.831144) (xy 381.335506 -226.805153) (xy 381.343632 -226.753812)
			(xy 381.359691 -226.704373) (xy 381.383287 -226.658056) (xy 381.413839 -226.616002) (xy 381.450594 -226.579245)
			(xy 381.492648 -226.548692) (xy 381.538964 -226.525094) (xy 381.588402 -226.509034) (xy 381.639743 -226.500907)
			(xy 381.665734 -226.500436) (xy 381.665988 -226.500436) (xy 381.6772 -226.500526) (xy 381.699572 -226.502049)
			(xy 381.710692 -226.503484) (xy 381.714248 -226.503992) (xy 381.715772 -226.503992) (xy 381.740218 -226.508196)
			(xy 381.787571 -226.522963) (xy 381.83219 -226.544632) (xy 381.873075 -226.572716) (xy 381.909311 -226.606588)
			(xy 381.940087 -226.645489) (xy 381.964712 -226.688546) (xy 381.97409 -226.71151) (xy 381.975868 -226.715574)
			(xy 382.011936 -226.746816) (xy 382.094486 -226.764596) (xy 382.106927 -226.76661) (xy 382.131086 -226.759556)
			(xy 382.14046 -226.751134) (xy 382.740662 -226.150932) (xy 382.747376 -226.143694) (xy 382.754978 -226.12549)
			(xy 382.755394 -226.115626) (xy 382.755394 -226.101402) (xy 382.75387 -226.09556) (xy 382.749651 -226.076791)
			(xy 382.745068 -226.038594) (xy 382.744726 -226.01936) (xy 382.744726 -226.014788) (xy 382.745422 -225.988931)
			(xy 382.753863 -225.937901) (xy 382.770146 -225.888808) (xy 382.793874 -225.842849) (xy 382.824468 -225.801144)
			(xy 382.861182 -225.764711) (xy 382.903121 -225.734439) (xy 382.949262 -225.711066) (xy 382.998479 -225.695161)
			(xy 383.049572 -225.687114) (xy 383.075434 -225.68662) (xy 383.100696 -225.687093) (xy 383.150633 -225.694766)
			(xy 383.198823 -225.709945) (xy 383.244145 -225.732275) (xy 383.285543 -225.761237) (xy 383.322055 -225.796158)
			(xy 383.337816 -225.815906) (xy 383.341118 -225.81997) (xy 383.357628 -225.834448) (xy 383.379218 -225.845624)
			(xy 383.384275 -225.847837) (xy 383.395037 -225.850279) (xy 383.400554 -225.85045) (xy 383.615184 -225.85045)
			(xy 383.625021 -225.849913) (xy 383.643184 -225.842328) (xy 383.65049 -225.835718) (xy 383.910586 -225.575622)
			(xy 383.917307 -225.568387) (xy 383.924918 -225.550182) (xy 383.925318 -225.540316) (xy 383.925318 -224.753678)
			(xy 383.84353 -224.67189) (xy 383.838704 -224.668842) (xy 383.817515 -224.654912) (xy 383.779292 -224.621593)
			(xy 383.746618 -224.582816) (xy 383.73304 -224.5614) (xy 383.571242 -224.399602) (xy 383.561177 -224.390188)
			(xy 383.537195 -224.376634) (xy 383.510462 -224.369983) (xy 383.482924 -224.37072) (xy 383.456586 -224.378791)
			(xy 383.433363 -224.393609) (xy 383.414945 -224.414094) (xy 383.402674 -224.438758) (xy 383.399538 -224.45218)
			(xy 383.394243 -224.476961) (xy 383.377126 -224.524654) (xy 383.352931 -224.569175) (xy 383.322225 -224.609483)
			(xy 383.285727 -224.644633) (xy 383.244292 -224.673801) (xy 383.198892 -224.696304) (xy 383.150589 -224.711615)
			(xy 383.100515 -224.719375) (xy 383.07518 -224.719896) (xy 383.049213 -224.719385) (xy 382.997918 -224.711259)
			(xy 382.948525 -224.695209) (xy 382.902251 -224.671631) (xy 382.860234 -224.641105) (xy 382.823509 -224.604383)
			(xy 382.792981 -224.562368) (xy 382.7694 -224.516095) (xy 382.753346 -224.466704) (xy 382.745216 -224.415409)
			(xy 382.744726 -224.389442) (xy 382.745184 -224.3641) (xy 382.752921 -224.31401) (xy 382.76822 -224.265689)
			(xy 382.790721 -224.220274) (xy 382.819896 -224.178828) (xy 382.855061 -224.142327) (xy 382.895389 -224.111626)
			(xy 382.939934 -224.087447) (xy 382.98765 -224.070357) (xy 383.012442 -224.065084) (xy 383.025878 -224.062016)
			(xy 383.050537 -224.049735) (xy 383.071017 -224.03131) (xy 383.085826 -224.00808) (xy 383.093888 -223.981738)
			(xy 383.094614 -223.954199) (xy 383.087953 -223.927468) (xy 383.074389 -223.90349) (xy 383.06502 -223.89338)
			(xy 382.981962 -223.810322) (xy 382.972256 -223.801227) (xy 382.949235 -223.787922) (xy 382.923559 -223.781013)
			(xy 382.89697 -223.78097) (xy 382.871272 -223.787795) (xy 382.848208 -223.801025) (xy 382.838452 -223.810068)
			(xy 382.819753 -223.827939) (xy 382.77783 -223.85823) (xy 382.731698 -223.881618) (xy 382.682486 -223.897531)
			(xy 382.631395 -223.90558) (xy 382.605534 -223.90608) (xy 382.579562 -223.9056) (xy 382.528257 -223.897479)
			(xy 382.478855 -223.881433) (xy 382.43257 -223.857855) (xy 382.390544 -223.827327) (xy 382.353812 -223.790601)
			(xy 382.323276 -223.748581) (xy 382.29969 -223.702301) (xy 382.283635 -223.652901) (xy 382.275505 -223.601598)
			(xy 382.27508 -223.575626) (xy 382.275604 -223.548756) (xy 382.284294 -223.495722) (xy 382.301449 -223.444793)
			(xy 382.326618 -223.39731) (xy 382.359137 -223.354525) (xy 382.398149 -223.317564) (xy 382.442627 -223.287402)
			(xy 382.491399 -223.264832) (xy 382.517142 -223.25711) (xy 382.55448 -223.24695) (xy 382.55448 -223.054672)
			(xy 382.554051 -223.041124) (xy 382.546913 -223.014985) (xy 382.533149 -222.991646) (xy 382.513728 -222.972751)
			(xy 382.49002 -222.959632) (xy 382.463695 -222.953215) (xy 382.436609 -222.953951) (xy 382.410672 -222.961789)
			(xy 382.387711 -222.976176) (xy 382.378204 -222.985838) (xy 382.359298 -223.005486) (xy 382.31623 -223.038922)
			(xy 382.268256 -223.064829) (xy 382.216677 -223.082503) (xy 382.162895 -223.091465) (xy 382.135634 -223.09201)
			(xy 382.109666 -223.09153) (xy 382.05837 -223.08341) (xy 382.008975 -223.067365) (xy 381.962699 -223.043791)
			(xy 381.920681 -223.013267) (xy 381.883955 -222.976545) (xy 381.853427 -222.93453) (xy 381.829848 -222.888256)
			(xy 381.813798 -222.838863) (xy 381.805673 -222.787568) (xy 381.805673 -222.735632) (xy 381.813798 -222.684337)
			(xy 381.829848 -222.634944) (xy 381.853427 -222.58867) (xy 381.883955 -222.546655) (xy 381.920681 -222.509933)
			(xy 381.962699 -222.479409) (xy 382.008975 -222.455835) (xy 382.05837 -222.43979) (xy 382.109666 -222.43167)
			(xy 382.135634 -222.431102) (xy 382.162894 -222.431664) (xy 382.216672 -222.440626) (xy 382.268248 -222.458299)
			(xy 382.31622 -222.484206) (xy 382.359284 -222.51764) (xy 382.378204 -222.537274) (xy 382.387702 -222.546947)
			(xy 382.410667 -222.561334) (xy 382.436609 -222.569172) (xy 382.463698 -222.569908) (xy 382.490027 -222.563489)
			(xy 382.513739 -222.55037) (xy 382.533163 -222.531473) (xy 382.546931 -222.508131) (xy 382.554072 -222.48199)
			(xy 382.55448 -222.46844) (xy 382.55448 -222.276416) (xy 382.517142 -222.266256) (xy 382.492911 -222.259014)
			(xy 382.446825 -222.238194) (xy 382.404446 -222.210601) (xy 382.366763 -222.176875) (xy 382.334654 -222.137806)
			(xy 382.308869 -222.094303) (xy 382.290009 -222.04738) (xy 382.278513 -221.998134) (xy 382.27465 -221.947711)
			(xy 382.27851 -221.897288) (xy 382.290003 -221.84804) (xy 382.30886 -221.801117) (xy 382.334642 -221.757612)
			(xy 382.366748 -221.71854) (xy 382.404429 -221.684813) (xy 382.446806 -221.657216) (xy 382.492891 -221.636394)
			(xy 382.517142 -221.629224) (xy 382.55448 -221.619064) (xy 382.55448 -221.42704) (xy 382.554059 -221.413485)
			(xy 382.546932 -221.38733) (xy 382.533171 -221.363974) (xy 382.513746 -221.345064) (xy 382.490028 -221.331936)
			(xy 382.463691 -221.325515) (xy 382.436592 -221.326254) (xy 382.410644 -221.334101) (xy 382.387677 -221.348503)
			(xy 382.378204 -221.358206) (xy 382.359299 -221.377856) (xy 382.316232 -221.411295) (xy 382.268258 -221.437204)
			(xy 382.216678 -221.45488) (xy 382.162896 -221.463843) (xy 382.135634 -221.464378) (xy 382.109662 -221.463898)
			(xy 382.058358 -221.455777) (xy 382.008955 -221.439731) (xy 381.962671 -221.416153) (xy 381.920645 -221.385625)
			(xy 381.883912 -221.348899) (xy 381.853377 -221.306879) (xy 381.829792 -221.260599) (xy 381.813736 -221.211199)
			(xy 381.805607 -221.159896) (xy 381.80518 -221.133924) (xy 381.805791 -221.105943) (xy 381.815239 -221.050784)
			(xy 381.823976 -221.024196) (xy 381.831596 -221.002098) (xy 381.627888 -220.649038) (xy 381.605028 -220.64472)
			(xy 381.580084 -220.639583) (xy 381.532051 -220.622663) (xy 381.487183 -220.598573) (xy 381.446542 -220.567886)
			(xy 381.41109 -220.531326) (xy 381.381667 -220.48976) (xy 381.358969 -220.444172) (xy 381.343535 -220.395641)
			(xy 381.335729 -220.345317) (xy 381.33528 -220.319854) (xy 381.335789 -220.293887) (xy 381.343914 -220.242592)
			(xy 381.359962 -220.193199) (xy 381.38354 -220.146925) (xy 381.414066 -220.104909) (xy 381.450789 -220.068186)
			(xy 381.492805 -220.03766) (xy 381.539079 -220.014082) (xy 381.588472 -219.998034) (xy 381.639767 -219.989909)
			(xy 381.691701 -219.989909) (xy 381.742996 -219.998034) (xy 381.792389 -220.014082) (xy 381.838663 -220.03766)
			(xy 381.880679 -220.068186) (xy 381.917402 -220.104909) (xy 381.947928 -220.146925) (xy 381.971506 -220.193199)
			(xy 381.987554 -220.242592) (xy 381.995679 -220.293887) (xy 381.996188 -220.319854) (xy 381.995579 -220.347835)
			(xy 381.986134 -220.402995) (xy 381.977392 -220.429582) (xy 381.969772 -220.451426) (xy 382.173734 -220.80474)
			(xy 382.196594 -220.809058) (xy 382.22245 -220.814467) (xy 382.272136 -220.832394) (xy 382.318342 -220.85799)
			(xy 382.359893 -220.890603) (xy 382.378204 -220.909642) (xy 382.3877 -220.919317) (xy 382.410663 -220.933708)
			(xy 382.436604 -220.941549) (xy 382.463694 -220.942286) (xy 382.490023 -220.935868) (xy 382.513734 -220.922746)
			(xy 382.533156 -220.903847) (xy 382.54692 -220.880502) (xy 382.554054 -220.854358) (xy 382.55448 -220.840808)
			(xy 382.55448 -220.648784) (xy 382.517142 -220.63837) (xy 382.49289 -220.631156) (xy 382.446757 -220.610383)
			(xy 382.40433 -220.582821) (xy 382.3666 -220.549113) (xy 382.334449 -220.510048) (xy 382.308629 -220.466538)
			(xy 382.289743 -220.419601) (xy 382.278233 -220.370334) (xy 382.274367 -220.319888) (xy 382.278237 -220.269442)
			(xy 382.289751 -220.220175) (xy 382.30864 -220.17324) (xy 382.334463 -220.129732) (xy 382.366617 -220.090669)
			(xy 382.40435 -220.056964) (xy 382.446779 -220.029405) (xy 382.492914 -220.008635) (xy 382.517142 -220.001338)
			(xy 382.55448 -219.990924) (xy 382.55448 -219.799154) (xy 382.55406 -219.785598) (xy 382.546936 -219.759439)
			(xy 382.533175 -219.736079) (xy 382.51375 -219.717167) (xy 382.49003 -219.704036) (xy 382.46369 -219.697614)
			(xy 382.436589 -219.698354) (xy 382.410638 -219.706204) (xy 382.38767 -219.720609) (xy 382.378204 -219.73032)
			(xy 382.359298 -219.749969) (xy 382.316231 -219.783407) (xy 382.268257 -219.809315) (xy 382.216678 -219.82699)
			(xy 382.162896 -219.835952) (xy 382.135634 -219.836492) (xy 382.10966 -219.836012) (xy 382.058351 -219.82789)
			(xy 382.008944 -219.811841) (xy 381.962656 -219.788261) (xy 381.920628 -219.757729) (xy 381.883893 -219.720998)
			(xy 381.853357 -219.678973) (xy 381.829772 -219.632687) (xy 381.813718 -219.583282) (xy 381.805591 -219.531974)
			(xy 381.805591 -219.480026) (xy 381.813718 -219.428718) (xy 381.829772 -219.379313) (xy 381.853357 -219.333027)
			(xy 381.883893 -219.291002) (xy 381.920628 -219.254271) (xy 381.962656 -219.223739) (xy 382.008944 -219.200159)
			(xy 382.058351 -219.18411) (xy 382.10966 -219.175988) (xy 382.135634 -219.175584) (xy 382.162894 -219.176146)
			(xy 382.216673 -219.185107) (xy 382.268249 -219.20278) (xy 382.316222 -219.228685) (xy 382.359288 -219.262119)
			(xy 382.378204 -219.281756) (xy 382.387701 -219.29143) (xy 382.410665 -219.30582) (xy 382.436606 -219.313659)
			(xy 382.463696 -219.314396) (xy 382.490024 -219.307977) (xy 382.513736 -219.294856) (xy 382.533159 -219.275958)
			(xy 382.546925 -219.252615) (xy 382.554062 -219.226472) (xy 382.55448 -219.212922) (xy 382.55448 -219.020898)
			(xy 382.517142 -219.010738) (xy 382.492913 -219.003496) (xy 382.446829 -218.982677) (xy 382.404453 -218.955084)
			(xy 382.366772 -218.92136) (xy 382.334666 -218.882292) (xy 382.308883 -218.838791) (xy 382.290024 -218.791871)
			(xy 382.27853 -218.742626) (xy 382.274668 -218.692206) (xy 382.278528 -218.641785) (xy 382.290021 -218.592541)
			(xy 382.308878 -218.54562) (xy 382.334659 -218.502118) (xy 382.366764 -218.463049) (xy 382.404443 -218.429323)
			(xy 382.446819 -218.401729) (xy 382.492901 -218.380908) (xy 382.517142 -218.373706) (xy 382.55448 -218.363546)
			(xy 382.55448 -218.171522) (xy 382.554057 -218.157969) (xy 382.546927 -218.131818) (xy 382.533165 -218.108466)
			(xy 382.513741 -218.089561) (xy 382.490026 -218.076435) (xy 382.463692 -218.070015) (xy 382.436597 -218.070753)
			(xy 382.410651 -218.078598) (xy 382.387686 -218.092996) (xy 382.378204 -218.102688) (xy 382.359297 -218.122334)
			(xy 382.316227 -218.155764) (xy 382.268252 -218.181667) (xy 382.216674 -218.199339) (xy 382.162895 -218.208299)
			(xy 382.135634 -218.20886) (xy 382.109663 -218.20838) (xy 382.058359 -218.200259) (xy 382.008958 -218.184212)
			(xy 381.962675 -218.160634) (xy 381.920651 -218.130106) (xy 381.88392 -218.09338) (xy 381.853387 -218.051359)
			(xy 381.829803 -218.005079) (xy 381.81375 -217.95568) (xy 381.805623 -217.904377) (xy 381.80518 -217.878406)
			(xy 381.805793 -217.850426) (xy 381.815243 -217.795268) (xy 381.823976 -217.768678) (xy 381.831596 -217.74658)
			(xy 381.627888 -217.39352) (xy 381.604774 -217.389202) (xy 381.579828 -217.384067) (xy 381.531791 -217.367152)
			(xy 381.486919 -217.343065) (xy 381.446273 -217.312378) (xy 381.410818 -217.275818) (xy 381.381392 -217.234251)
			(xy 381.358693 -217.188661) (xy 381.343258 -217.140127) (xy 381.335454 -217.0898) (xy 381.335026 -217.064336)
			(xy 381.335535 -217.038369) (xy 381.34366 -216.987074) (xy 381.359708 -216.937681) (xy 381.383286 -216.891407)
			(xy 381.413812 -216.849391) (xy 381.450535 -216.812668) (xy 381.492551 -216.782142) (xy 381.538825 -216.758564)
			(xy 381.588218 -216.742516) (xy 381.639513 -216.734391) (xy 381.691447 -216.734391) (xy 381.742742 -216.742516)
			(xy 381.792135 -216.758564) (xy 381.838409 -216.782142) (xy 381.880425 -216.812668) (xy 381.917148 -216.849391)
			(xy 381.947674 -216.891407) (xy 381.971252 -216.937681) (xy 381.9873 -216.987074) (xy 381.995425 -217.038369)
			(xy 381.995934 -217.064336) (xy 381.995934 -217.065098) (xy 381.995324 -217.092814) (xy 381.986003 -217.147459)
			(xy 381.977392 -217.17381) (xy 381.969518 -217.195654) (xy 382.173734 -217.549222) (xy 382.196594 -217.55354)
			(xy 382.22245 -217.558949) (xy 382.272137 -217.576875) (xy 382.318343 -217.60247) (xy 382.359896 -217.635081)
			(xy 382.378204 -217.654124) (xy 382.387699 -217.6638) (xy 382.410661 -217.678194) (xy 382.436601 -217.686036)
			(xy 382.463691 -217.686774) (xy 382.490021 -217.680355) (xy 382.513732 -217.667233) (xy 382.533152 -217.648332)
			(xy 382.546913 -217.624985) (xy 382.554044 -217.59884) (xy 382.55448 -217.58529) (xy 382.55448 -217.393012)
			(xy 382.517142 -217.382852) (xy 382.492912 -217.37561) (xy 382.446826 -217.354791) (xy 382.404447 -217.327197)
			(xy 382.366765 -217.293472) (xy 382.334657 -217.254403) (xy 382.308872 -217.2109) (xy 382.290012 -217.163978)
			(xy 382.278517 -217.114732) (xy 382.274654 -217.06431) (xy 382.278514 -217.013887) (xy 382.290007 -216.96464)
			(xy 382.308864 -216.917717) (xy 382.334646 -216.874213) (xy 382.366752 -216.835142) (xy 382.404432 -216.801415)
			(xy 382.446809 -216.773819) (xy 382.492893 -216.752997) (xy 382.517142 -216.74582) (xy 382.55448 -216.73566)
			(xy 382.55448 -216.550748) (xy 382.500124 -216.496392) (xy 382.48871 -216.485758) (xy 382.46105 -216.471369)
			(xy 382.430338 -216.465995) (xy 382.399435 -216.470139) (xy 382.371224 -216.483414) (xy 382.359408 -216.493598)
			(xy 382.341011 -216.509932) (xy 382.300285 -216.537529) (xy 382.255916 -216.558778) (xy 382.208884 -216.573207)
			(xy 382.160232 -216.580497) (xy 382.135634 -216.580974) (xy 382.109662 -216.580494) (xy 382.058358 -216.572373)
			(xy 382.008956 -216.556326) (xy 381.962672 -216.532749) (xy 381.920646 -216.502221) (xy 381.883914 -216.465495)
			(xy 381.853379 -216.423474) (xy 381.829794 -216.377194) (xy 381.81374 -216.327795) (xy 381.805611 -216.276492)
			(xy 381.80518 -216.25052) (xy 381.805631 -216.22592) (xy 381.812926 -216.177265) (xy 381.827356 -216.13023)
			(xy 381.848604 -216.085855) (xy 381.876198 -216.045123) (xy 381.892556 -216.026746) (xy 381.902703 -216.014906)
			(xy 381.915944 -215.986691) (xy 381.920084 -215.955801) (xy 381.914741 -215.925096) (xy 381.900409 -215.89742)
			(xy 381.889762 -215.88603) (xy 381.03048 -215.026748) (xy 375.75617 -215.026748) (xy 375.113804 -215.669114)
			(xy 375.113804 -216.276487) (xy 375.227089 -216.276487) (xy 375.227089 -216.224553) (xy 375.235214 -216.173258)
			(xy 375.251262 -216.123865) (xy 375.27484 -216.077591) (xy 375.305366 -216.035575) (xy 375.342089 -215.998852)
			(xy 375.384105 -215.968326) (xy 375.430379 -215.944748) (xy 375.479772 -215.9287) (xy 375.531067 -215.920575)
			(xy 375.583001 -215.920575) (xy 375.634296 -215.9287) (xy 375.683689 -215.944748) (xy 375.729963 -215.968326)
			(xy 375.771979 -215.998852) (xy 375.808702 -216.035575) (xy 375.839228 -216.077591) (xy 375.862806 -216.123865)
			(xy 375.878854 -216.173258) (xy 375.886979 -216.224553) (xy 375.887488 -216.25052) (xy 375.886979 -216.276487)
			(xy 376.166889 -216.276487) (xy 376.166889 -216.224553) (xy 376.175014 -216.173258) (xy 376.191062 -216.123865)
			(xy 376.21464 -216.077591) (xy 376.245166 -216.035575) (xy 376.281889 -215.998852) (xy 376.323905 -215.968326)
			(xy 376.370179 -215.944748) (xy 376.419572 -215.9287) (xy 376.470867 -215.920575) (xy 376.522801 -215.920575)
			(xy 376.574096 -215.9287) (xy 376.623489 -215.944748) (xy 376.669763 -215.968326) (xy 376.711779 -215.998852)
			(xy 376.748502 -216.035575) (xy 376.779028 -216.077591) (xy 376.802606 -216.123865) (xy 376.818654 -216.173258)
			(xy 376.826779 -216.224553) (xy 376.827288 -216.25052) (xy 376.826779 -216.276487) (xy 377.106689 -216.276487)
			(xy 377.106689 -216.224553) (xy 377.114814 -216.173258) (xy 377.130862 -216.123865) (xy 377.15444 -216.077591)
			(xy 377.184966 -216.035575) (xy 377.221689 -215.998852) (xy 377.263705 -215.968326) (xy 377.309979 -215.944748)
			(xy 377.359372 -215.9287) (xy 377.410667 -215.920575) (xy 377.462601 -215.920575) (xy 377.513896 -215.9287)
			(xy 377.563289 -215.944748) (xy 377.609563 -215.968326) (xy 377.651579 -215.998852) (xy 377.688302 -216.035575)
			(xy 377.718828 -216.077591) (xy 377.742406 -216.123865) (xy 377.758454 -216.173258) (xy 377.766579 -216.224553)
			(xy 377.767088 -216.25052) (xy 377.766579 -216.276487) (xy 378.046489 -216.276487) (xy 378.046489 -216.224553)
			(xy 378.054614 -216.173258) (xy 378.070662 -216.123865) (xy 378.09424 -216.077591) (xy 378.124766 -216.035575)
			(xy 378.161489 -215.998852) (xy 378.203505 -215.968326) (xy 378.249779 -215.944748) (xy 378.299172 -215.9287)
			(xy 378.350467 -215.920575) (xy 378.402401 -215.920575) (xy 378.453696 -215.9287) (xy 378.503089 -215.944748)
			(xy 378.549363 -215.968326) (xy 378.591379 -215.998852) (xy 378.628102 -216.035575) (xy 378.658628 -216.077591)
			(xy 378.682206 -216.123865) (xy 378.698254 -216.173258) (xy 378.706379 -216.224553) (xy 378.706888 -216.25052)
			(xy 378.706379 -216.276487) (xy 378.986289 -216.276487) (xy 378.986289 -216.224553) (xy 378.994414 -216.173258)
			(xy 379.010462 -216.123865) (xy 379.03404 -216.077591) (xy 379.064566 -216.035575) (xy 379.101289 -215.998852)
			(xy 379.143305 -215.968326) (xy 379.189579 -215.944748) (xy 379.238972 -215.9287) (xy 379.290267 -215.920575)
			(xy 379.342201 -215.920575) (xy 379.393496 -215.9287) (xy 379.442889 -215.944748) (xy 379.489163 -215.968326)
			(xy 379.531179 -215.998852) (xy 379.567902 -216.035575) (xy 379.598428 -216.077591) (xy 379.622006 -216.123865)
			(xy 379.638054 -216.173258) (xy 379.646179 -216.224553) (xy 379.646688 -216.25052) (xy 379.646179 -216.276487)
			(xy 379.926089 -216.276487) (xy 379.926089 -216.224553) (xy 379.934214 -216.173258) (xy 379.950262 -216.123865)
			(xy 379.97384 -216.077591) (xy 380.004366 -216.035575) (xy 380.041089 -215.998852) (xy 380.083105 -215.968326)
			(xy 380.129379 -215.944748) (xy 380.178772 -215.9287) (xy 380.230067 -215.920575) (xy 380.282001 -215.920575)
			(xy 380.333296 -215.9287) (xy 380.382689 -215.944748) (xy 380.428963 -215.968326) (xy 380.470979 -215.998852)
			(xy 380.507702 -216.035575) (xy 380.538228 -216.077591) (xy 380.561806 -216.123865) (xy 380.577854 -216.173258)
			(xy 380.585979 -216.224553) (xy 380.586488 -216.25052) (xy 380.585979 -216.276487) (xy 380.865889 -216.276487)
			(xy 380.865889 -216.224553) (xy 380.874014 -216.173258) (xy 380.890062 -216.123865) (xy 380.91364 -216.077591)
			(xy 380.944166 -216.035575) (xy 380.980889 -215.998852) (xy 381.022905 -215.968326) (xy 381.069179 -215.944748)
			(xy 381.118572 -215.9287) (xy 381.169867 -215.920575) (xy 381.221801 -215.920575) (xy 381.273096 -215.9287)
			(xy 381.322489 -215.944748) (xy 381.368763 -215.968326) (xy 381.410779 -215.998852) (xy 381.447502 -216.035575)
			(xy 381.478028 -216.077591) (xy 381.501606 -216.123865) (xy 381.517654 -216.173258) (xy 381.525779 -216.224553)
			(xy 381.526288 -216.25052) (xy 381.525779 -216.276487) (xy 381.517654 -216.327782) (xy 381.501606 -216.377175)
			(xy 381.478028 -216.423449) (xy 381.447502 -216.465465) (xy 381.410779 -216.502188) (xy 381.368763 -216.532714)
			(xy 381.322489 -216.556292) (xy 381.273096 -216.57234) (xy 381.221801 -216.580465) (xy 381.169867 -216.580465)
			(xy 381.118572 -216.57234) (xy 381.069179 -216.556292) (xy 381.022905 -216.532714) (xy 380.980889 -216.502188)
			(xy 380.944166 -216.465465) (xy 380.91364 -216.423449) (xy 380.890062 -216.377175) (xy 380.874014 -216.327782)
			(xy 380.865889 -216.276487) (xy 380.585979 -216.276487) (xy 380.577854 -216.327782) (xy 380.561806 -216.377175)
			(xy 380.538228 -216.423449) (xy 380.507702 -216.465465) (xy 380.470979 -216.502188) (xy 380.428963 -216.532714)
			(xy 380.382689 -216.556292) (xy 380.333296 -216.57234) (xy 380.282001 -216.580465) (xy 380.230067 -216.580465)
			(xy 380.178772 -216.57234) (xy 380.129379 -216.556292) (xy 380.083105 -216.532714) (xy 380.041089 -216.502188)
			(xy 380.004366 -216.465465) (xy 379.97384 -216.423449) (xy 379.950262 -216.377175) (xy 379.934214 -216.327782)
			(xy 379.926089 -216.276487) (xy 379.646179 -216.276487) (xy 379.638054 -216.327782) (xy 379.622006 -216.377175)
			(xy 379.598428 -216.423449) (xy 379.567902 -216.465465) (xy 379.531179 -216.502188) (xy 379.489163 -216.532714)
			(xy 379.442889 -216.556292) (xy 379.393496 -216.57234) (xy 379.342201 -216.580465) (xy 379.290267 -216.580465)
			(xy 379.238972 -216.57234) (xy 379.189579 -216.556292) (xy 379.143305 -216.532714) (xy 379.101289 -216.502188)
			(xy 379.064566 -216.465465) (xy 379.03404 -216.423449) (xy 379.010462 -216.377175) (xy 378.994414 -216.327782)
			(xy 378.986289 -216.276487) (xy 378.706379 -216.276487) (xy 378.698254 -216.327782) (xy 378.682206 -216.377175)
			(xy 378.658628 -216.423449) (xy 378.628102 -216.465465) (xy 378.591379 -216.502188) (xy 378.549363 -216.532714)
			(xy 378.503089 -216.556292) (xy 378.453696 -216.57234) (xy 378.402401 -216.580465) (xy 378.350467 -216.580465)
			(xy 378.299172 -216.57234) (xy 378.249779 -216.556292) (xy 378.203505 -216.532714) (xy 378.161489 -216.502188)
			(xy 378.124766 -216.465465) (xy 378.09424 -216.423449) (xy 378.070662 -216.377175) (xy 378.054614 -216.327782)
			(xy 378.046489 -216.276487) (xy 377.766579 -216.276487) (xy 377.758454 -216.327782) (xy 377.742406 -216.377175)
			(xy 377.718828 -216.423449) (xy 377.688302 -216.465465) (xy 377.651579 -216.502188) (xy 377.609563 -216.532714)
			(xy 377.563289 -216.556292) (xy 377.513896 -216.57234) (xy 377.462601 -216.580465) (xy 377.410667 -216.580465)
			(xy 377.359372 -216.57234) (xy 377.309979 -216.556292) (xy 377.263705 -216.532714) (xy 377.221689 -216.502188)
			(xy 377.184966 -216.465465) (xy 377.15444 -216.423449) (xy 377.130862 -216.377175) (xy 377.114814 -216.327782)
			(xy 377.106689 -216.276487) (xy 376.826779 -216.276487) (xy 376.818654 -216.327782) (xy 376.802606 -216.377175)
			(xy 376.779028 -216.423449) (xy 376.748502 -216.465465) (xy 376.711779 -216.502188) (xy 376.669763 -216.532714)
			(xy 376.623489 -216.556292) (xy 376.574096 -216.57234) (xy 376.522801 -216.580465) (xy 376.470867 -216.580465)
			(xy 376.419572 -216.57234) (xy 376.370179 -216.556292) (xy 376.323905 -216.532714) (xy 376.281889 -216.502188)
			(xy 376.245166 -216.465465) (xy 376.21464 -216.423449) (xy 376.191062 -216.377175) (xy 376.175014 -216.327782)
			(xy 376.166889 -216.276487) (xy 375.886979 -216.276487) (xy 375.878854 -216.327782) (xy 375.862806 -216.377175)
			(xy 375.839228 -216.423449) (xy 375.808702 -216.465465) (xy 375.771979 -216.502188) (xy 375.729963 -216.532714)
			(xy 375.683689 -216.556292) (xy 375.634296 -216.57234) (xy 375.583001 -216.580465) (xy 375.531067 -216.580465)
			(xy 375.479772 -216.57234) (xy 375.430379 -216.556292) (xy 375.384105 -216.532714) (xy 375.342089 -216.502188)
			(xy 375.305366 -216.465465) (xy 375.27484 -216.423449) (xy 375.251262 -216.377175) (xy 375.235214 -216.327782)
			(xy 375.227089 -216.276487) (xy 375.113804 -216.276487) (xy 375.113804 -216.732358) (xy 375.15419 -216.74074)
			(xy 375.178669 -216.746293) (xy 375.22571 -216.763799) (xy 375.269562 -216.788218) (xy 375.309217 -216.818989)
			(xy 375.343762 -216.855402) (xy 375.372402 -216.896622) (xy 375.39448 -216.941698) (xy 375.409486 -216.989595)
			(xy 375.417076 -217.039211) (xy 375.417075 -217.064336) (xy 375.696226 -217.064336) (xy 375.696735 -217.038369)
			(xy 375.70486 -216.987074) (xy 375.720908 -216.937681) (xy 375.744486 -216.891407) (xy 375.775012 -216.849391)
			(xy 375.811735 -216.812668) (xy 375.853751 -216.782142) (xy 375.900025 -216.758564) (xy 375.949418 -216.742516)
			(xy 376.000713 -216.734391) (xy 376.052647 -216.734391) (xy 376.103942 -216.742516) (xy 376.153335 -216.758564)
			(xy 376.199609 -216.782142) (xy 376.241625 -216.812668) (xy 376.278348 -216.849391) (xy 376.308874 -216.891407)
			(xy 376.332452 -216.937681) (xy 376.3485 -216.987074) (xy 376.356625 -217.038369) (xy 376.357134 -217.064336)
			(xy 376.357134 -217.065098) (xy 376.356602 -217.090303) (xy 376.636789 -217.090303) (xy 376.636789 -217.038369)
			(xy 376.644914 -216.987074) (xy 376.660962 -216.937681) (xy 376.68454 -216.891407) (xy 376.715066 -216.849391)
			(xy 376.751789 -216.812668) (xy 376.793805 -216.782142) (xy 376.840079 -216.758564) (xy 376.889472 -216.742516)
			(xy 376.940767 -216.734391) (xy 376.992701 -216.734391) (xy 377.043996 -216.742516) (xy 377.093389 -216.758564)
			(xy 377.139663 -216.782142) (xy 377.181679 -216.812668) (xy 377.218402 -216.849391) (xy 377.248928 -216.891407)
			(xy 377.272506 -216.937681) (xy 377.288554 -216.987074) (xy 377.296679 -217.038369) (xy 377.297188 -217.064336)
			(xy 377.575826 -217.064336) (xy 377.576335 -217.038369) (xy 377.58446 -216.987074) (xy 377.600508 -216.937681)
			(xy 377.624086 -216.891407) (xy 377.654612 -216.849391) (xy 377.691335 -216.812668) (xy 377.733351 -216.782142)
			(xy 377.779625 -216.758564) (xy 377.829018 -216.742516) (xy 377.880313 -216.734391) (xy 377.932247 -216.734391)
			(xy 377.983542 -216.742516) (xy 378.032935 -216.758564) (xy 378.079209 -216.782142) (xy 378.121225 -216.812668)
			(xy 378.157948 -216.849391) (xy 378.188474 -216.891407) (xy 378.212052 -216.937681) (xy 378.2281 -216.987074)
			(xy 378.236225 -217.038369) (xy 378.236734 -217.064336) (xy 378.236734 -217.065098) (xy 378.236202 -217.090303)
			(xy 378.516389 -217.090303) (xy 378.516389 -217.038369) (xy 378.524514 -216.987074) (xy 378.540562 -216.937681)
			(xy 378.56414 -216.891407) (xy 378.594666 -216.849391) (xy 378.631389 -216.812668) (xy 378.673405 -216.782142)
			(xy 378.719679 -216.758564) (xy 378.769072 -216.742516) (xy 378.820367 -216.734391) (xy 378.872301 -216.734391)
			(xy 378.923596 -216.742516) (xy 378.972989 -216.758564) (xy 379.019263 -216.782142) (xy 379.061279 -216.812668)
			(xy 379.098002 -216.849391) (xy 379.128528 -216.891407) (xy 379.152106 -216.937681) (xy 379.168154 -216.987074)
			(xy 379.176279 -217.038369) (xy 379.176788 -217.064336) (xy 379.455426 -217.064336) (xy 379.455935 -217.038369)
			(xy 379.46406 -216.987074) (xy 379.480108 -216.937681) (xy 379.503686 -216.891407) (xy 379.534212 -216.849391)
			(xy 379.570935 -216.812668) (xy 379.612951 -216.782142) (xy 379.659225 -216.758564) (xy 379.708618 -216.742516)
			(xy 379.759913 -216.734391) (xy 379.811847 -216.734391) (xy 379.863142 -216.742516) (xy 379.912535 -216.758564)
			(xy 379.958809 -216.782142) (xy 380.000825 -216.812668) (xy 380.037548 -216.849391) (xy 380.068074 -216.891407)
			(xy 380.091652 -216.937681) (xy 380.1077 -216.987074) (xy 380.115825 -217.038369) (xy 380.116334 -217.064336)
			(xy 380.116334 -217.065098) (xy 380.115802 -217.090303) (xy 380.395989 -217.090303) (xy 380.395989 -217.038369)
			(xy 380.404114 -216.987074) (xy 380.420162 -216.937681) (xy 380.44374 -216.891407) (xy 380.474266 -216.849391)
			(xy 380.510989 -216.812668) (xy 380.553005 -216.782142) (xy 380.599279 -216.758564) (xy 380.648672 -216.742516)
			(xy 380.699967 -216.734391) (xy 380.751901 -216.734391) (xy 380.803196 -216.742516) (xy 380.852589 -216.758564)
			(xy 380.898863 -216.782142) (xy 380.940879 -216.812668) (xy 380.977602 -216.849391) (xy 381.008128 -216.891407)
			(xy 381.031706 -216.937681) (xy 381.047754 -216.987074) (xy 381.055879 -217.038369) (xy 381.056388 -217.064336)
			(xy 381.055879 -217.090303) (xy 381.047754 -217.141598) (xy 381.031706 -217.190991) (xy 381.008128 -217.237265)
			(xy 380.977602 -217.279281) (xy 380.940879 -217.316004) (xy 380.898863 -217.34653) (xy 380.852589 -217.370108)
			(xy 380.803196 -217.386156) (xy 380.751901 -217.394281) (xy 380.699967 -217.394281) (xy 380.648672 -217.386156)
			(xy 380.599279 -217.370108) (xy 380.553005 -217.34653) (xy 380.510989 -217.316004) (xy 380.474266 -217.279281)
			(xy 380.44374 -217.237265) (xy 380.420162 -217.190991) (xy 380.404114 -217.141598) (xy 380.395989 -217.090303)
			(xy 380.115802 -217.090303) (xy 380.115749 -217.092816) (xy 380.106423 -217.147463) (xy 380.097792 -217.17381)
			(xy 380.089918 -217.195654) (xy 380.294134 -217.549222) (xy 380.316994 -217.55354) (xy 380.341903 -217.558766)
			(xy 380.389885 -217.575722) (xy 380.434702 -217.599831) (xy 380.475295 -217.630524) (xy 380.510705 -217.667074)
			(xy 380.540096 -217.70862) (xy 380.562772 -217.754178) (xy 380.5782 -217.802674) (xy 380.586013 -217.852961)
			(xy 380.586488 -217.878406) (xy 380.585979 -217.904373) (xy 380.577854 -217.955668) (xy 380.561806 -218.005061)
			(xy 380.538228 -218.051335) (xy 380.507702 -218.093351) (xy 380.470979 -218.130074) (xy 380.428963 -218.1606)
			(xy 380.382689 -218.184178) (xy 380.333296 -218.200226) (xy 380.282001 -218.208351) (xy 380.230067 -218.208351)
			(xy 380.178772 -218.200226) (xy 380.129379 -218.184178) (xy 380.083105 -218.1606) (xy 380.041089 -218.130074)
			(xy 380.004366 -218.093351) (xy 379.97384 -218.051335) (xy 379.950262 -218.005061) (xy 379.934214 -217.955668)
			(xy 379.926089 -217.904373) (xy 379.92558 -217.878406) (xy 379.926135 -217.85042) (xy 379.935584 -217.795252)
			(xy 379.944376 -217.768678) (xy 379.951996 -217.74658) (xy 379.748288 -217.39352) (xy 379.725174 -217.389202)
			(xy 379.700229 -217.384082) (xy 379.652205 -217.367147) (xy 379.607346 -217.343047) (xy 379.566713 -217.312353)
			(xy 379.531268 -217.275792) (xy 379.501849 -217.234227) (xy 379.479151 -217.188643) (xy 379.463713 -217.140117)
			(xy 379.455898 -217.089797) (xy 379.455426 -217.064336) (xy 379.176788 -217.064336) (xy 379.176279 -217.090303)
			(xy 379.168154 -217.141598) (xy 379.152106 -217.190991) (xy 379.128528 -217.237265) (xy 379.098002 -217.279281)
			(xy 379.061279 -217.316004) (xy 379.019263 -217.34653) (xy 378.972989 -217.370108) (xy 378.923596 -217.386156)
			(xy 378.872301 -217.394281) (xy 378.820367 -217.394281) (xy 378.769072 -217.386156) (xy 378.719679 -217.370108)
			(xy 378.673405 -217.34653) (xy 378.631389 -217.316004) (xy 378.594666 -217.279281) (xy 378.56414 -217.237265)
			(xy 378.540562 -217.190991) (xy 378.524514 -217.141598) (xy 378.516389 -217.090303) (xy 378.236202 -217.090303)
			(xy 378.236149 -217.092816) (xy 378.226823 -217.147463) (xy 378.218192 -217.17381) (xy 378.210318 -217.195654)
			(xy 378.414534 -217.549222) (xy 378.437394 -217.55354) (xy 378.462303 -217.558766) (xy 378.510285 -217.575722)
			(xy 378.555102 -217.599831) (xy 378.595695 -217.630524) (xy 378.631105 -217.667074) (xy 378.660496 -217.70862)
			(xy 378.683172 -217.754178) (xy 378.6986 -217.802674) (xy 378.706413 -217.852961) (xy 378.706888 -217.878406)
			(xy 378.706379 -217.904373) (xy 378.698254 -217.955668) (xy 378.682206 -218.005061) (xy 378.658628 -218.051335)
			(xy 378.628102 -218.093351) (xy 378.591379 -218.130074) (xy 378.549363 -218.1606) (xy 378.503089 -218.184178)
			(xy 378.453696 -218.200226) (xy 378.402401 -218.208351) (xy 378.350467 -218.208351) (xy 378.299172 -218.200226)
			(xy 378.249779 -218.184178) (xy 378.203505 -218.1606) (xy 378.161489 -218.130074) (xy 378.124766 -218.093351)
			(xy 378.09424 -218.051335) (xy 378.070662 -218.005061) (xy 378.054614 -217.955668) (xy 378.046489 -217.904373)
			(xy 378.04598 -217.878406) (xy 378.046535 -217.85042) (xy 378.055984 -217.795252) (xy 378.064776 -217.768678)
			(xy 378.072396 -217.74658) (xy 377.868688 -217.39352) (xy 377.845574 -217.389202) (xy 377.820629 -217.384082)
			(xy 377.772605 -217.367147) (xy 377.727746 -217.343047) (xy 377.687113 -217.312353) (xy 377.651668 -217.275792)
			(xy 377.622249 -217.234227) (xy 377.599551 -217.188643) (xy 377.584113 -217.140117) (xy 377.576298 -217.089797)
			(xy 377.575826 -217.064336) (xy 377.297188 -217.064336) (xy 377.296679 -217.090303) (xy 377.288554 -217.141598)
			(xy 377.272506 -217.190991) (xy 377.248928 -217.237265) (xy 377.218402 -217.279281) (xy 377.181679 -217.316004)
			(xy 377.139663 -217.34653) (xy 377.093389 -217.370108) (xy 377.043996 -217.386156) (xy 376.992701 -217.394281)
			(xy 376.940767 -217.394281) (xy 376.889472 -217.386156) (xy 376.840079 -217.370108) (xy 376.793805 -217.34653)
			(xy 376.751789 -217.316004) (xy 376.715066 -217.279281) (xy 376.68454 -217.237265) (xy 376.660962 -217.190991)
			(xy 376.644914 -217.141598) (xy 376.636789 -217.090303) (xy 376.356602 -217.090303) (xy 376.356549 -217.092816)
			(xy 376.347223 -217.147463) (xy 376.338592 -217.17381) (xy 376.330718 -217.195654) (xy 376.534934 -217.549222)
			(xy 376.557794 -217.55354) (xy 376.582703 -217.558766) (xy 376.630685 -217.575722) (xy 376.675502 -217.599831)
			(xy 376.716095 -217.630524) (xy 376.751505 -217.667074) (xy 376.780896 -217.70862) (xy 376.803572 -217.754178)
			(xy 376.819 -217.802674) (xy 376.826813 -217.852961) (xy 376.827288 -217.878406) (xy 376.826779 -217.904373)
			(xy 376.818654 -217.955668) (xy 376.802606 -218.005061) (xy 376.779028 -218.051335) (xy 376.748502 -218.093351)
			(xy 376.711779 -218.130074) (xy 376.669763 -218.1606) (xy 376.623489 -218.184178) (xy 376.574096 -218.200226)
			(xy 376.522801 -218.208351) (xy 376.470867 -218.208351) (xy 376.419572 -218.200226) (xy 376.370179 -218.184178)
			(xy 376.323905 -218.1606) (xy 376.281889 -218.130074) (xy 376.245166 -218.093351) (xy 376.21464 -218.051335)
			(xy 376.191062 -218.005061) (xy 376.175014 -217.955668) (xy 376.166889 -217.904373) (xy 376.16638 -217.878406)
			(xy 376.166935 -217.85042) (xy 376.176384 -217.795252) (xy 376.185176 -217.768678) (xy 376.192796 -217.74658)
			(xy 375.989088 -217.39352) (xy 375.965974 -217.389202) (xy 375.941029 -217.384082) (xy 375.893005 -217.367147)
			(xy 375.848146 -217.343047) (xy 375.807513 -217.312353) (xy 375.772068 -217.275792) (xy 375.742649 -217.234227)
			(xy 375.719951 -217.188643) (xy 375.704513 -217.140117) (xy 375.696698 -217.089797) (xy 375.696226 -217.064336)
			(xy 375.417075 -217.064336) (xy 375.417075 -217.089404) (xy 375.409483 -217.139019) (xy 375.394474 -217.186915)
			(xy 375.372395 -217.231991) (xy 375.343753 -217.273209) (xy 375.309206 -217.309621) (xy 375.26955 -217.34039)
			(xy 375.225696 -217.364807) (xy 375.178655 -217.382311) (xy 375.15419 -217.387932) (xy 375.113804 -217.396314)
			(xy 375.113804 -218.060778) (xy 375.114197 -218.070315) (xy 375.121159 -218.088074) (xy 375.134128 -218.102061)
			(xy 375.151311 -218.110342) (xy 375.170332 -218.111772) (xy 375.18856 -218.106153) (xy 375.203475 -218.094263)
			(xy 375.208546 -218.086178) (xy 375.252742 -218.00947) (xy 375.245122 -217.987626) (xy 375.236482 -217.961217)
			(xy 375.227169 -217.906441) (xy 375.22658 -217.87866) (xy 375.22658 -217.878406) (xy 375.227089 -217.852439)
			(xy 375.235214 -217.801144) (xy 375.251262 -217.751751) (xy 375.27484 -217.705477) (xy 375.305366 -217.663461)
			(xy 375.342089 -217.626738) (xy 375.384105 -217.596212) (xy 375.430379 -217.572634) (xy 375.479772 -217.556586)
			(xy 375.531067 -217.548461) (xy 375.583001 -217.548461) (xy 375.634296 -217.556586) (xy 375.683689 -217.572634)
			(xy 375.729963 -217.596212) (xy 375.771979 -217.626738) (xy 375.808702 -217.663461) (xy 375.839228 -217.705477)
			(xy 375.862806 -217.751751) (xy 375.878854 -217.801144) (xy 375.886979 -217.852439) (xy 375.887488 -217.878406)
			(xy 375.887017 -217.903878) (xy 375.879196 -217.954219) (xy 375.86374 -218.002763) (xy 375.841016 -218.048359)
			(xy 375.811562 -218.089926) (xy 375.776077 -218.126479) (xy 375.735401 -218.157153) (xy 375.690499 -218.181218)
			(xy 375.642435 -218.198106) (xy 375.617486 -218.203272) (xy 375.594372 -218.20759) (xy 375.390918 -218.560396)
			(xy 375.398538 -218.582494) (xy 375.407331 -218.609068) (xy 375.416779 -218.664236) (xy 375.417334 -218.692222)
			(xy 376.636026 -218.692222) (xy 376.636459 -218.66677) (xy 376.644247 -218.616464) (xy 376.65966 -218.567949)
			(xy 376.682331 -218.522372) (xy 376.711724 -218.480811) (xy 376.747144 -218.44425) (xy 376.787752 -218.413554)
			(xy 376.832588 -218.38945) (xy 376.88059 -218.372507) (xy 376.90552 -218.367356) (xy 376.92838 -218.363038)
			(xy 377.132342 -218.00947) (xy 377.124722 -217.987626) (xy 377.1161 -217.961212) (xy 377.106775 -217.906439)
			(xy 377.10618 -217.87866) (xy 377.10618 -217.878406) (xy 377.106689 -217.852439) (xy 377.114814 -217.801144)
			(xy 377.130862 -217.751751) (xy 377.15444 -217.705477) (xy 377.184966 -217.663461) (xy 377.221689 -217.626738)
			(xy 377.263705 -217.596212) (xy 377.309979 -217.572634) (xy 377.359372 -217.556586) (xy 377.410667 -217.548461)
			(xy 377.462601 -217.548461) (xy 377.513896 -217.556586) (xy 377.563289 -217.572634) (xy 377.609563 -217.596212)
			(xy 377.651579 -217.626738) (xy 377.688302 -217.663461) (xy 377.718828 -217.705477) (xy 377.742406 -217.751751)
			(xy 377.758454 -217.801144) (xy 377.766579 -217.852439) (xy 377.767088 -217.878406) (xy 377.766584 -217.903878)
			(xy 377.758764 -217.954219) (xy 377.743312 -218.002763) (xy 377.720593 -218.04836) (xy 377.691145 -218.089931)
			(xy 377.655666 -218.12649) (xy 377.614997 -218.15717) (xy 377.570101 -218.181246) (xy 377.522042 -218.198147)
			(xy 377.497086 -218.203272) (xy 377.473972 -218.20759) (xy 377.270518 -218.560396) (xy 377.278138 -218.582494)
			(xy 377.286872 -218.609083) (xy 377.296322 -218.664242) (xy 377.296934 -218.692222) (xy 378.515626 -218.692222)
			(xy 378.516059 -218.66677) (xy 378.523847 -218.616464) (xy 378.53926 -218.567949) (xy 378.561931 -218.522372)
			(xy 378.591324 -218.480811) (xy 378.626744 -218.44425) (xy 378.667352 -218.413554) (xy 378.712188 -218.38945)
			(xy 378.76019 -218.372507) (xy 378.78512 -218.367356) (xy 378.80798 -218.363038) (xy 379.011942 -218.00947)
			(xy 379.004322 -217.987626) (xy 378.9957 -217.961212) (xy 378.986375 -217.906439) (xy 378.98578 -217.87866)
			(xy 378.98578 -217.878406) (xy 378.986289 -217.852439) (xy 378.994414 -217.801144) (xy 379.010462 -217.751751)
			(xy 379.03404 -217.705477) (xy 379.064566 -217.663461) (xy 379.101289 -217.626738) (xy 379.143305 -217.596212)
			(xy 379.189579 -217.572634) (xy 379.238972 -217.556586) (xy 379.290267 -217.548461) (xy 379.342201 -217.548461)
			(xy 379.393496 -217.556586) (xy 379.442889 -217.572634) (xy 379.489163 -217.596212) (xy 379.531179 -217.626738)
			(xy 379.567902 -217.663461) (xy 379.598428 -217.705477) (xy 379.622006 -217.751751) (xy 379.638054 -217.801144)
			(xy 379.646179 -217.852439) (xy 379.646688 -217.878406) (xy 379.646184 -217.903878) (xy 379.638364 -217.954219)
			(xy 379.622912 -218.002763) (xy 379.600193 -218.04836) (xy 379.570745 -218.089931) (xy 379.535266 -218.12649)
			(xy 379.494597 -218.15717) (xy 379.449701 -218.181246) (xy 379.401642 -218.198147) (xy 379.376686 -218.203272)
			(xy 379.353572 -218.20759) (xy 379.150118 -218.560396) (xy 379.157738 -218.582494) (xy 379.166472 -218.609083)
			(xy 379.175922 -218.664242) (xy 379.176534 -218.692222) (xy 380.395226 -218.692222) (xy 380.395659 -218.66677)
			(xy 380.403447 -218.616464) (xy 380.41886 -218.567949) (xy 380.441531 -218.522372) (xy 380.470924 -218.480811)
			(xy 380.506344 -218.44425) (xy 380.546952 -218.413554) (xy 380.591788 -218.38945) (xy 380.63979 -218.372507)
			(xy 380.66472 -218.367356) (xy 380.68758 -218.363038) (xy 380.891542 -218.00947) (xy 380.883922 -217.987626)
			(xy 380.8753 -217.961212) (xy 380.865975 -217.906439) (xy 380.86538 -217.87866) (xy 380.86538 -217.878406)
			(xy 380.865889 -217.852439) (xy 380.874014 -217.801144) (xy 380.890062 -217.751751) (xy 380.91364 -217.705477)
			(xy 380.944166 -217.663461) (xy 380.980889 -217.626738) (xy 381.022905 -217.596212) (xy 381.069179 -217.572634)
			(xy 381.118572 -217.556586) (xy 381.169867 -217.548461) (xy 381.221801 -217.548461) (xy 381.273096 -217.556586)
			(xy 381.322489 -217.572634) (xy 381.368763 -217.596212) (xy 381.410779 -217.626738) (xy 381.447502 -217.663461)
			(xy 381.478028 -217.705477) (xy 381.501606 -217.751751) (xy 381.517654 -217.801144) (xy 381.525779 -217.852439)
			(xy 381.526288 -217.878406) (xy 381.525784 -217.903878) (xy 381.517964 -217.954219) (xy 381.502512 -218.002763)
			(xy 381.479793 -218.04836) (xy 381.450345 -218.089931) (xy 381.414866 -218.12649) (xy 381.374197 -218.15717)
			(xy 381.329301 -218.181246) (xy 381.281242 -218.198147) (xy 381.256286 -218.203272) (xy 381.233172 -218.20759)
			(xy 381.029718 -218.560396) (xy 381.037338 -218.582494) (xy 381.046072 -218.609083) (xy 381.055522 -218.664242)
			(xy 381.056134 -218.692222) (xy 381.055625 -218.718189) (xy 381.0475 -218.769484) (xy 381.031452 -218.818877)
			(xy 381.007874 -218.865151) (xy 380.977348 -218.907167) (xy 380.940625 -218.94389) (xy 380.898609 -218.974416)
			(xy 380.852335 -218.997994) (xy 380.802942 -219.014042) (xy 380.751647 -219.022167) (xy 380.699713 -219.022167)
			(xy 380.648418 -219.014042) (xy 380.599025 -218.997994) (xy 380.552751 -218.974416) (xy 380.510735 -218.94389)
			(xy 380.474012 -218.907167) (xy 380.443486 -218.865151) (xy 380.419908 -218.818877) (xy 380.40386 -218.769484)
			(xy 380.395735 -218.718189) (xy 380.395226 -218.692222) (xy 379.176534 -218.692222) (xy 379.176025 -218.718189)
			(xy 379.1679 -218.769484) (xy 379.151852 -218.818877) (xy 379.128274 -218.865151) (xy 379.097748 -218.907167)
			(xy 379.061025 -218.94389) (xy 379.019009 -218.974416) (xy 378.972735 -218.997994) (xy 378.923342 -219.014042)
			(xy 378.872047 -219.022167) (xy 378.820113 -219.022167) (xy 378.768818 -219.014042) (xy 378.719425 -218.997994)
			(xy 378.673151 -218.974416) (xy 378.631135 -218.94389) (xy 378.594412 -218.907167) (xy 378.563886 -218.865151)
			(xy 378.540308 -218.818877) (xy 378.52426 -218.769484) (xy 378.516135 -218.718189) (xy 378.515626 -218.692222)
			(xy 377.296934 -218.692222) (xy 377.296425 -218.718189) (xy 377.2883 -218.769484) (xy 377.272252 -218.818877)
			(xy 377.248674 -218.865151) (xy 377.218148 -218.907167) (xy 377.181425 -218.94389) (xy 377.139409 -218.974416)
			(xy 377.093135 -218.997994) (xy 377.043742 -219.014042) (xy 376.992447 -219.022167) (xy 376.940513 -219.022167)
			(xy 376.889218 -219.014042) (xy 376.839825 -218.997994) (xy 376.793551 -218.974416) (xy 376.751535 -218.94389)
			(xy 376.714812 -218.907167) (xy 376.684286 -218.865151) (xy 376.660708 -218.818877) (xy 376.64466 -218.769484)
			(xy 376.636535 -218.718189) (xy 376.636026 -218.692222) (xy 375.417334 -218.692222) (xy 375.416867 -218.71731)
			(xy 375.409282 -218.76691) (xy 375.39429 -218.814795) (xy 375.372234 -218.859864) (xy 375.343622 -218.901083)
			(xy 375.30911 -218.937505) (xy 375.26949 -218.968295) (xy 375.225674 -218.992745) (xy 375.178666 -219.010293)
			(xy 375.15419 -219.015818) (xy 375.113804 -219.0242) (xy 375.113804 -219.532005) (xy 375.227089 -219.532005)
			(xy 375.227089 -219.480071) (xy 375.235214 -219.428776) (xy 375.251262 -219.379383) (xy 375.27484 -219.333109)
			(xy 375.305366 -219.291093) (xy 375.342089 -219.25437) (xy 375.384105 -219.223844) (xy 375.430379 -219.200266)
			(xy 375.479772 -219.184218) (xy 375.531067 -219.176093) (xy 375.583001 -219.176093) (xy 375.634296 -219.184218)
			(xy 375.683689 -219.200266) (xy 375.729963 -219.223844) (xy 375.771979 -219.25437) (xy 375.808702 -219.291093)
			(xy 375.839228 -219.333109) (xy 375.862806 -219.379383) (xy 375.878854 -219.428776) (xy 375.886979 -219.480071)
			(xy 375.887488 -219.506038) (xy 375.886979 -219.532005) (xy 376.166889 -219.532005) (xy 376.166889 -219.480071)
			(xy 376.175014 -219.428776) (xy 376.191062 -219.379383) (xy 376.21464 -219.333109) (xy 376.245166 -219.291093)
			(xy 376.281889 -219.25437) (xy 376.323905 -219.223844) (xy 376.370179 -219.200266) (xy 376.419572 -219.184218)
			(xy 376.470867 -219.176093) (xy 376.522801 -219.176093) (xy 376.574096 -219.184218) (xy 376.623489 -219.200266)
			(xy 376.669763 -219.223844) (xy 376.711779 -219.25437) (xy 376.748502 -219.291093) (xy 376.779028 -219.333109)
			(xy 376.802606 -219.379383) (xy 376.818654 -219.428776) (xy 376.826779 -219.480071) (xy 376.827288 -219.506038)
			(xy 376.826779 -219.532005) (xy 377.106689 -219.532005) (xy 377.106689 -219.480071) (xy 377.114814 -219.428776)
			(xy 377.130862 -219.379383) (xy 377.15444 -219.333109) (xy 377.184966 -219.291093) (xy 377.221689 -219.25437)
			(xy 377.263705 -219.223844) (xy 377.309979 -219.200266) (xy 377.359372 -219.184218) (xy 377.410667 -219.176093)
			(xy 377.462601 -219.176093) (xy 377.513896 -219.184218) (xy 377.563289 -219.200266) (xy 377.609563 -219.223844)
			(xy 377.651579 -219.25437) (xy 377.688302 -219.291093) (xy 377.718828 -219.333109) (xy 377.742406 -219.379383)
			(xy 377.758454 -219.428776) (xy 377.766579 -219.480071) (xy 377.767088 -219.506038) (xy 377.766579 -219.532005)
			(xy 378.046489 -219.532005) (xy 378.046489 -219.480071) (xy 378.054614 -219.428776) (xy 378.070662 -219.379383)
			(xy 378.09424 -219.333109) (xy 378.124766 -219.291093) (xy 378.161489 -219.25437) (xy 378.203505 -219.223844)
			(xy 378.249779 -219.200266) (xy 378.299172 -219.184218) (xy 378.350467 -219.176093) (xy 378.402401 -219.176093)
			(xy 378.453696 -219.184218) (xy 378.503089 -219.200266) (xy 378.549363 -219.223844) (xy 378.591379 -219.25437)
			(xy 378.628102 -219.291093) (xy 378.658628 -219.333109) (xy 378.682206 -219.379383) (xy 378.698254 -219.428776)
			(xy 378.706379 -219.480071) (xy 378.706888 -219.506038) (xy 378.706379 -219.532005) (xy 378.986289 -219.532005)
			(xy 378.986289 -219.480071) (xy 378.994414 -219.428776) (xy 379.010462 -219.379383) (xy 379.03404 -219.333109)
			(xy 379.064566 -219.291093) (xy 379.101289 -219.25437) (xy 379.143305 -219.223844) (xy 379.189579 -219.200266)
			(xy 379.238972 -219.184218) (xy 379.290267 -219.176093) (xy 379.342201 -219.176093) (xy 379.393496 -219.184218)
			(xy 379.442889 -219.200266) (xy 379.489163 -219.223844) (xy 379.531179 -219.25437) (xy 379.567902 -219.291093)
			(xy 379.598428 -219.333109) (xy 379.622006 -219.379383) (xy 379.638054 -219.428776) (xy 379.646179 -219.480071)
			(xy 379.646688 -219.506038) (xy 379.646179 -219.532005) (xy 379.926089 -219.532005) (xy 379.926089 -219.480071)
			(xy 379.934214 -219.428776) (xy 379.950262 -219.379383) (xy 379.97384 -219.333109) (xy 380.004366 -219.291093)
			(xy 380.041089 -219.25437) (xy 380.083105 -219.223844) (xy 380.129379 -219.200266) (xy 380.178772 -219.184218)
			(xy 380.230067 -219.176093) (xy 380.282001 -219.176093) (xy 380.333296 -219.184218) (xy 380.382689 -219.200266)
			(xy 380.428963 -219.223844) (xy 380.470979 -219.25437) (xy 380.507702 -219.291093) (xy 380.538228 -219.333109)
			(xy 380.561806 -219.379383) (xy 380.577854 -219.428776) (xy 380.585979 -219.480071) (xy 380.586488 -219.506038)
			(xy 380.585979 -219.532005) (xy 380.865889 -219.532005) (xy 380.865889 -219.480071) (xy 380.874014 -219.428776)
			(xy 380.890062 -219.379383) (xy 380.91364 -219.333109) (xy 380.944166 -219.291093) (xy 380.980889 -219.25437)
			(xy 381.022905 -219.223844) (xy 381.069179 -219.200266) (xy 381.118572 -219.184218) (xy 381.169867 -219.176093)
			(xy 381.221801 -219.176093) (xy 381.273096 -219.184218) (xy 381.322489 -219.200266) (xy 381.368763 -219.223844)
			(xy 381.410779 -219.25437) (xy 381.447502 -219.291093) (xy 381.478028 -219.333109) (xy 381.501606 -219.379383)
			(xy 381.517654 -219.428776) (xy 381.525779 -219.480071) (xy 381.526288 -219.506038) (xy 381.525779 -219.532005)
			(xy 381.517654 -219.5833) (xy 381.501606 -219.632693) (xy 381.478028 -219.678967) (xy 381.447502 -219.720983)
			(xy 381.410779 -219.757706) (xy 381.368763 -219.788232) (xy 381.322489 -219.81181) (xy 381.273096 -219.827858)
			(xy 381.221801 -219.835983) (xy 381.169867 -219.835983) (xy 381.118572 -219.827858) (xy 381.069179 -219.81181)
			(xy 381.022905 -219.788232) (xy 380.980889 -219.757706) (xy 380.944166 -219.720983) (xy 380.91364 -219.678967)
			(xy 380.890062 -219.632693) (xy 380.874014 -219.5833) (xy 380.865889 -219.532005) (xy 380.585979 -219.532005)
			(xy 380.577854 -219.5833) (xy 380.561806 -219.632693) (xy 380.538228 -219.678967) (xy 380.507702 -219.720983)
			(xy 380.470979 -219.757706) (xy 380.428963 -219.788232) (xy 380.382689 -219.81181) (xy 380.333296 -219.827858)
			(xy 380.282001 -219.835983) (xy 380.230067 -219.835983) (xy 380.178772 -219.827858) (xy 380.129379 -219.81181)
			(xy 380.083105 -219.788232) (xy 380.041089 -219.757706) (xy 380.004366 -219.720983) (xy 379.97384 -219.678967)
			(xy 379.950262 -219.632693) (xy 379.934214 -219.5833) (xy 379.926089 -219.532005) (xy 379.646179 -219.532005)
			(xy 379.638054 -219.5833) (xy 379.622006 -219.632693) (xy 379.598428 -219.678967) (xy 379.567902 -219.720983)
			(xy 379.531179 -219.757706) (xy 379.489163 -219.788232) (xy 379.442889 -219.81181) (xy 379.393496 -219.827858)
			(xy 379.342201 -219.835983) (xy 379.290267 -219.835983) (xy 379.238972 -219.827858) (xy 379.189579 -219.81181)
			(xy 379.143305 -219.788232) (xy 379.101289 -219.757706) (xy 379.064566 -219.720983) (xy 379.03404 -219.678967)
			(xy 379.010462 -219.632693) (xy 378.994414 -219.5833) (xy 378.986289 -219.532005) (xy 378.706379 -219.532005)
			(xy 378.698254 -219.5833) (xy 378.682206 -219.632693) (xy 378.658628 -219.678967) (xy 378.628102 -219.720983)
			(xy 378.591379 -219.757706) (xy 378.549363 -219.788232) (xy 378.503089 -219.81181) (xy 378.453696 -219.827858)
			(xy 378.402401 -219.835983) (xy 378.350467 -219.835983) (xy 378.299172 -219.827858) (xy 378.249779 -219.81181)
			(xy 378.203505 -219.788232) (xy 378.161489 -219.757706) (xy 378.124766 -219.720983) (xy 378.09424 -219.678967)
			(xy 378.070662 -219.632693) (xy 378.054614 -219.5833) (xy 378.046489 -219.532005) (xy 377.766579 -219.532005)
			(xy 377.758454 -219.5833) (xy 377.742406 -219.632693) (xy 377.718828 -219.678967) (xy 377.688302 -219.720983)
			(xy 377.651579 -219.757706) (xy 377.609563 -219.788232) (xy 377.563289 -219.81181) (xy 377.513896 -219.827858)
			(xy 377.462601 -219.835983) (xy 377.410667 -219.835983) (xy 377.359372 -219.827858) (xy 377.309979 -219.81181)
			(xy 377.263705 -219.788232) (xy 377.221689 -219.757706) (xy 377.184966 -219.720983) (xy 377.15444 -219.678967)
			(xy 377.130862 -219.632693) (xy 377.114814 -219.5833) (xy 377.106689 -219.532005) (xy 376.826779 -219.532005)
			(xy 376.818654 -219.5833) (xy 376.802606 -219.632693) (xy 376.779028 -219.678967) (xy 376.748502 -219.720983)
			(xy 376.711779 -219.757706) (xy 376.669763 -219.788232) (xy 376.623489 -219.81181) (xy 376.574096 -219.827858)
			(xy 376.522801 -219.835983) (xy 376.470867 -219.835983) (xy 376.419572 -219.827858) (xy 376.370179 -219.81181)
			(xy 376.323905 -219.788232) (xy 376.281889 -219.757706) (xy 376.245166 -219.720983) (xy 376.21464 -219.678967)
			(xy 376.191062 -219.632693) (xy 376.175014 -219.5833) (xy 376.166889 -219.532005) (xy 375.886979 -219.532005)
			(xy 375.878854 -219.5833) (xy 375.862806 -219.632693) (xy 375.839228 -219.678967) (xy 375.808702 -219.720983)
			(xy 375.771979 -219.757706) (xy 375.729963 -219.788232) (xy 375.683689 -219.81181) (xy 375.634296 -219.827858)
			(xy 375.583001 -219.835983) (xy 375.531067 -219.835983) (xy 375.479772 -219.827858) (xy 375.430379 -219.81181)
			(xy 375.384105 -219.788232) (xy 375.342089 -219.757706) (xy 375.305366 -219.720983) (xy 375.27484 -219.678967)
			(xy 375.251262 -219.632693) (xy 375.235214 -219.5833) (xy 375.227089 -219.532005) (xy 375.113804 -219.532005)
			(xy 375.113804 -219.987876) (xy 375.15419 -219.996258) (xy 375.178675 -220.00181) (xy 375.225728 -220.019319)
			(xy 375.269593 -220.043742) (xy 375.309259 -220.074517) (xy 375.343814 -220.110938) (xy 375.372464 -220.152166)
			(xy 375.394549 -220.197253) (xy 375.409561 -220.245161) (xy 375.417155 -220.294788) (xy 375.417156 -220.319854)
			(xy 375.696226 -220.319854) (xy 375.696735 -220.293887) (xy 375.70486 -220.242592) (xy 375.720908 -220.193199)
			(xy 375.744486 -220.146925) (xy 375.775012 -220.104909) (xy 375.811735 -220.068186) (xy 375.853751 -220.03766)
			(xy 375.900025 -220.014082) (xy 375.949418 -219.998034) (xy 376.000713 -219.989909) (xy 376.052647 -219.989909)
			(xy 376.103942 -219.998034) (xy 376.153335 -220.014082) (xy 376.199609 -220.03766) (xy 376.241625 -220.068186)
			(xy 376.278348 -220.104909) (xy 376.308874 -220.146925) (xy 376.332452 -220.193199) (xy 376.3485 -220.242592)
			(xy 376.356625 -220.293887) (xy 376.357134 -220.319854) (xy 376.357134 -220.320616) (xy 376.356606 -220.345821)
			(xy 376.636789 -220.345821) (xy 376.636789 -220.293887) (xy 376.644914 -220.242592) (xy 376.660962 -220.193199)
			(xy 376.68454 -220.146925) (xy 376.715066 -220.104909) (xy 376.751789 -220.068186) (xy 376.793805 -220.03766)
			(xy 376.840079 -220.014082) (xy 376.889472 -219.998034) (xy 376.940767 -219.989909) (xy 376.992701 -219.989909)
			(xy 377.043996 -219.998034) (xy 377.093389 -220.014082) (xy 377.139663 -220.03766) (xy 377.181679 -220.068186)
			(xy 377.218402 -220.104909) (xy 377.248928 -220.146925) (xy 377.272506 -220.193199) (xy 377.288554 -220.242592)
			(xy 377.296679 -220.293887) (xy 377.297188 -220.319854) (xy 377.575826 -220.319854) (xy 377.576335 -220.293887)
			(xy 377.58446 -220.242592) (xy 377.600508 -220.193199) (xy 377.624086 -220.146925) (xy 377.654612 -220.104909)
			(xy 377.691335 -220.068186) (xy 377.733351 -220.03766) (xy 377.779625 -220.014082) (xy 377.829018 -219.998034)
			(xy 377.880313 -219.989909) (xy 377.932247 -219.989909) (xy 377.983542 -219.998034) (xy 378.032935 -220.014082)
			(xy 378.079209 -220.03766) (xy 378.121225 -220.068186) (xy 378.157948 -220.104909) (xy 378.188474 -220.146925)
			(xy 378.212052 -220.193199) (xy 378.2281 -220.242592) (xy 378.236225 -220.293887) (xy 378.236734 -220.319854)
			(xy 378.236734 -220.320616) (xy 378.236206 -220.345821) (xy 378.516389 -220.345821) (xy 378.516389 -220.293887)
			(xy 378.524514 -220.242592) (xy 378.540562 -220.193199) (xy 378.56414 -220.146925) (xy 378.594666 -220.104909)
			(xy 378.631389 -220.068186) (xy 378.673405 -220.03766) (xy 378.719679 -220.014082) (xy 378.769072 -219.998034)
			(xy 378.820367 -219.989909) (xy 378.872301 -219.989909) (xy 378.923596 -219.998034) (xy 378.972989 -220.014082)
			(xy 379.019263 -220.03766) (xy 379.061279 -220.068186) (xy 379.098002 -220.104909) (xy 379.128528 -220.146925)
			(xy 379.152106 -220.193199) (xy 379.168154 -220.242592) (xy 379.176279 -220.293887) (xy 379.176788 -220.319854)
			(xy 379.455426 -220.319854) (xy 379.455935 -220.293887) (xy 379.46406 -220.242592) (xy 379.480108 -220.193199)
			(xy 379.503686 -220.146925) (xy 379.534212 -220.104909) (xy 379.570935 -220.068186) (xy 379.612951 -220.03766)
			(xy 379.659225 -220.014082) (xy 379.708618 -219.998034) (xy 379.759913 -219.989909) (xy 379.811847 -219.989909)
			(xy 379.863142 -219.998034) (xy 379.912535 -220.014082) (xy 379.958809 -220.03766) (xy 380.000825 -220.068186)
			(xy 380.037548 -220.104909) (xy 380.068074 -220.146925) (xy 380.091652 -220.193199) (xy 380.1077 -220.242592)
			(xy 380.115825 -220.293887) (xy 380.116334 -220.319854) (xy 380.116334 -220.320616) (xy 380.115806 -220.345821)
			(xy 380.395989 -220.345821) (xy 380.395989 -220.293887) (xy 380.404114 -220.242592) (xy 380.420162 -220.193199)
			(xy 380.44374 -220.146925) (xy 380.474266 -220.104909) (xy 380.510989 -220.068186) (xy 380.553005 -220.03766)
			(xy 380.599279 -220.014082) (xy 380.648672 -219.998034) (xy 380.699967 -219.989909) (xy 380.751901 -219.989909)
			(xy 380.803196 -219.998034) (xy 380.852589 -220.014082) (xy 380.898863 -220.03766) (xy 380.940879 -220.068186)
			(xy 380.977602 -220.104909) (xy 381.008128 -220.146925) (xy 381.031706 -220.193199) (xy 381.047754 -220.242592)
			(xy 381.055879 -220.293887) (xy 381.056388 -220.319854) (xy 381.055879 -220.345821) (xy 381.047754 -220.397116)
			(xy 381.031706 -220.446509) (xy 381.008128 -220.492783) (xy 380.977602 -220.534799) (xy 380.940879 -220.571522)
			(xy 380.898863 -220.602048) (xy 380.852589 -220.625626) (xy 380.803196 -220.641674) (xy 380.751901 -220.649799)
			(xy 380.699967 -220.649799) (xy 380.648672 -220.641674) (xy 380.599279 -220.625626) (xy 380.553005 -220.602048)
			(xy 380.510989 -220.571522) (xy 380.474266 -220.534799) (xy 380.44374 -220.492783) (xy 380.420162 -220.446509)
			(xy 380.404114 -220.397116) (xy 380.395989 -220.345821) (xy 380.115806 -220.345821) (xy 380.115753 -220.348334)
			(xy 380.106424 -220.402981) (xy 380.097792 -220.429328) (xy 380.089918 -220.451172) (xy 380.294134 -220.80474)
			(xy 380.316994 -220.809058) (xy 380.341907 -220.814267) (xy 380.38989 -220.831224) (xy 380.434708 -220.855335)
			(xy 380.475302 -220.886029) (xy 380.510712 -220.922582) (xy 380.540102 -220.96413) (xy 380.562778 -221.009691)
			(xy 380.578203 -221.058189) (xy 380.586014 -221.108478) (xy 380.586488 -221.133924) (xy 380.585979 -221.159891)
			(xy 380.577854 -221.211186) (xy 380.561806 -221.260579) (xy 380.538228 -221.306853) (xy 380.507702 -221.348869)
			(xy 380.470979 -221.385592) (xy 380.428963 -221.416118) (xy 380.382689 -221.439696) (xy 380.333296 -221.455744)
			(xy 380.282001 -221.463869) (xy 380.230067 -221.463869) (xy 380.178772 -221.455744) (xy 380.129379 -221.439696)
			(xy 380.083105 -221.416118) (xy 380.041089 -221.385592) (xy 380.004366 -221.348869) (xy 379.97384 -221.306853)
			(xy 379.950262 -221.260579) (xy 379.934214 -221.211186) (xy 379.926089 -221.159891) (xy 379.92558 -221.133924)
			(xy 379.92614 -221.105938) (xy 379.935585 -221.050771) (xy 379.944376 -221.024196) (xy 379.951996 -221.002098)
			(xy 379.748288 -220.649038) (xy 379.725174 -220.64472) (xy 379.700233 -220.639583) (xy 379.65221 -220.622649)
			(xy 379.607352 -220.598551) (xy 379.56672 -220.567859) (xy 379.531275 -220.5313) (xy 379.501855 -220.489738)
			(xy 379.479156 -220.444156) (xy 379.463716 -220.395632) (xy 379.4559 -220.345314) (xy 379.455426 -220.319854)
			(xy 379.176788 -220.319854) (xy 379.176279 -220.345821) (xy 379.168154 -220.397116) (xy 379.152106 -220.446509)
			(xy 379.128528 -220.492783) (xy 379.098002 -220.534799) (xy 379.061279 -220.571522) (xy 379.019263 -220.602048)
			(xy 378.972989 -220.625626) (xy 378.923596 -220.641674) (xy 378.872301 -220.649799) (xy 378.820367 -220.649799)
			(xy 378.769072 -220.641674) (xy 378.719679 -220.625626) (xy 378.673405 -220.602048) (xy 378.631389 -220.571522)
			(xy 378.594666 -220.534799) (xy 378.56414 -220.492783) (xy 378.540562 -220.446509) (xy 378.524514 -220.397116)
			(xy 378.516389 -220.345821) (xy 378.236206 -220.345821) (xy 378.236153 -220.348334) (xy 378.226824 -220.402981)
			(xy 378.218192 -220.429328) (xy 378.210318 -220.451172) (xy 378.414534 -220.80474) (xy 378.437394 -220.809058)
			(xy 378.462307 -220.814267) (xy 378.51029 -220.831224) (xy 378.555108 -220.855335) (xy 378.595702 -220.886029)
			(xy 378.631112 -220.922582) (xy 378.660502 -220.96413) (xy 378.683178 -221.009691) (xy 378.698603 -221.058189)
			(xy 378.706414 -221.108478) (xy 378.706888 -221.133924) (xy 378.706379 -221.159891) (xy 378.698254 -221.211186)
			(xy 378.682206 -221.260579) (xy 378.658628 -221.306853) (xy 378.628102 -221.348869) (xy 378.591379 -221.385592)
			(xy 378.549363 -221.416118) (xy 378.503089 -221.439696) (xy 378.453696 -221.455744) (xy 378.402401 -221.463869)
			(xy 378.350467 -221.463869) (xy 378.299172 -221.455744) (xy 378.249779 -221.439696) (xy 378.203505 -221.416118)
			(xy 378.161489 -221.385592) (xy 378.124766 -221.348869) (xy 378.09424 -221.306853) (xy 378.070662 -221.260579)
			(xy 378.054614 -221.211186) (xy 378.046489 -221.159891) (xy 378.04598 -221.133924) (xy 378.04654 -221.105938)
			(xy 378.055985 -221.050771) (xy 378.064776 -221.024196) (xy 378.072396 -221.002098) (xy 377.868688 -220.649038)
			(xy 377.845574 -220.64472) (xy 377.820633 -220.639583) (xy 377.77261 -220.622649) (xy 377.727752 -220.598551)
			(xy 377.68712 -220.567859) (xy 377.651675 -220.5313) (xy 377.622255 -220.489738) (xy 377.599556 -220.444156)
			(xy 377.584116 -220.395632) (xy 377.5763 -220.345314) (xy 377.575826 -220.319854) (xy 377.297188 -220.319854)
			(xy 377.296679 -220.345821) (xy 377.288554 -220.397116) (xy 377.272506 -220.446509) (xy 377.248928 -220.492783)
			(xy 377.218402 -220.534799) (xy 377.181679 -220.571522) (xy 377.139663 -220.602048) (xy 377.093389 -220.625626)
			(xy 377.043996 -220.641674) (xy 376.992701 -220.649799) (xy 376.940767 -220.649799) (xy 376.889472 -220.641674)
			(xy 376.840079 -220.625626) (xy 376.793805 -220.602048) (xy 376.751789 -220.571522) (xy 376.715066 -220.534799)
			(xy 376.68454 -220.492783) (xy 376.660962 -220.446509) (xy 376.644914 -220.397116) (xy 376.636789 -220.345821)
			(xy 376.356606 -220.345821) (xy 376.356553 -220.348334) (xy 376.347224 -220.402981) (xy 376.338592 -220.429328)
			(xy 376.330718 -220.451172) (xy 376.534934 -220.80474) (xy 376.557794 -220.809058) (xy 376.582707 -220.814267)
			(xy 376.63069 -220.831224) (xy 376.675508 -220.855335) (xy 376.716102 -220.886029) (xy 376.751512 -220.922582)
			(xy 376.780902 -220.96413) (xy 376.803578 -221.009691) (xy 376.819003 -221.058189) (xy 376.826814 -221.108478)
			(xy 376.827288 -221.133924) (xy 376.826779 -221.159891) (xy 376.818654 -221.211186) (xy 376.802606 -221.260579)
			(xy 376.779028 -221.306853) (xy 376.748502 -221.348869) (xy 376.711779 -221.385592) (xy 376.669763 -221.416118)
			(xy 376.623489 -221.439696) (xy 376.574096 -221.455744) (xy 376.522801 -221.463869) (xy 376.470867 -221.463869)
			(xy 376.419572 -221.455744) (xy 376.370179 -221.439696) (xy 376.323905 -221.416118) (xy 376.281889 -221.385592)
			(xy 376.245166 -221.348869) (xy 376.21464 -221.306853) (xy 376.191062 -221.260579) (xy 376.175014 -221.211186)
			(xy 376.166889 -221.159891) (xy 376.16638 -221.133924) (xy 376.16694 -221.105938) (xy 376.176385 -221.050771)
			(xy 376.185176 -221.024196) (xy 376.192796 -221.002098) (xy 375.989088 -220.649038) (xy 375.965974 -220.64472)
			(xy 375.941033 -220.639583) (xy 375.89301 -220.622649) (xy 375.848152 -220.598551) (xy 375.80752 -220.567859)
			(xy 375.772075 -220.5313) (xy 375.742655 -220.489738) (xy 375.719956 -220.444156) (xy 375.704516 -220.395632)
			(xy 375.6967 -220.345314) (xy 375.696226 -220.319854) (xy 375.417156 -220.319854) (xy 375.417157 -220.344993)
			(xy 375.409565 -220.394621) (xy 375.394556 -220.44253) (xy 375.372473 -220.487618) (xy 375.343826 -220.528847)
			(xy 375.309272 -220.56527) (xy 375.269608 -220.596048) (xy 375.225745 -220.620474) (xy 375.178693 -220.637984)
			(xy 375.15419 -220.64345) (xy 375.113804 -220.651832) (xy 375.113804 -221.316296) (xy 375.1142 -221.325831)
			(xy 375.121164 -221.343583) (xy 375.134133 -221.357565) (xy 375.151312 -221.365843) (xy 375.170328 -221.367273)
			(xy 375.188553 -221.361657) (xy 375.203466 -221.349773) (xy 375.208546 -221.341696) (xy 375.252742 -221.264988)
			(xy 375.245122 -221.243144) (xy 375.23648 -221.216735) (xy 375.227165 -221.161959) (xy 375.22658 -221.134178)
			(xy 375.22658 -221.133924) (xy 375.227089 -221.107957) (xy 375.235214 -221.056662) (xy 375.251262 -221.007269)
			(xy 375.27484 -220.960995) (xy 375.305366 -220.918979) (xy 375.342089 -220.882256) (xy 375.384105 -220.85173)
			(xy 375.430379 -220.828152) (xy 375.479772 -220.812104) (xy 375.531067 -220.803979) (xy 375.583001 -220.803979)
			(xy 375.634296 -220.812104) (xy 375.683689 -220.828152) (xy 375.729963 -220.85173) (xy 375.771979 -220.882256)
			(xy 375.808702 -220.918979) (xy 375.839228 -220.960995) (xy 375.862806 -221.007269) (xy 375.878854 -221.056662)
			(xy 375.886979 -221.107957) (xy 375.887488 -221.133924) (xy 375.887015 -221.159396) (xy 375.879192 -221.209734)
			(xy 375.863735 -221.258276) (xy 375.84101 -221.303869) (xy 375.811555 -221.345434) (xy 375.77607 -221.381985)
			(xy 375.735395 -221.412657) (xy 375.690493 -221.436721) (xy 375.642431 -221.453607) (xy 375.617486 -221.45879)
			(xy 375.594372 -221.463108) (xy 375.390918 -221.815914) (xy 375.398538 -221.838012) (xy 375.40733 -221.864586)
			(xy 375.416775 -221.919754) (xy 375.417334 -221.94774) (xy 376.636026 -221.94774) (xy 376.636475 -221.922288)
			(xy 376.644261 -221.871984) (xy 376.659671 -221.823469) (xy 376.68234 -221.777892) (xy 376.711731 -221.73633)
			(xy 376.747149 -221.699769) (xy 376.787755 -221.669073) (xy 376.83259 -221.644968) (xy 376.880591 -221.628025)
			(xy 376.90552 -221.622874) (xy 376.92838 -221.618556) (xy 377.132342 -221.264988) (xy 377.124722 -221.243144)
			(xy 377.116104 -221.216728) (xy 377.106777 -221.161957) (xy 377.10618 -221.134178) (xy 377.10618 -221.133924)
			(xy 377.106689 -221.107957) (xy 377.114814 -221.056662) (xy 377.130862 -221.007269) (xy 377.15444 -220.960995)
			(xy 377.184966 -220.918979) (xy 377.221689 -220.882256) (xy 377.263705 -220.85173) (xy 377.309979 -220.828152)
			(xy 377.359372 -220.812104) (xy 377.410667 -220.803979) (xy 377.462601 -220.803979) (xy 377.513896 -220.812104)
			(xy 377.563289 -220.828152) (xy 377.609563 -220.85173) (xy 377.651579 -220.882256) (xy 377.688302 -220.918979)
			(xy 377.718828 -220.960995) (xy 377.742406 -221.007269) (xy 377.758454 -221.056662) (xy 377.766579 -221.107957)
			(xy 377.767088 -221.133924) (xy 377.7666 -221.159397) (xy 377.758778 -221.209738) (xy 377.743323 -221.258282)
			(xy 377.720602 -221.30388) (xy 377.691152 -221.34545) (xy 377.655671 -221.382009) (xy 377.615 -221.412689)
			(xy 377.570103 -221.436765) (xy 377.522042 -221.453665) (xy 377.497086 -221.45879) (xy 377.473972 -221.463108)
			(xy 377.270518 -221.815914) (xy 377.278138 -221.838012) (xy 377.286877 -221.8646) (xy 377.296324 -221.919759)
			(xy 377.296934 -221.94774) (xy 378.515626 -221.94774) (xy 378.516075 -221.922288) (xy 378.523861 -221.871984)
			(xy 378.539271 -221.823469) (xy 378.56194 -221.777892) (xy 378.591331 -221.73633) (xy 378.626749 -221.699769)
			(xy 378.667355 -221.669073) (xy 378.71219 -221.644968) (xy 378.760191 -221.628025) (xy 378.78512 -221.622874)
			(xy 378.80798 -221.618556) (xy 379.011942 -221.264988) (xy 379.004322 -221.243144) (xy 378.995704 -221.216728)
			(xy 378.986377 -221.161957) (xy 378.98578 -221.134178) (xy 378.98578 -221.133924) (xy 378.986289 -221.107957)
			(xy 378.994414 -221.056662) (xy 379.010462 -221.007269) (xy 379.03404 -220.960995) (xy 379.064566 -220.918979)
			(xy 379.101289 -220.882256) (xy 379.143305 -220.85173) (xy 379.189579 -220.828152) (xy 379.238972 -220.812104)
			(xy 379.290267 -220.803979) (xy 379.342201 -220.803979) (xy 379.393496 -220.812104) (xy 379.442889 -220.828152)
			(xy 379.489163 -220.85173) (xy 379.531179 -220.882256) (xy 379.567902 -220.918979) (xy 379.598428 -220.960995)
			(xy 379.622006 -221.007269) (xy 379.638054 -221.056662) (xy 379.646179 -221.107957) (xy 379.646688 -221.133924)
			(xy 379.6462 -221.159397) (xy 379.638378 -221.209738) (xy 379.622923 -221.258282) (xy 379.600202 -221.30388)
			(xy 379.570752 -221.34545) (xy 379.535271 -221.382009) (xy 379.4946 -221.412689) (xy 379.449703 -221.436765)
			(xy 379.401642 -221.453665) (xy 379.376686 -221.45879) (xy 379.353572 -221.463108) (xy 379.150118 -221.815914)
			(xy 379.157738 -221.838012) (xy 379.166477 -221.8646) (xy 379.175924 -221.919759) (xy 379.176534 -221.94774)
			(xy 380.394972 -221.94774) (xy 380.395383 -221.922253) (xy 380.403198 -221.871882) (xy 380.418651 -221.823307)
			(xy 380.441375 -221.777679) (xy 380.470831 -221.736078) (xy 380.506322 -221.69949) (xy 380.547008 -221.668781)
			(xy 380.591923 -221.644679) (xy 380.640005 -221.627755) (xy 380.664974 -221.62262) (xy 380.687834 -221.618302)
			(xy 380.891542 -221.264988) (xy 380.883922 -221.24289) (xy 380.875291 -221.216478) (xy 380.865972 -221.161704)
			(xy 380.86538 -221.133924) (xy 380.865889 -221.107957) (xy 380.874014 -221.056662) (xy 380.890062 -221.007269)
			(xy 380.91364 -220.960995) (xy 380.944166 -220.918979) (xy 380.980889 -220.882256) (xy 381.022905 -220.85173)
			(xy 381.069179 -220.828152) (xy 381.118572 -220.812104) (xy 381.169867 -220.803979) (xy 381.221801 -220.803979)
			(xy 381.273096 -220.812104) (xy 381.322489 -220.828152) (xy 381.368763 -220.85173) (xy 381.410779 -220.882256)
			(xy 381.447502 -220.918979) (xy 381.478028 -220.960995) (xy 381.501606 -221.007269) (xy 381.517654 -221.056662)
			(xy 381.525779 -221.107957) (xy 381.526288 -221.133924) (xy 381.5258 -221.159397) (xy 381.517978 -221.209738)
			(xy 381.502523 -221.258282) (xy 381.479802 -221.30388) (xy 381.450352 -221.34545) (xy 381.414871 -221.382009)
			(xy 381.3742 -221.412689) (xy 381.329303 -221.436765) (xy 381.281242 -221.453665) (xy 381.256286 -221.45879)
			(xy 381.233172 -221.463108) (xy 381.029718 -221.81566) (xy 381.037592 -221.837758) (xy 381.046334 -221.864345)
			(xy 381.05578 -221.919505) (xy 381.056388 -221.947486) (xy 381.056388 -221.94774) (xy 381.055878 -221.973727)
			(xy 381.047748 -222.025062) (xy 381.031687 -222.074492) (xy 381.008091 -222.120802) (xy 380.977541 -222.16285)
			(xy 380.94079 -222.199601) (xy 380.898742 -222.230151) (xy 380.852432 -222.253747) (xy 380.803002 -222.269808)
			(xy 380.751667 -222.277938) (xy 380.699693 -222.277938) (xy 380.648358 -222.269808) (xy 380.598928 -222.253747)
			(xy 380.552618 -222.230151) (xy 380.51057 -222.199601) (xy 380.473819 -222.16285) (xy 380.443269 -222.120802)
			(xy 380.419673 -222.074492) (xy 380.403612 -222.025062) (xy 380.395482 -221.973727) (xy 380.394972 -221.94774)
			(xy 379.176534 -221.94774) (xy 379.176025 -221.973707) (xy 379.1679 -222.025002) (xy 379.151852 -222.074395)
			(xy 379.128274 -222.120669) (xy 379.097748 -222.162685) (xy 379.061025 -222.199408) (xy 379.019009 -222.229934)
			(xy 378.972735 -222.253512) (xy 378.923342 -222.26956) (xy 378.872047 -222.277685) (xy 378.820113 -222.277685)
			(xy 378.768818 -222.26956) (xy 378.719425 -222.253512) (xy 378.673151 -222.229934) (xy 378.631135 -222.199408)
			(xy 378.594412 -222.162685) (xy 378.563886 -222.120669) (xy 378.540308 -222.074395) (xy 378.52426 -222.025002)
			(xy 378.516135 -221.973707) (xy 378.515626 -221.94774) (xy 377.296934 -221.94774) (xy 377.296425 -221.973707)
			(xy 377.2883 -222.025002) (xy 377.272252 -222.074395) (xy 377.248674 -222.120669) (xy 377.218148 -222.162685)
			(xy 377.181425 -222.199408) (xy 377.139409 -222.229934) (xy 377.093135 -222.253512) (xy 377.043742 -222.26956)
			(xy 376.992447 -222.277685) (xy 376.940513 -222.277685) (xy 376.889218 -222.26956) (xy 376.839825 -222.253512)
			(xy 376.793551 -222.229934) (xy 376.751535 -222.199408) (xy 376.714812 -222.162685) (xy 376.684286 -222.120669)
			(xy 376.660708 -222.074395) (xy 376.64466 -222.025002) (xy 376.636535 -221.973707) (xy 376.636026 -221.94774)
			(xy 375.417334 -221.94774) (xy 375.416866 -221.972827) (xy 375.409279 -222.022425) (xy 375.394284 -222.070308)
			(xy 375.372228 -222.115374) (xy 375.343615 -222.156591) (xy 375.309103 -222.193012) (xy 375.269484 -222.223799)
			(xy 375.225668 -222.248247) (xy 375.178661 -222.265794) (xy 375.15419 -222.271336) (xy 375.113804 -222.279718)
			(xy 375.113804 -222.787523) (xy 375.227089 -222.787523) (xy 375.227089 -222.735589) (xy 375.235214 -222.684294)
			(xy 375.251262 -222.634901) (xy 375.27484 -222.588627) (xy 375.305366 -222.546611) (xy 375.342089 -222.509888)
			(xy 375.384105 -222.479362) (xy 375.430379 -222.455784) (xy 375.479772 -222.439736) (xy 375.531067 -222.431611)
			(xy 375.583001 -222.431611) (xy 375.634296 -222.439736) (xy 375.683689 -222.455784) (xy 375.729963 -222.479362)
			(xy 375.771979 -222.509888) (xy 375.808702 -222.546611) (xy 375.839228 -222.588627) (xy 375.862806 -222.634901)
			(xy 375.878854 -222.684294) (xy 375.886979 -222.735589) (xy 375.887488 -222.761556) (xy 375.886979 -222.787523)
			(xy 376.166889 -222.787523) (xy 376.166889 -222.735589) (xy 376.175014 -222.684294) (xy 376.191062 -222.634901)
			(xy 376.21464 -222.588627) (xy 376.245166 -222.546611) (xy 376.281889 -222.509888) (xy 376.323905 -222.479362)
			(xy 376.370179 -222.455784) (xy 376.419572 -222.439736) (xy 376.470867 -222.431611) (xy 376.522801 -222.431611)
			(xy 376.574096 -222.439736) (xy 376.623489 -222.455784) (xy 376.669763 -222.479362) (xy 376.711779 -222.509888)
			(xy 376.748502 -222.546611) (xy 376.779028 -222.588627) (xy 376.802606 -222.634901) (xy 376.818654 -222.684294)
			(xy 376.826779 -222.735589) (xy 376.827288 -222.761556) (xy 376.826779 -222.787523) (xy 377.106689 -222.787523)
			(xy 377.106689 -222.735589) (xy 377.114814 -222.684294) (xy 377.130862 -222.634901) (xy 377.15444 -222.588627)
			(xy 377.184966 -222.546611) (xy 377.221689 -222.509888) (xy 377.263705 -222.479362) (xy 377.309979 -222.455784)
			(xy 377.359372 -222.439736) (xy 377.410667 -222.431611) (xy 377.462601 -222.431611) (xy 377.513896 -222.439736)
			(xy 377.563289 -222.455784) (xy 377.609563 -222.479362) (xy 377.651579 -222.509888) (xy 377.688302 -222.546611)
			(xy 377.718828 -222.588627) (xy 377.742406 -222.634901) (xy 377.758454 -222.684294) (xy 377.766579 -222.735589)
			(xy 377.767088 -222.761556) (xy 377.766579 -222.787523) (xy 378.046489 -222.787523) (xy 378.046489 -222.735589)
			(xy 378.054614 -222.684294) (xy 378.070662 -222.634901) (xy 378.09424 -222.588627) (xy 378.124766 -222.546611)
			(xy 378.161489 -222.509888) (xy 378.203505 -222.479362) (xy 378.249779 -222.455784) (xy 378.299172 -222.439736)
			(xy 378.350467 -222.431611) (xy 378.402401 -222.431611) (xy 378.453696 -222.439736) (xy 378.503089 -222.455784)
			(xy 378.549363 -222.479362) (xy 378.591379 -222.509888) (xy 378.628102 -222.546611) (xy 378.658628 -222.588627)
			(xy 378.682206 -222.634901) (xy 378.698254 -222.684294) (xy 378.706379 -222.735589) (xy 378.706888 -222.761556)
			(xy 378.706379 -222.787523) (xy 378.986289 -222.787523) (xy 378.986289 -222.735589) (xy 378.994414 -222.684294)
			(xy 379.010462 -222.634901) (xy 379.03404 -222.588627) (xy 379.064566 -222.546611) (xy 379.101289 -222.509888)
			(xy 379.143305 -222.479362) (xy 379.189579 -222.455784) (xy 379.238972 -222.439736) (xy 379.290267 -222.431611)
			(xy 379.342201 -222.431611) (xy 379.393496 -222.439736) (xy 379.442889 -222.455784) (xy 379.489163 -222.479362)
			(xy 379.531179 -222.509888) (xy 379.567902 -222.546611) (xy 379.598428 -222.588627) (xy 379.622006 -222.634901)
			(xy 379.638054 -222.684294) (xy 379.646179 -222.735589) (xy 379.646688 -222.761556) (xy 379.646179 -222.787523)
			(xy 379.646176 -222.787543) (xy 379.925836 -222.787543) (xy 379.925836 -222.735569) (xy 379.933966 -222.684234)
			(xy 379.950027 -222.634804) (xy 379.973623 -222.588494) (xy 380.004173 -222.546446) (xy 380.040924 -222.509695)
			(xy 380.082972 -222.479145) (xy 380.129282 -222.455549) (xy 380.178712 -222.439488) (xy 380.230047 -222.431358)
			(xy 380.282021 -222.431358) (xy 380.333356 -222.439488) (xy 380.382786 -222.455549) (xy 380.429096 -222.479145)
			(xy 380.471144 -222.509695) (xy 380.507895 -222.546446) (xy 380.538445 -222.588494) (xy 380.562041 -222.634804)
			(xy 380.578102 -222.684234) (xy 380.586232 -222.735569) (xy 380.586742 -222.761556) (xy 380.586232 -222.787543)
			(xy 380.865636 -222.787543) (xy 380.865636 -222.735569) (xy 380.873766 -222.684234) (xy 380.889827 -222.634804)
			(xy 380.913423 -222.588494) (xy 380.943973 -222.546446) (xy 380.980724 -222.509695) (xy 381.022772 -222.479145)
			(xy 381.069082 -222.455549) (xy 381.118512 -222.439488) (xy 381.169847 -222.431358) (xy 381.221821 -222.431358)
			(xy 381.273156 -222.439488) (xy 381.322586 -222.455549) (xy 381.368896 -222.479145) (xy 381.410944 -222.509695)
			(xy 381.447695 -222.546446) (xy 381.478245 -222.588494) (xy 381.501841 -222.634804) (xy 381.517902 -222.684234)
			(xy 381.526032 -222.735569) (xy 381.526542 -222.761556) (xy 381.526032 -222.787543) (xy 381.517902 -222.838878)
			(xy 381.501841 -222.888308) (xy 381.478245 -222.934618) (xy 381.447695 -222.976666) (xy 381.410944 -223.013417)
			(xy 381.368896 -223.043967) (xy 381.322586 -223.067563) (xy 381.273156 -223.083624) (xy 381.221821 -223.091754)
			(xy 381.169847 -223.091754) (xy 381.118512 -223.083624) (xy 381.069082 -223.067563) (xy 381.022772 -223.043967)
			(xy 380.980724 -223.013417) (xy 380.943973 -222.976666) (xy 380.913423 -222.934618) (xy 380.889827 -222.888308)
			(xy 380.873766 -222.838878) (xy 380.865636 -222.787543) (xy 380.586232 -222.787543) (xy 380.578102 -222.838878)
			(xy 380.562041 -222.888308) (xy 380.538445 -222.934618) (xy 380.507895 -222.976666) (xy 380.471144 -223.013417)
			(xy 380.429096 -223.043967) (xy 380.382786 -223.067563) (xy 380.333356 -223.083624) (xy 380.282021 -223.091754)
			(xy 380.230047 -223.091754) (xy 380.178712 -223.083624) (xy 380.129282 -223.067563) (xy 380.082972 -223.043967)
			(xy 380.040924 -223.013417) (xy 380.004173 -222.976666) (xy 379.973623 -222.934618) (xy 379.950027 -222.888308)
			(xy 379.933966 -222.838878) (xy 379.925836 -222.787543) (xy 379.646176 -222.787543) (xy 379.638054 -222.838818)
			(xy 379.622006 -222.888211) (xy 379.598428 -222.934485) (xy 379.567902 -222.976501) (xy 379.531179 -223.013224)
			(xy 379.489163 -223.04375) (xy 379.442889 -223.067328) (xy 379.393496 -223.083376) (xy 379.342201 -223.091501)
			(xy 379.290267 -223.091501) (xy 379.238972 -223.083376) (xy 379.189579 -223.067328) (xy 379.143305 -223.04375)
			(xy 379.101289 -223.013224) (xy 379.064566 -222.976501) (xy 379.03404 -222.934485) (xy 379.010462 -222.888211)
			(xy 378.994414 -222.838818) (xy 378.986289 -222.787523) (xy 378.706379 -222.787523) (xy 378.698254 -222.838818)
			(xy 378.682206 -222.888211) (xy 378.658628 -222.934485) (xy 378.628102 -222.976501) (xy 378.591379 -223.013224)
			(xy 378.549363 -223.04375) (xy 378.503089 -223.067328) (xy 378.453696 -223.083376) (xy 378.402401 -223.091501)
			(xy 378.350467 -223.091501) (xy 378.299172 -223.083376) (xy 378.249779 -223.067328) (xy 378.203505 -223.04375)
			(xy 378.161489 -223.013224) (xy 378.124766 -222.976501) (xy 378.09424 -222.934485) (xy 378.070662 -222.888211)
			(xy 378.054614 -222.838818) (xy 378.046489 -222.787523) (xy 377.766579 -222.787523) (xy 377.758454 -222.838818)
			(xy 377.742406 -222.888211) (xy 377.718828 -222.934485) (xy 377.688302 -222.976501) (xy 377.651579 -223.013224)
			(xy 377.609563 -223.04375) (xy 377.563289 -223.067328) (xy 377.513896 -223.083376) (xy 377.462601 -223.091501)
			(xy 377.410667 -223.091501) (xy 377.359372 -223.083376) (xy 377.309979 -223.067328) (xy 377.263705 -223.04375)
			(xy 377.221689 -223.013224) (xy 377.184966 -222.976501) (xy 377.15444 -222.934485) (xy 377.130862 -222.888211)
			(xy 377.114814 -222.838818) (xy 377.106689 -222.787523) (xy 376.826779 -222.787523) (xy 376.818654 -222.838818)
			(xy 376.802606 -222.888211) (xy 376.779028 -222.934485) (xy 376.748502 -222.976501) (xy 376.711779 -223.013224)
			(xy 376.669763 -223.04375) (xy 376.623489 -223.067328) (xy 376.574096 -223.083376) (xy 376.522801 -223.091501)
			(xy 376.470867 -223.091501) (xy 376.419572 -223.083376) (xy 376.370179 -223.067328) (xy 376.323905 -223.04375)
			(xy 376.281889 -223.013224) (xy 376.245166 -222.976501) (xy 376.21464 -222.934485) (xy 376.191062 -222.888211)
			(xy 376.175014 -222.838818) (xy 376.166889 -222.787523) (xy 375.886979 -222.787523) (xy 375.878854 -222.838818)
			(xy 375.862806 -222.888211) (xy 375.839228 -222.934485) (xy 375.808702 -222.976501) (xy 375.771979 -223.013224)
			(xy 375.729963 -223.04375) (xy 375.683689 -223.067328) (xy 375.634296 -223.083376) (xy 375.583001 -223.091501)
			(xy 375.531067 -223.091501) (xy 375.479772 -223.083376) (xy 375.430379 -223.067328) (xy 375.384105 -223.04375)
			(xy 375.342089 -223.013224) (xy 375.305366 -222.976501) (xy 375.27484 -222.934485) (xy 375.251262 -222.888211)
			(xy 375.235214 -222.838818) (xy 375.227089 -222.787523) (xy 375.113804 -222.787523) (xy 375.113804 -223.243648)
			(xy 375.15419 -223.25203) (xy 375.17867 -223.257583) (xy 375.225712 -223.275089) (xy 375.269566 -223.299509)
			(xy 375.309222 -223.33028) (xy 375.343768 -223.366694) (xy 375.37241 -223.407915) (xy 375.394488 -223.452993)
			(xy 375.409495 -223.500891) (xy 375.417086 -223.550508) (xy 375.417085 -223.600702) (xy 375.409493 -223.650319)
			(xy 375.394484 -223.698217) (xy 375.372405 -223.743294) (xy 375.343761 -223.784514) (xy 375.309214 -223.820927)
			(xy 375.269557 -223.851697) (xy 375.225702 -223.876115) (xy 375.178659 -223.89362) (xy 375.15419 -223.899222)
			(xy 375.113804 -223.907604) (xy 375.113804 -224.389442) (xy 375.22658 -224.389442) (xy 375.226987 -224.363988)
			(xy 375.234774 -224.31368) (xy 375.250187 -224.265161) (xy 375.27286 -224.219581) (xy 375.302256 -224.178019)
			(xy 375.33768 -224.141457) (xy 375.378293 -224.110763) (xy 375.423134 -224.086661) (xy 375.471142 -224.069724)
			(xy 375.496074 -224.064576) (xy 375.518934 -224.060258) (xy 375.722642 -223.707198) (xy 375.715022 -223.685354)
			(xy 375.706298 -223.658762) (xy 375.696841 -223.603606) (xy 375.696226 -223.575626) (xy 375.696735 -223.549659)
			(xy 375.70486 -223.498364) (xy 375.720908 -223.448971) (xy 375.744486 -223.402697) (xy 375.775012 -223.360681)
			(xy 375.811735 -223.323958) (xy 375.853751 -223.293432) (xy 375.900025 -223.269854) (xy 375.949418 -223.253806)
			(xy 376.000713 -223.245681) (xy 376.052647 -223.245681) (xy 376.103942 -223.253806) (xy 376.153335 -223.269854)
			(xy 376.199609 -223.293432) (xy 376.241625 -223.323958) (xy 376.278348 -223.360681) (xy 376.308874 -223.402697)
			(xy 376.332452 -223.448971) (xy 376.3485 -223.498364) (xy 376.356625 -223.549659) (xy 376.357134 -223.575626)
			(xy 376.356686 -223.601078) (xy 376.356606 -223.601593) (xy 376.636789 -223.601593) (xy 376.636789 -223.549659)
			(xy 376.644914 -223.498364) (xy 376.660962 -223.448971) (xy 376.68454 -223.402697) (xy 376.715066 -223.360681)
			(xy 376.751789 -223.323958) (xy 376.793805 -223.293432) (xy 376.840079 -223.269854) (xy 376.889472 -223.253806)
			(xy 376.940767 -223.245681) (xy 376.992701 -223.245681) (xy 377.043996 -223.253806) (xy 377.093389 -223.269854)
			(xy 377.139663 -223.293432) (xy 377.181679 -223.323958) (xy 377.218402 -223.360681) (xy 377.248928 -223.402697)
			(xy 377.272506 -223.448971) (xy 377.288554 -223.498364) (xy 377.296679 -223.549659) (xy 377.297188 -223.575626)
			(xy 377.296679 -223.601593) (xy 377.288554 -223.652888) (xy 377.272506 -223.702281) (xy 377.248928 -223.748555)
			(xy 377.218402 -223.790571) (xy 377.181679 -223.827294) (xy 377.139663 -223.85782) (xy 377.093389 -223.881398)
			(xy 377.043996 -223.897446) (xy 376.992701 -223.905571) (xy 376.940767 -223.905571) (xy 376.889472 -223.897446)
			(xy 376.840079 -223.881398) (xy 376.793805 -223.85782) (xy 376.751789 -223.827294) (xy 376.715066 -223.790571)
			(xy 376.68454 -223.748555) (xy 376.660962 -223.702281) (xy 376.644914 -223.652888) (xy 376.636789 -223.601593)
			(xy 376.356606 -223.601593) (xy 376.348904 -223.651385) (xy 376.333497 -223.699901) (xy 376.310829 -223.74548)
			(xy 376.281438 -223.787043) (xy 376.246019 -223.823605) (xy 376.20541 -223.8543) (xy 376.160574 -223.878403)
			(xy 376.11257 -223.895342) (xy 376.08764 -223.900492) (xy 376.064526 -223.90481) (xy 375.861072 -224.257616)
			(xy 375.868692 -224.279714) (xy 375.877433 -224.306301) (xy 375.886878 -224.361461) (xy 375.887488 -224.389442)
			(xy 376.16638 -224.389442) (xy 376.166889 -224.363475) (xy 376.175014 -224.31218) (xy 376.191062 -224.262787)
			(xy 376.21464 -224.216513) (xy 376.245166 -224.174497) (xy 376.281889 -224.137774) (xy 376.323905 -224.107248)
			(xy 376.370179 -224.08367) (xy 376.419572 -224.067622) (xy 376.470867 -224.059497) (xy 376.522801 -224.059497)
			(xy 376.574096 -224.067622) (xy 376.623489 -224.08367) (xy 376.669763 -224.107248) (xy 376.711779 -224.137774)
			(xy 376.748502 -224.174497) (xy 376.779028 -224.216513) (xy 376.802606 -224.262787) (xy 376.818654 -224.31218)
			(xy 376.826779 -224.363475) (xy 376.827288 -224.389442) (xy 377.10618 -224.389442) (xy 377.106587 -224.363988)
			(xy 377.114374 -224.31368) (xy 377.129787 -224.265161) (xy 377.15246 -224.219581) (xy 377.181856 -224.178019)
			(xy 377.21728 -224.141457) (xy 377.257893 -224.110763) (xy 377.302734 -224.086661) (xy 377.350742 -224.069724)
			(xy 377.375674 -224.064576) (xy 377.398534 -224.060258) (xy 377.602242 -223.707198) (xy 377.594622 -223.685354)
			(xy 377.585898 -223.658762) (xy 377.576441 -223.603606) (xy 377.575826 -223.575626) (xy 377.576335 -223.549659)
			(xy 377.58446 -223.498364) (xy 377.600508 -223.448971) (xy 377.624086 -223.402697) (xy 377.654612 -223.360681)
			(xy 377.691335 -223.323958) (xy 377.733351 -223.293432) (xy 377.779625 -223.269854) (xy 377.829018 -223.253806)
			(xy 377.880313 -223.245681) (xy 377.932247 -223.245681) (xy 377.983542 -223.253806) (xy 378.032935 -223.269854)
			(xy 378.079209 -223.293432) (xy 378.121225 -223.323958) (xy 378.157948 -223.360681) (xy 378.188474 -223.402697)
			(xy 378.212052 -223.448971) (xy 378.2281 -223.498364) (xy 378.236225 -223.549659) (xy 378.236734 -223.575626)
			(xy 378.236286 -223.601078) (xy 378.236206 -223.601593) (xy 378.516389 -223.601593) (xy 378.516389 -223.549659)
			(xy 378.524514 -223.498364) (xy 378.540562 -223.448971) (xy 378.56414 -223.402697) (xy 378.594666 -223.360681)
			(xy 378.631389 -223.323958) (xy 378.673405 -223.293432) (xy 378.719679 -223.269854) (xy 378.769072 -223.253806)
			(xy 378.820367 -223.245681) (xy 378.872301 -223.245681) (xy 378.923596 -223.253806) (xy 378.972989 -223.269854)
			(xy 379.019263 -223.293432) (xy 379.061279 -223.323958) (xy 379.098002 -223.360681) (xy 379.128528 -223.402697)
			(xy 379.152106 -223.448971) (xy 379.168154 -223.498364) (xy 379.176279 -223.549659) (xy 379.176788 -223.575626)
			(xy 379.176279 -223.601593) (xy 379.168154 -223.652888) (xy 379.152106 -223.702281) (xy 379.128528 -223.748555)
			(xy 379.098002 -223.790571) (xy 379.061279 -223.827294) (xy 379.019263 -223.85782) (xy 378.972989 -223.881398)
			(xy 378.923596 -223.897446) (xy 378.872301 -223.905571) (xy 378.820367 -223.905571) (xy 378.769072 -223.897446)
			(xy 378.719679 -223.881398) (xy 378.673405 -223.85782) (xy 378.631389 -223.827294) (xy 378.594666 -223.790571)
			(xy 378.56414 -223.748555) (xy 378.540562 -223.702281) (xy 378.524514 -223.652888) (xy 378.516389 -223.601593)
			(xy 378.236206 -223.601593) (xy 378.228504 -223.651385) (xy 378.213097 -223.699901) (xy 378.190429 -223.74548)
			(xy 378.161038 -223.787043) (xy 378.125619 -223.823605) (xy 378.08501 -223.8543) (xy 378.040174 -223.878403)
			(xy 377.99217 -223.895342) (xy 377.96724 -223.900492) (xy 377.944126 -223.90481) (xy 377.740672 -224.257616)
			(xy 377.748292 -224.279714) (xy 377.757033 -224.306301) (xy 377.766478 -224.361461) (xy 377.767088 -224.389442)
			(xy 378.04598 -224.389442) (xy 378.046489 -224.363475) (xy 378.054614 -224.31218) (xy 378.070662 -224.262787)
			(xy 378.09424 -224.216513) (xy 378.124766 -224.174497) (xy 378.161489 -224.137774) (xy 378.203505 -224.107248)
			(xy 378.249779 -224.08367) (xy 378.299172 -224.067622) (xy 378.350467 -224.059497) (xy 378.402401 -224.059497)
			(xy 378.453696 -224.067622) (xy 378.503089 -224.08367) (xy 378.549363 -224.107248) (xy 378.591379 -224.137774)
			(xy 378.628102 -224.174497) (xy 378.658628 -224.216513) (xy 378.682206 -224.262787) (xy 378.698254 -224.31218)
			(xy 378.706379 -224.363475) (xy 378.706888 -224.389442) (xy 378.98578 -224.389442) (xy 378.986187 -224.363988)
			(xy 378.993974 -224.31368) (xy 379.009387 -224.265161) (xy 379.03206 -224.219581) (xy 379.061456 -224.178019)
			(xy 379.09688 -224.141457) (xy 379.137493 -224.110763) (xy 379.182334 -224.086661) (xy 379.230342 -224.069724)
			(xy 379.255274 -224.064576) (xy 379.278388 -224.060258) (xy 379.481842 -223.707198) (xy 379.474222 -223.6851)
			(xy 379.465475 -223.658579) (xy 379.456027 -223.603545) (xy 379.455426 -223.575626) (xy 379.455935 -223.549659)
			(xy 379.46406 -223.498364) (xy 379.480108 -223.448971) (xy 379.503686 -223.402697) (xy 379.534212 -223.360681)
			(xy 379.570935 -223.323958) (xy 379.612951 -223.293432) (xy 379.659225 -223.269854) (xy 379.708618 -223.253806)
			(xy 379.759913 -223.245681) (xy 379.811847 -223.245681) (xy 379.863142 -223.253806) (xy 379.912535 -223.269854)
			(xy 379.958809 -223.293432) (xy 380.000825 -223.323958) (xy 380.037548 -223.360681) (xy 380.068074 -223.402697)
			(xy 380.091652 -223.448971) (xy 380.1077 -223.498364) (xy 380.115825 -223.549659) (xy 380.116334 -223.575626)
			(xy 380.115886 -223.601078) (xy 380.115806 -223.601593) (xy 380.395989 -223.601593) (xy 380.395989 -223.549659)
			(xy 380.404114 -223.498364) (xy 380.420162 -223.448971) (xy 380.44374 -223.402697) (xy 380.474266 -223.360681)
			(xy 380.510989 -223.323958) (xy 380.553005 -223.293432) (xy 380.599279 -223.269854) (xy 380.648672 -223.253806)
			(xy 380.699967 -223.245681) (xy 380.751901 -223.245681) (xy 380.803196 -223.253806) (xy 380.852589 -223.269854)
			(xy 380.898863 -223.293432) (xy 380.940879 -223.323958) (xy 380.977602 -223.360681) (xy 381.008128 -223.402697)
			(xy 381.031706 -223.448971) (xy 381.047754 -223.498364) (xy 381.055879 -223.549659) (xy 381.056388 -223.575626)
			(xy 381.055879 -223.601593) (xy 381.047754 -223.652888) (xy 381.031706 -223.702281) (xy 381.008128 -223.748555)
			(xy 380.977602 -223.790571) (xy 380.940879 -223.827294) (xy 380.898863 -223.85782) (xy 380.852589 -223.881398)
			(xy 380.803196 -223.897446) (xy 380.751901 -223.905571) (xy 380.699967 -223.905571) (xy 380.648672 -223.897446)
			(xy 380.599279 -223.881398) (xy 380.553005 -223.85782) (xy 380.510989 -223.827294) (xy 380.474266 -223.790571)
			(xy 380.44374 -223.748555) (xy 380.420162 -223.702281) (xy 380.404114 -223.652888) (xy 380.395989 -223.601593)
			(xy 380.115806 -223.601593) (xy 380.108104 -223.651385) (xy 380.092697 -223.699901) (xy 380.070029 -223.74548)
			(xy 380.040638 -223.787043) (xy 380.005219 -223.823605) (xy 379.96461 -223.8543) (xy 379.919774 -223.878403)
			(xy 379.87177 -223.895342) (xy 379.84684 -223.900492) (xy 379.823726 -223.90481) (xy 379.620272 -224.257616)
			(xy 379.627892 -224.279714) (xy 379.636633 -224.306301) (xy 379.646078 -224.361461) (xy 379.646688 -224.389442)
			(xy 379.92558 -224.389442) (xy 379.926089 -224.363475) (xy 379.934214 -224.31218) (xy 379.950262 -224.262787)
			(xy 379.97384 -224.216513) (xy 380.004366 -224.174497) (xy 380.041089 -224.137774) (xy 380.083105 -224.107248)
			(xy 380.129379 -224.08367) (xy 380.178772 -224.067622) (xy 380.230067 -224.059497) (xy 380.282001 -224.059497)
			(xy 380.333296 -224.067622) (xy 380.382689 -224.08367) (xy 380.428963 -224.107248) (xy 380.470979 -224.137774)
			(xy 380.507702 -224.174497) (xy 380.538228 -224.216513) (xy 380.561806 -224.262787) (xy 380.577854 -224.31218)
			(xy 380.585979 -224.363475) (xy 380.586488 -224.389442) (xy 380.86538 -224.389442) (xy 380.865787 -224.363988)
			(xy 380.873574 -224.31368) (xy 380.888987 -224.265161) (xy 380.91166 -224.219581) (xy 380.941056 -224.178019)
			(xy 380.97648 -224.141457) (xy 381.017093 -224.110763) (xy 381.061934 -224.086661) (xy 381.109942 -224.069724)
			(xy 381.134874 -224.064576) (xy 381.157988 -224.060258) (xy 381.361696 -223.706944) (xy 381.353822 -223.6851)
			(xy 381.345209 -223.658749) (xy 381.335889 -223.604104) (xy 381.33528 -223.576388) (xy 381.33528 -223.575626)
			(xy 381.335789 -223.549659) (xy 381.343914 -223.498364) (xy 381.359962 -223.448971) (xy 381.38354 -223.402697)
			(xy 381.414066 -223.360681) (xy 381.450789 -223.323958) (xy 381.492805 -223.293432) (xy 381.539079 -223.269854)
			(xy 381.588472 -223.253806) (xy 381.639767 -223.245681) (xy 381.691701 -223.245681) (xy 381.742996 -223.253806)
			(xy 381.792389 -223.269854) (xy 381.838663 -223.293432) (xy 381.880679 -223.323958) (xy 381.917402 -223.360681)
			(xy 381.947928 -223.402697) (xy 381.971506 -223.448971) (xy 381.987554 -223.498364) (xy 381.995679 -223.549659)
			(xy 381.996188 -223.575626) (xy 381.99574 -223.60109) (xy 381.987937 -223.651415) (xy 381.972504 -223.699947)
			(xy 381.949808 -223.745537) (xy 381.920385 -223.787104) (xy 381.884932 -223.823664) (xy 381.844289 -223.854351)
			(xy 381.799419 -223.878439) (xy 381.751385 -223.895356) (xy 381.72644 -223.900492) (xy 381.703326 -223.90481)
			(xy 381.499872 -224.257616) (xy 381.507492 -224.279714) (xy 381.516233 -224.306301) (xy 381.525678 -224.361461)
			(xy 381.526288 -224.389442) (xy 381.80518 -224.389442) (xy 381.805689 -224.363475) (xy 381.813814 -224.31218)
			(xy 381.829862 -224.262787) (xy 381.85344 -224.216513) (xy 381.883966 -224.174497) (xy 381.920689 -224.137774)
			(xy 381.962705 -224.107248) (xy 382.008979 -224.08367) (xy 382.058372 -224.067622) (xy 382.109667 -224.059497)
			(xy 382.161601 -224.059497) (xy 382.212896 -224.067622) (xy 382.262289 -224.08367) (xy 382.308563 -224.107248)
			(xy 382.350579 -224.137774) (xy 382.387302 -224.174497) (xy 382.417828 -224.216513) (xy 382.441406 -224.262787)
			(xy 382.457454 -224.31218) (xy 382.465579 -224.363475) (xy 382.466088 -224.389442) (xy 382.465458 -224.417358)
			(xy 382.456011 -224.472389) (xy 382.447292 -224.498916) (xy 382.439672 -224.521014) (xy 382.64338 -224.874074)
			(xy 382.666494 -224.878392) (xy 382.691414 -224.883569) (xy 382.7394 -224.900529) (xy 382.78422 -224.924643)
			(xy 382.824815 -224.955341) (xy 382.860225 -224.991898) (xy 382.889614 -225.03345) (xy 382.912288 -225.079016)
			(xy 382.92771 -225.127518) (xy 382.935516 -225.177811) (xy 382.935988 -225.203258) (xy 382.935479 -225.229225)
			(xy 382.927354 -225.28052) (xy 382.911306 -225.329913) (xy 382.887728 -225.376187) (xy 382.857202 -225.418203)
			(xy 382.820479 -225.454926) (xy 382.778463 -225.485452) (xy 382.732189 -225.50903) (xy 382.682796 -225.525078)
			(xy 382.631501 -225.533203) (xy 382.579567 -225.533203) (xy 382.528272 -225.525078) (xy 382.478879 -225.50903)
			(xy 382.432605 -225.485452) (xy 382.390589 -225.454926) (xy 382.353866 -225.418203) (xy 382.32334 -225.376187)
			(xy 382.299762 -225.329913) (xy 382.283714 -225.28052) (xy 382.275589 -225.229225) (xy 382.27508 -225.203258)
			(xy 382.275623 -225.175272) (xy 382.28508 -225.120104) (xy 382.293876 -225.09353) (xy 382.301496 -225.071432)
			(xy 382.098042 -224.718626) (xy 382.074928 -224.714308) (xy 382.049993 -224.709143) (xy 382.001969 -224.692216)
			(xy 381.957109 -224.668124) (xy 381.916475 -224.637437) (xy 381.881029 -224.600881) (xy 381.851608 -224.559321)
			(xy 381.828909 -224.51374) (xy 381.813468 -224.465218) (xy 381.805653 -224.414902) (xy 381.80518 -224.389442)
			(xy 381.526288 -224.389442) (xy 381.525779 -224.415409) (xy 381.517654 -224.466704) (xy 381.501606 -224.516097)
			(xy 381.478028 -224.562371) (xy 381.447502 -224.604387) (xy 381.410779 -224.64111) (xy 381.368763 -224.671636)
			(xy 381.322489 -224.695214) (xy 381.273096 -224.711262) (xy 381.221801 -224.719387) (xy 381.169867 -224.719387)
			(xy 381.118572 -224.711262) (xy 381.069179 -224.695214) (xy 381.022905 -224.671636) (xy 380.980889 -224.64111)
			(xy 380.944166 -224.604387) (xy 380.91364 -224.562371) (xy 380.890062 -224.516097) (xy 380.874014 -224.466704)
			(xy 380.865889 -224.415409) (xy 380.86538 -224.389442) (xy 380.586488 -224.389442) (xy 380.585946 -224.417428)
			(xy 380.576489 -224.472596) (xy 380.567692 -224.49917) (xy 380.560072 -224.521268) (xy 380.76378 -224.874074)
			(xy 380.78664 -224.878392) (xy 380.811567 -224.883535) (xy 380.859553 -224.900502) (xy 380.904372 -224.924622)
			(xy 380.944966 -224.955325) (xy 380.980375 -224.991886) (xy 381.009762 -225.033442) (xy 381.032435 -225.07901)
			(xy 381.047856 -225.127515) (xy 381.055662 -225.17781) (xy 381.056134 -225.203258) (xy 381.055625 -225.229225)
			(xy 381.0475 -225.28052) (xy 381.031452 -225.329913) (xy 381.007874 -225.376187) (xy 380.977348 -225.418203)
			(xy 380.940625 -225.454926) (xy 380.898609 -225.485452) (xy 380.852335 -225.50903) (xy 380.802942 -225.525078)
			(xy 380.751647 -225.533203) (xy 380.699713 -225.533203) (xy 380.648418 -225.525078) (xy 380.599025 -225.50903)
			(xy 380.552751 -225.485452) (xy 380.510735 -225.454926) (xy 380.474012 -225.418203) (xy 380.443486 -225.376187)
			(xy 380.419908 -225.329913) (xy 380.40386 -225.28052) (xy 380.395735 -225.229225) (xy 380.395226 -225.203258)
			(xy 380.395767 -225.175272) (xy 380.405225 -225.120104) (xy 380.414022 -225.09353) (xy 380.421642 -225.071432)
			(xy 380.217934 -224.718626) (xy 380.195074 -224.714308) (xy 380.170149 -224.709155) (xy 380.122163 -224.69219)
			(xy 380.077344 -224.668072) (xy 380.03675 -224.63737) (xy 380.00134 -224.60081) (xy 379.971952 -224.559256)
			(xy 379.94928 -224.513688) (xy 379.933858 -224.465184) (xy 379.926052 -224.41489) (xy 379.92558 -224.389442)
			(xy 379.646688 -224.389442) (xy 379.646179 -224.415409) (xy 379.638054 -224.466704) (xy 379.622006 -224.516097)
			(xy 379.598428 -224.562371) (xy 379.567902 -224.604387) (xy 379.531179 -224.64111) (xy 379.489163 -224.671636)
			(xy 379.442889 -224.695214) (xy 379.393496 -224.711262) (xy 379.342201 -224.719387) (xy 379.290267 -224.719387)
			(xy 379.238972 -224.711262) (xy 379.189579 -224.695214) (xy 379.143305 -224.671636) (xy 379.101289 -224.64111)
			(xy 379.064566 -224.604387) (xy 379.03404 -224.562371) (xy 379.010462 -224.516097) (xy 378.994414 -224.466704)
			(xy 378.986289 -224.415409) (xy 378.98578 -224.389442) (xy 378.706888 -224.389442) (xy 378.706346 -224.417428)
			(xy 378.696889 -224.472596) (xy 378.688092 -224.49917) (xy 378.680472 -224.521268) (xy 378.88418 -224.874074)
			(xy 378.90704 -224.878392) (xy 378.931967 -224.883535) (xy 378.979953 -224.900502) (xy 379.024772 -224.924622)
			(xy 379.065366 -224.955325) (xy 379.100775 -224.991886) (xy 379.130162 -225.033442) (xy 379.152835 -225.07901)
			(xy 379.168256 -225.127515) (xy 379.176062 -225.17781) (xy 379.176534 -225.203258) (xy 379.176025 -225.229225)
			(xy 379.1679 -225.28052) (xy 379.151852 -225.329913) (xy 379.128274 -225.376187) (xy 379.097748 -225.418203)
			(xy 379.061025 -225.454926) (xy 379.019009 -225.485452) (xy 378.972735 -225.50903) (xy 378.923342 -225.525078)
			(xy 378.872047 -225.533203) (xy 378.820113 -225.533203) (xy 378.768818 -225.525078) (xy 378.719425 -225.50903)
			(xy 378.673151 -225.485452) (xy 378.631135 -225.454926) (xy 378.594412 -225.418203) (xy 378.563886 -225.376187)
			(xy 378.540308 -225.329913) (xy 378.52426 -225.28052) (xy 378.516135 -225.229225) (xy 378.515626 -225.203258)
			(xy 378.516167 -225.175272) (xy 378.525625 -225.120104) (xy 378.534422 -225.09353) (xy 378.542042 -225.071432)
			(xy 378.338334 -224.718626) (xy 378.315474 -224.714308) (xy 378.290549 -224.709155) (xy 378.242563 -224.69219)
			(xy 378.197744 -224.668072) (xy 378.15715 -224.63737) (xy 378.12174 -224.60081) (xy 378.092352 -224.559256)
			(xy 378.06968 -224.513688) (xy 378.054258 -224.465184) (xy 378.046452 -224.41489) (xy 378.04598 -224.389442)
			(xy 377.767088 -224.389442) (xy 377.766579 -224.415409) (xy 377.758454 -224.466704) (xy 377.742406 -224.516097)
			(xy 377.718828 -224.562371) (xy 377.688302 -224.604387) (xy 377.651579 -224.64111) (xy 377.609563 -224.671636)
			(xy 377.563289 -224.695214) (xy 377.513896 -224.711262) (xy 377.462601 -224.719387) (xy 377.410667 -224.719387)
			(xy 377.359372 -224.711262) (xy 377.309979 -224.695214) (xy 377.263705 -224.671636) (xy 377.221689 -224.64111)
			(xy 377.184966 -224.604387) (xy 377.15444 -224.562371) (xy 377.130862 -224.516097) (xy 377.114814 -224.466704)
			(xy 377.106689 -224.415409) (xy 377.10618 -224.389442) (xy 376.827288 -224.389442) (xy 376.826746 -224.417428)
			(xy 376.817289 -224.472596) (xy 376.808492 -224.49917) (xy 376.800872 -224.521268) (xy 377.00458 -224.874074)
			(xy 377.02744 -224.878392) (xy 377.052367 -224.883535) (xy 377.100353 -224.900502) (xy 377.145172 -224.924622)
			(xy 377.185766 -224.955325) (xy 377.221175 -224.991886) (xy 377.250562 -225.033442) (xy 377.273235 -225.07901)
			(xy 377.288656 -225.127515) (xy 377.296462 -225.17781) (xy 377.296934 -225.203258) (xy 377.296425 -225.229225)
			(xy 377.2883 -225.28052) (xy 377.272252 -225.329913) (xy 377.248674 -225.376187) (xy 377.218148 -225.418203)
			(xy 377.181425 -225.454926) (xy 377.139409 -225.485452) (xy 377.093135 -225.50903) (xy 377.043742 -225.525078)
			(xy 376.992447 -225.533203) (xy 376.940513 -225.533203) (xy 376.889218 -225.525078) (xy 376.839825 -225.50903)
			(xy 376.793551 -225.485452) (xy 376.751535 -225.454926) (xy 376.714812 -225.418203) (xy 376.684286 -225.376187)
			(xy 376.660708 -225.329913) (xy 376.64466 -225.28052) (xy 376.636535 -225.229225) (xy 376.636026 -225.203258)
			(xy 376.636567 -225.175272) (xy 376.646025 -225.120104) (xy 376.654822 -225.09353) (xy 376.662442 -225.071432)
			(xy 376.458734 -224.718626) (xy 376.435874 -224.714308) (xy 376.410949 -224.709155) (xy 376.362963 -224.69219)
			(xy 376.318144 -224.668072) (xy 376.27755 -224.63737) (xy 376.24214 -224.60081) (xy 376.212752 -224.559256)
			(xy 376.19008 -224.513688) (xy 376.174658 -224.465184) (xy 376.166852 -224.41489) (xy 376.16638 -224.389442)
			(xy 375.887488 -224.389442) (xy 375.886979 -224.415409) (xy 375.878854 -224.466704) (xy 375.862806 -224.516097)
			(xy 375.839228 -224.562371) (xy 375.808702 -224.604387) (xy 375.771979 -224.64111) (xy 375.729963 -224.671636)
			(xy 375.683689 -224.695214) (xy 375.634296 -224.711262) (xy 375.583001 -224.719387) (xy 375.531067 -224.719387)
			(xy 375.479772 -224.711262) (xy 375.430379 -224.695214) (xy 375.384105 -224.671636) (xy 375.342089 -224.64111)
			(xy 375.305366 -224.604387) (xy 375.27484 -224.562371) (xy 375.251262 -224.516097) (xy 375.235214 -224.466704)
			(xy 375.227089 -224.415409) (xy 375.22658 -224.389442) (xy 375.113804 -224.389442) (xy 375.113804 -224.855024)
			(xy 375.124472 -224.873566) (xy 375.15419 -224.879662) (xy 375.178661 -224.885222) (xy 375.225684 -224.902742)
			(xy 375.269516 -224.927173) (xy 375.309149 -224.957952) (xy 375.343671 -224.994371) (xy 375.372288 -225.035592)
			(xy 375.394341 -225.080668) (xy 375.409322 -225.12856) (xy 375.416888 -225.178167) (xy 375.417334 -225.203258)
			(xy 375.417097 -225.221052) (xy 375.413278 -225.256435) (xy 375.409714 -225.27387) (xy 375.403872 -225.301048)
			(xy 375.797826 -225.695002) (xy 375.793508 -225.701352) (xy 375.787158 -225.721164) (xy 375.785989 -225.725186)
			(xy 375.784847 -225.733485) (xy 375.784872 -225.737674) (xy 375.785888 -225.749612) (xy 375.786904 -225.76282)
			(xy 375.787904 -225.771132) (xy 375.794658 -225.786439) (xy 375.800112 -225.792792) (xy 375.800112 -225.793046)
			(xy 375.816499 -225.811477) (xy 375.844186 -225.852286) (xy 375.865504 -225.896756) (xy 375.879977 -225.943899)
			(xy 375.887285 -225.99267) (xy 375.887742 -226.017328) (xy 375.88723 -226.043295) (xy 376.166889 -226.043295)
			(xy 376.166889 -225.991361) (xy 376.175014 -225.940066) (xy 376.191062 -225.890673) (xy 376.21464 -225.844399)
			(xy 376.245166 -225.802383) (xy 376.281889 -225.76566) (xy 376.323905 -225.735134) (xy 376.370179 -225.711556)
			(xy 376.419572 -225.695508) (xy 376.470867 -225.687383) (xy 376.522801 -225.687383) (xy 376.574096 -225.695508)
			(xy 376.623489 -225.711556) (xy 376.669763 -225.735134) (xy 376.711779 -225.76566) (xy 376.748502 -225.802383)
			(xy 376.779028 -225.844399) (xy 376.802606 -225.890673) (xy 376.818654 -225.940066) (xy 376.826779 -225.991361)
			(xy 376.827288 -226.017328) (xy 376.826779 -226.043295) (xy 377.106689 -226.043295) (xy 377.106689 -225.991361)
			(xy 377.114814 -225.940066) (xy 377.130862 -225.890673) (xy 377.15444 -225.844399) (xy 377.184966 -225.802383)
			(xy 377.221689 -225.76566) (xy 377.263705 -225.735134) (xy 377.309979 -225.711556) (xy 377.359372 -225.695508)
			(xy 377.410667 -225.687383) (xy 377.462601 -225.687383) (xy 377.513896 -225.695508) (xy 377.563289 -225.711556)
			(xy 377.609563 -225.735134) (xy 377.651579 -225.76566) (xy 377.688302 -225.802383) (xy 377.718828 -225.844399)
			(xy 377.742406 -225.890673) (xy 377.758454 -225.940066) (xy 377.766579 -225.991361) (xy 377.767088 -226.017328)
			(xy 377.766579 -226.043295) (xy 378.046489 -226.043295) (xy 378.046489 -225.991361) (xy 378.054614 -225.940066)
			(xy 378.070662 -225.890673) (xy 378.09424 -225.844399) (xy 378.124766 -225.802383) (xy 378.161489 -225.76566)
			(xy 378.203505 -225.735134) (xy 378.249779 -225.711556) (xy 378.299172 -225.695508) (xy 378.350467 -225.687383)
			(xy 378.402401 -225.687383) (xy 378.453696 -225.695508) (xy 378.503089 -225.711556) (xy 378.549363 -225.735134)
			(xy 378.591379 -225.76566) (xy 378.628102 -225.802383) (xy 378.658628 -225.844399) (xy 378.682206 -225.890673)
			(xy 378.698254 -225.940066) (xy 378.706379 -225.991361) (xy 378.706888 -226.017328) (xy 378.706379 -226.043295)
			(xy 378.986289 -226.043295) (xy 378.986289 -225.991361) (xy 378.994414 -225.940066) (xy 379.010462 -225.890673)
			(xy 379.03404 -225.844399) (xy 379.064566 -225.802383) (xy 379.101289 -225.76566) (xy 379.143305 -225.735134)
			(xy 379.189579 -225.711556) (xy 379.238972 -225.695508) (xy 379.290267 -225.687383) (xy 379.342201 -225.687383)
			(xy 379.393496 -225.695508) (xy 379.442889 -225.711556) (xy 379.489163 -225.735134) (xy 379.531179 -225.76566)
			(xy 379.567902 -225.802383) (xy 379.598428 -225.844399) (xy 379.622006 -225.890673) (xy 379.638054 -225.940066)
			(xy 379.646179 -225.991361) (xy 379.646688 -226.017328) (xy 379.646179 -226.043295) (xy 379.926089 -226.043295)
			(xy 379.926089 -225.991361) (xy 379.934214 -225.940066) (xy 379.950262 -225.890673) (xy 379.97384 -225.844399)
			(xy 380.004366 -225.802383) (xy 380.041089 -225.76566) (xy 380.083105 -225.735134) (xy 380.129379 -225.711556)
			(xy 380.178772 -225.695508) (xy 380.230067 -225.687383) (xy 380.282001 -225.687383) (xy 380.333296 -225.695508)
			(xy 380.382689 -225.711556) (xy 380.428963 -225.735134) (xy 380.470979 -225.76566) (xy 380.507702 -225.802383)
			(xy 380.538228 -225.844399) (xy 380.561806 -225.890673) (xy 380.577854 -225.940066) (xy 380.585979 -225.991361)
			(xy 380.586488 -226.017328) (xy 380.585979 -226.043295) (xy 380.865889 -226.043295) (xy 380.865889 -225.991361)
			(xy 380.874014 -225.940066) (xy 380.890062 -225.890673) (xy 380.91364 -225.844399) (xy 380.944166 -225.802383)
			(xy 380.980889 -225.76566) (xy 381.022905 -225.735134) (xy 381.069179 -225.711556) (xy 381.118572 -225.695508)
			(xy 381.169867 -225.687383) (xy 381.221801 -225.687383) (xy 381.273096 -225.695508) (xy 381.322489 -225.711556)
			(xy 381.368763 -225.735134) (xy 381.410779 -225.76566) (xy 381.447502 -225.802383) (xy 381.478028 -225.844399)
			(xy 381.501606 -225.890673) (xy 381.517654 -225.940066) (xy 381.525779 -225.991361) (xy 381.526288 -226.017328)
			(xy 381.525779 -226.043295) (xy 381.805689 -226.043295) (xy 381.805689 -225.991361) (xy 381.813814 -225.940066)
			(xy 381.829862 -225.890673) (xy 381.85344 -225.844399) (xy 381.883966 -225.802383) (xy 381.920689 -225.76566)
			(xy 381.962705 -225.735134) (xy 382.008979 -225.711556) (xy 382.058372 -225.695508) (xy 382.109667 -225.687383)
			(xy 382.161601 -225.687383) (xy 382.212896 -225.695508) (xy 382.262289 -225.711556) (xy 382.308563 -225.735134)
			(xy 382.350579 -225.76566) (xy 382.387302 -225.802383) (xy 382.417828 -225.844399) (xy 382.441406 -225.890673)
			(xy 382.457454 -225.940066) (xy 382.465579 -225.991361) (xy 382.466088 -226.017328) (xy 382.465579 -226.043295)
			(xy 382.457454 -226.09459) (xy 382.441406 -226.143983) (xy 382.417828 -226.190257) (xy 382.387302 -226.232273)
			(xy 382.350579 -226.268996) (xy 382.308563 -226.299522) (xy 382.262289 -226.3231) (xy 382.212896 -226.339148)
			(xy 382.161601 -226.347273) (xy 382.109667 -226.347273) (xy 382.058372 -226.339148) (xy 382.008979 -226.3231)
			(xy 381.962705 -226.299522) (xy 381.920689 -226.268996) (xy 381.883966 -226.232273) (xy 381.85344 -226.190257)
			(xy 381.829862 -226.143983) (xy 381.813814 -226.09459) (xy 381.805689 -226.043295) (xy 381.525779 -226.043295)
			(xy 381.517654 -226.09459) (xy 381.501606 -226.143983) (xy 381.478028 -226.190257) (xy 381.447502 -226.232273)
			(xy 381.410779 -226.268996) (xy 381.368763 -226.299522) (xy 381.322489 -226.3231) (xy 381.273096 -226.339148)
			(xy 381.221801 -226.347273) (xy 381.169867 -226.347273) (xy 381.118572 -226.339148) (xy 381.069179 -226.3231)
			(xy 381.022905 -226.299522) (xy 380.980889 -226.268996) (xy 380.944166 -226.232273) (xy 380.91364 -226.190257)
			(xy 380.890062 -226.143983) (xy 380.874014 -226.09459) (xy 380.865889 -226.043295) (xy 380.585979 -226.043295)
			(xy 380.577854 -226.09459) (xy 380.561806 -226.143983) (xy 380.538228 -226.190257) (xy 380.507702 -226.232273)
			(xy 380.470979 -226.268996) (xy 380.428963 -226.299522) (xy 380.382689 -226.3231) (xy 380.333296 -226.339148)
			(xy 380.282001 -226.347273) (xy 380.230067 -226.347273) (xy 380.178772 -226.339148) (xy 380.129379 -226.3231)
			(xy 380.083105 -226.299522) (xy 380.041089 -226.268996) (xy 380.004366 -226.232273) (xy 379.97384 -226.190257)
			(xy 379.950262 -226.143983) (xy 379.934214 -226.09459) (xy 379.926089 -226.043295) (xy 379.646179 -226.043295)
			(xy 379.638054 -226.09459) (xy 379.622006 -226.143983) (xy 379.598428 -226.190257) (xy 379.567902 -226.232273)
			(xy 379.531179 -226.268996) (xy 379.489163 -226.299522) (xy 379.442889 -226.3231) (xy 379.393496 -226.339148)
			(xy 379.342201 -226.347273) (xy 379.290267 -226.347273) (xy 379.238972 -226.339148) (xy 379.189579 -226.3231)
			(xy 379.143305 -226.299522) (xy 379.101289 -226.268996) (xy 379.064566 -226.232273) (xy 379.03404 -226.190257)
			(xy 379.010462 -226.143983) (xy 378.994414 -226.09459) (xy 378.986289 -226.043295) (xy 378.706379 -226.043295)
			(xy 378.698254 -226.09459) (xy 378.682206 -226.143983) (xy 378.658628 -226.190257) (xy 378.628102 -226.232273)
			(xy 378.591379 -226.268996) (xy 378.549363 -226.299522) (xy 378.503089 -226.3231) (xy 378.453696 -226.339148)
			(xy 378.402401 -226.347273) (xy 378.350467 -226.347273) (xy 378.299172 -226.339148) (xy 378.249779 -226.3231)
			(xy 378.203505 -226.299522) (xy 378.161489 -226.268996) (xy 378.124766 -226.232273) (xy 378.09424 -226.190257)
			(xy 378.070662 -226.143983) (xy 378.054614 -226.09459) (xy 378.046489 -226.043295) (xy 377.766579 -226.043295)
			(xy 377.758454 -226.09459) (xy 377.742406 -226.143983) (xy 377.718828 -226.190257) (xy 377.688302 -226.232273)
			(xy 377.651579 -226.268996) (xy 377.609563 -226.299522) (xy 377.563289 -226.3231) (xy 377.513896 -226.339148)
			(xy 377.462601 -226.347273) (xy 377.410667 -226.347273) (xy 377.359372 -226.339148) (xy 377.309979 -226.3231)
			(xy 377.263705 -226.299522) (xy 377.221689 -226.268996) (xy 377.184966 -226.232273) (xy 377.15444 -226.190257)
			(xy 377.130862 -226.143983) (xy 377.114814 -226.09459) (xy 377.106689 -226.043295) (xy 376.826779 -226.043295)
			(xy 376.818654 -226.09459) (xy 376.802606 -226.143983) (xy 376.779028 -226.190257) (xy 376.748502 -226.232273)
			(xy 376.711779 -226.268996) (xy 376.669763 -226.299522) (xy 376.623489 -226.3231) (xy 376.574096 -226.339148)
			(xy 376.522801 -226.347273) (xy 376.470867 -226.347273) (xy 376.419572 -226.339148) (xy 376.370179 -226.3231)
			(xy 376.323905 -226.299522) (xy 376.281889 -226.268996) (xy 376.245166 -226.232273) (xy 376.21464 -226.190257)
			(xy 376.191062 -226.143983) (xy 376.175014 -226.09459) (xy 376.166889 -226.043295) (xy 375.88723 -226.043295)
			(xy 375.88723 -226.043315) (xy 375.879097 -226.094648) (xy 375.863034 -226.144077) (xy 375.839437 -226.190385)
			(xy 375.808887 -226.232432) (xy 375.772137 -226.269183) (xy 375.73009 -226.299734) (xy 375.683782 -226.323331)
			(xy 375.634354 -226.339395) (xy 375.583021 -226.34753) (xy 375.557034 -226.348036) (xy 375.544474 -226.34792)
			(xy 375.519428 -226.346016) (xy 375.506996 -226.344226) (xy 375.477417 -226.339011) (xy 375.420676 -226.31933)
			(xy 375.39422 -226.30511) (xy 375.389394 -226.30257) (xy 375.364248 -226.295712) (xy 375.357728 -226.295923)
			(xy 375.345124 -226.299268) (xy 375.339356 -226.302316) (xy 375.30659 -226.321112) (xy 375.261378 -226.347274)
			(xy 375.251247 -226.354669) (xy 375.23926 -226.376663) (xy 375.238518 -226.389184) (xy 375.238518 -226.508056)
			(xy 375.261886 -226.549966) (xy 375.272046 -226.556824) (xy 375.292421 -226.571119) (xy 375.329037 -226.604829)
			(xy 375.360192 -226.643643) (xy 375.385183 -226.686684) (xy 375.403447 -226.732983) (xy 375.414571 -226.781494)
			(xy 375.418304 -226.831125) (xy 375.416345 -226.857111) (xy 375.696989 -226.857111) (xy 375.696989 -226.805177)
			(xy 375.705114 -226.753882) (xy 375.721162 -226.704489) (xy 375.74474 -226.658215) (xy 375.775266 -226.616199)
			(xy 375.811989 -226.579476) (xy 375.854005 -226.54895) (xy 375.900279 -226.525372) (xy 375.949672 -226.509324)
			(xy 376.000967 -226.501199) (xy 376.052901 -226.501199) (xy 376.104196 -226.509324) (xy 376.153589 -226.525372)
			(xy 376.199863 -226.54895) (xy 376.241879 -226.579476) (xy 376.278602 -226.616199) (xy 376.309128 -226.658215)
			(xy 376.332706 -226.704489) (xy 376.348754 -226.753882) (xy 376.356879 -226.805177) (xy 376.357388 -226.831144)
			(xy 376.356879 -226.857111) (xy 376.636535 -226.857111) (xy 376.636535 -226.805177) (xy 376.64466 -226.753882)
			(xy 376.660708 -226.704489) (xy 376.684286 -226.658215) (xy 376.714812 -226.616199) (xy 376.751535 -226.579476)
			(xy 376.793551 -226.54895) (xy 376.839825 -226.525372) (xy 376.889218 -226.509324) (xy 376.940513 -226.501199)
			(xy 376.992447 -226.501199) (xy 377.043742 -226.509324) (xy 377.093135 -226.525372) (xy 377.139409 -226.54895)
			(xy 377.181425 -226.579476) (xy 377.218148 -226.616199) (xy 377.248674 -226.658215) (xy 377.272252 -226.704489)
			(xy 377.2883 -226.753882) (xy 377.296425 -226.805177) (xy 377.296934 -226.831144) (xy 377.296425 -226.857111)
			(xy 377.576335 -226.857111) (xy 377.576335 -226.805177) (xy 377.58446 -226.753882) (xy 377.600508 -226.704489)
			(xy 377.624086 -226.658215) (xy 377.654612 -226.616199) (xy 377.691335 -226.579476) (xy 377.733351 -226.54895)
			(xy 377.779625 -226.525372) (xy 377.829018 -226.509324) (xy 377.880313 -226.501199) (xy 377.932247 -226.501199)
			(xy 377.983542 -226.509324) (xy 378.032935 -226.525372) (xy 378.079209 -226.54895) (xy 378.121225 -226.579476)
			(xy 378.157948 -226.616199) (xy 378.188474 -226.658215) (xy 378.212052 -226.704489) (xy 378.2281 -226.753882)
			(xy 378.236225 -226.805177) (xy 378.236734 -226.831144) (xy 378.236225 -226.857111) (xy 378.516389 -226.857111)
			(xy 378.516389 -226.805177) (xy 378.524514 -226.753882) (xy 378.540562 -226.704489) (xy 378.56414 -226.658215)
			(xy 378.594666 -226.616199) (xy 378.631389 -226.579476) (xy 378.673405 -226.54895) (xy 378.719679 -226.525372)
			(xy 378.769072 -226.509324) (xy 378.820367 -226.501199) (xy 378.872301 -226.501199) (xy 378.923596 -226.509324)
			(xy 378.972989 -226.525372) (xy 379.019263 -226.54895) (xy 379.061279 -226.579476) (xy 379.098002 -226.616199)
			(xy 379.128528 -226.658215) (xy 379.152106 -226.704489) (xy 379.168154 -226.753882) (xy 379.176279 -226.805177)
			(xy 379.176788 -226.831144) (xy 379.176279 -226.857111) (xy 379.455935 -226.857111) (xy 379.455935 -226.805177)
			(xy 379.46406 -226.753882) (xy 379.480108 -226.704489) (xy 379.503686 -226.658215) (xy 379.534212 -226.616199)
			(xy 379.570935 -226.579476) (xy 379.612951 -226.54895) (xy 379.659225 -226.525372) (xy 379.708618 -226.509324)
			(xy 379.759913 -226.501199) (xy 379.811847 -226.501199) (xy 379.863142 -226.509324) (xy 379.912535 -226.525372)
			(xy 379.958809 -226.54895) (xy 380.000825 -226.579476) (xy 380.037548 -226.616199) (xy 380.068074 -226.658215)
			(xy 380.091652 -226.704489) (xy 380.1077 -226.753882) (xy 380.115825 -226.805177) (xy 380.116334 -226.831144)
			(xy 380.115825 -226.857111) (xy 380.395735 -226.857111) (xy 380.395735 -226.805177) (xy 380.40386 -226.753882)
			(xy 380.419908 -226.704489) (xy 380.443486 -226.658215) (xy 380.474012 -226.616199) (xy 380.510735 -226.579476)
			(xy 380.552751 -226.54895) (xy 380.599025 -226.525372) (xy 380.648418 -226.509324) (xy 380.699713 -226.501199)
			(xy 380.751647 -226.501199) (xy 380.802942 -226.509324) (xy 380.852335 -226.525372) (xy 380.898609 -226.54895)
			(xy 380.940625 -226.579476) (xy 380.977348 -226.616199) (xy 381.007874 -226.658215) (xy 381.031452 -226.704489)
			(xy 381.0475 -226.753882) (xy 381.055625 -226.805177) (xy 381.056134 -226.831144) (xy 381.055625 -226.857111)
			(xy 381.0475 -226.908406) (xy 381.031452 -226.957799) (xy 381.007874 -227.004073) (xy 380.977348 -227.046089)
			(xy 380.940625 -227.082812) (xy 380.898609 -227.113338) (xy 380.852335 -227.136916) (xy 380.802942 -227.152964)
			(xy 380.751647 -227.161089) (xy 380.699713 -227.161089) (xy 380.648418 -227.152964) (xy 380.599025 -227.136916)
			(xy 380.552751 -227.113338) (xy 380.510735 -227.082812) (xy 380.474012 -227.046089) (xy 380.443486 -227.004073)
			(xy 380.419908 -226.957799) (xy 380.40386 -226.908406) (xy 380.395735 -226.857111) (xy 380.115825 -226.857111)
			(xy 380.1077 -226.908406) (xy 380.091652 -226.957799) (xy 380.068074 -227.004073) (xy 380.037548 -227.046089)
			(xy 380.000825 -227.082812) (xy 379.958809 -227.113338) (xy 379.912535 -227.136916) (xy 379.863142 -227.152964)
			(xy 379.811847 -227.161089) (xy 379.759913 -227.161089) (xy 379.708618 -227.152964) (xy 379.659225 -227.136916)
			(xy 379.612951 -227.113338) (xy 379.570935 -227.082812) (xy 379.534212 -227.046089) (xy 379.503686 -227.004073)
			(xy 379.480108 -226.957799) (xy 379.46406 -226.908406) (xy 379.455935 -226.857111) (xy 379.176279 -226.857111)
			(xy 379.168154 -226.908406) (xy 379.152106 -226.957799) (xy 379.128528 -227.004073) (xy 379.098002 -227.046089)
			(xy 379.061279 -227.082812) (xy 379.019263 -227.113338) (xy 378.972989 -227.136916) (xy 378.923596 -227.152964)
			(xy 378.872301 -227.161089) (xy 378.820367 -227.161089) (xy 378.769072 -227.152964) (xy 378.719679 -227.136916)
			(xy 378.673405 -227.113338) (xy 378.631389 -227.082812) (xy 378.594666 -227.046089) (xy 378.56414 -227.004073)
			(xy 378.540562 -226.957799) (xy 378.524514 -226.908406) (xy 378.516389 -226.857111) (xy 378.236225 -226.857111)
			(xy 378.2281 -226.908406) (xy 378.212052 -226.957799) (xy 378.188474 -227.004073) (xy 378.157948 -227.046089)
			(xy 378.121225 -227.082812) (xy 378.079209 -227.113338) (xy 378.032935 -227.136916) (xy 377.983542 -227.152964)
			(xy 377.932247 -227.161089) (xy 377.880313 -227.161089) (xy 377.829018 -227.152964) (xy 377.779625 -227.136916)
			(xy 377.733351 -227.113338) (xy 377.691335 -227.082812) (xy 377.654612 -227.046089) (xy 377.624086 -227.004073)
			(xy 377.600508 -226.957799) (xy 377.58446 -226.908406) (xy 377.576335 -226.857111) (xy 377.296425 -226.857111)
			(xy 377.2883 -226.908406) (xy 377.272252 -226.957799) (xy 377.248674 -227.004073) (xy 377.218148 -227.046089)
			(xy 377.181425 -227.082812) (xy 377.139409 -227.113338) (xy 377.093135 -227.136916) (xy 377.043742 -227.152964)
			(xy 376.992447 -227.161089) (xy 376.940513 -227.161089) (xy 376.889218 -227.152964) (xy 376.839825 -227.136916)
			(xy 376.793551 -227.113338) (xy 376.751535 -227.082812) (xy 376.714812 -227.046089) (xy 376.684286 -227.004073)
			(xy 376.660708 -226.957799) (xy 376.64466 -226.908406) (xy 376.636535 -226.857111) (xy 376.356879 -226.857111)
			(xy 376.348754 -226.908406) (xy 376.332706 -226.957799) (xy 376.309128 -227.004073) (xy 376.278602 -227.046089)
			(xy 376.241879 -227.082812) (xy 376.199863 -227.113338) (xy 376.153589 -227.136916) (xy 376.104196 -227.152964)
			(xy 376.052901 -227.161089) (xy 376.000967 -227.161089) (xy 375.949672 -227.152964) (xy 375.900279 -227.136916)
			(xy 375.854005 -227.113338) (xy 375.811989 -227.082812) (xy 375.775266 -227.046089) (xy 375.74474 -227.004073)
			(xy 375.721162 -226.957799) (xy 375.705114 -226.908406) (xy 375.696989 -226.857111) (xy 375.416345 -226.857111)
			(xy 375.414563 -226.880755) (xy 375.403432 -226.929264) (xy 375.385162 -226.97556) (xy 375.360164 -227.018598)
			(xy 375.329003 -227.057407) (xy 375.292382 -227.091112) (xy 375.272046 -227.105464) (xy 375.261886 -227.112322)
			(xy 375.238518 -227.154232) (xy 375.238518 -227.273104) (xy 375.239172 -227.285504) (xy 375.250901 -227.307355)
			(xy 375.26087 -227.31476) (xy 375.341896 -227.361496) (xy 375.352252 -227.366062) (xy 375.374862 -227.366312)
			(xy 375.38533 -227.362004) (xy 375.389648 -227.359464) (xy 375.415111 -227.345297) (xy 375.469785 -227.325162)
			(xy 375.52714 -227.314907) (xy 375.556272 -227.314252) (xy 375.55678 -227.314252) (xy 375.582773 -227.314734)
			(xy 375.634121 -227.322863) (xy 375.683564 -227.338926) (xy 375.729885 -227.362525) (xy 375.771945 -227.393081)
			(xy 375.808706 -227.42984) (xy 375.839264 -227.471898) (xy 375.862866 -227.518218) (xy 375.878932 -227.56766)
			(xy 375.887065 -227.619007) (xy 375.887065 -227.670927) (xy 376.166635 -227.670927) (xy 376.166635 -227.618993)
			(xy 376.17476 -227.567698) (xy 376.190808 -227.518305) (xy 376.214386 -227.472031) (xy 376.244912 -227.430015)
			(xy 376.281635 -227.393292) (xy 376.323651 -227.362766) (xy 376.369925 -227.339188) (xy 376.419318 -227.32314)
			(xy 376.470613 -227.315015) (xy 376.522547 -227.315015) (xy 376.573842 -227.32314) (xy 376.623235 -227.339188)
			(xy 376.669509 -227.362766) (xy 376.711525 -227.393292) (xy 376.748248 -227.430015) (xy 376.778774 -227.472031)
			(xy 376.802352 -227.518305) (xy 376.8184 -227.567698) (xy 376.826525 -227.618993) (xy 376.827034 -227.64496)
			(xy 376.826525 -227.670927) (xy 377.106689 -227.670927) (xy 377.106689 -227.618993) (xy 377.114814 -227.567698)
			(xy 377.130862 -227.518305) (xy 377.15444 -227.472031) (xy 377.184966 -227.430015) (xy 377.221689 -227.393292)
			(xy 377.263705 -227.362766) (xy 377.309979 -227.339188) (xy 377.359372 -227.32314) (xy 377.410667 -227.315015)
			(xy 377.462601 -227.315015) (xy 377.513896 -227.32314) (xy 377.563289 -227.339188) (xy 377.609563 -227.362766)
			(xy 377.651579 -227.393292) (xy 377.688302 -227.430015) (xy 377.718828 -227.472031) (xy 377.742406 -227.518305)
			(xy 377.758454 -227.567698) (xy 377.766579 -227.618993) (xy 377.767088 -227.64496) (xy 377.766579 -227.670927)
			(xy 378.046489 -227.670927) (xy 378.046489 -227.618993) (xy 378.054614 -227.567698) (xy 378.070662 -227.518305)
			(xy 378.09424 -227.472031) (xy 378.124766 -227.430015) (xy 378.161489 -227.393292) (xy 378.203505 -227.362766)
			(xy 378.249779 -227.339188) (xy 378.299172 -227.32314) (xy 378.350467 -227.315015) (xy 378.402401 -227.315015)
			(xy 378.453696 -227.32314) (xy 378.503089 -227.339188) (xy 378.549363 -227.362766) (xy 378.591379 -227.393292)
			(xy 378.628102 -227.430015) (xy 378.658628 -227.472031) (xy 378.682206 -227.518305) (xy 378.698254 -227.567698)
			(xy 378.706379 -227.618993) (xy 378.706888 -227.64496) (xy 378.706379 -227.670927) (xy 378.986289 -227.670927)
			(xy 378.986289 -227.618993) (xy 378.994414 -227.567698) (xy 379.010462 -227.518305) (xy 379.03404 -227.472031)
			(xy 379.064566 -227.430015) (xy 379.101289 -227.393292) (xy 379.143305 -227.362766) (xy 379.189579 -227.339188)
			(xy 379.238972 -227.32314) (xy 379.290267 -227.315015) (xy 379.342201 -227.315015) (xy 379.393496 -227.32314)
			(xy 379.442889 -227.339188) (xy 379.489163 -227.362766) (xy 379.531179 -227.393292) (xy 379.567902 -227.430015)
			(xy 379.598428 -227.472031) (xy 379.622006 -227.518305) (xy 379.638054 -227.567698) (xy 379.646179 -227.618993)
			(xy 379.646688 -227.64496) (xy 379.646179 -227.670927) (xy 379.926089 -227.670927) (xy 379.926089 -227.618993)
			(xy 379.934214 -227.567698) (xy 379.950262 -227.518305) (xy 379.97384 -227.472031) (xy 380.004366 -227.430015)
			(xy 380.041089 -227.393292) (xy 380.083105 -227.362766) (xy 380.129379 -227.339188) (xy 380.178772 -227.32314)
			(xy 380.230067 -227.315015) (xy 380.282001 -227.315015) (xy 380.333296 -227.32314) (xy 380.382689 -227.339188)
			(xy 380.428963 -227.362766) (xy 380.470979 -227.393292) (xy 380.507702 -227.430015) (xy 380.538228 -227.472031)
			(xy 380.561806 -227.518305) (xy 380.577854 -227.567698) (xy 380.585979 -227.618993) (xy 380.586488 -227.64496)
			(xy 380.585979 -227.670927) (xy 380.577854 -227.722222) (xy 380.561806 -227.771615) (xy 380.538228 -227.817889)
			(xy 380.507702 -227.859905) (xy 380.470979 -227.896628) (xy 380.428963 -227.927154) (xy 380.382689 -227.950732)
			(xy 380.333296 -227.96678) (xy 380.282001 -227.974905) (xy 380.230067 -227.974905) (xy 380.178772 -227.96678)
			(xy 380.129379 -227.950732) (xy 380.083105 -227.927154) (xy 380.041089 -227.896628) (xy 380.004366 -227.859905)
			(xy 379.97384 -227.817889) (xy 379.950262 -227.771615) (xy 379.934214 -227.722222) (xy 379.926089 -227.670927)
			(xy 379.646179 -227.670927) (xy 379.638054 -227.722222) (xy 379.622006 -227.771615) (xy 379.598428 -227.817889)
			(xy 379.567902 -227.859905) (xy 379.531179 -227.896628) (xy 379.489163 -227.927154) (xy 379.442889 -227.950732)
			(xy 379.393496 -227.96678) (xy 379.342201 -227.974905) (xy 379.290267 -227.974905) (xy 379.238972 -227.96678)
			(xy 379.189579 -227.950732) (xy 379.143305 -227.927154) (xy 379.101289 -227.896628) (xy 379.064566 -227.859905)
			(xy 379.03404 -227.817889) (xy 379.010462 -227.771615) (xy 378.994414 -227.722222) (xy 378.986289 -227.670927)
			(xy 378.706379 -227.670927) (xy 378.698254 -227.722222) (xy 378.682206 -227.771615) (xy 378.658628 -227.817889)
			(xy 378.628102 -227.859905) (xy 378.591379 -227.896628) (xy 378.549363 -227.927154) (xy 378.503089 -227.950732)
			(xy 378.453696 -227.96678) (xy 378.402401 -227.974905) (xy 378.350467 -227.974905) (xy 378.299172 -227.96678)
			(xy 378.249779 -227.950732) (xy 378.203505 -227.927154) (xy 378.161489 -227.896628) (xy 378.124766 -227.859905)
			(xy 378.09424 -227.817889) (xy 378.070662 -227.771615) (xy 378.054614 -227.722222) (xy 378.046489 -227.670927)
			(xy 377.766579 -227.670927) (xy 377.758454 -227.722222) (xy 377.742406 -227.771615) (xy 377.718828 -227.817889)
			(xy 377.688302 -227.859905) (xy 377.651579 -227.896628) (xy 377.609563 -227.927154) (xy 377.563289 -227.950732)
			(xy 377.513896 -227.96678) (xy 377.462601 -227.974905) (xy 377.410667 -227.974905) (xy 377.359372 -227.96678)
			(xy 377.309979 -227.950732) (xy 377.263705 -227.927154) (xy 377.221689 -227.896628) (xy 377.184966 -227.859905)
			(xy 377.15444 -227.817889) (xy 377.130862 -227.771615) (xy 377.114814 -227.722222) (xy 377.106689 -227.670927)
			(xy 376.826525 -227.670927) (xy 376.8184 -227.722222) (xy 376.802352 -227.771615) (xy 376.778774 -227.817889)
			(xy 376.748248 -227.859905) (xy 376.711525 -227.896628) (xy 376.669509 -227.927154) (xy 376.623235 -227.950732)
			(xy 376.573842 -227.96678) (xy 376.522547 -227.974905) (xy 376.470613 -227.974905) (xy 376.419318 -227.96678)
			(xy 376.369925 -227.950732) (xy 376.323651 -227.927154) (xy 376.281635 -227.896628) (xy 376.244912 -227.859905)
			(xy 376.214386 -227.817889) (xy 376.190808 -227.771615) (xy 376.17476 -227.722222) (xy 376.166635 -227.670927)
			(xy 375.887065 -227.670927) (xy 375.887065 -227.670993) (xy 375.878932 -227.72234) (xy 375.862866 -227.771782)
			(xy 375.839264 -227.818102) (xy 375.808706 -227.86016) (xy 375.771945 -227.896919) (xy 375.729885 -227.927475)
			(xy 375.683564 -227.951074) (xy 375.634121 -227.967137) (xy 375.582773 -227.975266) (xy 375.55678 -227.975668)
			(xy 375.556272 -227.975668) (xy 375.527196 -227.975027) (xy 375.469945 -227.964819) (xy 375.415349 -227.944791)
			(xy 375.389902 -227.93071) (xy 375.385076 -227.927916) (xy 375.373906 -227.923606) (xy 375.350028 -227.92478)
			(xy 375.339356 -227.930202) (xy 375.263918 -227.973382) (xy 375.256384 -227.977998) (xy 375.244913 -227.991422)
			(xy 375.238802 -228.007987) (xy 375.238518 -228.016816) (xy 375.238518 -228.136196) (xy 375.261886 -228.178106)
			(xy 375.272046 -228.184964) (xy 375.292394 -228.199252) (xy 375.328961 -228.232939) (xy 375.360073 -228.271721)
			(xy 375.385029 -228.314723) (xy 375.403267 -228.360976) (xy 375.414376 -228.409438) (xy 375.418105 -228.459017)
			(xy 375.416148 -228.484997) (xy 375.696735 -228.484997) (xy 375.696735 -228.433063) (xy 375.70486 -228.381768)
			(xy 375.720908 -228.332375) (xy 375.744486 -228.286101) (xy 375.775012 -228.244085) (xy 375.811735 -228.207362)
			(xy 375.853751 -228.176836) (xy 375.900025 -228.153258) (xy 375.949418 -228.13721) (xy 376.000713 -228.129085)
			(xy 376.052647 -228.129085) (xy 376.103942 -228.13721) (xy 376.153335 -228.153258) (xy 376.199609 -228.176836)
			(xy 376.241625 -228.207362) (xy 376.278348 -228.244085) (xy 376.308874 -228.286101) (xy 376.332452 -228.332375)
			(xy 376.3485 -228.381768) (xy 376.356625 -228.433063) (xy 376.357134 -228.45903) (xy 376.356625 -228.484997)
			(xy 376.636535 -228.484997) (xy 376.636535 -228.433063) (xy 376.64466 -228.381768) (xy 376.660708 -228.332375)
			(xy 376.684286 -228.286101) (xy 376.714812 -228.244085) (xy 376.751535 -228.207362) (xy 376.793551 -228.176836)
			(xy 376.839825 -228.153258) (xy 376.889218 -228.13721) (xy 376.940513 -228.129085) (xy 376.992447 -228.129085)
			(xy 377.043742 -228.13721) (xy 377.093135 -228.153258) (xy 377.139409 -228.176836) (xy 377.181425 -228.207362)
			(xy 377.218148 -228.244085) (xy 377.248674 -228.286101) (xy 377.272252 -228.332375) (xy 377.2883 -228.381768)
			(xy 377.296425 -228.433063) (xy 377.296934 -228.45903) (xy 377.296425 -228.484997) (xy 377.576335 -228.484997)
			(xy 377.576335 -228.433063) (xy 377.58446 -228.381768) (xy 377.600508 -228.332375) (xy 377.624086 -228.286101)
			(xy 377.654612 -228.244085) (xy 377.691335 -228.207362) (xy 377.733351 -228.176836) (xy 377.779625 -228.153258)
			(xy 377.829018 -228.13721) (xy 377.880313 -228.129085) (xy 377.932247 -228.129085) (xy 377.983542 -228.13721)
			(xy 378.032935 -228.153258) (xy 378.079209 -228.176836) (xy 378.121225 -228.207362) (xy 378.157948 -228.244085)
			(xy 378.188474 -228.286101) (xy 378.212052 -228.332375) (xy 378.2281 -228.381768) (xy 378.236225 -228.433063)
			(xy 378.236734 -228.45903) (xy 378.236225 -228.484997) (xy 378.516135 -228.484997) (xy 378.516135 -228.433063)
			(xy 378.52426 -228.381768) (xy 378.540308 -228.332375) (xy 378.563886 -228.286101) (xy 378.594412 -228.244085)
			(xy 378.631135 -228.207362) (xy 378.673151 -228.176836) (xy 378.719425 -228.153258) (xy 378.768818 -228.13721)
			(xy 378.820113 -228.129085) (xy 378.872047 -228.129085) (xy 378.923342 -228.13721) (xy 378.972735 -228.153258)
			(xy 379.019009 -228.176836) (xy 379.061025 -228.207362) (xy 379.097748 -228.244085) (xy 379.128274 -228.286101)
			(xy 379.151852 -228.332375) (xy 379.1679 -228.381768) (xy 379.176025 -228.433063) (xy 379.176534 -228.45903)
			(xy 379.176025 -228.484997) (xy 379.455935 -228.484997) (xy 379.455935 -228.433063) (xy 379.46406 -228.381768)
			(xy 379.480108 -228.332375) (xy 379.503686 -228.286101) (xy 379.534212 -228.244085) (xy 379.570935 -228.207362)
			(xy 379.612951 -228.176836) (xy 379.659225 -228.153258) (xy 379.708618 -228.13721) (xy 379.759913 -228.129085)
			(xy 379.811847 -228.129085) (xy 379.863142 -228.13721) (xy 379.912535 -228.153258) (xy 379.958809 -228.176836)
			(xy 380.000825 -228.207362) (xy 380.037548 -228.244085) (xy 380.068074 -228.286101) (xy 380.091652 -228.332375)
			(xy 380.1077 -228.381768) (xy 380.115825 -228.433063) (xy 380.116334 -228.45903) (xy 380.115825 -228.484997)
			(xy 380.1077 -228.536292) (xy 380.091652 -228.585685) (xy 380.068074 -228.631959) (xy 380.037548 -228.673975)
			(xy 380.000825 -228.710698) (xy 379.958809 -228.741224) (xy 379.912535 -228.764802) (xy 379.863142 -228.78085)
			(xy 379.811847 -228.788975) (xy 379.759913 -228.788975) (xy 379.708618 -228.78085) (xy 379.659225 -228.764802)
			(xy 379.612951 -228.741224) (xy 379.570935 -228.710698) (xy 379.534212 -228.673975) (xy 379.503686 -228.631959)
			(xy 379.480108 -228.585685) (xy 379.46406 -228.536292) (xy 379.455935 -228.484997) (xy 379.176025 -228.484997)
			(xy 379.1679 -228.536292) (xy 379.151852 -228.585685) (xy 379.128274 -228.631959) (xy 379.097748 -228.673975)
			(xy 379.061025 -228.710698) (xy 379.019009 -228.741224) (xy 378.972735 -228.764802) (xy 378.923342 -228.78085)
			(xy 378.872047 -228.788975) (xy 378.820113 -228.788975) (xy 378.768818 -228.78085) (xy 378.719425 -228.764802)
			(xy 378.673151 -228.741224) (xy 378.631135 -228.710698) (xy 378.594412 -228.673975) (xy 378.563886 -228.631959)
			(xy 378.540308 -228.585685) (xy 378.52426 -228.536292) (xy 378.516135 -228.484997) (xy 378.236225 -228.484997)
			(xy 378.2281 -228.536292) (xy 378.212052 -228.585685) (xy 378.188474 -228.631959) (xy 378.157948 -228.673975)
			(xy 378.121225 -228.710698) (xy 378.079209 -228.741224) (xy 378.032935 -228.764802) (xy 377.983542 -228.78085)
			(xy 377.932247 -228.788975) (xy 377.880313 -228.788975) (xy 377.829018 -228.78085) (xy 377.779625 -228.764802)
			(xy 377.733351 -228.741224) (xy 377.691335 -228.710698) (xy 377.654612 -228.673975) (xy 377.624086 -228.631959)
			(xy 377.600508 -228.585685) (xy 377.58446 -228.536292) (xy 377.576335 -228.484997) (xy 377.296425 -228.484997)
			(xy 377.2883 -228.536292) (xy 377.272252 -228.585685) (xy 377.248674 -228.631959) (xy 377.218148 -228.673975)
			(xy 377.181425 -228.710698) (xy 377.139409 -228.741224) (xy 377.093135 -228.764802) (xy 377.043742 -228.78085)
			(xy 376.992447 -228.788975) (xy 376.940513 -228.788975) (xy 376.889218 -228.78085) (xy 376.839825 -228.764802)
			(xy 376.793551 -228.741224) (xy 376.751535 -228.710698) (xy 376.714812 -228.673975) (xy 376.684286 -228.631959)
			(xy 376.660708 -228.585685) (xy 376.64466 -228.536292) (xy 376.636535 -228.484997) (xy 376.356625 -228.484997)
			(xy 376.3485 -228.536292) (xy 376.332452 -228.585685) (xy 376.308874 -228.631959) (xy 376.278348 -228.673975)
			(xy 376.241625 -228.710698) (xy 376.199609 -228.741224) (xy 376.153335 -228.764802) (xy 376.103942 -228.78085)
			(xy 376.052647 -228.788975) (xy 376.000713 -228.788975) (xy 375.949418 -228.78085) (xy 375.900025 -228.764802)
			(xy 375.853751 -228.741224) (xy 375.811735 -228.710698) (xy 375.775012 -228.673975) (xy 375.744486 -228.631959)
			(xy 375.720908 -228.585685) (xy 375.70486 -228.536292) (xy 375.696735 -228.484997) (xy 375.416148 -228.484997)
			(xy 375.414371 -228.508595) (xy 375.403257 -228.557056) (xy 375.385014 -228.603307) (xy 375.360054 -228.646307)
			(xy 375.328938 -228.685085) (xy 375.292368 -228.718769) (xy 375.272046 -228.733096) (xy 375.261886 -228.739954)
			(xy 375.238518 -228.781864) (xy 375.238518 -228.90099) (xy 375.239193 -228.913531) (xy 375.251195 -228.93555)
			(xy 375.261378 -228.9429) (xy 375.30659 -228.969062) (xy 375.339356 -228.987858) (xy 375.345119 -228.990917)
			(xy 375.357726 -228.994254) (xy 375.364248 -228.994462) (xy 375.389394 -228.987604) (xy 375.39422 -228.985064)
			(xy 375.419214 -228.971574) (xy 375.472682 -228.952437) (xy 375.528638 -228.942737) (xy 375.557034 -228.942138)
			(xy 375.583016 -228.94265) (xy 375.634339 -228.950784) (xy 375.683758 -228.966846) (xy 375.730056 -228.99044)
			(xy 375.772094 -229.020986) (xy 375.808836 -229.057732) (xy 375.839378 -229.099773) (xy 375.862967 -229.146073)
			(xy 375.879024 -229.195494) (xy 375.887152 -229.246818) (xy 375.887152 -229.298782) (xy 375.887147 -229.298813)
			(xy 376.166889 -229.298813) (xy 376.166889 -229.246879) (xy 376.175014 -229.195584) (xy 376.191062 -229.146191)
			(xy 376.21464 -229.099917) (xy 376.245166 -229.057901) (xy 376.281889 -229.021178) (xy 376.323905 -228.990652)
			(xy 376.370179 -228.967074) (xy 376.419572 -228.951026) (xy 376.470867 -228.942901) (xy 376.522801 -228.942901)
			(xy 376.574096 -228.951026) (xy 376.623489 -228.967074) (xy 376.669763 -228.990652) (xy 376.711779 -229.021178)
			(xy 376.748502 -229.057901) (xy 376.779028 -229.099917) (xy 376.802606 -229.146191) (xy 376.818654 -229.195584)
			(xy 376.826779 -229.246879) (xy 376.827288 -229.272846) (xy 376.826779 -229.298813) (xy 377.106435 -229.298813)
			(xy 377.106435 -229.246879) (xy 377.11456 -229.195584) (xy 377.130608 -229.146191) (xy 377.154186 -229.099917)
			(xy 377.184712 -229.057901) (xy 377.221435 -229.021178) (xy 377.263451 -228.990652) (xy 377.309725 -228.967074)
			(xy 377.359118 -228.951026) (xy 377.410413 -228.942901) (xy 377.462347 -228.942901) (xy 377.513642 -228.951026)
			(xy 377.563035 -228.967074) (xy 377.609309 -228.990652) (xy 377.651325 -229.021178) (xy 377.688048 -229.057901)
			(xy 377.718574 -229.099917) (xy 377.742152 -229.146191) (xy 377.7582 -229.195584) (xy 377.766325 -229.246879)
			(xy 377.766834 -229.272846) (xy 377.766325 -229.298813) (xy 378.046489 -229.298813) (xy 378.046489 -229.246879)
			(xy 378.054614 -229.195584) (xy 378.070662 -229.146191) (xy 378.09424 -229.099917) (xy 378.124766 -229.057901)
			(xy 378.161489 -229.021178) (xy 378.203505 -228.990652) (xy 378.249779 -228.967074) (xy 378.299172 -228.951026)
			(xy 378.350467 -228.942901) (xy 378.402401 -228.942901) (xy 378.453696 -228.951026) (xy 378.503089 -228.967074)
			(xy 378.549363 -228.990652) (xy 378.591379 -229.021178) (xy 378.628102 -229.057901) (xy 378.658628 -229.099917)
			(xy 378.682206 -229.146191) (xy 378.698254 -229.195584) (xy 378.706379 -229.246879) (xy 378.706888 -229.272846)
			(xy 378.706379 -229.298813) (xy 378.986289 -229.298813) (xy 378.986289 -229.246879) (xy 378.994414 -229.195584)
			(xy 379.010462 -229.146191) (xy 379.03404 -229.099917) (xy 379.064566 -229.057901) (xy 379.101289 -229.021178)
			(xy 379.143305 -228.990652) (xy 379.189579 -228.967074) (xy 379.238972 -228.951026) (xy 379.290267 -228.942901)
			(xy 379.342201 -228.942901) (xy 379.393496 -228.951026) (xy 379.442889 -228.967074) (xy 379.489163 -228.990652)
			(xy 379.531179 -229.021178) (xy 379.567902 -229.057901) (xy 379.598428 -229.099917) (xy 379.622006 -229.146191)
			(xy 379.638054 -229.195584) (xy 379.646179 -229.246879) (xy 379.646688 -229.272846) (xy 379.646179 -229.298813)
			(xy 379.638054 -229.350108) (xy 379.622006 -229.399501) (xy 379.598428 -229.445775) (xy 379.567902 -229.487791)
			(xy 379.531179 -229.524514) (xy 379.489163 -229.55504) (xy 379.442889 -229.578618) (xy 379.393496 -229.594666)
			(xy 379.342201 -229.602791) (xy 379.290267 -229.602791) (xy 379.238972 -229.594666) (xy 379.189579 -229.578618)
			(xy 379.143305 -229.55504) (xy 379.101289 -229.524514) (xy 379.064566 -229.487791) (xy 379.03404 -229.445775)
			(xy 379.010462 -229.399501) (xy 378.994414 -229.350108) (xy 378.986289 -229.298813) (xy 378.706379 -229.298813)
			(xy 378.698254 -229.350108) (xy 378.682206 -229.399501) (xy 378.658628 -229.445775) (xy 378.628102 -229.487791)
			(xy 378.591379 -229.524514) (xy 378.549363 -229.55504) (xy 378.503089 -229.578618) (xy 378.453696 -229.594666)
			(xy 378.402401 -229.602791) (xy 378.350467 -229.602791) (xy 378.299172 -229.594666) (xy 378.249779 -229.578618)
			(xy 378.203505 -229.55504) (xy 378.161489 -229.524514) (xy 378.124766 -229.487791) (xy 378.09424 -229.445775)
			(xy 378.070662 -229.399501) (xy 378.054614 -229.350108) (xy 378.046489 -229.298813) (xy 377.766325 -229.298813)
			(xy 377.7582 -229.350108) (xy 377.742152 -229.399501) (xy 377.718574 -229.445775) (xy 377.688048 -229.487791)
			(xy 377.651325 -229.524514) (xy 377.609309 -229.55504) (xy 377.563035 -229.578618) (xy 377.513642 -229.594666)
			(xy 377.462347 -229.602791) (xy 377.410413 -229.602791) (xy 377.359118 -229.594666) (xy 377.309725 -229.578618)
			(xy 377.263451 -229.55504) (xy 377.221435 -229.524514) (xy 377.184712 -229.487791) (xy 377.154186 -229.445775)
			(xy 377.130608 -229.399501) (xy 377.11456 -229.350108) (xy 377.106435 -229.298813) (xy 376.826779 -229.298813)
			(xy 376.818654 -229.350108) (xy 376.802606 -229.399501) (xy 376.779028 -229.445775) (xy 376.748502 -229.487791)
			(xy 376.711779 -229.524514) (xy 376.669763 -229.55504) (xy 376.623489 -229.578618) (xy 376.574096 -229.594666)
			(xy 376.522801 -229.602791) (xy 376.470867 -229.602791) (xy 376.419572 -229.594666) (xy 376.370179 -229.578618)
			(xy 376.323905 -229.55504) (xy 376.281889 -229.524514) (xy 376.245166 -229.487791) (xy 376.21464 -229.445775)
			(xy 376.191062 -229.399501) (xy 376.175014 -229.350108) (xy 376.166889 -229.298813) (xy 375.887147 -229.298813)
			(xy 375.879024 -229.350106) (xy 375.862967 -229.399527) (xy 375.839378 -229.445827) (xy 375.808836 -229.487868)
			(xy 375.772094 -229.524614) (xy 375.730056 -229.55516) (xy 375.683758 -229.578754) (xy 375.634339 -229.594816)
			(xy 375.583016 -229.60295) (xy 375.557034 -229.603554) (xy 375.544474 -229.603438) (xy 375.519428 -229.601534)
			(xy 375.506996 -229.599744) (xy 375.477417 -229.594529) (xy 375.420676 -229.574849) (xy 375.39422 -229.560628)
			(xy 375.389394 -229.558088) (xy 375.364248 -229.55123) (xy 375.357728 -229.551441) (xy 375.345125 -229.554788)
			(xy 375.339356 -229.557834) (xy 375.30659 -229.57663) (xy 375.261378 -229.602792) (xy 375.251233 -229.610181)
			(xy 375.23921 -229.632174) (xy 375.238518 -229.644702) (xy 375.238518 -229.763828) (xy 375.261886 -229.805738)
			(xy 375.272046 -229.812596) (xy 375.294066 -229.828113) (xy 375.33322 -229.865105) (xy 375.365859 -229.907955)
			(xy 375.391117 -229.955531) (xy 375.408328 -230.006572) (xy 375.417036 -230.059729) (xy 375.417588 -230.086662)
			(xy 375.417108 -230.112629) (xy 375.696735 -230.112629) (xy 375.696735 -230.060695) (xy 375.70486 -230.0094)
			(xy 375.720908 -229.960007) (xy 375.744486 -229.913733) (xy 375.775012 -229.871717) (xy 375.811735 -229.834994)
			(xy 375.853751 -229.804468) (xy 375.900025 -229.78089) (xy 375.949418 -229.764842) (xy 376.000713 -229.756717)
			(xy 376.052647 -229.756717) (xy 376.103942 -229.764842) (xy 376.153335 -229.78089) (xy 376.199609 -229.804468)
			(xy 376.241625 -229.834994) (xy 376.278348 -229.871717) (xy 376.308874 -229.913733) (xy 376.332452 -229.960007)
			(xy 376.3485 -230.0094) (xy 376.356625 -230.060695) (xy 376.357134 -230.086662) (xy 376.356625 -230.112629)
			(xy 376.636535 -230.112629) (xy 376.636535 -230.060695) (xy 376.64466 -230.0094) (xy 376.660708 -229.960007)
			(xy 376.684286 -229.913733) (xy 376.714812 -229.871717) (xy 376.751535 -229.834994) (xy 376.793551 -229.804468)
			(xy 376.839825 -229.78089) (xy 376.889218 -229.764842) (xy 376.940513 -229.756717) (xy 376.992447 -229.756717)
			(xy 377.043742 -229.764842) (xy 377.093135 -229.78089) (xy 377.139409 -229.804468) (xy 377.181425 -229.834994)
			(xy 377.218148 -229.871717) (xy 377.248674 -229.913733) (xy 377.272252 -229.960007) (xy 377.2883 -230.0094)
			(xy 377.296425 -230.060695) (xy 377.296934 -230.086662) (xy 377.296425 -230.112629) (xy 377.576335 -230.112629)
			(xy 377.576335 -230.060695) (xy 377.58446 -230.0094) (xy 377.600508 -229.960007) (xy 377.624086 -229.913733)
			(xy 377.654612 -229.871717) (xy 377.691335 -229.834994) (xy 377.733351 -229.804468) (xy 377.779625 -229.78089)
			(xy 377.829018 -229.764842) (xy 377.880313 -229.756717) (xy 377.932247 -229.756717) (xy 377.983542 -229.764842)
			(xy 378.032935 -229.78089) (xy 378.079209 -229.804468) (xy 378.121225 -229.834994) (xy 378.157948 -229.871717)
			(xy 378.188474 -229.913733) (xy 378.212052 -229.960007) (xy 378.2281 -230.0094) (xy 378.236225 -230.060695)
			(xy 378.236734 -230.086662) (xy 378.236225 -230.112629) (xy 378.516135 -230.112629) (xy 378.516135 -230.060695)
			(xy 378.52426 -230.0094) (xy 378.540308 -229.960007) (xy 378.563886 -229.913733) (xy 378.594412 -229.871717)
			(xy 378.631135 -229.834994) (xy 378.673151 -229.804468) (xy 378.719425 -229.78089) (xy 378.768818 -229.764842)
			(xy 378.820113 -229.756717) (xy 378.872047 -229.756717) (xy 378.923342 -229.764842) (xy 378.972735 -229.78089)
			(xy 379.019009 -229.804468) (xy 379.061025 -229.834994) (xy 379.097748 -229.871717) (xy 379.128274 -229.913733)
			(xy 379.151852 -229.960007) (xy 379.1679 -230.0094) (xy 379.176025 -230.060695) (xy 379.176534 -230.086662)
			(xy 379.176025 -230.112629) (xy 379.1679 -230.163924) (xy 379.151852 -230.213317) (xy 379.128274 -230.259591)
			(xy 379.097748 -230.301607) (xy 379.061025 -230.33833) (xy 379.019009 -230.368856) (xy 378.972735 -230.392434)
			(xy 378.923342 -230.408482) (xy 378.872047 -230.416607) (xy 378.820113 -230.416607) (xy 378.768818 -230.408482)
			(xy 378.719425 -230.392434) (xy 378.673151 -230.368856) (xy 378.631135 -230.33833) (xy 378.594412 -230.301607)
			(xy 378.563886 -230.259591) (xy 378.540308 -230.213317) (xy 378.52426 -230.163924) (xy 378.516135 -230.112629)
			(xy 378.236225 -230.112629) (xy 378.2281 -230.163924) (xy 378.212052 -230.213317) (xy 378.188474 -230.259591)
			(xy 378.157948 -230.301607) (xy 378.121225 -230.33833) (xy 378.079209 -230.368856) (xy 378.032935 -230.392434)
			(xy 377.983542 -230.408482) (xy 377.932247 -230.416607) (xy 377.880313 -230.416607) (xy 377.829018 -230.408482)
			(xy 377.779625 -230.392434) (xy 377.733351 -230.368856) (xy 377.691335 -230.33833) (xy 377.654612 -230.301607)
			(xy 377.624086 -230.259591) (xy 377.600508 -230.213317) (xy 377.58446 -230.163924) (xy 377.576335 -230.112629)
			(xy 377.296425 -230.112629) (xy 377.2883 -230.163924) (xy 377.272252 -230.213317) (xy 377.248674 -230.259591)
			(xy 377.218148 -230.301607) (xy 377.181425 -230.33833) (xy 377.139409 -230.368856) (xy 377.093135 -230.392434)
			(xy 377.043742 -230.408482) (xy 376.992447 -230.416607) (xy 376.940513 -230.416607) (xy 376.889218 -230.408482)
			(xy 376.839825 -230.392434) (xy 376.793551 -230.368856) (xy 376.751535 -230.33833) (xy 376.714812 -230.301607)
			(xy 376.684286 -230.259591) (xy 376.660708 -230.213317) (xy 376.64466 -230.163924) (xy 376.636535 -230.112629)
			(xy 376.356625 -230.112629) (xy 376.3485 -230.163924) (xy 376.332452 -230.213317) (xy 376.308874 -230.259591)
			(xy 376.278348 -230.301607) (xy 376.241625 -230.33833) (xy 376.199609 -230.368856) (xy 376.153335 -230.392434)
			(xy 376.103942 -230.408482) (xy 376.052647 -230.416607) (xy 376.000713 -230.416607) (xy 375.949418 -230.408482)
			(xy 375.900025 -230.392434) (xy 375.853751 -230.368856) (xy 375.811735 -230.33833) (xy 375.775012 -230.301607)
			(xy 375.744486 -230.259591) (xy 375.720908 -230.213317) (xy 375.70486 -230.163924) (xy 375.696735 -230.112629)
			(xy 375.417108 -230.112629) (xy 375.417108 -230.112653) (xy 375.408981 -230.163995) (xy 375.392922 -230.213433)
			(xy 375.369326 -230.25975) (xy 375.338774 -230.301805) (xy 375.302019 -230.338562) (xy 375.259965 -230.369116)
			(xy 375.21365 -230.392715) (xy 375.164212 -230.408777) (xy 375.112871 -230.416906) (xy 375.08688 -230.41737)
			(xy 375.086372 -230.41737) (xy 375.063269 -230.417021) (xy 375.017506 -230.410645) (xy 374.995186 -230.40467)
			(xy 374.992138 -230.403654) (xy 374.97766 -230.401622) (xy 374.967849 -230.402108) (xy 374.949699 -230.409573)
			(xy 374.942354 -230.4161) (xy 374.842024 -230.51643) (xy 374.835573 -230.523517) (xy 374.828121 -230.541154)
			(xy 374.827546 -230.55072) (xy 374.828054 -230.586026) (xy 374.828562 -230.62438) (xy 374.82922 -230.634391)
			(xy 374.837344 -230.652719) (xy 374.84431 -230.65994) (xy 374.84431 -230.660194) (xy 374.863525 -230.679059)
			(xy 374.896175 -230.721875) (xy 374.921454 -230.769416) (xy 374.938695 -230.820426) (xy 374.94744 -230.873556)
			(xy 374.947942 -230.900478) (xy 374.947432 -230.926445) (xy 375.227089 -230.926445) (xy 375.227089 -230.874511)
			(xy 375.235214 -230.823216) (xy 375.251262 -230.773823) (xy 375.27484 -230.727549) (xy 375.305366 -230.685533)
			(xy 375.342089 -230.64881) (xy 375.384105 -230.618284) (xy 375.430379 -230.594706) (xy 375.479772 -230.578658)
			(xy 375.531067 -230.570533) (xy 375.583001 -230.570533) (xy 375.634296 -230.578658) (xy 375.683689 -230.594706)
			(xy 375.729963 -230.618284) (xy 375.771979 -230.64881) (xy 375.808702 -230.685533) (xy 375.839228 -230.727549)
			(xy 375.862806 -230.773823) (xy 375.878854 -230.823216) (xy 375.886979 -230.874511) (xy 375.887488 -230.900478)
			(xy 375.886979 -230.926445) (xy 376.166889 -230.926445) (xy 376.166889 -230.874511) (xy 376.175014 -230.823216)
			(xy 376.191062 -230.773823) (xy 376.21464 -230.727549) (xy 376.245166 -230.685533) (xy 376.281889 -230.64881)
			(xy 376.323905 -230.618284) (xy 376.370179 -230.594706) (xy 376.419572 -230.578658) (xy 376.470867 -230.570533)
			(xy 376.522801 -230.570533) (xy 376.574096 -230.578658) (xy 376.623489 -230.594706) (xy 376.669763 -230.618284)
			(xy 376.711779 -230.64881) (xy 376.748502 -230.685533) (xy 376.779028 -230.727549) (xy 376.802606 -230.773823)
			(xy 376.818654 -230.823216) (xy 376.826779 -230.874511) (xy 376.827288 -230.900478) (xy 376.826779 -230.926445)
			(xy 377.106689 -230.926445) (xy 377.106689 -230.874511) (xy 377.114814 -230.823216) (xy 377.130862 -230.773823)
			(xy 377.15444 -230.727549) (xy 377.184966 -230.685533) (xy 377.221689 -230.64881) (xy 377.263705 -230.618284)
			(xy 377.309979 -230.594706) (xy 377.359372 -230.578658) (xy 377.410667 -230.570533) (xy 377.462601 -230.570533)
			(xy 377.513896 -230.578658) (xy 377.563289 -230.594706) (xy 377.609563 -230.618284) (xy 377.651579 -230.64881)
			(xy 377.688302 -230.685533) (xy 377.718828 -230.727549) (xy 377.742406 -230.773823) (xy 377.758454 -230.823216)
			(xy 377.766579 -230.874511) (xy 377.767088 -230.900478) (xy 377.766579 -230.926445) (xy 378.046489 -230.926445)
			(xy 378.046489 -230.874511) (xy 378.054614 -230.823216) (xy 378.070662 -230.773823) (xy 378.09424 -230.727549)
			(xy 378.124766 -230.685533) (xy 378.161489 -230.64881) (xy 378.203505 -230.618284) (xy 378.249779 -230.594706)
			(xy 378.299172 -230.578658) (xy 378.350467 -230.570533) (xy 378.402401 -230.570533) (xy 378.453696 -230.578658)
			(xy 378.503089 -230.594706) (xy 378.549363 -230.618284) (xy 378.591379 -230.64881) (xy 378.628102 -230.685533)
			(xy 378.658628 -230.727549) (xy 378.682206 -230.773823) (xy 378.698254 -230.823216) (xy 378.706379 -230.874511)
			(xy 378.706888 -230.900478) (xy 378.706379 -230.926445) (xy 378.986289 -230.926445) (xy 378.986289 -230.874511)
			(xy 378.994414 -230.823216) (xy 379.010462 -230.773823) (xy 379.03404 -230.727549) (xy 379.064566 -230.685533)
			(xy 379.101289 -230.64881) (xy 379.143305 -230.618284) (xy 379.189579 -230.594706) (xy 379.238972 -230.578658)
			(xy 379.290267 -230.570533) (xy 379.342201 -230.570533) (xy 379.393496 -230.578658) (xy 379.442889 -230.594706)
			(xy 379.489163 -230.618284) (xy 379.531179 -230.64881) (xy 379.567902 -230.685533) (xy 379.598428 -230.727549)
			(xy 379.622006 -230.773823) (xy 379.638054 -230.823216) (xy 379.646179 -230.874511) (xy 379.646688 -230.900478)
			(xy 379.646179 -230.926445) (xy 379.638054 -230.97774) (xy 379.622006 -231.027133) (xy 379.598428 -231.073407)
			(xy 379.567902 -231.115423) (xy 379.531179 -231.152146) (xy 379.489163 -231.182672) (xy 379.442889 -231.20625)
			(xy 379.393496 -231.222298) (xy 379.342201 -231.230423) (xy 379.290267 -231.230423) (xy 379.238972 -231.222298)
			(xy 379.189579 -231.20625) (xy 379.143305 -231.182672) (xy 379.101289 -231.152146) (xy 379.064566 -231.115423)
			(xy 379.03404 -231.073407) (xy 379.010462 -231.027133) (xy 378.994414 -230.97774) (xy 378.986289 -230.926445)
			(xy 378.706379 -230.926445) (xy 378.698254 -230.97774) (xy 378.682206 -231.027133) (xy 378.658628 -231.073407)
			(xy 378.628102 -231.115423) (xy 378.591379 -231.152146) (xy 378.549363 -231.182672) (xy 378.503089 -231.20625)
			(xy 378.453696 -231.222298) (xy 378.402401 -231.230423) (xy 378.350467 -231.230423) (xy 378.299172 -231.222298)
			(xy 378.249779 -231.20625) (xy 378.203505 -231.182672) (xy 378.161489 -231.152146) (xy 378.124766 -231.115423)
			(xy 378.09424 -231.073407) (xy 378.070662 -231.027133) (xy 378.054614 -230.97774) (xy 378.046489 -230.926445)
			(xy 377.766579 -230.926445) (xy 377.758454 -230.97774) (xy 377.742406 -231.027133) (xy 377.718828 -231.073407)
			(xy 377.688302 -231.115423) (xy 377.651579 -231.152146) (xy 377.609563 -231.182672) (xy 377.563289 -231.20625)
			(xy 377.513896 -231.222298) (xy 377.462601 -231.230423) (xy 377.410667 -231.230423) (xy 377.359372 -231.222298)
			(xy 377.309979 -231.20625) (xy 377.263705 -231.182672) (xy 377.221689 -231.152146) (xy 377.184966 -231.115423)
			(xy 377.15444 -231.073407) (xy 377.130862 -231.027133) (xy 377.114814 -230.97774) (xy 377.106689 -230.926445)
			(xy 376.826779 -230.926445) (xy 376.818654 -230.97774) (xy 376.802606 -231.027133) (xy 376.779028 -231.073407)
			(xy 376.748502 -231.115423) (xy 376.711779 -231.152146) (xy 376.669763 -231.182672) (xy 376.623489 -231.20625)
			(xy 376.574096 -231.222298) (xy 376.522801 -231.230423) (xy 376.470867 -231.230423) (xy 376.419572 -231.222298)
			(xy 376.370179 -231.20625) (xy 376.323905 -231.182672) (xy 376.281889 -231.152146) (xy 376.245166 -231.115423)
			(xy 376.21464 -231.073407) (xy 376.191062 -231.027133) (xy 376.175014 -230.97774) (xy 376.166889 -230.926445)
			(xy 375.886979 -230.926445) (xy 375.878854 -230.97774) (xy 375.862806 -231.027133) (xy 375.839228 -231.073407)
			(xy 375.808702 -231.115423) (xy 375.771979 -231.152146) (xy 375.729963 -231.182672) (xy 375.683689 -231.20625)
			(xy 375.634296 -231.222298) (xy 375.583001 -231.230423) (xy 375.531067 -231.230423) (xy 375.479772 -231.222298)
			(xy 375.430379 -231.20625) (xy 375.384105 -231.182672) (xy 375.342089 -231.152146) (xy 375.305366 -231.115423)
			(xy 375.27484 -231.073407) (xy 375.251262 -231.027133) (xy 375.235214 -230.97774) (xy 375.227089 -230.926445)
			(xy 374.947432 -230.926445) (xy 374.947432 -230.926465) (xy 374.939302 -230.9778) (xy 374.923241 -231.02723)
			(xy 374.899645 -231.07354) (xy 374.869095 -231.115588) (xy 374.832344 -231.152339) (xy 374.790296 -231.182889)
			(xy 374.743986 -231.206485) (xy 374.694556 -231.222546) (xy 374.643221 -231.230676) (xy 374.591247 -231.230676)
			(xy 374.539912 -231.222546) (xy 374.490482 -231.206485) (xy 374.444172 -231.182889) (xy 374.402124 -231.152339)
			(xy 374.365373 -231.115588) (xy 374.334823 -231.07354) (xy 374.311227 -231.02723) (xy 374.295166 -230.9778)
			(xy 374.287036 -230.926465) (xy 374.286526 -230.900478) (xy 374.286526 -230.900224) (xy 374.286874 -230.877895)
			(xy 374.292852 -230.833638) (xy 374.304742 -230.790592) (xy 374.313196 -230.769922) (xy 374.315228 -230.76535)
			(xy 374.319546 -230.745284) (xy 374.319343 -230.738679) (xy 374.315856 -230.725938) (xy 374.312688 -230.720138)
			(xy 374.292876 -230.689404) (xy 374.265698 -230.64724) (xy 374.258343 -230.637184) (xy 374.236481 -230.625301)
			(xy 374.224042 -230.624634) (xy 374.070626 -230.624634) (xy 374.058195 -230.62535) (xy 374.036329 -230.637198)
			(xy 374.02897 -230.64724) (xy 374.001792 -230.689404) (xy 373.98198 -230.720138) (xy 373.978851 -230.725953)
			(xy 373.975373 -230.738686) (xy 373.975122 -230.745284) (xy 373.97944 -230.76535) (xy 373.981472 -230.769922)
			(xy 373.989915 -230.790596) (xy 374.001799 -230.833643) (xy 374.007793 -230.877895) (xy 374.008142 -230.900224)
			(xy 374.008142 -230.900478) (xy 374.007632 -230.926465) (xy 373.999502 -230.9778) (xy 373.983441 -231.02723)
			(xy 373.959845 -231.07354) (xy 373.929295 -231.115588) (xy 373.892544 -231.152339) (xy 373.850496 -231.182889)
			(xy 373.804186 -231.206485) (xy 373.754756 -231.222546) (xy 373.703421 -231.230676) (xy 373.651447 -231.230676)
			(xy 373.600112 -231.222546) (xy 373.550682 -231.206485) (xy 373.504372 -231.182889) (xy 373.462324 -231.152339)
			(xy 373.425573 -231.115588) (xy 373.395023 -231.07354) (xy 373.371427 -231.02723) (xy 373.355366 -230.9778)
			(xy 373.347236 -230.926465) (xy 373.346726 -230.900478) (xy 373.346726 -230.900224) (xy 373.347074 -230.877895)
			(xy 373.353052 -230.833638) (xy 373.364942 -230.790592) (xy 373.373396 -230.769922) (xy 373.375428 -230.76535)
			(xy 373.379746 -230.745284) (xy 373.379543 -230.738679) (xy 373.376056 -230.725938) (xy 373.372888 -230.720138)
			(xy 373.353076 -230.689404) (xy 373.325898 -230.64724) (xy 373.318543 -230.637184) (xy 373.296681 -230.625301)
			(xy 373.284242 -230.624634) (xy 373.130826 -230.624634) (xy 373.118395 -230.62535) (xy 373.096529 -230.637198)
			(xy 373.08917 -230.64724) (xy 373.061992 -230.689404) (xy 373.04218 -230.720138) (xy 373.039051 -230.725953)
			(xy 373.035573 -230.738686) (xy 373.035322 -230.745284) (xy 373.03964 -230.76535) (xy 373.041672 -230.769922)
			(xy 373.050115 -230.790596) (xy 373.061999 -230.833643) (xy 373.067993 -230.877895) (xy 373.068342 -230.900224)
			(xy 373.068342 -230.900478) (xy 373.067832 -230.926465) (xy 373.059702 -230.9778) (xy 373.043641 -231.02723)
			(xy 373.020045 -231.07354) (xy 372.989495 -231.115588) (xy 372.952744 -231.152339) (xy 372.910696 -231.182889)
			(xy 372.864386 -231.206485) (xy 372.814956 -231.222546) (xy 372.763621 -231.230676) (xy 372.711647 -231.230676)
			(xy 372.660312 -231.222546) (xy 372.610882 -231.206485) (xy 372.564572 -231.182889) (xy 372.522524 -231.152339)
			(xy 372.485773 -231.115588) (xy 372.455223 -231.07354) (xy 372.431627 -231.02723) (xy 372.415566 -230.9778)
			(xy 372.407436 -230.926465) (xy 372.406926 -230.900478) (xy 372.406926 -230.900224) (xy 372.407274 -230.877895)
			(xy 372.413252 -230.833638) (xy 372.425142 -230.790592) (xy 372.433596 -230.769922) (xy 372.435628 -230.76535)
			(xy 372.439946 -230.745284) (xy 372.439743 -230.738679) (xy 372.436256 -230.725938) (xy 372.433088 -230.720138)
			(xy 372.413276 -230.689404) (xy 372.386098 -230.64724) (xy 372.378743 -230.637184) (xy 372.356881 -230.625301)
			(xy 372.344442 -230.624634) (xy 372.191026 -230.624634) (xy 372.178595 -230.62535) (xy 372.156729 -230.637198)
			(xy 372.14937 -230.64724) (xy 372.122192 -230.689404) (xy 372.10238 -230.720138) (xy 372.099251 -230.725953)
			(xy 372.095773 -230.738686) (xy 372.095522 -230.745284) (xy 372.09984 -230.76535) (xy 372.101872 -230.769922)
			(xy 372.110315 -230.790596) (xy 372.122199 -230.833643) (xy 372.128193 -230.877895) (xy 372.128542 -230.900224)
			(xy 372.128542 -230.900478) (xy 372.128032 -230.926465) (xy 372.119902 -230.9778) (xy 372.103841 -231.02723)
			(xy 372.080245 -231.07354) (xy 372.049695 -231.115588) (xy 372.012944 -231.152339) (xy 371.970896 -231.182889)
			(xy 371.924586 -231.206485) (xy 371.875156 -231.222546) (xy 371.823821 -231.230676) (xy 371.771847 -231.230676)
			(xy 371.720512 -231.222546) (xy 371.671082 -231.206485) (xy 371.624772 -231.182889) (xy 371.582724 -231.152339)
			(xy 371.545973 -231.115588) (xy 371.515423 -231.07354) (xy 371.491827 -231.02723) (xy 371.475766 -230.9778)
			(xy 371.467636 -230.926465) (xy 371.467126 -230.900478) (xy 371.467126 -230.900224) (xy 371.467474 -230.877895)
			(xy 371.473452 -230.833638) (xy 371.485342 -230.790592) (xy 371.493796 -230.769922) (xy 371.495828 -230.76535)
			(xy 371.500146 -230.745284) (xy 371.499943 -230.738679) (xy 371.496456 -230.725938) (xy 371.493288 -230.720138)
			(xy 371.473476 -230.689404) (xy 371.446298 -230.64724) (xy 371.438943 -230.637184) (xy 371.417081 -230.625301)
			(xy 371.404642 -230.624634) (xy 371.251226 -230.624634) (xy 371.238795 -230.62535) (xy 371.216929 -230.637198)
			(xy 371.20957 -230.64724) (xy 371.182392 -230.689404) (xy 371.16258 -230.720138) (xy 371.159451 -230.725953)
			(xy 371.155973 -230.738686) (xy 371.155722 -230.745284) (xy 371.16004 -230.76535) (xy 371.162072 -230.769922)
			(xy 371.170515 -230.790596) (xy 371.182399 -230.833643) (xy 371.188393 -230.877895) (xy 371.188742 -230.900224)
			(xy 371.188742 -230.900478) (xy 371.188232 -230.926465) (xy 371.180102 -230.9778) (xy 371.164041 -231.02723)
			(xy 371.140445 -231.07354) (xy 371.109895 -231.115588) (xy 371.073144 -231.152339) (xy 371.031096 -231.182889)
			(xy 370.984786 -231.206485) (xy 370.935356 -231.222546) (xy 370.884021 -231.230676) (xy 370.832047 -231.230676)
			(xy 370.780712 -231.222546) (xy 370.731282 -231.206485) (xy 370.684972 -231.182889) (xy 370.642924 -231.152339)
			(xy 370.606173 -231.115588) (xy 370.575623 -231.07354) (xy 370.552027 -231.02723) (xy 370.535966 -230.9778)
			(xy 370.527836 -230.926465) (xy 370.527326 -230.900478) (xy 370.527326 -230.900224) (xy 370.527674 -230.877895)
			(xy 370.533652 -230.833638) (xy 370.545542 -230.790592) (xy 370.553996 -230.769922) (xy 370.556028 -230.76535)
			(xy 370.560346 -230.745284) (xy 370.560143 -230.738679) (xy 370.556656 -230.725938) (xy 370.553488 -230.720138)
			(xy 370.533676 -230.689404) (xy 370.506498 -230.64724) (xy 370.499143 -230.637184) (xy 370.477281 -230.625301)
			(xy 370.464842 -230.624634) (xy 370.339112 -230.624634) (xy 370.326798 -230.625253) (xy 370.305069 -230.636841)
			(xy 370.29771 -230.646732) (xy 370.270786 -230.687118) (xy 370.25072 -230.71709) (xy 370.247121 -230.723167)
			(xy 370.243116 -230.736703) (xy 370.242846 -230.74376) (xy 370.246656 -230.763064) (xy 370.248434 -230.767636)
			(xy 370.25655 -230.788832) (xy 370.267964 -230.832762) (xy 370.273718 -230.877784) (xy 370.274088 -230.900478)
			(xy 370.27359 -230.927127) (xy 370.265647 -230.979831) (xy 370.249937 -231.030761) (xy 370.226811 -231.078782)
			(xy 370.196787 -231.122819) (xy 370.160535 -231.16189) (xy 370.118864 -231.195121) (xy 370.072706 -231.22177)
			(xy 370.023092 -231.241242) (xy 369.97113 -231.253102) (xy 369.91798 -231.257086) (xy 369.86483 -231.253102)
			(xy 369.812868 -231.241242) (xy 369.763254 -231.22177) (xy 369.717096 -231.195121) (xy 369.675425 -231.16189)
			(xy 369.639173 -231.122819) (xy 369.609149 -231.078782) (xy 369.586023 -231.030761) (xy 369.570313 -230.979831)
			(xy 369.56237 -230.927127) (xy 369.561872 -230.900478) (xy 369.562228 -230.877784) (xy 369.56799 -230.832762)
			(xy 369.579418 -230.788836) (xy 369.587526 -230.767636) (xy 369.589304 -230.763064) (xy 369.593114 -230.74376)
			(xy 369.592838 -230.736703) (xy 369.58884 -230.723165) (xy 369.58524 -230.71709) (xy 369.565174 -230.687118)
			(xy 369.53825 -230.646732) (xy 369.530841 -230.636901) (xy 369.50914 -230.625334) (xy 369.496848 -230.624634)
			(xy 369.399312 -230.624634) (xy 369.387573 -230.625254) (xy 369.366629 -230.63586) (xy 369.35918 -230.644954)
			(xy 369.309904 -230.719122) (xy 369.306862 -230.724824) (xy 369.303512 -230.737301) (xy 369.3033 -230.74376)
			(xy 369.30711 -230.763064) (xy 369.308888 -230.767636) (xy 369.317013 -230.788786) (xy 369.328439 -230.832629)
			(xy 369.33419 -230.87757) (xy 369.334542 -230.900224) (xy 369.334542 -230.900478) (xy 369.333995 -230.928463)
			(xy 369.325243 -230.983745) (xy 369.30795 -231.036977) (xy 369.282544 -231.086849) (xy 369.249649 -231.132132)
			(xy 369.210075 -231.171712) (xy 369.164797 -231.204615) (xy 369.114929 -231.230029) (xy 369.0617 -231.24733)
			(xy 369.006419 -231.25609) (xy 368.978434 -231.256586) (xy 368.96675 -231.256332) (xy 368.956679 -231.25652)
			(xy 368.93793 -231.263838) (xy 368.930428 -231.270556) (xy 368.878358 -231.320594) (xy 368.871428 -231.327881)
			(xy 368.863548 -231.346362) (xy 368.863118 -231.356408) (xy 368.863118 -231.740515) (xy 369.118643 -231.740515)
			(xy 369.118643 -231.688581) (xy 369.126768 -231.637286) (xy 369.142816 -231.587893) (xy 369.166394 -231.541619)
			(xy 369.19692 -231.499603) (xy 369.233643 -231.46288) (xy 369.275659 -231.432354) (xy 369.321933 -231.408776)
			(xy 369.371326 -231.392728) (xy 369.422621 -231.384603) (xy 369.474555 -231.384603) (xy 369.52585 -231.392728)
			(xy 369.575243 -231.408776) (xy 369.621517 -231.432354) (xy 369.663533 -231.46288) (xy 369.700256 -231.499603)
			(xy 369.730782 -231.541619) (xy 369.75436 -231.587893) (xy 369.770408 -231.637286) (xy 369.778533 -231.688581)
			(xy 369.779042 -231.714548) (xy 369.778533 -231.740515) (xy 370.058189 -231.740515) (xy 370.058189 -231.688581)
			(xy 370.066314 -231.637286) (xy 370.082362 -231.587893) (xy 370.10594 -231.541619) (xy 370.136466 -231.499603)
			(xy 370.173189 -231.46288) (xy 370.215205 -231.432354) (xy 370.261479 -231.408776) (xy 370.310872 -231.392728)
			(xy 370.362167 -231.384603) (xy 370.414101 -231.384603) (xy 370.465396 -231.392728) (xy 370.514789 -231.408776)
			(xy 370.561063 -231.432354) (xy 370.603079 -231.46288) (xy 370.639802 -231.499603) (xy 370.670328 -231.541619)
			(xy 370.693906 -231.587893) (xy 370.709954 -231.637286) (xy 370.718079 -231.688581) (xy 370.718588 -231.714548)
			(xy 370.718079 -231.740515) (xy 370.997735 -231.740515) (xy 370.997735 -231.688581) (xy 371.00586 -231.637286)
			(xy 371.021908 -231.587893) (xy 371.045486 -231.541619) (xy 371.076012 -231.499603) (xy 371.112735 -231.46288)
			(xy 371.154751 -231.432354) (xy 371.201025 -231.408776) (xy 371.250418 -231.392728) (xy 371.301713 -231.384603)
			(xy 371.353647 -231.384603) (xy 371.404942 -231.392728) (xy 371.454335 -231.408776) (xy 371.500609 -231.432354)
			(xy 371.542625 -231.46288) (xy 371.579348 -231.499603) (xy 371.609874 -231.541619) (xy 371.633452 -231.587893)
			(xy 371.6495 -231.637286) (xy 371.657625 -231.688581) (xy 371.658134 -231.714548) (xy 371.657625 -231.740515)
			(xy 371.937535 -231.740515) (xy 371.937535 -231.688581) (xy 371.94566 -231.637286) (xy 371.961708 -231.587893)
			(xy 371.985286 -231.541619) (xy 372.015812 -231.499603) (xy 372.052535 -231.46288) (xy 372.094551 -231.432354)
			(xy 372.140825 -231.408776) (xy 372.190218 -231.392728) (xy 372.241513 -231.384603) (xy 372.293447 -231.384603)
			(xy 372.344742 -231.392728) (xy 372.394135 -231.408776) (xy 372.440409 -231.432354) (xy 372.482425 -231.46288)
			(xy 372.519148 -231.499603) (xy 372.549674 -231.541619) (xy 372.573252 -231.587893) (xy 372.5893 -231.637286)
			(xy 372.597425 -231.688581) (xy 372.597934 -231.714548) (xy 372.597425 -231.740515) (xy 372.877335 -231.740515)
			(xy 372.877335 -231.688581) (xy 372.88546 -231.637286) (xy 372.901508 -231.587893) (xy 372.925086 -231.541619)
			(xy 372.955612 -231.499603) (xy 372.992335 -231.46288) (xy 373.034351 -231.432354) (xy 373.080625 -231.408776)
			(xy 373.130018 -231.392728) (xy 373.181313 -231.384603) (xy 373.233247 -231.384603) (xy 373.284542 -231.392728)
			(xy 373.333935 -231.408776) (xy 373.380209 -231.432354) (xy 373.422225 -231.46288) (xy 373.458948 -231.499603)
			(xy 373.489474 -231.541619) (xy 373.513052 -231.587893) (xy 373.5291 -231.637286) (xy 373.537225 -231.688581)
			(xy 373.537734 -231.714548) (xy 373.537225 -231.740515) (xy 373.817135 -231.740515) (xy 373.817135 -231.688581)
			(xy 373.82526 -231.637286) (xy 373.841308 -231.587893) (xy 373.864886 -231.541619) (xy 373.895412 -231.499603)
			(xy 373.932135 -231.46288) (xy 373.974151 -231.432354) (xy 374.020425 -231.408776) (xy 374.069818 -231.392728)
			(xy 374.121113 -231.384603) (xy 374.173047 -231.384603) (xy 374.224342 -231.392728) (xy 374.273735 -231.408776)
			(xy 374.320009 -231.432354) (xy 374.362025 -231.46288) (xy 374.398748 -231.499603) (xy 374.429274 -231.541619)
			(xy 374.452852 -231.587893) (xy 374.4689 -231.637286) (xy 374.477025 -231.688581) (xy 374.477534 -231.714548)
			(xy 374.477025 -231.740515) (xy 374.756935 -231.740515) (xy 374.756935 -231.688581) (xy 374.76506 -231.637286)
			(xy 374.781108 -231.587893) (xy 374.804686 -231.541619) (xy 374.835212 -231.499603) (xy 374.871935 -231.46288)
			(xy 374.913951 -231.432354) (xy 374.960225 -231.408776) (xy 375.009618 -231.392728) (xy 375.060913 -231.384603)
			(xy 375.112847 -231.384603) (xy 375.164142 -231.392728) (xy 375.213535 -231.408776) (xy 375.259809 -231.432354)
			(xy 375.301825 -231.46288) (xy 375.338548 -231.499603) (xy 375.369074 -231.541619) (xy 375.392652 -231.587893)
			(xy 375.4087 -231.637286) (xy 375.416825 -231.688581) (xy 375.417334 -231.714548) (xy 375.416825 -231.740515)
			(xy 375.696735 -231.740515) (xy 375.696735 -231.688581) (xy 375.70486 -231.637286) (xy 375.720908 -231.587893)
			(xy 375.744486 -231.541619) (xy 375.775012 -231.499603) (xy 375.811735 -231.46288) (xy 375.853751 -231.432354)
			(xy 375.900025 -231.408776) (xy 375.949418 -231.392728) (xy 376.000713 -231.384603) (xy 376.052647 -231.384603)
			(xy 376.103942 -231.392728) (xy 376.153335 -231.408776) (xy 376.199609 -231.432354) (xy 376.241625 -231.46288)
			(xy 376.278348 -231.499603) (xy 376.308874 -231.541619) (xy 376.332452 -231.587893) (xy 376.3485 -231.637286)
			(xy 376.356625 -231.688581) (xy 376.357134 -231.714548) (xy 376.356625 -231.740515) (xy 376.636789 -231.740515)
			(xy 376.636789 -231.688581) (xy 376.644914 -231.637286) (xy 376.660962 -231.587893) (xy 376.68454 -231.541619)
			(xy 376.715066 -231.499603) (xy 376.751789 -231.46288) (xy 376.793805 -231.432354) (xy 376.840079 -231.408776)
			(xy 376.889472 -231.392728) (xy 376.940767 -231.384603) (xy 376.992701 -231.384603) (xy 377.043996 -231.392728)
			(xy 377.093389 -231.408776) (xy 377.139663 -231.432354) (xy 377.181679 -231.46288) (xy 377.218402 -231.499603)
			(xy 377.248928 -231.541619) (xy 377.272506 -231.587893) (xy 377.288554 -231.637286) (xy 377.296679 -231.688581)
			(xy 377.297188 -231.714548) (xy 377.296679 -231.740515) (xy 377.576335 -231.740515) (xy 377.576335 -231.688581)
			(xy 377.58446 -231.637286) (xy 377.600508 -231.587893) (xy 377.624086 -231.541619) (xy 377.654612 -231.499603)
			(xy 377.691335 -231.46288) (xy 377.733351 -231.432354) (xy 377.779625 -231.408776) (xy 377.829018 -231.392728)
			(xy 377.880313 -231.384603) (xy 377.932247 -231.384603) (xy 377.983542 -231.392728) (xy 378.032935 -231.408776)
			(xy 378.079209 -231.432354) (xy 378.121225 -231.46288) (xy 378.157948 -231.499603) (xy 378.188474 -231.541619)
			(xy 378.212052 -231.587893) (xy 378.2281 -231.637286) (xy 378.236225 -231.688581) (xy 378.236734 -231.714548)
			(xy 378.236225 -231.740515) (xy 378.516135 -231.740515) (xy 378.516135 -231.688581) (xy 378.52426 -231.637286)
			(xy 378.540308 -231.587893) (xy 378.563886 -231.541619) (xy 378.594412 -231.499603) (xy 378.631135 -231.46288)
			(xy 378.673151 -231.432354) (xy 378.719425 -231.408776) (xy 378.768818 -231.392728) (xy 378.820113 -231.384603)
			(xy 378.872047 -231.384603) (xy 378.923342 -231.392728) (xy 378.972735 -231.408776) (xy 379.019009 -231.432354)
			(xy 379.061025 -231.46288) (xy 379.097748 -231.499603) (xy 379.128274 -231.541619) (xy 379.151852 -231.587893)
			(xy 379.1679 -231.637286) (xy 379.176025 -231.688581) (xy 379.176534 -231.714548) (xy 379.176025 -231.740515)
			(xy 379.455935 -231.740515) (xy 379.455935 -231.688581) (xy 379.46406 -231.637286) (xy 379.480108 -231.587893)
			(xy 379.503686 -231.541619) (xy 379.534212 -231.499603) (xy 379.570935 -231.46288) (xy 379.612951 -231.432354)
			(xy 379.659225 -231.408776) (xy 379.708618 -231.392728) (xy 379.759913 -231.384603) (xy 379.811847 -231.384603)
			(xy 379.863142 -231.392728) (xy 379.912535 -231.408776) (xy 379.958809 -231.432354) (xy 380.000825 -231.46288)
			(xy 380.037548 -231.499603) (xy 380.068074 -231.541619) (xy 380.091652 -231.587893) (xy 380.1077 -231.637286)
			(xy 380.115825 -231.688581) (xy 380.116334 -231.714548) (xy 380.115825 -231.740515) (xy 380.1077 -231.79181)
			(xy 380.091652 -231.841203) (xy 380.068074 -231.887477) (xy 380.037548 -231.929493) (xy 380.000825 -231.966216)
			(xy 379.958809 -231.996742) (xy 379.912535 -232.02032) (xy 379.863142 -232.036368) (xy 379.811847 -232.044493)
			(xy 379.759913 -232.044493) (xy 379.708618 -232.036368) (xy 379.659225 -232.02032) (xy 379.612951 -231.996742)
			(xy 379.570935 -231.966216) (xy 379.534212 -231.929493) (xy 379.503686 -231.887477) (xy 379.480108 -231.841203)
			(xy 379.46406 -231.79181) (xy 379.455935 -231.740515) (xy 379.176025 -231.740515) (xy 379.1679 -231.79181)
			(xy 379.151852 -231.841203) (xy 379.128274 -231.887477) (xy 379.097748 -231.929493) (xy 379.061025 -231.966216)
			(xy 379.019009 -231.996742) (xy 378.972735 -232.02032) (xy 378.923342 -232.036368) (xy 378.872047 -232.044493)
			(xy 378.820113 -232.044493) (xy 378.768818 -232.036368) (xy 378.719425 -232.02032) (xy 378.673151 -231.996742)
			(xy 378.631135 -231.966216) (xy 378.594412 -231.929493) (xy 378.563886 -231.887477) (xy 378.540308 -231.841203)
			(xy 378.52426 -231.79181) (xy 378.516135 -231.740515) (xy 378.236225 -231.740515) (xy 378.2281 -231.79181)
			(xy 378.212052 -231.841203) (xy 378.188474 -231.887477) (xy 378.157948 -231.929493) (xy 378.121225 -231.966216)
			(xy 378.079209 -231.996742) (xy 378.032935 -232.02032) (xy 377.983542 -232.036368) (xy 377.932247 -232.044493)
			(xy 377.880313 -232.044493) (xy 377.829018 -232.036368) (xy 377.779625 -232.02032) (xy 377.733351 -231.996742)
			(xy 377.691335 -231.966216) (xy 377.654612 -231.929493) (xy 377.624086 -231.887477) (xy 377.600508 -231.841203)
			(xy 377.58446 -231.79181) (xy 377.576335 -231.740515) (xy 377.296679 -231.740515) (xy 377.288554 -231.79181)
			(xy 377.272506 -231.841203) (xy 377.248928 -231.887477) (xy 377.218402 -231.929493) (xy 377.181679 -231.966216)
			(xy 377.139663 -231.996742) (xy 377.093389 -232.02032) (xy 377.043996 -232.036368) (xy 376.992701 -232.044493)
			(xy 376.940767 -232.044493) (xy 376.889472 -232.036368) (xy 376.840079 -232.02032) (xy 376.793805 -231.996742)
			(xy 376.751789 -231.966216) (xy 376.715066 -231.929493) (xy 376.68454 -231.887477) (xy 376.660962 -231.841203)
			(xy 376.644914 -231.79181) (xy 376.636789 -231.740515) (xy 376.356625 -231.740515) (xy 376.3485 -231.79181)
			(xy 376.332452 -231.841203) (xy 376.308874 -231.887477) (xy 376.278348 -231.929493) (xy 376.241625 -231.966216)
			(xy 376.199609 -231.996742) (xy 376.153335 -232.02032) (xy 376.103942 -232.036368) (xy 376.052647 -232.044493)
			(xy 376.000713 -232.044493) (xy 375.949418 -232.036368) (xy 375.900025 -232.02032) (xy 375.853751 -231.996742)
			(xy 375.811735 -231.966216) (xy 375.775012 -231.929493) (xy 375.744486 -231.887477) (xy 375.720908 -231.841203)
			(xy 375.70486 -231.79181) (xy 375.696735 -231.740515) (xy 375.416825 -231.740515) (xy 375.4087 -231.79181)
			(xy 375.392652 -231.841203) (xy 375.369074 -231.887477) (xy 375.338548 -231.929493) (xy 375.301825 -231.966216)
			(xy 375.259809 -231.996742) (xy 375.213535 -232.02032) (xy 375.164142 -232.036368) (xy 375.112847 -232.044493)
			(xy 375.060913 -232.044493) (xy 375.009618 -232.036368) (xy 374.960225 -232.02032) (xy 374.913951 -231.996742)
			(xy 374.871935 -231.966216) (xy 374.835212 -231.929493) (xy 374.804686 -231.887477) (xy 374.781108 -231.841203)
			(xy 374.76506 -231.79181) (xy 374.756935 -231.740515) (xy 374.477025 -231.740515) (xy 374.4689 -231.79181)
			(xy 374.452852 -231.841203) (xy 374.429274 -231.887477) (xy 374.398748 -231.929493) (xy 374.362025 -231.966216)
			(xy 374.320009 -231.996742) (xy 374.273735 -232.02032) (xy 374.224342 -232.036368) (xy 374.173047 -232.044493)
			(xy 374.121113 -232.044493) (xy 374.069818 -232.036368) (xy 374.020425 -232.02032) (xy 373.974151 -231.996742)
			(xy 373.932135 -231.966216) (xy 373.895412 -231.929493) (xy 373.864886 -231.887477) (xy 373.841308 -231.841203)
			(xy 373.82526 -231.79181) (xy 373.817135 -231.740515) (xy 373.537225 -231.740515) (xy 373.5291 -231.79181)
			(xy 373.513052 -231.841203) (xy 373.489474 -231.887477) (xy 373.458948 -231.929493) (xy 373.422225 -231.966216)
			(xy 373.380209 -231.996742) (xy 373.333935 -232.02032) (xy 373.284542 -232.036368) (xy 373.233247 -232.044493)
			(xy 373.181313 -232.044493) (xy 373.130018 -232.036368) (xy 373.080625 -232.02032) (xy 373.034351 -231.996742)
			(xy 372.992335 -231.966216) (xy 372.955612 -231.929493) (xy 372.925086 -231.887477) (xy 372.901508 -231.841203)
			(xy 372.88546 -231.79181) (xy 372.877335 -231.740515) (xy 372.597425 -231.740515) (xy 372.5893 -231.79181)
			(xy 372.573252 -231.841203) (xy 372.549674 -231.887477) (xy 372.519148 -231.929493) (xy 372.482425 -231.966216)
			(xy 372.440409 -231.996742) (xy 372.394135 -232.02032) (xy 372.344742 -232.036368) (xy 372.293447 -232.044493)
			(xy 372.241513 -232.044493) (xy 372.190218 -232.036368) (xy 372.140825 -232.02032) (xy 372.094551 -231.996742)
			(xy 372.052535 -231.966216) (xy 372.015812 -231.929493) (xy 371.985286 -231.887477) (xy 371.961708 -231.841203)
			(xy 371.94566 -231.79181) (xy 371.937535 -231.740515) (xy 371.657625 -231.740515) (xy 371.6495 -231.79181)
			(xy 371.633452 -231.841203) (xy 371.609874 -231.887477) (xy 371.579348 -231.929493) (xy 371.542625 -231.966216)
			(xy 371.500609 -231.996742) (xy 371.454335 -232.02032) (xy 371.404942 -232.036368) (xy 371.353647 -232.044493)
			(xy 371.301713 -232.044493) (xy 371.250418 -232.036368) (xy 371.201025 -232.02032) (xy 371.154751 -231.996742)
			(xy 371.112735 -231.966216) (xy 371.076012 -231.929493) (xy 371.045486 -231.887477) (xy 371.021908 -231.841203)
			(xy 371.00586 -231.79181) (xy 370.997735 -231.740515) (xy 370.718079 -231.740515) (xy 370.709954 -231.79181)
			(xy 370.693906 -231.841203) (xy 370.670328 -231.887477) (xy 370.639802 -231.929493) (xy 370.603079 -231.966216)
			(xy 370.561063 -231.996742) (xy 370.514789 -232.02032) (xy 370.465396 -232.036368) (xy 370.414101 -232.044493)
			(xy 370.362167 -232.044493) (xy 370.310872 -232.036368) (xy 370.261479 -232.02032) (xy 370.215205 -231.996742)
			(xy 370.173189 -231.966216) (xy 370.136466 -231.929493) (xy 370.10594 -231.887477) (xy 370.082362 -231.841203)
			(xy 370.066314 -231.79181) (xy 370.058189 -231.740515) (xy 369.778533 -231.740515) (xy 369.770408 -231.79181)
			(xy 369.75436 -231.841203) (xy 369.730782 -231.887477) (xy 369.700256 -231.929493) (xy 369.663533 -231.966216)
			(xy 369.621517 -231.996742) (xy 369.575243 -232.02032) (xy 369.52585 -232.036368) (xy 369.474555 -232.044493)
			(xy 369.422621 -232.044493) (xy 369.371326 -232.036368) (xy 369.321933 -232.02032) (xy 369.275659 -231.996742)
			(xy 369.233643 -231.966216) (xy 369.19692 -231.929493) (xy 369.166394 -231.887477) (xy 369.142816 -231.841203)
			(xy 369.126768 -231.79181) (xy 369.118643 -231.740515) (xy 368.863118 -231.740515) (xy 368.863118 -232.072434)
			(xy 368.863592 -232.082009) (xy 368.870766 -232.099772) (xy 368.877088 -232.106978) (xy 368.902234 -232.131362)
			(xy 368.930428 -232.158286) (xy 368.937932 -232.165012) (xy 368.956675 -232.172363) (xy 368.96675 -232.17251)
			(xy 368.978434 -232.172256) (xy 369.005084 -232.172756) (xy 369.057789 -232.180705) (xy 369.108721 -232.196419)
			(xy 369.156741 -232.219549) (xy 369.200779 -232.249577) (xy 369.239849 -232.285833) (xy 369.27308 -232.327506)
			(xy 369.299729 -232.373667) (xy 369.319201 -232.423284) (xy 369.331061 -232.475248) (xy 369.335044 -232.5284)
			(xy 369.333101 -232.554331) (xy 369.588289 -232.554331) (xy 369.588289 -232.502397) (xy 369.596414 -232.451102)
			(xy 369.612462 -232.401709) (xy 369.63604 -232.355435) (xy 369.666566 -232.313419) (xy 369.703289 -232.276696)
			(xy 369.745305 -232.24617) (xy 369.791579 -232.222592) (xy 369.840972 -232.206544) (xy 369.892267 -232.198419)
			(xy 369.944201 -232.198419) (xy 369.995496 -232.206544) (xy 370.044889 -232.222592) (xy 370.091163 -232.24617)
			(xy 370.133179 -232.276696) (xy 370.169902 -232.313419) (xy 370.200428 -232.355435) (xy 370.224006 -232.401709)
			(xy 370.240054 -232.451102) (xy 370.248179 -232.502397) (xy 370.248688 -232.528364) (xy 370.248179 -232.554331)
			(xy 370.528089 -232.554331) (xy 370.528089 -232.502397) (xy 370.536214 -232.451102) (xy 370.552262 -232.401709)
			(xy 370.57584 -232.355435) (xy 370.606366 -232.313419) (xy 370.643089 -232.276696) (xy 370.685105 -232.24617)
			(xy 370.731379 -232.222592) (xy 370.780772 -232.206544) (xy 370.832067 -232.198419) (xy 370.884001 -232.198419)
			(xy 370.935296 -232.206544) (xy 370.984689 -232.222592) (xy 371.030963 -232.24617) (xy 371.072979 -232.276696)
			(xy 371.109702 -232.313419) (xy 371.140228 -232.355435) (xy 371.163806 -232.401709) (xy 371.179854 -232.451102)
			(xy 371.187979 -232.502397) (xy 371.188488 -232.528364) (xy 371.187979 -232.554331) (xy 371.467889 -232.554331)
			(xy 371.467889 -232.502397) (xy 371.476014 -232.451102) (xy 371.492062 -232.401709) (xy 371.51564 -232.355435)
			(xy 371.546166 -232.313419) (xy 371.582889 -232.276696) (xy 371.624905 -232.24617) (xy 371.671179 -232.222592)
			(xy 371.720572 -232.206544) (xy 371.771867 -232.198419) (xy 371.823801 -232.198419) (xy 371.875096 -232.206544)
			(xy 371.924489 -232.222592) (xy 371.970763 -232.24617) (xy 372.012779 -232.276696) (xy 372.049502 -232.313419)
			(xy 372.080028 -232.355435) (xy 372.103606 -232.401709) (xy 372.119654 -232.451102) (xy 372.127779 -232.502397)
			(xy 372.128288 -232.528364) (xy 372.127779 -232.554331) (xy 372.407689 -232.554331) (xy 372.407689 -232.502397)
			(xy 372.415814 -232.451102) (xy 372.431862 -232.401709) (xy 372.45544 -232.355435) (xy 372.485966 -232.313419)
			(xy 372.522689 -232.276696) (xy 372.564705 -232.24617) (xy 372.610979 -232.222592) (xy 372.660372 -232.206544)
			(xy 372.711667 -232.198419) (xy 372.763601 -232.198419) (xy 372.814896 -232.206544) (xy 372.864289 -232.222592)
			(xy 372.910563 -232.24617) (xy 372.952579 -232.276696) (xy 372.989302 -232.313419) (xy 373.019828 -232.355435)
			(xy 373.043406 -232.401709) (xy 373.059454 -232.451102) (xy 373.067579 -232.502397) (xy 373.068088 -232.528364)
			(xy 373.067579 -232.554331) (xy 373.347489 -232.554331) (xy 373.347489 -232.502397) (xy 373.355614 -232.451102)
			(xy 373.371662 -232.401709) (xy 373.39524 -232.355435) (xy 373.425766 -232.313419) (xy 373.462489 -232.276696)
			(xy 373.504505 -232.24617) (xy 373.550779 -232.222592) (xy 373.600172 -232.206544) (xy 373.651467 -232.198419)
			(xy 373.703401 -232.198419) (xy 373.754696 -232.206544) (xy 373.804089 -232.222592) (xy 373.850363 -232.24617)
			(xy 373.892379 -232.276696) (xy 373.929102 -232.313419) (xy 373.959628 -232.355435) (xy 373.983206 -232.401709)
			(xy 373.999254 -232.451102) (xy 374.007379 -232.502397) (xy 374.007888 -232.528364) (xy 374.007379 -232.554331)
			(xy 374.287035 -232.554331) (xy 374.287035 -232.502397) (xy 374.29516 -232.451102) (xy 374.311208 -232.401709)
			(xy 374.334786 -232.355435) (xy 374.365312 -232.313419) (xy 374.402035 -232.276696) (xy 374.444051 -232.24617)
			(xy 374.490325 -232.222592) (xy 374.539718 -232.206544) (xy 374.591013 -232.198419) (xy 374.642947 -232.198419)
			(xy 374.694242 -232.206544) (xy 374.743635 -232.222592) (xy 374.789909 -232.24617) (xy 374.831925 -232.276696)
			(xy 374.868648 -232.313419) (xy 374.899174 -232.355435) (xy 374.922752 -232.401709) (xy 374.9388 -232.451102)
			(xy 374.946925 -232.502397) (xy 374.947434 -232.528364) (xy 374.946925 -232.554331) (xy 375.227089 -232.554331)
			(xy 375.227089 -232.502397) (xy 375.235214 -232.451102) (xy 375.251262 -232.401709) (xy 375.27484 -232.355435)
			(xy 375.305366 -232.313419) (xy 375.342089 -232.276696) (xy 375.384105 -232.24617) (xy 375.430379 -232.222592)
			(xy 375.479772 -232.206544) (xy 375.531067 -232.198419) (xy 375.583001 -232.198419) (xy 375.634296 -232.206544)
			(xy 375.683689 -232.222592) (xy 375.729963 -232.24617) (xy 375.771979 -232.276696) (xy 375.808702 -232.313419)
			(xy 375.839228 -232.355435) (xy 375.862806 -232.401709) (xy 375.878854 -232.451102) (xy 375.886979 -232.502397)
			(xy 375.887488 -232.528364) (xy 375.886979 -232.554331) (xy 376.166889 -232.554331) (xy 376.166889 -232.502397)
			(xy 376.175014 -232.451102) (xy 376.191062 -232.401709) (xy 376.21464 -232.355435) (xy 376.245166 -232.313419)
			(xy 376.281889 -232.276696) (xy 376.323905 -232.24617) (xy 376.370179 -232.222592) (xy 376.419572 -232.206544)
			(xy 376.470867 -232.198419) (xy 376.522801 -232.198419) (xy 376.574096 -232.206544) (xy 376.623489 -232.222592)
			(xy 376.669763 -232.24617) (xy 376.711779 -232.276696) (xy 376.748502 -232.313419) (xy 376.779028 -232.355435)
			(xy 376.802606 -232.401709) (xy 376.818654 -232.451102) (xy 376.826779 -232.502397) (xy 376.827288 -232.528364)
			(xy 376.826779 -232.554331) (xy 377.106689 -232.554331) (xy 377.106689 -232.502397) (xy 377.114814 -232.451102)
			(xy 377.130862 -232.401709) (xy 377.15444 -232.355435) (xy 377.184966 -232.313419) (xy 377.221689 -232.276696)
			(xy 377.263705 -232.24617) (xy 377.309979 -232.222592) (xy 377.359372 -232.206544) (xy 377.410667 -232.198419)
			(xy 377.462601 -232.198419) (xy 377.513896 -232.206544) (xy 377.563289 -232.222592) (xy 377.609563 -232.24617)
			(xy 377.651579 -232.276696) (xy 377.688302 -232.313419) (xy 377.718828 -232.355435) (xy 377.742406 -232.401709)
			(xy 377.758454 -232.451102) (xy 377.766579 -232.502397) (xy 377.767088 -232.528364) (xy 377.766579 -232.554331)
			(xy 378.046489 -232.554331) (xy 378.046489 -232.502397) (xy 378.054614 -232.451102) (xy 378.070662 -232.401709)
			(xy 378.09424 -232.355435) (xy 378.124766 -232.313419) (xy 378.161489 -232.276696) (xy 378.203505 -232.24617)
			(xy 378.249779 -232.222592) (xy 378.299172 -232.206544) (xy 378.350467 -232.198419) (xy 378.402401 -232.198419)
			(xy 378.453696 -232.206544) (xy 378.503089 -232.222592) (xy 378.549363 -232.24617) (xy 378.591379 -232.276696)
			(xy 378.628102 -232.313419) (xy 378.658628 -232.355435) (xy 378.682206 -232.401709) (xy 378.698254 -232.451102)
			(xy 378.706379 -232.502397) (xy 378.706888 -232.528364) (xy 378.706379 -232.554331) (xy 378.986289 -232.554331)
			(xy 378.986289 -232.502397) (xy 378.994414 -232.451102) (xy 379.010462 -232.401709) (xy 379.03404 -232.355435)
			(xy 379.064566 -232.313419) (xy 379.101289 -232.276696) (xy 379.143305 -232.24617) (xy 379.189579 -232.222592)
			(xy 379.238972 -232.206544) (xy 379.290267 -232.198419) (xy 379.342201 -232.198419) (xy 379.393496 -232.206544)
			(xy 379.442889 -232.222592) (xy 379.489163 -232.24617) (xy 379.531179 -232.276696) (xy 379.567902 -232.313419)
			(xy 379.598428 -232.355435) (xy 379.622006 -232.401709) (xy 379.638054 -232.451102) (xy 379.646179 -232.502397)
			(xy 379.646688 -232.528364) (xy 379.646179 -232.554331) (xy 379.638054 -232.605626) (xy 379.622006 -232.655019)
			(xy 379.598428 -232.701293) (xy 379.567902 -232.743309) (xy 379.531179 -232.780032) (xy 379.489163 -232.810558)
			(xy 379.442889 -232.834136) (xy 379.393496 -232.850184) (xy 379.342201 -232.858309) (xy 379.290267 -232.858309)
			(xy 379.238972 -232.850184) (xy 379.189579 -232.834136) (xy 379.143305 -232.810558) (xy 379.101289 -232.780032)
			(xy 379.064566 -232.743309) (xy 379.03404 -232.701293) (xy 379.010462 -232.655019) (xy 378.994414 -232.605626)
			(xy 378.986289 -232.554331) (xy 378.706379 -232.554331) (xy 378.698254 -232.605626) (xy 378.682206 -232.655019)
			(xy 378.658628 -232.701293) (xy 378.628102 -232.743309) (xy 378.591379 -232.780032) (xy 378.549363 -232.810558)
			(xy 378.503089 -232.834136) (xy 378.453696 -232.850184) (xy 378.402401 -232.858309) (xy 378.350467 -232.858309)
			(xy 378.299172 -232.850184) (xy 378.249779 -232.834136) (xy 378.203505 -232.810558) (xy 378.161489 -232.780032)
			(xy 378.124766 -232.743309) (xy 378.09424 -232.701293) (xy 378.070662 -232.655019) (xy 378.054614 -232.605626)
			(xy 378.046489 -232.554331) (xy 377.766579 -232.554331) (xy 377.758454 -232.605626) (xy 377.742406 -232.655019)
			(xy 377.718828 -232.701293) (xy 377.688302 -232.743309) (xy 377.651579 -232.780032) (xy 377.609563 -232.810558)
			(xy 377.563289 -232.834136) (xy 377.513896 -232.850184) (xy 377.462601 -232.858309) (xy 377.410667 -232.858309)
			(xy 377.359372 -232.850184) (xy 377.309979 -232.834136) (xy 377.263705 -232.810558) (xy 377.221689 -232.780032)
			(xy 377.184966 -232.743309) (xy 377.15444 -232.701293) (xy 377.130862 -232.655019) (xy 377.114814 -232.605626)
			(xy 377.106689 -232.554331) (xy 376.826779 -232.554331) (xy 376.818654 -232.605626) (xy 376.802606 -232.655019)
			(xy 376.779028 -232.701293) (xy 376.748502 -232.743309) (xy 376.711779 -232.780032) (xy 376.669763 -232.810558)
			(xy 376.623489 -232.834136) (xy 376.574096 -232.850184) (xy 376.522801 -232.858309) (xy 376.470867 -232.858309)
			(xy 376.419572 -232.850184) (xy 376.370179 -232.834136) (xy 376.323905 -232.810558) (xy 376.281889 -232.780032)
			(xy 376.245166 -232.743309) (xy 376.21464 -232.701293) (xy 376.191062 -232.655019) (xy 376.175014 -232.605626)
			(xy 376.166889 -232.554331) (xy 375.886979 -232.554331) (xy 375.878854 -232.605626) (xy 375.862806 -232.655019)
			(xy 375.839228 -232.701293) (xy 375.808702 -232.743309) (xy 375.771979 -232.780032) (xy 375.729963 -232.810558)
			(xy 375.683689 -232.834136) (xy 375.634296 -232.850184) (xy 375.583001 -232.858309) (xy 375.531067 -232.858309)
			(xy 375.479772 -232.850184) (xy 375.430379 -232.834136) (xy 375.384105 -232.810558) (xy 375.342089 -232.780032)
			(xy 375.305366 -232.743309) (xy 375.27484 -232.701293) (xy 375.251262 -232.655019) (xy 375.235214 -232.605626)
			(xy 375.227089 -232.554331) (xy 374.946925 -232.554331) (xy 374.9388 -232.605626) (xy 374.922752 -232.655019)
			(xy 374.899174 -232.701293) (xy 374.868648 -232.743309) (xy 374.831925 -232.780032) (xy 374.789909 -232.810558)
			(xy 374.743635 -232.834136) (xy 374.694242 -232.850184) (xy 374.642947 -232.858309) (xy 374.591013 -232.858309)
			(xy 374.539718 -232.850184) (xy 374.490325 -232.834136) (xy 374.444051 -232.810558) (xy 374.402035 -232.780032)
			(xy 374.365312 -232.743309) (xy 374.334786 -232.701293) (xy 374.311208 -232.655019) (xy 374.29516 -232.605626)
			(xy 374.287035 -232.554331) (xy 374.007379 -232.554331) (xy 373.999254 -232.605626) (xy 373.983206 -232.655019)
			(xy 373.959628 -232.701293) (xy 373.929102 -232.743309) (xy 373.892379 -232.780032) (xy 373.850363 -232.810558)
			(xy 373.804089 -232.834136) (xy 373.754696 -232.850184) (xy 373.703401 -232.858309) (xy 373.651467 -232.858309)
			(xy 373.600172 -232.850184) (xy 373.550779 -232.834136) (xy 373.504505 -232.810558) (xy 373.462489 -232.780032)
			(xy 373.425766 -232.743309) (xy 373.39524 -232.701293) (xy 373.371662 -232.655019) (xy 373.355614 -232.605626)
			(xy 373.347489 -232.554331) (xy 373.067579 -232.554331) (xy 373.059454 -232.605626) (xy 373.043406 -232.655019)
			(xy 373.019828 -232.701293) (xy 372.989302 -232.743309) (xy 372.952579 -232.780032) (xy 372.910563 -232.810558)
			(xy 372.864289 -232.834136) (xy 372.814896 -232.850184) (xy 372.763601 -232.858309) (xy 372.711667 -232.858309)
			(xy 372.660372 -232.850184) (xy 372.610979 -232.834136) (xy 372.564705 -232.810558) (xy 372.522689 -232.780032)
			(xy 372.485966 -232.743309) (xy 372.45544 -232.701293) (xy 372.431862 -232.655019) (xy 372.415814 -232.605626)
			(xy 372.407689 -232.554331) (xy 372.127779 -232.554331) (xy 372.119654 -232.605626) (xy 372.103606 -232.655019)
			(xy 372.080028 -232.701293) (xy 372.049502 -232.743309) (xy 372.012779 -232.780032) (xy 371.970763 -232.810558)
			(xy 371.924489 -232.834136) (xy 371.875096 -232.850184) (xy 371.823801 -232.858309) (xy 371.771867 -232.858309)
			(xy 371.720572 -232.850184) (xy 371.671179 -232.834136) (xy 371.624905 -232.810558) (xy 371.582889 -232.780032)
			(xy 371.546166 -232.743309) (xy 371.51564 -232.701293) (xy 371.492062 -232.655019) (xy 371.476014 -232.605626)
			(xy 371.467889 -232.554331) (xy 371.187979 -232.554331) (xy 371.179854 -232.605626) (xy 371.163806 -232.655019)
			(xy 371.140228 -232.701293) (xy 371.109702 -232.743309) (xy 371.072979 -232.780032) (xy 371.030963 -232.810558)
			(xy 370.984689 -232.834136) (xy 370.935296 -232.850184) (xy 370.884001 -232.858309) (xy 370.832067 -232.858309)
			(xy 370.780772 -232.850184) (xy 370.731379 -232.834136) (xy 370.685105 -232.810558) (xy 370.643089 -232.780032)
			(xy 370.606366 -232.743309) (xy 370.57584 -232.701293) (xy 370.552262 -232.655019) (xy 370.536214 -232.605626)
			(xy 370.528089 -232.554331) (xy 370.248179 -232.554331) (xy 370.240054 -232.605626) (xy 370.224006 -232.655019)
			(xy 370.200428 -232.701293) (xy 370.169902 -232.743309) (xy 370.133179 -232.780032) (xy 370.091163 -232.810558)
			(xy 370.044889 -232.834136) (xy 369.995496 -232.850184) (xy 369.944201 -232.858309) (xy 369.892267 -232.858309)
			(xy 369.840972 -232.850184) (xy 369.791579 -232.834136) (xy 369.745305 -232.810558) (xy 369.703289 -232.780032)
			(xy 369.666566 -232.743309) (xy 369.63604 -232.701293) (xy 369.612462 -232.655019) (xy 369.596414 -232.605626)
			(xy 369.588289 -232.554331) (xy 369.333101 -232.554331) (xy 369.331061 -232.581552) (xy 369.319201 -232.633516)
			(xy 369.299729 -232.683133) (xy 369.27308 -232.729294) (xy 369.239849 -232.770967) (xy 369.200779 -232.807223)
			(xy 369.156741 -232.837251) (xy 369.108721 -232.860381) (xy 369.057789 -232.876095) (xy 369.005084 -232.884044)
			(xy 368.978434 -232.884472) (xy 368.96675 -232.884218) (xy 368.956681 -232.884408) (xy 368.937939 -232.891735)
			(xy 368.930428 -232.898442) (xy 368.878358 -232.94848) (xy 368.871425 -232.955766) (xy 368.86354 -232.974247)
			(xy 368.863118 -232.984294) (xy 368.863118 -233.368147) (xy 369.118389 -233.368147) (xy 369.118389 -233.316213)
			(xy 369.126514 -233.264918) (xy 369.142562 -233.215525) (xy 369.16614 -233.169251) (xy 369.196666 -233.127235)
			(xy 369.233389 -233.090512) (xy 369.275405 -233.059986) (xy 369.321679 -233.036408) (xy 369.371072 -233.02036)
			(xy 369.422367 -233.012235) (xy 369.474301 -233.012235) (xy 369.525596 -233.02036) (xy 369.574989 -233.036408)
			(xy 369.621263 -233.059986) (xy 369.663279 -233.090512) (xy 369.700002 -233.127235) (xy 369.730528 -233.169251)
			(xy 369.754106 -233.215525) (xy 369.770154 -233.264918) (xy 369.778279 -233.316213) (xy 369.778788 -233.34218)
			(xy 369.778279 -233.368147) (xy 370.057935 -233.368147) (xy 370.057935 -233.316213) (xy 370.06606 -233.264918)
			(xy 370.082108 -233.215525) (xy 370.105686 -233.169251) (xy 370.136212 -233.127235) (xy 370.172935 -233.090512)
			(xy 370.214951 -233.059986) (xy 370.261225 -233.036408) (xy 370.310618 -233.02036) (xy 370.361913 -233.012235)
			(xy 370.413847 -233.012235) (xy 370.465142 -233.02036) (xy 370.514535 -233.036408) (xy 370.560809 -233.059986)
			(xy 370.602825 -233.090512) (xy 370.639548 -233.127235) (xy 370.670074 -233.169251) (xy 370.693652 -233.215525)
			(xy 370.7097 -233.264918) (xy 370.717825 -233.316213) (xy 370.718334 -233.34218) (xy 370.717825 -233.368147)
			(xy 370.997735 -233.368147) (xy 370.997735 -233.316213) (xy 371.00586 -233.264918) (xy 371.021908 -233.215525)
			(xy 371.045486 -233.169251) (xy 371.076012 -233.127235) (xy 371.112735 -233.090512) (xy 371.154751 -233.059986)
			(xy 371.201025 -233.036408) (xy 371.250418 -233.02036) (xy 371.301713 -233.012235) (xy 371.353647 -233.012235)
			(xy 371.404942 -233.02036) (xy 371.454335 -233.036408) (xy 371.500609 -233.059986) (xy 371.542625 -233.090512)
			(xy 371.579348 -233.127235) (xy 371.609874 -233.169251) (xy 371.633452 -233.215525) (xy 371.6495 -233.264918)
			(xy 371.657625 -233.316213) (xy 371.658134 -233.34218) (xy 371.657625 -233.368147) (xy 371.937535 -233.368147)
			(xy 371.937535 -233.316213) (xy 371.94566 -233.264918) (xy 371.961708 -233.215525) (xy 371.985286 -233.169251)
			(xy 372.015812 -233.127235) (xy 372.052535 -233.090512) (xy 372.094551 -233.059986) (xy 372.140825 -233.036408)
			(xy 372.190218 -233.02036) (xy 372.241513 -233.012235) (xy 372.293447 -233.012235) (xy 372.344742 -233.02036)
			(xy 372.394135 -233.036408) (xy 372.440409 -233.059986) (xy 372.482425 -233.090512) (xy 372.519148 -233.127235)
			(xy 372.549674 -233.169251) (xy 372.573252 -233.215525) (xy 372.5893 -233.264918) (xy 372.597425 -233.316213)
			(xy 372.597934 -233.34218) (xy 372.597425 -233.368147) (xy 372.877335 -233.368147) (xy 372.877335 -233.316213)
			(xy 372.88546 -233.264918) (xy 372.901508 -233.215525) (xy 372.925086 -233.169251) (xy 372.955612 -233.127235)
			(xy 372.992335 -233.090512) (xy 373.034351 -233.059986) (xy 373.080625 -233.036408) (xy 373.130018 -233.02036)
			(xy 373.181313 -233.012235) (xy 373.233247 -233.012235) (xy 373.284542 -233.02036) (xy 373.333935 -233.036408)
			(xy 373.380209 -233.059986) (xy 373.422225 -233.090512) (xy 373.458948 -233.127235) (xy 373.489474 -233.169251)
			(xy 373.513052 -233.215525) (xy 373.5291 -233.264918) (xy 373.537225 -233.316213) (xy 373.537734 -233.34218)
			(xy 373.537225 -233.368147) (xy 373.817389 -233.368147) (xy 373.817389 -233.316213) (xy 373.825514 -233.264918)
			(xy 373.841562 -233.215525) (xy 373.86514 -233.169251) (xy 373.895666 -233.127235) (xy 373.932389 -233.090512)
			(xy 373.974405 -233.059986) (xy 374.020679 -233.036408) (xy 374.070072 -233.02036) (xy 374.121367 -233.012235)
			(xy 374.173301 -233.012235) (xy 374.224596 -233.02036) (xy 374.273989 -233.036408) (xy 374.320263 -233.059986)
			(xy 374.362279 -233.090512) (xy 374.399002 -233.127235) (xy 374.429528 -233.169251) (xy 374.453106 -233.215525)
			(xy 374.469154 -233.264918) (xy 374.477279 -233.316213) (xy 374.477788 -233.34218) (xy 374.477279 -233.368147)
			(xy 374.756935 -233.368147) (xy 374.756935 -233.316213) (xy 374.76506 -233.264918) (xy 374.781108 -233.215525)
			(xy 374.804686 -233.169251) (xy 374.835212 -233.127235) (xy 374.871935 -233.090512) (xy 374.913951 -233.059986)
			(xy 374.960225 -233.036408) (xy 375.009618 -233.02036) (xy 375.060913 -233.012235) (xy 375.112847 -233.012235)
			(xy 375.164142 -233.02036) (xy 375.213535 -233.036408) (xy 375.259809 -233.059986) (xy 375.301825 -233.090512)
			(xy 375.338548 -233.127235) (xy 375.369074 -233.169251) (xy 375.392652 -233.215525) (xy 375.4087 -233.264918)
			(xy 375.416825 -233.316213) (xy 375.417334 -233.34218) (xy 375.416825 -233.368147) (xy 375.696735 -233.368147)
			(xy 375.696735 -233.316213) (xy 375.70486 -233.264918) (xy 375.720908 -233.215525) (xy 375.744486 -233.169251)
			(xy 375.775012 -233.127235) (xy 375.811735 -233.090512) (xy 375.853751 -233.059986) (xy 375.900025 -233.036408)
			(xy 375.949418 -233.02036) (xy 376.000713 -233.012235) (xy 376.052647 -233.012235) (xy 376.103942 -233.02036)
			(xy 376.153335 -233.036408) (xy 376.199609 -233.059986) (xy 376.241625 -233.090512) (xy 376.278348 -233.127235)
			(xy 376.308874 -233.169251) (xy 376.332452 -233.215525) (xy 376.3485 -233.264918) (xy 376.356625 -233.316213)
			(xy 376.357134 -233.34218) (xy 376.356625 -233.368147) (xy 376.636535 -233.368147) (xy 376.636535 -233.316213)
			(xy 376.64466 -233.264918) (xy 376.660708 -233.215525) (xy 376.684286 -233.169251) (xy 376.714812 -233.127235)
			(xy 376.751535 -233.090512) (xy 376.793551 -233.059986) (xy 376.839825 -233.036408) (xy 376.889218 -233.02036)
			(xy 376.940513 -233.012235) (xy 376.992447 -233.012235) (xy 377.043742 -233.02036) (xy 377.093135 -233.036408)
			(xy 377.139409 -233.059986) (xy 377.181425 -233.090512) (xy 377.218148 -233.127235) (xy 377.248674 -233.169251)
			(xy 377.272252 -233.215525) (xy 377.2883 -233.264918) (xy 377.296425 -233.316213) (xy 377.296934 -233.34218)
			(xy 377.296425 -233.368147) (xy 377.576335 -233.368147) (xy 377.576335 -233.316213) (xy 377.58446 -233.264918)
			(xy 377.600508 -233.215525) (xy 377.624086 -233.169251) (xy 377.654612 -233.127235) (xy 377.691335 -233.090512)
			(xy 377.733351 -233.059986) (xy 377.779625 -233.036408) (xy 377.829018 -233.02036) (xy 377.880313 -233.012235)
			(xy 377.932247 -233.012235) (xy 377.983542 -233.02036) (xy 378.032935 -233.036408) (xy 378.079209 -233.059986)
			(xy 378.121225 -233.090512) (xy 378.157948 -233.127235) (xy 378.188474 -233.169251) (xy 378.212052 -233.215525)
			(xy 378.2281 -233.264918) (xy 378.236225 -233.316213) (xy 378.236734 -233.34218) (xy 378.236225 -233.368147)
			(xy 378.516135 -233.368147) (xy 378.516135 -233.316213) (xy 378.52426 -233.264918) (xy 378.540308 -233.215525)
			(xy 378.563886 -233.169251) (xy 378.594412 -233.127235) (xy 378.631135 -233.090512) (xy 378.673151 -233.059986)
			(xy 378.719425 -233.036408) (xy 378.768818 -233.02036) (xy 378.820113 -233.012235) (xy 378.872047 -233.012235)
			(xy 378.923342 -233.02036) (xy 378.972735 -233.036408) (xy 379.019009 -233.059986) (xy 379.061025 -233.090512)
			(xy 379.097748 -233.127235) (xy 379.128274 -233.169251) (xy 379.151852 -233.215525) (xy 379.1679 -233.264918)
			(xy 379.176025 -233.316213) (xy 379.176534 -233.34218) (xy 379.176025 -233.368147) (xy 379.455935 -233.368147)
			(xy 379.455935 -233.316213) (xy 379.46406 -233.264918) (xy 379.480108 -233.215525) (xy 379.503686 -233.169251)
			(xy 379.534212 -233.127235) (xy 379.570935 -233.090512) (xy 379.612951 -233.059986) (xy 379.659225 -233.036408)
			(xy 379.708618 -233.02036) (xy 379.759913 -233.012235) (xy 379.811847 -233.012235) (xy 379.863142 -233.02036)
			(xy 379.912535 -233.036408) (xy 379.958809 -233.059986) (xy 380.000825 -233.090512) (xy 380.037548 -233.127235)
			(xy 380.068074 -233.169251) (xy 380.091652 -233.215525) (xy 380.1077 -233.264918) (xy 380.115825 -233.316213)
			(xy 380.116334 -233.34218) (xy 380.115825 -233.368147) (xy 380.1077 -233.419442) (xy 380.091652 -233.468835)
			(xy 380.068074 -233.515109) (xy 380.037548 -233.557125) (xy 380.000825 -233.593848) (xy 379.958809 -233.624374)
			(xy 379.912535 -233.647952) (xy 379.863142 -233.664) (xy 379.811847 -233.672125) (xy 379.759913 -233.672125)
			(xy 379.708618 -233.664) (xy 379.659225 -233.647952) (xy 379.612951 -233.624374) (xy 379.570935 -233.593848)
			(xy 379.534212 -233.557125) (xy 379.503686 -233.515109) (xy 379.480108 -233.468835) (xy 379.46406 -233.419442)
			(xy 379.455935 -233.368147) (xy 379.176025 -233.368147) (xy 379.1679 -233.419442) (xy 379.151852 -233.468835)
			(xy 379.128274 -233.515109) (xy 379.097748 -233.557125) (xy 379.061025 -233.593848) (xy 379.019009 -233.624374)
			(xy 378.972735 -233.647952) (xy 378.923342 -233.664) (xy 378.872047 -233.672125) (xy 378.820113 -233.672125)
			(xy 378.768818 -233.664) (xy 378.719425 -233.647952) (xy 378.673151 -233.624374) (xy 378.631135 -233.593848)
			(xy 378.594412 -233.557125) (xy 378.563886 -233.515109) (xy 378.540308 -233.468835) (xy 378.52426 -233.419442)
			(xy 378.516135 -233.368147) (xy 378.236225 -233.368147) (xy 378.2281 -233.419442) (xy 378.212052 -233.468835)
			(xy 378.188474 -233.515109) (xy 378.157948 -233.557125) (xy 378.121225 -233.593848) (xy 378.079209 -233.624374)
			(xy 378.032935 -233.647952) (xy 377.983542 -233.664) (xy 377.932247 -233.672125) (xy 377.880313 -233.672125)
			(xy 377.829018 -233.664) (xy 377.779625 -233.647952) (xy 377.733351 -233.624374) (xy 377.691335 -233.593848)
			(xy 377.654612 -233.557125) (xy 377.624086 -233.515109) (xy 377.600508 -233.468835) (xy 377.58446 -233.419442)
			(xy 377.576335 -233.368147) (xy 377.296425 -233.368147) (xy 377.2883 -233.419442) (xy 377.272252 -233.468835)
			(xy 377.248674 -233.515109) (xy 377.218148 -233.557125) (xy 377.181425 -233.593848) (xy 377.139409 -233.624374)
			(xy 377.093135 -233.647952) (xy 377.043742 -233.664) (xy 376.992447 -233.672125) (xy 376.940513 -233.672125)
			(xy 376.889218 -233.664) (xy 376.839825 -233.647952) (xy 376.793551 -233.624374) (xy 376.751535 -233.593848)
			(xy 376.714812 -233.557125) (xy 376.684286 -233.515109) (xy 376.660708 -233.468835) (xy 376.64466 -233.419442)
			(xy 376.636535 -233.368147) (xy 376.356625 -233.368147) (xy 376.3485 -233.419442) (xy 376.332452 -233.468835)
			(xy 376.308874 -233.515109) (xy 376.278348 -233.557125) (xy 376.241625 -233.593848) (xy 376.199609 -233.624374)
			(xy 376.153335 -233.647952) (xy 376.103942 -233.664) (xy 376.052647 -233.672125) (xy 376.000713 -233.672125)
			(xy 375.949418 -233.664) (xy 375.900025 -233.647952) (xy 375.853751 -233.624374) (xy 375.811735 -233.593848)
			(xy 375.775012 -233.557125) (xy 375.744486 -233.515109) (xy 375.720908 -233.468835) (xy 375.70486 -233.419442)
			(xy 375.696735 -233.368147) (xy 375.416825 -233.368147) (xy 375.4087 -233.419442) (xy 375.392652 -233.468835)
			(xy 375.369074 -233.515109) (xy 375.338548 -233.557125) (xy 375.301825 -233.593848) (xy 375.259809 -233.624374)
			(xy 375.213535 -233.647952) (xy 375.164142 -233.664) (xy 375.112847 -233.672125) (xy 375.060913 -233.672125)
			(xy 375.009618 -233.664) (xy 374.960225 -233.647952) (xy 374.913951 -233.624374) (xy 374.871935 -233.593848)
			(xy 374.835212 -233.557125) (xy 374.804686 -233.515109) (xy 374.781108 -233.468835) (xy 374.76506 -233.419442)
			(xy 374.756935 -233.368147) (xy 374.477279 -233.368147) (xy 374.469154 -233.419442) (xy 374.453106 -233.468835)
			(xy 374.429528 -233.515109) (xy 374.399002 -233.557125) (xy 374.362279 -233.593848) (xy 374.320263 -233.624374)
			(xy 374.273989 -233.647952) (xy 374.224596 -233.664) (xy 374.173301 -233.672125) (xy 374.121367 -233.672125)
			(xy 374.070072 -233.664) (xy 374.020679 -233.647952) (xy 373.974405 -233.624374) (xy 373.932389 -233.593848)
			(xy 373.895666 -233.557125) (xy 373.86514 -233.515109) (xy 373.841562 -233.468835) (xy 373.825514 -233.419442)
			(xy 373.817389 -233.368147) (xy 373.537225 -233.368147) (xy 373.5291 -233.419442) (xy 373.513052 -233.468835)
			(xy 373.489474 -233.515109) (xy 373.458948 -233.557125) (xy 373.422225 -233.593848) (xy 373.380209 -233.624374)
			(xy 373.333935 -233.647952) (xy 373.284542 -233.664) (xy 373.233247 -233.672125) (xy 373.181313 -233.672125)
			(xy 373.130018 -233.664) (xy 373.080625 -233.647952) (xy 373.034351 -233.624374) (xy 372.992335 -233.593848)
			(xy 372.955612 -233.557125) (xy 372.925086 -233.515109) (xy 372.901508 -233.468835) (xy 372.88546 -233.419442)
			(xy 372.877335 -233.368147) (xy 372.597425 -233.368147) (xy 372.5893 -233.419442) (xy 372.573252 -233.468835)
			(xy 372.549674 -233.515109) (xy 372.519148 -233.557125) (xy 372.482425 -233.593848) (xy 372.440409 -233.624374)
			(xy 372.394135 -233.647952) (xy 372.344742 -233.664) (xy 372.293447 -233.672125) (xy 372.241513 -233.672125)
			(xy 372.190218 -233.664) (xy 372.140825 -233.647952) (xy 372.094551 -233.624374) (xy 372.052535 -233.593848)
			(xy 372.015812 -233.557125) (xy 371.985286 -233.515109) (xy 371.961708 -233.468835) (xy 371.94566 -233.419442)
			(xy 371.937535 -233.368147) (xy 371.657625 -233.368147) (xy 371.6495 -233.419442) (xy 371.633452 -233.468835)
			(xy 371.609874 -233.515109) (xy 371.579348 -233.557125) (xy 371.542625 -233.593848) (xy 371.500609 -233.624374)
			(xy 371.454335 -233.647952) (xy 371.404942 -233.664) (xy 371.353647 -233.672125) (xy 371.301713 -233.672125)
			(xy 371.250418 -233.664) (xy 371.201025 -233.647952) (xy 371.154751 -233.624374) (xy 371.112735 -233.593848)
			(xy 371.076012 -233.557125) (xy 371.045486 -233.515109) (xy 371.021908 -233.468835) (xy 371.00586 -233.419442)
			(xy 370.997735 -233.368147) (xy 370.717825 -233.368147) (xy 370.7097 -233.419442) (xy 370.693652 -233.468835)
			(xy 370.670074 -233.515109) (xy 370.639548 -233.557125) (xy 370.602825 -233.593848) (xy 370.560809 -233.624374)
			(xy 370.514535 -233.647952) (xy 370.465142 -233.664) (xy 370.413847 -233.672125) (xy 370.361913 -233.672125)
			(xy 370.310618 -233.664) (xy 370.261225 -233.647952) (xy 370.214951 -233.624374) (xy 370.172935 -233.593848)
			(xy 370.136212 -233.557125) (xy 370.105686 -233.515109) (xy 370.082108 -233.468835) (xy 370.06606 -233.419442)
			(xy 370.057935 -233.368147) (xy 369.778279 -233.368147) (xy 369.770154 -233.419442) (xy 369.754106 -233.468835)
			(xy 369.730528 -233.515109) (xy 369.700002 -233.557125) (xy 369.663279 -233.593848) (xy 369.621263 -233.624374)
			(xy 369.574989 -233.647952) (xy 369.525596 -233.664) (xy 369.474301 -233.672125) (xy 369.422367 -233.672125)
			(xy 369.371072 -233.664) (xy 369.321679 -233.647952) (xy 369.275405 -233.624374) (xy 369.233389 -233.593848)
			(xy 369.196666 -233.557125) (xy 369.16614 -233.515109) (xy 369.142562 -233.468835) (xy 369.126514 -233.419442)
			(xy 369.118389 -233.368147) (xy 368.863118 -233.368147) (xy 368.863118 -233.725466) (xy 368.863638 -233.735586)
			(xy 368.87163 -233.75419) (xy 368.878612 -233.761534) (xy 368.930428 -233.811826) (xy 368.937744 -233.818334)
			(xy 368.955944 -233.82552) (xy 368.965734 -233.825796) (xy 368.967004 -233.825796) (xy 368.97818 -233.825542)
			(xy 369.004166 -233.826023) (xy 369.0555 -233.834151) (xy 369.104929 -233.850209) (xy 369.151238 -233.873802)
			(xy 369.193286 -233.904349) (xy 369.230038 -233.941099) (xy 369.260587 -233.983145) (xy 369.284183 -234.029452)
			(xy 369.300244 -234.078881) (xy 369.308375 -234.130214) (xy 369.308375 -234.182186) (xy 369.30837 -234.182217)
			(xy 369.588289 -234.182217) (xy 369.588289 -234.130283) (xy 369.596414 -234.078988) (xy 369.612462 -234.029595)
			(xy 369.63604 -233.983321) (xy 369.666566 -233.941305) (xy 369.703289 -233.904582) (xy 369.745305 -233.874056)
			(xy 369.791579 -233.850478) (xy 369.840972 -233.83443) (xy 369.892267 -233.826305) (xy 369.944201 -233.826305)
			(xy 369.995496 -233.83443) (xy 370.044889 -233.850478) (xy 370.091163 -233.874056) (xy 370.133179 -233.904582)
			(xy 370.169902 -233.941305) (xy 370.200428 -233.983321) (xy 370.224006 -234.029595) (xy 370.240054 -234.078988)
			(xy 370.248179 -234.130283) (xy 370.248688 -234.15625) (xy 370.248179 -234.182217) (xy 370.527835 -234.182217)
			(xy 370.527835 -234.130283) (xy 370.53596 -234.078988) (xy 370.552008 -234.029595) (xy 370.575586 -233.983321)
			(xy 370.606112 -233.941305) (xy 370.642835 -233.904582) (xy 370.684851 -233.874056) (xy 370.731125 -233.850478)
			(xy 370.780518 -233.83443) (xy 370.831813 -233.826305) (xy 370.883747 -233.826305) (xy 370.935042 -233.83443)
			(xy 370.984435 -233.850478) (xy 371.030709 -233.874056) (xy 371.072725 -233.904582) (xy 371.109448 -233.941305)
			(xy 371.139974 -233.983321) (xy 371.163552 -234.029595) (xy 371.1796 -234.078988) (xy 371.187725 -234.130283)
			(xy 371.188234 -234.15625) (xy 371.187725 -234.182217) (xy 371.467889 -234.182217) (xy 371.467889 -234.130283)
			(xy 371.476014 -234.078988) (xy 371.492062 -234.029595) (xy 371.51564 -233.983321) (xy 371.546166 -233.941305)
			(xy 371.582889 -233.904582) (xy 371.624905 -233.874056) (xy 371.671179 -233.850478) (xy 371.720572 -233.83443)
			(xy 371.771867 -233.826305) (xy 371.823801 -233.826305) (xy 371.875096 -233.83443) (xy 371.924489 -233.850478)
			(xy 371.970763 -233.874056) (xy 372.012779 -233.904582) (xy 372.049502 -233.941305) (xy 372.080028 -233.983321)
			(xy 372.103606 -234.029595) (xy 372.119654 -234.078988) (xy 372.127779 -234.130283) (xy 372.128288 -234.15625)
			(xy 372.127779 -234.182217) (xy 372.407689 -234.182217) (xy 372.407689 -234.130283) (xy 372.415814 -234.078988)
			(xy 372.431862 -234.029595) (xy 372.45544 -233.983321) (xy 372.485966 -233.941305) (xy 372.522689 -233.904582)
			(xy 372.564705 -233.874056) (xy 372.610979 -233.850478) (xy 372.660372 -233.83443) (xy 372.711667 -233.826305)
			(xy 372.763601 -233.826305) (xy 372.814896 -233.83443) (xy 372.864289 -233.850478) (xy 372.910563 -233.874056)
			(xy 372.952579 -233.904582) (xy 372.989302 -233.941305) (xy 373.019828 -233.983321) (xy 373.043406 -234.029595)
			(xy 373.059454 -234.078988) (xy 373.067579 -234.130283) (xy 373.068088 -234.15625) (xy 373.067579 -234.182217)
			(xy 373.347489 -234.182217) (xy 373.347489 -234.130283) (xy 373.355614 -234.078988) (xy 373.371662 -234.029595)
			(xy 373.39524 -233.983321) (xy 373.425766 -233.941305) (xy 373.462489 -233.904582) (xy 373.504505 -233.874056)
			(xy 373.550779 -233.850478) (xy 373.600172 -233.83443) (xy 373.651467 -233.826305) (xy 373.703401 -233.826305)
			(xy 373.754696 -233.83443) (xy 373.804089 -233.850478) (xy 373.850363 -233.874056) (xy 373.892379 -233.904582)
			(xy 373.929102 -233.941305) (xy 373.959628 -233.983321) (xy 373.983206 -234.029595) (xy 373.999254 -234.078988)
			(xy 374.007379 -234.130283) (xy 374.007888 -234.15625) (xy 374.007379 -234.182217) (xy 374.287289 -234.182217)
			(xy 374.287289 -234.130283) (xy 374.295414 -234.078988) (xy 374.311462 -234.029595) (xy 374.33504 -233.983321)
			(xy 374.365566 -233.941305) (xy 374.402289 -233.904582) (xy 374.444305 -233.874056) (xy 374.490579 -233.850478)
			(xy 374.539972 -233.83443) (xy 374.591267 -233.826305) (xy 374.643201 -233.826305) (xy 374.694496 -233.83443)
			(xy 374.743889 -233.850478) (xy 374.790163 -233.874056) (xy 374.832179 -233.904582) (xy 374.868902 -233.941305)
			(xy 374.899428 -233.983321) (xy 374.923006 -234.029595) (xy 374.939054 -234.078988) (xy 374.947179 -234.130283)
			(xy 374.947688 -234.15625) (xy 374.947179 -234.182217) (xy 375.227089 -234.182217) (xy 375.227089 -234.130283)
			(xy 375.235214 -234.078988) (xy 375.251262 -234.029595) (xy 375.27484 -233.983321) (xy 375.305366 -233.941305)
			(xy 375.342089 -233.904582) (xy 375.384105 -233.874056) (xy 375.430379 -233.850478) (xy 375.479772 -233.83443)
			(xy 375.531067 -233.826305) (xy 375.583001 -233.826305) (xy 375.634296 -233.83443) (xy 375.683689 -233.850478)
			(xy 375.729963 -233.874056) (xy 375.771979 -233.904582) (xy 375.808702 -233.941305) (xy 375.839228 -233.983321)
			(xy 375.862806 -234.029595) (xy 375.878854 -234.078988) (xy 375.886979 -234.130283) (xy 375.887488 -234.15625)
			(xy 375.886979 -234.182217) (xy 376.166889 -234.182217) (xy 376.166889 -234.130283) (xy 376.175014 -234.078988)
			(xy 376.191062 -234.029595) (xy 376.21464 -233.983321) (xy 376.245166 -233.941305) (xy 376.281889 -233.904582)
			(xy 376.323905 -233.874056) (xy 376.370179 -233.850478) (xy 376.419572 -233.83443) (xy 376.470867 -233.826305)
			(xy 376.522801 -233.826305) (xy 376.574096 -233.83443) (xy 376.623489 -233.850478) (xy 376.669763 -233.874056)
			(xy 376.711779 -233.904582) (xy 376.748502 -233.941305) (xy 376.779028 -233.983321) (xy 376.802606 -234.029595)
			(xy 376.818654 -234.078988) (xy 376.826779 -234.130283) (xy 376.827288 -234.15625) (xy 376.826779 -234.182217)
			(xy 377.106435 -234.182217) (xy 377.106435 -234.130283) (xy 377.11456 -234.078988) (xy 377.130608 -234.029595)
			(xy 377.154186 -233.983321) (xy 377.184712 -233.941305) (xy 377.221435 -233.904582) (xy 377.263451 -233.874056)
			(xy 377.309725 -233.850478) (xy 377.359118 -233.83443) (xy 377.410413 -233.826305) (xy 377.462347 -233.826305)
			(xy 377.513642 -233.83443) (xy 377.563035 -233.850478) (xy 377.609309 -233.874056) (xy 377.651325 -233.904582)
			(xy 377.688048 -233.941305) (xy 377.718574 -233.983321) (xy 377.742152 -234.029595) (xy 377.7582 -234.078988)
			(xy 377.766325 -234.130283) (xy 377.766834 -234.15625) (xy 377.766325 -234.182217) (xy 378.046489 -234.182217)
			(xy 378.046489 -234.130283) (xy 378.054614 -234.078988) (xy 378.070662 -234.029595) (xy 378.09424 -233.983321)
			(xy 378.124766 -233.941305) (xy 378.161489 -233.904582) (xy 378.203505 -233.874056) (xy 378.249779 -233.850478)
			(xy 378.299172 -233.83443) (xy 378.350467 -233.826305) (xy 378.402401 -233.826305) (xy 378.453696 -233.83443)
			(xy 378.503089 -233.850478) (xy 378.549363 -233.874056) (xy 378.591379 -233.904582) (xy 378.628102 -233.941305)
			(xy 378.658628 -233.983321) (xy 378.682206 -234.029595) (xy 378.698254 -234.078988) (xy 378.706379 -234.130283)
			(xy 378.706888 -234.15625) (xy 378.706379 -234.182217) (xy 378.986289 -234.182217) (xy 378.986289 -234.130283)
			(xy 378.994414 -234.078988) (xy 379.010462 -234.029595) (xy 379.03404 -233.983321) (xy 379.064566 -233.941305)
			(xy 379.101289 -233.904582) (xy 379.143305 -233.874056) (xy 379.189579 -233.850478) (xy 379.238972 -233.83443)
			(xy 379.290267 -233.826305) (xy 379.342201 -233.826305) (xy 379.393496 -233.83443) (xy 379.442889 -233.850478)
			(xy 379.489163 -233.874056) (xy 379.531179 -233.904582) (xy 379.567902 -233.941305) (xy 379.598428 -233.983321)
			(xy 379.622006 -234.029595) (xy 379.638054 -234.078988) (xy 379.646179 -234.130283) (xy 379.646688 -234.15625)
			(xy 379.646179 -234.182217) (xy 379.638054 -234.233512) (xy 379.622006 -234.282905) (xy 379.598428 -234.329179)
			(xy 379.567902 -234.371195) (xy 379.531179 -234.407918) (xy 379.489163 -234.438444) (xy 379.442889 -234.462022)
			(xy 379.393496 -234.47807) (xy 379.342201 -234.486195) (xy 379.290267 -234.486195) (xy 379.238972 -234.47807)
			(xy 379.189579 -234.462022) (xy 379.143305 -234.438444) (xy 379.101289 -234.407918) (xy 379.064566 -234.371195)
			(xy 379.03404 -234.329179) (xy 379.010462 -234.282905) (xy 378.994414 -234.233512) (xy 378.986289 -234.182217)
			(xy 378.706379 -234.182217) (xy 378.698254 -234.233512) (xy 378.682206 -234.282905) (xy 378.658628 -234.329179)
			(xy 378.628102 -234.371195) (xy 378.591379 -234.407918) (xy 378.549363 -234.438444) (xy 378.503089 -234.462022)
			(xy 378.453696 -234.47807) (xy 378.402401 -234.486195) (xy 378.350467 -234.486195) (xy 378.299172 -234.47807)
			(xy 378.249779 -234.462022) (xy 378.203505 -234.438444) (xy 378.161489 -234.407918) (xy 378.124766 -234.371195)
			(xy 378.09424 -234.329179) (xy 378.070662 -234.282905) (xy 378.054614 -234.233512) (xy 378.046489 -234.182217)
			(xy 377.766325 -234.182217) (xy 377.7582 -234.233512) (xy 377.742152 -234.282905) (xy 377.718574 -234.329179)
			(xy 377.688048 -234.371195) (xy 377.651325 -234.407918) (xy 377.609309 -234.438444) (xy 377.563035 -234.462022)
			(xy 377.513642 -234.47807) (xy 377.462347 -234.486195) (xy 377.410413 -234.486195) (xy 377.359118 -234.47807)
			(xy 377.309725 -234.462022) (xy 377.263451 -234.438444) (xy 377.221435 -234.407918) (xy 377.184712 -234.371195)
			(xy 377.154186 -234.329179) (xy 377.130608 -234.282905) (xy 377.11456 -234.233512) (xy 377.106435 -234.182217)
			(xy 376.826779 -234.182217) (xy 376.818654 -234.233512) (xy 376.802606 -234.282905) (xy 376.779028 -234.329179)
			(xy 376.748502 -234.371195) (xy 376.711779 -234.407918) (xy 376.669763 -234.438444) (xy 376.623489 -234.462022)
			(xy 376.574096 -234.47807) (xy 376.522801 -234.486195) (xy 376.470867 -234.486195) (xy 376.419572 -234.47807)
			(xy 376.370179 -234.462022) (xy 376.323905 -234.438444) (xy 376.281889 -234.407918) (xy 376.245166 -234.371195)
			(xy 376.21464 -234.329179) (xy 376.191062 -234.282905) (xy 376.175014 -234.233512) (xy 376.166889 -234.182217)
			(xy 375.886979 -234.182217) (xy 375.878854 -234.233512) (xy 375.862806 -234.282905) (xy 375.839228 -234.329179)
			(xy 375.808702 -234.371195) (xy 375.771979 -234.407918) (xy 375.729963 -234.438444) (xy 375.683689 -234.462022)
			(xy 375.634296 -234.47807) (xy 375.583001 -234.486195) (xy 375.531067 -234.486195) (xy 375.479772 -234.47807)
			(xy 375.430379 -234.462022) (xy 375.384105 -234.438444) (xy 375.342089 -234.407918) (xy 375.305366 -234.371195)
			(xy 375.27484 -234.329179) (xy 375.251262 -234.282905) (xy 375.235214 -234.233512) (xy 375.227089 -234.182217)
			(xy 374.947179 -234.182217) (xy 374.939054 -234.233512) (xy 374.923006 -234.282905) (xy 374.899428 -234.329179)
			(xy 374.868902 -234.371195) (xy 374.832179 -234.407918) (xy 374.790163 -234.438444) (xy 374.743889 -234.462022)
			(xy 374.694496 -234.47807) (xy 374.643201 -234.486195) (xy 374.591267 -234.486195) (xy 374.539972 -234.47807)
			(xy 374.490579 -234.462022) (xy 374.444305 -234.438444) (xy 374.402289 -234.407918) (xy 374.365566 -234.371195)
			(xy 374.33504 -234.329179) (xy 374.311462 -234.282905) (xy 374.295414 -234.233512) (xy 374.287289 -234.182217)
			(xy 374.007379 -234.182217) (xy 373.999254 -234.233512) (xy 373.983206 -234.282905) (xy 373.959628 -234.329179)
			(xy 373.929102 -234.371195) (xy 373.892379 -234.407918) (xy 373.850363 -234.438444) (xy 373.804089 -234.462022)
			(xy 373.754696 -234.47807) (xy 373.703401 -234.486195) (xy 373.651467 -234.486195) (xy 373.600172 -234.47807)
			(xy 373.550779 -234.462022) (xy 373.504505 -234.438444) (xy 373.462489 -234.407918) (xy 373.425766 -234.371195)
			(xy 373.39524 -234.329179) (xy 373.371662 -234.282905) (xy 373.355614 -234.233512) (xy 373.347489 -234.182217)
			(xy 373.067579 -234.182217) (xy 373.059454 -234.233512) (xy 373.043406 -234.282905) (xy 373.019828 -234.329179)
			(xy 372.989302 -234.371195) (xy 372.952579 -234.407918) (xy 372.910563 -234.438444) (xy 372.864289 -234.462022)
			(xy 372.814896 -234.47807) (xy 372.763601 -234.486195) (xy 372.711667 -234.486195) (xy 372.660372 -234.47807)
			(xy 372.610979 -234.462022) (xy 372.564705 -234.438444) (xy 372.522689 -234.407918) (xy 372.485966 -234.371195)
			(xy 372.45544 -234.329179) (xy 372.431862 -234.282905) (xy 372.415814 -234.233512) (xy 372.407689 -234.182217)
			(xy 372.127779 -234.182217) (xy 372.119654 -234.233512) (xy 372.103606 -234.282905) (xy 372.080028 -234.329179)
			(xy 372.049502 -234.371195) (xy 372.012779 -234.407918) (xy 371.970763 -234.438444) (xy 371.924489 -234.462022)
			(xy 371.875096 -234.47807) (xy 371.823801 -234.486195) (xy 371.771867 -234.486195) (xy 371.720572 -234.47807)
			(xy 371.671179 -234.462022) (xy 371.624905 -234.438444) (xy 371.582889 -234.407918) (xy 371.546166 -234.371195)
			(xy 371.51564 -234.329179) (xy 371.492062 -234.282905) (xy 371.476014 -234.233512) (xy 371.467889 -234.182217)
			(xy 371.187725 -234.182217) (xy 371.1796 -234.233512) (xy 371.163552 -234.282905) (xy 371.139974 -234.329179)
			(xy 371.109448 -234.371195) (xy 371.072725 -234.407918) (xy 371.030709 -234.438444) (xy 370.984435 -234.462022)
			(xy 370.935042 -234.47807) (xy 370.883747 -234.486195) (xy 370.831813 -234.486195) (xy 370.780518 -234.47807)
			(xy 370.731125 -234.462022) (xy 370.684851 -234.438444) (xy 370.642835 -234.407918) (xy 370.606112 -234.371195)
			(xy 370.575586 -234.329179) (xy 370.552008 -234.282905) (xy 370.53596 -234.233512) (xy 370.527835 -234.182217)
			(xy 370.248179 -234.182217) (xy 370.240054 -234.233512) (xy 370.224006 -234.282905) (xy 370.200428 -234.329179)
			(xy 370.169902 -234.371195) (xy 370.133179 -234.407918) (xy 370.091163 -234.438444) (xy 370.044889 -234.462022)
			(xy 369.995496 -234.47807) (xy 369.944201 -234.486195) (xy 369.892267 -234.486195) (xy 369.840972 -234.47807)
			(xy 369.791579 -234.462022) (xy 369.745305 -234.438444) (xy 369.703289 -234.407918) (xy 369.666566 -234.371195)
			(xy 369.63604 -234.329179) (xy 369.612462 -234.282905) (xy 369.596414 -234.233512) (xy 369.588289 -234.182217)
			(xy 369.30837 -234.182217) (xy 369.300244 -234.233519) (xy 369.284183 -234.282948) (xy 369.260587 -234.329255)
			(xy 369.230038 -234.371301) (xy 369.193286 -234.408051) (xy 369.151238 -234.438598) (xy 369.104929 -234.462191)
			(xy 369.0555 -234.478249) (xy 369.004166 -234.486377) (xy 368.97818 -234.486958) (xy 368.967004 -234.486704)
			(xy 368.965734 -234.486704) (xy 368.955963 -234.487067) (xy 368.937793 -234.494243) (xy 368.930428 -234.500674)
			(xy 368.878612 -234.550966) (xy 368.87158 -234.55828) (xy 368.863571 -234.576899) (xy 368.863118 -234.587034)
			(xy 368.863118 -234.996033) (xy 369.118135 -234.996033) (xy 369.118135 -234.944099) (xy 369.12626 -234.892804)
			(xy 369.142308 -234.843411) (xy 369.165886 -234.797137) (xy 369.196412 -234.755121) (xy 369.233135 -234.718398)
			(xy 369.275151 -234.687872) (xy 369.321425 -234.664294) (xy 369.370818 -234.648246) (xy 369.422113 -234.640121)
			(xy 369.474047 -234.640121) (xy 369.525342 -234.648246) (xy 369.574735 -234.664294) (xy 369.621009 -234.687872)
			(xy 369.663025 -234.718398) (xy 369.699748 -234.755121) (xy 369.730274 -234.797137) (xy 369.753852 -234.843411)
			(xy 369.7699 -234.892804) (xy 369.778025 -234.944099) (xy 369.778534 -234.970066) (xy 369.778025 -234.996033)
			(xy 370.057935 -234.996033) (xy 370.057935 -234.944099) (xy 370.06606 -234.892804) (xy 370.082108 -234.843411)
			(xy 370.105686 -234.797137) (xy 370.136212 -234.755121) (xy 370.172935 -234.718398) (xy 370.214951 -234.687872)
			(xy 370.261225 -234.664294) (xy 370.310618 -234.648246) (xy 370.361913 -234.640121) (xy 370.413847 -234.640121)
			(xy 370.465142 -234.648246) (xy 370.514535 -234.664294) (xy 370.560809 -234.687872) (xy 370.602825 -234.718398)
			(xy 370.639548 -234.755121) (xy 370.670074 -234.797137) (xy 370.693652 -234.843411) (xy 370.7097 -234.892804)
			(xy 370.717825 -234.944099) (xy 370.718334 -234.970066) (xy 370.717825 -234.996033) (xy 370.997735 -234.996033)
			(xy 370.997735 -234.944099) (xy 371.00586 -234.892804) (xy 371.021908 -234.843411) (xy 371.045486 -234.797137)
			(xy 371.076012 -234.755121) (xy 371.112735 -234.718398) (xy 371.154751 -234.687872) (xy 371.201025 -234.664294)
			(xy 371.250418 -234.648246) (xy 371.301713 -234.640121) (xy 371.353647 -234.640121) (xy 371.404942 -234.648246)
			(xy 371.454335 -234.664294) (xy 371.500609 -234.687872) (xy 371.542625 -234.718398) (xy 371.579348 -234.755121)
			(xy 371.609874 -234.797137) (xy 371.633452 -234.843411) (xy 371.6495 -234.892804) (xy 371.657625 -234.944099)
			(xy 371.658134 -234.970066) (xy 371.657625 -234.996033) (xy 371.937535 -234.996033) (xy 371.937535 -234.944099)
			(xy 371.94566 -234.892804) (xy 371.961708 -234.843411) (xy 371.985286 -234.797137) (xy 372.015812 -234.755121)
			(xy 372.052535 -234.718398) (xy 372.094551 -234.687872) (xy 372.140825 -234.664294) (xy 372.190218 -234.648246)
			(xy 372.241513 -234.640121) (xy 372.293447 -234.640121) (xy 372.344742 -234.648246) (xy 372.394135 -234.664294)
			(xy 372.440409 -234.687872) (xy 372.482425 -234.718398) (xy 372.519148 -234.755121) (xy 372.549674 -234.797137)
			(xy 372.573252 -234.843411) (xy 372.5893 -234.892804) (xy 372.597425 -234.944099) (xy 372.597934 -234.970066)
			(xy 372.597425 -234.996033) (xy 372.877589 -234.996033) (xy 372.877589 -234.944099) (xy 372.885714 -234.892804)
			(xy 372.901762 -234.843411) (xy 372.92534 -234.797137) (xy 372.955866 -234.755121) (xy 372.992589 -234.718398)
			(xy 373.034605 -234.687872) (xy 373.080879 -234.664294) (xy 373.130272 -234.648246) (xy 373.181567 -234.640121)
			(xy 373.233501 -234.640121) (xy 373.284796 -234.648246) (xy 373.334189 -234.664294) (xy 373.380463 -234.687872)
			(xy 373.422479 -234.718398) (xy 373.459202 -234.755121) (xy 373.489728 -234.797137) (xy 373.513306 -234.843411)
			(xy 373.529354 -234.892804) (xy 373.537479 -234.944099) (xy 373.537988 -234.970066) (xy 373.537479 -234.996033)
			(xy 373.817135 -234.996033) (xy 373.817135 -234.944099) (xy 373.82526 -234.892804) (xy 373.841308 -234.843411)
			(xy 373.864886 -234.797137) (xy 373.895412 -234.755121) (xy 373.932135 -234.718398) (xy 373.974151 -234.687872)
			(xy 374.020425 -234.664294) (xy 374.069818 -234.648246) (xy 374.121113 -234.640121) (xy 374.173047 -234.640121)
			(xy 374.224342 -234.648246) (xy 374.273735 -234.664294) (xy 374.320009 -234.687872) (xy 374.362025 -234.718398)
			(xy 374.398748 -234.755121) (xy 374.429274 -234.797137) (xy 374.452852 -234.843411) (xy 374.4689 -234.892804)
			(xy 374.477025 -234.944099) (xy 374.477534 -234.970066) (xy 374.477025 -234.996033) (xy 374.756935 -234.996033)
			(xy 374.756935 -234.944099) (xy 374.76506 -234.892804) (xy 374.781108 -234.843411) (xy 374.804686 -234.797137)
			(xy 374.835212 -234.755121) (xy 374.871935 -234.718398) (xy 374.913951 -234.687872) (xy 374.960225 -234.664294)
			(xy 375.009618 -234.648246) (xy 375.060913 -234.640121) (xy 375.112847 -234.640121) (xy 375.164142 -234.648246)
			(xy 375.213535 -234.664294) (xy 375.259809 -234.687872) (xy 375.301825 -234.718398) (xy 375.338548 -234.755121)
			(xy 375.369074 -234.797137) (xy 375.392652 -234.843411) (xy 375.4087 -234.892804) (xy 375.416825 -234.944099)
			(xy 375.417334 -234.970066) (xy 375.416825 -234.996033) (xy 375.696735 -234.996033) (xy 375.696735 -234.944099)
			(xy 375.70486 -234.892804) (xy 375.720908 -234.843411) (xy 375.744486 -234.797137) (xy 375.775012 -234.755121)
			(xy 375.811735 -234.718398) (xy 375.853751 -234.687872) (xy 375.900025 -234.664294) (xy 375.949418 -234.648246)
			(xy 376.000713 -234.640121) (xy 376.052647 -234.640121) (xy 376.103942 -234.648246) (xy 376.153335 -234.664294)
			(xy 376.199609 -234.687872) (xy 376.241625 -234.718398) (xy 376.278348 -234.755121) (xy 376.308874 -234.797137)
			(xy 376.332452 -234.843411) (xy 376.3485 -234.892804) (xy 376.356625 -234.944099) (xy 376.357134 -234.970066)
			(xy 376.356625 -234.996033) (xy 376.636535 -234.996033) (xy 376.636535 -234.944099) (xy 376.64466 -234.892804)
			(xy 376.660708 -234.843411) (xy 376.684286 -234.797137) (xy 376.714812 -234.755121) (xy 376.751535 -234.718398)
			(xy 376.793551 -234.687872) (xy 376.839825 -234.664294) (xy 376.889218 -234.648246) (xy 376.940513 -234.640121)
			(xy 376.992447 -234.640121) (xy 377.043742 -234.648246) (xy 377.093135 -234.664294) (xy 377.139409 -234.687872)
			(xy 377.181425 -234.718398) (xy 377.218148 -234.755121) (xy 377.248674 -234.797137) (xy 377.272252 -234.843411)
			(xy 377.2883 -234.892804) (xy 377.296425 -234.944099) (xy 377.296934 -234.970066) (xy 377.296425 -234.996033)
			(xy 377.576335 -234.996033) (xy 377.576335 -234.944099) (xy 377.58446 -234.892804) (xy 377.600508 -234.843411)
			(xy 377.624086 -234.797137) (xy 377.654612 -234.755121) (xy 377.691335 -234.718398) (xy 377.733351 -234.687872)
			(xy 377.779625 -234.664294) (xy 377.829018 -234.648246) (xy 377.880313 -234.640121) (xy 377.932247 -234.640121)
			(xy 377.983542 -234.648246) (xy 378.032935 -234.664294) (xy 378.079209 -234.687872) (xy 378.121225 -234.718398)
			(xy 378.157948 -234.755121) (xy 378.188474 -234.797137) (xy 378.212052 -234.843411) (xy 378.2281 -234.892804)
			(xy 378.236225 -234.944099) (xy 378.236734 -234.970066) (xy 378.236225 -234.996033) (xy 378.516135 -234.996033)
			(xy 378.516135 -234.944099) (xy 378.52426 -234.892804) (xy 378.540308 -234.843411) (xy 378.563886 -234.797137)
			(xy 378.594412 -234.755121) (xy 378.631135 -234.718398) (xy 378.673151 -234.687872) (xy 378.719425 -234.664294)
			(xy 378.768818 -234.648246) (xy 378.820113 -234.640121) (xy 378.872047 -234.640121) (xy 378.923342 -234.648246)
			(xy 378.972735 -234.664294) (xy 379.019009 -234.687872) (xy 379.061025 -234.718398) (xy 379.097748 -234.755121)
			(xy 379.128274 -234.797137) (xy 379.151852 -234.843411) (xy 379.1679 -234.892804) (xy 379.176025 -234.944099)
			(xy 379.176534 -234.970066) (xy 379.176025 -234.996033) (xy 379.1679 -235.047328) (xy 379.151852 -235.096721)
			(xy 379.128274 -235.142995) (xy 379.097748 -235.185011) (xy 379.061025 -235.221734) (xy 379.019009 -235.25226)
			(xy 378.972735 -235.275838) (xy 378.923342 -235.291886) (xy 378.872047 -235.300011) (xy 378.820113 -235.300011)
			(xy 378.768818 -235.291886) (xy 378.719425 -235.275838) (xy 378.673151 -235.25226) (xy 378.631135 -235.221734)
			(xy 378.594412 -235.185011) (xy 378.563886 -235.142995) (xy 378.540308 -235.096721) (xy 378.52426 -235.047328)
			(xy 378.516135 -234.996033) (xy 378.236225 -234.996033) (xy 378.2281 -235.047328) (xy 378.212052 -235.096721)
			(xy 378.188474 -235.142995) (xy 378.157948 -235.185011) (xy 378.121225 -235.221734) (xy 378.079209 -235.25226)
			(xy 378.032935 -235.275838) (xy 377.983542 -235.291886) (xy 377.932247 -235.300011) (xy 377.880313 -235.300011)
			(xy 377.829018 -235.291886) (xy 377.779625 -235.275838) (xy 377.733351 -235.25226) (xy 377.691335 -235.221734)
			(xy 377.654612 -235.185011) (xy 377.624086 -235.142995) (xy 377.600508 -235.096721) (xy 377.58446 -235.047328)
			(xy 377.576335 -234.996033) (xy 377.296425 -234.996033) (xy 377.2883 -235.047328) (xy 377.272252 -235.096721)
			(xy 377.248674 -235.142995) (xy 377.218148 -235.185011) (xy 377.181425 -235.221734) (xy 377.139409 -235.25226)
			(xy 377.093135 -235.275838) (xy 377.043742 -235.291886) (xy 376.992447 -235.300011) (xy 376.940513 -235.300011)
			(xy 376.889218 -235.291886) (xy 376.839825 -235.275838) (xy 376.793551 -235.25226) (xy 376.751535 -235.221734)
			(xy 376.714812 -235.185011) (xy 376.684286 -235.142995) (xy 376.660708 -235.096721) (xy 376.64466 -235.047328)
			(xy 376.636535 -234.996033) (xy 376.356625 -234.996033) (xy 376.3485 -235.047328) (xy 376.332452 -235.096721)
			(xy 376.308874 -235.142995) (xy 376.278348 -235.185011) (xy 376.241625 -235.221734) (xy 376.199609 -235.25226)
			(xy 376.153335 -235.275838) (xy 376.103942 -235.291886) (xy 376.052647 -235.300011) (xy 376.000713 -235.300011)
			(xy 375.949418 -235.291886) (xy 375.900025 -235.275838) (xy 375.853751 -235.25226) (xy 375.811735 -235.221734)
			(xy 375.775012 -235.185011) (xy 375.744486 -235.142995) (xy 375.720908 -235.096721) (xy 375.70486 -235.047328)
			(xy 375.696735 -234.996033) (xy 375.416825 -234.996033) (xy 375.4087 -235.047328) (xy 375.392652 -235.096721)
			(xy 375.369074 -235.142995) (xy 375.338548 -235.185011) (xy 375.301825 -235.221734) (xy 375.259809 -235.25226)
			(xy 375.213535 -235.275838) (xy 375.164142 -235.291886) (xy 375.112847 -235.300011) (xy 375.060913 -235.300011)
			(xy 375.009618 -235.291886) (xy 374.960225 -235.275838) (xy 374.913951 -235.25226) (xy 374.871935 -235.221734)
			(xy 374.835212 -235.185011) (xy 374.804686 -235.142995) (xy 374.781108 -235.096721) (xy 374.76506 -235.047328)
			(xy 374.756935 -234.996033) (xy 374.477025 -234.996033) (xy 374.4689 -235.047328) (xy 374.452852 -235.096721)
			(xy 374.429274 -235.142995) (xy 374.398748 -235.185011) (xy 374.362025 -235.221734) (xy 374.320009 -235.25226)
			(xy 374.273735 -235.275838) (xy 374.224342 -235.291886) (xy 374.173047 -235.300011) (xy 374.121113 -235.300011)
			(xy 374.069818 -235.291886) (xy 374.020425 -235.275838) (xy 373.974151 -235.25226) (xy 373.932135 -235.221734)
			(xy 373.895412 -235.185011) (xy 373.864886 -235.142995) (xy 373.841308 -235.096721) (xy 373.82526 -235.047328)
			(xy 373.817135 -234.996033) (xy 373.537479 -234.996033) (xy 373.529354 -235.047328) (xy 373.513306 -235.096721)
			(xy 373.489728 -235.142995) (xy 373.459202 -235.185011) (xy 373.422479 -235.221734) (xy 373.380463 -235.25226)
			(xy 373.334189 -235.275838) (xy 373.284796 -235.291886) (xy 373.233501 -235.300011) (xy 373.181567 -235.300011)
			(xy 373.130272 -235.291886) (xy 373.080879 -235.275838) (xy 373.034605 -235.25226) (xy 372.992589 -235.221734)
			(xy 372.955866 -235.185011) (xy 372.92534 -235.142995) (xy 372.901762 -235.096721) (xy 372.885714 -235.047328)
			(xy 372.877589 -234.996033) (xy 372.597425 -234.996033) (xy 372.5893 -235.047328) (xy 372.573252 -235.096721)
			(xy 372.549674 -235.142995) (xy 372.519148 -235.185011) (xy 372.482425 -235.221734) (xy 372.440409 -235.25226)
			(xy 372.394135 -235.275838) (xy 372.344742 -235.291886) (xy 372.293447 -235.300011) (xy 372.241513 -235.300011)
			(xy 372.190218 -235.291886) (xy 372.140825 -235.275838) (xy 372.094551 -235.25226) (xy 372.052535 -235.221734)
			(xy 372.015812 -235.185011) (xy 371.985286 -235.142995) (xy 371.961708 -235.096721) (xy 371.94566 -235.047328)
			(xy 371.937535 -234.996033) (xy 371.657625 -234.996033) (xy 371.6495 -235.047328) (xy 371.633452 -235.096721)
			(xy 371.609874 -235.142995) (xy 371.579348 -235.185011) (xy 371.542625 -235.221734) (xy 371.500609 -235.25226)
			(xy 371.454335 -235.275838) (xy 371.404942 -235.291886) (xy 371.353647 -235.300011) (xy 371.301713 -235.300011)
			(xy 371.250418 -235.291886) (xy 371.201025 -235.275838) (xy 371.154751 -235.25226) (xy 371.112735 -235.221734)
			(xy 371.076012 -235.185011) (xy 371.045486 -235.142995) (xy 371.021908 -235.096721) (xy 371.00586 -235.047328)
			(xy 370.997735 -234.996033) (xy 370.717825 -234.996033) (xy 370.7097 -235.047328) (xy 370.693652 -235.096721)
			(xy 370.670074 -235.142995) (xy 370.639548 -235.185011) (xy 370.602825 -235.221734) (xy 370.560809 -235.25226)
			(xy 370.514535 -235.275838) (xy 370.465142 -235.291886) (xy 370.413847 -235.300011) (xy 370.361913 -235.300011)
			(xy 370.310618 -235.291886) (xy 370.261225 -235.275838) (xy 370.214951 -235.25226) (xy 370.172935 -235.221734)
			(xy 370.136212 -235.185011) (xy 370.105686 -235.142995) (xy 370.082108 -235.096721) (xy 370.06606 -235.047328)
			(xy 370.057935 -234.996033) (xy 369.778025 -234.996033) (xy 369.7699 -235.047328) (xy 369.753852 -235.096721)
			(xy 369.730274 -235.142995) (xy 369.699748 -235.185011) (xy 369.663025 -235.221734) (xy 369.621009 -235.25226)
			(xy 369.574735 -235.275838) (xy 369.525342 -235.291886) (xy 369.474047 -235.300011) (xy 369.422113 -235.300011)
			(xy 369.370818 -235.291886) (xy 369.321425 -235.275838) (xy 369.275151 -235.25226) (xy 369.233135 -235.221734)
			(xy 369.196412 -235.185011) (xy 369.165886 -235.142995) (xy 369.142308 -235.096721) (xy 369.12626 -235.047328)
			(xy 369.118135 -234.996033) (xy 368.863118 -234.996033) (xy 368.863118 -235.809849) (xy 369.588289 -235.809849)
			(xy 369.588289 -235.757915) (xy 369.596414 -235.70662) (xy 369.612462 -235.657227) (xy 369.63604 -235.610953)
			(xy 369.666566 -235.568937) (xy 369.703289 -235.532214) (xy 369.745305 -235.501688) (xy 369.791579 -235.47811)
			(xy 369.840972 -235.462062) (xy 369.892267 -235.453937) (xy 369.944201 -235.453937) (xy 369.995496 -235.462062)
			(xy 370.044889 -235.47811) (xy 370.091163 -235.501688) (xy 370.133179 -235.532214) (xy 370.169902 -235.568937)
			(xy 370.200428 -235.610953) (xy 370.224006 -235.657227) (xy 370.240054 -235.70662) (xy 370.248179 -235.757915)
			(xy 370.248688 -235.783882) (xy 370.248179 -235.809849) (xy 370.528089 -235.809849) (xy 370.528089 -235.757915)
			(xy 370.536214 -235.70662) (xy 370.552262 -235.657227) (xy 370.57584 -235.610953) (xy 370.606366 -235.568937)
			(xy 370.643089 -235.532214) (xy 370.685105 -235.501688) (xy 370.731379 -235.47811) (xy 370.780772 -235.462062)
			(xy 370.832067 -235.453937) (xy 370.884001 -235.453937) (xy 370.935296 -235.462062) (xy 370.984689 -235.47811)
			(xy 371.030963 -235.501688) (xy 371.072979 -235.532214) (xy 371.109702 -235.568937) (xy 371.140228 -235.610953)
			(xy 371.163806 -235.657227) (xy 371.179854 -235.70662) (xy 371.187979 -235.757915) (xy 371.188488 -235.783882)
			(xy 371.187979 -235.809849) (xy 371.467889 -235.809849) (xy 371.467889 -235.757915) (xy 371.476014 -235.70662)
			(xy 371.492062 -235.657227) (xy 371.51564 -235.610953) (xy 371.546166 -235.568937) (xy 371.582889 -235.532214)
			(xy 371.624905 -235.501688) (xy 371.671179 -235.47811) (xy 371.720572 -235.462062) (xy 371.771867 -235.453937)
			(xy 371.823801 -235.453937) (xy 371.875096 -235.462062) (xy 371.924489 -235.47811) (xy 371.970763 -235.501688)
			(xy 372.012779 -235.532214) (xy 372.049502 -235.568937) (xy 372.080028 -235.610953) (xy 372.103606 -235.657227)
			(xy 372.119654 -235.70662) (xy 372.127779 -235.757915) (xy 372.128288 -235.783882) (xy 372.127779 -235.809849)
			(xy 372.407689 -235.809849) (xy 372.407689 -235.757915) (xy 372.415814 -235.70662) (xy 372.431862 -235.657227)
			(xy 372.45544 -235.610953) (xy 372.485966 -235.568937) (xy 372.522689 -235.532214) (xy 372.564705 -235.501688)
			(xy 372.610979 -235.47811) (xy 372.660372 -235.462062) (xy 372.711667 -235.453937) (xy 372.763601 -235.453937)
			(xy 372.814896 -235.462062) (xy 372.864289 -235.47811) (xy 372.910563 -235.501688) (xy 372.952579 -235.532214)
			(xy 372.989302 -235.568937) (xy 373.019828 -235.610953) (xy 373.043406 -235.657227) (xy 373.059454 -235.70662)
			(xy 373.067579 -235.757915) (xy 373.068088 -235.783882) (xy 373.067579 -235.809849) (xy 373.347235 -235.809849)
			(xy 373.347235 -235.757915) (xy 373.35536 -235.70662) (xy 373.371408 -235.657227) (xy 373.394986 -235.610953)
			(xy 373.425512 -235.568937) (xy 373.462235 -235.532214) (xy 373.504251 -235.501688) (xy 373.550525 -235.47811)
			(xy 373.599918 -235.462062) (xy 373.651213 -235.453937) (xy 373.703147 -235.453937) (xy 373.754442 -235.462062)
			(xy 373.803835 -235.47811) (xy 373.850109 -235.501688) (xy 373.892125 -235.532214) (xy 373.928848 -235.568937)
			(xy 373.959374 -235.610953) (xy 373.982952 -235.657227) (xy 373.999 -235.70662) (xy 374.007125 -235.757915)
			(xy 374.007634 -235.783882) (xy 374.007125 -235.809849) (xy 374.287289 -235.809849) (xy 374.287289 -235.757915)
			(xy 374.295414 -235.70662) (xy 374.311462 -235.657227) (xy 374.33504 -235.610953) (xy 374.365566 -235.568937)
			(xy 374.402289 -235.532214) (xy 374.444305 -235.501688) (xy 374.490579 -235.47811) (xy 374.539972 -235.462062)
			(xy 374.591267 -235.453937) (xy 374.643201 -235.453937) (xy 374.694496 -235.462062) (xy 374.743889 -235.47811)
			(xy 374.790163 -235.501688) (xy 374.832179 -235.532214) (xy 374.868902 -235.568937) (xy 374.899428 -235.610953)
			(xy 374.923006 -235.657227) (xy 374.939054 -235.70662) (xy 374.947179 -235.757915) (xy 374.947688 -235.783882)
			(xy 374.947179 -235.809849) (xy 375.227089 -235.809849) (xy 375.227089 -235.757915) (xy 375.235214 -235.70662)
			(xy 375.251262 -235.657227) (xy 375.27484 -235.610953) (xy 375.305366 -235.568937) (xy 375.342089 -235.532214)
			(xy 375.384105 -235.501688) (xy 375.430379 -235.47811) (xy 375.479772 -235.462062) (xy 375.531067 -235.453937)
			(xy 375.583001 -235.453937) (xy 375.634296 -235.462062) (xy 375.683689 -235.47811) (xy 375.729963 -235.501688)
			(xy 375.771979 -235.532214) (xy 375.808702 -235.568937) (xy 375.839228 -235.610953) (xy 375.862806 -235.657227)
			(xy 375.878854 -235.70662) (xy 375.886979 -235.757915) (xy 375.887488 -235.783882) (xy 375.886979 -235.809849)
			(xy 376.166889 -235.809849) (xy 376.166889 -235.757915) (xy 376.175014 -235.70662) (xy 376.191062 -235.657227)
			(xy 376.21464 -235.610953) (xy 376.245166 -235.568937) (xy 376.281889 -235.532214) (xy 376.323905 -235.501688)
			(xy 376.370179 -235.47811) (xy 376.419572 -235.462062) (xy 376.470867 -235.453937) (xy 376.522801 -235.453937)
			(xy 376.574096 -235.462062) (xy 376.623489 -235.47811) (xy 376.669763 -235.501688) (xy 376.711779 -235.532214)
			(xy 376.748502 -235.568937) (xy 376.779028 -235.610953) (xy 376.802606 -235.657227) (xy 376.818654 -235.70662)
			(xy 376.826779 -235.757915) (xy 376.827288 -235.783882) (xy 376.826779 -235.809849) (xy 377.106689 -235.809849)
			(xy 377.106689 -235.757915) (xy 377.114814 -235.70662) (xy 377.130862 -235.657227) (xy 377.15444 -235.610953)
			(xy 377.184966 -235.568937) (xy 377.221689 -235.532214) (xy 377.263705 -235.501688) (xy 377.309979 -235.47811)
			(xy 377.359372 -235.462062) (xy 377.410667 -235.453937) (xy 377.462601 -235.453937) (xy 377.513896 -235.462062)
			(xy 377.563289 -235.47811) (xy 377.609563 -235.501688) (xy 377.651579 -235.532214) (xy 377.688302 -235.568937)
			(xy 377.718828 -235.610953) (xy 377.742406 -235.657227) (xy 377.758454 -235.70662) (xy 377.766579 -235.757915)
			(xy 377.767088 -235.783882) (xy 377.766579 -235.809849) (xy 378.046489 -235.809849) (xy 378.046489 -235.757915)
			(xy 378.054614 -235.70662) (xy 378.070662 -235.657227) (xy 378.09424 -235.610953) (xy 378.124766 -235.568937)
			(xy 378.161489 -235.532214) (xy 378.203505 -235.501688) (xy 378.249779 -235.47811) (xy 378.299172 -235.462062)
			(xy 378.350467 -235.453937) (xy 378.402401 -235.453937) (xy 378.453696 -235.462062) (xy 378.503089 -235.47811)
			(xy 378.549363 -235.501688) (xy 378.591379 -235.532214) (xy 378.628102 -235.568937) (xy 378.658628 -235.610953)
			(xy 378.682206 -235.657227) (xy 378.698254 -235.70662) (xy 378.706379 -235.757915) (xy 378.706888 -235.783882)
			(xy 378.706379 -235.809849) (xy 378.986289 -235.809849) (xy 378.986289 -235.757915) (xy 378.994414 -235.70662)
			(xy 379.010462 -235.657227) (xy 379.03404 -235.610953) (xy 379.064566 -235.568937) (xy 379.101289 -235.532214)
			(xy 379.143305 -235.501688) (xy 379.189579 -235.47811) (xy 379.238972 -235.462062) (xy 379.290267 -235.453937)
			(xy 379.342201 -235.453937) (xy 379.393496 -235.462062) (xy 379.442889 -235.47811) (xy 379.489163 -235.501688)
			(xy 379.531179 -235.532214) (xy 379.567902 -235.568937) (xy 379.598428 -235.610953) (xy 379.622006 -235.657227)
			(xy 379.638054 -235.70662) (xy 379.646179 -235.757915) (xy 379.646688 -235.783882) (xy 379.646179 -235.809849)
			(xy 379.638054 -235.861144) (xy 379.622006 -235.910537) (xy 379.598428 -235.956811) (xy 379.567902 -235.998827)
			(xy 379.531179 -236.03555) (xy 379.489163 -236.066076) (xy 379.442889 -236.089654) (xy 379.393496 -236.105702)
			(xy 379.342201 -236.113827) (xy 379.290267 -236.113827) (xy 379.238972 -236.105702) (xy 379.189579 -236.089654)
			(xy 379.143305 -236.066076) (xy 379.101289 -236.03555) (xy 379.064566 -235.998827) (xy 379.03404 -235.956811)
			(xy 379.010462 -235.910537) (xy 378.994414 -235.861144) (xy 378.986289 -235.809849) (xy 378.706379 -235.809849)
			(xy 378.698254 -235.861144) (xy 378.682206 -235.910537) (xy 378.658628 -235.956811) (xy 378.628102 -235.998827)
			(xy 378.591379 -236.03555) (xy 378.549363 -236.066076) (xy 378.503089 -236.089654) (xy 378.453696 -236.105702)
			(xy 378.402401 -236.113827) (xy 378.350467 -236.113827) (xy 378.299172 -236.105702) (xy 378.249779 -236.089654)
			(xy 378.203505 -236.066076) (xy 378.161489 -236.03555) (xy 378.124766 -235.998827) (xy 378.09424 -235.956811)
			(xy 378.070662 -235.910537) (xy 378.054614 -235.861144) (xy 378.046489 -235.809849) (xy 377.766579 -235.809849)
			(xy 377.758454 -235.861144) (xy 377.742406 -235.910537) (xy 377.718828 -235.956811) (xy 377.688302 -235.998827)
			(xy 377.651579 -236.03555) (xy 377.609563 -236.066076) (xy 377.563289 -236.089654) (xy 377.513896 -236.105702)
			(xy 377.462601 -236.113827) (xy 377.410667 -236.113827) (xy 377.359372 -236.105702) (xy 377.309979 -236.089654)
			(xy 377.263705 -236.066076) (xy 377.221689 -236.03555) (xy 377.184966 -235.998827) (xy 377.15444 -235.956811)
			(xy 377.130862 -235.910537) (xy 377.114814 -235.861144) (xy 377.106689 -235.809849) (xy 376.826779 -235.809849)
			(xy 376.818654 -235.861144) (xy 376.802606 -235.910537) (xy 376.779028 -235.956811) (xy 376.748502 -235.998827)
			(xy 376.711779 -236.03555) (xy 376.669763 -236.066076) (xy 376.623489 -236.089654) (xy 376.574096 -236.105702)
			(xy 376.522801 -236.113827) (xy 376.470867 -236.113827) (xy 376.419572 -236.105702) (xy 376.370179 -236.089654)
			(xy 376.323905 -236.066076) (xy 376.281889 -236.03555) (xy 376.245166 -235.998827) (xy 376.21464 -235.956811)
			(xy 376.191062 -235.910537) (xy 376.175014 -235.861144) (xy 376.166889 -235.809849) (xy 375.886979 -235.809849)
			(xy 375.878854 -235.861144) (xy 375.862806 -235.910537) (xy 375.839228 -235.956811) (xy 375.808702 -235.998827)
			(xy 375.771979 -236.03555) (xy 375.729963 -236.066076) (xy 375.683689 -236.089654) (xy 375.634296 -236.105702)
			(xy 375.583001 -236.113827) (xy 375.531067 -236.113827) (xy 375.479772 -236.105702) (xy 375.430379 -236.089654)
			(xy 375.384105 -236.066076) (xy 375.342089 -236.03555) (xy 375.305366 -235.998827) (xy 375.27484 -235.956811)
			(xy 375.251262 -235.910537) (xy 375.235214 -235.861144) (xy 375.227089 -235.809849) (xy 374.947179 -235.809849)
			(xy 374.939054 -235.861144) (xy 374.923006 -235.910537) (xy 374.899428 -235.956811) (xy 374.868902 -235.998827)
			(xy 374.832179 -236.03555) (xy 374.790163 -236.066076) (xy 374.743889 -236.089654) (xy 374.694496 -236.105702)
			(xy 374.643201 -236.113827) (xy 374.591267 -236.113827) (xy 374.539972 -236.105702) (xy 374.490579 -236.089654)
			(xy 374.444305 -236.066076) (xy 374.402289 -236.03555) (xy 374.365566 -235.998827) (xy 374.33504 -235.956811)
			(xy 374.311462 -235.910537) (xy 374.295414 -235.861144) (xy 374.287289 -235.809849) (xy 374.007125 -235.809849)
			(xy 373.999 -235.861144) (xy 373.982952 -235.910537) (xy 373.959374 -235.956811) (xy 373.928848 -235.998827)
			(xy 373.892125 -236.03555) (xy 373.850109 -236.066076) (xy 373.803835 -236.089654) (xy 373.754442 -236.105702)
			(xy 373.703147 -236.113827) (xy 373.651213 -236.113827) (xy 373.599918 -236.105702) (xy 373.550525 -236.089654)
			(xy 373.504251 -236.066076) (xy 373.462235 -236.03555) (xy 373.425512 -235.998827) (xy 373.394986 -235.956811)
			(xy 373.371408 -235.910537) (xy 373.35536 -235.861144) (xy 373.347235 -235.809849) (xy 373.067579 -235.809849)
			(xy 373.059454 -235.861144) (xy 373.043406 -235.910537) (xy 373.019828 -235.956811) (xy 372.989302 -235.998827)
			(xy 372.952579 -236.03555) (xy 372.910563 -236.066076) (xy 372.864289 -236.089654) (xy 372.814896 -236.105702)
			(xy 372.763601 -236.113827) (xy 372.711667 -236.113827) (xy 372.660372 -236.105702) (xy 372.610979 -236.089654)
			(xy 372.564705 -236.066076) (xy 372.522689 -236.03555) (xy 372.485966 -235.998827) (xy 372.45544 -235.956811)
			(xy 372.431862 -235.910537) (xy 372.415814 -235.861144) (xy 372.407689 -235.809849) (xy 372.127779 -235.809849)
			(xy 372.119654 -235.861144) (xy 372.103606 -235.910537) (xy 372.080028 -235.956811) (xy 372.049502 -235.998827)
			(xy 372.012779 -236.03555) (xy 371.970763 -236.066076) (xy 371.924489 -236.089654) (xy 371.875096 -236.105702)
			(xy 371.823801 -236.113827) (xy 371.771867 -236.113827) (xy 371.720572 -236.105702) (xy 371.671179 -236.089654)
			(xy 371.624905 -236.066076) (xy 371.582889 -236.03555) (xy 371.546166 -235.998827) (xy 371.51564 -235.956811)
			(xy 371.492062 -235.910537) (xy 371.476014 -235.861144) (xy 371.467889 -235.809849) (xy 371.187979 -235.809849)
			(xy 371.179854 -235.861144) (xy 371.163806 -235.910537) (xy 371.140228 -235.956811) (xy 371.109702 -235.998827)
			(xy 371.072979 -236.03555) (xy 371.030963 -236.066076) (xy 370.984689 -236.089654) (xy 370.935296 -236.105702)
			(xy 370.884001 -236.113827) (xy 370.832067 -236.113827) (xy 370.780772 -236.105702) (xy 370.731379 -236.089654)
			(xy 370.685105 -236.066076) (xy 370.643089 -236.03555) (xy 370.606366 -235.998827) (xy 370.57584 -235.956811)
			(xy 370.552262 -235.910537) (xy 370.536214 -235.861144) (xy 370.528089 -235.809849) (xy 370.248179 -235.809849)
			(xy 370.240054 -235.861144) (xy 370.224006 -235.910537) (xy 370.200428 -235.956811) (xy 370.169902 -235.998827)
			(xy 370.133179 -236.03555) (xy 370.091163 -236.066076) (xy 370.044889 -236.089654) (xy 369.995496 -236.105702)
			(xy 369.944201 -236.113827) (xy 369.892267 -236.113827) (xy 369.840972 -236.105702) (xy 369.791579 -236.089654)
			(xy 369.745305 -236.066076) (xy 369.703289 -236.03555) (xy 369.666566 -235.998827) (xy 369.63604 -235.956811)
			(xy 369.612462 -235.910537) (xy 369.596414 -235.861144) (xy 369.588289 -235.809849) (xy 368.863118 -235.809849)
			(xy 368.863118 -235.850176) (xy 368.863643 -235.859776) (xy 368.870942 -235.877547) (xy 368.877342 -235.88472)
			(xy 368.899694 -235.907072) (xy 368.932206 -235.921296) (xy 368.940842 -235.922058) (xy 368.958699 -235.923625)
			(xy 368.993955 -235.930118) (xy 369.0112 -235.935012) (xy 369.034501 -235.942458) (xy 369.078775 -235.963256)
			(xy 369.1195 -235.990352) (xy 369.155786 -236.023156) (xy 369.186841 -236.060949) (xy 369.211987 -236.102906)
			(xy 369.230674 -236.148112) (xy 369.237006 -236.17174) (xy 369.238784 -236.17809) (xy 369.26139 -236.209332)
			(xy 369.322858 -236.246924) (xy 369.32891 -236.250362) (xy 369.342316 -236.254087) (xy 369.349274 -236.25429)
			(xy 369.361212 -236.252766) (xy 369.364006 -236.252004) (xy 369.384825 -236.247237) (xy 369.427232 -236.242145)
			(xy 369.448588 -236.241844) (xy 369.45062 -236.241844) (xy 369.478498 -236.242543) (xy 369.533528 -236.251548)
			(xy 369.586482 -236.269022) (xy 369.636065 -236.294537) (xy 369.681064 -236.327469) (xy 369.720379 -236.367014)
			(xy 369.753049 -236.412204) (xy 369.778275 -236.461934) (xy 369.79544 -236.514989) (xy 369.804125 -236.570071)
			(xy 369.804696 -236.597952) (xy 369.804216 -236.623919) (xy 370.057935 -236.623919) (xy 370.057935 -236.571985)
			(xy 370.06606 -236.52069) (xy 370.082108 -236.471297) (xy 370.105686 -236.425023) (xy 370.136212 -236.383007)
			(xy 370.172935 -236.346284) (xy 370.214951 -236.315758) (xy 370.261225 -236.29218) (xy 370.310618 -236.276132)
			(xy 370.361913 -236.268007) (xy 370.413847 -236.268007) (xy 370.465142 -236.276132) (xy 370.514535 -236.29218)
			(xy 370.560809 -236.315758) (xy 370.602825 -236.346284) (xy 370.639548 -236.383007) (xy 370.670074 -236.425023)
			(xy 370.693652 -236.471297) (xy 370.7097 -236.52069) (xy 370.717825 -236.571985) (xy 370.718334 -236.597952)
			(xy 370.717825 -236.623919) (xy 370.997735 -236.623919) (xy 370.997735 -236.571985) (xy 371.00586 -236.52069)
			(xy 371.021908 -236.471297) (xy 371.045486 -236.425023) (xy 371.076012 -236.383007) (xy 371.112735 -236.346284)
			(xy 371.154751 -236.315758) (xy 371.201025 -236.29218) (xy 371.250418 -236.276132) (xy 371.301713 -236.268007)
			(xy 371.353647 -236.268007) (xy 371.404942 -236.276132) (xy 371.454335 -236.29218) (xy 371.500609 -236.315758)
			(xy 371.542625 -236.346284) (xy 371.579348 -236.383007) (xy 371.609874 -236.425023) (xy 371.633452 -236.471297)
			(xy 371.6495 -236.52069) (xy 371.657625 -236.571985) (xy 371.658134 -236.597952) (xy 371.657625 -236.623919)
			(xy 371.937535 -236.623919) (xy 371.937535 -236.571985) (xy 371.94566 -236.52069) (xy 371.961708 -236.471297)
			(xy 371.985286 -236.425023) (xy 372.015812 -236.383007) (xy 372.052535 -236.346284) (xy 372.094551 -236.315758)
			(xy 372.140825 -236.29218) (xy 372.190218 -236.276132) (xy 372.241513 -236.268007) (xy 372.293447 -236.268007)
			(xy 372.344742 -236.276132) (xy 372.394135 -236.29218) (xy 372.440409 -236.315758) (xy 372.482425 -236.346284)
			(xy 372.519148 -236.383007) (xy 372.549674 -236.425023) (xy 372.573252 -236.471297) (xy 372.5893 -236.52069)
			(xy 372.597425 -236.571985) (xy 372.597934 -236.597952) (xy 372.597425 -236.623919) (xy 372.877335 -236.623919)
			(xy 372.877335 -236.571985) (xy 372.88546 -236.52069) (xy 372.901508 -236.471297) (xy 372.925086 -236.425023)
			(xy 372.955612 -236.383007) (xy 372.992335 -236.346284) (xy 373.034351 -236.315758) (xy 373.080625 -236.29218)
			(xy 373.130018 -236.276132) (xy 373.181313 -236.268007) (xy 373.233247 -236.268007) (xy 373.284542 -236.276132)
			(xy 373.333935 -236.29218) (xy 373.380209 -236.315758) (xy 373.422225 -236.346284) (xy 373.458948 -236.383007)
			(xy 373.489474 -236.425023) (xy 373.513052 -236.471297) (xy 373.5291 -236.52069) (xy 373.537225 -236.571985)
			(xy 373.537734 -236.597952) (xy 373.537225 -236.623919) (xy 373.817135 -236.623919) (xy 373.817135 -236.571985)
			(xy 373.82526 -236.52069) (xy 373.841308 -236.471297) (xy 373.864886 -236.425023) (xy 373.895412 -236.383007)
			(xy 373.932135 -236.346284) (xy 373.974151 -236.315758) (xy 374.020425 -236.29218) (xy 374.069818 -236.276132)
			(xy 374.121113 -236.268007) (xy 374.173047 -236.268007) (xy 374.224342 -236.276132) (xy 374.273735 -236.29218)
			(xy 374.320009 -236.315758) (xy 374.362025 -236.346284) (xy 374.398748 -236.383007) (xy 374.429274 -236.425023)
			(xy 374.452852 -236.471297) (xy 374.4689 -236.52069) (xy 374.477025 -236.571985) (xy 374.477534 -236.597952)
			(xy 374.477025 -236.623919) (xy 374.756935 -236.623919) (xy 374.756935 -236.571985) (xy 374.76506 -236.52069)
			(xy 374.781108 -236.471297) (xy 374.804686 -236.425023) (xy 374.835212 -236.383007) (xy 374.871935 -236.346284)
			(xy 374.913951 -236.315758) (xy 374.960225 -236.29218) (xy 375.009618 -236.276132) (xy 375.060913 -236.268007)
			(xy 375.112847 -236.268007) (xy 375.164142 -236.276132) (xy 375.213535 -236.29218) (xy 375.259809 -236.315758)
			(xy 375.301825 -236.346284) (xy 375.338548 -236.383007) (xy 375.369074 -236.425023) (xy 375.392652 -236.471297)
			(xy 375.4087 -236.52069) (xy 375.416825 -236.571985) (xy 375.417334 -236.597952) (xy 375.416825 -236.623919)
			(xy 375.696735 -236.623919) (xy 375.696735 -236.571985) (xy 375.70486 -236.52069) (xy 375.720908 -236.471297)
			(xy 375.744486 -236.425023) (xy 375.775012 -236.383007) (xy 375.811735 -236.346284) (xy 375.853751 -236.315758)
			(xy 375.900025 -236.29218) (xy 375.949418 -236.276132) (xy 376.000713 -236.268007) (xy 376.052647 -236.268007)
			(xy 376.103942 -236.276132) (xy 376.153335 -236.29218) (xy 376.199609 -236.315758) (xy 376.241625 -236.346284)
			(xy 376.278348 -236.383007) (xy 376.308874 -236.425023) (xy 376.332452 -236.471297) (xy 376.3485 -236.52069)
			(xy 376.356625 -236.571985) (xy 376.357134 -236.597952) (xy 376.356625 -236.623919) (xy 376.636789 -236.623919)
			(xy 376.636789 -236.571985) (xy 376.644914 -236.52069) (xy 376.660962 -236.471297) (xy 376.68454 -236.425023)
			(xy 376.715066 -236.383007) (xy 376.751789 -236.346284) (xy 376.793805 -236.315758) (xy 376.840079 -236.29218)
			(xy 376.889472 -236.276132) (xy 376.940767 -236.268007) (xy 376.992701 -236.268007) (xy 377.043996 -236.276132)
			(xy 377.093389 -236.29218) (xy 377.139663 -236.315758) (xy 377.181679 -236.346284) (xy 377.218402 -236.383007)
			(xy 377.248928 -236.425023) (xy 377.272506 -236.471297) (xy 377.288554 -236.52069) (xy 377.296679 -236.571985)
			(xy 377.297188 -236.597952) (xy 377.296679 -236.623919) (xy 377.576335 -236.623919) (xy 377.576335 -236.571985)
			(xy 377.58446 -236.52069) (xy 377.600508 -236.471297) (xy 377.624086 -236.425023) (xy 377.654612 -236.383007)
			(xy 377.691335 -236.346284) (xy 377.733351 -236.315758) (xy 377.779625 -236.29218) (xy 377.829018 -236.276132)
			(xy 377.880313 -236.268007) (xy 377.932247 -236.268007) (xy 377.983542 -236.276132) (xy 378.032935 -236.29218)
			(xy 378.079209 -236.315758) (xy 378.121225 -236.346284) (xy 378.157948 -236.383007) (xy 378.188474 -236.425023)
			(xy 378.212052 -236.471297) (xy 378.2281 -236.52069) (xy 378.236225 -236.571985) (xy 378.236734 -236.597952)
			(xy 378.236225 -236.623919) (xy 378.516135 -236.623919) (xy 378.516135 -236.571985) (xy 378.52426 -236.52069)
			(xy 378.540308 -236.471297) (xy 378.563886 -236.425023) (xy 378.594412 -236.383007) (xy 378.631135 -236.346284)
			(xy 378.673151 -236.315758) (xy 378.719425 -236.29218) (xy 378.768818 -236.276132) (xy 378.820113 -236.268007)
			(xy 378.872047 -236.268007) (xy 378.923342 -236.276132) (xy 378.972735 -236.29218) (xy 379.019009 -236.315758)
			(xy 379.061025 -236.346284) (xy 379.097748 -236.383007) (xy 379.128274 -236.425023) (xy 379.151852 -236.471297)
			(xy 379.1679 -236.52069) (xy 379.176025 -236.571985) (xy 379.176534 -236.597952) (xy 379.176025 -236.623919)
			(xy 379.1679 -236.675214) (xy 379.151852 -236.724607) (xy 379.128274 -236.770881) (xy 379.097748 -236.812897)
			(xy 379.061025 -236.84962) (xy 379.019009 -236.880146) (xy 378.972735 -236.903724) (xy 378.923342 -236.919772)
			(xy 378.872047 -236.927897) (xy 378.820113 -236.927897) (xy 378.768818 -236.919772) (xy 378.719425 -236.903724)
			(xy 378.673151 -236.880146) (xy 378.631135 -236.84962) (xy 378.594412 -236.812897) (xy 378.563886 -236.770881)
			(xy 378.540308 -236.724607) (xy 378.52426 -236.675214) (xy 378.516135 -236.623919) (xy 378.236225 -236.623919)
			(xy 378.2281 -236.675214) (xy 378.212052 -236.724607) (xy 378.188474 -236.770881) (xy 378.157948 -236.812897)
			(xy 378.121225 -236.84962) (xy 378.079209 -236.880146) (xy 378.032935 -236.903724) (xy 377.983542 -236.919772)
			(xy 377.932247 -236.927897) (xy 377.880313 -236.927897) (xy 377.829018 -236.919772) (xy 377.779625 -236.903724)
			(xy 377.733351 -236.880146) (xy 377.691335 -236.84962) (xy 377.654612 -236.812897) (xy 377.624086 -236.770881)
			(xy 377.600508 -236.724607) (xy 377.58446 -236.675214) (xy 377.576335 -236.623919) (xy 377.296679 -236.623919)
			(xy 377.288554 -236.675214) (xy 377.272506 -236.724607) (xy 377.248928 -236.770881) (xy 377.218402 -236.812897)
			(xy 377.181679 -236.84962) (xy 377.139663 -236.880146) (xy 377.093389 -236.903724) (xy 377.043996 -236.919772)
			(xy 376.992701 -236.927897) (xy 376.940767 -236.927897) (xy 376.889472 -236.919772) (xy 376.840079 -236.903724)
			(xy 376.793805 -236.880146) (xy 376.751789 -236.84962) (xy 376.715066 -236.812897) (xy 376.68454 -236.770881)
			(xy 376.660962 -236.724607) (xy 376.644914 -236.675214) (xy 376.636789 -236.623919) (xy 376.356625 -236.623919)
			(xy 376.3485 -236.675214) (xy 376.332452 -236.724607) (xy 376.308874 -236.770881) (xy 376.278348 -236.812897)
			(xy 376.241625 -236.84962) (xy 376.199609 -236.880146) (xy 376.153335 -236.903724) (xy 376.103942 -236.919772)
			(xy 376.052647 -236.927897) (xy 376.000713 -236.927897) (xy 375.949418 -236.919772) (xy 375.900025 -236.903724)
			(xy 375.853751 -236.880146) (xy 375.811735 -236.84962) (xy 375.775012 -236.812897) (xy 375.744486 -236.770881)
			(xy 375.720908 -236.724607) (xy 375.70486 -236.675214) (xy 375.696735 -236.623919) (xy 375.416825 -236.623919)
			(xy 375.4087 -236.675214) (xy 375.392652 -236.724607) (xy 375.369074 -236.770881) (xy 375.338548 -236.812897)
			(xy 375.301825 -236.84962) (xy 375.259809 -236.880146) (xy 375.213535 -236.903724) (xy 375.164142 -236.919772)
			(xy 375.112847 -236.927897) (xy 375.060913 -236.927897) (xy 375.009618 -236.919772) (xy 374.960225 -236.903724)
			(xy 374.913951 -236.880146) (xy 374.871935 -236.84962) (xy 374.835212 -236.812897) (xy 374.804686 -236.770881)
			(xy 374.781108 -236.724607) (xy 374.76506 -236.675214) (xy 374.756935 -236.623919) (xy 374.477025 -236.623919)
			(xy 374.4689 -236.675214) (xy 374.452852 -236.724607) (xy 374.429274 -236.770881) (xy 374.398748 -236.812897)
			(xy 374.362025 -236.84962) (xy 374.320009 -236.880146) (xy 374.273735 -236.903724) (xy 374.224342 -236.919772)
			(xy 374.173047 -236.927897) (xy 374.121113 -236.927897) (xy 374.069818 -236.919772) (xy 374.020425 -236.903724)
			(xy 373.974151 -236.880146) (xy 373.932135 -236.84962) (xy 373.895412 -236.812897) (xy 373.864886 -236.770881)
			(xy 373.841308 -236.724607) (xy 373.82526 -236.675214) (xy 373.817135 -236.623919) (xy 373.537225 -236.623919)
			(xy 373.5291 -236.675214) (xy 373.513052 -236.724607) (xy 373.489474 -236.770881) (xy 373.458948 -236.812897)
			(xy 373.422225 -236.84962) (xy 373.380209 -236.880146) (xy 373.333935 -236.903724) (xy 373.284542 -236.919772)
			(xy 373.233247 -236.927897) (xy 373.181313 -236.927897) (xy 373.130018 -236.919772) (xy 373.080625 -236.903724)
			(xy 373.034351 -236.880146) (xy 372.992335 -236.84962) (xy 372.955612 -236.812897) (xy 372.925086 -236.770881)
			(xy 372.901508 -236.724607) (xy 372.88546 -236.675214) (xy 372.877335 -236.623919) (xy 372.597425 -236.623919)
			(xy 372.5893 -236.675214) (xy 372.573252 -236.724607) (xy 372.549674 -236.770881) (xy 372.519148 -236.812897)
			(xy 372.482425 -236.84962) (xy 372.440409 -236.880146) (xy 372.394135 -236.903724) (xy 372.344742 -236.919772)
			(xy 372.293447 -236.927897) (xy 372.241513 -236.927897) (xy 372.190218 -236.919772) (xy 372.140825 -236.903724)
			(xy 372.094551 -236.880146) (xy 372.052535 -236.84962) (xy 372.015812 -236.812897) (xy 371.985286 -236.770881)
			(xy 371.961708 -236.724607) (xy 371.94566 -236.675214) (xy 371.937535 -236.623919) (xy 371.657625 -236.623919)
			(xy 371.6495 -236.675214) (xy 371.633452 -236.724607) (xy 371.609874 -236.770881) (xy 371.579348 -236.812897)
			(xy 371.542625 -236.84962) (xy 371.500609 -236.880146) (xy 371.454335 -236.903724) (xy 371.404942 -236.919772)
			(xy 371.353647 -236.927897) (xy 371.301713 -236.927897) (xy 371.250418 -236.919772) (xy 371.201025 -236.903724)
			(xy 371.154751 -236.880146) (xy 371.112735 -236.84962) (xy 371.076012 -236.812897) (xy 371.045486 -236.770881)
			(xy 371.021908 -236.724607) (xy 371.00586 -236.675214) (xy 370.997735 -236.623919) (xy 370.717825 -236.623919)
			(xy 370.7097 -236.675214) (xy 370.693652 -236.724607) (xy 370.670074 -236.770881) (xy 370.639548 -236.812897)
			(xy 370.602825 -236.84962) (xy 370.560809 -236.880146) (xy 370.514535 -236.903724) (xy 370.465142 -236.919772)
			(xy 370.413847 -236.927897) (xy 370.361913 -236.927897) (xy 370.310618 -236.919772) (xy 370.261225 -236.903724)
			(xy 370.214951 -236.880146) (xy 370.172935 -236.84962) (xy 370.136212 -236.812897) (xy 370.105686 -236.770881)
			(xy 370.082108 -236.724607) (xy 370.06606 -236.675214) (xy 370.057935 -236.623919) (xy 369.804216 -236.623919)
			(xy 369.804179 -236.625939) (xy 369.795429 -236.681226) (xy 369.778137 -236.734463) (xy 369.75273 -236.784339)
			(xy 369.719831 -236.829626) (xy 369.680253 -236.869208) (xy 369.63497 -236.902111) (xy 369.585096 -236.927524)
			(xy 369.531861 -236.944821) (xy 369.476575 -236.953576) (xy 369.448588 -236.95406) (xy 369.421143 -236.953559)
			(xy 369.366903 -236.945147) (xy 369.314597 -236.928508) (xy 369.265465 -236.904038) (xy 369.220671 -236.872315)
			(xy 369.181278 -236.834092) (xy 369.14822 -236.790276) (xy 369.122279 -236.741904) (xy 369.104071 -236.690123)
			(xy 369.098576 -236.66323) (xy 369.097306 -236.657642) (xy 369.076732 -236.62513) (xy 369.017296 -236.583982)
			(xy 369.01121 -236.580433) (xy 368.997669 -236.576569) (xy 368.990626 -236.576362) (xy 368.979704 -236.576362)
			(xy 368.975132 -236.577124) (xy 368.960277 -236.579657) (xy 368.930257 -236.582328) (xy 368.915188 -236.582458)
			(xy 368.888762 -236.581883) (xy 368.8366 -236.573363) (xy 368.786457 -236.556654) (xy 368.739611 -236.532181)
			(xy 368.697254 -236.500568) (xy 368.660466 -236.462619) (xy 368.644932 -236.441234) (xy 368.63909 -236.432598)
			(xy 368.602768 -236.410246) (xy 368.52225 -236.402118) (xy 368.511895 -236.402199) (xy 368.492605 -236.409666)
			(xy 368.484912 -236.416596) (xy 368.398806 -236.502702) (xy 368.391569 -236.509419) (xy 368.373364 -236.517021)
			(xy 368.3635 -236.517434) (xy 364.358428 -236.517434) (xy 364.34859 -236.516899) (xy 364.330426 -236.509315)
			(xy 364.323122 -236.502702) (xy 363.822488 -236.002068) (xy 363.815807 -235.99475) (xy 363.808339 -235.976412)
			(xy 363.80801 -235.966508) (xy 363.80801 -233.71937) (xy 363.765084 -233.670348) (xy 363.753654 -233.668062)
			(xy 363.728348 -233.663241) (xy 363.67953 -233.646799) (xy 363.633854 -233.622983) (xy 363.592424 -233.592371)
			(xy 363.556245 -233.555703) (xy 363.52619 -233.513867) (xy 363.502989 -233.467875) (xy 363.487203 -233.418842)
			(xy 363.479213 -233.367953) (xy 363.479214 -233.31644) (xy 363.487204 -233.265552) (xy 363.502992 -233.216518)
			(xy 363.526194 -233.170527) (xy 363.556249 -233.128692) (xy 363.59243 -233.092024) (xy 363.63386 -233.061413)
			(xy 363.679537 -233.037598) (xy 363.728355 -233.021157) (xy 363.753654 -233.016298) (xy 363.765084 -233.014012)
			(xy 363.80801 -232.96499) (xy 363.80801 -232.091738) (xy 363.765084 -232.042716) (xy 363.753654 -232.04043)
			(xy 363.728343 -232.035609) (xy 363.679515 -232.019165) (xy 363.633828 -231.995346) (xy 363.592389 -231.964729)
			(xy 363.556201 -231.928055) (xy 363.526139 -231.886212) (xy 363.502932 -231.840212) (xy 363.48714 -231.791168)
			(xy 363.479147 -231.740269) (xy 363.479146 -231.688747) (xy 363.487136 -231.637847) (xy 363.502925 -231.588803)
			(xy 363.526131 -231.542802) (xy 363.55619 -231.500957) (xy 363.592377 -231.464281) (xy 363.633814 -231.433662)
			(xy 363.6795 -231.409841) (xy 363.728327 -231.393395) (xy 363.753654 -231.388666) (xy 363.765084 -231.38638)
			(xy 363.80801 -231.337358) (xy 363.80801 -230.923846) (xy 363.807495 -230.914096) (xy 363.800046 -230.896067)
			(xy 363.793532 -230.888794) (xy 363.784642 -230.879904) (xy 363.777276 -230.87323) (xy 363.758946 -230.865593)
			(xy 363.739089 -230.865468) (xy 363.720665 -230.872874) (xy 363.706418 -230.886707) (xy 363.702092 -230.895652)
			(xy 363.695488 -230.910384) (xy 363.695488 -230.91267) (xy 363.695234 -230.919528) (xy 363.693289 -230.946494)
			(xy 363.682274 -230.999423) (xy 363.663385 -231.05008) (xy 363.637058 -231.097299) (xy 363.603896 -231.139997)
			(xy 363.564661 -231.177192) (xy 363.520255 -231.20803) (xy 363.471699 -231.231802) (xy 363.420107 -231.247962)
			(xy 363.366666 -231.256138) (xy 363.339634 -231.256586) (xy 363.311648 -231.256068) (xy 363.256363 -231.247316)
			(xy 363.203129 -231.230023) (xy 363.153255 -231.204614) (xy 363.107971 -231.171716) (xy 363.068392 -231.132138)
			(xy 363.035492 -231.086855) (xy 363.010081 -231.036982) (xy 362.992787 -230.983749) (xy 362.984033 -230.928464)
			(xy 362.983526 -230.900478) (xy 362.984048 -230.872861) (xy 362.992581 -230.818289) (xy 363.009438 -230.765689)
			(xy 363.034215 -230.716324) (xy 363.066317 -230.671376) (xy 363.104976 -230.631925) (xy 363.149262 -230.598916)
			(xy 363.198115 -230.573142) (xy 363.224064 -230.563674) (xy 363.232954 -230.560626) (xy 363.266228 -230.525066)
			(xy 363.287564 -230.438198) (xy 363.288874 -230.426219) (xy 363.281568 -230.403293) (xy 363.273594 -230.394256)
			(xy 363.239558 -230.36022) (xy 363.233185 -230.354438) (xy 363.217603 -230.347164) (xy 363.209078 -230.345996)
			(xy 363.142784 -230.34371) (xy 363.13916 -230.34388) (xy 363.132018 -230.345153) (xy 363.12856 -230.34625)
			(xy 363.103414 -230.355648) (xy 363.09681 -230.360982) (xy 363.077569 -230.376372) (xy 363.035651 -230.402263)
			(xy 362.990563 -230.422128) (xy 362.943167 -230.435587) (xy 362.894369 -230.442384) (xy 362.869734 -230.44277)
			(xy 362.841748 -230.442252) (xy 362.786465 -230.4335) (xy 362.733231 -230.416207) (xy 362.683359 -230.390798)
			(xy 362.638076 -230.357899) (xy 362.598498 -230.318321) (xy 362.5656 -230.273038) (xy 362.540192 -230.223165)
			(xy 362.522899 -230.169932) (xy 362.514148 -230.114648) (xy 362.513626 -230.086662) (xy 362.514036 -230.062062)
			(xy 362.520799 -230.01333) (xy 362.534205 -229.965993) (xy 362.553999 -229.920951) (xy 362.579804 -229.879062)
			(xy 362.59516 -229.85984) (xy 362.595414 -229.859586) (xy 362.600748 -229.852982) (xy 362.610146 -229.827836)
			(xy 362.611225 -229.824373) (xy 362.612506 -229.817234) (xy 362.612686 -229.813612) (xy 362.6104 -229.747318)
			(xy 362.609258 -229.738786) (xy 362.601974 -229.723202) (xy 362.596176 -229.716838) (xy 362.49356 -229.614222)
			(xy 362.486312 -229.607666) (xy 362.46827 -229.600208) (xy 362.458508 -229.599744) (xy 362.450126 -229.599744)
			(xy 362.44657 -229.600252) (xy 362.435012 -229.601801) (xy 362.411749 -229.603453) (xy 362.400088 -229.603554)
			(xy 362.399834 -229.603554) (xy 362.374737 -229.603091) (xy 362.325118 -229.595509) (xy 362.277215 -229.580515)
			(xy 362.232129 -229.558453) (xy 362.190896 -229.52983) (xy 362.154462 -229.495303) (xy 362.123665 -229.455667)
			(xy 362.099213 -229.411831) (xy 362.081668 -229.364803) (xy 362.071432 -229.315663) (xy 362.069634 -229.290626)
			(xy 362.068618 -229.276148) (xy 362.019088 -229.227126) (xy 361.84078 -229.227126) (xy 361.79125 -229.276148)
			(xy 361.790234 -229.290626) (xy 361.78842 -229.315659) (xy 361.778178 -229.364793) (xy 361.76063 -229.411815)
			(xy 361.736177 -229.455645) (xy 361.705381 -229.495276) (xy 361.66895 -229.529798) (xy 361.62772 -229.558418)
			(xy 361.582639 -229.580479) (xy 361.534742 -229.595474) (xy 361.485129 -229.603059) (xy 361.434939 -229.603059)
			(xy 361.385326 -229.595474) (xy 361.337429 -229.580479) (xy 361.292348 -229.558418) (xy 361.251118 -229.529798)
			(xy 361.214687 -229.495276) (xy 361.183891 -229.455645) (xy 361.159438 -229.411815) (xy 361.14189 -229.364793)
			(xy 361.131648 -229.315659) (xy 361.129834 -229.290626) (xy 361.128818 -229.276148) (xy 361.079288 -229.227126)
			(xy 360.90098 -229.227126) (xy 360.85145 -229.276148) (xy 360.850434 -229.290626) (xy 360.84862 -229.315659)
			(xy 360.838378 -229.364793) (xy 360.82083 -229.411815) (xy 360.796377 -229.455645) (xy 360.765581 -229.495276)
			(xy 360.72915 -229.529798) (xy 360.68792 -229.558418) (xy 360.642839 -229.580479) (xy 360.594942 -229.595474)
			(xy 360.545329 -229.603059) (xy 360.495139 -229.603059) (xy 360.445526 -229.595474) (xy 360.397629 -229.580479)
			(xy 360.352548 -229.558418) (xy 360.311318 -229.529798) (xy 360.274887 -229.495276) (xy 360.244091 -229.455645)
			(xy 360.219638 -229.411815) (xy 360.20209 -229.364793) (xy 360.191848 -229.315659) (xy 360.190034 -229.290626)
			(xy 360.189018 -229.276148) (xy 360.139488 -229.227126) (xy 359.960926 -229.227126) (xy 359.911396 -229.276148)
			(xy 359.91038 -229.290626) (xy 359.908566 -229.315659) (xy 359.898324 -229.364793) (xy 359.880776 -229.411815)
			(xy 359.856323 -229.455645) (xy 359.825527 -229.495276) (xy 359.789096 -229.529798) (xy 359.747866 -229.558418)
			(xy 359.702785 -229.580479) (xy 359.654888 -229.595474) (xy 359.605275 -229.603059) (xy 359.555085 -229.603059)
			(xy 359.505472 -229.595474) (xy 359.457575 -229.580479) (xy 359.412494 -229.558418) (xy 359.371264 -229.529798)
			(xy 359.334833 -229.495276) (xy 359.304037 -229.455645) (xy 359.279584 -229.411815) (xy 359.262036 -229.364793)
			(xy 359.251794 -229.315659) (xy 359.24998 -229.290626) (xy 359.248964 -229.276148) (xy 359.199434 -229.227126)
			(xy 359.02138 -229.227126) (xy 358.97185 -229.276148) (xy 358.970834 -229.290626) (xy 358.96902 -229.315659)
			(xy 358.958778 -229.364793) (xy 358.94123 -229.411815) (xy 358.916777 -229.455645) (xy 358.885981 -229.495276)
			(xy 358.84955 -229.529798) (xy 358.80832 -229.558418) (xy 358.763239 -229.580479) (xy 358.715342 -229.595474)
			(xy 358.665729 -229.603059) (xy 358.615539 -229.603059) (xy 358.565926 -229.595474) (xy 358.518029 -229.580479)
			(xy 358.472948 -229.558418) (xy 358.431718 -229.529798) (xy 358.395287 -229.495276) (xy 358.364491 -229.455645)
			(xy 358.340038 -229.411815) (xy 358.32249 -229.364793) (xy 358.312248 -229.315659) (xy 358.310434 -229.290626)
			(xy 358.309418 -229.276148) (xy 358.259888 -229.227126) (xy 358.08158 -229.227126) (xy 358.03205 -229.276148)
			(xy 358.031034 -229.290626) (xy 358.02922 -229.315659) (xy 358.018978 -229.364793) (xy 358.00143 -229.411815)
			(xy 357.976977 -229.455645) (xy 357.946181 -229.495276) (xy 357.90975 -229.529798) (xy 357.86852 -229.558418)
			(xy 357.823439 -229.580479) (xy 357.775542 -229.595474) (xy 357.725929 -229.603059) (xy 357.675739 -229.603059)
			(xy 357.626126 -229.595474) (xy 357.578229 -229.580479) (xy 357.533148 -229.558418) (xy 357.491918 -229.529798)
			(xy 357.455487 -229.495276) (xy 357.424691 -229.455645) (xy 357.400238 -229.411815) (xy 357.38269 -229.364793)
			(xy 357.372448 -229.315659) (xy 357.370634 -229.290626) (xy 357.369618 -229.276148) (xy 357.320088 -229.227126)
			(xy 357.14178 -229.227126) (xy 357.09225 -229.276148) (xy 357.091234 -229.290626) (xy 357.08942 -229.315659)
			(xy 357.079178 -229.364793) (xy 357.06163 -229.411815) (xy 357.037177 -229.455645) (xy 357.006381 -229.495276)
			(xy 356.96995 -229.529798) (xy 356.92872 -229.558418) (xy 356.883639 -229.580479) (xy 356.835742 -229.595474)
			(xy 356.786129 -229.603059) (xy 356.735939 -229.603059) (xy 356.686326 -229.595474) (xy 356.638429 -229.580479)
			(xy 356.593348 -229.558418) (xy 356.552118 -229.529798) (xy 356.515687 -229.495276) (xy 356.484891 -229.455645)
			(xy 356.460438 -229.411815) (xy 356.44289 -229.364793) (xy 356.432648 -229.315659) (xy 356.430834 -229.290626)
			(xy 356.429818 -229.276148) (xy 356.380288 -229.227126) (xy 356.20198 -229.227126) (xy 356.15245 -229.276148)
			(xy 356.151434 -229.290372) (xy 356.149605 -229.315787) (xy 356.139117 -229.365648) (xy 356.12111 -229.413313)
			(xy 356.096009 -229.457653) (xy 356.064408 -229.497623) (xy 356.027054 -229.532275) (xy 355.98483 -229.560793)
			(xy 355.938733 -229.582501) (xy 355.889853 -229.596887) (xy 355.864668 -229.60076) (xy 355.858826 -229.601522)
			(xy 355.849459 -229.602498) (xy 355.830652 -229.603517) (xy 355.821234 -229.603554) (xy 355.795484 -229.603066)
			(xy 355.744607 -229.595092) (xy 355.695579 -229.579331) (xy 355.649585 -229.556163) (xy 355.607737 -229.526149)
			(xy 355.571044 -229.490013) (xy 355.540394 -229.448629) (xy 355.516526 -229.402994) (xy 355.507798 -229.378764)
			(xy 355.505258 -229.371144) (xy 355.491034 -229.35184) (xy 355.488578 -229.348663) (xy 355.482834 -229.343051)
			(xy 355.479604 -229.340664) (xy 355.475286 -229.337616) (xy 355.4603 -229.327202) (xy 355.454387 -229.323735)
			(xy 355.44124 -229.319879) (xy 355.434392 -229.319582) (xy 355.429312 -229.319836) (xy 355.408404 -229.321615)
			(xy 355.366476 -229.323394) (xy 355.345492 -229.323392) (xy 355.328199 -229.323234) (xy 355.293644 -229.321709)
			(xy 355.276404 -229.320344) (xy 355.274372 -229.32009) (xy 355.266498 -229.32009) (xy 355.259818 -229.32061)
			(xy 355.247076 -229.324735) (xy 355.241352 -229.328218) (xy 355.216714 -229.344982) (xy 355.19741 -229.371144)
			(xy 355.19487 -229.378764) (xy 355.186159 -229.403008) (xy 355.162304 -229.448663) (xy 355.13166 -229.49007)
			(xy 355.09497 -229.526228) (xy 355.053119 -229.556261) (xy 355.007118 -229.579446) (xy 354.95808 -229.59522)
			(xy 354.90719 -229.603204) (xy 354.855678 -229.603204) (xy 354.804788 -229.59522) (xy 354.75575 -229.579446)
			(xy 354.709749 -229.556261) (xy 354.667898 -229.526228) (xy 354.631208 -229.49007) (xy 354.600564 -229.448663)
			(xy 354.576709 -229.403008) (xy 354.567998 -229.378764) (xy 354.565458 -229.371144) (xy 354.546408 -229.345236)
			(xy 354.522532 -229.328472) (xy 354.516086 -229.324349) (xy 354.501478 -229.319823) (xy 354.49383 -229.319582)
			(xy 354.489258 -229.319836) (xy 354.468413 -229.32161) (xy 354.426612 -229.323386) (xy 354.405692 -229.323392)
			(xy 354.388399 -229.323234) (xy 354.353844 -229.321709) (xy 354.336604 -229.320344) (xy 354.334572 -229.32009)
			(xy 354.326698 -229.32009) (xy 354.320018 -229.32061) (xy 354.307276 -229.324735) (xy 354.301552 -229.328218)
			(xy 354.276914 -229.344982) (xy 354.25761 -229.371144) (xy 354.25507 -229.378764) (xy 354.246359 -229.403008)
			(xy 354.222504 -229.448663) (xy 354.19186 -229.49007) (xy 354.15517 -229.526228) (xy 354.113319 -229.556261)
			(xy 354.067318 -229.579446) (xy 354.01828 -229.59522) (xy 353.96739 -229.603204) (xy 353.915878 -229.603204)
			(xy 353.864988 -229.59522) (xy 353.81595 -229.579446) (xy 353.769949 -229.556261) (xy 353.728098 -229.526228)
			(xy 353.691408 -229.49007) (xy 353.660764 -229.448663) (xy 353.636909 -229.403008) (xy 353.628198 -229.378764)
			(xy 353.625658 -229.371144) (xy 353.606608 -229.345236) (xy 353.582732 -229.328472) (xy 353.576286 -229.324349)
			(xy 353.561678 -229.319823) (xy 353.55403 -229.319582) (xy 353.549458 -229.319836) (xy 353.528613 -229.32161)
			(xy 353.486812 -229.323386) (xy 353.465892 -229.323392) (xy 353.448599 -229.323234) (xy 353.414044 -229.321709)
			(xy 353.396804 -229.320344) (xy 353.394772 -229.32009) (xy 353.386898 -229.32009) (xy 353.380526 -229.320544)
			(xy 353.368314 -229.324283) (xy 353.362768 -229.327456) (xy 353.336352 -229.34549) (xy 353.332002 -229.349013)
			(xy 353.32483 -229.357605) (xy 353.322128 -229.362508) (xy 353.317556 -229.371398) (xy 353.316286 -229.375462)
			(xy 353.308253 -229.398637) (xy 353.286315 -229.442504) (xy 353.272598 -229.462838) (xy 353.26828 -229.468934)
			(xy 353.258628 -229.498144) (xy 353.259013 -229.507761) (xy 353.266057 -229.525655) (xy 353.272344 -229.532942)
			(xy 353.455986 -229.71633) (xy 353.488498 -229.731062) (xy 353.488752 -229.731062) (xy 353.496372 -229.73157)
			(xy 353.497388 -229.73157) (xy 353.523963 -229.733991) (xy 353.576007 -229.74578) (xy 353.625709 -229.765201)
			(xy 353.671959 -229.791819) (xy 353.713719 -229.825039) (xy 353.750057 -229.864117) (xy 353.780159 -229.908179)
			(xy 353.80335 -229.956238) (xy 353.819113 -230.007219) (xy 353.827094 -230.059981) (xy 353.827588 -230.086662)
			(xy 353.827001 -230.112629) (xy 354.081589 -230.112629) (xy 354.081589 -230.060695) (xy 354.089714 -230.0094)
			(xy 354.105762 -229.960007) (xy 354.12934 -229.913733) (xy 354.159866 -229.871717) (xy 354.196589 -229.834994)
			(xy 354.238605 -229.804468) (xy 354.284879 -229.78089) (xy 354.334272 -229.764842) (xy 354.385567 -229.756717)
			(xy 354.437501 -229.756717) (xy 354.488796 -229.764842) (xy 354.538189 -229.78089) (xy 354.584463 -229.804468)
			(xy 354.626479 -229.834994) (xy 354.663202 -229.871717) (xy 354.693728 -229.913733) (xy 354.717306 -229.960007)
			(xy 354.733354 -230.0094) (xy 354.741479 -230.060695) (xy 354.741988 -230.086662) (xy 354.741479 -230.112629)
			(xy 355.021135 -230.112629) (xy 355.021135 -230.060695) (xy 355.02926 -230.0094) (xy 355.045308 -229.960007)
			(xy 355.068886 -229.913733) (xy 355.099412 -229.871717) (xy 355.136135 -229.834994) (xy 355.178151 -229.804468)
			(xy 355.224425 -229.78089) (xy 355.273818 -229.764842) (xy 355.325113 -229.756717) (xy 355.377047 -229.756717)
			(xy 355.428342 -229.764842) (xy 355.477735 -229.78089) (xy 355.524009 -229.804468) (xy 355.566025 -229.834994)
			(xy 355.602748 -229.871717) (xy 355.633274 -229.913733) (xy 355.656852 -229.960007) (xy 355.6729 -230.0094)
			(xy 355.681025 -230.060695) (xy 355.681534 -230.086662) (xy 355.681025 -230.112629) (xy 355.960935 -230.112629)
			(xy 355.960935 -230.060695) (xy 355.96906 -230.0094) (xy 355.985108 -229.960007) (xy 356.008686 -229.913733)
			(xy 356.039212 -229.871717) (xy 356.075935 -229.834994) (xy 356.117951 -229.804468) (xy 356.164225 -229.78089)
			(xy 356.213618 -229.764842) (xy 356.264913 -229.756717) (xy 356.316847 -229.756717) (xy 356.368142 -229.764842)
			(xy 356.417535 -229.78089) (xy 356.463809 -229.804468) (xy 356.505825 -229.834994) (xy 356.542548 -229.871717)
			(xy 356.573074 -229.913733) (xy 356.596652 -229.960007) (xy 356.6127 -230.0094) (xy 356.620825 -230.060695)
			(xy 356.621334 -230.086662) (xy 356.620825 -230.112629) (xy 356.900735 -230.112629) (xy 356.900735 -230.060695)
			(xy 356.90886 -230.0094) (xy 356.924908 -229.960007) (xy 356.948486 -229.913733) (xy 356.979012 -229.871717)
			(xy 357.015735 -229.834994) (xy 357.057751 -229.804468) (xy 357.104025 -229.78089) (xy 357.153418 -229.764842)
			(xy 357.204713 -229.756717) (xy 357.256647 -229.756717) (xy 357.307942 -229.764842) (xy 357.357335 -229.78089)
			(xy 357.403609 -229.804468) (xy 357.445625 -229.834994) (xy 357.482348 -229.871717) (xy 357.512874 -229.913733)
			(xy 357.536452 -229.960007) (xy 357.5525 -230.0094) (xy 357.560625 -230.060695) (xy 357.561134 -230.086662)
			(xy 357.560625 -230.112629) (xy 357.840535 -230.112629) (xy 357.840535 -230.060695) (xy 357.84866 -230.0094)
			(xy 357.864708 -229.960007) (xy 357.888286 -229.913733) (xy 357.918812 -229.871717) (xy 357.955535 -229.834994)
			(xy 357.997551 -229.804468) (xy 358.043825 -229.78089) (xy 358.093218 -229.764842) (xy 358.144513 -229.756717)
			(xy 358.196447 -229.756717) (xy 358.247742 -229.764842) (xy 358.297135 -229.78089) (xy 358.343409 -229.804468)
			(xy 358.385425 -229.834994) (xy 358.422148 -229.871717) (xy 358.452674 -229.913733) (xy 358.476252 -229.960007)
			(xy 358.4923 -230.0094) (xy 358.500425 -230.060695) (xy 358.500934 -230.086662) (xy 358.500425 -230.112629)
			(xy 358.780589 -230.112629) (xy 358.780589 -230.060695) (xy 358.788714 -230.0094) (xy 358.804762 -229.960007)
			(xy 358.82834 -229.913733) (xy 358.858866 -229.871717) (xy 358.895589 -229.834994) (xy 358.937605 -229.804468)
			(xy 358.983879 -229.78089) (xy 359.033272 -229.764842) (xy 359.084567 -229.756717) (xy 359.136501 -229.756717)
			(xy 359.187796 -229.764842) (xy 359.237189 -229.78089) (xy 359.283463 -229.804468) (xy 359.325479 -229.834994)
			(xy 359.362202 -229.871717) (xy 359.392728 -229.913733) (xy 359.416306 -229.960007) (xy 359.432354 -230.0094)
			(xy 359.440479 -230.060695) (xy 359.440988 -230.086662) (xy 359.440479 -230.112629) (xy 359.720389 -230.112629)
			(xy 359.720389 -230.060695) (xy 359.728514 -230.0094) (xy 359.744562 -229.960007) (xy 359.76814 -229.913733)
			(xy 359.798666 -229.871717) (xy 359.835389 -229.834994) (xy 359.877405 -229.804468) (xy 359.923679 -229.78089)
			(xy 359.973072 -229.764842) (xy 360.024367 -229.756717) (xy 360.076301 -229.756717) (xy 360.127596 -229.764842)
			(xy 360.176989 -229.78089) (xy 360.223263 -229.804468) (xy 360.265279 -229.834994) (xy 360.302002 -229.871717)
			(xy 360.332528 -229.913733) (xy 360.356106 -229.960007) (xy 360.372154 -230.0094) (xy 360.380279 -230.060695)
			(xy 360.380788 -230.086662) (xy 360.380279 -230.112629) (xy 360.660189 -230.112629) (xy 360.660189 -230.060695)
			(xy 360.668314 -230.0094) (xy 360.684362 -229.960007) (xy 360.70794 -229.913733) (xy 360.738466 -229.871717)
			(xy 360.775189 -229.834994) (xy 360.817205 -229.804468) (xy 360.863479 -229.78089) (xy 360.912872 -229.764842)
			(xy 360.964167 -229.756717) (xy 361.016101 -229.756717) (xy 361.067396 -229.764842) (xy 361.116789 -229.78089)
			(xy 361.163063 -229.804468) (xy 361.205079 -229.834994) (xy 361.241802 -229.871717) (xy 361.272328 -229.913733)
			(xy 361.295906 -229.960007) (xy 361.311954 -230.0094) (xy 361.320079 -230.060695) (xy 361.320588 -230.086662)
			(xy 361.320079 -230.112629) (xy 361.599989 -230.112629) (xy 361.599989 -230.060695) (xy 361.608114 -230.0094)
			(xy 361.624162 -229.960007) (xy 361.64774 -229.913733) (xy 361.678266 -229.871717) (xy 361.714989 -229.834994)
			(xy 361.757005 -229.804468) (xy 361.803279 -229.78089) (xy 361.852672 -229.764842) (xy 361.903967 -229.756717)
			(xy 361.955901 -229.756717) (xy 362.007196 -229.764842) (xy 362.056589 -229.78089) (xy 362.102863 -229.804468)
			(xy 362.144879 -229.834994) (xy 362.181602 -229.871717) (xy 362.212128 -229.913733) (xy 362.235706 -229.960007)
			(xy 362.251754 -230.0094) (xy 362.259879 -230.060695) (xy 362.260388 -230.086662) (xy 362.259879 -230.112629)
			(xy 362.251754 -230.163924) (xy 362.235706 -230.213317) (xy 362.212128 -230.259591) (xy 362.181602 -230.301607)
			(xy 362.144879 -230.33833) (xy 362.102863 -230.368856) (xy 362.056589 -230.392434) (xy 362.007196 -230.408482)
			(xy 361.955901 -230.416607) (xy 361.903967 -230.416607) (xy 361.852672 -230.408482) (xy 361.803279 -230.392434)
			(xy 361.757005 -230.368856) (xy 361.714989 -230.33833) (xy 361.678266 -230.301607) (xy 361.64774 -230.259591)
			(xy 361.624162 -230.213317) (xy 361.608114 -230.163924) (xy 361.599989 -230.112629) (xy 361.320079 -230.112629)
			(xy 361.311954 -230.163924) (xy 361.295906 -230.213317) (xy 361.272328 -230.259591) (xy 361.241802 -230.301607)
			(xy 361.205079 -230.33833) (xy 361.163063 -230.368856) (xy 361.116789 -230.392434) (xy 361.067396 -230.408482)
			(xy 361.016101 -230.416607) (xy 360.964167 -230.416607) (xy 360.912872 -230.408482) (xy 360.863479 -230.392434)
			(xy 360.817205 -230.368856) (xy 360.775189 -230.33833) (xy 360.738466 -230.301607) (xy 360.70794 -230.259591)
			(xy 360.684362 -230.213317) (xy 360.668314 -230.163924) (xy 360.660189 -230.112629) (xy 360.380279 -230.112629)
			(xy 360.372154 -230.163924) (xy 360.356106 -230.213317) (xy 360.332528 -230.259591) (xy 360.302002 -230.301607)
			(xy 360.265279 -230.33833) (xy 360.223263 -230.368856) (xy 360.176989 -230.392434) (xy 360.127596 -230.408482)
			(xy 360.076301 -230.416607) (xy 360.024367 -230.416607) (xy 359.973072 -230.408482) (xy 359.923679 -230.392434)
			(xy 359.877405 -230.368856) (xy 359.835389 -230.33833) (xy 359.798666 -230.301607) (xy 359.76814 -230.259591)
			(xy 359.744562 -230.213317) (xy 359.728514 -230.163924) (xy 359.720389 -230.112629) (xy 359.440479 -230.112629)
			(xy 359.432354 -230.163924) (xy 359.416306 -230.213317) (xy 359.392728 -230.259591) (xy 359.362202 -230.301607)
			(xy 359.325479 -230.33833) (xy 359.283463 -230.368856) (xy 359.237189 -230.392434) (xy 359.187796 -230.408482)
			(xy 359.136501 -230.416607) (xy 359.084567 -230.416607) (xy 359.033272 -230.408482) (xy 358.983879 -230.392434)
			(xy 358.937605 -230.368856) (xy 358.895589 -230.33833) (xy 358.858866 -230.301607) (xy 358.82834 -230.259591)
			(xy 358.804762 -230.213317) (xy 358.788714 -230.163924) (xy 358.780589 -230.112629) (xy 358.500425 -230.112629)
			(xy 358.4923 -230.163924) (xy 358.476252 -230.213317) (xy 358.452674 -230.259591) (xy 358.422148 -230.301607)
			(xy 358.385425 -230.33833) (xy 358.343409 -230.368856) (xy 358.297135 -230.392434) (xy 358.247742 -230.408482)
			(xy 358.196447 -230.416607) (xy 358.144513 -230.416607) (xy 358.093218 -230.408482) (xy 358.043825 -230.392434)
			(xy 357.997551 -230.368856) (xy 357.955535 -230.33833) (xy 357.918812 -230.301607) (xy 357.888286 -230.259591)
			(xy 357.864708 -230.213317) (xy 357.84866 -230.163924) (xy 357.840535 -230.112629) (xy 357.560625 -230.112629)
			(xy 357.5525 -230.163924) (xy 357.536452 -230.213317) (xy 357.512874 -230.259591) (xy 357.482348 -230.301607)
			(xy 357.445625 -230.33833) (xy 357.403609 -230.368856) (xy 357.357335 -230.392434) (xy 357.307942 -230.408482)
			(xy 357.256647 -230.416607) (xy 357.204713 -230.416607) (xy 357.153418 -230.408482) (xy 357.104025 -230.392434)
			(xy 357.057751 -230.368856) (xy 357.015735 -230.33833) (xy 356.979012 -230.301607) (xy 356.948486 -230.259591)
			(xy 356.924908 -230.213317) (xy 356.90886 -230.163924) (xy 356.900735 -230.112629) (xy 356.620825 -230.112629)
			(xy 356.6127 -230.163924) (xy 356.596652 -230.213317) (xy 356.573074 -230.259591) (xy 356.542548 -230.301607)
			(xy 356.505825 -230.33833) (xy 356.463809 -230.368856) (xy 356.417535 -230.392434) (xy 356.368142 -230.408482)
			(xy 356.316847 -230.416607) (xy 356.264913 -230.416607) (xy 356.213618 -230.408482) (xy 356.164225 -230.392434)
			(xy 356.117951 -230.368856) (xy 356.075935 -230.33833) (xy 356.039212 -230.301607) (xy 356.008686 -230.259591)
			(xy 355.985108 -230.213317) (xy 355.96906 -230.163924) (xy 355.960935 -230.112629) (xy 355.681025 -230.112629)
			(xy 355.6729 -230.163924) (xy 355.656852 -230.213317) (xy 355.633274 -230.259591) (xy 355.602748 -230.301607)
			(xy 355.566025 -230.33833) (xy 355.524009 -230.368856) (xy 355.477735 -230.392434) (xy 355.428342 -230.408482)
			(xy 355.377047 -230.416607) (xy 355.325113 -230.416607) (xy 355.273818 -230.408482) (xy 355.224425 -230.392434)
			(xy 355.178151 -230.368856) (xy 355.136135 -230.33833) (xy 355.099412 -230.301607) (xy 355.068886 -230.259591)
			(xy 355.045308 -230.213317) (xy 355.02926 -230.163924) (xy 355.021135 -230.112629) (xy 354.741479 -230.112629)
			(xy 354.733354 -230.163924) (xy 354.717306 -230.213317) (xy 354.693728 -230.259591) (xy 354.663202 -230.301607)
			(xy 354.626479 -230.33833) (xy 354.584463 -230.368856) (xy 354.538189 -230.392434) (xy 354.488796 -230.408482)
			(xy 354.437501 -230.416607) (xy 354.385567 -230.416607) (xy 354.334272 -230.408482) (xy 354.284879 -230.392434)
			(xy 354.238605 -230.368856) (xy 354.196589 -230.33833) (xy 354.159866 -230.301607) (xy 354.12934 -230.259591)
			(xy 354.105762 -230.213317) (xy 354.089714 -230.163924) (xy 354.081589 -230.112629) (xy 353.827001 -230.112629)
			(xy 353.826857 -230.119022) (xy 353.815092 -230.182666) (xy 353.80422 -230.213154) (xy 353.800918 -230.22179)
			(xy 353.800918 -230.446072) (xy 353.801379 -230.45658) (xy 353.809935 -230.475774) (xy 353.817428 -230.483156)
			(xy 353.872038 -230.532686) (xy 353.87921 -230.538744) (xy 353.896694 -230.545546) (xy 353.906074 -230.545894)
			(xy 353.909884 -230.54564) (xy 353.941634 -230.54437) (xy 353.968283 -230.54487) (xy 354.020986 -230.552818)
			(xy 354.071916 -230.568532) (xy 354.119934 -230.591661) (xy 354.16397 -230.621688) (xy 354.203039 -230.657942)
			(xy 354.236268 -230.699614) (xy 354.262916 -230.745773) (xy 354.282387 -230.795388) (xy 354.294247 -230.84735)
			(xy 354.29823 -230.9005) (xy 354.296286 -230.926445) (xy 354.551489 -230.926445) (xy 354.551489 -230.874511)
			(xy 354.559614 -230.823216) (xy 354.575662 -230.773823) (xy 354.59924 -230.727549) (xy 354.629766 -230.685533)
			(xy 354.666489 -230.64881) (xy 354.708505 -230.618284) (xy 354.754779 -230.594706) (xy 354.804172 -230.578658)
			(xy 354.855467 -230.570533) (xy 354.907401 -230.570533) (xy 354.958696 -230.578658) (xy 355.008089 -230.594706)
			(xy 355.054363 -230.618284) (xy 355.096379 -230.64881) (xy 355.133102 -230.685533) (xy 355.163628 -230.727549)
			(xy 355.187206 -230.773823) (xy 355.203254 -230.823216) (xy 355.211379 -230.874511) (xy 355.211888 -230.900478)
			(xy 355.211379 -230.926445) (xy 355.491035 -230.926445) (xy 355.491035 -230.874511) (xy 355.49916 -230.823216)
			(xy 355.515208 -230.773823) (xy 355.538786 -230.727549) (xy 355.569312 -230.685533) (xy 355.606035 -230.64881)
			(xy 355.648051 -230.618284) (xy 355.694325 -230.594706) (xy 355.743718 -230.578658) (xy 355.795013 -230.570533)
			(xy 355.846947 -230.570533) (xy 355.898242 -230.578658) (xy 355.947635 -230.594706) (xy 355.993909 -230.618284)
			(xy 356.035925 -230.64881) (xy 356.072648 -230.685533) (xy 356.103174 -230.727549) (xy 356.126752 -230.773823)
			(xy 356.1428 -230.823216) (xy 356.150925 -230.874511) (xy 356.151434 -230.900478) (xy 356.150925 -230.926445)
			(xy 356.431089 -230.926445) (xy 356.431089 -230.874511) (xy 356.439214 -230.823216) (xy 356.455262 -230.773823)
			(xy 356.47884 -230.727549) (xy 356.509366 -230.685533) (xy 356.546089 -230.64881) (xy 356.588105 -230.618284)
			(xy 356.634379 -230.594706) (xy 356.683772 -230.578658) (xy 356.735067 -230.570533) (xy 356.787001 -230.570533)
			(xy 356.838296 -230.578658) (xy 356.887689 -230.594706) (xy 356.933963 -230.618284) (xy 356.975979 -230.64881)
			(xy 357.012702 -230.685533) (xy 357.043228 -230.727549) (xy 357.066806 -230.773823) (xy 357.082854 -230.823216)
			(xy 357.090979 -230.874511) (xy 357.091488 -230.900478) (xy 357.090979 -230.926445) (xy 357.370635 -230.926445)
			(xy 357.370635 -230.874511) (xy 357.37876 -230.823216) (xy 357.394808 -230.773823) (xy 357.418386 -230.727549)
			(xy 357.448912 -230.685533) (xy 357.485635 -230.64881) (xy 357.527651 -230.618284) (xy 357.573925 -230.594706)
			(xy 357.623318 -230.578658) (xy 357.674613 -230.570533) (xy 357.726547 -230.570533) (xy 357.777842 -230.578658)
			(xy 357.827235 -230.594706) (xy 357.873509 -230.618284) (xy 357.915525 -230.64881) (xy 357.952248 -230.685533)
			(xy 357.982774 -230.727549) (xy 358.006352 -230.773823) (xy 358.0224 -230.823216) (xy 358.030525 -230.874511)
			(xy 358.031034 -230.900478) (xy 358.030525 -230.926445) (xy 358.310689 -230.926445) (xy 358.310689 -230.874511)
			(xy 358.318814 -230.823216) (xy 358.334862 -230.773823) (xy 358.35844 -230.727549) (xy 358.388966 -230.685533)
			(xy 358.425689 -230.64881) (xy 358.467705 -230.618284) (xy 358.513979 -230.594706) (xy 358.563372 -230.578658)
			(xy 358.614667 -230.570533) (xy 358.666601 -230.570533) (xy 358.717896 -230.578658) (xy 358.767289 -230.594706)
			(xy 358.813563 -230.618284) (xy 358.855579 -230.64881) (xy 358.892302 -230.685533) (xy 358.922828 -230.727549)
			(xy 358.946406 -230.773823) (xy 358.962454 -230.823216) (xy 358.970579 -230.874511) (xy 358.971088 -230.900478)
			(xy 358.970579 -230.926445) (xy 359.250489 -230.926445) (xy 359.250489 -230.874511) (xy 359.258614 -230.823216)
			(xy 359.274662 -230.773823) (xy 359.29824 -230.727549) (xy 359.328766 -230.685533) (xy 359.365489 -230.64881)
			(xy 359.407505 -230.618284) (xy 359.453779 -230.594706) (xy 359.503172 -230.578658) (xy 359.554467 -230.570533)
			(xy 359.606401 -230.570533) (xy 359.657696 -230.578658) (xy 359.707089 -230.594706) (xy 359.753363 -230.618284)
			(xy 359.795379 -230.64881) (xy 359.832102 -230.685533) (xy 359.862628 -230.727549) (xy 359.886206 -230.773823)
			(xy 359.902254 -230.823216) (xy 359.910379 -230.874511) (xy 359.910888 -230.900478) (xy 359.910379 -230.926445)
			(xy 360.190289 -230.926445) (xy 360.190289 -230.874511) (xy 360.198414 -230.823216) (xy 360.214462 -230.773823)
			(xy 360.23804 -230.727549) (xy 360.268566 -230.685533) (xy 360.305289 -230.64881) (xy 360.347305 -230.618284)
			(xy 360.393579 -230.594706) (xy 360.442972 -230.578658) (xy 360.494267 -230.570533) (xy 360.546201 -230.570533)
			(xy 360.597496 -230.578658) (xy 360.646889 -230.594706) (xy 360.693163 -230.618284) (xy 360.735179 -230.64881)
			(xy 360.771902 -230.685533) (xy 360.802428 -230.727549) (xy 360.826006 -230.773823) (xy 360.842054 -230.823216)
			(xy 360.850179 -230.874511) (xy 360.850688 -230.900478) (xy 360.850179 -230.926445) (xy 361.130089 -230.926445)
			(xy 361.130089 -230.874511) (xy 361.138214 -230.823216) (xy 361.154262 -230.773823) (xy 361.17784 -230.727549)
			(xy 361.208366 -230.685533) (xy 361.245089 -230.64881) (xy 361.287105 -230.618284) (xy 361.333379 -230.594706)
			(xy 361.382772 -230.578658) (xy 361.434067 -230.570533) (xy 361.486001 -230.570533) (xy 361.537296 -230.578658)
			(xy 361.586689 -230.594706) (xy 361.632963 -230.618284) (xy 361.674979 -230.64881) (xy 361.711702 -230.685533)
			(xy 361.742228 -230.727549) (xy 361.765806 -230.773823) (xy 361.781854 -230.823216) (xy 361.789979 -230.874511)
			(xy 361.790488 -230.900478) (xy 361.789979 -230.926445) (xy 362.070143 -230.926445) (xy 362.070143 -230.874511)
			(xy 362.078268 -230.823216) (xy 362.094316 -230.773823) (xy 362.117894 -230.727549) (xy 362.14842 -230.685533)
			(xy 362.185143 -230.64881) (xy 362.227159 -230.618284) (xy 362.273433 -230.594706) (xy 362.322826 -230.578658)
			(xy 362.374121 -230.570533) (xy 362.426055 -230.570533) (xy 362.47735 -230.578658) (xy 362.526743 -230.594706)
			(xy 362.573017 -230.618284) (xy 362.615033 -230.64881) (xy 362.651756 -230.685533) (xy 362.682282 -230.727549)
			(xy 362.70586 -230.773823) (xy 362.721908 -230.823216) (xy 362.730033 -230.874511) (xy 362.730542 -230.900478)
			(xy 362.730033 -230.926445) (xy 362.721908 -230.97774) (xy 362.70586 -231.027133) (xy 362.682282 -231.073407)
			(xy 362.651756 -231.115423) (xy 362.615033 -231.152146) (xy 362.573017 -231.182672) (xy 362.526743 -231.20625)
			(xy 362.47735 -231.222298) (xy 362.426055 -231.230423) (xy 362.374121 -231.230423) (xy 362.322826 -231.222298)
			(xy 362.273433 -231.20625) (xy 362.227159 -231.182672) (xy 362.185143 -231.152146) (xy 362.14842 -231.115423)
			(xy 362.117894 -231.073407) (xy 362.094316 -231.027133) (xy 362.078268 -230.97774) (xy 362.070143 -230.926445)
			(xy 361.789979 -230.926445) (xy 361.781854 -230.97774) (xy 361.765806 -231.027133) (xy 361.742228 -231.073407)
			(xy 361.711702 -231.115423) (xy 361.674979 -231.152146) (xy 361.632963 -231.182672) (xy 361.586689 -231.20625)
			(xy 361.537296 -231.222298) (xy 361.486001 -231.230423) (xy 361.434067 -231.230423) (xy 361.382772 -231.222298)
			(xy 361.333379 -231.20625) (xy 361.287105 -231.182672) (xy 361.245089 -231.152146) (xy 361.208366 -231.115423)
			(xy 361.17784 -231.073407) (xy 361.154262 -231.027133) (xy 361.138214 -230.97774) (xy 361.130089 -230.926445)
			(xy 360.850179 -230.926445) (xy 360.842054 -230.97774) (xy 360.826006 -231.027133) (xy 360.802428 -231.073407)
			(xy 360.771902 -231.115423) (xy 360.735179 -231.152146) (xy 360.693163 -231.182672) (xy 360.646889 -231.20625)
			(xy 360.597496 -231.222298) (xy 360.546201 -231.230423) (xy 360.494267 -231.230423) (xy 360.442972 -231.222298)
			(xy 360.393579 -231.20625) (xy 360.347305 -231.182672) (xy 360.305289 -231.152146) (xy 360.268566 -231.115423)
			(xy 360.23804 -231.073407) (xy 360.214462 -231.027133) (xy 360.198414 -230.97774) (xy 360.190289 -230.926445)
			(xy 359.910379 -230.926445) (xy 359.902254 -230.97774) (xy 359.886206 -231.027133) (xy 359.862628 -231.073407)
			(xy 359.832102 -231.115423) (xy 359.795379 -231.152146) (xy 359.753363 -231.182672) (xy 359.707089 -231.20625)
			(xy 359.657696 -231.222298) (xy 359.606401 -231.230423) (xy 359.554467 -231.230423) (xy 359.503172 -231.222298)
			(xy 359.453779 -231.20625) (xy 359.407505 -231.182672) (xy 359.365489 -231.152146) (xy 359.328766 -231.115423)
			(xy 359.29824 -231.073407) (xy 359.274662 -231.027133) (xy 359.258614 -230.97774) (xy 359.250489 -230.926445)
			(xy 358.970579 -230.926445) (xy 358.962454 -230.97774) (xy 358.946406 -231.027133) (xy 358.922828 -231.073407)
			(xy 358.892302 -231.115423) (xy 358.855579 -231.152146) (xy 358.813563 -231.182672) (xy 358.767289 -231.20625)
			(xy 358.717896 -231.222298) (xy 358.666601 -231.230423) (xy 358.614667 -231.230423) (xy 358.563372 -231.222298)
			(xy 358.513979 -231.20625) (xy 358.467705 -231.182672) (xy 358.425689 -231.152146) (xy 358.388966 -231.115423)
			(xy 358.35844 -231.073407) (xy 358.334862 -231.027133) (xy 358.318814 -230.97774) (xy 358.310689 -230.926445)
			(xy 358.030525 -230.926445) (xy 358.0224 -230.97774) (xy 358.006352 -231.027133) (xy 357.982774 -231.073407)
			(xy 357.952248 -231.115423) (xy 357.915525 -231.152146) (xy 357.873509 -231.182672) (xy 357.827235 -231.20625)
			(xy 357.777842 -231.222298) (xy 357.726547 -231.230423) (xy 357.674613 -231.230423) (xy 357.623318 -231.222298)
			(xy 357.573925 -231.20625) (xy 357.527651 -231.182672) (xy 357.485635 -231.152146) (xy 357.448912 -231.115423)
			(xy 357.418386 -231.073407) (xy 357.394808 -231.027133) (xy 357.37876 -230.97774) (xy 357.370635 -230.926445)
			(xy 357.090979 -230.926445) (xy 357.082854 -230.97774) (xy 357.066806 -231.027133) (xy 357.043228 -231.073407)
			(xy 357.012702 -231.115423) (xy 356.975979 -231.152146) (xy 356.933963 -231.182672) (xy 356.887689 -231.20625)
			(xy 356.838296 -231.222298) (xy 356.787001 -231.230423) (xy 356.735067 -231.230423) (xy 356.683772 -231.222298)
			(xy 356.634379 -231.20625) (xy 356.588105 -231.182672) (xy 356.546089 -231.152146) (xy 356.509366 -231.115423)
			(xy 356.47884 -231.073407) (xy 356.455262 -231.027133) (xy 356.439214 -230.97774) (xy 356.431089 -230.926445)
			(xy 356.150925 -230.926445) (xy 356.1428 -230.97774) (xy 356.126752 -231.027133) (xy 356.103174 -231.073407)
			(xy 356.072648 -231.115423) (xy 356.035925 -231.152146) (xy 355.993909 -231.182672) (xy 355.947635 -231.20625)
			(xy 355.898242 -231.222298) (xy 355.846947 -231.230423) (xy 355.795013 -231.230423) (xy 355.743718 -231.222298)
			(xy 355.694325 -231.20625) (xy 355.648051 -231.182672) (xy 355.606035 -231.152146) (xy 355.569312 -231.115423)
			(xy 355.538786 -231.073407) (xy 355.515208 -231.027133) (xy 355.49916 -230.97774) (xy 355.491035 -230.926445)
			(xy 355.211379 -230.926445) (xy 355.203254 -230.97774) (xy 355.187206 -231.027133) (xy 355.163628 -231.073407)
			(xy 355.133102 -231.115423) (xy 355.096379 -231.152146) (xy 355.054363 -231.182672) (xy 355.008089 -231.20625)
			(xy 354.958696 -231.222298) (xy 354.907401 -231.230423) (xy 354.855467 -231.230423) (xy 354.804172 -231.222298)
			(xy 354.754779 -231.20625) (xy 354.708505 -231.182672) (xy 354.666489 -231.152146) (xy 354.629766 -231.115423)
			(xy 354.59924 -231.073407) (xy 354.575662 -231.027133) (xy 354.559614 -230.97774) (xy 354.551489 -230.926445)
			(xy 354.296286 -230.926445) (xy 354.294247 -230.95365) (xy 354.282387 -231.005612) (xy 354.262916 -231.055227)
			(xy 354.236268 -231.101386) (xy 354.203039 -231.143058) (xy 354.16397 -231.179312) (xy 354.119934 -231.209339)
			(xy 354.071916 -231.232468) (xy 354.020986 -231.248182) (xy 353.968283 -231.25613) (xy 353.941634 -231.256586)
			(xy 353.909884 -231.255316) (xy 353.906074 -231.255062) (xy 353.896685 -231.255392) (xy 353.879178 -231.262166)
			(xy 353.872038 -231.26827) (xy 353.817174 -231.318054) (xy 353.813872 -231.321356) (xy 353.808521 -231.32775)
			(xy 353.801918 -231.343049) (xy 353.800918 -231.351328) (xy 353.800918 -231.57942) (xy 353.80422 -231.588056)
			(xy 353.815076 -231.618548) (xy 353.826836 -231.68219) (xy 353.827588 -231.714548) (xy 353.827002 -231.740515)
			(xy 354.081335 -231.740515) (xy 354.081335 -231.688581) (xy 354.08946 -231.637286) (xy 354.105508 -231.587893)
			(xy 354.129086 -231.541619) (xy 354.159612 -231.499603) (xy 354.196335 -231.46288) (xy 354.238351 -231.432354)
			(xy 354.284625 -231.408776) (xy 354.334018 -231.392728) (xy 354.385313 -231.384603) (xy 354.437247 -231.384603)
			(xy 354.488542 -231.392728) (xy 354.537935 -231.408776) (xy 354.584209 -231.432354) (xy 354.626225 -231.46288)
			(xy 354.662948 -231.499603) (xy 354.693474 -231.541619) (xy 354.717052 -231.587893) (xy 354.7331 -231.637286)
			(xy 354.741225 -231.688581) (xy 354.741734 -231.714548) (xy 354.741225 -231.740515) (xy 355.021135 -231.740515)
			(xy 355.021135 -231.688581) (xy 355.02926 -231.637286) (xy 355.045308 -231.587893) (xy 355.068886 -231.541619)
			(xy 355.099412 -231.499603) (xy 355.136135 -231.46288) (xy 355.178151 -231.432354) (xy 355.224425 -231.408776)
			(xy 355.273818 -231.392728) (xy 355.325113 -231.384603) (xy 355.377047 -231.384603) (xy 355.428342 -231.392728)
			(xy 355.477735 -231.408776) (xy 355.524009 -231.432354) (xy 355.566025 -231.46288) (xy 355.602748 -231.499603)
			(xy 355.633274 -231.541619) (xy 355.656852 -231.587893) (xy 355.6729 -231.637286) (xy 355.681025 -231.688581)
			(xy 355.681534 -231.714548) (xy 355.681025 -231.740515) (xy 355.960935 -231.740515) (xy 355.960935 -231.688581)
			(xy 355.96906 -231.637286) (xy 355.985108 -231.587893) (xy 356.008686 -231.541619) (xy 356.039212 -231.499603)
			(xy 356.075935 -231.46288) (xy 356.117951 -231.432354) (xy 356.164225 -231.408776) (xy 356.213618 -231.392728)
			(xy 356.264913 -231.384603) (xy 356.316847 -231.384603) (xy 356.368142 -231.392728) (xy 356.417535 -231.408776)
			(xy 356.463809 -231.432354) (xy 356.505825 -231.46288) (xy 356.542548 -231.499603) (xy 356.573074 -231.541619)
			(xy 356.596652 -231.587893) (xy 356.6127 -231.637286) (xy 356.620825 -231.688581) (xy 356.621334 -231.714548)
			(xy 356.620825 -231.740515) (xy 356.900735 -231.740515) (xy 356.900735 -231.688581) (xy 356.90886 -231.637286)
			(xy 356.924908 -231.587893) (xy 356.948486 -231.541619) (xy 356.979012 -231.499603) (xy 357.015735 -231.46288)
			(xy 357.057751 -231.432354) (xy 357.104025 -231.408776) (xy 357.153418 -231.392728) (xy 357.204713 -231.384603)
			(xy 357.256647 -231.384603) (xy 357.307942 -231.392728) (xy 357.357335 -231.408776) (xy 357.403609 -231.432354)
			(xy 357.445625 -231.46288) (xy 357.482348 -231.499603) (xy 357.512874 -231.541619) (xy 357.536452 -231.587893)
			(xy 357.5525 -231.637286) (xy 357.560625 -231.688581) (xy 357.561134 -231.714548) (xy 357.560625 -231.740515)
			(xy 357.840789 -231.740515) (xy 357.840789 -231.688581) (xy 357.848914 -231.637286) (xy 357.864962 -231.587893)
			(xy 357.88854 -231.541619) (xy 357.919066 -231.499603) (xy 357.955789 -231.46288) (xy 357.997805 -231.432354)
			(xy 358.044079 -231.408776) (xy 358.093472 -231.392728) (xy 358.144767 -231.384603) (xy 358.196701 -231.384603)
			(xy 358.247996 -231.392728) (xy 358.297389 -231.408776) (xy 358.343663 -231.432354) (xy 358.385679 -231.46288)
			(xy 358.422402 -231.499603) (xy 358.452928 -231.541619) (xy 358.476506 -231.587893) (xy 358.492554 -231.637286)
			(xy 358.500679 -231.688581) (xy 358.501188 -231.714548) (xy 358.500679 -231.740515) (xy 358.780335 -231.740515)
			(xy 358.780335 -231.688581) (xy 358.78846 -231.637286) (xy 358.804508 -231.587893) (xy 358.828086 -231.541619)
			(xy 358.858612 -231.499603) (xy 358.895335 -231.46288) (xy 358.937351 -231.432354) (xy 358.983625 -231.408776)
			(xy 359.033018 -231.392728) (xy 359.084313 -231.384603) (xy 359.136247 -231.384603) (xy 359.187542 -231.392728)
			(xy 359.236935 -231.408776) (xy 359.283209 -231.432354) (xy 359.325225 -231.46288) (xy 359.361948 -231.499603)
			(xy 359.392474 -231.541619) (xy 359.416052 -231.587893) (xy 359.4321 -231.637286) (xy 359.440225 -231.688581)
			(xy 359.440734 -231.714548) (xy 359.440225 -231.740515) (xy 359.720643 -231.740515) (xy 359.720643 -231.688581)
			(xy 359.728768 -231.637286) (xy 359.744816 -231.587893) (xy 359.768394 -231.541619) (xy 359.79892 -231.499603)
			(xy 359.835643 -231.46288) (xy 359.877659 -231.432354) (xy 359.923933 -231.408776) (xy 359.973326 -231.392728)
			(xy 360.024621 -231.384603) (xy 360.076555 -231.384603) (xy 360.12785 -231.392728) (xy 360.177243 -231.408776)
			(xy 360.223517 -231.432354) (xy 360.265533 -231.46288) (xy 360.302256 -231.499603) (xy 360.332782 -231.541619)
			(xy 360.35636 -231.587893) (xy 360.372408 -231.637286) (xy 360.380533 -231.688581) (xy 360.381042 -231.714548)
			(xy 360.380533 -231.740515) (xy 360.660443 -231.740515) (xy 360.660443 -231.688581) (xy 360.668568 -231.637286)
			(xy 360.684616 -231.587893) (xy 360.708194 -231.541619) (xy 360.73872 -231.499603) (xy 360.775443 -231.46288)
			(xy 360.817459 -231.432354) (xy 360.863733 -231.408776) (xy 360.913126 -231.392728) (xy 360.964421 -231.384603)
			(xy 361.016355 -231.384603) (xy 361.06765 -231.392728) (xy 361.117043 -231.408776) (xy 361.163317 -231.432354)
			(xy 361.205333 -231.46288) (xy 361.242056 -231.499603) (xy 361.272582 -231.541619) (xy 361.29616 -231.587893)
			(xy 361.312208 -231.637286) (xy 361.320333 -231.688581) (xy 361.320842 -231.714548) (xy 361.320333 -231.740515)
			(xy 361.600243 -231.740515) (xy 361.600243 -231.688581) (xy 361.608368 -231.637286) (xy 361.624416 -231.587893)
			(xy 361.647994 -231.541619) (xy 361.67852 -231.499603) (xy 361.715243 -231.46288) (xy 361.757259 -231.432354)
			(xy 361.803533 -231.408776) (xy 361.852926 -231.392728) (xy 361.904221 -231.384603) (xy 361.956155 -231.384603)
			(xy 362.00745 -231.392728) (xy 362.056843 -231.408776) (xy 362.103117 -231.432354) (xy 362.145133 -231.46288)
			(xy 362.181856 -231.499603) (xy 362.212382 -231.541619) (xy 362.23596 -231.587893) (xy 362.252008 -231.637286)
			(xy 362.260133 -231.688581) (xy 362.260642 -231.714548) (xy 362.260133 -231.740515) (xy 362.539535 -231.740515)
			(xy 362.539535 -231.688581) (xy 362.54766 -231.637286) (xy 362.563708 -231.587893) (xy 362.587286 -231.541619)
			(xy 362.617812 -231.499603) (xy 362.654535 -231.46288) (xy 362.696551 -231.432354) (xy 362.742825 -231.408776)
			(xy 362.792218 -231.392728) (xy 362.843513 -231.384603) (xy 362.895447 -231.384603) (xy 362.946742 -231.392728)
			(xy 362.996135 -231.408776) (xy 363.042409 -231.432354) (xy 363.084425 -231.46288) (xy 363.121148 -231.499603)
			(xy 363.151674 -231.541619) (xy 363.175252 -231.587893) (xy 363.1913 -231.637286) (xy 363.199425 -231.688581)
			(xy 363.199934 -231.714548) (xy 363.199425 -231.740515) (xy 363.1913 -231.79181) (xy 363.175252 -231.841203)
			(xy 363.151674 -231.887477) (xy 363.121148 -231.929493) (xy 363.084425 -231.966216) (xy 363.042409 -231.996742)
			(xy 362.996135 -232.02032) (xy 362.946742 -232.036368) (xy 362.895447 -232.044493) (xy 362.843513 -232.044493)
			(xy 362.792218 -232.036368) (xy 362.742825 -232.02032) (xy 362.696551 -231.996742) (xy 362.654535 -231.966216)
			(xy 362.617812 -231.929493) (xy 362.587286 -231.887477) (xy 362.563708 -231.841203) (xy 362.54766 -231.79181)
			(xy 362.539535 -231.740515) (xy 362.260133 -231.740515) (xy 362.252008 -231.79181) (xy 362.23596 -231.841203)
			(xy 362.212382 -231.887477) (xy 362.181856 -231.929493) (xy 362.145133 -231.966216) (xy 362.103117 -231.996742)
			(xy 362.056843 -232.02032) (xy 362.00745 -232.036368) (xy 361.956155 -232.044493) (xy 361.904221 -232.044493)
			(xy 361.852926 -232.036368) (xy 361.803533 -232.02032) (xy 361.757259 -231.996742) (xy 361.715243 -231.966216)
			(xy 361.67852 -231.929493) (xy 361.647994 -231.887477) (xy 361.624416 -231.841203) (xy 361.608368 -231.79181)
			(xy 361.600243 -231.740515) (xy 361.320333 -231.740515) (xy 361.312208 -231.79181) (xy 361.29616 -231.841203)
			(xy 361.272582 -231.887477) (xy 361.242056 -231.929493) (xy 361.205333 -231.966216) (xy 361.163317 -231.996742)
			(xy 361.117043 -232.02032) (xy 361.06765 -232.036368) (xy 361.016355 -232.044493) (xy 360.964421 -232.044493)
			(xy 360.913126 -232.036368) (xy 360.863733 -232.02032) (xy 360.817459 -231.996742) (xy 360.775443 -231.966216)
			(xy 360.73872 -231.929493) (xy 360.708194 -231.887477) (xy 360.684616 -231.841203) (xy 360.668568 -231.79181)
			(xy 360.660443 -231.740515) (xy 360.380533 -231.740515) (xy 360.372408 -231.79181) (xy 360.35636 -231.841203)
			(xy 360.332782 -231.887477) (xy 360.302256 -231.929493) (xy 360.265533 -231.966216) (xy 360.223517 -231.996742)
			(xy 360.177243 -232.02032) (xy 360.12785 -232.036368) (xy 360.076555 -232.044493) (xy 360.024621 -232.044493)
			(xy 359.973326 -232.036368) (xy 359.923933 -232.02032) (xy 359.877659 -231.996742) (xy 359.835643 -231.966216)
			(xy 359.79892 -231.929493) (xy 359.768394 -231.887477) (xy 359.744816 -231.841203) (xy 359.728768 -231.79181)
			(xy 359.720643 -231.740515) (xy 359.440225 -231.740515) (xy 359.4321 -231.79181) (xy 359.416052 -231.841203)
			(xy 359.392474 -231.887477) (xy 359.361948 -231.929493) (xy 359.325225 -231.966216) (xy 359.283209 -231.996742)
			(xy 359.236935 -232.02032) (xy 359.187542 -232.036368) (xy 359.136247 -232.044493) (xy 359.084313 -232.044493)
			(xy 359.033018 -232.036368) (xy 358.983625 -232.02032) (xy 358.937351 -231.996742) (xy 358.895335 -231.966216)
			(xy 358.858612 -231.929493) (xy 358.828086 -231.887477) (xy 358.804508 -231.841203) (xy 358.78846 -231.79181)
			(xy 358.780335 -231.740515) (xy 358.500679 -231.740515) (xy 358.492554 -231.79181) (xy 358.476506 -231.841203)
			(xy 358.452928 -231.887477) (xy 358.422402 -231.929493) (xy 358.385679 -231.966216) (xy 358.343663 -231.996742)
			(xy 358.297389 -232.02032) (xy 358.247996 -232.036368) (xy 358.196701 -232.044493) (xy 358.144767 -232.044493)
			(xy 358.093472 -232.036368) (xy 358.044079 -232.02032) (xy 357.997805 -231.996742) (xy 357.955789 -231.966216)
			(xy 357.919066 -231.929493) (xy 357.88854 -231.887477) (xy 357.864962 -231.841203) (xy 357.848914 -231.79181)
			(xy 357.840789 -231.740515) (xy 357.560625 -231.740515) (xy 357.5525 -231.79181) (xy 357.536452 -231.841203)
			(xy 357.512874 -231.887477) (xy 357.482348 -231.929493) (xy 357.445625 -231.966216) (xy 357.403609 -231.996742)
			(xy 357.357335 -232.02032) (xy 357.307942 -232.036368) (xy 357.256647 -232.044493) (xy 357.204713 -232.044493)
			(xy 357.153418 -232.036368) (xy 357.104025 -232.02032) (xy 357.057751 -231.996742) (xy 357.015735 -231.966216)
			(xy 356.979012 -231.929493) (xy 356.948486 -231.887477) (xy 356.924908 -231.841203) (xy 356.90886 -231.79181)
			(xy 356.900735 -231.740515) (xy 356.620825 -231.740515) (xy 356.6127 -231.79181) (xy 356.596652 -231.841203)
			(xy 356.573074 -231.887477) (xy 356.542548 -231.929493) (xy 356.505825 -231.966216) (xy 356.463809 -231.996742)
			(xy 356.417535 -232.02032) (xy 356.368142 -232.036368) (xy 356.316847 -232.044493) (xy 356.264913 -232.044493)
			(xy 356.213618 -232.036368) (xy 356.164225 -232.02032) (xy 356.117951 -231.996742) (xy 356.075935 -231.966216)
			(xy 356.039212 -231.929493) (xy 356.008686 -231.887477) (xy 355.985108 -231.841203) (xy 355.96906 -231.79181)
			(xy 355.960935 -231.740515) (xy 355.681025 -231.740515) (xy 355.6729 -231.79181) (xy 355.656852 -231.841203)
			(xy 355.633274 -231.887477) (xy 355.602748 -231.929493) (xy 355.566025 -231.966216) (xy 355.524009 -231.996742)
			(xy 355.477735 -232.02032) (xy 355.428342 -232.036368) (xy 355.377047 -232.044493) (xy 355.325113 -232.044493)
			(xy 355.273818 -232.036368) (xy 355.224425 -232.02032) (xy 355.178151 -231.996742) (xy 355.136135 -231.966216)
			(xy 355.099412 -231.929493) (xy 355.068886 -231.887477) (xy 355.045308 -231.841203) (xy 355.02926 -231.79181)
			(xy 355.021135 -231.740515) (xy 354.741225 -231.740515) (xy 354.7331 -231.79181) (xy 354.717052 -231.841203)
			(xy 354.693474 -231.887477) (xy 354.662948 -231.929493) (xy 354.626225 -231.966216) (xy 354.584209 -231.996742)
			(xy 354.537935 -232.02032) (xy 354.488542 -232.036368) (xy 354.437247 -232.044493) (xy 354.385313 -232.044493)
			(xy 354.334018 -232.036368) (xy 354.284625 -232.02032) (xy 354.238351 -231.996742) (xy 354.196335 -231.966216)
			(xy 354.159612 -231.929493) (xy 354.129086 -231.887477) (xy 354.105508 -231.841203) (xy 354.08946 -231.79181)
			(xy 354.081335 -231.740515) (xy 353.827002 -231.740515) (xy 353.826858 -231.746909) (xy 353.815096 -231.810553)
			(xy 353.80422 -231.84104) (xy 353.800918 -231.849676) (xy 353.800918 -232.073958) (xy 353.801376 -232.084467)
			(xy 353.809928 -232.103666) (xy 353.817428 -232.111042) (xy 353.872038 -232.160572) (xy 353.879209 -232.166631)
			(xy 353.896693 -232.173435) (xy 353.906074 -232.17378) (xy 353.909884 -232.173526) (xy 353.941634 -232.172256)
			(xy 353.968284 -232.172756) (xy 354.020989 -232.180705) (xy 354.071921 -232.196419) (xy 354.119941 -232.219549)
			(xy 354.163979 -232.249577) (xy 354.203049 -232.285833) (xy 354.23628 -232.327506) (xy 354.262929 -232.373667)
			(xy 354.282401 -232.423284) (xy 354.294261 -232.475248) (xy 354.298244 -232.5284) (xy 354.296301 -232.554331)
			(xy 354.551489 -232.554331) (xy 354.551489 -232.502397) (xy 354.559614 -232.451102) (xy 354.575662 -232.401709)
			(xy 354.59924 -232.355435) (xy 354.629766 -232.313419) (xy 354.666489 -232.276696) (xy 354.708505 -232.24617)
			(xy 354.754779 -232.222592) (xy 354.804172 -232.206544) (xy 354.855467 -232.198419) (xy 354.907401 -232.198419)
			(xy 354.958696 -232.206544) (xy 355.008089 -232.222592) (xy 355.054363 -232.24617) (xy 355.096379 -232.276696)
			(xy 355.133102 -232.313419) (xy 355.163628 -232.355435) (xy 355.187206 -232.401709) (xy 355.203254 -232.451102)
			(xy 355.211379 -232.502397) (xy 355.211888 -232.528364) (xy 355.211379 -232.554331) (xy 355.491289 -232.554331)
			(xy 355.491289 -232.502397) (xy 355.499414 -232.451102) (xy 355.515462 -232.401709) (xy 355.53904 -232.355435)
			(xy 355.569566 -232.313419) (xy 355.606289 -232.276696) (xy 355.648305 -232.24617) (xy 355.694579 -232.222592)
			(xy 355.743972 -232.206544) (xy 355.795267 -232.198419) (xy 355.847201 -232.198419) (xy 355.898496 -232.206544)
			(xy 355.947889 -232.222592) (xy 355.994163 -232.24617) (xy 356.036179 -232.276696) (xy 356.072902 -232.313419)
			(xy 356.103428 -232.355435) (xy 356.127006 -232.401709) (xy 356.143054 -232.451102) (xy 356.151179 -232.502397)
			(xy 356.151688 -232.528364) (xy 356.151179 -232.554331) (xy 356.431089 -232.554331) (xy 356.431089 -232.502397)
			(xy 356.439214 -232.451102) (xy 356.455262 -232.401709) (xy 356.47884 -232.355435) (xy 356.509366 -232.313419)
			(xy 356.546089 -232.276696) (xy 356.588105 -232.24617) (xy 356.634379 -232.222592) (xy 356.683772 -232.206544)
			(xy 356.735067 -232.198419) (xy 356.787001 -232.198419) (xy 356.838296 -232.206544) (xy 356.887689 -232.222592)
			(xy 356.933963 -232.24617) (xy 356.975979 -232.276696) (xy 357.012702 -232.313419) (xy 357.043228 -232.355435)
			(xy 357.066806 -232.401709) (xy 357.082854 -232.451102) (xy 357.090979 -232.502397) (xy 357.091488 -232.528364)
			(xy 357.090979 -232.554331) (xy 357.370889 -232.554331) (xy 357.370889 -232.502397) (xy 357.379014 -232.451102)
			(xy 357.395062 -232.401709) (xy 357.41864 -232.355435) (xy 357.449166 -232.313419) (xy 357.485889 -232.276696)
			(xy 357.527905 -232.24617) (xy 357.574179 -232.222592) (xy 357.623572 -232.206544) (xy 357.674867 -232.198419)
			(xy 357.726801 -232.198419) (xy 357.778096 -232.206544) (xy 357.827489 -232.222592) (xy 357.873763 -232.24617)
			(xy 357.915779 -232.276696) (xy 357.952502 -232.313419) (xy 357.983028 -232.355435) (xy 358.006606 -232.401709)
			(xy 358.022654 -232.451102) (xy 358.030779 -232.502397) (xy 358.031288 -232.528364) (xy 358.030779 -232.554331)
			(xy 358.310689 -232.554331) (xy 358.310689 -232.502397) (xy 358.318814 -232.451102) (xy 358.334862 -232.401709)
			(xy 358.35844 -232.355435) (xy 358.388966 -232.313419) (xy 358.425689 -232.276696) (xy 358.467705 -232.24617)
			(xy 358.513979 -232.222592) (xy 358.563372 -232.206544) (xy 358.614667 -232.198419) (xy 358.666601 -232.198419)
			(xy 358.717896 -232.206544) (xy 358.767289 -232.222592) (xy 358.813563 -232.24617) (xy 358.855579 -232.276696)
			(xy 358.892302 -232.313419) (xy 358.922828 -232.355435) (xy 358.946406 -232.401709) (xy 358.962454 -232.451102)
			(xy 358.970579 -232.502397) (xy 358.971088 -232.528364) (xy 358.970579 -232.554331) (xy 359.250489 -232.554331)
			(xy 359.250489 -232.502397) (xy 359.258614 -232.451102) (xy 359.274662 -232.401709) (xy 359.29824 -232.355435)
			(xy 359.328766 -232.313419) (xy 359.365489 -232.276696) (xy 359.407505 -232.24617) (xy 359.453779 -232.222592)
			(xy 359.503172 -232.206544) (xy 359.554467 -232.198419) (xy 359.606401 -232.198419) (xy 359.657696 -232.206544)
			(xy 359.707089 -232.222592) (xy 359.753363 -232.24617) (xy 359.795379 -232.276696) (xy 359.832102 -232.313419)
			(xy 359.862628 -232.355435) (xy 359.886206 -232.401709) (xy 359.902254 -232.451102) (xy 359.910379 -232.502397)
			(xy 359.910888 -232.528364) (xy 359.910379 -232.554331) (xy 360.190289 -232.554331) (xy 360.190289 -232.502397)
			(xy 360.198414 -232.451102) (xy 360.214462 -232.401709) (xy 360.23804 -232.355435) (xy 360.268566 -232.313419)
			(xy 360.305289 -232.276696) (xy 360.347305 -232.24617) (xy 360.393579 -232.222592) (xy 360.442972 -232.206544)
			(xy 360.494267 -232.198419) (xy 360.546201 -232.198419) (xy 360.597496 -232.206544) (xy 360.646889 -232.222592)
			(xy 360.693163 -232.24617) (xy 360.735179 -232.276696) (xy 360.771902 -232.313419) (xy 360.802428 -232.355435)
			(xy 360.826006 -232.401709) (xy 360.842054 -232.451102) (xy 360.850179 -232.502397) (xy 360.850688 -232.528364)
			(xy 360.850179 -232.554331) (xy 361.130089 -232.554331) (xy 361.130089 -232.502397) (xy 361.138214 -232.451102)
			(xy 361.154262 -232.401709) (xy 361.17784 -232.355435) (xy 361.208366 -232.313419) (xy 361.245089 -232.276696)
			(xy 361.287105 -232.24617) (xy 361.333379 -232.222592) (xy 361.382772 -232.206544) (xy 361.434067 -232.198419)
			(xy 361.486001 -232.198419) (xy 361.537296 -232.206544) (xy 361.586689 -232.222592) (xy 361.632963 -232.24617)
			(xy 361.674979 -232.276696) (xy 361.711702 -232.313419) (xy 361.742228 -232.355435) (xy 361.765806 -232.401709)
			(xy 361.781854 -232.451102) (xy 361.789979 -232.502397) (xy 361.790488 -232.528364) (xy 361.789979 -232.554331)
			(xy 362.069889 -232.554331) (xy 362.069889 -232.502397) (xy 362.078014 -232.451102) (xy 362.094062 -232.401709)
			(xy 362.11764 -232.355435) (xy 362.148166 -232.313419) (xy 362.184889 -232.276696) (xy 362.226905 -232.24617)
			(xy 362.273179 -232.222592) (xy 362.322572 -232.206544) (xy 362.373867 -232.198419) (xy 362.425801 -232.198419)
			(xy 362.477096 -232.206544) (xy 362.526489 -232.222592) (xy 362.572763 -232.24617) (xy 362.614779 -232.276696)
			(xy 362.651502 -232.313419) (xy 362.682028 -232.355435) (xy 362.705606 -232.401709) (xy 362.721654 -232.451102)
			(xy 362.729779 -232.502397) (xy 362.730288 -232.528364) (xy 362.729779 -232.554331) (xy 363.009689 -232.554331)
			(xy 363.009689 -232.502397) (xy 363.017814 -232.451102) (xy 363.033862 -232.401709) (xy 363.05744 -232.355435)
			(xy 363.087966 -232.313419) (xy 363.124689 -232.276696) (xy 363.166705 -232.24617) (xy 363.212979 -232.222592)
			(xy 363.262372 -232.206544) (xy 363.313667 -232.198419) (xy 363.365601 -232.198419) (xy 363.416896 -232.206544)
			(xy 363.466289 -232.222592) (xy 363.512563 -232.24617) (xy 363.554579 -232.276696) (xy 363.591302 -232.313419)
			(xy 363.621828 -232.355435) (xy 363.645406 -232.401709) (xy 363.661454 -232.451102) (xy 363.669579 -232.502397)
			(xy 363.670088 -232.528364) (xy 363.669579 -232.554331) (xy 363.661454 -232.605626) (xy 363.645406 -232.655019)
			(xy 363.621828 -232.701293) (xy 363.591302 -232.743309) (xy 363.554579 -232.780032) (xy 363.512563 -232.810558)
			(xy 363.466289 -232.834136) (xy 363.416896 -232.850184) (xy 363.365601 -232.858309) (xy 363.313667 -232.858309)
			(xy 363.262372 -232.850184) (xy 363.212979 -232.834136) (xy 363.166705 -232.810558) (xy 363.124689 -232.780032)
			(xy 363.087966 -232.743309) (xy 363.05744 -232.701293) (xy 363.033862 -232.655019) (xy 363.017814 -232.605626)
			(xy 363.009689 -232.554331) (xy 362.729779 -232.554331) (xy 362.721654 -232.605626) (xy 362.705606 -232.655019)
			(xy 362.682028 -232.701293) (xy 362.651502 -232.743309) (xy 362.614779 -232.780032) (xy 362.572763 -232.810558)
			(xy 362.526489 -232.834136) (xy 362.477096 -232.850184) (xy 362.425801 -232.858309) (xy 362.373867 -232.858309)
			(xy 362.322572 -232.850184) (xy 362.273179 -232.834136) (xy 362.226905 -232.810558) (xy 362.184889 -232.780032)
			(xy 362.148166 -232.743309) (xy 362.11764 -232.701293) (xy 362.094062 -232.655019) (xy 362.078014 -232.605626)
			(xy 362.069889 -232.554331) (xy 361.789979 -232.554331) (xy 361.781854 -232.605626) (xy 361.765806 -232.655019)
			(xy 361.742228 -232.701293) (xy 361.711702 -232.743309) (xy 361.674979 -232.780032) (xy 361.632963 -232.810558)
			(xy 361.586689 -232.834136) (xy 361.537296 -232.850184) (xy 361.486001 -232.858309) (xy 361.434067 -232.858309)
			(xy 361.382772 -232.850184) (xy 361.333379 -232.834136) (xy 361.287105 -232.810558) (xy 361.245089 -232.780032)
			(xy 361.208366 -232.743309) (xy 361.17784 -232.701293) (xy 361.154262 -232.655019) (xy 361.138214 -232.605626)
			(xy 361.130089 -232.554331) (xy 360.850179 -232.554331) (xy 360.842054 -232.605626) (xy 360.826006 -232.655019)
			(xy 360.802428 -232.701293) (xy 360.771902 -232.743309) (xy 360.735179 -232.780032) (xy 360.693163 -232.810558)
			(xy 360.646889 -232.834136) (xy 360.597496 -232.850184) (xy 360.546201 -232.858309) (xy 360.494267 -232.858309)
			(xy 360.442972 -232.850184) (xy 360.393579 -232.834136) (xy 360.347305 -232.810558) (xy 360.305289 -232.780032)
			(xy 360.268566 -232.743309) (xy 360.23804 -232.701293) (xy 360.214462 -232.655019) (xy 360.198414 -232.605626)
			(xy 360.190289 -232.554331) (xy 359.910379 -232.554331) (xy 359.902254 -232.605626) (xy 359.886206 -232.655019)
			(xy 359.862628 -232.701293) (xy 359.832102 -232.743309) (xy 359.795379 -232.780032) (xy 359.753363 -232.810558)
			(xy 359.707089 -232.834136) (xy 359.657696 -232.850184) (xy 359.606401 -232.858309) (xy 359.554467 -232.858309)
			(xy 359.503172 -232.850184) (xy 359.453779 -232.834136) (xy 359.407505 -232.810558) (xy 359.365489 -232.780032)
			(xy 359.328766 -232.743309) (xy 359.29824 -232.701293) (xy 359.274662 -232.655019) (xy 359.258614 -232.605626)
			(xy 359.250489 -232.554331) (xy 358.970579 -232.554331) (xy 358.962454 -232.605626) (xy 358.946406 -232.655019)
			(xy 358.922828 -232.701293) (xy 358.892302 -232.743309) (xy 358.855579 -232.780032) (xy 358.813563 -232.810558)
			(xy 358.767289 -232.834136) (xy 358.717896 -232.850184) (xy 358.666601 -232.858309) (xy 358.614667 -232.858309)
			(xy 358.563372 -232.850184) (xy 358.513979 -232.834136) (xy 358.467705 -232.810558) (xy 358.425689 -232.780032)
			(xy 358.388966 -232.743309) (xy 358.35844 -232.701293) (xy 358.334862 -232.655019) (xy 358.318814 -232.605626)
			(xy 358.310689 -232.554331) (xy 358.030779 -232.554331) (xy 358.022654 -232.605626) (xy 358.006606 -232.655019)
			(xy 357.983028 -232.701293) (xy 357.952502 -232.743309) (xy 357.915779 -232.780032) (xy 357.873763 -232.810558)
			(xy 357.827489 -232.834136) (xy 357.778096 -232.850184) (xy 357.726801 -232.858309) (xy 357.674867 -232.858309)
			(xy 357.623572 -232.850184) (xy 357.574179 -232.834136) (xy 357.527905 -232.810558) (xy 357.485889 -232.780032)
			(xy 357.449166 -232.743309) (xy 357.41864 -232.701293) (xy 357.395062 -232.655019) (xy 357.379014 -232.605626)
			(xy 357.370889 -232.554331) (xy 357.090979 -232.554331) (xy 357.082854 -232.605626) (xy 357.066806 -232.655019)
			(xy 357.043228 -232.701293) (xy 357.012702 -232.743309) (xy 356.975979 -232.780032) (xy 356.933963 -232.810558)
			(xy 356.887689 -232.834136) (xy 356.838296 -232.850184) (xy 356.787001 -232.858309) (xy 356.735067 -232.858309)
			(xy 356.683772 -232.850184) (xy 356.634379 -232.834136) (xy 356.588105 -232.810558) (xy 356.546089 -232.780032)
			(xy 356.509366 -232.743309) (xy 356.47884 -232.701293) (xy 356.455262 -232.655019) (xy 356.439214 -232.605626)
			(xy 356.431089 -232.554331) (xy 356.151179 -232.554331) (xy 356.143054 -232.605626) (xy 356.127006 -232.655019)
			(xy 356.103428 -232.701293) (xy 356.072902 -232.743309) (xy 356.036179 -232.780032) (xy 355.994163 -232.810558)
			(xy 355.947889 -232.834136) (xy 355.898496 -232.850184) (xy 355.847201 -232.858309) (xy 355.795267 -232.858309)
			(xy 355.743972 -232.850184) (xy 355.694579 -232.834136) (xy 355.648305 -232.810558) (xy 355.606289 -232.780032)
			(xy 355.569566 -232.743309) (xy 355.53904 -232.701293) (xy 355.515462 -232.655019) (xy 355.499414 -232.605626)
			(xy 355.491289 -232.554331) (xy 355.211379 -232.554331) (xy 355.203254 -232.605626) (xy 355.187206 -232.655019)
			(xy 355.163628 -232.701293) (xy 355.133102 -232.743309) (xy 355.096379 -232.780032) (xy 355.054363 -232.810558)
			(xy 355.008089 -232.834136) (xy 354.958696 -232.850184) (xy 354.907401 -232.858309) (xy 354.855467 -232.858309)
			(xy 354.804172 -232.850184) (xy 354.754779 -232.834136) (xy 354.708505 -232.810558) (xy 354.666489 -232.780032)
			(xy 354.629766 -232.743309) (xy 354.59924 -232.701293) (xy 354.575662 -232.655019) (xy 354.559614 -232.605626)
			(xy 354.551489 -232.554331) (xy 354.296301 -232.554331) (xy 354.294261 -232.581552) (xy 354.282401 -232.633516)
			(xy 354.262929 -232.683133) (xy 354.23628 -232.729294) (xy 354.203049 -232.770967) (xy 354.163979 -232.807223)
			(xy 354.119941 -232.837251) (xy 354.071921 -232.860381) (xy 354.020989 -232.876095) (xy 353.968284 -232.884044)
			(xy 353.941634 -232.884472) (xy 353.909884 -232.883202) (xy 353.906074 -232.882948) (xy 353.896687 -232.88328)
			(xy 353.879186 -232.890063) (xy 353.872038 -232.896156) (xy 353.817174 -232.94594) (xy 353.813872 -232.949242)
			(xy 353.808519 -232.955636) (xy 353.801912 -232.970934) (xy 353.800918 -232.979214) (xy 353.800918 -233.205274)
			(xy 353.803712 -233.213148) (xy 353.804474 -233.214672) (xy 353.815406 -233.245341) (xy 353.827161 -233.309374)
			(xy 353.827842 -233.341926) (xy 353.827842 -233.342434) (xy 353.827288 -233.368147) (xy 354.081335 -233.368147)
			(xy 354.081335 -233.316213) (xy 354.08946 -233.264918) (xy 354.105508 -233.215525) (xy 354.129086 -233.169251)
			(xy 354.159612 -233.127235) (xy 354.196335 -233.090512) (xy 354.238351 -233.059986) (xy 354.284625 -233.036408)
			(xy 354.334018 -233.02036) (xy 354.385313 -233.012235) (xy 354.437247 -233.012235) (xy 354.488542 -233.02036)
			(xy 354.537935 -233.036408) (xy 354.584209 -233.059986) (xy 354.626225 -233.090512) (xy 354.662948 -233.127235)
			(xy 354.693474 -233.169251) (xy 354.717052 -233.215525) (xy 354.7331 -233.264918) (xy 354.741225 -233.316213)
			(xy 354.741734 -233.34218) (xy 354.741225 -233.368147) (xy 355.021135 -233.368147) (xy 355.021135 -233.316213)
			(xy 355.02926 -233.264918) (xy 355.045308 -233.215525) (xy 355.068886 -233.169251) (xy 355.099412 -233.127235)
			(xy 355.136135 -233.090512) (xy 355.178151 -233.059986) (xy 355.224425 -233.036408) (xy 355.273818 -233.02036)
			(xy 355.325113 -233.012235) (xy 355.377047 -233.012235) (xy 355.428342 -233.02036) (xy 355.477735 -233.036408)
			(xy 355.524009 -233.059986) (xy 355.566025 -233.090512) (xy 355.602748 -233.127235) (xy 355.633274 -233.169251)
			(xy 355.656852 -233.215525) (xy 355.6729 -233.264918) (xy 355.681025 -233.316213) (xy 355.681534 -233.34218)
			(xy 355.681025 -233.368147) (xy 355.960935 -233.368147) (xy 355.960935 -233.316213) (xy 355.96906 -233.264918)
			(xy 355.985108 -233.215525) (xy 356.008686 -233.169251) (xy 356.039212 -233.127235) (xy 356.075935 -233.090512)
			(xy 356.117951 -233.059986) (xy 356.164225 -233.036408) (xy 356.213618 -233.02036) (xy 356.264913 -233.012235)
			(xy 356.316847 -233.012235) (xy 356.368142 -233.02036) (xy 356.417535 -233.036408) (xy 356.463809 -233.059986)
			(xy 356.505825 -233.090512) (xy 356.542548 -233.127235) (xy 356.573074 -233.169251) (xy 356.596652 -233.215525)
			(xy 356.6127 -233.264918) (xy 356.620825 -233.316213) (xy 356.621334 -233.34218) (xy 356.620825 -233.368147)
			(xy 356.900735 -233.368147) (xy 356.900735 -233.316213) (xy 356.90886 -233.264918) (xy 356.924908 -233.215525)
			(xy 356.948486 -233.169251) (xy 356.979012 -233.127235) (xy 357.015735 -233.090512) (xy 357.057751 -233.059986)
			(xy 357.104025 -233.036408) (xy 357.153418 -233.02036) (xy 357.204713 -233.012235) (xy 357.256647 -233.012235)
			(xy 357.307942 -233.02036) (xy 357.357335 -233.036408) (xy 357.403609 -233.059986) (xy 357.445625 -233.090512)
			(xy 357.482348 -233.127235) (xy 357.512874 -233.169251) (xy 357.536452 -233.215525) (xy 357.5525 -233.264918)
			(xy 357.560625 -233.316213) (xy 357.561134 -233.34218) (xy 357.560625 -233.368147) (xy 357.840789 -233.368147)
			(xy 357.840789 -233.316213) (xy 357.848914 -233.264918) (xy 357.864962 -233.215525) (xy 357.88854 -233.169251)
			(xy 357.919066 -233.127235) (xy 357.955789 -233.090512) (xy 357.997805 -233.059986) (xy 358.044079 -233.036408)
			(xy 358.093472 -233.02036) (xy 358.144767 -233.012235) (xy 358.196701 -233.012235) (xy 358.247996 -233.02036)
			(xy 358.297389 -233.036408) (xy 358.343663 -233.059986) (xy 358.385679 -233.090512) (xy 358.422402 -233.127235)
			(xy 358.452928 -233.169251) (xy 358.476506 -233.215525) (xy 358.492554 -233.264918) (xy 358.500679 -233.316213)
			(xy 358.501188 -233.34218) (xy 358.500679 -233.368147) (xy 358.780335 -233.368147) (xy 358.780335 -233.316213)
			(xy 358.78846 -233.264918) (xy 358.804508 -233.215525) (xy 358.828086 -233.169251) (xy 358.858612 -233.127235)
			(xy 358.895335 -233.090512) (xy 358.937351 -233.059986) (xy 358.983625 -233.036408) (xy 359.033018 -233.02036)
			(xy 359.084313 -233.012235) (xy 359.136247 -233.012235) (xy 359.187542 -233.02036) (xy 359.236935 -233.036408)
			(xy 359.283209 -233.059986) (xy 359.325225 -233.090512) (xy 359.361948 -233.127235) (xy 359.392474 -233.169251)
			(xy 359.416052 -233.215525) (xy 359.4321 -233.264918) (xy 359.440225 -233.316213) (xy 359.440734 -233.34218)
			(xy 359.440225 -233.368147) (xy 359.720135 -233.368147) (xy 359.720135 -233.316213) (xy 359.72826 -233.264918)
			(xy 359.744308 -233.215525) (xy 359.767886 -233.169251) (xy 359.798412 -233.127235) (xy 359.835135 -233.090512)
			(xy 359.877151 -233.059986) (xy 359.923425 -233.036408) (xy 359.972818 -233.02036) (xy 360.024113 -233.012235)
			(xy 360.076047 -233.012235) (xy 360.127342 -233.02036) (xy 360.176735 -233.036408) (xy 360.223009 -233.059986)
			(xy 360.265025 -233.090512) (xy 360.301748 -233.127235) (xy 360.332274 -233.169251) (xy 360.355852 -233.215525)
			(xy 360.3719 -233.264918) (xy 360.380025 -233.316213) (xy 360.380534 -233.34218) (xy 360.380025 -233.368147)
			(xy 360.659935 -233.368147) (xy 360.659935 -233.316213) (xy 360.66806 -233.264918) (xy 360.684108 -233.215525)
			(xy 360.707686 -233.169251) (xy 360.738212 -233.127235) (xy 360.774935 -233.090512) (xy 360.816951 -233.059986)
			(xy 360.863225 -233.036408) (xy 360.912618 -233.02036) (xy 360.963913 -233.012235) (xy 361.015847 -233.012235)
			(xy 361.067142 -233.02036) (xy 361.116535 -233.036408) (xy 361.162809 -233.059986) (xy 361.204825 -233.090512)
			(xy 361.241548 -233.127235) (xy 361.272074 -233.169251) (xy 361.295652 -233.215525) (xy 361.3117 -233.264918)
			(xy 361.319825 -233.316213) (xy 361.320334 -233.34218) (xy 361.319825 -233.368147) (xy 361.599989 -233.368147)
			(xy 361.599989 -233.316213) (xy 361.608114 -233.264918) (xy 361.624162 -233.215525) (xy 361.64774 -233.169251)
			(xy 361.678266 -233.127235) (xy 361.714989 -233.090512) (xy 361.757005 -233.059986) (xy 361.803279 -233.036408)
			(xy 361.852672 -233.02036) (xy 361.903967 -233.012235) (xy 361.955901 -233.012235) (xy 362.007196 -233.02036)
			(xy 362.056589 -233.036408) (xy 362.102863 -233.059986) (xy 362.144879 -233.090512) (xy 362.181602 -233.127235)
			(xy 362.212128 -233.169251) (xy 362.235706 -233.215525) (xy 362.251754 -233.264918) (xy 362.259879 -233.316213)
			(xy 362.260388 -233.34218) (xy 362.259879 -233.368147) (xy 362.539535 -233.368147) (xy 362.539535 -233.316213)
			(xy 362.54766 -233.264918) (xy 362.563708 -233.215525) (xy 362.587286 -233.169251) (xy 362.617812 -233.127235)
			(xy 362.654535 -233.090512) (xy 362.696551 -233.059986) (xy 362.742825 -233.036408) (xy 362.792218 -233.02036)
			(xy 362.843513 -233.012235) (xy 362.895447 -233.012235) (xy 362.946742 -233.02036) (xy 362.996135 -233.036408)
			(xy 363.042409 -233.059986) (xy 363.084425 -233.090512) (xy 363.121148 -233.127235) (xy 363.151674 -233.169251)
			(xy 363.175252 -233.215525) (xy 363.1913 -233.264918) (xy 363.199425 -233.316213) (xy 363.199934 -233.34218)
			(xy 363.199425 -233.368147) (xy 363.1913 -233.419442) (xy 363.175252 -233.468835) (xy 363.151674 -233.515109)
			(xy 363.121148 -233.557125) (xy 363.084425 -233.593848) (xy 363.042409 -233.624374) (xy 362.996135 -233.647952)
			(xy 362.946742 -233.664) (xy 362.895447 -233.672125) (xy 362.843513 -233.672125) (xy 362.792218 -233.664)
			(xy 362.742825 -233.647952) (xy 362.696551 -233.624374) (xy 362.654535 -233.593848) (xy 362.617812 -233.557125)
			(xy 362.587286 -233.515109) (xy 362.563708 -233.468835) (xy 362.54766 -233.419442) (xy 362.539535 -233.368147)
			(xy 362.259879 -233.368147) (xy 362.251754 -233.419442) (xy 362.235706 -233.468835) (xy 362.212128 -233.515109)
			(xy 362.181602 -233.557125) (xy 362.144879 -233.593848) (xy 362.102863 -233.624374) (xy 362.056589 -233.647952)
			(xy 362.007196 -233.664) (xy 361.955901 -233.672125) (xy 361.903967 -233.672125) (xy 361.852672 -233.664)
			(xy 361.803279 -233.647952) (xy 361.757005 -233.624374) (xy 361.714989 -233.593848) (xy 361.678266 -233.557125)
			(xy 361.64774 -233.515109) (xy 361.624162 -233.468835) (xy 361.608114 -233.419442) (xy 361.599989 -233.368147)
			(xy 361.319825 -233.368147) (xy 361.3117 -233.419442) (xy 361.295652 -233.468835) (xy 361.272074 -233.515109)
			(xy 361.241548 -233.557125) (xy 361.204825 -233.593848) (xy 361.162809 -233.624374) (xy 361.116535 -233.647952)
			(xy 361.067142 -233.664) (xy 361.015847 -233.672125) (xy 360.963913 -233.672125) (xy 360.912618 -233.664)
			(xy 360.863225 -233.647952) (xy 360.816951 -233.624374) (xy 360.774935 -233.593848) (xy 360.738212 -233.557125)
			(xy 360.707686 -233.515109) (xy 360.684108 -233.468835) (xy 360.66806 -233.419442) (xy 360.659935 -233.368147)
			(xy 360.380025 -233.368147) (xy 360.3719 -233.419442) (xy 360.355852 -233.468835) (xy 360.332274 -233.515109)
			(xy 360.301748 -233.557125) (xy 360.265025 -233.593848) (xy 360.223009 -233.624374) (xy 360.176735 -233.647952)
			(xy 360.127342 -233.664) (xy 360.076047 -233.672125) (xy 360.024113 -233.672125) (xy 359.972818 -233.664)
			(xy 359.923425 -233.647952) (xy 359.877151 -233.624374) (xy 359.835135 -233.593848) (xy 359.798412 -233.557125)
			(xy 359.767886 -233.515109) (xy 359.744308 -233.468835) (xy 359.72826 -233.419442) (xy 359.720135 -233.368147)
			(xy 359.440225 -233.368147) (xy 359.4321 -233.419442) (xy 359.416052 -233.468835) (xy 359.392474 -233.515109)
			(xy 359.361948 -233.557125) (xy 359.325225 -233.593848) (xy 359.283209 -233.624374) (xy 359.236935 -233.647952)
			(xy 359.187542 -233.664) (xy 359.136247 -233.672125) (xy 359.084313 -233.672125) (xy 359.033018 -233.664)
			(xy 358.983625 -233.647952) (xy 358.937351 -233.624374) (xy 358.895335 -233.593848) (xy 358.858612 -233.557125)
			(xy 358.828086 -233.515109) (xy 358.804508 -233.468835) (xy 358.78846 -233.419442) (xy 358.780335 -233.368147)
			(xy 358.500679 -233.368147) (xy 358.492554 -233.419442) (xy 358.476506 -233.468835) (xy 358.452928 -233.515109)
			(xy 358.422402 -233.557125) (xy 358.385679 -233.593848) (xy 358.343663 -233.624374) (xy 358.297389 -233.647952)
			(xy 358.247996 -233.664) (xy 358.196701 -233.672125) (xy 358.144767 -233.672125) (xy 358.093472 -233.664)
			(xy 358.044079 -233.647952) (xy 357.997805 -233.624374) (xy 357.955789 -233.593848) (xy 357.919066 -233.557125)
			(xy 357.88854 -233.515109) (xy 357.864962 -233.468835) (xy 357.848914 -233.419442) (xy 357.840789 -233.368147)
			(xy 357.560625 -233.368147) (xy 357.5525 -233.419442) (xy 357.536452 -233.468835) (xy 357.512874 -233.515109)
			(xy 357.482348 -233.557125) (xy 357.445625 -233.593848) (xy 357.403609 -233.624374) (xy 357.357335 -233.647952)
			(xy 357.307942 -233.664) (xy 357.256647 -233.672125) (xy 357.204713 -233.672125) (xy 357.153418 -233.664)
			(xy 357.104025 -233.647952) (xy 357.057751 -233.624374) (xy 357.015735 -233.593848) (xy 356.979012 -233.557125)
			(xy 356.948486 -233.515109) (xy 356.924908 -233.468835) (xy 356.90886 -233.419442) (xy 356.900735 -233.368147)
			(xy 356.620825 -233.368147) (xy 356.6127 -233.419442) (xy 356.596652 -233.468835) (xy 356.573074 -233.515109)
			(xy 356.542548 -233.557125) (xy 356.505825 -233.593848) (xy 356.463809 -233.624374) (xy 356.417535 -233.647952)
			(xy 356.368142 -233.664) (xy 356.316847 -233.672125) (xy 356.264913 -233.672125) (xy 356.213618 -233.664)
			(xy 356.164225 -233.647952) (xy 356.117951 -233.624374) (xy 356.075935 -233.593848) (xy 356.039212 -233.557125)
			(xy 356.008686 -233.515109) (xy 355.985108 -233.468835) (xy 355.96906 -233.419442) (xy 355.960935 -233.368147)
			(xy 355.681025 -233.368147) (xy 355.6729 -233.419442) (xy 355.656852 -233.468835) (xy 355.633274 -233.515109)
			(xy 355.602748 -233.557125) (xy 355.566025 -233.593848) (xy 355.524009 -233.624374) (xy 355.477735 -233.647952)
			(xy 355.428342 -233.664) (xy 355.377047 -233.672125) (xy 355.325113 -233.672125) (xy 355.273818 -233.664)
			(xy 355.224425 -233.647952) (xy 355.178151 -233.624374) (xy 355.136135 -233.593848) (xy 355.099412 -233.557125)
			(xy 355.068886 -233.515109) (xy 355.045308 -233.468835) (xy 355.02926 -233.419442) (xy 355.021135 -233.368147)
			(xy 354.741225 -233.368147) (xy 354.7331 -233.419442) (xy 354.717052 -233.468835) (xy 354.693474 -233.515109)
			(xy 354.662948 -233.557125) (xy 354.626225 -233.593848) (xy 354.584209 -233.624374) (xy 354.537935 -233.647952)
			(xy 354.488542 -233.664) (xy 354.437247 -233.672125) (xy 354.385313 -233.672125) (xy 354.334018 -233.664)
			(xy 354.284625 -233.647952) (xy 354.238351 -233.624374) (xy 354.196335 -233.593848) (xy 354.159612 -233.557125)
			(xy 354.129086 -233.515109) (xy 354.105508 -233.468835) (xy 354.08946 -233.419442) (xy 354.081335 -233.368147)
			(xy 353.827288 -233.368147) (xy 353.827141 -233.374984) (xy 353.815388 -233.439014) (xy 353.804474 -233.469688)
			(xy 353.803712 -233.471212) (xy 353.800918 -233.479086) (xy 353.800918 -233.701844) (xy 353.801374 -233.712354)
			(xy 353.809922 -233.731557) (xy 353.817428 -233.738928) (xy 353.872038 -233.788458) (xy 353.879213 -233.794509)
			(xy 353.896696 -233.801301) (xy 353.906074 -233.801666) (xy 353.909884 -233.801412) (xy 353.941634 -233.800142)
			(xy 353.968278 -233.800642) (xy 354.02097 -233.808589) (xy 354.071889 -233.8243) (xy 354.119898 -233.847424)
			(xy 354.163925 -233.877445) (xy 354.202986 -233.913692) (xy 354.236209 -233.955355) (xy 354.262851 -234.001504)
			(xy 354.282318 -234.051109) (xy 354.294175 -234.103061) (xy 354.298157 -234.1562) (xy 354.296207 -234.182217)
			(xy 354.551489 -234.182217) (xy 354.551489 -234.130283) (xy 354.559614 -234.078988) (xy 354.575662 -234.029595)
			(xy 354.59924 -233.983321) (xy 354.629766 -233.941305) (xy 354.666489 -233.904582) (xy 354.708505 -233.874056)
			(xy 354.754779 -233.850478) (xy 354.804172 -233.83443) (xy 354.855467 -233.826305) (xy 354.907401 -233.826305)
			(xy 354.958696 -233.83443) (xy 355.008089 -233.850478) (xy 355.054363 -233.874056) (xy 355.096379 -233.904582)
			(xy 355.133102 -233.941305) (xy 355.163628 -233.983321) (xy 355.187206 -234.029595) (xy 355.203254 -234.078988)
			(xy 355.211379 -234.130283) (xy 355.211888 -234.15625) (xy 355.211379 -234.182217) (xy 355.491289 -234.182217)
			(xy 355.491289 -234.130283) (xy 355.499414 -234.078988) (xy 355.515462 -234.029595) (xy 355.53904 -233.983321)
			(xy 355.569566 -233.941305) (xy 355.606289 -233.904582) (xy 355.648305 -233.874056) (xy 355.694579 -233.850478)
			(xy 355.743972 -233.83443) (xy 355.795267 -233.826305) (xy 355.847201 -233.826305) (xy 355.898496 -233.83443)
			(xy 355.947889 -233.850478) (xy 355.994163 -233.874056) (xy 356.036179 -233.904582) (xy 356.072902 -233.941305)
			(xy 356.103428 -233.983321) (xy 356.127006 -234.029595) (xy 356.143054 -234.078988) (xy 356.151179 -234.130283)
			(xy 356.151688 -234.15625) (xy 356.151179 -234.182217) (xy 356.431089 -234.182217) (xy 356.431089 -234.130283)
			(xy 356.439214 -234.078988) (xy 356.455262 -234.029595) (xy 356.47884 -233.983321) (xy 356.509366 -233.941305)
			(xy 356.546089 -233.904582) (xy 356.588105 -233.874056) (xy 356.634379 -233.850478) (xy 356.683772 -233.83443)
			(xy 356.735067 -233.826305) (xy 356.787001 -233.826305) (xy 356.838296 -233.83443) (xy 356.887689 -233.850478)
			(xy 356.933963 -233.874056) (xy 356.975979 -233.904582) (xy 357.012702 -233.941305) (xy 357.043228 -233.983321)
			(xy 357.066806 -234.029595) (xy 357.082854 -234.078988) (xy 357.090979 -234.130283) (xy 357.091488 -234.15625)
			(xy 357.090979 -234.182217) (xy 357.370889 -234.182217) (xy 357.370889 -234.130283) (xy 357.379014 -234.078988)
			(xy 357.395062 -234.029595) (xy 357.41864 -233.983321) (xy 357.449166 -233.941305) (xy 357.485889 -233.904582)
			(xy 357.527905 -233.874056) (xy 357.574179 -233.850478) (xy 357.623572 -233.83443) (xy 357.674867 -233.826305)
			(xy 357.726801 -233.826305) (xy 357.778096 -233.83443) (xy 357.827489 -233.850478) (xy 357.873763 -233.874056)
			(xy 357.915779 -233.904582) (xy 357.952502 -233.941305) (xy 357.983028 -233.983321) (xy 358.006606 -234.029595)
			(xy 358.022654 -234.078988) (xy 358.030779 -234.130283) (xy 358.031288 -234.15625) (xy 358.030779 -234.182217)
			(xy 358.310689 -234.182217) (xy 358.310689 -234.130283) (xy 358.318814 -234.078988) (xy 358.334862 -234.029595)
			(xy 358.35844 -233.983321) (xy 358.388966 -233.941305) (xy 358.425689 -233.904582) (xy 358.467705 -233.874056)
			(xy 358.513979 -233.850478) (xy 358.563372 -233.83443) (xy 358.614667 -233.826305) (xy 358.666601 -233.826305)
			(xy 358.717896 -233.83443) (xy 358.767289 -233.850478) (xy 358.813563 -233.874056) (xy 358.855579 -233.904582)
			(xy 358.892302 -233.941305) (xy 358.922828 -233.983321) (xy 358.946406 -234.029595) (xy 358.962454 -234.078988)
			(xy 358.970579 -234.130283) (xy 358.971088 -234.15625) (xy 358.970579 -234.182217) (xy 359.250489 -234.182217)
			(xy 359.250489 -234.130283) (xy 359.258614 -234.078988) (xy 359.274662 -234.029595) (xy 359.29824 -233.983321)
			(xy 359.328766 -233.941305) (xy 359.365489 -233.904582) (xy 359.407505 -233.874056) (xy 359.453779 -233.850478)
			(xy 359.503172 -233.83443) (xy 359.554467 -233.826305) (xy 359.606401 -233.826305) (xy 359.657696 -233.83443)
			(xy 359.707089 -233.850478) (xy 359.753363 -233.874056) (xy 359.795379 -233.904582) (xy 359.832102 -233.941305)
			(xy 359.862628 -233.983321) (xy 359.886206 -234.029595) (xy 359.902254 -234.078988) (xy 359.910379 -234.130283)
			(xy 359.910888 -234.15625) (xy 359.910379 -234.182217) (xy 360.190289 -234.182217) (xy 360.190289 -234.130283)
			(xy 360.198414 -234.078988) (xy 360.214462 -234.029595) (xy 360.23804 -233.983321) (xy 360.268566 -233.941305)
			(xy 360.305289 -233.904582) (xy 360.347305 -233.874056) (xy 360.393579 -233.850478) (xy 360.442972 -233.83443)
			(xy 360.494267 -233.826305) (xy 360.546201 -233.826305) (xy 360.597496 -233.83443) (xy 360.646889 -233.850478)
			(xy 360.693163 -233.874056) (xy 360.735179 -233.904582) (xy 360.771902 -233.941305) (xy 360.802428 -233.983321)
			(xy 360.826006 -234.029595) (xy 360.842054 -234.078988) (xy 360.850179 -234.130283) (xy 360.850688 -234.15625)
			(xy 360.850179 -234.182217) (xy 361.130089 -234.182217) (xy 361.130089 -234.130283) (xy 361.138214 -234.078988)
			(xy 361.154262 -234.029595) (xy 361.17784 -233.983321) (xy 361.208366 -233.941305) (xy 361.245089 -233.904582)
			(xy 361.287105 -233.874056) (xy 361.333379 -233.850478) (xy 361.382772 -233.83443) (xy 361.434067 -233.826305)
			(xy 361.486001 -233.826305) (xy 361.537296 -233.83443) (xy 361.586689 -233.850478) (xy 361.632963 -233.874056)
			(xy 361.674979 -233.904582) (xy 361.711702 -233.941305) (xy 361.742228 -233.983321) (xy 361.765806 -234.029595)
			(xy 361.781854 -234.078988) (xy 361.789979 -234.130283) (xy 361.790488 -234.15625) (xy 361.789979 -234.182217)
			(xy 362.069889 -234.182217) (xy 362.069889 -234.130283) (xy 362.078014 -234.078988) (xy 362.094062 -234.029595)
			(xy 362.11764 -233.983321) (xy 362.148166 -233.941305) (xy 362.184889 -233.904582) (xy 362.226905 -233.874056)
			(xy 362.273179 -233.850478) (xy 362.322572 -233.83443) (xy 362.373867 -233.826305) (xy 362.425801 -233.826305)
			(xy 362.477096 -233.83443) (xy 362.526489 -233.850478) (xy 362.572763 -233.874056) (xy 362.614779 -233.904582)
			(xy 362.651502 -233.941305) (xy 362.682028 -233.983321) (xy 362.705606 -234.029595) (xy 362.721654 -234.078988)
			(xy 362.729779 -234.130283) (xy 362.730288 -234.15625) (xy 362.729779 -234.182217) (xy 363.009689 -234.182217)
			(xy 363.009689 -234.130283) (xy 363.017814 -234.078988) (xy 363.033862 -234.029595) (xy 363.05744 -233.983321)
			(xy 363.087966 -233.941305) (xy 363.124689 -233.904582) (xy 363.166705 -233.874056) (xy 363.212979 -233.850478)
			(xy 363.262372 -233.83443) (xy 363.313667 -233.826305) (xy 363.365601 -233.826305) (xy 363.416896 -233.83443)
			(xy 363.466289 -233.850478) (xy 363.512563 -233.874056) (xy 363.554579 -233.904582) (xy 363.591302 -233.941305)
			(xy 363.621828 -233.983321) (xy 363.645406 -234.029595) (xy 363.661454 -234.078988) (xy 363.669579 -234.130283)
			(xy 363.670088 -234.15625) (xy 363.669579 -234.182217) (xy 363.661454 -234.233512) (xy 363.645406 -234.282905)
			(xy 363.621828 -234.329179) (xy 363.591302 -234.371195) (xy 363.554579 -234.407918) (xy 363.512563 -234.438444)
			(xy 363.466289 -234.462022) (xy 363.416896 -234.47807) (xy 363.365601 -234.486195) (xy 363.313667 -234.486195)
			(xy 363.262372 -234.47807) (xy 363.212979 -234.462022) (xy 363.166705 -234.438444) (xy 363.124689 -234.407918)
			(xy 363.087966 -234.371195) (xy 363.05744 -234.329179) (xy 363.033862 -234.282905) (xy 363.017814 -234.233512)
			(xy 363.009689 -234.182217) (xy 362.729779 -234.182217) (xy 362.721654 -234.233512) (xy 362.705606 -234.282905)
			(xy 362.682028 -234.329179) (xy 362.651502 -234.371195) (xy 362.614779 -234.407918) (xy 362.572763 -234.438444)
			(xy 362.526489 -234.462022) (xy 362.477096 -234.47807) (xy 362.425801 -234.486195) (xy 362.373867 -234.486195)
			(xy 362.322572 -234.47807) (xy 362.273179 -234.462022) (xy 362.226905 -234.438444) (xy 362.184889 -234.407918)
			(xy 362.148166 -234.371195) (xy 362.11764 -234.329179) (xy 362.094062 -234.282905) (xy 362.078014 -234.233512)
			(xy 362.069889 -234.182217) (xy 361.789979 -234.182217) (xy 361.781854 -234.233512) (xy 361.765806 -234.282905)
			(xy 361.742228 -234.329179) (xy 361.711702 -234.371195) (xy 361.674979 -234.407918) (xy 361.632963 -234.438444)
			(xy 361.586689 -234.462022) (xy 361.537296 -234.47807) (xy 361.486001 -234.486195) (xy 361.434067 -234.486195)
			(xy 361.382772 -234.47807) (xy 361.333379 -234.462022) (xy 361.287105 -234.438444) (xy 361.245089 -234.407918)
			(xy 361.208366 -234.371195) (xy 361.17784 -234.329179) (xy 361.154262 -234.282905) (xy 361.138214 -234.233512)
			(xy 361.130089 -234.182217) (xy 360.850179 -234.182217) (xy 360.842054 -234.233512) (xy 360.826006 -234.282905)
			(xy 360.802428 -234.329179) (xy 360.771902 -234.371195) (xy 360.735179 -234.407918) (xy 360.693163 -234.438444)
			(xy 360.646889 -234.462022) (xy 360.597496 -234.47807) (xy 360.546201 -234.486195) (xy 360.494267 -234.486195)
			(xy 360.442972 -234.47807) (xy 360.393579 -234.462022) (xy 360.347305 -234.438444) (xy 360.305289 -234.407918)
			(xy 360.268566 -234.371195) (xy 360.23804 -234.329179) (xy 360.214462 -234.282905) (xy 360.198414 -234.233512)
			(xy 360.190289 -234.182217) (xy 359.910379 -234.182217) (xy 359.902254 -234.233512) (xy 359.886206 -234.282905)
			(xy 359.862628 -234.329179) (xy 359.832102 -234.371195) (xy 359.795379 -234.407918) (xy 359.753363 -234.438444)
			(xy 359.707089 -234.462022) (xy 359.657696 -234.47807) (xy 359.606401 -234.486195) (xy 359.554467 -234.486195)
			(xy 359.503172 -234.47807) (xy 359.453779 -234.462022) (xy 359.407505 -234.438444) (xy 359.365489 -234.407918)
			(xy 359.328766 -234.371195) (xy 359.29824 -234.329179) (xy 359.274662 -234.282905) (xy 359.258614 -234.233512)
			(xy 359.250489 -234.182217) (xy 358.970579 -234.182217) (xy 358.962454 -234.233512) (xy 358.946406 -234.282905)
			(xy 358.922828 -234.329179) (xy 358.892302 -234.371195) (xy 358.855579 -234.407918) (xy 358.813563 -234.438444)
			(xy 358.767289 -234.462022) (xy 358.717896 -234.47807) (xy 358.666601 -234.486195) (xy 358.614667 -234.486195)
			(xy 358.563372 -234.47807) (xy 358.513979 -234.462022) (xy 358.467705 -234.438444) (xy 358.425689 -234.407918)
			(xy 358.388966 -234.371195) (xy 358.35844 -234.329179) (xy 358.334862 -234.282905) (xy 358.318814 -234.233512)
			(xy 358.310689 -234.182217) (xy 358.030779 -234.182217) (xy 358.022654 -234.233512) (xy 358.006606 -234.282905)
			(xy 357.983028 -234.329179) (xy 357.952502 -234.371195) (xy 357.915779 -234.407918) (xy 357.873763 -234.438444)
			(xy 357.827489 -234.462022) (xy 357.778096 -234.47807) (xy 357.726801 -234.486195) (xy 357.674867 -234.486195)
			(xy 357.623572 -234.47807) (xy 357.574179 -234.462022) (xy 357.527905 -234.438444) (xy 357.485889 -234.407918)
			(xy 357.449166 -234.371195) (xy 357.41864 -234.329179) (xy 357.395062 -234.282905) (xy 357.379014 -234.233512)
			(xy 357.370889 -234.182217) (xy 357.090979 -234.182217) (xy 357.082854 -234.233512) (xy 357.066806 -234.282905)
			(xy 357.043228 -234.329179) (xy 357.012702 -234.371195) (xy 356.975979 -234.407918) (xy 356.933963 -234.438444)
			(xy 356.887689 -234.462022) (xy 356.838296 -234.47807) (xy 356.787001 -234.486195) (xy 356.735067 -234.486195)
			(xy 356.683772 -234.47807) (xy 356.634379 -234.462022) (xy 356.588105 -234.438444) (xy 356.546089 -234.407918)
			(xy 356.509366 -234.371195) (xy 356.47884 -234.329179) (xy 356.455262 -234.282905) (xy 356.439214 -234.233512)
			(xy 356.431089 -234.182217) (xy 356.151179 -234.182217) (xy 356.143054 -234.233512) (xy 356.127006 -234.282905)
			(xy 356.103428 -234.329179) (xy 356.072902 -234.371195) (xy 356.036179 -234.407918) (xy 355.994163 -234.438444)
			(xy 355.947889 -234.462022) (xy 355.898496 -234.47807) (xy 355.847201 -234.486195) (xy 355.795267 -234.486195)
			(xy 355.743972 -234.47807) (xy 355.694579 -234.462022) (xy 355.648305 -234.438444) (xy 355.606289 -234.407918)
			(xy 355.569566 -234.371195) (xy 355.53904 -234.329179) (xy 355.515462 -234.282905) (xy 355.499414 -234.233512)
			(xy 355.491289 -234.182217) (xy 355.211379 -234.182217) (xy 355.203254 -234.233512) (xy 355.187206 -234.282905)
			(xy 355.163628 -234.329179) (xy 355.133102 -234.371195) (xy 355.096379 -234.407918) (xy 355.054363 -234.438444)
			(xy 355.008089 -234.462022) (xy 354.958696 -234.47807) (xy 354.907401 -234.486195) (xy 354.855467 -234.486195)
			(xy 354.804172 -234.47807) (xy 354.754779 -234.462022) (xy 354.708505 -234.438444) (xy 354.666489 -234.407918)
			(xy 354.629766 -234.371195) (xy 354.59924 -234.329179) (xy 354.575662 -234.282905) (xy 354.559614 -234.233512)
			(xy 354.551489 -234.182217) (xy 354.296207 -234.182217) (xy 354.294175 -234.209339) (xy 354.282318 -234.261291)
			(xy 354.262851 -234.310896) (xy 354.236209 -234.357045) (xy 354.202986 -234.398708) (xy 354.163925 -234.434955)
			(xy 354.119898 -234.464976) (xy 354.071889 -234.4881) (xy 354.02097 -234.503811) (xy 353.968278 -234.511758)
			(xy 353.941634 -234.512358) (xy 353.909884 -234.511088) (xy 353.906074 -234.510834) (xy 353.896686 -234.511165)
			(xy 353.879185 -234.517947) (xy 353.872038 -234.524042) (xy 353.817174 -234.573826) (xy 353.813872 -234.577128)
			(xy 353.808517 -234.583521) (xy 353.801906 -234.598819) (xy 353.800918 -234.6071) (xy 353.800918 -234.925616)
			(xy 353.80168 -234.929934) (xy 353.802188 -234.931712) (xy 353.805759 -234.949789) (xy 353.809574 -234.986439)
			(xy 353.809808 -235.004864) (xy 353.809808 -235.006388) (xy 353.809553 -235.024811) (xy 353.805736 -235.06146)
			(xy 353.802188 -235.07954) (xy 353.80168 -235.081318) (xy 353.800918 -235.085636) (xy 353.800918 -235.297277)
			(xy 354.047553 -235.297277) (xy 354.047553 -235.245343) (xy 354.055678 -235.194048) (xy 354.071726 -235.144655)
			(xy 354.095304 -235.098381) (xy 354.12583 -235.056365) (xy 354.162553 -235.019642) (xy 354.204569 -234.989116)
			(xy 354.250843 -234.965538) (xy 354.300236 -234.94949) (xy 354.351531 -234.941365) (xy 354.403465 -234.941365)
			(xy 354.45476 -234.94949) (xy 354.504153 -234.965538) (xy 354.550427 -234.989116) (xy 354.559948 -234.996033)
			(xy 356.900735 -234.996033) (xy 356.900735 -234.944099) (xy 356.90886 -234.892804) (xy 356.924908 -234.843411)
			(xy 356.948486 -234.797137) (xy 356.979012 -234.755121) (xy 357.015735 -234.718398) (xy 357.057751 -234.687872)
			(xy 357.104025 -234.664294) (xy 357.153418 -234.648246) (xy 357.204713 -234.640121) (xy 357.256647 -234.640121)
			(xy 357.307942 -234.648246) (xy 357.357335 -234.664294) (xy 357.403609 -234.687872) (xy 357.445625 -234.718398)
			(xy 357.482348 -234.755121) (xy 357.512874 -234.797137) (xy 357.536452 -234.843411) (xy 357.5525 -234.892804)
			(xy 357.560625 -234.944099) (xy 357.561134 -234.970066) (xy 357.560625 -234.996033) (xy 357.840789 -234.996033)
			(xy 357.840789 -234.944099) (xy 357.848914 -234.892804) (xy 357.864962 -234.843411) (xy 357.88854 -234.797137)
			(xy 357.919066 -234.755121) (xy 357.955789 -234.718398) (xy 357.997805 -234.687872) (xy 358.044079 -234.664294)
			(xy 358.093472 -234.648246) (xy 358.144767 -234.640121) (xy 358.196701 -234.640121) (xy 358.247996 -234.648246)
			(xy 358.297389 -234.664294) (xy 358.343663 -234.687872) (xy 358.385679 -234.718398) (xy 358.422402 -234.755121)
			(xy 358.452928 -234.797137) (xy 358.476506 -234.843411) (xy 358.492554 -234.892804) (xy 358.500679 -234.944099)
			(xy 358.501188 -234.970066) (xy 358.500679 -234.996033) (xy 358.780335 -234.996033) (xy 358.780335 -234.944099)
			(xy 358.78846 -234.892804) (xy 358.804508 -234.843411) (xy 358.828086 -234.797137) (xy 358.858612 -234.755121)
			(xy 358.895335 -234.718398) (xy 358.937351 -234.687872) (xy 358.983625 -234.664294) (xy 359.033018 -234.648246)
			(xy 359.084313 -234.640121) (xy 359.136247 -234.640121) (xy 359.187542 -234.648246) (xy 359.236935 -234.664294)
			(xy 359.283209 -234.687872) (xy 359.325225 -234.718398) (xy 359.361948 -234.755121) (xy 359.392474 -234.797137)
			(xy 359.416052 -234.843411) (xy 359.4321 -234.892804) (xy 359.440225 -234.944099) (xy 359.440734 -234.970066)
			(xy 359.440225 -234.996033) (xy 359.720135 -234.996033) (xy 359.720135 -234.944099) (xy 359.72826 -234.892804)
			(xy 359.744308 -234.843411) (xy 359.767886 -234.797137) (xy 359.798412 -234.755121) (xy 359.835135 -234.718398)
			(xy 359.877151 -234.687872) (xy 359.923425 -234.664294) (xy 359.972818 -234.648246) (xy 360.024113 -234.640121)
			(xy 360.076047 -234.640121) (xy 360.127342 -234.648246) (xy 360.176735 -234.664294) (xy 360.223009 -234.687872)
			(xy 360.265025 -234.718398) (xy 360.301748 -234.755121) (xy 360.332274 -234.797137) (xy 360.355852 -234.843411)
			(xy 360.3719 -234.892804) (xy 360.380025 -234.944099) (xy 360.380534 -234.970066) (xy 360.380025 -234.996033)
			(xy 360.659935 -234.996033) (xy 360.659935 -234.944099) (xy 360.66806 -234.892804) (xy 360.684108 -234.843411)
			(xy 360.707686 -234.797137) (xy 360.738212 -234.755121) (xy 360.774935 -234.718398) (xy 360.816951 -234.687872)
			(xy 360.863225 -234.664294) (xy 360.912618 -234.648246) (xy 360.963913 -234.640121) (xy 361.015847 -234.640121)
			(xy 361.067142 -234.648246) (xy 361.116535 -234.664294) (xy 361.162809 -234.687872) (xy 361.204825 -234.718398)
			(xy 361.241548 -234.755121) (xy 361.272074 -234.797137) (xy 361.295652 -234.843411) (xy 361.3117 -234.892804)
			(xy 361.319825 -234.944099) (xy 361.320334 -234.970066) (xy 361.319825 -234.996033) (xy 361.599989 -234.996033)
			(xy 361.599989 -234.944099) (xy 361.608114 -234.892804) (xy 361.624162 -234.843411) (xy 361.64774 -234.797137)
			(xy 361.678266 -234.755121) (xy 361.714989 -234.718398) (xy 361.757005 -234.687872) (xy 361.803279 -234.664294)
			(xy 361.852672 -234.648246) (xy 361.903967 -234.640121) (xy 361.955901 -234.640121) (xy 362.007196 -234.648246)
			(xy 362.056589 -234.664294) (xy 362.102863 -234.687872) (xy 362.144879 -234.718398) (xy 362.181602 -234.755121)
			(xy 362.212128 -234.797137) (xy 362.235706 -234.843411) (xy 362.251754 -234.892804) (xy 362.259879 -234.944099)
			(xy 362.260388 -234.970066) (xy 362.259879 -234.996033) (xy 362.251754 -235.047328) (xy 362.235706 -235.096721)
			(xy 362.212128 -235.142995) (xy 362.181602 -235.185011) (xy 362.144879 -235.221734) (xy 362.102863 -235.25226)
			(xy 362.056589 -235.275838) (xy 362.007196 -235.291886) (xy 361.955901 -235.300011) (xy 361.903967 -235.300011)
			(xy 361.852672 -235.291886) (xy 361.803279 -235.275838) (xy 361.757005 -235.25226) (xy 361.714989 -235.221734)
			(xy 361.678266 -235.185011) (xy 361.64774 -235.142995) (xy 361.624162 -235.096721) (xy 361.608114 -235.047328)
			(xy 361.599989 -234.996033) (xy 361.319825 -234.996033) (xy 361.3117 -235.047328) (xy 361.295652 -235.096721)
			(xy 361.272074 -235.142995) (xy 361.241548 -235.185011) (xy 361.204825 -235.221734) (xy 361.162809 -235.25226)
			(xy 361.116535 -235.275838) (xy 361.067142 -235.291886) (xy 361.015847 -235.300011) (xy 360.963913 -235.300011)
			(xy 360.912618 -235.291886) (xy 360.863225 -235.275838) (xy 360.816951 -235.25226) (xy 360.774935 -235.221734)
			(xy 360.738212 -235.185011) (xy 360.707686 -235.142995) (xy 360.684108 -235.096721) (xy 360.66806 -235.047328)
			(xy 360.659935 -234.996033) (xy 360.380025 -234.996033) (xy 360.3719 -235.047328) (xy 360.355852 -235.096721)
			(xy 360.332274 -235.142995) (xy 360.301748 -235.185011) (xy 360.265025 -235.221734) (xy 360.223009 -235.25226)
			(xy 360.176735 -235.275838) (xy 360.127342 -235.291886) (xy 360.076047 -235.300011) (xy 360.024113 -235.300011)
			(xy 359.972818 -235.291886) (xy 359.923425 -235.275838) (xy 359.877151 -235.25226) (xy 359.835135 -235.221734)
			(xy 359.798412 -235.185011) (xy 359.767886 -235.142995) (xy 359.744308 -235.096721) (xy 359.72826 -235.047328)
			(xy 359.720135 -234.996033) (xy 359.440225 -234.996033) (xy 359.4321 -235.047328) (xy 359.416052 -235.096721)
			(xy 359.392474 -235.142995) (xy 359.361948 -235.185011) (xy 359.325225 -235.221734) (xy 359.283209 -235.25226)
			(xy 359.236935 -235.275838) (xy 359.187542 -235.291886) (xy 359.136247 -235.300011) (xy 359.084313 -235.300011)
			(xy 359.033018 -235.291886) (xy 358.983625 -235.275838) (xy 358.937351 -235.25226) (xy 358.895335 -235.221734)
			(xy 358.858612 -235.185011) (xy 358.828086 -235.142995) (xy 358.804508 -235.096721) (xy 358.78846 -235.047328)
			(xy 358.780335 -234.996033) (xy 358.500679 -234.996033) (xy 358.492554 -235.047328) (xy 358.476506 -235.096721)
			(xy 358.452928 -235.142995) (xy 358.422402 -235.185011) (xy 358.385679 -235.221734) (xy 358.343663 -235.25226)
			(xy 358.297389 -235.275838) (xy 358.247996 -235.291886) (xy 358.196701 -235.300011) (xy 358.144767 -235.300011)
			(xy 358.093472 -235.291886) (xy 358.044079 -235.275838) (xy 357.997805 -235.25226) (xy 357.955789 -235.221734)
			(xy 357.919066 -235.185011) (xy 357.88854 -235.142995) (xy 357.864962 -235.096721) (xy 357.848914 -235.047328)
			(xy 357.840789 -234.996033) (xy 357.560625 -234.996033) (xy 357.5525 -235.047328) (xy 357.536452 -235.096721)
			(xy 357.512874 -235.142995) (xy 357.482348 -235.185011) (xy 357.445625 -235.221734) (xy 357.403609 -235.25226)
			(xy 357.357335 -235.275838) (xy 357.307942 -235.291886) (xy 357.256647 -235.300011) (xy 357.204713 -235.300011)
			(xy 357.153418 -235.291886) (xy 357.104025 -235.275838) (xy 357.057751 -235.25226) (xy 357.015735 -235.221734)
			(xy 356.979012 -235.185011) (xy 356.948486 -235.142995) (xy 356.924908 -235.096721) (xy 356.90886 -235.047328)
			(xy 356.900735 -234.996033) (xy 354.559948 -234.996033) (xy 354.592443 -235.019642) (xy 354.629166 -235.056365)
			(xy 354.659692 -235.098381) (xy 354.68327 -235.144655) (xy 354.699318 -235.194048) (xy 354.707443 -235.245343)
			(xy 354.707952 -235.27131) (xy 354.707443 -235.297277) (xy 354.699318 -235.348572) (xy 354.68327 -235.397965)
			(xy 354.659692 -235.444239) (xy 354.629166 -235.486255) (xy 354.618051 -235.49737) (xy 355.022658 -235.49737)
			(xy 355.023128 -235.471401) (xy 355.031257 -235.420104) (xy 355.04731 -235.37071) (xy 355.070893 -235.324435)
			(xy 355.101424 -235.282419) (xy 355.138151 -235.245696) (xy 355.180171 -235.215171) (xy 355.226449 -235.191594)
			(xy 355.275845 -235.175547) (xy 355.327143 -235.167424) (xy 355.353112 -235.166916) (xy 355.38041 -235.167456)
			(xy 355.434263 -235.176439) (xy 355.485904 -235.194158) (xy 355.533928 -235.22013) (xy 355.577024 -235.253648)
			(xy 355.595936 -235.273342) (xy 355.605769 -235.283322) (xy 355.629653 -235.297948) (xy 355.656609 -235.305547)
			(xy 355.684615 -235.305547) (xy 355.711571 -235.297948) (xy 355.735455 -235.283322) (xy 355.745288 -235.273342)
			(xy 355.764185 -235.253635) (xy 355.807289 -235.220127) (xy 355.855317 -235.194165) (xy 355.906961 -235.176454)
			(xy 355.960814 -235.167477) (xy 355.988112 -235.166916) (xy 356.014078 -235.167444) (xy 356.065371 -235.175569)
			(xy 356.114761 -235.191618) (xy 356.161033 -235.215194) (xy 356.203047 -235.245719) (xy 356.23977 -235.282439)
			(xy 356.270296 -235.324452) (xy 356.293875 -235.370723) (xy 356.309927 -235.420112) (xy 356.318055 -235.471404)
			(xy 356.318566 -235.49737) (xy 356.318069 -235.523354) (xy 356.309921 -235.574679) (xy 356.293839 -235.624096)
			(xy 356.270217 -235.670385) (xy 356.25532 -235.69168) (xy 356.246688 -235.704379) (xy 356.236825 -235.733445)
			(xy 356.236032 -235.76413) (xy 356.24438 -235.793667) (xy 356.254907 -235.809849) (xy 357.370889 -235.809849)
			(xy 357.370889 -235.757915) (xy 357.379014 -235.70662) (xy 357.395062 -235.657227) (xy 357.41864 -235.610953)
			(xy 357.449166 -235.568937) (xy 357.485889 -235.532214) (xy 357.527905 -235.501688) (xy 357.574179 -235.47811)
			(xy 357.623572 -235.462062) (xy 357.674867 -235.453937) (xy 357.726801 -235.453937) (xy 357.778096 -235.462062)
			(xy 357.827489 -235.47811) (xy 357.873763 -235.501688) (xy 357.915779 -235.532214) (xy 357.952502 -235.568937)
			(xy 357.983028 -235.610953) (xy 358.006606 -235.657227) (xy 358.022654 -235.70662) (xy 358.030779 -235.757915)
			(xy 358.031288 -235.783882) (xy 358.030779 -235.809849) (xy 358.310689 -235.809849) (xy 358.310689 -235.757915)
			(xy 358.318814 -235.70662) (xy 358.334862 -235.657227) (xy 358.35844 -235.610953) (xy 358.388966 -235.568937)
			(xy 358.425689 -235.532214) (xy 358.467705 -235.501688) (xy 358.513979 -235.47811) (xy 358.563372 -235.462062)
			(xy 358.614667 -235.453937) (xy 358.666601 -235.453937) (xy 358.717896 -235.462062) (xy 358.767289 -235.47811)
			(xy 358.813563 -235.501688) (xy 358.855579 -235.532214) (xy 358.892302 -235.568937) (xy 358.922828 -235.610953)
			(xy 358.946406 -235.657227) (xy 358.962454 -235.70662) (xy 358.970579 -235.757915) (xy 358.971088 -235.783882)
			(xy 358.970579 -235.809849) (xy 359.250489 -235.809849) (xy 359.250489 -235.757915) (xy 359.258614 -235.70662)
			(xy 359.274662 -235.657227) (xy 359.29824 -235.610953) (xy 359.328766 -235.568937) (xy 359.365489 -235.532214)
			(xy 359.407505 -235.501688) (xy 359.453779 -235.47811) (xy 359.503172 -235.462062) (xy 359.554467 -235.453937)
			(xy 359.606401 -235.453937) (xy 359.657696 -235.462062) (xy 359.707089 -235.47811) (xy 359.753363 -235.501688)
			(xy 359.795379 -235.532214) (xy 359.832102 -235.568937) (xy 359.862628 -235.610953) (xy 359.886206 -235.657227)
			(xy 359.902254 -235.70662) (xy 359.910379 -235.757915) (xy 359.910888 -235.783882) (xy 359.910379 -235.809849)
			(xy 360.190289 -235.809849) (xy 360.190289 -235.757915) (xy 360.198414 -235.70662) (xy 360.214462 -235.657227)
			(xy 360.23804 -235.610953) (xy 360.268566 -235.568937) (xy 360.305289 -235.532214) (xy 360.347305 -235.501688)
			(xy 360.393579 -235.47811) (xy 360.442972 -235.462062) (xy 360.494267 -235.453937) (xy 360.546201 -235.453937)
			(xy 360.597496 -235.462062) (xy 360.646889 -235.47811) (xy 360.693163 -235.501688) (xy 360.735179 -235.532214)
			(xy 360.771902 -235.568937) (xy 360.802428 -235.610953) (xy 360.826006 -235.657227) (xy 360.842054 -235.70662)
			(xy 360.850179 -235.757915) (xy 360.850688 -235.783882) (xy 360.850179 -235.809849) (xy 361.130089 -235.809849)
			(xy 361.130089 -235.757915) (xy 361.138214 -235.70662) (xy 361.154262 -235.657227) (xy 361.17784 -235.610953)
			(xy 361.208366 -235.568937) (xy 361.245089 -235.532214) (xy 361.287105 -235.501688) (xy 361.333379 -235.47811)
			(xy 361.382772 -235.462062) (xy 361.434067 -235.453937) (xy 361.486001 -235.453937) (xy 361.537296 -235.462062)
			(xy 361.586689 -235.47811) (xy 361.632963 -235.501688) (xy 361.674979 -235.532214) (xy 361.711702 -235.568937)
			(xy 361.742228 -235.610953) (xy 361.765806 -235.657227) (xy 361.781854 -235.70662) (xy 361.789979 -235.757915)
			(xy 361.790488 -235.783882) (xy 361.789979 -235.809849) (xy 362.069889 -235.809849) (xy 362.069889 -235.757915)
			(xy 362.078014 -235.70662) (xy 362.094062 -235.657227) (xy 362.11764 -235.610953) (xy 362.148166 -235.568937)
			(xy 362.184889 -235.532214) (xy 362.226905 -235.501688) (xy 362.273179 -235.47811) (xy 362.322572 -235.462062)
			(xy 362.373867 -235.453937) (xy 362.425801 -235.453937) (xy 362.477096 -235.462062) (xy 362.526489 -235.47811)
			(xy 362.572763 -235.501688) (xy 362.614779 -235.532214) (xy 362.651502 -235.568937) (xy 362.682028 -235.610953)
			(xy 362.705606 -235.657227) (xy 362.721654 -235.70662) (xy 362.729779 -235.757915) (xy 362.730288 -235.783882)
			(xy 362.729779 -235.809849) (xy 362.721654 -235.861144) (xy 362.705606 -235.910537) (xy 362.682028 -235.956811)
			(xy 362.651502 -235.998827) (xy 362.614779 -236.03555) (xy 362.572763 -236.066076) (xy 362.526489 -236.089654)
			(xy 362.477096 -236.105702) (xy 362.425801 -236.113827) (xy 362.373867 -236.113827) (xy 362.322572 -236.105702)
			(xy 362.273179 -236.089654) (xy 362.226905 -236.066076) (xy 362.184889 -236.03555) (xy 362.148166 -235.998827)
			(xy 362.11764 -235.956811) (xy 362.094062 -235.910537) (xy 362.078014 -235.861144) (xy 362.069889 -235.809849)
			(xy 361.789979 -235.809849) (xy 361.781854 -235.861144) (xy 361.765806 -235.910537) (xy 361.742228 -235.956811)
			(xy 361.711702 -235.998827) (xy 361.674979 -236.03555) (xy 361.632963 -236.066076) (xy 361.586689 -236.089654)
			(xy 361.537296 -236.105702) (xy 361.486001 -236.113827) (xy 361.434067 -236.113827) (xy 361.382772 -236.105702)
			(xy 361.333379 -236.089654) (xy 361.287105 -236.066076) (xy 361.245089 -236.03555) (xy 361.208366 -235.998827)
			(xy 361.17784 -235.956811) (xy 361.154262 -235.910537) (xy 361.138214 -235.861144) (xy 361.130089 -235.809849)
			(xy 360.850179 -235.809849) (xy 360.842054 -235.861144) (xy 360.826006 -235.910537) (xy 360.802428 -235.956811)
			(xy 360.771902 -235.998827) (xy 360.735179 -236.03555) (xy 360.693163 -236.066076) (xy 360.646889 -236.089654)
			(xy 360.597496 -236.105702) (xy 360.546201 -236.113827) (xy 360.494267 -236.113827) (xy 360.442972 -236.105702)
			(xy 360.393579 -236.089654) (xy 360.347305 -236.066076) (xy 360.305289 -236.03555) (xy 360.268566 -235.998827)
			(xy 360.23804 -235.956811) (xy 360.214462 -235.910537) (xy 360.198414 -235.861144) (xy 360.190289 -235.809849)
			(xy 359.910379 -235.809849) (xy 359.902254 -235.861144) (xy 359.886206 -235.910537) (xy 359.862628 -235.956811)
			(xy 359.832102 -235.998827) (xy 359.795379 -236.03555) (xy 359.753363 -236.066076) (xy 359.707089 -236.089654)
			(xy 359.657696 -236.105702) (xy 359.606401 -236.113827) (xy 359.554467 -236.113827) (xy 359.503172 -236.105702)
			(xy 359.453779 -236.089654) (xy 359.407505 -236.066076) (xy 359.365489 -236.03555) (xy 359.328766 -235.998827)
			(xy 359.29824 -235.956811) (xy 359.274662 -235.910537) (xy 359.258614 -235.861144) (xy 359.250489 -235.809849)
			(xy 358.970579 -235.809849) (xy 358.962454 -235.861144) (xy 358.946406 -235.910537) (xy 358.922828 -235.956811)
			(xy 358.892302 -235.998827) (xy 358.855579 -236.03555) (xy 358.813563 -236.066076) (xy 358.767289 -236.089654)
			(xy 358.717896 -236.105702) (xy 358.666601 -236.113827) (xy 358.614667 -236.113827) (xy 358.563372 -236.105702)
			(xy 358.513979 -236.089654) (xy 358.467705 -236.066076) (xy 358.425689 -236.03555) (xy 358.388966 -235.998827)
			(xy 358.35844 -235.956811) (xy 358.334862 -235.910537) (xy 358.318814 -235.861144) (xy 358.310689 -235.809849)
			(xy 358.030779 -235.809849) (xy 358.022654 -235.861144) (xy 358.006606 -235.910537) (xy 357.983028 -235.956811)
			(xy 357.952502 -235.998827) (xy 357.915779 -236.03555) (xy 357.873763 -236.066076) (xy 357.827489 -236.089654)
			(xy 357.778096 -236.105702) (xy 357.726801 -236.113827) (xy 357.674867 -236.113827) (xy 357.623572 -236.105702)
			(xy 357.574179 -236.089654) (xy 357.527905 -236.066076) (xy 357.485889 -236.03555) (xy 357.449166 -235.998827)
			(xy 357.41864 -235.956811) (xy 357.395062 -235.910537) (xy 357.379014 -235.861144) (xy 357.370889 -235.809849)
			(xy 356.254907 -235.809849) (xy 356.261118 -235.819396) (xy 356.272592 -235.829602) (xy 356.290919 -235.845393)
			(xy 356.323238 -235.881387) (xy 356.349965 -235.921708) (xy 356.370528 -235.965495) (xy 356.384489 -236.011812)
			(xy 356.391547 -236.059669) (xy 356.391972 -236.083856) (xy 356.391431 -236.109823) (xy 356.383313 -236.161119)
			(xy 356.36727 -236.210513) (xy 356.343697 -236.25679) (xy 356.313175 -236.298809) (xy 356.276456 -236.335535)
			(xy 356.234443 -236.366065) (xy 356.188171 -236.389646) (xy 356.138779 -236.405698) (xy 356.087485 -236.413826)
			(xy 356.061518 -236.41431) (xy 356.034219 -236.413774) (xy 355.980365 -236.404793) (xy 355.928723 -236.387075)
			(xy 355.8807 -236.361101) (xy 355.837604 -236.32758) (xy 355.818694 -236.307884) (xy 355.808861 -236.297904)
			(xy 355.784977 -236.283278) (xy 355.758021 -236.275679) (xy 355.730015 -236.275679) (xy 355.703059 -236.283278)
			(xy 355.679175 -236.297904) (xy 355.669342 -236.307884) (xy 355.650416 -236.327563) (xy 355.607322 -236.361077)
			(xy 355.559301 -236.387047) (xy 355.507663 -236.404764) (xy 355.453814 -236.413746) (xy 355.426518 -236.41431)
			(xy 355.400547 -236.413854) (xy 355.349244 -236.405731) (xy 355.299844 -236.389681) (xy 355.253564 -236.366099)
			(xy 355.211542 -236.335568) (xy 355.174815 -236.298838) (xy 355.144287 -236.256814) (xy 355.120709 -236.210532)
			(xy 355.104663 -236.16113) (xy 355.096544 -236.109827) (xy 355.096064 -236.083856) (xy 355.096569 -236.057872)
			(xy 355.104713 -236.006547) (xy 355.120793 -235.95713) (xy 355.144413 -235.910841) (xy 355.15931 -235.889546)
			(xy 355.167908 -235.876827) (xy 355.177771 -235.847769) (xy 355.17857 -235.817092) (xy 355.170231 -235.78756)
			(xy 355.153506 -235.761831) (xy 355.142038 -235.751624) (xy 355.123682 -235.735865) (xy 355.091363 -235.699865)
			(xy 355.064639 -235.659538) (xy 355.044081 -235.615745) (xy 355.030127 -235.569422) (xy 355.023078 -235.521559)
			(xy 355.022658 -235.49737) (xy 354.618051 -235.49737) (xy 354.592443 -235.522978) (xy 354.550427 -235.553504)
			(xy 354.504153 -235.577082) (xy 354.45476 -235.59313) (xy 354.403465 -235.601255) (xy 354.351531 -235.601255)
			(xy 354.300236 -235.59313) (xy 354.250843 -235.577082) (xy 354.204569 -235.553504) (xy 354.162553 -235.522978)
			(xy 354.12583 -235.486255) (xy 354.095304 -235.444239) (xy 354.071726 -235.397965) (xy 354.055678 -235.348572)
			(xy 354.047553 -235.297277) (xy 353.800918 -235.297277) (xy 353.800918 -235.763308) (xy 353.800484 -235.773192)
			(xy 353.793042 -235.791501) (xy 353.78644 -235.798868) (xy 353.209606 -236.375702) (xy 353.209098 -236.376464)
			(xy 353.207066 -236.378242) (xy 353.205796 -236.379258) (xy 353.202494 -236.382814) (xy 353.184206 -236.390434)
			(xy 351.202244 -236.390434) (xy 351.192889 -236.390878) (xy 351.175494 -236.397784) (xy 351.161784 -236.410524)
			(xy 351.153623 -236.427367) (xy 351.15246 -236.436662) (xy 351.15246 -236.439202) (xy 351.150966 -236.464489)
			(xy 351.14125 -236.514203) (xy 351.124066 -236.561853) (xy 351.099818 -236.606325) (xy 351.08638 -236.623919)
			(xy 356.900735 -236.623919) (xy 356.900735 -236.571985) (xy 356.90886 -236.52069) (xy 356.924908 -236.471297)
			(xy 356.948486 -236.425023) (xy 356.979012 -236.383007) (xy 357.015735 -236.346284) (xy 357.057751 -236.315758)
			(xy 357.104025 -236.29218) (xy 357.153418 -236.276132) (xy 357.204713 -236.268007) (xy 357.256647 -236.268007)
			(xy 357.307942 -236.276132) (xy 357.357335 -236.29218) (xy 357.403609 -236.315758) (xy 357.445625 -236.346284)
			(xy 357.482348 -236.383007) (xy 357.512874 -236.425023) (xy 357.536452 -236.471297) (xy 357.5525 -236.52069)
			(xy 357.560625 -236.571985) (xy 357.561134 -236.597952) (xy 357.560625 -236.623919) (xy 357.840789 -236.623919)
			(xy 357.840789 -236.571985) (xy 357.848914 -236.52069) (xy 357.864962 -236.471297) (xy 357.88854 -236.425023)
			(xy 357.919066 -236.383007) (xy 357.955789 -236.346284) (xy 357.997805 -236.315758) (xy 358.044079 -236.29218)
			(xy 358.093472 -236.276132) (xy 358.144767 -236.268007) (xy 358.196701 -236.268007) (xy 358.247996 -236.276132)
			(xy 358.297389 -236.29218) (xy 358.343663 -236.315758) (xy 358.385679 -236.346284) (xy 358.422402 -236.383007)
			(xy 358.452928 -236.425023) (xy 358.476506 -236.471297) (xy 358.492554 -236.52069) (xy 358.500679 -236.571985)
			(xy 358.501188 -236.597952) (xy 358.500679 -236.623919) (xy 358.780335 -236.623919) (xy 358.780335 -236.571985)
			(xy 358.78846 -236.52069) (xy 358.804508 -236.471297) (xy 358.828086 -236.425023) (xy 358.858612 -236.383007)
			(xy 358.895335 -236.346284) (xy 358.937351 -236.315758) (xy 358.983625 -236.29218) (xy 359.033018 -236.276132)
			(xy 359.084313 -236.268007) (xy 359.136247 -236.268007) (xy 359.187542 -236.276132) (xy 359.236935 -236.29218)
			(xy 359.283209 -236.315758) (xy 359.325225 -236.346284) (xy 359.361948 -236.383007) (xy 359.392474 -236.425023)
			(xy 359.416052 -236.471297) (xy 359.4321 -236.52069) (xy 359.440225 -236.571985) (xy 359.440734 -236.597952)
			(xy 359.440225 -236.623919) (xy 359.720135 -236.623919) (xy 359.720135 -236.571985) (xy 359.72826 -236.52069)
			(xy 359.744308 -236.471297) (xy 359.767886 -236.425023) (xy 359.798412 -236.383007) (xy 359.835135 -236.346284)
			(xy 359.877151 -236.315758) (xy 359.923425 -236.29218) (xy 359.972818 -236.276132) (xy 360.024113 -236.268007)
			(xy 360.076047 -236.268007) (xy 360.127342 -236.276132) (xy 360.176735 -236.29218) (xy 360.223009 -236.315758)
			(xy 360.265025 -236.346284) (xy 360.301748 -236.383007) (xy 360.332274 -236.425023) (xy 360.355852 -236.471297)
			(xy 360.3719 -236.52069) (xy 360.380025 -236.571985) (xy 360.380534 -236.597952) (xy 360.380025 -236.623919)
			(xy 360.659935 -236.623919) (xy 360.659935 -236.571985) (xy 360.66806 -236.52069) (xy 360.684108 -236.471297)
			(xy 360.707686 -236.425023) (xy 360.738212 -236.383007) (xy 360.774935 -236.346284) (xy 360.816951 -236.315758)
			(xy 360.863225 -236.29218) (xy 360.912618 -236.276132) (xy 360.963913 -236.268007) (xy 361.015847 -236.268007)
			(xy 361.067142 -236.276132) (xy 361.116535 -236.29218) (xy 361.162809 -236.315758) (xy 361.204825 -236.346284)
			(xy 361.241548 -236.383007) (xy 361.272074 -236.425023) (xy 361.295652 -236.471297) (xy 361.3117 -236.52069)
			(xy 361.319825 -236.571985) (xy 361.320334 -236.597952) (xy 361.319825 -236.623919) (xy 361.599989 -236.623919)
			(xy 361.599989 -236.571985) (xy 361.608114 -236.52069) (xy 361.624162 -236.471297) (xy 361.64774 -236.425023)
			(xy 361.678266 -236.383007) (xy 361.714989 -236.346284) (xy 361.757005 -236.315758) (xy 361.803279 -236.29218)
			(xy 361.852672 -236.276132) (xy 361.903967 -236.268007) (xy 361.955901 -236.268007) (xy 362.007196 -236.276132)
			(xy 362.056589 -236.29218) (xy 362.102863 -236.315758) (xy 362.144879 -236.346284) (xy 362.181602 -236.383007)
			(xy 362.212128 -236.425023) (xy 362.235706 -236.471297) (xy 362.251754 -236.52069) (xy 362.259879 -236.571985)
			(xy 362.260388 -236.597952) (xy 362.259879 -236.623919) (xy 362.251754 -236.675214) (xy 362.235706 -236.724607)
			(xy 362.212128 -236.770881) (xy 362.181602 -236.812897) (xy 362.144879 -236.84962) (xy 362.102863 -236.880146)
			(xy 362.056589 -236.903724) (xy 362.007196 -236.919772) (xy 361.955901 -236.927897) (xy 361.903967 -236.927897)
			(xy 361.852672 -236.919772) (xy 361.803279 -236.903724) (xy 361.757005 -236.880146) (xy 361.714989 -236.84962)
			(xy 361.678266 -236.812897) (xy 361.64774 -236.770881) (xy 361.624162 -236.724607) (xy 361.608114 -236.675214)
			(xy 361.599989 -236.623919) (xy 361.319825 -236.623919) (xy 361.3117 -236.675214) (xy 361.295652 -236.724607)
			(xy 361.272074 -236.770881) (xy 361.241548 -236.812897) (xy 361.204825 -236.84962) (xy 361.162809 -236.880146)
			(xy 361.116535 -236.903724) (xy 361.067142 -236.919772) (xy 361.015847 -236.927897) (xy 360.963913 -236.927897)
			(xy 360.912618 -236.919772) (xy 360.863225 -236.903724) (xy 360.816951 -236.880146) (xy 360.774935 -236.84962)
			(xy 360.738212 -236.812897) (xy 360.707686 -236.770881) (xy 360.684108 -236.724607) (xy 360.66806 -236.675214)
			(xy 360.659935 -236.623919) (xy 360.380025 -236.623919) (xy 360.3719 -236.675214) (xy 360.355852 -236.724607)
			(xy 360.332274 -236.770881) (xy 360.301748 -236.812897) (xy 360.265025 -236.84962) (xy 360.223009 -236.880146)
			(xy 360.176735 -236.903724) (xy 360.127342 -236.919772) (xy 360.076047 -236.927897) (xy 360.024113 -236.927897)
			(xy 359.972818 -236.919772) (xy 359.923425 -236.903724) (xy 359.877151 -236.880146) (xy 359.835135 -236.84962)
			(xy 359.798412 -236.812897) (xy 359.767886 -236.770881) (xy 359.744308 -236.724607) (xy 359.72826 -236.675214)
			(xy 359.720135 -236.623919) (xy 359.440225 -236.623919) (xy 359.4321 -236.675214) (xy 359.416052 -236.724607)
			(xy 359.392474 -236.770881) (xy 359.361948 -236.812897) (xy 359.325225 -236.84962) (xy 359.283209 -236.880146)
			(xy 359.236935 -236.903724) (xy 359.187542 -236.919772) (xy 359.136247 -236.927897) (xy 359.084313 -236.927897)
			(xy 359.033018 -236.919772) (xy 358.983625 -236.903724) (xy 358.937351 -236.880146) (xy 358.895335 -236.84962)
			(xy 358.858612 -236.812897) (xy 358.828086 -236.770881) (xy 358.804508 -236.724607) (xy 358.78846 -236.675214)
			(xy 358.780335 -236.623919) (xy 358.500679 -236.623919) (xy 358.492554 -236.675214) (xy 358.476506 -236.724607)
			(xy 358.452928 -236.770881) (xy 358.422402 -236.812897) (xy 358.385679 -236.84962) (xy 358.343663 -236.880146)
			(xy 358.297389 -236.903724) (xy 358.247996 -236.919772) (xy 358.196701 -236.927897) (xy 358.144767 -236.927897)
			(xy 358.093472 -236.919772) (xy 358.044079 -236.903724) (xy 357.997805 -236.880146) (xy 357.955789 -236.84962)
			(xy 357.919066 -236.812897) (xy 357.88854 -236.770881) (xy 357.864962 -236.724607) (xy 357.848914 -236.675214)
			(xy 357.840789 -236.623919) (xy 357.560625 -236.623919) (xy 357.5525 -236.675214) (xy 357.536452 -236.724607)
			(xy 357.512874 -236.770881) (xy 357.482348 -236.812897) (xy 357.445625 -236.84962) (xy 357.403609 -236.880146)
			(xy 357.357335 -236.903724) (xy 357.307942 -236.919772) (xy 357.256647 -236.927897) (xy 357.204713 -236.927897)
			(xy 357.153418 -236.919772) (xy 357.104025 -236.903724) (xy 357.057751 -236.880146) (xy 357.015735 -236.84962)
			(xy 356.979012 -236.812897) (xy 356.948486 -236.770881) (xy 356.924908 -236.724607) (xy 356.90886 -236.675214)
			(xy 356.900735 -236.623919) (xy 351.08638 -236.623919) (xy 351.069072 -236.64658) (xy 351.032546 -236.681676)
			(xy 350.991097 -236.710792) (xy 350.945692 -236.733247) (xy 350.897394 -236.748515) (xy 350.847333 -236.75624)
			(xy 350.822006 -236.756702) (xy 350.796017 -236.756219) (xy 350.744678 -236.748089) (xy 350.695243 -236.732027)
			(xy 350.648929 -236.708429) (xy 350.606877 -236.677877) (xy 350.570123 -236.641123) (xy 350.539571 -236.599071)
			(xy 350.515973 -236.552757) (xy 350.499911 -236.503322) (xy 350.491781 -236.451983) (xy 350.491298 -236.425994)
			(xy 350.49333 -236.389926) (xy 350.49333 -236.389672) (xy 350.493864 -236.378469) (xy 350.486358 -236.357364)
			(xy 350.478852 -236.349032) (xy 350.376236 -236.246416) (xy 350.279208 -236.149134) (xy 350.272022 -236.142928)
			(xy 350.254402 -236.135889) (xy 350.244918 -236.135418) (xy 350.237044 -236.135926) (xy 350.223475 -236.137859)
			(xy 350.19614 -236.139892) (xy 350.182434 -236.13999) (xy 350.154447 -236.139472) (xy 350.099163 -236.13072)
			(xy 350.045928 -236.113427) (xy 349.996054 -236.088019) (xy 349.95077 -236.05512) (xy 349.91119 -236.015542)
			(xy 349.87829 -235.970259) (xy 349.852879 -235.920387) (xy 349.835583 -235.867153) (xy 349.826829 -235.811869)
			(xy 349.826326 -235.783882) (xy 349.826416 -235.770176) (xy 349.82845 -235.74284) (xy 349.83039 -235.729272)
			(xy 349.830898 -235.721398) (xy 349.830489 -235.711902) (xy 349.823427 -235.694275) (xy 349.817182 -235.687108)
			(xy 349.649288 -235.519468) (xy 349.642607 -235.51215) (xy 349.635139 -235.493812) (xy 349.63481 -235.483908)
			(xy 349.63481 -235.328968) (xy 349.634332 -235.31913) (xy 349.62683 -235.30094) (xy 349.612967 -235.286976)
			(xy 349.604076 -235.28274) (xy 349.601028 -235.281724) (xy 349.577256 -235.272743) (xy 349.532575 -235.24854)
			(xy 349.492119 -235.21779) (xy 349.45684 -235.181216) (xy 349.427567 -235.139679) (xy 349.404989 -235.094155)
			(xy 349.389636 -235.045715) (xy 349.381869 -234.995496) (xy 349.381871 -234.944681) (xy 349.389641 -234.894463)
			(xy 349.404998 -234.846023) (xy 349.427579 -234.800501) (xy 349.456855 -234.758966) (xy 349.492136 -234.722395)
			(xy 349.532594 -234.691648) (xy 349.577277 -234.667448) (xy 349.601028 -234.658408) (xy 349.604076 -234.657392)
			(xy 349.613018 -234.653223) (xy 349.626932 -234.639255) (xy 349.634434 -234.621023) (xy 349.63481 -234.611164)
			(xy 349.63481 -234.472988) (xy 349.634303 -234.463295) (xy 349.626898 -234.445373) (xy 349.613295 -234.431552)
			(xy 349.604584 -234.427268) (xy 349.524828 -234.39247) (xy 349.515669 -234.388897) (xy 349.496028 -234.388516)
			(xy 349.486728 -234.391708) (xy 349.466408 -234.399836) (xy 349.465138 -234.400852) (xy 349.460058 -234.40517)
			(xy 349.441899 -234.42052) (xy 349.402003 -234.446388) (xy 349.358811 -234.466268) (xy 349.313213 -234.479748)
			(xy 349.266154 -234.48655) (xy 349.24238 -234.486958) (xy 349.21639 -234.486447) (xy 349.16505 -234.478313)
			(xy 349.115615 -234.462247) (xy 349.069301 -234.438647) (xy 349.027249 -234.408092) (xy 348.990495 -234.371335)
			(xy 348.959943 -234.329282) (xy 348.936345 -234.282967) (xy 348.920283 -234.23353) (xy 348.912152 -234.18219)
			(xy 348.912152 -234.13021) (xy 348.920283 -234.07887) (xy 348.936345 -234.029433) (xy 348.959943 -233.983118)
			(xy 348.990495 -233.941065) (xy 349.027249 -233.904308) (xy 349.069301 -233.873753) (xy 349.115615 -233.850153)
			(xy 349.16505 -233.834087) (xy 349.21639 -233.825953) (xy 349.24238 -233.825542) (xy 349.266152 -233.82596)
			(xy 349.313203 -233.832781) (xy 349.358793 -233.84627) (xy 349.401981 -233.86615) (xy 349.441876 -233.89201)
			(xy 349.460058 -233.90733) (xy 349.465138 -233.911648) (xy 349.466408 -233.912664) (xy 349.486728 -233.920792)
			(xy 349.496041 -233.92388) (xy 349.515638 -233.923472) (xy 349.524828 -233.92003) (xy 349.604584 -233.885232)
			(xy 349.613316 -233.88098) (xy 349.626927 -233.867152) (xy 349.634319 -233.849212) (xy 349.63481 -233.839512)
			(xy 349.63481 -232.10012) (xy 349.60052 -232.05313) (xy 349.586296 -232.047796) (xy 349.561267 -232.037805)
			(xy 349.514303 -232.011375) (xy 349.471855 -231.978173) (xy 349.434891 -231.938959) (xy 349.404254 -231.894625)
			(xy 349.380642 -231.846183) (xy 349.364594 -231.794737) (xy 349.356477 -231.741462) (xy 349.356474 -231.687572)
			(xy 349.364587 -231.634296) (xy 349.38063 -231.582849) (xy 349.404237 -231.534405) (xy 349.43487 -231.490068)
			(xy 349.47183 -231.45085) (xy 349.514275 -231.417644) (xy 349.561236 -231.391209) (xy 349.586296 -231.3813)
			(xy 349.60052 -231.375966) (xy 349.63481 -231.328976) (xy 349.63481 -231.21747) (xy 349.634317 -231.207768)
			(xy 349.626929 -231.189821) (xy 349.613329 -231.175976) (xy 349.604584 -231.17175) (xy 349.524574 -231.136698)
			(xy 349.515413 -231.133129) (xy 349.49577 -231.132734) (xy 349.486474 -231.135936) (xy 349.46717 -231.143556)
			(xy 349.460312 -231.149398) (xy 349.442151 -231.164744) (xy 349.402254 -231.190605) (xy 349.359061 -231.210477)
			(xy 349.313464 -231.22395) (xy 349.266407 -231.230744) (xy 349.242634 -231.231186) (xy 349.216645 -231.230705)
			(xy 349.165305 -231.222579) (xy 349.11587 -231.206521) (xy 349.069555 -231.182926) (xy 349.027501 -231.152377)
			(xy 348.990745 -231.115624) (xy 348.960191 -231.073574) (xy 348.936592 -231.027262) (xy 348.920529 -230.977828)
			(xy 348.912397 -230.926489) (xy 348.912397 -230.874511) (xy 348.920529 -230.823172) (xy 348.936592 -230.773738)
			(xy 348.960191 -230.727426) (xy 348.990745 -230.685376) (xy 349.027501 -230.648623) (xy 349.069555 -230.618074)
			(xy 349.11587 -230.594479) (xy 349.165305 -230.578421) (xy 349.216645 -230.570295) (xy 349.242634 -230.56977)
			(xy 349.266407 -230.570185) (xy 349.313461 -230.577) (xy 349.359054 -230.590485) (xy 349.402245 -230.610362)
			(xy 349.442144 -230.63622) (xy 349.460312 -230.651558) (xy 349.46717 -230.6574) (xy 349.486474 -230.66502)
			(xy 349.495789 -230.668109) (xy 349.515392 -230.667722) (xy 349.524574 -230.664258) (xy 349.604584 -230.629206)
			(xy 349.613313 -230.624953) (xy 349.626917 -230.611123) (xy 349.6343 -230.593184) (xy 349.63481 -230.583486)
			(xy 349.63481 -230.472234) (xy 349.60052 -230.425244) (xy 349.586296 -230.41991) (xy 349.561279 -230.40991)
			(xy 349.51434 -230.383467) (xy 349.471917 -230.35026) (xy 349.434974 -230.311047) (xy 349.404354 -230.26672)
			(xy 349.380755 -230.218289) (xy 349.364713 -230.166858) (xy 349.356595 -230.113599) (xy 349.356172 -230.086662)
			(xy 349.356625 -230.060886) (xy 349.364053 -230.009872) (xy 349.378763 -229.960463) (xy 349.400448 -229.913693)
			(xy 349.428653 -229.870541) (xy 349.462788 -229.831909) (xy 349.502139 -229.798606) (xy 349.545883 -229.771329)
			(xy 349.593105 -229.750648) (xy 349.642817 -229.736995) (xy 349.668338 -229.733348) (xy 349.682562 -229.73157)
			(xy 349.71228 -229.7303) (xy 349.712788 -229.7303) (xy 349.741269 -229.730882) (xy 349.797499 -229.739987)
			(xy 349.851565 -229.757921) (xy 349.90209 -229.784227) (xy 349.947788 -229.818234) (xy 349.968058 -229.83825)
			(xy 349.971106 -229.841298) (xy 349.977655 -229.846543) (xy 349.993227 -229.852764) (xy 350.001586 -229.85349)
			(xy 350.041464 -229.853998) (xy 350.074738 -229.854252) (xy 350.08462 -229.853813) (xy 350.102924 -229.846367)
			(xy 350.110298 -229.839774) (xy 350.160082 -229.78999) (xy 350.165826 -229.783649) (xy 350.173053 -229.768154)
			(xy 350.174713 -229.751137) (xy 350.173036 -229.742746) (xy 350.147382 -229.656132) (xy 350.10979 -229.621588)
			(xy 350.101408 -229.619556) (xy 350.075672 -229.613036) (xy 350.026343 -229.593412) (xy 349.980473 -229.566683)
			(xy 349.939078 -229.533443) (xy 349.903075 -229.494426) (xy 349.873261 -229.450499) (xy 349.850297 -229.402633)
			(xy 349.834692 -229.351889) (xy 349.826791 -229.299391) (xy 349.826326 -229.272846) (xy 349.826877 -229.244144)
			(xy 349.836097 -229.187484) (xy 349.85429 -229.133038) (xy 349.880983 -229.082216) (xy 349.915485 -229.036337)
			(xy 349.9358 -229.016052) (xy 349.936054 -229.015798) (xy 349.95104 -228.979984) (xy 349.94215 -228.951536)
			(xy 349.924034 -228.924816) (xy 349.891363 -228.869131) (xy 349.876872 -228.840284) (xy 349.858584 -228.820218)
			(xy 349.841312 -228.809296) (xy 349.835379 -228.805899) (xy 349.822236 -228.802156) (xy 349.815404 -228.80193)
			(xy 349.802704 -228.803708) (xy 349.79991 -228.80447) (xy 349.778483 -228.809502) (xy 349.734796 -228.814852)
			(xy 349.712788 -228.815138) (xy 349.71228 -228.815138) (xy 349.684297 -228.814588) (xy 349.629021 -228.80583)
			(xy 349.575794 -228.788534) (xy 349.525929 -228.763126) (xy 349.480651 -228.73023) (xy 349.441077 -228.690656)
			(xy 349.40818 -228.64538) (xy 349.38277 -228.595515) (xy 349.365472 -228.542289) (xy 349.356713 -228.487013)
			(xy 349.356172 -228.45903) (xy 349.356725 -228.430328) (xy 349.365948 -228.373671) (xy 349.384144 -228.319228)
			(xy 349.410841 -228.268411) (xy 349.445347 -228.222536) (xy 349.465646 -228.202236) (xy 349.4659 -228.201982)
			(xy 349.48114 -228.166422) (xy 349.48114 -228.165914) (xy 349.471996 -228.137466) (xy 349.463065 -228.124405)
			(xy 349.446044 -228.097728) (xy 349.43796 -228.084126) (xy 349.429668 -228.069977) (xy 349.414042 -228.041141)
			(xy 349.406718 -228.026468) (xy 349.406718 -228.026214) (xy 349.406464 -228.026214) (xy 349.403588 -228.020717)
			(xy 349.395629 -228.011205) (xy 349.390716 -228.007418) (xy 349.370396 -227.994718) (xy 349.364582 -227.991588)
			(xy 349.351848 -227.988105) (xy 349.34525 -227.98786) (xy 349.332804 -227.989384) (xy 349.311154 -227.994712)
			(xy 349.266956 -228.000577) (xy 349.244666 -228.001068) (xy 349.241364 -228.001068) (xy 349.214778 -228.000482)
			(xy 349.162222 -227.992392) (xy 349.111453 -227.976575) (xy 349.063601 -227.953385) (xy 349.01973 -227.923335)
			(xy 348.980816 -227.887096) (xy 348.947723 -227.845473) (xy 348.921189 -227.799391) (xy 348.901803 -227.749875)
			(xy 348.889996 -227.698027) (xy 348.886031 -227.645) (xy 348.889996 -227.591973) (xy 348.901803 -227.540125)
			(xy 348.921189 -227.490609) (xy 348.947723 -227.444527) (xy 348.980816 -227.402904) (xy 349.01973 -227.366664)
			(xy 349.063601 -227.336615) (xy 349.111454 -227.313425) (xy 349.162222 -227.297608) (xy 349.214778 -227.289518)
			(xy 349.241364 -227.288852) (xy 349.242888 -227.288852) (xy 349.265625 -227.289245) (xy 349.31072 -227.295111)
			(xy 349.332804 -227.300536) (xy 349.34525 -227.30206) (xy 349.351858 -227.301866) (xy 349.364608 -227.298394)
			(xy 349.370396 -227.295202) (xy 349.388684 -227.283772) (xy 349.406972 -227.263706) (xy 349.41002 -227.257356)
			(xy 349.423056 -227.231898) (xy 349.452038 -227.182583) (xy 349.467932 -227.158804) (xy 349.47225 -227.152708)
			(xy 349.48114 -227.12426) (xy 349.4659 -227.088192) (xy 349.465646 -227.087938) (xy 349.445309 -227.067672)
			(xy 349.410796 -227.021794) (xy 349.384098 -226.970969) (xy 349.365908 -226.916516) (xy 349.356698 -226.859849)
			(xy 349.356172 -226.831144) (xy 349.356689 -226.803156) (xy 349.365439 -226.747868) (xy 349.382731 -226.694629)
			(xy 349.408138 -226.644751) (xy 349.441036 -226.599462) (xy 349.480614 -226.559878) (xy 349.525897 -226.526972)
			(xy 349.57577 -226.501555) (xy 349.629005 -226.484254) (xy 349.684292 -226.475494) (xy 349.71228 -226.475036)
			(xy 349.712788 -226.475036) (xy 349.734794 -226.475348) (xy 349.778478 -226.480701) (xy 349.79991 -226.485704)
			(xy 349.802704 -226.486466) (xy 349.815404 -226.488244) (xy 349.82223 -226.487975) (xy 349.835363 -226.484236)
			(xy 349.841312 -226.480878) (xy 349.858584 -226.469956) (xy 349.876872 -226.44989) (xy 349.87992 -226.44354)
			(xy 349.887713 -226.428206) (xy 349.904355 -226.398098) (xy 349.913194 -226.383342) (xy 349.941388 -226.339654)
			(xy 349.942912 -226.337622) (xy 349.945706 -226.333304) (xy 349.952056 -226.313492) (xy 349.953358 -226.308913)
			(xy 349.954379 -226.299448) (xy 349.954088 -226.294696) (xy 349.953072 -226.27971) (xy 349.950024 -226.266756)
			(xy 349.939356 -226.241864) (xy 349.922547 -226.222953) (xy 349.894287 -226.180987) (xy 349.872751 -226.135205)
			(xy 349.858444 -226.086676) (xy 349.851699 -226.036533) (xy 349.851726 -226.011232) (xy 349.852488 -225.998278)
			(xy 349.85475 -225.969692) (xy 349.867876 -225.913879) (xy 349.890435 -225.861166) (xy 349.92175 -225.813136)
			(xy 349.94088 -225.791776) (xy 349.94088 -224.615248) (xy 349.924211 -224.596779) (xy 349.896044 -224.555771)
			(xy 349.874342 -224.511005) (xy 349.859594 -224.463492) (xy 349.852133 -224.414305) (xy 349.852128 -224.364556)
			(xy 349.85958 -224.315368) (xy 349.874319 -224.267852) (xy 349.896013 -224.223082) (xy 349.924172 -224.182069)
			(xy 349.94088 -224.163636) (xy 349.94088 -223.988884) (xy 349.94046 -223.975304) (xy 349.933311 -223.949103)
			(xy 349.919499 -223.925718) (xy 349.900003 -223.906809) (xy 349.876207 -223.893719) (xy 349.849799 -223.887375)
			(xy 349.822654 -223.888228) (xy 349.809562 -223.891856) (xy 349.800534 -223.894532) (xy 349.782235 -223.89898)
			(xy 349.772986 -223.900746) (xy 349.749872 -223.905064) (xy 349.546672 -224.257362) (xy 349.554546 -224.27946)
			(xy 349.563299 -224.306044) (xy 349.572746 -224.361206) (xy 349.573342 -224.389188) (xy 349.573342 -224.389442)
			(xy 349.572832 -224.415429) (xy 349.564702 -224.466764) (xy 349.548641 -224.516194) (xy 349.525045 -224.562504)
			(xy 349.494495 -224.604552) (xy 349.457744 -224.641303) (xy 349.415696 -224.671853) (xy 349.369386 -224.695449)
			(xy 349.319956 -224.71151) (xy 349.268621 -224.71964) (xy 349.216647 -224.71964) (xy 349.165312 -224.71151)
			(xy 349.115882 -224.695449) (xy 349.069572 -224.671853) (xy 349.027524 -224.641303) (xy 348.990773 -224.604552)
			(xy 348.960223 -224.562504) (xy 348.936627 -224.516194) (xy 348.920566 -224.466764) (xy 348.912436 -224.415429)
			(xy 348.911926 -224.389442) (xy 348.912399 -224.363972) (xy 348.920215 -224.313636) (xy 348.935653 -224.265093)
			(xy 348.958349 -224.219489) (xy 348.987766 -224.177902) (xy 349.023209 -224.141315) (xy 349.06384 -224.110592)
			(xy 349.1087 -224.086459) (xy 349.156729 -224.069487) (xy 349.181674 -224.064322) (xy 349.204788 -224.060004)
			(xy 349.408242 -223.707452) (xy 349.400368 -223.685608) (xy 349.391618 -223.659023) (xy 349.382176 -223.603862)
			(xy 349.381572 -223.57588) (xy 349.381572 -223.575626) (xy 349.382053 -223.549635) (xy 349.390181 -223.498292)
			(xy 349.406241 -223.448853) (xy 349.429837 -223.402534) (xy 349.460388 -223.360478) (xy 349.497143 -223.323718)
			(xy 349.539195 -223.293161) (xy 349.58551 -223.269558) (xy 349.634947 -223.253492) (xy 349.686289 -223.245357)
			(xy 349.71228 -223.244918) (xy 349.736972 -223.245338) (xy 349.785818 -223.252607) (xy 349.809562 -223.259396)
			(xy 349.822665 -223.262958) (xy 349.849795 -223.263781) (xy 349.876184 -223.257428) (xy 349.899968 -223.244348)
			(xy 349.919465 -223.225464) (xy 349.933299 -223.202111) (xy 349.940493 -223.175939) (xy 349.94088 -223.162368)
			(xy 349.94088 -222.987108) (xy 349.924257 -222.96865) (xy 349.896174 -222.927678) (xy 349.87454 -222.882965)
			(xy 349.859842 -222.835517) (xy 349.852412 -222.786404) (xy 349.852417 -222.736732) (xy 349.859857 -222.68762)
			(xy 349.874564 -222.640175) (xy 349.896207 -222.595466) (xy 349.924298 -222.5545) (xy 349.94088 -222.536004)
			(xy 349.94088 -222.360744) (xy 349.940453 -222.347144) (xy 349.93328 -222.320907) (xy 349.919432 -222.297497)
			(xy 349.899892 -222.278576) (xy 349.876048 -222.265488) (xy 349.849595 -222.259163) (xy 349.822409 -222.26005)
			(xy 349.809308 -222.263716) (xy 349.785751 -222.270469) (xy 349.73729 -222.277743) (xy 349.712788 -222.278194)
			(xy 349.71228 -222.278194) (xy 349.686311 -222.277683) (xy 349.635012 -222.269555) (xy 349.585616 -222.253503)
			(xy 349.539339 -222.229921) (xy 349.497321 -222.199391) (xy 349.460596 -222.162664) (xy 349.430068 -222.120644)
			(xy 349.406489 -222.074366) (xy 349.39044 -222.024969) (xy 349.382315 -221.973669) (xy 349.382315 -221.921731)
			(xy 349.39044 -221.870431) (xy 349.406489 -221.821034) (xy 349.430068 -221.774756) (xy 349.460596 -221.732736)
			(xy 349.497321 -221.696009) (xy 349.539339 -221.665479) (xy 349.585616 -221.641897) (xy 349.635012 -221.625845)
			(xy 349.686311 -221.617717) (xy 349.71228 -221.617286) (xy 349.712788 -221.617286) (xy 349.737289 -221.61775)
			(xy 349.785749 -221.625019) (xy 349.809308 -221.631764) (xy 349.822424 -221.635365) (xy 349.849597 -221.636249)
			(xy 349.87604 -221.629928) (xy 349.899876 -221.61685) (xy 349.919415 -221.597944) (xy 349.933269 -221.574551)
			(xy 349.940455 -221.54833) (xy 349.94088 -221.534736) (xy 349.94088 -221.359476) (xy 349.924252 -221.341018)
			(xy 349.896159 -221.300045) (xy 349.874515 -221.255328) (xy 349.859808 -221.207876) (xy 349.852369 -221.158757)
			(xy 349.852367 -221.109078) (xy 349.8598 -221.059958) (xy 349.874502 -221.012504) (xy 349.896141 -220.967786)
			(xy 349.92423 -220.92681) (xy 349.94088 -220.908372) (xy 349.94088 -220.732858) (xy 349.940455 -220.719257)
			(xy 349.933284 -220.693017) (xy 349.919437 -220.669603) (xy 349.899896 -220.650679) (xy 349.876051 -220.637589)
			(xy 349.849594 -220.631263) (xy 349.822407 -220.63215) (xy 349.809308 -220.63583) (xy 349.800406 -220.638497)
			(xy 349.782362 -220.642946) (xy 349.77324 -220.64472) (xy 349.75038 -220.649038) (xy 349.546672 -221.002098)
			(xy 349.554292 -221.024196) (xy 349.563084 -221.050771) (xy 349.57253 -221.105938) (xy 349.573088 -221.133924)
			(xy 349.572579 -221.159891) (xy 349.564454 -221.211186) (xy 349.548406 -221.260579) (xy 349.524828 -221.306853)
			(xy 349.494302 -221.348869) (xy 349.457579 -221.385592) (xy 349.415563 -221.416118) (xy 349.369289 -221.439696)
			(xy 349.319896 -221.455744) (xy 349.268601 -221.463869) (xy 349.216667 -221.463869) (xy 349.165372 -221.455744)
			(xy 349.115979 -221.439696) (xy 349.069705 -221.416118) (xy 349.027689 -221.385592) (xy 348.990966 -221.348869)
			(xy 348.96044 -221.306853) (xy 348.936862 -221.260579) (xy 348.920814 -221.211186) (xy 348.912689 -221.159891)
			(xy 348.91218 -221.133924) (xy 348.912654 -221.108477) (xy 348.920465 -221.058187) (xy 348.935889 -221.009687)
			(xy 348.958564 -220.964124) (xy 348.987953 -220.922574) (xy 349.023362 -220.886018) (xy 349.063955 -220.85532)
			(xy 349.108773 -220.831206) (xy 349.156756 -220.814243) (xy 349.181674 -220.809058) (xy 349.204534 -220.80474)
			(xy 349.408242 -220.45168) (xy 349.400622 -220.429582) (xy 349.391832 -220.403007) (xy 349.382389 -220.347839)
			(xy 349.381826 -220.319854) (xy 349.382339 -220.293889) (xy 349.390469 -220.242598) (xy 349.406521 -220.19321)
			(xy 349.430101 -220.146941) (xy 349.460628 -220.10493) (xy 349.49735 -220.068211) (xy 349.539363 -220.037687)
			(xy 349.585634 -220.014111) (xy 349.635023 -219.998063) (xy 349.686315 -219.989937) (xy 349.71228 -219.9894)
			(xy 349.712788 -219.9894) (xy 349.737289 -219.989864) (xy 349.785749 -219.997133) (xy 349.809308 -220.003878)
			(xy 349.822424 -220.007478) (xy 349.849599 -220.008362) (xy 349.876043 -220.002041) (xy 349.89988 -219.988964)
			(xy 349.91942 -219.970058) (xy 349.933277 -219.946665) (xy 349.940467 -219.920444) (xy 349.94088 -219.90685)
			(xy 349.94088 -219.73159) (xy 349.924251 -219.713132) (xy 349.896155 -219.672158) (xy 349.87451 -219.627441)
			(xy 349.859801 -219.579988) (xy 349.85236 -219.530868) (xy 349.852356 -219.481187) (xy 349.859788 -219.432066)
			(xy 349.874489 -219.38461) (xy 349.896128 -219.33989) (xy 349.924216 -219.298912) (xy 349.94088 -219.280486)
			(xy 349.94088 -219.105226) (xy 349.940451 -219.091628) (xy 349.933275 -219.065395) (xy 349.919426 -219.04199)
			(xy 349.899887 -219.023072) (xy 349.876046 -219.009987) (xy 349.849595 -219.003663) (xy 349.822413 -219.004549)
			(xy 349.809308 -219.008198) (xy 349.785751 -219.014951) (xy 349.73729 -219.022226) (xy 349.712788 -219.022676)
			(xy 349.71228 -219.022676) (xy 349.686313 -219.022165) (xy 349.635019 -219.014039) (xy 349.585628 -218.997988)
			(xy 349.539355 -218.97441) (xy 349.49734 -218.943884) (xy 349.460618 -218.907161) (xy 349.430091 -218.865146)
			(xy 349.406512 -218.818874) (xy 349.390462 -218.769483) (xy 349.382335 -218.718189) (xy 349.381826 -218.692222)
			(xy 349.382284 -218.667529) (xy 349.389633 -218.618693) (xy 349.404169 -218.571494) (xy 349.425569 -218.526986)
			(xy 349.453356 -218.486159) (xy 349.486911 -218.449923) (xy 349.525487 -218.419086) (xy 349.568223 -218.394335)
			(xy 349.614167 -218.376221) (xy 349.662296 -218.365148) (xy 349.68688 -218.362784) (xy 349.70128 -218.361155)
			(xy 349.72837 -218.350899) (xy 349.751495 -218.333455) (xy 349.768798 -218.310225) (xy 349.778889 -218.283073)
			(xy 349.780958 -218.254181) (xy 349.774838 -218.225868) (xy 349.761022 -218.20041) (xy 349.751142 -218.18981)
			(xy 349.645478 -218.084146) (xy 349.635221 -218.074513) (xy 349.610664 -218.060794) (xy 349.583293 -218.054309)
			(xy 349.555191 -218.055551) (xy 349.528499 -218.064425) (xy 349.505248 -218.080257) (xy 349.495872 -218.09075)
			(xy 349.480086 -218.108904) (xy 349.444159 -218.140898) (xy 349.403972 -218.167342) (xy 349.360374 -218.187678)
			(xy 349.314288 -218.201476) (xy 349.266688 -218.208444) (xy 349.242634 -218.20886) (xy 349.216663 -218.20838)
			(xy 349.165359 -218.200259) (xy 349.115958 -218.184212) (xy 349.069675 -218.160634) (xy 349.027651 -218.130106)
			(xy 348.99092 -218.09338) (xy 348.960387 -218.051359) (xy 348.936803 -218.005079) (xy 348.92075 -217.95568)
			(xy 348.912623 -217.904377) (xy 348.91218 -217.878406) (xy 348.912525 -217.857408) (xy 348.917877 -217.815753)
			(xy 348.922848 -217.795348) (xy 348.926179 -217.780235) (xy 348.924585 -217.749344) (xy 348.91383 -217.720342)
			(xy 348.894898 -217.69588) (xy 348.86952 -217.678196) (xy 348.840015 -217.668906) (xy 348.82455 -217.668348)
			(xy 348.720918 -217.668348) (xy 348.705443 -217.668891) (xy 348.67591 -217.678152) (xy 348.650505 -217.69583)
			(xy 348.631558 -217.720304) (xy 348.620807 -217.749327) (xy 348.619239 -217.780238) (xy 348.62262 -217.795348)
			(xy 348.627599 -217.815751) (xy 348.632951 -217.857407) (xy 348.633288 -217.878406) (xy 348.632674 -217.906386)
			(xy 348.623221 -217.961543) (xy 348.614492 -217.988134) (xy 348.606872 -218.010232) (xy 348.81058 -218.363038)
			(xy 348.83344 -218.367356) (xy 348.858372 -218.372505) (xy 348.906379 -218.389443) (xy 348.95122 -218.413545)
			(xy 348.991833 -218.44424) (xy 349.027258 -218.480801) (xy 349.056655 -218.522363) (xy 349.079329 -218.567942)
			(xy 349.094744 -218.61646) (xy 349.102534 -218.666768) (xy 349.102934 -218.692222) (xy 349.102425 -218.718189)
			(xy 349.0943 -218.769484) (xy 349.078252 -218.818877) (xy 349.054674 -218.865151) (xy 349.024148 -218.907167)
			(xy 348.987425 -218.94389) (xy 348.945409 -218.974416) (xy 348.899135 -218.997994) (xy 348.849742 -219.014042)
			(xy 348.798447 -219.022167) (xy 348.746513 -219.022167) (xy 348.695218 -219.014042) (xy 348.645825 -218.997994)
			(xy 348.599551 -218.974416) (xy 348.557535 -218.94389) (xy 348.520812 -218.907167) (xy 348.490286 -218.865151)
			(xy 348.466708 -218.818877) (xy 348.45066 -218.769484) (xy 348.442535 -218.718189) (xy 348.442026 -218.692222)
			(xy 348.442637 -218.664242) (xy 348.452086 -218.609083) (xy 348.460822 -218.582494) (xy 348.468442 -218.560396)
			(xy 348.264734 -218.20759) (xy 348.241874 -218.203272) (xy 348.216944 -218.198123) (xy 348.16894 -218.181185)
			(xy 348.124103 -218.157082) (xy 348.083495 -218.126387) (xy 348.048076 -218.089825) (xy 348.018686 -218.048262)
			(xy 347.99602 -218.002682) (xy 347.980614 -217.954165) (xy 347.972835 -217.903858) (xy 347.97238 -217.878406)
			(xy 347.972725 -217.857408) (xy 347.978077 -217.815753) (xy 347.983048 -217.795348) (xy 347.986379 -217.780235)
			(xy 347.984785 -217.749344) (xy 347.97403 -217.720342) (xy 347.955098 -217.69588) (xy 347.92972 -217.678196)
			(xy 347.900215 -217.668906) (xy 347.88475 -217.668348) (xy 347.71203 -217.668348) (xy 347.667072 -217.74658)
			(xy 347.674692 -217.768678) (xy 347.683485 -217.795252) (xy 347.692934 -217.85042) (xy 347.693488 -217.878406)
			(xy 347.692979 -217.904373) (xy 347.684854 -217.955668) (xy 347.668806 -218.005061) (xy 347.645228 -218.051335)
			(xy 347.614702 -218.093351) (xy 347.577979 -218.130074) (xy 347.535963 -218.1606) (xy 347.489689 -218.184178)
			(xy 347.440296 -218.200226) (xy 347.389001 -218.208351) (xy 347.337067 -218.208351) (xy 347.285772 -218.200226)
			(xy 347.236379 -218.184178) (xy 347.190105 -218.1606) (xy 347.148089 -218.130074) (xy 347.111366 -218.093351)
			(xy 347.08084 -218.051335) (xy 347.057262 -218.005061) (xy 347.041214 -217.955668) (xy 347.033089 -217.904373)
			(xy 347.03258 -217.878406) (xy 347.032925 -217.857408) (xy 347.038277 -217.815753) (xy 347.043248 -217.795348)
			(xy 347.046579 -217.780235) (xy 347.044985 -217.749344) (xy 347.03423 -217.720342) (xy 347.015298 -217.69588)
			(xy 346.98992 -217.678196) (xy 346.960415 -217.668906) (xy 346.94495 -217.668348) (xy 346.841318 -217.668348)
			(xy 346.825843 -217.668891) (xy 346.79631 -217.678152) (xy 346.770905 -217.69583) (xy 346.751958 -217.720304)
			(xy 346.741207 -217.749327) (xy 346.739639 -217.780238) (xy 346.74302 -217.795348) (xy 346.747999 -217.815751)
			(xy 346.753351 -217.857407) (xy 346.753688 -217.878406) (xy 346.753074 -217.906386) (xy 346.743621 -217.961543)
			(xy 346.734892 -217.988134) (xy 346.727272 -218.010232) (xy 346.93098 -218.363038) (xy 346.95384 -218.367356)
			(xy 346.978772 -218.372505) (xy 347.026779 -218.389443) (xy 347.07162 -218.413545) (xy 347.112233 -218.44424)
			(xy 347.147658 -218.480801) (xy 347.177055 -218.522363) (xy 347.199729 -218.567942) (xy 347.215144 -218.61646)
			(xy 347.222934 -218.666768) (xy 347.223334 -218.692222) (xy 347.222825 -218.718189) (xy 347.2147 -218.769484)
			(xy 347.198652 -218.818877) (xy 347.175074 -218.865151) (xy 347.144548 -218.907167) (xy 347.107825 -218.94389)
			(xy 347.065809 -218.974416) (xy 347.019535 -218.997994) (xy 346.970142 -219.014042) (xy 346.918847 -219.022167)
			(xy 346.866913 -219.022167) (xy 346.815618 -219.014042) (xy 346.766225 -218.997994) (xy 346.719951 -218.974416)
			(xy 346.677935 -218.94389) (xy 346.641212 -218.907167) (xy 346.610686 -218.865151) (xy 346.587108 -218.818877)
			(xy 346.57106 -218.769484) (xy 346.562935 -218.718189) (xy 346.562426 -218.692222) (xy 346.563037 -218.664242)
			(xy 346.572486 -218.609083) (xy 346.581222 -218.582494) (xy 346.588842 -218.560396) (xy 346.385134 -218.20759)
			(xy 346.362274 -218.203272) (xy 346.337344 -218.198123) (xy 346.28934 -218.181185) (xy 346.244503 -218.157082)
			(xy 346.203895 -218.126387) (xy 346.168476 -218.089825) (xy 346.139086 -218.048262) (xy 346.11642 -218.002682)
			(xy 346.101014 -217.954165) (xy 346.093235 -217.903858) (xy 346.09278 -217.878406) (xy 346.093125 -217.857408)
			(xy 346.098477 -217.815753) (xy 346.103448 -217.795348) (xy 346.106779 -217.780235) (xy 346.105185 -217.749344)
			(xy 346.09443 -217.720342) (xy 346.075498 -217.69588) (xy 346.05012 -217.678196) (xy 346.020615 -217.668906)
			(xy 346.00515 -217.668348) (xy 345.83243 -217.668348) (xy 345.787472 -217.74658) (xy 345.795092 -217.768678)
			(xy 345.803885 -217.795252) (xy 345.813334 -217.85042) (xy 345.813888 -217.878406) (xy 345.813379 -217.904373)
			(xy 345.805254 -217.955668) (xy 345.789206 -218.005061) (xy 345.765628 -218.051335) (xy 345.735102 -218.093351)
			(xy 345.698379 -218.130074) (xy 345.656363 -218.1606) (xy 345.610089 -218.184178) (xy 345.560696 -218.200226)
			(xy 345.509401 -218.208351) (xy 345.457467 -218.208351) (xy 345.406172 -218.200226) (xy 345.356779 -218.184178)
			(xy 345.310505 -218.1606) (xy 345.268489 -218.130074) (xy 345.231766 -218.093351) (xy 345.20124 -218.051335)
			(xy 345.177662 -218.005061) (xy 345.161614 -217.955668) (xy 345.153489 -217.904373) (xy 345.15298 -217.878406)
			(xy 345.153325 -217.857408) (xy 345.158677 -217.815753) (xy 345.163648 -217.795348) (xy 345.166979 -217.780235)
			(xy 345.165385 -217.749344) (xy 345.15463 -217.720342) (xy 345.135698 -217.69588) (xy 345.11032 -217.678196)
			(xy 345.080815 -217.668906) (xy 345.06535 -217.668348) (xy 344.961718 -217.668348) (xy 344.946243 -217.668891)
			(xy 344.91671 -217.678152) (xy 344.891305 -217.69583) (xy 344.872358 -217.720304) (xy 344.861607 -217.749327)
			(xy 344.860039 -217.780238) (xy 344.86342 -217.795348) (xy 344.868399 -217.815751) (xy 344.873751 -217.857407)
			(xy 344.874088 -217.878406) (xy 344.873474 -217.906386) (xy 344.864021 -217.961543) (xy 344.855292 -217.988134)
			(xy 344.847672 -218.010232) (xy 345.05138 -218.363038) (xy 345.07424 -218.367356) (xy 345.099172 -218.372505)
			(xy 345.147179 -218.389443) (xy 345.19202 -218.413545) (xy 345.232633 -218.44424) (xy 345.268058 -218.480801)
			(xy 345.297455 -218.522363) (xy 345.320129 -218.567942) (xy 345.335544 -218.61646) (xy 345.343334 -218.666768)
			(xy 345.343734 -218.692222) (xy 345.343225 -218.718189) (xy 345.3351 -218.769484) (xy 345.319052 -218.818877)
			(xy 345.295474 -218.865151) (xy 345.264948 -218.907167) (xy 345.228225 -218.94389) (xy 345.186209 -218.974416)
			(xy 345.139935 -218.997994) (xy 345.090542 -219.014042) (xy 345.039247 -219.022167) (xy 344.987313 -219.022167)
			(xy 344.936018 -219.014042) (xy 344.886625 -218.997994) (xy 344.840351 -218.974416) (xy 344.798335 -218.94389)
			(xy 344.761612 -218.907167) (xy 344.731086 -218.865151) (xy 344.707508 -218.818877) (xy 344.69146 -218.769484)
			(xy 344.683335 -218.718189) (xy 344.682826 -218.692222) (xy 344.683437 -218.664242) (xy 344.692886 -218.609083)
			(xy 344.701622 -218.582494) (xy 344.709242 -218.560396) (xy 344.505534 -218.20759) (xy 344.482674 -218.203272)
			(xy 344.457744 -218.198123) (xy 344.40974 -218.181185) (xy 344.364903 -218.157082) (xy 344.324295 -218.126387)
			(xy 344.288876 -218.089825) (xy 344.259486 -218.048262) (xy 344.23682 -218.002682) (xy 344.221414 -217.954165)
			(xy 344.213635 -217.903858) (xy 344.21318 -217.878406) (xy 344.213525 -217.857408) (xy 344.218877 -217.815753)
			(xy 344.223848 -217.795348) (xy 344.227179 -217.780235) (xy 344.225585 -217.749344) (xy 344.21483 -217.720342)
			(xy 344.195898 -217.69588) (xy 344.17052 -217.678196) (xy 344.141015 -217.668906) (xy 344.12555 -217.668348)
			(xy 343.95283 -217.668348) (xy 343.907872 -217.74658) (xy 343.915492 -217.768678) (xy 343.924285 -217.795252)
			(xy 343.933734 -217.85042) (xy 343.934288 -217.878406) (xy 343.933779 -217.904373) (xy 343.925654 -217.955668)
			(xy 343.909606 -218.005061) (xy 343.886028 -218.051335) (xy 343.855502 -218.093351) (xy 343.818779 -218.130074)
			(xy 343.776763 -218.1606) (xy 343.730489 -218.184178) (xy 343.681096 -218.200226) (xy 343.629801 -218.208351)
			(xy 343.577867 -218.208351) (xy 343.526572 -218.200226) (xy 343.477179 -218.184178) (xy 343.430905 -218.1606)
			(xy 343.388889 -218.130074) (xy 343.352166 -218.093351) (xy 343.32164 -218.051335) (xy 343.298062 -218.005061)
			(xy 343.282014 -217.955668) (xy 343.273889 -217.904373) (xy 343.27338 -217.878406) (xy 343.273725 -217.857408)
			(xy 343.279077 -217.815753) (xy 343.284048 -217.795348) (xy 343.287379 -217.780235) (xy 343.285785 -217.749344)
			(xy 343.27503 -217.720342) (xy 343.256098 -217.69588) (xy 343.23072 -217.678196) (xy 343.201215 -217.668906)
			(xy 343.18575 -217.668348) (xy 343.082118 -217.668348) (xy 343.066643 -217.668891) (xy 343.03711 -217.678152)
			(xy 343.011705 -217.69583) (xy 342.992758 -217.720304) (xy 342.982007 -217.749327) (xy 342.980439 -217.780238)
			(xy 342.98382 -217.795348) (xy 342.988799 -217.815751) (xy 342.994151 -217.857407) (xy 342.994488 -217.878406)
			(xy 342.993874 -217.906386) (xy 342.984421 -217.961543) (xy 342.975692 -217.988134) (xy 342.968072 -218.010232)
			(xy 343.17178 -218.363038) (xy 343.19464 -218.367356) (xy 343.219572 -218.372505) (xy 343.267579 -218.389443)
			(xy 343.31242 -218.413545) (xy 343.353033 -218.44424) (xy 343.388458 -218.480801) (xy 343.417855 -218.522363)
			(xy 343.440529 -218.567942) (xy 343.455944 -218.61646) (xy 343.463734 -218.666768) (xy 343.464134 -218.692222)
			(xy 343.463625 -218.718189) (xy 343.4555 -218.769484) (xy 343.439452 -218.818877) (xy 343.415874 -218.865151)
			(xy 343.385348 -218.907167) (xy 343.348625 -218.94389) (xy 343.306609 -218.974416) (xy 343.260335 -218.997994)
			(xy 343.210942 -219.014042) (xy 343.159647 -219.022167) (xy 343.107713 -219.022167) (xy 343.056418 -219.014042)
			(xy 343.007025 -218.997994) (xy 342.960751 -218.974416) (xy 342.918735 -218.94389) (xy 342.882012 -218.907167)
			(xy 342.851486 -218.865151) (xy 342.827908 -218.818877) (xy 342.81186 -218.769484) (xy 342.803735 -218.718189)
			(xy 342.803226 -218.692222) (xy 342.803837 -218.664242) (xy 342.813286 -218.609083) (xy 342.822022 -218.582494)
			(xy 342.829642 -218.560396) (xy 342.625934 -218.20759) (xy 342.603074 -218.203272) (xy 342.578144 -218.198123)
			(xy 342.53014 -218.181185) (xy 342.485303 -218.157082) (xy 342.444695 -218.126387) (xy 342.409276 -218.089825)
			(xy 342.379886 -218.048262) (xy 342.35722 -218.002682) (xy 342.341814 -217.954165) (xy 342.334035 -217.903858)
			(xy 342.33358 -217.878406) (xy 342.333925 -217.857408) (xy 342.339277 -217.815753) (xy 342.344248 -217.795348)
			(xy 342.347579 -217.780235) (xy 342.345985 -217.749344) (xy 342.33523 -217.720342) (xy 342.316298 -217.69588)
			(xy 342.29092 -217.678196) (xy 342.261415 -217.668906) (xy 342.24595 -217.668348) (xy 342.07323 -217.668348)
			(xy 342.028272 -217.74658) (xy 342.035892 -217.768678) (xy 342.044685 -217.795252) (xy 342.054134 -217.85042)
			(xy 342.054688 -217.878406) (xy 342.054179 -217.904373) (xy 342.046054 -217.955668) (xy 342.030006 -218.005061)
			(xy 342.006428 -218.051335) (xy 341.975902 -218.093351) (xy 341.939179 -218.130074) (xy 341.897163 -218.1606)
			(xy 341.850889 -218.184178) (xy 341.801496 -218.200226) (xy 341.750201 -218.208351) (xy 341.698267 -218.208351)
			(xy 341.646972 -218.200226) (xy 341.597579 -218.184178) (xy 341.551305 -218.1606) (xy 341.509289 -218.130074)
			(xy 341.472566 -218.093351) (xy 341.44204 -218.051335) (xy 341.418462 -218.005061) (xy 341.402414 -217.955668)
			(xy 341.394289 -217.904373) (xy 341.39378 -217.878406) (xy 341.394125 -217.857408) (xy 341.399477 -217.815753)
			(xy 341.404448 -217.795348) (xy 341.407779 -217.780235) (xy 341.406185 -217.749344) (xy 341.39543 -217.720342)
			(xy 341.376498 -217.69588) (xy 341.35112 -217.678196) (xy 341.321615 -217.668906) (xy 341.30615 -217.668348)
			(xy 341.202518 -217.668348) (xy 341.187043 -217.668891) (xy 341.15751 -217.678152) (xy 341.132105 -217.69583)
			(xy 341.113158 -217.720304) (xy 341.102407 -217.749327) (xy 341.100839 -217.780238) (xy 341.10422 -217.795348)
			(xy 341.109199 -217.815751) (xy 341.114551 -217.857407) (xy 341.114888 -217.878406) (xy 341.114274 -217.906386)
			(xy 341.104821 -217.961543) (xy 341.096092 -217.988134) (xy 341.088472 -218.010232) (xy 341.29218 -218.363038)
			(xy 341.31504 -218.367356) (xy 341.339972 -218.372505) (xy 341.387979 -218.389443) (xy 341.43282 -218.413545)
			(xy 341.473433 -218.44424) (xy 341.508858 -218.480801) (xy 341.538255 -218.522363) (xy 341.560929 -218.567942)
			(xy 341.576344 -218.61646) (xy 341.584134 -218.666768) (xy 341.584534 -218.692222) (xy 341.584025 -218.718189)
			(xy 341.5759 -218.769484) (xy 341.559852 -218.818877) (xy 341.536274 -218.865151) (xy 341.505748 -218.907167)
			(xy 341.469025 -218.94389) (xy 341.427009 -218.974416) (xy 341.380735 -218.997994) (xy 341.331342 -219.014042)
			(xy 341.280047 -219.022167) (xy 341.228113 -219.022167) (xy 341.176818 -219.014042) (xy 341.127425 -218.997994)
			(xy 341.081151 -218.974416) (xy 341.039135 -218.94389) (xy 341.002412 -218.907167) (xy 340.971886 -218.865151)
			(xy 340.948308 -218.818877) (xy 340.93226 -218.769484) (xy 340.924135 -218.718189) (xy 340.923626 -218.692222)
			(xy 340.924237 -218.664242) (xy 340.933686 -218.609083) (xy 340.942422 -218.582494) (xy 340.950042 -218.560396)
			(xy 340.746334 -218.20759) (xy 340.723474 -218.203272) (xy 340.698544 -218.198123) (xy 340.65054 -218.181185)
			(xy 340.605703 -218.157082) (xy 340.565095 -218.126387) (xy 340.529676 -218.089825) (xy 340.500286 -218.048262)
			(xy 340.47762 -218.002682) (xy 340.462214 -217.954165) (xy 340.454435 -217.903858) (xy 340.45398 -217.878406)
			(xy 340.454325 -217.857408) (xy 340.459677 -217.815753) (xy 340.464648 -217.795348) (xy 340.467979 -217.780235)
			(xy 340.466385 -217.749344) (xy 340.45563 -217.720342) (xy 340.436698 -217.69588) (xy 340.41132 -217.678196)
			(xy 340.381815 -217.668906) (xy 340.36635 -217.668348) (xy 340.19363 -217.668348) (xy 340.148672 -217.74658)
			(xy 340.156292 -217.768678) (xy 340.165085 -217.795252) (xy 340.174534 -217.85042) (xy 340.175088 -217.878406)
			(xy 340.174579 -217.904373) (xy 340.166454 -217.955668) (xy 340.150406 -218.005061) (xy 340.126828 -218.051335)
			(xy 340.096302 -218.093351) (xy 340.059579 -218.130074) (xy 340.017563 -218.1606) (xy 339.971289 -218.184178)
			(xy 339.921896 -218.200226) (xy 339.870601 -218.208351) (xy 339.818667 -218.208351) (xy 339.767372 -218.200226)
			(xy 339.717979 -218.184178) (xy 339.671705 -218.1606) (xy 339.629689 -218.130074) (xy 339.592966 -218.093351)
			(xy 339.56244 -218.051335) (xy 339.538862 -218.005061) (xy 339.522814 -217.955668) (xy 339.514689 -217.904373)
			(xy 339.51418 -217.878406) (xy 339.514525 -217.857408) (xy 339.519877 -217.815753) (xy 339.524848 -217.795348)
			(xy 339.528179 -217.780235) (xy 339.526585 -217.749344) (xy 339.51583 -217.720342) (xy 339.496898 -217.69588)
			(xy 339.47152 -217.678196) (xy 339.442015 -217.668906) (xy 339.42655 -217.668348) (xy 339.322918 -217.668348)
			(xy 339.307443 -217.668891) (xy 339.27791 -217.678152) (xy 339.252505 -217.69583) (xy 339.233558 -217.720304)
			(xy 339.222807 -217.749327) (xy 339.221239 -217.780238) (xy 339.22462 -217.795348) (xy 339.229599 -217.815751)
			(xy 339.234951 -217.857407) (xy 339.235288 -217.878406) (xy 339.234674 -217.906386) (xy 339.225221 -217.961543)
			(xy 339.216492 -217.988134) (xy 339.208872 -218.010232) (xy 339.41258 -218.363038) (xy 339.43544 -218.367356)
			(xy 339.460372 -218.372505) (xy 339.508379 -218.389443) (xy 339.55322 -218.413545) (xy 339.593833 -218.44424)
			(xy 339.629258 -218.480801) (xy 339.658655 -218.522363) (xy 339.681329 -218.567942) (xy 339.696744 -218.61646)
			(xy 339.704534 -218.666768) (xy 339.704934 -218.692222) (xy 339.704425 -218.718189) (xy 339.6963 -218.769484)
			(xy 339.680252 -218.818877) (xy 339.656674 -218.865151) (xy 339.626148 -218.907167) (xy 339.589425 -218.94389)
			(xy 339.547409 -218.974416) (xy 339.501135 -218.997994) (xy 339.451742 -219.014042) (xy 339.400447 -219.022167)
			(xy 339.348513 -219.022167) (xy 339.297218 -219.014042) (xy 339.247825 -218.997994) (xy 339.201551 -218.974416)
			(xy 339.159535 -218.94389) (xy 339.122812 -218.907167) (xy 339.092286 -218.865151) (xy 339.068708 -218.818877)
			(xy 339.05266 -218.769484) (xy 339.044535 -218.718189) (xy 339.044026 -218.692222) (xy 339.044637 -218.664242)
			(xy 339.054086 -218.609083) (xy 339.062822 -218.582494) (xy 339.070442 -218.560396) (xy 338.866734 -218.20759)
			(xy 338.843874 -218.203272) (xy 338.818944 -218.198123) (xy 338.77094 -218.181185) (xy 338.726103 -218.157082)
			(xy 338.685495 -218.126387) (xy 338.650076 -218.089825) (xy 338.620686 -218.048262) (xy 338.59802 -218.002682)
			(xy 338.582614 -217.954165) (xy 338.574835 -217.903858) (xy 338.57438 -217.878406) (xy 338.574725 -217.857408)
			(xy 338.580077 -217.815753) (xy 338.585048 -217.795348) (xy 338.588379 -217.780235) (xy 338.586785 -217.749344)
			(xy 338.57603 -217.720342) (xy 338.557098 -217.69588) (xy 338.53172 -217.678196) (xy 338.502215 -217.668906)
			(xy 338.48675 -217.668348) (xy 338.31403 -217.668348) (xy 338.269072 -217.74658) (xy 338.276692 -217.768678)
			(xy 338.285485 -217.795252) (xy 338.294934 -217.85042) (xy 338.295488 -217.878406) (xy 338.294979 -217.904373)
			(xy 338.286854 -217.955668) (xy 338.270806 -218.005061) (xy 338.247228 -218.051335) (xy 338.216702 -218.093351)
			(xy 338.179979 -218.130074) (xy 338.137963 -218.1606) (xy 338.091689 -218.184178) (xy 338.042296 -218.200226)
			(xy 337.991001 -218.208351) (xy 337.939067 -218.208351) (xy 337.887772 -218.200226) (xy 337.838379 -218.184178)
			(xy 337.792105 -218.1606) (xy 337.750089 -218.130074) (xy 337.713366 -218.093351) (xy 337.68284 -218.051335)
			(xy 337.659262 -218.005061) (xy 337.643214 -217.955668) (xy 337.635089 -217.904373) (xy 337.63458 -217.878406)
			(xy 337.634925 -217.857408) (xy 337.640277 -217.815753) (xy 337.645248 -217.795348) (xy 337.648579 -217.780235)
			(xy 337.646985 -217.749344) (xy 337.63623 -217.720342) (xy 337.617298 -217.69588) (xy 337.59192 -217.678196)
			(xy 337.562415 -217.668906) (xy 337.54695 -217.668348) (xy 337.443318 -217.668348) (xy 337.427843 -217.668891)
			(xy 337.39831 -217.678152) (xy 337.372905 -217.69583) (xy 337.353958 -217.720304) (xy 337.343207 -217.749327)
			(xy 337.341639 -217.780238) (xy 337.34502 -217.795348) (xy 337.349999 -217.815751) (xy 337.355351 -217.857407)
			(xy 337.355688 -217.878406) (xy 337.355074 -217.906386) (xy 337.345621 -217.961543) (xy 337.336892 -217.988134)
			(xy 337.329272 -218.010232) (xy 337.53298 -218.363038) (xy 337.55584 -218.367356) (xy 337.580772 -218.372505)
			(xy 337.628779 -218.389443) (xy 337.67362 -218.413545) (xy 337.714233 -218.44424) (xy 337.749658 -218.480801)
			(xy 337.779055 -218.522363) (xy 337.801729 -218.567942) (xy 337.817144 -218.61646) (xy 337.824934 -218.666768)
			(xy 337.825334 -218.692222) (xy 337.824825 -218.718189) (xy 337.8167 -218.769484) (xy 337.800652 -218.818877)
			(xy 337.777074 -218.865151) (xy 337.746548 -218.907167) (xy 337.709825 -218.94389) (xy 337.667809 -218.974416)
			(xy 337.621535 -218.997994) (xy 337.572142 -219.014042) (xy 337.520847 -219.022167) (xy 337.468913 -219.022167)
			(xy 337.417618 -219.014042) (xy 337.368225 -218.997994) (xy 337.321951 -218.974416) (xy 337.279935 -218.94389)
			(xy 337.243212 -218.907167) (xy 337.212686 -218.865151) (xy 337.189108 -218.818877) (xy 337.17306 -218.769484)
			(xy 337.164935 -218.718189) (xy 337.164426 -218.692222) (xy 337.165037 -218.664242) (xy 337.174486 -218.609083)
			(xy 337.183222 -218.582494) (xy 337.190842 -218.560396) (xy 336.987134 -218.20759) (xy 336.964274 -218.203272)
			(xy 336.939431 -218.198141) (xy 336.891589 -218.181278) (xy 336.846886 -218.157302) (xy 336.806372 -218.126776)
			(xy 336.770999 -218.090417) (xy 336.741599 -218.049079) (xy 336.718861 -218.003734) (xy 336.703321 -217.955446)
			(xy 336.698844 -217.930476) (xy 336.696243 -217.916736) (xy 336.684576 -217.891333) (xy 336.66645 -217.870051)
			(xy 336.643227 -217.85449) (xy 336.616652 -217.845819) (xy 336.58872 -217.844688) (xy 336.561531 -217.851184)
			(xy 336.537127 -217.864817) (xy 336.526886 -217.874342) (xy 336.386678 -218.01455) (xy 336.382868 -218.022424)
			(xy 336.370315 -218.047068) (xy 336.338268 -218.092137) (xy 336.299165 -218.131243) (xy 336.2541 -218.163296)
			(xy 336.229452 -218.17584) (xy 336.221578 -218.17965) (xy 336.19948 -218.201748) (xy 336.19948 -219.194126)
			(xy 336.228436 -219.208096) (xy 336.252122 -219.220053) (xy 336.295666 -219.250364) (xy 336.333808 -219.287242)
			(xy 336.365568 -219.329741) (xy 336.39013 -219.376768) (xy 336.406863 -219.427115) (xy 336.415338 -219.479489)
			(xy 336.415335 -219.532005) (xy 336.695289 -219.532005) (xy 336.695289 -219.480071) (xy 336.703414 -219.428776)
			(xy 336.719462 -219.379383) (xy 336.74304 -219.333109) (xy 336.773566 -219.291093) (xy 336.810289 -219.25437)
			(xy 336.852305 -219.223844) (xy 336.898579 -219.200266) (xy 336.947972 -219.184218) (xy 336.999267 -219.176093)
			(xy 337.051201 -219.176093) (xy 337.102496 -219.184218) (xy 337.151889 -219.200266) (xy 337.198163 -219.223844)
			(xy 337.240179 -219.25437) (xy 337.276902 -219.291093) (xy 337.307428 -219.333109) (xy 337.331006 -219.379383)
			(xy 337.347054 -219.428776) (xy 337.355179 -219.480071) (xy 337.355688 -219.506038) (xy 337.355179 -219.532005)
			(xy 337.635089 -219.532005) (xy 337.635089 -219.480071) (xy 337.643214 -219.428776) (xy 337.659262 -219.379383)
			(xy 337.68284 -219.333109) (xy 337.713366 -219.291093) (xy 337.750089 -219.25437) (xy 337.792105 -219.223844)
			(xy 337.838379 -219.200266) (xy 337.887772 -219.184218) (xy 337.939067 -219.176093) (xy 337.991001 -219.176093)
			(xy 338.042296 -219.184218) (xy 338.091689 -219.200266) (xy 338.137963 -219.223844) (xy 338.179979 -219.25437)
			(xy 338.216702 -219.291093) (xy 338.247228 -219.333109) (xy 338.270806 -219.379383) (xy 338.286854 -219.428776)
			(xy 338.294979 -219.480071) (xy 338.295488 -219.506038) (xy 338.294979 -219.532005) (xy 338.574889 -219.532005)
			(xy 338.574889 -219.480071) (xy 338.583014 -219.428776) (xy 338.599062 -219.379383) (xy 338.62264 -219.333109)
			(xy 338.653166 -219.291093) (xy 338.689889 -219.25437) (xy 338.731905 -219.223844) (xy 338.778179 -219.200266)
			(xy 338.827572 -219.184218) (xy 338.878867 -219.176093) (xy 338.930801 -219.176093) (xy 338.982096 -219.184218)
			(xy 339.031489 -219.200266) (xy 339.077763 -219.223844) (xy 339.119779 -219.25437) (xy 339.156502 -219.291093)
			(xy 339.187028 -219.333109) (xy 339.210606 -219.379383) (xy 339.226654 -219.428776) (xy 339.234779 -219.480071)
			(xy 339.235288 -219.506038) (xy 339.234779 -219.532005) (xy 339.514689 -219.532005) (xy 339.514689 -219.480071)
			(xy 339.522814 -219.428776) (xy 339.538862 -219.379383) (xy 339.56244 -219.333109) (xy 339.592966 -219.291093)
			(xy 339.629689 -219.25437) (xy 339.671705 -219.223844) (xy 339.717979 -219.200266) (xy 339.767372 -219.184218)
			(xy 339.818667 -219.176093) (xy 339.870601 -219.176093) (xy 339.921896 -219.184218) (xy 339.971289 -219.200266)
			(xy 340.017563 -219.223844) (xy 340.059579 -219.25437) (xy 340.096302 -219.291093) (xy 340.126828 -219.333109)
			(xy 340.150406 -219.379383) (xy 340.166454 -219.428776) (xy 340.174579 -219.480071) (xy 340.175088 -219.506038)
			(xy 340.174579 -219.532005) (xy 340.454489 -219.532005) (xy 340.454489 -219.480071) (xy 340.462614 -219.428776)
			(xy 340.478662 -219.379383) (xy 340.50224 -219.333109) (xy 340.532766 -219.291093) (xy 340.569489 -219.25437)
			(xy 340.611505 -219.223844) (xy 340.657779 -219.200266) (xy 340.707172 -219.184218) (xy 340.758467 -219.176093)
			(xy 340.810401 -219.176093) (xy 340.861696 -219.184218) (xy 340.911089 -219.200266) (xy 340.957363 -219.223844)
			(xy 340.999379 -219.25437) (xy 341.036102 -219.291093) (xy 341.066628 -219.333109) (xy 341.090206 -219.379383)
			(xy 341.106254 -219.428776) (xy 341.114379 -219.480071) (xy 341.114888 -219.506038) (xy 341.114379 -219.532005)
			(xy 341.394289 -219.532005) (xy 341.394289 -219.480071) (xy 341.402414 -219.428776) (xy 341.418462 -219.379383)
			(xy 341.44204 -219.333109) (xy 341.472566 -219.291093) (xy 341.509289 -219.25437) (xy 341.551305 -219.223844)
			(xy 341.597579 -219.200266) (xy 341.646972 -219.184218) (xy 341.698267 -219.176093) (xy 341.750201 -219.176093)
			(xy 341.801496 -219.184218) (xy 341.850889 -219.200266) (xy 341.897163 -219.223844) (xy 341.939179 -219.25437)
			(xy 341.975902 -219.291093) (xy 342.006428 -219.333109) (xy 342.030006 -219.379383) (xy 342.046054 -219.428776)
			(xy 342.054179 -219.480071) (xy 342.054688 -219.506038) (xy 342.054179 -219.532005) (xy 342.334089 -219.532005)
			(xy 342.334089 -219.480071) (xy 342.342214 -219.428776) (xy 342.358262 -219.379383) (xy 342.38184 -219.333109)
			(xy 342.412366 -219.291093) (xy 342.449089 -219.25437) (xy 342.491105 -219.223844) (xy 342.537379 -219.200266)
			(xy 342.586772 -219.184218) (xy 342.638067 -219.176093) (xy 342.690001 -219.176093) (xy 342.741296 -219.184218)
			(xy 342.790689 -219.200266) (xy 342.836963 -219.223844) (xy 342.878979 -219.25437) (xy 342.915702 -219.291093)
			(xy 342.946228 -219.333109) (xy 342.969806 -219.379383) (xy 342.985854 -219.428776) (xy 342.993979 -219.480071)
			(xy 342.994488 -219.506038) (xy 342.993979 -219.532005) (xy 343.273889 -219.532005) (xy 343.273889 -219.480071)
			(xy 343.282014 -219.428776) (xy 343.298062 -219.379383) (xy 343.32164 -219.333109) (xy 343.352166 -219.291093)
			(xy 343.388889 -219.25437) (xy 343.430905 -219.223844) (xy 343.477179 -219.200266) (xy 343.526572 -219.184218)
			(xy 343.577867 -219.176093) (xy 343.629801 -219.176093) (xy 343.681096 -219.184218) (xy 343.730489 -219.200266)
			(xy 343.776763 -219.223844) (xy 343.818779 -219.25437) (xy 343.855502 -219.291093) (xy 343.886028 -219.333109)
			(xy 343.909606 -219.379383) (xy 343.925654 -219.428776) (xy 343.933779 -219.480071) (xy 343.934288 -219.506038)
			(xy 343.933779 -219.532005) (xy 344.213689 -219.532005) (xy 344.213689 -219.480071) (xy 344.221814 -219.428776)
			(xy 344.237862 -219.379383) (xy 344.26144 -219.333109) (xy 344.291966 -219.291093) (xy 344.328689 -219.25437)
			(xy 344.370705 -219.223844) (xy 344.416979 -219.200266) (xy 344.466372 -219.184218) (xy 344.517667 -219.176093)
			(xy 344.569601 -219.176093) (xy 344.620896 -219.184218) (xy 344.670289 -219.200266) (xy 344.716563 -219.223844)
			(xy 344.758579 -219.25437) (xy 344.795302 -219.291093) (xy 344.825828 -219.333109) (xy 344.849406 -219.379383)
			(xy 344.865454 -219.428776) (xy 344.873579 -219.480071) (xy 344.874088 -219.506038) (xy 344.873579 -219.532005)
			(xy 345.153489 -219.532005) (xy 345.153489 -219.480071) (xy 345.161614 -219.428776) (xy 345.177662 -219.379383)
			(xy 345.20124 -219.333109) (xy 345.231766 -219.291093) (xy 345.268489 -219.25437) (xy 345.310505 -219.223844)
			(xy 345.356779 -219.200266) (xy 345.406172 -219.184218) (xy 345.457467 -219.176093) (xy 345.509401 -219.176093)
			(xy 345.560696 -219.184218) (xy 345.610089 -219.200266) (xy 345.656363 -219.223844) (xy 345.698379 -219.25437)
			(xy 345.735102 -219.291093) (xy 345.765628 -219.333109) (xy 345.789206 -219.379383) (xy 345.805254 -219.428776)
			(xy 345.813379 -219.480071) (xy 345.813888 -219.506038) (xy 345.813379 -219.532005) (xy 346.093289 -219.532005)
			(xy 346.093289 -219.480071) (xy 346.101414 -219.428776) (xy 346.117462 -219.379383) (xy 346.14104 -219.333109)
			(xy 346.171566 -219.291093) (xy 346.208289 -219.25437) (xy 346.250305 -219.223844) (xy 346.296579 -219.200266)
			(xy 346.345972 -219.184218) (xy 346.397267 -219.176093) (xy 346.449201 -219.176093) (xy 346.500496 -219.184218)
			(xy 346.549889 -219.200266) (xy 346.596163 -219.223844) (xy 346.638179 -219.25437) (xy 346.674902 -219.291093)
			(xy 346.705428 -219.333109) (xy 346.729006 -219.379383) (xy 346.745054 -219.428776) (xy 346.753179 -219.480071)
			(xy 346.753688 -219.506038) (xy 346.753179 -219.532005) (xy 347.033089 -219.532005) (xy 347.033089 -219.480071)
			(xy 347.041214 -219.428776) (xy 347.057262 -219.379383) (xy 347.08084 -219.333109) (xy 347.111366 -219.291093)
			(xy 347.148089 -219.25437) (xy 347.190105 -219.223844) (xy 347.236379 -219.200266) (xy 347.285772 -219.184218)
			(xy 347.337067 -219.176093) (xy 347.389001 -219.176093) (xy 347.440296 -219.184218) (xy 347.489689 -219.200266)
			(xy 347.535963 -219.223844) (xy 347.577979 -219.25437) (xy 347.614702 -219.291093) (xy 347.645228 -219.333109)
			(xy 347.668806 -219.379383) (xy 347.684854 -219.428776) (xy 347.692979 -219.480071) (xy 347.693488 -219.506038)
			(xy 347.692979 -219.532005) (xy 347.972889 -219.532005) (xy 347.972889 -219.480071) (xy 347.981014 -219.428776)
			(xy 347.997062 -219.379383) (xy 348.02064 -219.333109) (xy 348.051166 -219.291093) (xy 348.087889 -219.25437)
			(xy 348.129905 -219.223844) (xy 348.176179 -219.200266) (xy 348.225572 -219.184218) (xy 348.276867 -219.176093)
			(xy 348.328801 -219.176093) (xy 348.380096 -219.184218) (xy 348.429489 -219.200266) (xy 348.475763 -219.223844)
			(xy 348.517779 -219.25437) (xy 348.554502 -219.291093) (xy 348.585028 -219.333109) (xy 348.608606 -219.379383)
			(xy 348.624654 -219.428776) (xy 348.632779 -219.480071) (xy 348.633288 -219.506038) (xy 348.632779 -219.532005)
			(xy 348.912689 -219.532005) (xy 348.912689 -219.480071) (xy 348.920814 -219.428776) (xy 348.936862 -219.379383)
			(xy 348.96044 -219.333109) (xy 348.990966 -219.291093) (xy 349.027689 -219.25437) (xy 349.069705 -219.223844)
			(xy 349.115979 -219.200266) (xy 349.165372 -219.184218) (xy 349.216667 -219.176093) (xy 349.268601 -219.176093)
			(xy 349.319896 -219.184218) (xy 349.369289 -219.200266) (xy 349.415563 -219.223844) (xy 349.457579 -219.25437)
			(xy 349.494302 -219.291093) (xy 349.524828 -219.333109) (xy 349.548406 -219.379383) (xy 349.564454 -219.428776)
			(xy 349.572579 -219.480071) (xy 349.573088 -219.506038) (xy 349.572579 -219.532005) (xy 349.564454 -219.5833)
			(xy 349.548406 -219.632693) (xy 349.524828 -219.678967) (xy 349.494302 -219.720983) (xy 349.457579 -219.757706)
			(xy 349.415563 -219.788232) (xy 349.369289 -219.81181) (xy 349.319896 -219.827858) (xy 349.268601 -219.835983)
			(xy 349.216667 -219.835983) (xy 349.165372 -219.827858) (xy 349.115979 -219.81181) (xy 349.069705 -219.788232)
			(xy 349.027689 -219.757706) (xy 348.990966 -219.720983) (xy 348.96044 -219.678967) (xy 348.936862 -219.632693)
			(xy 348.920814 -219.5833) (xy 348.912689 -219.532005) (xy 348.632779 -219.532005) (xy 348.624654 -219.5833)
			(xy 348.608606 -219.632693) (xy 348.585028 -219.678967) (xy 348.554502 -219.720983) (xy 348.517779 -219.757706)
			(xy 348.475763 -219.788232) (xy 348.429489 -219.81181) (xy 348.380096 -219.827858) (xy 348.328801 -219.835983)
			(xy 348.276867 -219.835983) (xy 348.225572 -219.827858) (xy 348.176179 -219.81181) (xy 348.129905 -219.788232)
			(xy 348.087889 -219.757706) (xy 348.051166 -219.720983) (xy 348.02064 -219.678967) (xy 347.997062 -219.632693)
			(xy 347.981014 -219.5833) (xy 347.972889 -219.532005) (xy 347.692979 -219.532005) (xy 347.684854 -219.5833)
			(xy 347.668806 -219.632693) (xy 347.645228 -219.678967) (xy 347.614702 -219.720983) (xy 347.577979 -219.757706)
			(xy 347.535963 -219.788232) (xy 347.489689 -219.81181) (xy 347.440296 -219.827858) (xy 347.389001 -219.835983)
			(xy 347.337067 -219.835983) (xy 347.285772 -219.827858) (xy 347.236379 -219.81181) (xy 347.190105 -219.788232)
			(xy 347.148089 -219.757706) (xy 347.111366 -219.720983) (xy 347.08084 -219.678967) (xy 347.057262 -219.632693)
			(xy 347.041214 -219.5833) (xy 347.033089 -219.532005) (xy 346.753179 -219.532005) (xy 346.745054 -219.5833)
			(xy 346.729006 -219.632693) (xy 346.705428 -219.678967) (xy 346.674902 -219.720983) (xy 346.638179 -219.757706)
			(xy 346.596163 -219.788232) (xy 346.549889 -219.81181) (xy 346.500496 -219.827858) (xy 346.449201 -219.835983)
			(xy 346.397267 -219.835983) (xy 346.345972 -219.827858) (xy 346.296579 -219.81181) (xy 346.250305 -219.788232)
			(xy 346.208289 -219.757706) (xy 346.171566 -219.720983) (xy 346.14104 -219.678967) (xy 346.117462 -219.632693)
			(xy 346.101414 -219.5833) (xy 346.093289 -219.532005) (xy 345.813379 -219.532005) (xy 345.805254 -219.5833)
			(xy 345.789206 -219.632693) (xy 345.765628 -219.678967) (xy 345.735102 -219.720983) (xy 345.698379 -219.757706)
			(xy 345.656363 -219.788232) (xy 345.610089 -219.81181) (xy 345.560696 -219.827858) (xy 345.509401 -219.835983)
			(xy 345.457467 -219.835983) (xy 345.406172 -219.827858) (xy 345.356779 -219.81181) (xy 345.310505 -219.788232)
			(xy 345.268489 -219.757706) (xy 345.231766 -219.720983) (xy 345.20124 -219.678967) (xy 345.177662 -219.632693)
			(xy 345.161614 -219.5833) (xy 345.153489 -219.532005) (xy 344.873579 -219.532005) (xy 344.865454 -219.5833)
			(xy 344.849406 -219.632693) (xy 344.825828 -219.678967) (xy 344.795302 -219.720983) (xy 344.758579 -219.757706)
			(xy 344.716563 -219.788232) (xy 344.670289 -219.81181) (xy 344.620896 -219.827858) (xy 344.569601 -219.835983)
			(xy 344.517667 -219.835983) (xy 344.466372 -219.827858) (xy 344.416979 -219.81181) (xy 344.370705 -219.788232)
			(xy 344.328689 -219.757706) (xy 344.291966 -219.720983) (xy 344.26144 -219.678967) (xy 344.237862 -219.632693)
			(xy 344.221814 -219.5833) (xy 344.213689 -219.532005) (xy 343.933779 -219.532005) (xy 343.925654 -219.5833)
			(xy 343.909606 -219.632693) (xy 343.886028 -219.678967) (xy 343.855502 -219.720983) (xy 343.818779 -219.757706)
			(xy 343.776763 -219.788232) (xy 343.730489 -219.81181) (xy 343.681096 -219.827858) (xy 343.629801 -219.835983)
			(xy 343.577867 -219.835983) (xy 343.526572 -219.827858) (xy 343.477179 -219.81181) (xy 343.430905 -219.788232)
			(xy 343.388889 -219.757706) (xy 343.352166 -219.720983) (xy 343.32164 -219.678967) (xy 343.298062 -219.632693)
			(xy 343.282014 -219.5833) (xy 343.273889 -219.532005) (xy 342.993979 -219.532005) (xy 342.985854 -219.5833)
			(xy 342.969806 -219.632693) (xy 342.946228 -219.678967) (xy 342.915702 -219.720983) (xy 342.878979 -219.757706)
			(xy 342.836963 -219.788232) (xy 342.790689 -219.81181) (xy 342.741296 -219.827858) (xy 342.690001 -219.835983)
			(xy 342.638067 -219.835983) (xy 342.586772 -219.827858) (xy 342.537379 -219.81181) (xy 342.491105 -219.788232)
			(xy 342.449089 -219.757706) (xy 342.412366 -219.720983) (xy 342.38184 -219.678967) (xy 342.358262 -219.632693)
			(xy 342.342214 -219.5833) (xy 342.334089 -219.532005) (xy 342.054179 -219.532005) (xy 342.046054 -219.5833)
			(xy 342.030006 -219.632693) (xy 342.006428 -219.678967) (xy 341.975902 -219.720983) (xy 341.939179 -219.757706)
			(xy 341.897163 -219.788232) (xy 341.850889 -219.81181) (xy 341.801496 -219.827858) (xy 341.750201 -219.835983)
			(xy 341.698267 -219.835983) (xy 341.646972 -219.827858) (xy 341.597579 -219.81181) (xy 341.551305 -219.788232)
			(xy 341.509289 -219.757706) (xy 341.472566 -219.720983) (xy 341.44204 -219.678967) (xy 341.418462 -219.632693)
			(xy 341.402414 -219.5833) (xy 341.394289 -219.532005) (xy 341.114379 -219.532005) (xy 341.106254 -219.5833)
			(xy 341.090206 -219.632693) (xy 341.066628 -219.678967) (xy 341.036102 -219.720983) (xy 340.999379 -219.757706)
			(xy 340.957363 -219.788232) (xy 340.911089 -219.81181) (xy 340.861696 -219.827858) (xy 340.810401 -219.835983)
			(xy 340.758467 -219.835983) (xy 340.707172 -219.827858) (xy 340.657779 -219.81181) (xy 340.611505 -219.788232)
			(xy 340.569489 -219.757706) (xy 340.532766 -219.720983) (xy 340.50224 -219.678967) (xy 340.478662 -219.632693)
			(xy 340.462614 -219.5833) (xy 340.454489 -219.532005) (xy 340.174579 -219.532005) (xy 340.166454 -219.5833)
			(xy 340.150406 -219.632693) (xy 340.126828 -219.678967) (xy 340.096302 -219.720983) (xy 340.059579 -219.757706)
			(xy 340.017563 -219.788232) (xy 339.971289 -219.81181) (xy 339.921896 -219.827858) (xy 339.870601 -219.835983)
			(xy 339.818667 -219.835983) (xy 339.767372 -219.827858) (xy 339.717979 -219.81181) (xy 339.671705 -219.788232)
			(xy 339.629689 -219.757706) (xy 339.592966 -219.720983) (xy 339.56244 -219.678967) (xy 339.538862 -219.632693)
			(xy 339.522814 -219.5833) (xy 339.514689 -219.532005) (xy 339.234779 -219.532005) (xy 339.226654 -219.5833)
			(xy 339.210606 -219.632693) (xy 339.187028 -219.678967) (xy 339.156502 -219.720983) (xy 339.119779 -219.757706)
			(xy 339.077763 -219.788232) (xy 339.031489 -219.81181) (xy 338.982096 -219.827858) (xy 338.930801 -219.835983)
			(xy 338.878867 -219.835983) (xy 338.827572 -219.827858) (xy 338.778179 -219.81181) (xy 338.731905 -219.788232)
			(xy 338.689889 -219.757706) (xy 338.653166 -219.720983) (xy 338.62264 -219.678967) (xy 338.599062 -219.632693)
			(xy 338.583014 -219.5833) (xy 338.574889 -219.532005) (xy 338.294979 -219.532005) (xy 338.286854 -219.5833)
			(xy 338.270806 -219.632693) (xy 338.247228 -219.678967) (xy 338.216702 -219.720983) (xy 338.179979 -219.757706)
			(xy 338.137963 -219.788232) (xy 338.091689 -219.81181) (xy 338.042296 -219.827858) (xy 337.991001 -219.835983)
			(xy 337.939067 -219.835983) (xy 337.887772 -219.827858) (xy 337.838379 -219.81181) (xy 337.792105 -219.788232)
			(xy 337.750089 -219.757706) (xy 337.713366 -219.720983) (xy 337.68284 -219.678967) (xy 337.659262 -219.632693)
			(xy 337.643214 -219.5833) (xy 337.635089 -219.532005) (xy 337.355179 -219.532005) (xy 337.347054 -219.5833)
			(xy 337.331006 -219.632693) (xy 337.307428 -219.678967) (xy 337.276902 -219.720983) (xy 337.240179 -219.757706)
			(xy 337.198163 -219.788232) (xy 337.151889 -219.81181) (xy 337.102496 -219.827858) (xy 337.051201 -219.835983)
			(xy 336.999267 -219.835983) (xy 336.947972 -219.827858) (xy 336.898579 -219.81181) (xy 336.852305 -219.788232)
			(xy 336.810289 -219.757706) (xy 336.773566 -219.720983) (xy 336.74304 -219.678967) (xy 336.719462 -219.632693)
			(xy 336.703414 -219.5833) (xy 336.695289 -219.532005) (xy 336.415335 -219.532005) (xy 336.415335 -219.532544)
			(xy 336.406856 -219.584917) (xy 336.390118 -219.635263) (xy 336.365551 -219.682287) (xy 336.333786 -219.724783)
			(xy 336.295641 -219.761657) (xy 336.252093 -219.791963) (xy 336.228436 -219.80398) (xy 336.19948 -219.81795)
			(xy 336.19948 -219.970604) (xy 336.19991 -219.984603) (xy 336.207493 -220.011554) (xy 336.222116 -220.035429)
			(xy 336.242677 -220.054432) (xy 336.267629 -220.067131) (xy 336.295093 -220.072571) (xy 336.323001 -220.070342)
			(xy 336.349254 -220.060612) (xy 336.36077 -220.052646) (xy 336.382084 -220.03778) (xy 336.428373 -220.014171)
			(xy 336.477783 -219.998084) (xy 336.529099 -219.989915) (xy 336.55508 -219.9894) (xy 336.555334 -219.9894)
			(xy 336.581303 -219.989912) (xy 336.632601 -219.998042) (xy 336.681996 -220.014095) (xy 336.728272 -220.037678)
			(xy 336.770289 -220.068209) (xy 336.807013 -220.104937) (xy 336.83754 -220.146957) (xy 336.861118 -220.193235)
			(xy 336.877166 -220.242632) (xy 336.885291 -220.293931) (xy 336.885291 -220.345821) (xy 337.165189 -220.345821)
			(xy 337.165189 -220.293887) (xy 337.173314 -220.242592) (xy 337.189362 -220.193199) (xy 337.21294 -220.146925)
			(xy 337.243466 -220.104909) (xy 337.280189 -220.068186) (xy 337.322205 -220.03766) (xy 337.368479 -220.014082)
			(xy 337.417872 -219.998034) (xy 337.469167 -219.989909) (xy 337.521101 -219.989909) (xy 337.572396 -219.998034)
			(xy 337.621789 -220.014082) (xy 337.668063 -220.03766) (xy 337.710079 -220.068186) (xy 337.746802 -220.104909)
			(xy 337.777328 -220.146925) (xy 337.800906 -220.193199) (xy 337.816954 -220.242592) (xy 337.825079 -220.293887)
			(xy 337.825588 -220.319854) (xy 337.825079 -220.345821) (xy 337.816954 -220.397116) (xy 337.800906 -220.446509)
			(xy 337.777328 -220.492783) (xy 337.746802 -220.534799) (xy 337.710079 -220.571522) (xy 337.668063 -220.602048)
			(xy 337.621789 -220.625626) (xy 337.572396 -220.641674) (xy 337.521101 -220.649799) (xy 337.469167 -220.649799)
			(xy 337.417872 -220.641674) (xy 337.368479 -220.625626) (xy 337.322205 -220.602048) (xy 337.280189 -220.571522)
			(xy 337.243466 -220.534799) (xy 337.21294 -220.492783) (xy 337.189362 -220.446509) (xy 337.173314 -220.397116)
			(xy 337.165189 -220.345821) (xy 336.885291 -220.345821) (xy 336.885291 -220.345869) (xy 336.877166 -220.397168)
			(xy 336.861118 -220.446565) (xy 336.83754 -220.492843) (xy 336.807013 -220.534863) (xy 336.770289 -220.571591)
			(xy 336.728272 -220.602122) (xy 336.681996 -220.625705) (xy 336.632601 -220.641758) (xy 336.581303 -220.649888)
			(xy 336.555334 -220.650308) (xy 336.55508 -220.650308) (xy 336.529095 -220.649827) (xy 336.477765 -220.641689)
			(xy 336.428348 -220.625601) (xy 336.382065 -220.601962) (xy 336.36077 -220.587062) (xy 336.3492 -220.579209)
			(xy 336.322972 -220.569542) (xy 336.295105 -220.567349) (xy 336.267687 -220.572793) (xy 336.242772 -220.585467)
			(xy 336.222227 -220.604422) (xy 336.207591 -220.628237) (xy 336.19996 -220.655128) (xy 336.19948 -220.669104)
			(xy 336.19948 -220.822012) (xy 336.228436 -220.835982) (xy 336.252123 -220.847939) (xy 336.295669 -220.87825)
			(xy 336.333814 -220.915129) (xy 336.365576 -220.957629) (xy 336.39014 -221.004657) (xy 336.406874 -221.055006)
			(xy 336.41535 -221.107382) (xy 336.415349 -221.133924) (xy 336.69478 -221.133924) (xy 336.695289 -221.107957)
			(xy 336.703414 -221.056662) (xy 336.719462 -221.007269) (xy 336.74304 -220.960995) (xy 336.773566 -220.918979)
			(xy 336.810289 -220.882256) (xy 336.852305 -220.85173) (xy 336.898579 -220.828152) (xy 336.947972 -220.812104)
			(xy 336.999267 -220.803979) (xy 337.051201 -220.803979) (xy 337.102496 -220.812104) (xy 337.151889 -220.828152)
			(xy 337.198163 -220.85173) (xy 337.240179 -220.882256) (xy 337.276902 -220.918979) (xy 337.307428 -220.960995)
			(xy 337.331006 -221.007269) (xy 337.347054 -221.056662) (xy 337.355179 -221.107957) (xy 337.355688 -221.133924)
			(xy 337.63458 -221.133924) (xy 337.634971 -221.108469) (xy 337.642761 -221.05816) (xy 337.658176 -221.009641)
			(xy 337.680851 -220.964061) (xy 337.710249 -220.922499) (xy 337.745675 -220.885938) (xy 337.78629 -220.855244)
			(xy 337.831132 -220.831143) (xy 337.879141 -220.814206) (xy 337.904074 -220.809058) (xy 337.926934 -220.80474)
			(xy 338.130642 -220.45168) (xy 338.123022 -220.429582) (xy 338.114281 -220.402995) (xy 338.104835 -220.347835)
			(xy 338.104226 -220.319854) (xy 338.104735 -220.293887) (xy 338.11286 -220.242592) (xy 338.128908 -220.193199)
			(xy 338.152486 -220.146925) (xy 338.183012 -220.104909) (xy 338.219735 -220.068186) (xy 338.261751 -220.03766)
			(xy 338.308025 -220.014082) (xy 338.357418 -219.998034) (xy 338.408713 -219.989909) (xy 338.460647 -219.989909)
			(xy 338.511942 -219.998034) (xy 338.561335 -220.014082) (xy 338.607609 -220.03766) (xy 338.649625 -220.068186)
			(xy 338.686348 -220.104909) (xy 338.716874 -220.146925) (xy 338.740452 -220.193199) (xy 338.7565 -220.242592)
			(xy 338.764625 -220.293887) (xy 338.765134 -220.319854) (xy 338.764712 -220.345307) (xy 338.764632 -220.345821)
			(xy 339.044789 -220.345821) (xy 339.044789 -220.293887) (xy 339.052914 -220.242592) (xy 339.068962 -220.193199)
			(xy 339.09254 -220.146925) (xy 339.123066 -220.104909) (xy 339.159789 -220.068186) (xy 339.201805 -220.03766)
			(xy 339.248079 -220.014082) (xy 339.297472 -219.998034) (xy 339.348767 -219.989909) (xy 339.400701 -219.989909)
			(xy 339.451996 -219.998034) (xy 339.501389 -220.014082) (xy 339.547663 -220.03766) (xy 339.589679 -220.068186)
			(xy 339.626402 -220.104909) (xy 339.656928 -220.146925) (xy 339.680506 -220.193199) (xy 339.696554 -220.242592)
			(xy 339.704679 -220.293887) (xy 339.705188 -220.319854) (xy 339.704679 -220.345821) (xy 339.696554 -220.397116)
			(xy 339.680506 -220.446509) (xy 339.656928 -220.492783) (xy 339.626402 -220.534799) (xy 339.589679 -220.571522)
			(xy 339.547663 -220.602048) (xy 339.501389 -220.625626) (xy 339.451996 -220.641674) (xy 339.400701 -220.649799)
			(xy 339.348767 -220.649799) (xy 339.297472 -220.641674) (xy 339.248079 -220.625626) (xy 339.201805 -220.602048)
			(xy 339.159789 -220.571522) (xy 339.123066 -220.534799) (xy 339.09254 -220.492783) (xy 339.068962 -220.446509)
			(xy 339.052914 -220.397116) (xy 339.044789 -220.345821) (xy 338.764632 -220.345821) (xy 338.756926 -220.395615)
			(xy 338.741514 -220.444132) (xy 338.718843 -220.489711) (xy 338.689449 -220.531273) (xy 338.654027 -220.567835)
			(xy 338.613416 -220.59853) (xy 338.568577 -220.622632) (xy 338.520571 -220.639571) (xy 338.49564 -220.64472)
			(xy 338.47278 -220.649038) (xy 338.269072 -221.002098) (xy 338.276692 -221.024196) (xy 338.285429 -221.050785)
			(xy 338.294877 -221.105944) (xy 338.295488 -221.133924) (xy 338.57438 -221.133924) (xy 338.574889 -221.107957)
			(xy 338.583014 -221.056662) (xy 338.599062 -221.007269) (xy 338.62264 -220.960995) (xy 338.653166 -220.918979)
			(xy 338.689889 -220.882256) (xy 338.731905 -220.85173) (xy 338.778179 -220.828152) (xy 338.827572 -220.812104)
			(xy 338.878867 -220.803979) (xy 338.930801 -220.803979) (xy 338.982096 -220.812104) (xy 339.031489 -220.828152)
			(xy 339.077763 -220.85173) (xy 339.119779 -220.882256) (xy 339.156502 -220.918979) (xy 339.187028 -220.960995)
			(xy 339.210606 -221.007269) (xy 339.226654 -221.056662) (xy 339.234779 -221.107957) (xy 339.235288 -221.133924)
			(xy 339.51418 -221.133924) (xy 339.514571 -221.108469) (xy 339.522361 -221.05816) (xy 339.537776 -221.009641)
			(xy 339.560451 -220.964061) (xy 339.589849 -220.922499) (xy 339.625275 -220.885938) (xy 339.66589 -220.855244)
			(xy 339.710732 -220.831143) (xy 339.758741 -220.814206) (xy 339.783674 -220.809058) (xy 339.806534 -220.80474)
			(xy 340.010242 -220.45168) (xy 340.002622 -220.429582) (xy 339.993881 -220.402995) (xy 339.984435 -220.347835)
			(xy 339.983826 -220.319854) (xy 339.984335 -220.293887) (xy 339.99246 -220.242592) (xy 340.008508 -220.193199)
			(xy 340.032086 -220.146925) (xy 340.062612 -220.104909) (xy 340.099335 -220.068186) (xy 340.141351 -220.03766)
			(xy 340.187625 -220.014082) (xy 340.237018 -219.998034) (xy 340.288313 -219.989909) (xy 340.340247 -219.989909)
			(xy 340.391542 -219.998034) (xy 340.440935 -220.014082) (xy 340.487209 -220.03766) (xy 340.529225 -220.068186)
			(xy 340.565948 -220.104909) (xy 340.596474 -220.146925) (xy 340.620052 -220.193199) (xy 340.6361 -220.242592)
			(xy 340.644225 -220.293887) (xy 340.644734 -220.319854) (xy 340.644312 -220.345307) (xy 340.644232 -220.345821)
			(xy 340.924389 -220.345821) (xy 340.924389 -220.293887) (xy 340.932514 -220.242592) (xy 340.948562 -220.193199)
			(xy 340.97214 -220.146925) (xy 341.002666 -220.104909) (xy 341.039389 -220.068186) (xy 341.081405 -220.03766)
			(xy 341.127679 -220.014082) (xy 341.177072 -219.998034) (xy 341.228367 -219.989909) (xy 341.280301 -219.989909)
			(xy 341.331596 -219.998034) (xy 341.380989 -220.014082) (xy 341.427263 -220.03766) (xy 341.469279 -220.068186)
			(xy 341.506002 -220.104909) (xy 341.536528 -220.146925) (xy 341.560106 -220.193199) (xy 341.576154 -220.242592)
			(xy 341.584279 -220.293887) (xy 341.584788 -220.319854) (xy 341.584279 -220.345821) (xy 341.576154 -220.397116)
			(xy 341.560106 -220.446509) (xy 341.536528 -220.492783) (xy 341.506002 -220.534799) (xy 341.469279 -220.571522)
			(xy 341.427263 -220.602048) (xy 341.380989 -220.625626) (xy 341.331596 -220.641674) (xy 341.280301 -220.649799)
			(xy 341.228367 -220.649799) (xy 341.177072 -220.641674) (xy 341.127679 -220.625626) (xy 341.081405 -220.602048)
			(xy 341.039389 -220.571522) (xy 341.002666 -220.534799) (xy 340.97214 -220.492783) (xy 340.948562 -220.446509)
			(xy 340.932514 -220.397116) (xy 340.924389 -220.345821) (xy 340.644232 -220.345821) (xy 340.636526 -220.395615)
			(xy 340.621114 -220.444132) (xy 340.598443 -220.489711) (xy 340.569049 -220.531273) (xy 340.533627 -220.567835)
			(xy 340.493016 -220.59853) (xy 340.448177 -220.622632) (xy 340.400171 -220.639571) (xy 340.37524 -220.64472)
			(xy 340.35238 -220.649038) (xy 340.148672 -221.002098) (xy 340.156292 -221.024196) (xy 340.165029 -221.050785)
			(xy 340.174477 -221.105944) (xy 340.175088 -221.133924) (xy 340.45398 -221.133924) (xy 340.454489 -221.107957)
			(xy 340.462614 -221.056662) (xy 340.478662 -221.007269) (xy 340.50224 -220.960995) (xy 340.532766 -220.918979)
			(xy 340.569489 -220.882256) (xy 340.611505 -220.85173) (xy 340.657779 -220.828152) (xy 340.707172 -220.812104)
			(xy 340.758467 -220.803979) (xy 340.810401 -220.803979) (xy 340.861696 -220.812104) (xy 340.911089 -220.828152)
			(xy 340.957363 -220.85173) (xy 340.999379 -220.882256) (xy 341.036102 -220.918979) (xy 341.066628 -220.960995)
			(xy 341.090206 -221.007269) (xy 341.106254 -221.056662) (xy 341.114379 -221.107957) (xy 341.114888 -221.133924)
			(xy 341.39378 -221.133924) (xy 341.394171 -221.108469) (xy 341.401961 -221.05816) (xy 341.417376 -221.009641)
			(xy 341.440051 -220.964061) (xy 341.469449 -220.922499) (xy 341.504875 -220.885938) (xy 341.54549 -220.855244)
			(xy 341.590332 -220.831143) (xy 341.638341 -220.814206) (xy 341.663274 -220.809058) (xy 341.686134 -220.80474)
			(xy 341.889842 -220.45168) (xy 341.882222 -220.429582) (xy 341.873481 -220.402995) (xy 341.864035 -220.347835)
			(xy 341.863426 -220.319854) (xy 341.863935 -220.293887) (xy 341.87206 -220.242592) (xy 341.888108 -220.193199)
			(xy 341.911686 -220.146925) (xy 341.942212 -220.104909) (xy 341.978935 -220.068186) (xy 342.020951 -220.03766)
			(xy 342.067225 -220.014082) (xy 342.116618 -219.998034) (xy 342.167913 -219.989909) (xy 342.219847 -219.989909)
			(xy 342.271142 -219.998034) (xy 342.320535 -220.014082) (xy 342.366809 -220.03766) (xy 342.408825 -220.068186)
			(xy 342.445548 -220.104909) (xy 342.476074 -220.146925) (xy 342.499652 -220.193199) (xy 342.5157 -220.242592)
			(xy 342.523825 -220.293887) (xy 342.524334 -220.319854) (xy 342.523912 -220.345307) (xy 342.523832 -220.345821)
			(xy 342.803989 -220.345821) (xy 342.803989 -220.293887) (xy 342.812114 -220.242592) (xy 342.828162 -220.193199)
			(xy 342.85174 -220.146925) (xy 342.882266 -220.104909) (xy 342.918989 -220.068186) (xy 342.961005 -220.03766)
			(xy 343.007279 -220.014082) (xy 343.056672 -219.998034) (xy 343.107967 -219.989909) (xy 343.159901 -219.989909)
			(xy 343.211196 -219.998034) (xy 343.260589 -220.014082) (xy 343.306863 -220.03766) (xy 343.348879 -220.068186)
			(xy 343.385602 -220.104909) (xy 343.416128 -220.146925) (xy 343.439706 -220.193199) (xy 343.455754 -220.242592)
			(xy 343.463879 -220.293887) (xy 343.464388 -220.319854) (xy 343.463879 -220.345821) (xy 343.455754 -220.397116)
			(xy 343.439706 -220.446509) (xy 343.416128 -220.492783) (xy 343.385602 -220.534799) (xy 343.348879 -220.571522)
			(xy 343.306863 -220.602048) (xy 343.260589 -220.625626) (xy 343.211196 -220.641674) (xy 343.159901 -220.649799)
			(xy 343.107967 -220.649799) (xy 343.056672 -220.641674) (xy 343.007279 -220.625626) (xy 342.961005 -220.602048)
			(xy 342.918989 -220.571522) (xy 342.882266 -220.534799) (xy 342.85174 -220.492783) (xy 342.828162 -220.446509)
			(xy 342.812114 -220.397116) (xy 342.803989 -220.345821) (xy 342.523832 -220.345821) (xy 342.516126 -220.395615)
			(xy 342.500714 -220.444132) (xy 342.478043 -220.489711) (xy 342.448649 -220.531273) (xy 342.413227 -220.567835)
			(xy 342.372616 -220.59853) (xy 342.327777 -220.622632) (xy 342.279771 -220.639571) (xy 342.25484 -220.64472)
			(xy 342.23198 -220.649038) (xy 342.028272 -221.002098) (xy 342.035892 -221.024196) (xy 342.044629 -221.050785)
			(xy 342.054077 -221.105944) (xy 342.054688 -221.133924) (xy 342.33358 -221.133924) (xy 342.334089 -221.107957)
			(xy 342.342214 -221.056662) (xy 342.358262 -221.007269) (xy 342.38184 -220.960995) (xy 342.412366 -220.918979)
			(xy 342.449089 -220.882256) (xy 342.491105 -220.85173) (xy 342.537379 -220.828152) (xy 342.586772 -220.812104)
			(xy 342.638067 -220.803979) (xy 342.690001 -220.803979) (xy 342.741296 -220.812104) (xy 342.790689 -220.828152)
			(xy 342.836963 -220.85173) (xy 342.878979 -220.882256) (xy 342.915702 -220.918979) (xy 342.946228 -220.960995)
			(xy 342.969806 -221.007269) (xy 342.985854 -221.056662) (xy 342.993979 -221.107957) (xy 342.994488 -221.133924)
			(xy 343.27338 -221.133924) (xy 343.273771 -221.108469) (xy 343.281561 -221.05816) (xy 343.296976 -221.009641)
			(xy 343.319651 -220.964061) (xy 343.349049 -220.922499) (xy 343.384475 -220.885938) (xy 343.42509 -220.855244)
			(xy 343.469932 -220.831143) (xy 343.517941 -220.814206) (xy 343.542874 -220.809058) (xy 343.565734 -220.80474)
			(xy 343.769442 -220.45168) (xy 343.761822 -220.429582) (xy 343.753081 -220.402995) (xy 343.743635 -220.347835)
			(xy 343.743026 -220.319854) (xy 343.743535 -220.293887) (xy 343.75166 -220.242592) (xy 343.767708 -220.193199)
			(xy 343.791286 -220.146925) (xy 343.821812 -220.104909) (xy 343.858535 -220.068186) (xy 343.900551 -220.03766)
			(xy 343.946825 -220.014082) (xy 343.996218 -219.998034) (xy 344.047513 -219.989909) (xy 344.099447 -219.989909)
			(xy 344.150742 -219.998034) (xy 344.200135 -220.014082) (xy 344.246409 -220.03766) (xy 344.288425 -220.068186)
			(xy 344.325148 -220.104909) (xy 344.355674 -220.146925) (xy 344.379252 -220.193199) (xy 344.3953 -220.242592)
			(xy 344.403425 -220.293887) (xy 344.403934 -220.319854) (xy 344.403512 -220.345307) (xy 344.403432 -220.345821)
			(xy 344.683589 -220.345821) (xy 344.683589 -220.293887) (xy 344.691714 -220.242592) (xy 344.707762 -220.193199)
			(xy 344.73134 -220.146925) (xy 344.761866 -220.104909) (xy 344.798589 -220.068186) (xy 344.840605 -220.03766)
			(xy 344.886879 -220.014082) (xy 344.936272 -219.998034) (xy 344.987567 -219.989909) (xy 345.039501 -219.989909)
			(xy 345.090796 -219.998034) (xy 345.140189 -220.014082) (xy 345.186463 -220.03766) (xy 345.228479 -220.068186)
			(xy 345.265202 -220.104909) (xy 345.295728 -220.146925) (xy 345.319306 -220.193199) (xy 345.335354 -220.242592)
			(xy 345.343479 -220.293887) (xy 345.343988 -220.319854) (xy 345.343479 -220.345821) (xy 345.335354 -220.397116)
			(xy 345.319306 -220.446509) (xy 345.295728 -220.492783) (xy 345.265202 -220.534799) (xy 345.228479 -220.571522)
			(xy 345.186463 -220.602048) (xy 345.140189 -220.625626) (xy 345.090796 -220.641674) (xy 345.039501 -220.649799)
			(xy 344.987567 -220.649799) (xy 344.936272 -220.641674) (xy 344.886879 -220.625626) (xy 344.840605 -220.602048)
			(xy 344.798589 -220.571522) (xy 344.761866 -220.534799) (xy 344.73134 -220.492783) (xy 344.707762 -220.446509)
			(xy 344.691714 -220.397116) (xy 344.683589 -220.345821) (xy 344.403432 -220.345821) (xy 344.395726 -220.395615)
			(xy 344.380314 -220.444132) (xy 344.357643 -220.489711) (xy 344.328249 -220.531273) (xy 344.292827 -220.567835)
			(xy 344.252216 -220.59853) (xy 344.207377 -220.622632) (xy 344.159371 -220.639571) (xy 344.13444 -220.64472)
			(xy 344.11158 -220.649038) (xy 343.907872 -221.002098) (xy 343.915492 -221.024196) (xy 343.924229 -221.050785)
			(xy 343.933677 -221.105944) (xy 343.934288 -221.133924) (xy 344.21318 -221.133924) (xy 344.213689 -221.107957)
			(xy 344.221814 -221.056662) (xy 344.237862 -221.007269) (xy 344.26144 -220.960995) (xy 344.291966 -220.918979)
			(xy 344.328689 -220.882256) (xy 344.370705 -220.85173) (xy 344.416979 -220.828152) (xy 344.466372 -220.812104)
			(xy 344.517667 -220.803979) (xy 344.569601 -220.803979) (xy 344.620896 -220.812104) (xy 344.670289 -220.828152)
			(xy 344.716563 -220.85173) (xy 344.758579 -220.882256) (xy 344.795302 -220.918979) (xy 344.825828 -220.960995)
			(xy 344.849406 -221.007269) (xy 344.865454 -221.056662) (xy 344.873579 -221.107957) (xy 344.874088 -221.133924)
			(xy 345.15298 -221.133924) (xy 345.153371 -221.108469) (xy 345.161161 -221.05816) (xy 345.176576 -221.009641)
			(xy 345.199251 -220.964061) (xy 345.228649 -220.922499) (xy 345.264075 -220.885938) (xy 345.30469 -220.855244)
			(xy 345.349532 -220.831143) (xy 345.397541 -220.814206) (xy 345.422474 -220.809058) (xy 345.445334 -220.80474)
			(xy 345.649042 -220.45168) (xy 345.641422 -220.429582) (xy 345.632681 -220.402995) (xy 345.623235 -220.347835)
			(xy 345.622626 -220.319854) (xy 345.623135 -220.293887) (xy 345.63126 -220.242592) (xy 345.647308 -220.193199)
			(xy 345.670886 -220.146925) (xy 345.701412 -220.104909) (xy 345.738135 -220.068186) (xy 345.780151 -220.03766)
			(xy 345.826425 -220.014082) (xy 345.875818 -219.998034) (xy 345.927113 -219.989909) (xy 345.979047 -219.989909)
			(xy 346.030342 -219.998034) (xy 346.079735 -220.014082) (xy 346.126009 -220.03766) (xy 346.168025 -220.068186)
			(xy 346.204748 -220.104909) (xy 346.235274 -220.146925) (xy 346.258852 -220.193199) (xy 346.2749 -220.242592)
			(xy 346.283025 -220.293887) (xy 346.283534 -220.319854) (xy 346.283112 -220.345307) (xy 346.283032 -220.345821)
			(xy 346.563189 -220.345821) (xy 346.563189 -220.293887) (xy 346.571314 -220.242592) (xy 346.587362 -220.193199)
			(xy 346.61094 -220.146925) (xy 346.641466 -220.104909) (xy 346.678189 -220.068186) (xy 346.720205 -220.03766)
			(xy 346.766479 -220.014082) (xy 346.815872 -219.998034) (xy 346.867167 -219.989909) (xy 346.919101 -219.989909)
			(xy 346.970396 -219.998034) (xy 347.019789 -220.014082) (xy 347.066063 -220.03766) (xy 347.108079 -220.068186)
			(xy 347.144802 -220.104909) (xy 347.175328 -220.146925) (xy 347.198906 -220.193199) (xy 347.214954 -220.242592)
			(xy 347.223079 -220.293887) (xy 347.223588 -220.319854) (xy 347.223079 -220.345821) (xy 347.214954 -220.397116)
			(xy 347.198906 -220.446509) (xy 347.175328 -220.492783) (xy 347.144802 -220.534799) (xy 347.108079 -220.571522)
			(xy 347.066063 -220.602048) (xy 347.019789 -220.625626) (xy 346.970396 -220.641674) (xy 346.919101 -220.649799)
			(xy 346.867167 -220.649799) (xy 346.815872 -220.641674) (xy 346.766479 -220.625626) (xy 346.720205 -220.602048)
			(xy 346.678189 -220.571522) (xy 346.641466 -220.534799) (xy 346.61094 -220.492783) (xy 346.587362 -220.446509)
			(xy 346.571314 -220.397116) (xy 346.563189 -220.345821) (xy 346.283032 -220.345821) (xy 346.275326 -220.395615)
			(xy 346.259914 -220.444132) (xy 346.237243 -220.489711) (xy 346.207849 -220.531273) (xy 346.172427 -220.567835)
			(xy 346.131816 -220.59853) (xy 346.086977 -220.622632) (xy 346.038971 -220.639571) (xy 346.01404 -220.64472)
			(xy 345.99118 -220.649038) (xy 345.787472 -221.002098) (xy 345.795092 -221.024196) (xy 345.803829 -221.050785)
			(xy 345.813277 -221.105944) (xy 345.813888 -221.133924) (xy 346.09278 -221.133924) (xy 346.093289 -221.107957)
			(xy 346.101414 -221.056662) (xy 346.117462 -221.007269) (xy 346.14104 -220.960995) (xy 346.171566 -220.918979)
			(xy 346.208289 -220.882256) (xy 346.250305 -220.85173) (xy 346.296579 -220.828152) (xy 346.345972 -220.812104)
			(xy 346.397267 -220.803979) (xy 346.449201 -220.803979) (xy 346.500496 -220.812104) (xy 346.549889 -220.828152)
			(xy 346.596163 -220.85173) (xy 346.638179 -220.882256) (xy 346.674902 -220.918979) (xy 346.705428 -220.960995)
			(xy 346.729006 -221.007269) (xy 346.745054 -221.056662) (xy 346.753179 -221.107957) (xy 346.753688 -221.133924)
			(xy 347.03258 -221.133924) (xy 347.032971 -221.108469) (xy 347.040761 -221.05816) (xy 347.056176 -221.009641)
			(xy 347.078851 -220.964061) (xy 347.108249 -220.922499) (xy 347.143675 -220.885938) (xy 347.18429 -220.855244)
			(xy 347.229132 -220.831143) (xy 347.277141 -220.814206) (xy 347.302074 -220.809058) (xy 347.324934 -220.80474)
			(xy 347.528642 -220.45168) (xy 347.521022 -220.429582) (xy 347.512281 -220.402995) (xy 347.502835 -220.347835)
			(xy 347.502226 -220.319854) (xy 347.502735 -220.293887) (xy 347.51086 -220.242592) (xy 347.526908 -220.193199)
			(xy 347.550486 -220.146925) (xy 347.581012 -220.104909) (xy 347.617735 -220.068186) (xy 347.659751 -220.03766)
			(xy 347.706025 -220.014082) (xy 347.755418 -219.998034) (xy 347.806713 -219.989909) (xy 347.858647 -219.989909)
			(xy 347.909942 -219.998034) (xy 347.959335 -220.014082) (xy 348.005609 -220.03766) (xy 348.047625 -220.068186)
			(xy 348.084348 -220.104909) (xy 348.114874 -220.146925) (xy 348.138452 -220.193199) (xy 348.1545 -220.242592)
			(xy 348.162625 -220.293887) (xy 348.163134 -220.319854) (xy 348.162712 -220.345307) (xy 348.162632 -220.345821)
			(xy 348.442789 -220.345821) (xy 348.442789 -220.293887) (xy 348.450914 -220.242592) (xy 348.466962 -220.193199)
			(xy 348.49054 -220.146925) (xy 348.521066 -220.104909) (xy 348.557789 -220.068186) (xy 348.599805 -220.03766)
			(xy 348.646079 -220.014082) (xy 348.695472 -219.998034) (xy 348.746767 -219.989909) (xy 348.798701 -219.989909)
			(xy 348.849996 -219.998034) (xy 348.899389 -220.014082) (xy 348.945663 -220.03766) (xy 348.987679 -220.068186)
			(xy 349.024402 -220.104909) (xy 349.054928 -220.146925) (xy 349.078506 -220.193199) (xy 349.094554 -220.242592)
			(xy 349.102679 -220.293887) (xy 349.103188 -220.319854) (xy 349.102679 -220.345821) (xy 349.094554 -220.397116)
			(xy 349.078506 -220.446509) (xy 349.054928 -220.492783) (xy 349.024402 -220.534799) (xy 348.987679 -220.571522)
			(xy 348.945663 -220.602048) (xy 348.899389 -220.625626) (xy 348.849996 -220.641674) (xy 348.798701 -220.649799)
			(xy 348.746767 -220.649799) (xy 348.695472 -220.641674) (xy 348.646079 -220.625626) (xy 348.599805 -220.602048)
			(xy 348.557789 -220.571522) (xy 348.521066 -220.534799) (xy 348.49054 -220.492783) (xy 348.466962 -220.446509)
			(xy 348.450914 -220.397116) (xy 348.442789 -220.345821) (xy 348.162632 -220.345821) (xy 348.154926 -220.395615)
			(xy 348.139514 -220.444132) (xy 348.116843 -220.489711) (xy 348.087449 -220.531273) (xy 348.052027 -220.567835)
			(xy 348.011416 -220.59853) (xy 347.966577 -220.622632) (xy 347.918571 -220.639571) (xy 347.89364 -220.64472)
			(xy 347.87078 -220.649038) (xy 347.667072 -221.002098) (xy 347.674692 -221.024196) (xy 347.683429 -221.050785)
			(xy 347.692877 -221.105944) (xy 347.693488 -221.133924) (xy 347.97238 -221.133924) (xy 347.972889 -221.107957)
			(xy 347.981014 -221.056662) (xy 347.997062 -221.007269) (xy 348.02064 -220.960995) (xy 348.051166 -220.918979)
			(xy 348.087889 -220.882256) (xy 348.129905 -220.85173) (xy 348.176179 -220.828152) (xy 348.225572 -220.812104)
			(xy 348.276867 -220.803979) (xy 348.328801 -220.803979) (xy 348.380096 -220.812104) (xy 348.429489 -220.828152)
			(xy 348.475763 -220.85173) (xy 348.517779 -220.882256) (xy 348.554502 -220.918979) (xy 348.585028 -220.960995)
			(xy 348.608606 -221.007269) (xy 348.624654 -221.056662) (xy 348.632779 -221.107957) (xy 348.633288 -221.133924)
			(xy 348.632742 -221.16191) (xy 348.623287 -221.217078) (xy 348.614492 -221.243652) (xy 348.606872 -221.26575)
			(xy 348.81058 -221.618556) (xy 348.83344 -221.622874) (xy 348.858363 -221.628034) (xy 348.906348 -221.644999)
			(xy 348.951166 -221.669118) (xy 348.991759 -221.699819) (xy 349.027168 -221.736378) (xy 349.056556 -221.777931)
			(xy 349.07923 -221.823497) (xy 349.094653 -221.871999) (xy 349.102461 -221.922292) (xy 349.102934 -221.94774)
			(xy 349.102425 -221.973707) (xy 349.0943 -222.025002) (xy 349.078252 -222.074395) (xy 349.054674 -222.120669)
			(xy 349.024148 -222.162685) (xy 348.987425 -222.199408) (xy 348.945409 -222.229934) (xy 348.899135 -222.253512)
			(xy 348.849742 -222.26956) (xy 348.798447 -222.277685) (xy 348.746513 -222.277685) (xy 348.695218 -222.26956)
			(xy 348.645825 -222.253512) (xy 348.599551 -222.229934) (xy 348.557535 -222.199408) (xy 348.520812 -222.162685)
			(xy 348.490286 -222.120669) (xy 348.466708 -222.074395) (xy 348.45066 -222.025002) (xy 348.442535 -221.973707)
			(xy 348.442026 -221.94774) (xy 348.442587 -221.919755) (xy 348.452031 -221.864587) (xy 348.460822 -221.838012)
			(xy 348.468442 -221.815914) (xy 348.264734 -221.463108) (xy 348.241874 -221.45879) (xy 348.216945 -221.453653)
			(xy 348.168958 -221.436688) (xy 348.124137 -221.412568) (xy 348.083543 -221.381864) (xy 348.048134 -221.345302)
			(xy 348.018746 -221.303745) (xy 347.996074 -221.258175) (xy 347.980654 -221.209669) (xy 347.97285 -221.159373)
			(xy 347.97238 -221.133924) (xy 347.693488 -221.133924) (xy 347.692979 -221.159891) (xy 347.684854 -221.211186)
			(xy 347.668806 -221.260579) (xy 347.645228 -221.306853) (xy 347.614702 -221.348869) (xy 347.577979 -221.385592)
			(xy 347.535963 -221.416118) (xy 347.489689 -221.439696) (xy 347.440296 -221.455744) (xy 347.389001 -221.463869)
			(xy 347.337067 -221.463869) (xy 347.285772 -221.455744) (xy 347.236379 -221.439696) (xy 347.190105 -221.416118)
			(xy 347.148089 -221.385592) (xy 347.111366 -221.348869) (xy 347.08084 -221.306853) (xy 347.057262 -221.260579)
			(xy 347.041214 -221.211186) (xy 347.033089 -221.159891) (xy 347.03258 -221.133924) (xy 346.753688 -221.133924)
			(xy 346.753142 -221.16191) (xy 346.743687 -221.217078) (xy 346.734892 -221.243652) (xy 346.727272 -221.26575)
			(xy 346.93098 -221.618556) (xy 346.95384 -221.622874) (xy 346.978763 -221.628034) (xy 347.026748 -221.644999)
			(xy 347.071566 -221.669118) (xy 347.112159 -221.699819) (xy 347.147568 -221.736378) (xy 347.176956 -221.777931)
			(xy 347.19963 -221.823497) (xy 347.215053 -221.871999) (xy 347.222861 -221.922292) (xy 347.223334 -221.94774)
			(xy 347.222825 -221.973707) (xy 347.2147 -222.025002) (xy 347.198652 -222.074395) (xy 347.175074 -222.120669)
			(xy 347.144548 -222.162685) (xy 347.107825 -222.199408) (xy 347.065809 -222.229934) (xy 347.019535 -222.253512)
			(xy 346.970142 -222.26956) (xy 346.918847 -222.277685) (xy 346.866913 -222.277685) (xy 346.815618 -222.26956)
			(xy 346.766225 -222.253512) (xy 346.719951 -222.229934) (xy 346.677935 -222.199408) (xy 346.641212 -222.162685)
			(xy 346.610686 -222.120669) (xy 346.587108 -222.074395) (xy 346.57106 -222.025002) (xy 346.562935 -221.973707)
			(xy 346.562426 -221.94774) (xy 346.562987 -221.919755) (xy 346.572431 -221.864587) (xy 346.581222 -221.838012)
			(xy 346.588842 -221.815914) (xy 346.385134 -221.463108) (xy 346.362274 -221.45879) (xy 346.337345 -221.453653)
			(xy 346.289358 -221.436688) (xy 346.244537 -221.412568) (xy 346.203943 -221.381864) (xy 346.168534 -221.345302)
			(xy 346.139146 -221.303745) (xy 346.116474 -221.258175) (xy 346.101054 -221.209669) (xy 346.09325 -221.159373)
			(xy 346.09278 -221.133924) (xy 345.813888 -221.133924) (xy 345.813379 -221.159891) (xy 345.805254 -221.211186)
			(xy 345.789206 -221.260579) (xy 345.765628 -221.306853) (xy 345.735102 -221.348869) (xy 345.698379 -221.385592)
			(xy 345.656363 -221.416118) (xy 345.610089 -221.439696) (xy 345.560696 -221.455744) (xy 345.509401 -221.463869)
			(xy 345.457467 -221.463869) (xy 345.406172 -221.455744) (xy 345.356779 -221.439696) (xy 345.310505 -221.416118)
			(xy 345.268489 -221.385592) (xy 345.231766 -221.348869) (xy 345.20124 -221.306853) (xy 345.177662 -221.260579)
			(xy 345.161614 -221.211186) (xy 345.153489 -221.159891) (xy 345.15298 -221.133924) (xy 344.874088 -221.133924)
			(xy 344.873542 -221.16191) (xy 344.864087 -221.217078) (xy 344.855292 -221.243652) (xy 344.847672 -221.26575)
			(xy 345.05138 -221.618556) (xy 345.07424 -221.622874) (xy 345.099163 -221.628034) (xy 345.147148 -221.644999)
			(xy 345.191966 -221.669118) (xy 345.232559 -221.699819) (xy 345.267968 -221.736378) (xy 345.297356 -221.777931)
			(xy 345.32003 -221.823497) (xy 345.335453 -221.871999) (xy 345.343261 -221.922292) (xy 345.343734 -221.94774)
			(xy 345.343225 -221.973707) (xy 345.3351 -222.025002) (xy 345.319052 -222.074395) (xy 345.295474 -222.120669)
			(xy 345.264948 -222.162685) (xy 345.228225 -222.199408) (xy 345.186209 -222.229934) (xy 345.139935 -222.253512)
			(xy 345.090542 -222.26956) (xy 345.039247 -222.277685) (xy 344.987313 -222.277685) (xy 344.936018 -222.26956)
			(xy 344.886625 -222.253512) (xy 344.840351 -222.229934) (xy 344.798335 -222.199408) (xy 344.761612 -222.162685)
			(xy 344.731086 -222.120669) (xy 344.707508 -222.074395) (xy 344.69146 -222.025002) (xy 344.683335 -221.973707)
			(xy 344.682826 -221.94774) (xy 344.683387 -221.919755) (xy 344.692831 -221.864587) (xy 344.701622 -221.838012)
			(xy 344.709242 -221.815914) (xy 344.505534 -221.463108) (xy 344.482674 -221.45879) (xy 344.457745 -221.453653)
			(xy 344.409758 -221.436688) (xy 344.364937 -221.412568) (xy 344.324343 -221.381864) (xy 344.288934 -221.345302)
			(xy 344.259546 -221.303745) (xy 344.236874 -221.258175) (xy 344.221454 -221.209669) (xy 344.21365 -221.159373)
			(xy 344.21318 -221.133924) (xy 343.934288 -221.133924) (xy 343.933779 -221.159891) (xy 343.925654 -221.211186)
			(xy 343.909606 -221.260579) (xy 343.886028 -221.306853) (xy 343.855502 -221.348869) (xy 343.818779 -221.385592)
			(xy 343.776763 -221.416118) (xy 343.730489 -221.439696) (xy 343.681096 -221.455744) (xy 343.629801 -221.463869)
			(xy 343.577867 -221.463869) (xy 343.526572 -221.455744) (xy 343.477179 -221.439696) (xy 343.430905 -221.416118)
			(xy 343.388889 -221.385592) (xy 343.352166 -221.348869) (xy 343.32164 -221.306853) (xy 343.298062 -221.260579)
			(xy 343.282014 -221.211186) (xy 343.273889 -221.159891) (xy 343.27338 -221.133924) (xy 342.994488 -221.133924)
			(xy 342.993942 -221.16191) (xy 342.984487 -221.217078) (xy 342.975692 -221.243652) (xy 342.968072 -221.26575)
			(xy 343.17178 -221.618556) (xy 343.19464 -221.622874) (xy 343.219563 -221.628034) (xy 343.267548 -221.644999)
			(xy 343.312366 -221.669118) (xy 343.352959 -221.699819) (xy 343.388368 -221.736378) (xy 343.417756 -221.777931)
			(xy 343.44043 -221.823497) (xy 343.455853 -221.871999) (xy 343.463661 -221.922292) (xy 343.464134 -221.94774)
			(xy 343.463625 -221.973707) (xy 343.4555 -222.025002) (xy 343.439452 -222.074395) (xy 343.415874 -222.120669)
			(xy 343.385348 -222.162685) (xy 343.348625 -222.199408) (xy 343.306609 -222.229934) (xy 343.260335 -222.253512)
			(xy 343.210942 -222.26956) (xy 343.159647 -222.277685) (xy 343.107713 -222.277685) (xy 343.056418 -222.26956)
			(xy 343.007025 -222.253512) (xy 342.960751 -222.229934) (xy 342.918735 -222.199408) (xy 342.882012 -222.162685)
			(xy 342.851486 -222.120669) (xy 342.827908 -222.074395) (xy 342.81186 -222.025002) (xy 342.803735 -221.973707)
			(xy 342.803226 -221.94774) (xy 342.803787 -221.919755) (xy 342.813231 -221.864587) (xy 342.822022 -221.838012)
			(xy 342.829642 -221.815914) (xy 342.625934 -221.463108) (xy 342.603074 -221.45879) (xy 342.578145 -221.453653)
			(xy 342.530158 -221.436688) (xy 342.485337 -221.412568) (xy 342.444743 -221.381864) (xy 342.409334 -221.345302)
			(xy 342.379946 -221.303745) (xy 342.357274 -221.258175) (xy 342.341854 -221.209669) (xy 342.33405 -221.159373)
			(xy 342.33358 -221.133924) (xy 342.054688 -221.133924) (xy 342.054179 -221.159891) (xy 342.046054 -221.211186)
			(xy 342.030006 -221.260579) (xy 342.006428 -221.306853) (xy 341.975902 -221.348869) (xy 341.939179 -221.385592)
			(xy 341.897163 -221.416118) (xy 341.850889 -221.439696) (xy 341.801496 -221.455744) (xy 341.750201 -221.463869)
			(xy 341.698267 -221.463869) (xy 341.646972 -221.455744) (xy 341.597579 -221.439696) (xy 341.551305 -221.416118)
			(xy 341.509289 -221.385592) (xy 341.472566 -221.348869) (xy 341.44204 -221.306853) (xy 341.418462 -221.260579)
			(xy 341.402414 -221.211186) (xy 341.394289 -221.159891) (xy 341.39378 -221.133924) (xy 341.114888 -221.133924)
			(xy 341.114342 -221.16191) (xy 341.104887 -221.217078) (xy 341.096092 -221.243652) (xy 341.088472 -221.26575)
			(xy 341.29218 -221.618556) (xy 341.31504 -221.622874) (xy 341.339963 -221.628034) (xy 341.387948 -221.644999)
			(xy 341.432766 -221.669118) (xy 341.473359 -221.699819) (xy 341.508768 -221.736378) (xy 341.538156 -221.777931)
			(xy 341.56083 -221.823497) (xy 341.576253 -221.871999) (xy 341.584061 -221.922292) (xy 341.584534 -221.94774)
			(xy 341.584025 -221.973707) (xy 341.5759 -222.025002) (xy 341.559852 -222.074395) (xy 341.536274 -222.120669)
			(xy 341.505748 -222.162685) (xy 341.469025 -222.199408) (xy 341.427009 -222.229934) (xy 341.380735 -222.253512)
			(xy 341.331342 -222.26956) (xy 341.280047 -222.277685) (xy 341.228113 -222.277685) (xy 341.176818 -222.26956)
			(xy 341.127425 -222.253512) (xy 341.081151 -222.229934) (xy 341.039135 -222.199408) (xy 341.002412 -222.162685)
			(xy 340.971886 -222.120669) (xy 340.948308 -222.074395) (xy 340.93226 -222.025002) (xy 340.924135 -221.973707)
			(xy 340.923626 -221.94774) (xy 340.924187 -221.919755) (xy 340.933631 -221.864587) (xy 340.942422 -221.838012)
			(xy 340.950042 -221.815914) (xy 340.746334 -221.463108) (xy 340.723474 -221.45879) (xy 340.698545 -221.453653)
			(xy 340.650558 -221.436688) (xy 340.605737 -221.412568) (xy 340.565143 -221.381864) (xy 340.529734 -221.345302)
			(xy 340.500346 -221.303745) (xy 340.477674 -221.258175) (xy 340.462254 -221.209669) (xy 340.45445 -221.159373)
			(xy 340.45398 -221.133924) (xy 340.175088 -221.133924) (xy 340.174579 -221.159891) (xy 340.166454 -221.211186)
			(xy 340.150406 -221.260579) (xy 340.126828 -221.306853) (xy 340.096302 -221.348869) (xy 340.059579 -221.385592)
			(xy 340.017563 -221.416118) (xy 339.971289 -221.439696) (xy 339.921896 -221.455744) (xy 339.870601 -221.463869)
			(xy 339.818667 -221.463869) (xy 339.767372 -221.455744) (xy 339.717979 -221.439696) (xy 339.671705 -221.416118)
			(xy 339.629689 -221.385592) (xy 339.592966 -221.348869) (xy 339.56244 -221.306853) (xy 339.538862 -221.260579)
			(xy 339.522814 -221.211186) (xy 339.514689 -221.159891) (xy 339.51418 -221.133924) (xy 339.235288 -221.133924)
			(xy 339.234742 -221.16191) (xy 339.225287 -221.217078) (xy 339.216492 -221.243652) (xy 339.208872 -221.26575)
			(xy 339.41258 -221.618556) (xy 339.43544 -221.622874) (xy 339.460363 -221.628034) (xy 339.508348 -221.644999)
			(xy 339.553166 -221.669118) (xy 339.593759 -221.699819) (xy 339.629168 -221.736378) (xy 339.658556 -221.777931)
			(xy 339.68123 -221.823497) (xy 339.696653 -221.871999) (xy 339.704461 -221.922292) (xy 339.704934 -221.94774)
			(xy 339.704425 -221.973707) (xy 339.6963 -222.025002) (xy 339.680252 -222.074395) (xy 339.656674 -222.120669)
			(xy 339.626148 -222.162685) (xy 339.589425 -222.199408) (xy 339.547409 -222.229934) (xy 339.501135 -222.253512)
			(xy 339.451742 -222.26956) (xy 339.400447 -222.277685) (xy 339.348513 -222.277685) (xy 339.297218 -222.26956)
			(xy 339.247825 -222.253512) (xy 339.201551 -222.229934) (xy 339.159535 -222.199408) (xy 339.122812 -222.162685)
			(xy 339.092286 -222.120669) (xy 339.068708 -222.074395) (xy 339.05266 -222.025002) (xy 339.044535 -221.973707)
			(xy 339.044026 -221.94774) (xy 339.044587 -221.919755) (xy 339.054031 -221.864587) (xy 339.062822 -221.838012)
			(xy 339.070442 -221.815914) (xy 338.866734 -221.463108) (xy 338.843874 -221.45879) (xy 338.818945 -221.453653)
			(xy 338.770958 -221.436688) (xy 338.726137 -221.412568) (xy 338.685543 -221.381864) (xy 338.650134 -221.345302)
			(xy 338.620746 -221.303745) (xy 338.598074 -221.258175) (xy 338.582654 -221.209669) (xy 338.57485 -221.159373)
			(xy 338.57438 -221.133924) (xy 338.295488 -221.133924) (xy 338.294979 -221.159891) (xy 338.286854 -221.211186)
			(xy 338.270806 -221.260579) (xy 338.247228 -221.306853) (xy 338.216702 -221.348869) (xy 338.179979 -221.385592)
			(xy 338.137963 -221.416118) (xy 338.091689 -221.439696) (xy 338.042296 -221.455744) (xy 337.991001 -221.463869)
			(xy 337.939067 -221.463869) (xy 337.887772 -221.455744) (xy 337.838379 -221.439696) (xy 337.792105 -221.416118)
			(xy 337.750089 -221.385592) (xy 337.713366 -221.348869) (xy 337.68284 -221.306853) (xy 337.659262 -221.260579)
			(xy 337.643214 -221.211186) (xy 337.635089 -221.159891) (xy 337.63458 -221.133924) (xy 337.355688 -221.133924)
			(xy 337.355142 -221.16191) (xy 337.345687 -221.217078) (xy 337.336892 -221.243652) (xy 337.329272 -221.26575)
			(xy 337.53298 -221.618556) (xy 337.55584 -221.622874) (xy 337.580763 -221.628034) (xy 337.628748 -221.644999)
			(xy 337.673566 -221.669118) (xy 337.714159 -221.699819) (xy 337.749568 -221.736378) (xy 337.778956 -221.777931)
			(xy 337.80163 -221.823497) (xy 337.817053 -221.871999) (xy 337.824861 -221.922292) (xy 337.825334 -221.94774)
			(xy 337.824825 -221.973707) (xy 337.8167 -222.025002) (xy 337.800652 -222.074395) (xy 337.777074 -222.120669)
			(xy 337.746548 -222.162685) (xy 337.709825 -222.199408) (xy 337.667809 -222.229934) (xy 337.621535 -222.253512)
			(xy 337.572142 -222.26956) (xy 337.520847 -222.277685) (xy 337.468913 -222.277685) (xy 337.417618 -222.26956)
			(xy 337.368225 -222.253512) (xy 337.321951 -222.229934) (xy 337.279935 -222.199408) (xy 337.243212 -222.162685)
			(xy 337.212686 -222.120669) (xy 337.189108 -222.074395) (xy 337.17306 -222.025002) (xy 337.164935 -221.973707)
			(xy 337.164426 -221.94774) (xy 337.164987 -221.919755) (xy 337.174431 -221.864587) (xy 337.183222 -221.838012)
			(xy 337.190842 -221.815914) (xy 336.987134 -221.463108) (xy 336.964274 -221.45879) (xy 336.939345 -221.453653)
			(xy 336.891358 -221.436688) (xy 336.846537 -221.412568) (xy 336.805943 -221.381864) (xy 336.770534 -221.345302)
			(xy 336.741146 -221.303745) (xy 336.718474 -221.258175) (xy 336.703054 -221.209669) (xy 336.69525 -221.159373)
			(xy 336.69478 -221.133924) (xy 336.415349 -221.133924) (xy 336.415348 -221.160439) (xy 336.406869 -221.212814)
			(xy 336.390132 -221.263162) (xy 336.365565 -221.310189) (xy 336.3338 -221.352686) (xy 336.295653 -221.389563)
			(xy 336.252105 -221.419871) (xy 336.228436 -221.431866) (xy 336.19948 -221.445836) (xy 336.19948 -221.900496)
			(xy 336.809842 -222.510858) (xy 336.827917 -222.495886) (xy 336.867497 -222.470664) (xy 336.910246 -222.451291)
			(xy 336.955304 -222.438156) (xy 337.001767 -222.431525) (xy 337.025234 -222.431102) (xy 337.051201 -222.431614)
			(xy 337.102494 -222.439742) (xy 337.151885 -222.455793) (xy 337.198157 -222.479372) (xy 337.240172 -222.509898)
			(xy 337.276895 -222.54662) (xy 337.307423 -222.588634) (xy 337.331003 -222.634906) (xy 337.347056 -222.684296)
			(xy 337.355185 -222.735589) (xy 337.355688 -222.761556) (xy 337.355266 -222.785759) (xy 337.355006 -222.787523)
			(xy 337.635089 -222.787523) (xy 337.635089 -222.735589) (xy 337.643214 -222.684294) (xy 337.659262 -222.634901)
			(xy 337.68284 -222.588627) (xy 337.713366 -222.546611) (xy 337.750089 -222.509888) (xy 337.792105 -222.479362)
			(xy 337.838379 -222.455784) (xy 337.887772 -222.439736) (xy 337.939067 -222.431611) (xy 337.991001 -222.431611)
			(xy 338.042296 -222.439736) (xy 338.091689 -222.455784) (xy 338.137963 -222.479362) (xy 338.179979 -222.509888)
			(xy 338.216702 -222.546611) (xy 338.247228 -222.588627) (xy 338.270806 -222.634901) (xy 338.286854 -222.684294)
			(xy 338.294979 -222.735589) (xy 338.295488 -222.761556) (xy 338.294979 -222.787523) (xy 338.574889 -222.787523)
			(xy 338.574889 -222.735589) (xy 338.583014 -222.684294) (xy 338.599062 -222.634901) (xy 338.62264 -222.588627)
			(xy 338.653166 -222.546611) (xy 338.689889 -222.509888) (xy 338.731905 -222.479362) (xy 338.778179 -222.455784)
			(xy 338.827572 -222.439736) (xy 338.878867 -222.431611) (xy 338.930801 -222.431611) (xy 338.982096 -222.439736)
			(xy 339.031489 -222.455784) (xy 339.077763 -222.479362) (xy 339.119779 -222.509888) (xy 339.156502 -222.546611)
			(xy 339.187028 -222.588627) (xy 339.210606 -222.634901) (xy 339.226654 -222.684294) (xy 339.234779 -222.735589)
			(xy 339.235288 -222.761556) (xy 339.234779 -222.787523) (xy 339.514689 -222.787523) (xy 339.514689 -222.735589)
			(xy 339.522814 -222.684294) (xy 339.538862 -222.634901) (xy 339.56244 -222.588627) (xy 339.592966 -222.546611)
			(xy 339.629689 -222.509888) (xy 339.671705 -222.479362) (xy 339.717979 -222.455784) (xy 339.767372 -222.439736)
			(xy 339.818667 -222.431611) (xy 339.870601 -222.431611) (xy 339.921896 -222.439736) (xy 339.971289 -222.455784)
			(xy 340.017563 -222.479362) (xy 340.059579 -222.509888) (xy 340.096302 -222.546611) (xy 340.126828 -222.588627)
			(xy 340.150406 -222.634901) (xy 340.166454 -222.684294) (xy 340.174579 -222.735589) (xy 340.175088 -222.761556)
			(xy 340.174579 -222.787523) (xy 340.454489 -222.787523) (xy 340.454489 -222.735589) (xy 340.462614 -222.684294)
			(xy 340.478662 -222.634901) (xy 340.50224 -222.588627) (xy 340.532766 -222.546611) (xy 340.569489 -222.509888)
			(xy 340.611505 -222.479362) (xy 340.657779 -222.455784) (xy 340.707172 -222.439736) (xy 340.758467 -222.431611)
			(xy 340.810401 -222.431611) (xy 340.861696 -222.439736) (xy 340.911089 -222.455784) (xy 340.957363 -222.479362)
			(xy 340.999379 -222.509888) (xy 341.036102 -222.546611) (xy 341.066628 -222.588627) (xy 341.090206 -222.634901)
			(xy 341.106254 -222.684294) (xy 341.114379 -222.735589) (xy 341.114888 -222.761556) (xy 341.114379 -222.787523)
			(xy 341.394289 -222.787523) (xy 341.394289 -222.735589) (xy 341.402414 -222.684294) (xy 341.418462 -222.634901)
			(xy 341.44204 -222.588627) (xy 341.472566 -222.546611) (xy 341.509289 -222.509888) (xy 341.551305 -222.479362)
			(xy 341.597579 -222.455784) (xy 341.646972 -222.439736) (xy 341.698267 -222.431611) (xy 341.750201 -222.431611)
			(xy 341.801496 -222.439736) (xy 341.850889 -222.455784) (xy 341.897163 -222.479362) (xy 341.939179 -222.509888)
			(xy 341.975902 -222.546611) (xy 342.006428 -222.588627) (xy 342.030006 -222.634901) (xy 342.046054 -222.684294)
			(xy 342.054179 -222.735589) (xy 342.054688 -222.761556) (xy 342.054179 -222.787523) (xy 342.334089 -222.787523)
			(xy 342.334089 -222.735589) (xy 342.342214 -222.684294) (xy 342.358262 -222.634901) (xy 342.38184 -222.588627)
			(xy 342.412366 -222.546611) (xy 342.449089 -222.509888) (xy 342.491105 -222.479362) (xy 342.537379 -222.455784)
			(xy 342.586772 -222.439736) (xy 342.638067 -222.431611) (xy 342.690001 -222.431611) (xy 342.741296 -222.439736)
			(xy 342.790689 -222.455784) (xy 342.836963 -222.479362) (xy 342.878979 -222.509888) (xy 342.915702 -222.546611)
			(xy 342.946228 -222.588627) (xy 342.969806 -222.634901) (xy 342.985854 -222.684294) (xy 342.993979 -222.735589)
			(xy 342.994488 -222.761556) (xy 342.993979 -222.787523) (xy 343.273889 -222.787523) (xy 343.273889 -222.735589)
			(xy 343.282014 -222.684294) (xy 343.298062 -222.634901) (xy 343.32164 -222.588627) (xy 343.352166 -222.546611)
			(xy 343.388889 -222.509888) (xy 343.430905 -222.479362) (xy 343.477179 -222.455784) (xy 343.526572 -222.439736)
			(xy 343.577867 -222.431611) (xy 343.629801 -222.431611) (xy 343.681096 -222.439736) (xy 343.730489 -222.455784)
			(xy 343.776763 -222.479362) (xy 343.818779 -222.509888) (xy 343.855502 -222.546611) (xy 343.886028 -222.588627)
			(xy 343.909606 -222.634901) (xy 343.925654 -222.684294) (xy 343.933779 -222.735589) (xy 343.934288 -222.761556)
			(xy 343.933779 -222.787523) (xy 344.213689 -222.787523) (xy 344.213689 -222.735589) (xy 344.221814 -222.684294)
			(xy 344.237862 -222.634901) (xy 344.26144 -222.588627) (xy 344.291966 -222.546611) (xy 344.328689 -222.509888)
			(xy 344.370705 -222.479362) (xy 344.416979 -222.455784) (xy 344.466372 -222.439736) (xy 344.517667 -222.431611)
			(xy 344.569601 -222.431611) (xy 344.620896 -222.439736) (xy 344.670289 -222.455784) (xy 344.716563 -222.479362)
			(xy 344.758579 -222.509888) (xy 344.795302 -222.546611) (xy 344.825828 -222.588627) (xy 344.849406 -222.634901)
			(xy 344.865454 -222.684294) (xy 344.873579 -222.735589) (xy 344.874088 -222.761556) (xy 344.873579 -222.787523)
			(xy 345.153489 -222.787523) (xy 345.153489 -222.735589) (xy 345.161614 -222.684294) (xy 345.177662 -222.634901)
			(xy 345.20124 -222.588627) (xy 345.231766 -222.546611) (xy 345.268489 -222.509888) (xy 345.310505 -222.479362)
			(xy 345.356779 -222.455784) (xy 345.406172 -222.439736) (xy 345.457467 -222.431611) (xy 345.509401 -222.431611)
			(xy 345.560696 -222.439736) (xy 345.610089 -222.455784) (xy 345.656363 -222.479362) (xy 345.698379 -222.509888)
			(xy 345.735102 -222.546611) (xy 345.765628 -222.588627) (xy 345.789206 -222.634901) (xy 345.805254 -222.684294)
			(xy 345.813379 -222.735589) (xy 345.813888 -222.761556) (xy 345.813379 -222.787523) (xy 346.093289 -222.787523)
			(xy 346.093289 -222.735589) (xy 346.101414 -222.684294) (xy 346.117462 -222.634901) (xy 346.14104 -222.588627)
			(xy 346.171566 -222.546611) (xy 346.208289 -222.509888) (xy 346.250305 -222.479362) (xy 346.296579 -222.455784)
			(xy 346.345972 -222.439736) (xy 346.397267 -222.431611) (xy 346.449201 -222.431611) (xy 346.500496 -222.439736)
			(xy 346.549889 -222.455784) (xy 346.596163 -222.479362) (xy 346.638179 -222.509888) (xy 346.674902 -222.546611)
			(xy 346.705428 -222.588627) (xy 346.729006 -222.634901) (xy 346.745054 -222.684294) (xy 346.753179 -222.735589)
			(xy 346.753688 -222.761556) (xy 346.753179 -222.787523) (xy 347.033089 -222.787523) (xy 347.033089 -222.735589)
			(xy 347.041214 -222.684294) (xy 347.057262 -222.634901) (xy 347.08084 -222.588627) (xy 347.111366 -222.546611)
			(xy 347.148089 -222.509888) (xy 347.190105 -222.479362) (xy 347.236379 -222.455784) (xy 347.285772 -222.439736)
			(xy 347.337067 -222.431611) (xy 347.389001 -222.431611) (xy 347.440296 -222.439736) (xy 347.489689 -222.455784)
			(xy 347.535963 -222.479362) (xy 347.577979 -222.509888) (xy 347.614702 -222.546611) (xy 347.645228 -222.588627)
			(xy 347.668806 -222.634901) (xy 347.684854 -222.684294) (xy 347.692979 -222.735589) (xy 347.693488 -222.761556)
			(xy 347.692979 -222.787523) (xy 347.972889 -222.787523) (xy 347.972889 -222.735589) (xy 347.981014 -222.684294)
			(xy 347.997062 -222.634901) (xy 348.02064 -222.588627) (xy 348.051166 -222.546611) (xy 348.087889 -222.509888)
			(xy 348.129905 -222.479362) (xy 348.176179 -222.455784) (xy 348.225572 -222.439736) (xy 348.276867 -222.431611)
			(xy 348.328801 -222.431611) (xy 348.380096 -222.439736) (xy 348.429489 -222.455784) (xy 348.475763 -222.479362)
			(xy 348.517779 -222.509888) (xy 348.554502 -222.546611) (xy 348.585028 -222.588627) (xy 348.608606 -222.634901)
			(xy 348.624654 -222.684294) (xy 348.632779 -222.735589) (xy 348.633288 -222.761556) (xy 348.632779 -222.787523)
			(xy 348.912689 -222.787523) (xy 348.912689 -222.735589) (xy 348.920814 -222.684294) (xy 348.936862 -222.634901)
			(xy 348.96044 -222.588627) (xy 348.990966 -222.546611) (xy 349.027689 -222.509888) (xy 349.069705 -222.479362)
			(xy 349.115979 -222.455784) (xy 349.165372 -222.439736) (xy 349.216667 -222.431611) (xy 349.268601 -222.431611)
			(xy 349.319896 -222.439736) (xy 349.369289 -222.455784) (xy 349.415563 -222.479362) (xy 349.457579 -222.509888)
			(xy 349.494302 -222.546611) (xy 349.524828 -222.588627) (xy 349.548406 -222.634901) (xy 349.564454 -222.684294)
			(xy 349.572579 -222.735589) (xy 349.573088 -222.761556) (xy 349.572579 -222.787523) (xy 349.564454 -222.838818)
			(xy 349.548406 -222.888211) (xy 349.524828 -222.934485) (xy 349.494302 -222.976501) (xy 349.457579 -223.013224)
			(xy 349.415563 -223.04375) (xy 349.369289 -223.067328) (xy 349.319896 -223.083376) (xy 349.268601 -223.091501)
			(xy 349.216667 -223.091501) (xy 349.165372 -223.083376) (xy 349.115979 -223.067328) (xy 349.069705 -223.04375)
			(xy 349.027689 -223.013224) (xy 348.990966 -222.976501) (xy 348.96044 -222.934485) (xy 348.936862 -222.888211)
			(xy 348.920814 -222.838818) (xy 348.912689 -222.787523) (xy 348.632779 -222.787523) (xy 348.624654 -222.838818)
			(xy 348.608606 -222.888211) (xy 348.585028 -222.934485) (xy 348.554502 -222.976501) (xy 348.517779 -223.013224)
			(xy 348.475763 -223.04375) (xy 348.429489 -223.067328) (xy 348.380096 -223.083376) (xy 348.328801 -223.091501)
			(xy 348.276867 -223.091501) (xy 348.225572 -223.083376) (xy 348.176179 -223.067328) (xy 348.129905 -223.04375)
			(xy 348.087889 -223.013224) (xy 348.051166 -222.976501) (xy 348.02064 -222.934485) (xy 347.997062 -222.888211)
			(xy 347.981014 -222.838818) (xy 347.972889 -222.787523) (xy 347.692979 -222.787523) (xy 347.684854 -222.838818)
			(xy 347.668806 -222.888211) (xy 347.645228 -222.934485) (xy 347.614702 -222.976501) (xy 347.577979 -223.013224)
			(xy 347.535963 -223.04375) (xy 347.489689 -223.067328) (xy 347.440296 -223.083376) (xy 347.389001 -223.091501)
			(xy 347.337067 -223.091501) (xy 347.285772 -223.083376) (xy 347.236379 -223.067328) (xy 347.190105 -223.04375)
			(xy 347.148089 -223.013224) (xy 347.111366 -222.976501) (xy 347.08084 -222.934485) (xy 347.057262 -222.888211)
			(xy 347.041214 -222.838818) (xy 347.033089 -222.787523) (xy 346.753179 -222.787523) (xy 346.745054 -222.838818)
			(xy 346.729006 -222.888211) (xy 346.705428 -222.934485) (xy 346.674902 -222.976501) (xy 346.638179 -223.013224)
			(xy 346.596163 -223.04375) (xy 346.549889 -223.067328) (xy 346.500496 -223.083376) (xy 346.449201 -223.091501)
			(xy 346.397267 -223.091501) (xy 346.345972 -223.083376) (xy 346.296579 -223.067328) (xy 346.250305 -223.04375)
			(xy 346.208289 -223.013224) (xy 346.171566 -222.976501) (xy 346.14104 -222.934485) (xy 346.117462 -222.888211)
			(xy 346.101414 -222.838818) (xy 346.093289 -222.787523) (xy 345.813379 -222.787523) (xy 345.805254 -222.838818)
			(xy 345.789206 -222.888211) (xy 345.765628 -222.934485) (xy 345.735102 -222.976501) (xy 345.698379 -223.013224)
			(xy 345.656363 -223.04375) (xy 345.610089 -223.067328) (xy 345.560696 -223.083376) (xy 345.509401 -223.091501)
			(xy 345.457467 -223.091501) (xy 345.406172 -223.083376) (xy 345.356779 -223.067328) (xy 345.310505 -223.04375)
			(xy 345.268489 -223.013224) (xy 345.231766 -222.976501) (xy 345.20124 -222.934485) (xy 345.177662 -222.888211)
			(xy 345.161614 -222.838818) (xy 345.153489 -222.787523) (xy 344.873579 -222.787523) (xy 344.865454 -222.838818)
			(xy 344.849406 -222.888211) (xy 344.825828 -222.934485) (xy 344.795302 -222.976501) (xy 344.758579 -223.013224)
			(xy 344.716563 -223.04375) (xy 344.670289 -223.067328) (xy 344.620896 -223.083376) (xy 344.569601 -223.091501)
			(xy 344.517667 -223.091501) (xy 344.466372 -223.083376) (xy 344.416979 -223.067328) (xy 344.370705 -223.04375)
			(xy 344.328689 -223.013224) (xy 344.291966 -222.976501) (xy 344.26144 -222.934485) (xy 344.237862 -222.888211)
			(xy 344.221814 -222.838818) (xy 344.213689 -222.787523) (xy 343.933779 -222.787523) (xy 343.925654 -222.838818)
			(xy 343.909606 -222.888211) (xy 343.886028 -222.934485) (xy 343.855502 -222.976501) (xy 343.818779 -223.013224)
			(xy 343.776763 -223.04375) (xy 343.730489 -223.067328) (xy 343.681096 -223.083376) (xy 343.629801 -223.091501)
			(xy 343.577867 -223.091501) (xy 343.526572 -223.083376) (xy 343.477179 -223.067328) (xy 343.430905 -223.04375)
			(xy 343.388889 -223.013224) (xy 343.352166 -222.976501) (xy 343.32164 -222.934485) (xy 343.298062 -222.888211)
			(xy 343.282014 -222.838818) (xy 343.273889 -222.787523) (xy 342.993979 -222.787523) (xy 342.985854 -222.838818)
			(xy 342.969806 -222.888211) (xy 342.946228 -222.934485) (xy 342.915702 -222.976501) (xy 342.878979 -223.013224)
			(xy 342.836963 -223.04375) (xy 342.790689 -223.067328) (xy 342.741296 -223.083376) (xy 342.690001 -223.091501)
			(xy 342.638067 -223.091501) (xy 342.586772 -223.083376) (xy 342.537379 -223.067328) (xy 342.491105 -223.04375)
			(xy 342.449089 -223.013224) (xy 342.412366 -222.976501) (xy 342.38184 -222.934485) (xy 342.358262 -222.888211)
			(xy 342.342214 -222.838818) (xy 342.334089 -222.787523) (xy 342.054179 -222.787523) (xy 342.046054 -222.838818)
			(xy 342.030006 -222.888211) (xy 342.006428 -222.934485) (xy 341.975902 -222.976501) (xy 341.939179 -223.013224)
			(xy 341.897163 -223.04375) (xy 341.850889 -223.067328) (xy 341.801496 -223.083376) (xy 341.750201 -223.091501)
			(xy 341.698267 -223.091501) (xy 341.646972 -223.083376) (xy 341.597579 -223.067328) (xy 341.551305 -223.04375)
			(xy 341.509289 -223.013224) (xy 341.472566 -222.976501) (xy 341.44204 -222.934485) (xy 341.418462 -222.888211)
			(xy 341.402414 -222.838818) (xy 341.394289 -222.787523) (xy 341.114379 -222.787523) (xy 341.106254 -222.838818)
			(xy 341.090206 -222.888211) (xy 341.066628 -222.934485) (xy 341.036102 -222.976501) (xy 340.999379 -223.013224)
			(xy 340.957363 -223.04375) (xy 340.911089 -223.067328) (xy 340.861696 -223.083376) (xy 340.810401 -223.091501)
			(xy 340.758467 -223.091501) (xy 340.707172 -223.083376) (xy 340.657779 -223.067328) (xy 340.611505 -223.04375)
			(xy 340.569489 -223.013224) (xy 340.532766 -222.976501) (xy 340.50224 -222.934485) (xy 340.478662 -222.888211)
			(xy 340.462614 -222.838818) (xy 340.454489 -222.787523) (xy 340.174579 -222.787523) (xy 340.166454 -222.838818)
			(xy 340.150406 -222.888211) (xy 340.126828 -222.934485) (xy 340.096302 -222.976501) (xy 340.059579 -223.013224)
			(xy 340.017563 -223.04375) (xy 339.971289 -223.067328) (xy 339.921896 -223.083376) (xy 339.870601 -223.091501)
			(xy 339.818667 -223.091501) (xy 339.767372 -223.083376) (xy 339.717979 -223.067328) (xy 339.671705 -223.04375)
			(xy 339.629689 -223.013224) (xy 339.592966 -222.976501) (xy 339.56244 -222.934485) (xy 339.538862 -222.888211)
			(xy 339.522814 -222.838818) (xy 339.514689 -222.787523) (xy 339.234779 -222.787523) (xy 339.226654 -222.838818)
			(xy 339.210606 -222.888211) (xy 339.187028 -222.934485) (xy 339.156502 -222.976501) (xy 339.119779 -223.013224)
			(xy 339.077763 -223.04375) (xy 339.031489 -223.067328) (xy 338.982096 -223.083376) (xy 338.930801 -223.091501)
			(xy 338.878867 -223.091501) (xy 338.827572 -223.083376) (xy 338.778179 -223.067328) (xy 338.731905 -223.04375)
			(xy 338.689889 -223.013224) (xy 338.653166 -222.976501) (xy 338.62264 -222.934485) (xy 338.599062 -222.888211)
			(xy 338.583014 -222.838818) (xy 338.574889 -222.787523) (xy 338.294979 -222.787523) (xy 338.286854 -222.838818)
			(xy 338.270806 -222.888211) (xy 338.247228 -222.934485) (xy 338.216702 -222.976501) (xy 338.179979 -223.013224)
			(xy 338.137963 -223.04375) (xy 338.091689 -223.067328) (xy 338.042296 -223.083376) (xy 337.991001 -223.091501)
			(xy 337.939067 -223.091501) (xy 337.887772 -223.083376) (xy 337.838379 -223.067328) (xy 337.792105 -223.04375)
			(xy 337.750089 -223.013224) (xy 337.713366 -222.976501) (xy 337.68284 -222.934485) (xy 337.659262 -222.888211)
			(xy 337.643214 -222.838818) (xy 337.635089 -222.787523) (xy 337.355006 -222.787523) (xy 337.348201 -222.833646)
			(xy 337.334216 -222.879987) (xy 337.313611 -222.923788) (xy 337.30057 -222.944182) (xy 337.27771 -222.978726)
			(xy 337.547966 -223.248982) (xy 337.562952 -223.25203) (xy 337.589652 -223.258153) (xy 337.640693 -223.278033)
			(xy 337.687758 -223.306055) (xy 337.72956 -223.341452) (xy 337.764955 -223.383256) (xy 337.792974 -223.430322)
			(xy 337.812852 -223.481364) (xy 337.818984 -223.508062) (xy 337.822032 -223.523048) (xy 338.03844 -223.739456)
			(xy 338.04534 -223.745731) (xy 338.062383 -223.753266) (xy 338.080995 -223.754197) (xy 338.098704 -223.748398)
			(xy 338.113162 -223.736641) (xy 338.118196 -223.728788) (xy 338.130388 -223.707452) (xy 338.122768 -223.685354)
			(xy 338.114013 -223.65877) (xy 338.104564 -223.603608) (xy 338.103972 -223.575626) (xy 338.104482 -223.549639)
			(xy 338.112612 -223.498304) (xy 338.128673 -223.448874) (xy 338.152269 -223.402564) (xy 338.182819 -223.360516)
			(xy 338.21957 -223.323765) (xy 338.261618 -223.293215) (xy 338.307928 -223.269619) (xy 338.357358 -223.253558)
			(xy 338.408693 -223.245428) (xy 338.460667 -223.245428) (xy 338.512002 -223.253558) (xy 338.561432 -223.269619)
			(xy 338.607742 -223.293215) (xy 338.64979 -223.323765) (xy 338.686541 -223.360516) (xy 338.717091 -223.402564)
			(xy 338.740687 -223.448874) (xy 338.756748 -223.498304) (xy 338.764878 -223.549639) (xy 338.765388 -223.575626)
			(xy 338.764916 -223.601109) (xy 338.764841 -223.601593) (xy 339.044789 -223.601593) (xy 339.044789 -223.549659)
			(xy 339.052914 -223.498364) (xy 339.068962 -223.448971) (xy 339.09254 -223.402697) (xy 339.123066 -223.360681)
			(xy 339.159789 -223.323958) (xy 339.201805 -223.293432) (xy 339.248079 -223.269854) (xy 339.297472 -223.253806)
			(xy 339.348767 -223.245681) (xy 339.400701 -223.245681) (xy 339.451996 -223.253806) (xy 339.501389 -223.269854)
			(xy 339.547663 -223.293432) (xy 339.589679 -223.323958) (xy 339.626402 -223.360681) (xy 339.656928 -223.402697)
			(xy 339.680506 -223.448971) (xy 339.696554 -223.498364) (xy 339.704679 -223.549659) (xy 339.705188 -223.575626)
			(xy 339.704679 -223.601593) (xy 339.696554 -223.652888) (xy 339.680506 -223.702281) (xy 339.656928 -223.748555)
			(xy 339.626402 -223.790571) (xy 339.589679 -223.827294) (xy 339.547663 -223.85782) (xy 339.501389 -223.881398)
			(xy 339.451996 -223.897446) (xy 339.400701 -223.905571) (xy 339.348767 -223.905571) (xy 339.297472 -223.897446)
			(xy 339.248079 -223.881398) (xy 339.201805 -223.85782) (xy 339.159789 -223.827294) (xy 339.123066 -223.790571)
			(xy 339.09254 -223.748555) (xy 339.068962 -223.702281) (xy 339.052914 -223.652888) (xy 339.044789 -223.601593)
			(xy 338.764841 -223.601593) (xy 338.757095 -223.651471) (xy 338.741641 -223.700038) (xy 338.718922 -223.74566)
			(xy 338.689473 -223.787257) (xy 338.653993 -223.823846) (xy 338.613321 -223.854559) (xy 338.568419 -223.878671)
			(xy 338.52035 -223.89561) (xy 338.495386 -223.900746) (xy 338.472526 -223.905064) (xy 338.374228 -224.075244)
			(xy 338.4931 -224.194116) (xy 338.503573 -224.20392) (xy 338.528677 -224.217779) (xy 338.556647 -224.224097)
			(xy 338.585271 -224.222376) (xy 338.612282 -224.21275) (xy 338.635543 -224.195982) (xy 338.644738 -224.184972)
			(xy 338.660521 -224.165646) (xy 338.696912 -224.131511) (xy 338.738017 -224.103229) (xy 338.782904 -224.081442)
			(xy 338.830554 -224.066643) (xy 338.879886 -224.059169) (xy 338.904834 -224.058734) (xy 338.93082 -224.05922)
			(xy 338.982152 -224.067355) (xy 339.03158 -224.083421) (xy 339.077885 -224.107021) (xy 339.119928 -224.137575)
			(xy 339.156674 -224.174329) (xy 339.187218 -224.21638) (xy 339.210808 -224.262691) (xy 339.226862 -224.312122)
			(xy 339.234986 -224.363456) (xy 339.235542 -224.389442) (xy 339.513926 -224.389442) (xy 339.514376 -224.363957)
			(xy 339.52219 -224.31359) (xy 339.53764 -224.265018) (xy 339.56036 -224.219392) (xy 339.589811 -224.177792)
			(xy 339.625297 -224.141204) (xy 339.665976 -224.110494) (xy 339.710886 -224.086389) (xy 339.758962 -224.06946)
			(xy 339.783928 -224.064322) (xy 339.806788 -224.060004) (xy 340.009988 -223.707452) (xy 340.002368 -223.685354)
			(xy 339.993628 -223.658766) (xy 339.98418 -223.603607) (xy 339.983572 -223.575626) (xy 339.984082 -223.549639)
			(xy 339.992212 -223.498304) (xy 340.008273 -223.448874) (xy 340.031869 -223.402564) (xy 340.062419 -223.360516)
			(xy 340.09917 -223.323765) (xy 340.141218 -223.293215) (xy 340.187528 -223.269619) (xy 340.236958 -223.253558)
			(xy 340.288293 -223.245428) (xy 340.340267 -223.245428) (xy 340.391602 -223.253558) (xy 340.441032 -223.269619)
			(xy 340.487342 -223.293215) (xy 340.52939 -223.323765) (xy 340.566141 -223.360516) (xy 340.596691 -223.402564)
			(xy 340.620287 -223.448874) (xy 340.636348 -223.498304) (xy 340.644478 -223.549639) (xy 340.644988 -223.575626)
			(xy 340.644497 -223.601109) (xy 340.644422 -223.601593) (xy 340.924389 -223.601593) (xy 340.924389 -223.549659)
			(xy 340.932514 -223.498364) (xy 340.948562 -223.448971) (xy 340.97214 -223.402697) (xy 341.002666 -223.360681)
			(xy 341.039389 -223.323958) (xy 341.081405 -223.293432) (xy 341.127679 -223.269854) (xy 341.177072 -223.253806)
			(xy 341.228367 -223.245681) (xy 341.280301 -223.245681) (xy 341.331596 -223.253806) (xy 341.380989 -223.269854)
			(xy 341.427263 -223.293432) (xy 341.469279 -223.323958) (xy 341.506002 -223.360681) (xy 341.536528 -223.402697)
			(xy 341.560106 -223.448971) (xy 341.576154 -223.498364) (xy 341.584279 -223.549659) (xy 341.584788 -223.575626)
			(xy 341.584279 -223.601593) (xy 341.576154 -223.652888) (xy 341.560106 -223.702281) (xy 341.536528 -223.748555)
			(xy 341.506002 -223.790571) (xy 341.469279 -223.827294) (xy 341.427263 -223.85782) (xy 341.380989 -223.881398)
			(xy 341.331596 -223.897446) (xy 341.280301 -223.905571) (xy 341.228367 -223.905571) (xy 341.177072 -223.897446)
			(xy 341.127679 -223.881398) (xy 341.081405 -223.85782) (xy 341.039389 -223.827294) (xy 341.002666 -223.790571)
			(xy 340.97214 -223.748555) (xy 340.948562 -223.702281) (xy 340.932514 -223.652888) (xy 340.924389 -223.601593)
			(xy 340.644422 -223.601593) (xy 340.636688 -223.651474) (xy 340.621244 -223.700045) (xy 340.598529 -223.74567)
			(xy 340.569083 -223.787269) (xy 340.533602 -223.823858) (xy 340.492928 -223.854569) (xy 340.448022 -223.878676)
			(xy 340.39995 -223.895606) (xy 340.374986 -223.900746) (xy 340.352126 -223.905064) (xy 340.148672 -224.257362)
			(xy 340.156546 -224.27946) (xy 340.16529 -224.306047) (xy 340.174735 -224.361207) (xy 340.175342 -224.389188)
			(xy 340.175342 -224.389442) (xy 340.453726 -224.389442) (xy 340.454236 -224.363455) (xy 340.462366 -224.31212)
			(xy 340.478427 -224.26269) (xy 340.502023 -224.21638) (xy 340.532573 -224.174332) (xy 340.569324 -224.137581)
			(xy 340.611372 -224.107031) (xy 340.657682 -224.083435) (xy 340.707112 -224.067374) (xy 340.758447 -224.059244)
			(xy 340.810421 -224.059244) (xy 340.861756 -224.067374) (xy 340.911186 -224.083435) (xy 340.957496 -224.107031)
			(xy 340.999544 -224.137581) (xy 341.036295 -224.174332) (xy 341.066845 -224.21638) (xy 341.090441 -224.26269)
			(xy 341.106502 -224.31212) (xy 341.114632 -224.363455) (xy 341.115142 -224.389442) (xy 341.393526 -224.389442)
			(xy 341.393938 -224.363966) (xy 341.401733 -224.313615) (xy 341.41716 -224.265055) (xy 341.439855 -224.219437)
			(xy 341.469279 -224.177841) (xy 341.504736 -224.141251) (xy 341.545387 -224.110534) (xy 341.590269 -224.086417)
			(xy 341.63832 -224.069471) (xy 341.663274 -224.064322) (xy 341.686388 -224.060004) (xy 341.889842 -223.707452)
			(xy 341.881968 -223.685608) (xy 341.873217 -223.659024) (xy 341.863777 -223.603862) (xy 341.863172 -223.57588)
			(xy 341.863172 -223.575626) (xy 341.863682 -223.549639) (xy 341.871812 -223.498304) (xy 341.887873 -223.448874)
			(xy 341.911469 -223.402564) (xy 341.942019 -223.360516) (xy 341.97877 -223.323765) (xy 342.020818 -223.293215)
			(xy 342.067128 -223.269619) (xy 342.116558 -223.253558) (xy 342.167893 -223.245428) (xy 342.219867 -223.245428)
			(xy 342.271202 -223.253558) (xy 342.320632 -223.269619) (xy 342.366942 -223.293215) (xy 342.40899 -223.323765)
			(xy 342.445741 -223.360516) (xy 342.476291 -223.402564) (xy 342.499887 -223.448874) (xy 342.515948 -223.498304)
			(xy 342.524078 -223.549639) (xy 342.524588 -223.575626) (xy 342.524097 -223.601109) (xy 342.524022 -223.601593)
			(xy 342.803989 -223.601593) (xy 342.803989 -223.549659) (xy 342.812114 -223.498364) (xy 342.828162 -223.448971)
			(xy 342.85174 -223.402697) (xy 342.882266 -223.360681) (xy 342.918989 -223.323958) (xy 342.961005 -223.293432)
			(xy 343.007279 -223.269854) (xy 343.056672 -223.253806) (xy 343.107967 -223.245681) (xy 343.159901 -223.245681)
			(xy 343.211196 -223.253806) (xy 343.260589 -223.269854) (xy 343.306863 -223.293432) (xy 343.348879 -223.323958)
			(xy 343.385602 -223.360681) (xy 343.416128 -223.402697) (xy 343.439706 -223.448971) (xy 343.455754 -223.498364)
			(xy 343.463879 -223.549659) (xy 343.464388 -223.575626) (xy 343.463879 -223.601593) (xy 343.455754 -223.652888)
			(xy 343.439706 -223.702281) (xy 343.416128 -223.748555) (xy 343.385602 -223.790571) (xy 343.348879 -223.827294)
			(xy 343.306863 -223.85782) (xy 343.260589 -223.881398) (xy 343.211196 -223.897446) (xy 343.159901 -223.905571)
			(xy 343.107967 -223.905571) (xy 343.056672 -223.897446) (xy 343.007279 -223.881398) (xy 342.961005 -223.85782)
			(xy 342.918989 -223.827294) (xy 342.882266 -223.790571) (xy 342.85174 -223.748555) (xy 342.828162 -223.702281)
			(xy 342.812114 -223.652888) (xy 342.803989 -223.601593) (xy 342.524022 -223.601593) (xy 342.516288 -223.651474)
			(xy 342.500844 -223.700045) (xy 342.478129 -223.74567) (xy 342.448683 -223.787269) (xy 342.413202 -223.823858)
			(xy 342.372528 -223.854569) (xy 342.327622 -223.878676) (xy 342.27955 -223.895606) (xy 342.254586 -223.900746)
			(xy 342.231472 -223.905064) (xy 342.028272 -224.257362) (xy 342.036146 -224.27946) (xy 342.04489 -224.306047)
			(xy 342.054335 -224.361207) (xy 342.054942 -224.389188) (xy 342.054942 -224.389442) (xy 342.333326 -224.389442)
			(xy 342.333836 -224.363455) (xy 342.341966 -224.31212) (xy 342.358027 -224.26269) (xy 342.381623 -224.21638)
			(xy 342.412173 -224.174332) (xy 342.448924 -224.137581) (xy 342.490972 -224.107031) (xy 342.537282 -224.083435)
			(xy 342.586712 -224.067374) (xy 342.638047 -224.059244) (xy 342.690021 -224.059244) (xy 342.741356 -224.067374)
			(xy 342.790786 -224.083435) (xy 342.837096 -224.107031) (xy 342.879144 -224.137581) (xy 342.915895 -224.174332)
			(xy 342.946445 -224.21638) (xy 342.970041 -224.26269) (xy 342.986102 -224.31212) (xy 342.994232 -224.363455)
			(xy 342.994742 -224.389442) (xy 343.273126 -224.389442) (xy 343.273538 -224.363966) (xy 343.281333 -224.313615)
			(xy 343.29676 -224.265055) (xy 343.319455 -224.219437) (xy 343.348879 -224.177841) (xy 343.384336 -224.141251)
			(xy 343.424987 -224.110534) (xy 343.469869 -224.086417) (xy 343.51792 -224.069471) (xy 343.542874 -224.064322)
			(xy 343.565988 -224.060004) (xy 343.769442 -223.707452) (xy 343.761568 -223.685608) (xy 343.752817 -223.659024)
			(xy 343.743377 -223.603862) (xy 343.742772 -223.57588) (xy 343.742772 -223.575626) (xy 343.743282 -223.549639)
			(xy 343.751412 -223.498304) (xy 343.767473 -223.448874) (xy 343.791069 -223.402564) (xy 343.821619 -223.360516)
			(xy 343.85837 -223.323765) (xy 343.900418 -223.293215) (xy 343.946728 -223.269619) (xy 343.996158 -223.253558)
			(xy 344.047493 -223.245428) (xy 344.099467 -223.245428) (xy 344.150802 -223.253558) (xy 344.200232 -223.269619)
			(xy 344.246542 -223.293215) (xy 344.28859 -223.323765) (xy 344.325341 -223.360516) (xy 344.355891 -223.402564)
			(xy 344.379487 -223.448874) (xy 344.395548 -223.498304) (xy 344.403678 -223.549639) (xy 344.404188 -223.575626)
			(xy 344.403697 -223.601109) (xy 344.403622 -223.601593) (xy 344.683589 -223.601593) (xy 344.683589 -223.549659)
			(xy 344.691714 -223.498364) (xy 344.707762 -223.448971) (xy 344.73134 -223.402697) (xy 344.761866 -223.360681)
			(xy 344.798589 -223.323958) (xy 344.840605 -223.293432) (xy 344.886879 -223.269854) (xy 344.936272 -223.253806)
			(xy 344.987567 -223.245681) (xy 345.039501 -223.245681) (xy 345.090796 -223.253806) (xy 345.140189 -223.269854)
			(xy 345.186463 -223.293432) (xy 345.228479 -223.323958) (xy 345.265202 -223.360681) (xy 345.295728 -223.402697)
			(xy 345.319306 -223.448971) (xy 345.335354 -223.498364) (xy 345.343479 -223.549659) (xy 345.343988 -223.575626)
			(xy 345.343479 -223.601593) (xy 345.335354 -223.652888) (xy 345.319306 -223.702281) (xy 345.295728 -223.748555)
			(xy 345.265202 -223.790571) (xy 345.228479 -223.827294) (xy 345.186463 -223.85782) (xy 345.140189 -223.881398)
			(xy 345.090796 -223.897446) (xy 345.039501 -223.905571) (xy 344.987567 -223.905571) (xy 344.936272 -223.897446)
			(xy 344.886879 -223.881398) (xy 344.840605 -223.85782) (xy 344.798589 -223.827294) (xy 344.761866 -223.790571)
			(xy 344.73134 -223.748555) (xy 344.707762 -223.702281) (xy 344.691714 -223.652888) (xy 344.683589 -223.601593)
			(xy 344.403622 -223.601593) (xy 344.395888 -223.651474) (xy 344.380444 -223.700045) (xy 344.357729 -223.74567)
			(xy 344.328283 -223.787269) (xy 344.292802 -223.823858) (xy 344.252128 -223.854569) (xy 344.207222 -223.878676)
			(xy 344.15915 -223.895606) (xy 344.134186 -223.900746) (xy 344.111072 -223.905064) (xy 343.907872 -224.257362)
			(xy 343.915746 -224.27946) (xy 343.92449 -224.306047) (xy 343.933935 -224.361207) (xy 343.934542 -224.389188)
			(xy 343.934542 -224.389442) (xy 344.212926 -224.389442) (xy 344.213436 -224.363455) (xy 344.221566 -224.31212)
			(xy 344.237627 -224.26269) (xy 344.261223 -224.21638) (xy 344.291773 -224.174332) (xy 344.328524 -224.137581)
			(xy 344.370572 -224.107031) (xy 344.416882 -224.083435) (xy 344.466312 -224.067374) (xy 344.517647 -224.059244)
			(xy 344.569621 -224.059244) (xy 344.620956 -224.067374) (xy 344.670386 -224.083435) (xy 344.716696 -224.107031)
			(xy 344.758744 -224.137581) (xy 344.795495 -224.174332) (xy 344.826045 -224.21638) (xy 344.849641 -224.26269)
			(xy 344.865702 -224.31212) (xy 344.873832 -224.363455) (xy 344.874342 -224.389442) (xy 345.152726 -224.389442)
			(xy 345.153138 -224.363966) (xy 345.160933 -224.313615) (xy 345.17636 -224.265055) (xy 345.199055 -224.219437)
			(xy 345.228479 -224.177841) (xy 345.263936 -224.141251) (xy 345.304587 -224.110534) (xy 345.349469 -224.086417)
			(xy 345.39752 -224.069471) (xy 345.422474 -224.064322) (xy 345.445588 -224.060004) (xy 345.649042 -223.707452)
			(xy 345.641168 -223.685608) (xy 345.632417 -223.659024) (xy 345.622977 -223.603862) (xy 345.622372 -223.57588)
			(xy 345.622372 -223.575626) (xy 345.622882 -223.549639) (xy 345.631012 -223.498304) (xy 345.647073 -223.448874)
			(xy 345.670669 -223.402564) (xy 345.701219 -223.360516) (xy 345.73797 -223.323765) (xy 345.780018 -223.293215)
			(xy 345.826328 -223.269619) (xy 345.875758 -223.253558) (xy 345.927093 -223.245428) (xy 345.979067 -223.245428)
			(xy 346.030402 -223.253558) (xy 346.079832 -223.269619) (xy 346.126142 -223.293215) (xy 346.16819 -223.323765)
			(xy 346.204941 -223.360516) (xy 346.235491 -223.402564) (xy 346.259087 -223.448874) (xy 346.275148 -223.498304)
			(xy 346.283278 -223.549639) (xy 346.283788 -223.575626) (xy 346.283297 -223.601109) (xy 346.283222 -223.601593)
			(xy 346.563189 -223.601593) (xy 346.563189 -223.549659) (xy 346.571314 -223.498364) (xy 346.587362 -223.448971)
			(xy 346.61094 -223.402697) (xy 346.641466 -223.360681) (xy 346.678189 -223.323958) (xy 346.720205 -223.293432)
			(xy 346.766479 -223.269854) (xy 346.815872 -223.253806) (xy 346.867167 -223.245681) (xy 346.919101 -223.245681)
			(xy 346.970396 -223.253806) (xy 347.019789 -223.269854) (xy 347.066063 -223.293432) (xy 347.108079 -223.323958)
			(xy 347.144802 -223.360681) (xy 347.175328 -223.402697) (xy 347.198906 -223.448971) (xy 347.214954 -223.498364)
			(xy 347.223079 -223.549659) (xy 347.223588 -223.575626) (xy 347.223079 -223.601593) (xy 347.214954 -223.652888)
			(xy 347.198906 -223.702281) (xy 347.175328 -223.748555) (xy 347.144802 -223.790571) (xy 347.108079 -223.827294)
			(xy 347.066063 -223.85782) (xy 347.019789 -223.881398) (xy 346.970396 -223.897446) (xy 346.919101 -223.905571)
			(xy 346.867167 -223.905571) (xy 346.815872 -223.897446) (xy 346.766479 -223.881398) (xy 346.720205 -223.85782)
			(xy 346.678189 -223.827294) (xy 346.641466 -223.790571) (xy 346.61094 -223.748555) (xy 346.587362 -223.702281)
			(xy 346.571314 -223.652888) (xy 346.563189 -223.601593) (xy 346.283222 -223.601593) (xy 346.275488 -223.651474)
			(xy 346.260044 -223.700045) (xy 346.237329 -223.74567) (xy 346.207883 -223.787269) (xy 346.172402 -223.823858)
			(xy 346.131728 -223.854569) (xy 346.086822 -223.878676) (xy 346.03875 -223.895606) (xy 346.013786 -223.900746)
			(xy 345.990672 -223.905064) (xy 345.787472 -224.257362) (xy 345.795346 -224.27946) (xy 345.80409 -224.306047)
			(xy 345.813535 -224.361207) (xy 345.814142 -224.389188) (xy 345.814142 -224.389442) (xy 346.092526 -224.389442)
			(xy 346.093036 -224.363455) (xy 346.101166 -224.31212) (xy 346.117227 -224.26269) (xy 346.140823 -224.21638)
			(xy 346.171373 -224.174332) (xy 346.208124 -224.137581) (xy 346.250172 -224.107031) (xy 346.296482 -224.083435)
			(xy 346.345912 -224.067374) (xy 346.397247 -224.059244) (xy 346.449221 -224.059244) (xy 346.500556 -224.067374)
			(xy 346.549986 -224.083435) (xy 346.596296 -224.107031) (xy 346.638344 -224.137581) (xy 346.675095 -224.174332)
			(xy 346.705645 -224.21638) (xy 346.729241 -224.26269) (xy 346.745302 -224.31212) (xy 346.753432 -224.363455)
			(xy 346.753942 -224.389442) (xy 347.032326 -224.389442) (xy 347.032738 -224.363966) (xy 347.040533 -224.313615)
			(xy 347.05596 -224.265055) (xy 347.078655 -224.219437) (xy 347.108079 -224.177841) (xy 347.143536 -224.141251)
			(xy 347.184187 -224.110534) (xy 347.229069 -224.086417) (xy 347.27712 -224.069471) (xy 347.302074 -224.064322)
			(xy 347.325188 -224.060004) (xy 347.528642 -223.707452) (xy 347.520768 -223.685608) (xy 347.512017 -223.659024)
			(xy 347.502577 -223.603862) (xy 347.501972 -223.57588) (xy 347.501972 -223.575626) (xy 347.502482 -223.549639)
			(xy 347.510612 -223.498304) (xy 347.526673 -223.448874) (xy 347.550269 -223.402564) (xy 347.580819 -223.360516)
			(xy 347.61757 -223.323765) (xy 347.659618 -223.293215) (xy 347.705928 -223.269619) (xy 347.755358 -223.253558)
			(xy 347.806693 -223.245428) (xy 347.858667 -223.245428) (xy 347.910002 -223.253558) (xy 347.959432 -223.269619)
			(xy 348.005742 -223.293215) (xy 348.04779 -223.323765) (xy 348.084541 -223.360516) (xy 348.115091 -223.402564)
			(xy 348.138687 -223.448874) (xy 348.154748 -223.498304) (xy 348.162878 -223.549639) (xy 348.163388 -223.575626)
			(xy 348.162897 -223.601109) (xy 348.162822 -223.601593) (xy 348.442789 -223.601593) (xy 348.442789 -223.549659)
			(xy 348.450914 -223.498364) (xy 348.466962 -223.448971) (xy 348.49054 -223.402697) (xy 348.521066 -223.360681)
			(xy 348.557789 -223.323958) (xy 348.599805 -223.293432) (xy 348.646079 -223.269854) (xy 348.695472 -223.253806)
			(xy 348.746767 -223.245681) (xy 348.798701 -223.245681) (xy 348.849996 -223.253806) (xy 348.899389 -223.269854)
			(xy 348.945663 -223.293432) (xy 348.987679 -223.323958) (xy 349.024402 -223.360681) (xy 349.054928 -223.402697)
			(xy 349.078506 -223.448971) (xy 349.094554 -223.498364) (xy 349.102679 -223.549659) (xy 349.103188 -223.575626)
			(xy 349.102679 -223.601593) (xy 349.094554 -223.652888) (xy 349.078506 -223.702281) (xy 349.054928 -223.748555)
			(xy 349.024402 -223.790571) (xy 348.987679 -223.827294) (xy 348.945663 -223.85782) (xy 348.899389 -223.881398)
			(xy 348.849996 -223.897446) (xy 348.798701 -223.905571) (xy 348.746767 -223.905571) (xy 348.695472 -223.897446)
			(xy 348.646079 -223.881398) (xy 348.599805 -223.85782) (xy 348.557789 -223.827294) (xy 348.521066 -223.790571)
			(xy 348.49054 -223.748555) (xy 348.466962 -223.702281) (xy 348.450914 -223.652888) (xy 348.442789 -223.601593)
			(xy 348.162822 -223.601593) (xy 348.155088 -223.651474) (xy 348.139644 -223.700045) (xy 348.116929 -223.74567)
			(xy 348.087483 -223.787269) (xy 348.052002 -223.823858) (xy 348.011328 -223.854569) (xy 347.966422 -223.878676)
			(xy 347.91835 -223.895606) (xy 347.893386 -223.900746) (xy 347.870272 -223.905064) (xy 347.667072 -224.257362)
			(xy 347.674946 -224.27946) (xy 347.68369 -224.306047) (xy 347.693135 -224.361207) (xy 347.693742 -224.389188)
			(xy 347.693742 -224.389442) (xy 347.972126 -224.389442) (xy 347.972636 -224.363455) (xy 347.980766 -224.31212)
			(xy 347.996827 -224.26269) (xy 348.020423 -224.21638) (xy 348.050973 -224.174332) (xy 348.087724 -224.137581)
			(xy 348.129772 -224.107031) (xy 348.176082 -224.083435) (xy 348.225512 -224.067374) (xy 348.276847 -224.059244)
			(xy 348.328821 -224.059244) (xy 348.380156 -224.067374) (xy 348.429586 -224.083435) (xy 348.475896 -224.107031)
			(xy 348.517944 -224.137581) (xy 348.554695 -224.174332) (xy 348.585245 -224.21638) (xy 348.608841 -224.26269)
			(xy 348.624902 -224.31212) (xy 348.633032 -224.363455) (xy 348.633542 -224.389442) (xy 348.633542 -224.389696)
			(xy 348.632942 -224.417678) (xy 348.623498 -224.472839) (xy 348.614746 -224.499424) (xy 348.606872 -224.521522)
			(xy 348.810326 -224.87382) (xy 348.833186 -224.878138) (xy 348.858147 -224.883289) (xy 348.906214 -224.900227)
			(xy 348.951115 -224.924337) (xy 348.991787 -224.955049) (xy 349.027267 -224.991635) (xy 349.056716 -225.03323)
			(xy 349.079437 -225.07885) (xy 349.094892 -225.127415) (xy 349.102715 -225.177776) (xy 349.103188 -225.203258)
			(xy 349.102678 -225.229245) (xy 349.094548 -225.28058) (xy 349.078487 -225.33001) (xy 349.054891 -225.37632)
			(xy 349.024341 -225.418368) (xy 348.98759 -225.455119) (xy 348.945542 -225.485669) (xy 348.899232 -225.509265)
			(xy 348.849802 -225.525326) (xy 348.798467 -225.533456) (xy 348.746493 -225.533456) (xy 348.695158 -225.525326)
			(xy 348.645728 -225.509265) (xy 348.599418 -225.485669) (xy 348.55737 -225.455119) (xy 348.520619 -225.418368)
			(xy 348.490069 -225.37632) (xy 348.466473 -225.33001) (xy 348.450412 -225.28058) (xy 348.442282 -225.229245)
			(xy 348.441772 -225.203258) (xy 348.441772 -225.203004) (xy 348.442372 -225.175022) (xy 348.451816 -225.119861)
			(xy 348.460568 -225.093276) (xy 348.468442 -225.071178) (xy 348.264988 -224.71888) (xy 348.242128 -224.714562)
			(xy 348.217169 -224.709401) (xy 348.169102 -224.692465) (xy 348.1242 -224.668356) (xy 348.083528 -224.637646)
			(xy 348.048048 -224.601061) (xy 348.018599 -224.559467) (xy 347.995878 -224.513848) (xy 347.980423 -224.465284)
			(xy 347.972599 -224.414924) (xy 347.972126 -224.389442) (xy 347.693742 -224.389442) (xy 347.693232 -224.415429)
			(xy 347.685102 -224.466764) (xy 347.669041 -224.516194) (xy 347.645445 -224.562504) (xy 347.614895 -224.604552)
			(xy 347.578144 -224.641303) (xy 347.536096 -224.671853) (xy 347.489786 -224.695449) (xy 347.440356 -224.71151)
			(xy 347.389021 -224.71964) (xy 347.337047 -224.71964) (xy 347.285712 -224.71151) (xy 347.236282 -224.695449)
			(xy 347.189972 -224.671853) (xy 347.147924 -224.641303) (xy 347.111173 -224.604552) (xy 347.080623 -224.562504)
			(xy 347.057027 -224.516194) (xy 347.040966 -224.466764) (xy 347.032836 -224.415429) (xy 347.032326 -224.389442)
			(xy 346.753942 -224.389442) (xy 346.753942 -224.389696) (xy 346.753342 -224.417678) (xy 346.743898 -224.472839)
			(xy 346.735146 -224.499424) (xy 346.727272 -224.521522) (xy 346.930726 -224.87382) (xy 346.953586 -224.878138)
			(xy 346.978547 -224.883289) (xy 347.026614 -224.900227) (xy 347.071515 -224.924337) (xy 347.112187 -224.955049)
			(xy 347.147667 -224.991635) (xy 347.177116 -225.03323) (xy 347.199837 -225.07885) (xy 347.215292 -225.127415)
			(xy 347.223115 -225.177776) (xy 347.223588 -225.203258) (xy 347.223078 -225.229245) (xy 347.214948 -225.28058)
			(xy 347.198887 -225.33001) (xy 347.175291 -225.37632) (xy 347.144741 -225.418368) (xy 347.10799 -225.455119)
			(xy 347.065942 -225.485669) (xy 347.019632 -225.509265) (xy 346.970202 -225.525326) (xy 346.918867 -225.533456)
			(xy 346.866893 -225.533456) (xy 346.815558 -225.525326) (xy 346.766128 -225.509265) (xy 346.719818 -225.485669)
			(xy 346.67777 -225.455119) (xy 346.641019 -225.418368) (xy 346.610469 -225.37632) (xy 346.586873 -225.33001)
			(xy 346.570812 -225.28058) (xy 346.562682 -225.229245) (xy 346.562172 -225.203258) (xy 346.562172 -225.203004)
			(xy 346.562772 -225.175022) (xy 346.572216 -225.119861) (xy 346.580968 -225.093276) (xy 346.588842 -225.071178)
			(xy 346.385388 -224.71888) (xy 346.362528 -224.714562) (xy 346.337569 -224.709401) (xy 346.289502 -224.692465)
			(xy 346.2446 -224.668356) (xy 346.203928 -224.637646) (xy 346.168448 -224.601061) (xy 346.138999 -224.559467)
			(xy 346.116278 -224.513848) (xy 346.100823 -224.465284) (xy 346.092999 -224.414924) (xy 346.092526 -224.389442)
			(xy 345.814142 -224.389442) (xy 345.813632 -224.415429) (xy 345.805502 -224.466764) (xy 345.789441 -224.516194)
			(xy 345.765845 -224.562504) (xy 345.735295 -224.604552) (xy 345.698544 -224.641303) (xy 345.656496 -224.671853)
			(xy 345.610186 -224.695449) (xy 345.560756 -224.71151) (xy 345.509421 -224.71964) (xy 345.457447 -224.71964)
			(xy 345.406112 -224.71151) (xy 345.356682 -224.695449) (xy 345.310372 -224.671853) (xy 345.268324 -224.641303)
			(xy 345.231573 -224.604552) (xy 345.201023 -224.562504) (xy 345.177427 -224.516194) (xy 345.161366 -224.466764)
			(xy 345.153236 -224.415429) (xy 345.152726 -224.389442) (xy 344.874342 -224.389442) (xy 344.874342 -224.389696)
			(xy 344.873742 -224.417678) (xy 344.864298 -224.472839) (xy 344.855546 -224.499424) (xy 344.847672 -224.521522)
			(xy 345.051126 -224.87382) (xy 345.073986 -224.878138) (xy 345.098947 -224.883289) (xy 345.147014 -224.900227)
			(xy 345.191915 -224.924337) (xy 345.232587 -224.955049) (xy 345.268067 -224.991635) (xy 345.297516 -225.03323)
			(xy 345.320237 -225.07885) (xy 345.335692 -225.127415) (xy 345.343515 -225.177776) (xy 345.343988 -225.203258)
			(xy 345.343478 -225.229245) (xy 345.335348 -225.28058) (xy 345.319287 -225.33001) (xy 345.295691 -225.37632)
			(xy 345.265141 -225.418368) (xy 345.22839 -225.455119) (xy 345.186342 -225.485669) (xy 345.140032 -225.509265)
			(xy 345.090602 -225.525326) (xy 345.039267 -225.533456) (xy 344.987293 -225.533456) (xy 344.935958 -225.525326)
			(xy 344.886528 -225.509265) (xy 344.840218 -225.485669) (xy 344.79817 -225.455119) (xy 344.761419 -225.418368)
			(xy 344.730869 -225.37632) (xy 344.707273 -225.33001) (xy 344.691212 -225.28058) (xy 344.683082 -225.229245)
			(xy 344.682572 -225.203258) (xy 344.682572 -225.203004) (xy 344.683172 -225.175022) (xy 344.692616 -225.119861)
			(xy 344.701368 -225.093276) (xy 344.709242 -225.071178) (xy 344.505788 -224.71888) (xy 344.482928 -224.714562)
			(xy 344.457969 -224.709401) (xy 344.409902 -224.692465) (xy 344.365 -224.668356) (xy 344.324328 -224.637646)
			(xy 344.288848 -224.601061) (xy 344.259399 -224.559467) (xy 344.236678 -224.513848) (xy 344.221223 -224.465284)
			(xy 344.213399 -224.414924) (xy 344.212926 -224.389442) (xy 343.934542 -224.389442) (xy 343.934032 -224.415429)
			(xy 343.925902 -224.466764) (xy 343.909841 -224.516194) (xy 343.886245 -224.562504) (xy 343.855695 -224.604552)
			(xy 343.818944 -224.641303) (xy 343.776896 -224.671853) (xy 343.730586 -224.695449) (xy 343.681156 -224.71151)
			(xy 343.629821 -224.71964) (xy 343.577847 -224.71964) (xy 343.526512 -224.71151) (xy 343.477082 -224.695449)
			(xy 343.430772 -224.671853) (xy 343.388724 -224.641303) (xy 343.351973 -224.604552) (xy 343.321423 -224.562504)
			(xy 343.297827 -224.516194) (xy 343.281766 -224.466764) (xy 343.273636 -224.415429) (xy 343.273126 -224.389442)
			(xy 342.994742 -224.389442) (xy 342.994742 -224.389696) (xy 342.994142 -224.417678) (xy 342.984698 -224.472839)
			(xy 342.975946 -224.499424) (xy 342.968072 -224.521522) (xy 343.171526 -224.87382) (xy 343.194386 -224.878138)
			(xy 343.219347 -224.883289) (xy 343.267414 -224.900227) (xy 343.312315 -224.924337) (xy 343.352987 -224.955049)
			(xy 343.388467 -224.991635) (xy 343.417916 -225.03323) (xy 343.440637 -225.07885) (xy 343.456092 -225.127415)
			(xy 343.463915 -225.177776) (xy 343.464388 -225.203258) (xy 343.463878 -225.229245) (xy 343.455748 -225.28058)
			(xy 343.439687 -225.33001) (xy 343.416091 -225.37632) (xy 343.385541 -225.418368) (xy 343.34879 -225.455119)
			(xy 343.306742 -225.485669) (xy 343.260432 -225.509265) (xy 343.211002 -225.525326) (xy 343.159667 -225.533456)
			(xy 343.107693 -225.533456) (xy 343.056358 -225.525326) (xy 343.006928 -225.509265) (xy 342.960618 -225.485669)
			(xy 342.91857 -225.455119) (xy 342.881819 -225.418368) (xy 342.851269 -225.37632) (xy 342.827673 -225.33001)
			(xy 342.811612 -225.28058) (xy 342.803482 -225.229245) (xy 342.802972 -225.203258) (xy 342.802972 -225.203004)
			(xy 342.803572 -225.175022) (xy 342.813016 -225.119861) (xy 342.821768 -225.093276) (xy 342.829642 -225.071178)
			(xy 342.626188 -224.71888) (xy 342.603328 -224.714562) (xy 342.578369 -224.709401) (xy 342.530302 -224.692465)
			(xy 342.4854 -224.668356) (xy 342.444728 -224.637646) (xy 342.409248 -224.601061) (xy 342.379799 -224.559467)
			(xy 342.357078 -224.513848) (xy 342.341623 -224.465284) (xy 342.333799 -224.414924) (xy 342.333326 -224.389442)
			(xy 342.054942 -224.389442) (xy 342.054432 -224.415429) (xy 342.046302 -224.466764) (xy 342.030241 -224.516194)
			(xy 342.006645 -224.562504) (xy 341.976095 -224.604552) (xy 341.939344 -224.641303) (xy 341.897296 -224.671853)
			(xy 341.850986 -224.695449) (xy 341.801556 -224.71151) (xy 341.750221 -224.71964) (xy 341.698247 -224.71964)
			(xy 341.646912 -224.71151) (xy 341.597482 -224.695449) (xy 341.551172 -224.671853) (xy 341.509124 -224.641303)
			(xy 341.472373 -224.604552) (xy 341.441823 -224.562504) (xy 341.418227 -224.516194) (xy 341.402166 -224.466764)
			(xy 341.394036 -224.415429) (xy 341.393526 -224.389442) (xy 341.115142 -224.389442) (xy 341.115142 -224.389696)
			(xy 341.114542 -224.417678) (xy 341.105098 -224.472839) (xy 341.096346 -224.499424) (xy 341.088472 -224.521522)
			(xy 341.291926 -224.87382) (xy 341.314786 -224.878138) (xy 341.339747 -224.883289) (xy 341.387814 -224.900227)
			(xy 341.432715 -224.924337) (xy 341.473387 -224.955049) (xy 341.508867 -224.991635) (xy 341.538316 -225.03323)
			(xy 341.561037 -225.07885) (xy 341.576492 -225.127415) (xy 341.584315 -225.177776) (xy 341.584788 -225.203258)
			(xy 341.584278 -225.229245) (xy 341.576148 -225.28058) (xy 341.560087 -225.33001) (xy 341.536491 -225.37632)
			(xy 341.505941 -225.418368) (xy 341.46919 -225.455119) (xy 341.427142 -225.485669) (xy 341.380832 -225.509265)
			(xy 341.331402 -225.525326) (xy 341.280067 -225.533456) (xy 341.228093 -225.533456) (xy 341.176758 -225.525326)
			(xy 341.127328 -225.509265) (xy 341.081018 -225.485669) (xy 341.03897 -225.455119) (xy 341.002219 -225.418368)
			(xy 340.971669 -225.37632) (xy 340.948073 -225.33001) (xy 340.932012 -225.28058) (xy 340.923882 -225.229245)
			(xy 340.923372 -225.203258) (xy 340.923372 -225.203004) (xy 340.923972 -225.175022) (xy 340.933416 -225.119861)
			(xy 340.942168 -225.093276) (xy 340.950042 -225.071178) (xy 340.746588 -224.71888) (xy 340.723728 -224.714562)
			(xy 340.698769 -224.709401) (xy 340.650702 -224.692465) (xy 340.6058 -224.668356) (xy 340.565128 -224.637646)
			(xy 340.529648 -224.601061) (xy 340.500199 -224.559467) (xy 340.477478 -224.513848) (xy 340.462023 -224.465284)
			(xy 340.454199 -224.414924) (xy 340.453726 -224.389442) (xy 340.175342 -224.389442) (xy 340.174832 -224.415429)
			(xy 340.166702 -224.466764) (xy 340.150641 -224.516194) (xy 340.127045 -224.562504) (xy 340.096495 -224.604552)
			(xy 340.059744 -224.641303) (xy 340.017696 -224.671853) (xy 339.971386 -224.695449) (xy 339.921956 -224.71151)
			(xy 339.870621 -224.71964) (xy 339.818647 -224.71964) (xy 339.767312 -224.71151) (xy 339.717882 -224.695449)
			(xy 339.671572 -224.671853) (xy 339.629524 -224.641303) (xy 339.592773 -224.604552) (xy 339.562223 -224.562504)
			(xy 339.538627 -224.516194) (xy 339.522566 -224.466764) (xy 339.514436 -224.415429) (xy 339.513926 -224.389442)
			(xy 339.235542 -224.389442) (xy 339.235542 -224.389696) (xy 339.234936 -224.417677) (xy 339.225494 -224.472839)
			(xy 339.216746 -224.499424) (xy 339.208872 -224.521522) (xy 339.412326 -224.87382) (xy 339.435186 -224.878138)
			(xy 339.460151 -224.883277) (xy 339.508224 -224.900208) (xy 339.553131 -224.924314) (xy 339.593807 -224.955025)
			(xy 339.629289 -224.991613) (xy 339.658737 -225.033213) (xy 339.681454 -225.078838) (xy 339.696901 -225.127408)
			(xy 339.704712 -225.177774) (xy 339.705188 -225.203258) (xy 339.704717 -225.228776) (xy 339.696881 -225.279206)
			(xy 339.681387 -225.327833) (xy 339.658604 -225.373501) (xy 339.629073 -225.415125) (xy 339.593496 -225.451717)
			(xy 339.552719 -225.482406) (xy 339.530436 -225.49485) (xy 339.503512 -225.509328) (xy 339.503512 -225.657918)
			(xy 339.504002 -225.671633) (xy 339.511384 -225.698054) (xy 339.52553 -225.721558) (xy 339.54542 -225.740451)
			(xy 339.56962 -225.753371) (xy 339.596386 -225.759386) (xy 339.623787 -225.758062) (xy 339.649848 -225.749494)
			(xy 339.6615 -225.742246) (xy 339.681943 -225.729148) (xy 339.725857 -225.708442) (xy 339.77233 -225.694387)
			(xy 339.820358 -225.687285) (xy 339.844634 -225.686874) (xy 339.870597 -225.687386) (xy 339.921884 -225.695514)
			(xy 339.971268 -225.711564) (xy 340.017533 -225.735141) (xy 340.059541 -225.765666) (xy 340.096256 -225.802385)
			(xy 340.126776 -225.844396) (xy 340.150349 -225.890664) (xy 340.166394 -225.940049) (xy 340.174517 -225.991337)
			(xy 340.174517 -226.043263) (xy 340.174512 -226.043295) (xy 340.454489 -226.043295) (xy 340.454489 -225.991361)
			(xy 340.462614 -225.940066) (xy 340.478662 -225.890673) (xy 340.50224 -225.844399) (xy 340.532766 -225.802383)
			(xy 340.569489 -225.76566) (xy 340.611505 -225.735134) (xy 340.657779 -225.711556) (xy 340.707172 -225.695508)
			(xy 340.758467 -225.687383) (xy 340.810401 -225.687383) (xy 340.861696 -225.695508) (xy 340.911089 -225.711556)
			(xy 340.957363 -225.735134) (xy 340.999379 -225.76566) (xy 341.036102 -225.802383) (xy 341.066628 -225.844399)
			(xy 341.090206 -225.890673) (xy 341.106254 -225.940066) (xy 341.114379 -225.991361) (xy 341.114888 -226.017328)
			(xy 341.114379 -226.043295) (xy 341.394289 -226.043295) (xy 341.394289 -225.991361) (xy 341.402414 -225.940066)
			(xy 341.418462 -225.890673) (xy 341.44204 -225.844399) (xy 341.472566 -225.802383) (xy 341.509289 -225.76566)
			(xy 341.551305 -225.735134) (xy 341.597579 -225.711556) (xy 341.646972 -225.695508) (xy 341.698267 -225.687383)
			(xy 341.750201 -225.687383) (xy 341.801496 -225.695508) (xy 341.850889 -225.711556) (xy 341.897163 -225.735134)
			(xy 341.939179 -225.76566) (xy 341.975902 -225.802383) (xy 342.006428 -225.844399) (xy 342.030006 -225.890673)
			(xy 342.046054 -225.940066) (xy 342.054179 -225.991361) (xy 342.054688 -226.017328) (xy 342.054179 -226.043295)
			(xy 342.334089 -226.043295) (xy 342.334089 -225.991361) (xy 342.342214 -225.940066) (xy 342.358262 -225.890673)
			(xy 342.38184 -225.844399) (xy 342.412366 -225.802383) (xy 342.449089 -225.76566) (xy 342.491105 -225.735134)
			(xy 342.537379 -225.711556) (xy 342.586772 -225.695508) (xy 342.638067 -225.687383) (xy 342.690001 -225.687383)
			(xy 342.741296 -225.695508) (xy 342.790689 -225.711556) (xy 342.836963 -225.735134) (xy 342.878979 -225.76566)
			(xy 342.915702 -225.802383) (xy 342.946228 -225.844399) (xy 342.969806 -225.890673) (xy 342.985854 -225.940066)
			(xy 342.993979 -225.991361) (xy 342.994488 -226.017328) (xy 342.993979 -226.043295) (xy 343.273889 -226.043295)
			(xy 343.273889 -225.991361) (xy 343.282014 -225.940066) (xy 343.298062 -225.890673) (xy 343.32164 -225.844399)
			(xy 343.352166 -225.802383) (xy 343.388889 -225.76566) (xy 343.430905 -225.735134) (xy 343.477179 -225.711556)
			(xy 343.526572 -225.695508) (xy 343.577867 -225.687383) (xy 343.629801 -225.687383) (xy 343.681096 -225.695508)
			(xy 343.730489 -225.711556) (xy 343.776763 -225.735134) (xy 343.818779 -225.76566) (xy 343.855502 -225.802383)
			(xy 343.886028 -225.844399) (xy 343.909606 -225.890673) (xy 343.925654 -225.940066) (xy 343.933779 -225.991361)
			(xy 343.934288 -226.017328) (xy 343.933779 -226.043295) (xy 344.213689 -226.043295) (xy 344.213689 -225.991361)
			(xy 344.221814 -225.940066) (xy 344.237862 -225.890673) (xy 344.26144 -225.844399) (xy 344.291966 -225.802383)
			(xy 344.328689 -225.76566) (xy 344.370705 -225.735134) (xy 344.416979 -225.711556) (xy 344.466372 -225.695508)
			(xy 344.517667 -225.687383) (xy 344.569601 -225.687383) (xy 344.620896 -225.695508) (xy 344.670289 -225.711556)
			(xy 344.716563 -225.735134) (xy 344.758579 -225.76566) (xy 344.795302 -225.802383) (xy 344.825828 -225.844399)
			(xy 344.849406 -225.890673) (xy 344.865454 -225.940066) (xy 344.873579 -225.991361) (xy 344.874088 -226.017328)
			(xy 344.873579 -226.043295) (xy 345.153489 -226.043295) (xy 345.153489 -225.991361) (xy 345.161614 -225.940066)
			(xy 345.177662 -225.890673) (xy 345.20124 -225.844399) (xy 345.231766 -225.802383) (xy 345.268489 -225.76566)
			(xy 345.310505 -225.735134) (xy 345.356779 -225.711556) (xy 345.406172 -225.695508) (xy 345.457467 -225.687383)
			(xy 345.509401 -225.687383) (xy 345.560696 -225.695508) (xy 345.610089 -225.711556) (xy 345.656363 -225.735134)
			(xy 345.698379 -225.76566) (xy 345.735102 -225.802383) (xy 345.765628 -225.844399) (xy 345.789206 -225.890673)
			(xy 345.805254 -225.940066) (xy 345.813379 -225.991361) (xy 345.813888 -226.017328) (xy 345.813379 -226.043295)
			(xy 346.093289 -226.043295) (xy 346.093289 -225.991361) (xy 346.101414 -225.940066) (xy 346.117462 -225.890673)
			(xy 346.14104 -225.844399) (xy 346.171566 -225.802383) (xy 346.208289 -225.76566) (xy 346.250305 -225.735134)
			(xy 346.296579 -225.711556) (xy 346.345972 -225.695508) (xy 346.397267 -225.687383) (xy 346.449201 -225.687383)
			(xy 346.500496 -225.695508) (xy 346.549889 -225.711556) (xy 346.596163 -225.735134) (xy 346.638179 -225.76566)
			(xy 346.674902 -225.802383) (xy 346.705428 -225.844399) (xy 346.729006 -225.890673) (xy 346.745054 -225.940066)
			(xy 346.753179 -225.991361) (xy 346.753688 -226.017328) (xy 346.753179 -226.043295) (xy 347.033089 -226.043295)
			(xy 347.033089 -225.991361) (xy 347.041214 -225.940066) (xy 347.057262 -225.890673) (xy 347.08084 -225.844399)
			(xy 347.111366 -225.802383) (xy 347.148089 -225.76566) (xy 347.190105 -225.735134) (xy 347.236379 -225.711556)
			(xy 347.285772 -225.695508) (xy 347.337067 -225.687383) (xy 347.389001 -225.687383) (xy 347.440296 -225.695508)
			(xy 347.489689 -225.711556) (xy 347.535963 -225.735134) (xy 347.577979 -225.76566) (xy 347.614702 -225.802383)
			(xy 347.645228 -225.844399) (xy 347.668806 -225.890673) (xy 347.684854 -225.940066) (xy 347.692979 -225.991361)
			(xy 347.693488 -226.017328) (xy 347.692979 -226.043295) (xy 347.972889 -226.043295) (xy 347.972889 -225.991361)
			(xy 347.981014 -225.940066) (xy 347.997062 -225.890673) (xy 348.02064 -225.844399) (xy 348.051166 -225.802383)
			(xy 348.087889 -225.76566) (xy 348.129905 -225.735134) (xy 348.176179 -225.711556) (xy 348.225572 -225.695508)
			(xy 348.276867 -225.687383) (xy 348.328801 -225.687383) (xy 348.380096 -225.695508) (xy 348.429489 -225.711556)
			(xy 348.475763 -225.735134) (xy 348.517779 -225.76566) (xy 348.554502 -225.802383) (xy 348.585028 -225.844399)
			(xy 348.608606 -225.890673) (xy 348.624654 -225.940066) (xy 348.632779 -225.991361) (xy 348.633288 -226.017328)
			(xy 348.632779 -226.043295) (xy 348.912689 -226.043295) (xy 348.912689 -225.991361) (xy 348.920814 -225.940066)
			(xy 348.936862 -225.890673) (xy 348.96044 -225.844399) (xy 348.990966 -225.802383) (xy 349.027689 -225.76566)
			(xy 349.069705 -225.735134) (xy 349.115979 -225.711556) (xy 349.165372 -225.695508) (xy 349.216667 -225.687383)
			(xy 349.268601 -225.687383) (xy 349.319896 -225.695508) (xy 349.369289 -225.711556) (xy 349.415563 -225.735134)
			(xy 349.457579 -225.76566) (xy 349.494302 -225.802383) (xy 349.524828 -225.844399) (xy 349.548406 -225.890673)
			(xy 349.564454 -225.940066) (xy 349.572579 -225.991361) (xy 349.573088 -226.017328) (xy 349.572579 -226.043295)
			(xy 349.564454 -226.09459) (xy 349.548406 -226.143983) (xy 349.524828 -226.190257) (xy 349.494302 -226.232273)
			(xy 349.457579 -226.268996) (xy 349.415563 -226.299522) (xy 349.369289 -226.3231) (xy 349.319896 -226.339148)
			(xy 349.268601 -226.347273) (xy 349.216667 -226.347273) (xy 349.165372 -226.339148) (xy 349.115979 -226.3231)
			(xy 349.069705 -226.299522) (xy 349.027689 -226.268996) (xy 348.990966 -226.232273) (xy 348.96044 -226.190257)
			(xy 348.936862 -226.143983) (xy 348.920814 -226.09459) (xy 348.912689 -226.043295) (xy 348.632779 -226.043295)
			(xy 348.624654 -226.09459) (xy 348.608606 -226.143983) (xy 348.585028 -226.190257) (xy 348.554502 -226.232273)
			(xy 348.517779 -226.268996) (xy 348.475763 -226.299522) (xy 348.429489 -226.3231) (xy 348.380096 -226.339148)
			(xy 348.328801 -226.347273) (xy 348.276867 -226.347273) (xy 348.225572 -226.339148) (xy 348.176179 -226.3231)
			(xy 348.129905 -226.299522) (xy 348.087889 -226.268996) (xy 348.051166 -226.232273) (xy 348.02064 -226.190257)
			(xy 347.997062 -226.143983) (xy 347.981014 -226.09459) (xy 347.972889 -226.043295) (xy 347.692979 -226.043295)
			(xy 347.684854 -226.09459) (xy 347.668806 -226.143983) (xy 347.645228 -226.190257) (xy 347.614702 -226.232273)
			(xy 347.577979 -226.268996) (xy 347.535963 -226.299522) (xy 347.489689 -226.3231) (xy 347.440296 -226.339148)
			(xy 347.389001 -226.347273) (xy 347.337067 -226.347273) (xy 347.285772 -226.339148) (xy 347.236379 -226.3231)
			(xy 347.190105 -226.299522) (xy 347.148089 -226.268996) (xy 347.111366 -226.232273) (xy 347.08084 -226.190257)
			(xy 347.057262 -226.143983) (xy 347.041214 -226.09459) (xy 347.033089 -226.043295) (xy 346.753179 -226.043295)
			(xy 346.745054 -226.09459) (xy 346.729006 -226.143983) (xy 346.705428 -226.190257) (xy 346.674902 -226.232273)
			(xy 346.638179 -226.268996) (xy 346.596163 -226.299522) (xy 346.549889 -226.3231) (xy 346.500496 -226.339148)
			(xy 346.449201 -226.347273) (xy 346.397267 -226.347273) (xy 346.345972 -226.339148) (xy 346.296579 -226.3231)
			(xy 346.250305 -226.299522) (xy 346.208289 -226.268996) (xy 346.171566 -226.232273) (xy 346.14104 -226.190257)
			(xy 346.117462 -226.143983) (xy 346.101414 -226.09459) (xy 346.093289 -226.043295) (xy 345.813379 -226.043295)
			(xy 345.805254 -226.09459) (xy 345.789206 -226.143983) (xy 345.765628 -226.190257) (xy 345.735102 -226.232273)
			(xy 345.698379 -226.268996) (xy 345.656363 -226.299522) (xy 345.610089 -226.3231) (xy 345.560696 -226.339148)
			(xy 345.509401 -226.347273) (xy 345.457467 -226.347273) (xy 345.406172 -226.339148) (xy 345.356779 -226.3231)
			(xy 345.310505 -226.299522) (xy 345.268489 -226.268996) (xy 345.231766 -226.232273) (xy 345.20124 -226.190257)
			(xy 345.177662 -226.143983) (xy 345.161614 -226.09459) (xy 345.153489 -226.043295) (xy 344.873579 -226.043295)
			(xy 344.865454 -226.09459) (xy 344.849406 -226.143983) (xy 344.825828 -226.190257) (xy 344.795302 -226.232273)
			(xy 344.758579 -226.268996) (xy 344.716563 -226.299522) (xy 344.670289 -226.3231) (xy 344.620896 -226.339148)
			(xy 344.569601 -226.347273) (xy 344.517667 -226.347273) (xy 344.466372 -226.339148) (xy 344.416979 -226.3231)
			(xy 344.370705 -226.299522) (xy 344.328689 -226.268996) (xy 344.291966 -226.232273) (xy 344.26144 -226.190257)
			(xy 344.237862 -226.143983) (xy 344.221814 -226.09459) (xy 344.213689 -226.043295) (xy 343.933779 -226.043295)
			(xy 343.925654 -226.09459) (xy 343.909606 -226.143983) (xy 343.886028 -226.190257) (xy 343.855502 -226.232273)
			(xy 343.818779 -226.268996) (xy 343.776763 -226.299522) (xy 343.730489 -226.3231) (xy 343.681096 -226.339148)
			(xy 343.629801 -226.347273) (xy 343.577867 -226.347273) (xy 343.526572 -226.339148) (xy 343.477179 -226.3231)
			(xy 343.430905 -226.299522) (xy 343.388889 -226.268996) (xy 343.352166 -226.232273) (xy 343.32164 -226.190257)
			(xy 343.298062 -226.143983) (xy 343.282014 -226.09459) (xy 343.273889 -226.043295) (xy 342.993979 -226.043295)
			(xy 342.985854 -226.09459) (xy 342.969806 -226.143983) (xy 342.946228 -226.190257) (xy 342.915702 -226.232273)
			(xy 342.878979 -226.268996) (xy 342.836963 -226.299522) (xy 342.790689 -226.3231) (xy 342.741296 -226.339148)
			(xy 342.690001 -226.347273) (xy 342.638067 -226.347273) (xy 342.586772 -226.339148) (xy 342.537379 -226.3231)
			(xy 342.491105 -226.299522) (xy 342.449089 -226.268996) (xy 342.412366 -226.232273) (xy 342.38184 -226.190257)
			(xy 342.358262 -226.143983) (xy 342.342214 -226.09459) (xy 342.334089 -226.043295) (xy 342.054179 -226.043295)
			(xy 342.046054 -226.09459) (xy 342.030006 -226.143983) (xy 342.006428 -226.190257) (xy 341.975902 -226.232273)
			(xy 341.939179 -226.268996) (xy 341.897163 -226.299522) (xy 341.850889 -226.3231) (xy 341.801496 -226.339148)
			(xy 341.750201 -226.347273) (xy 341.698267 -226.347273) (xy 341.646972 -226.339148) (xy 341.597579 -226.3231)
			(xy 341.551305 -226.299522) (xy 341.509289 -226.268996) (xy 341.472566 -226.232273) (xy 341.44204 -226.190257)
			(xy 341.418462 -226.143983) (xy 341.402414 -226.09459) (xy 341.394289 -226.043295) (xy 341.114379 -226.043295)
			(xy 341.106254 -226.09459) (xy 341.090206 -226.143983) (xy 341.066628 -226.190257) (xy 341.036102 -226.232273)
			(xy 340.999379 -226.268996) (xy 340.957363 -226.299522) (xy 340.911089 -226.3231) (xy 340.861696 -226.339148)
			(xy 340.810401 -226.347273) (xy 340.758467 -226.347273) (xy 340.707172 -226.339148) (xy 340.657779 -226.3231)
			(xy 340.611505 -226.299522) (xy 340.569489 -226.268996) (xy 340.532766 -226.232273) (xy 340.50224 -226.190257)
			(xy 340.478662 -226.143983) (xy 340.462614 -226.09459) (xy 340.454489 -226.043295) (xy 340.174512 -226.043295)
			(xy 340.166394 -226.094551) (xy 340.150349 -226.143936) (xy 340.126776 -226.190204) (xy 340.096256 -226.232215)
			(xy 340.059541 -226.268934) (xy 340.017533 -226.299459) (xy 339.971268 -226.323036) (xy 339.921884 -226.339086)
			(xy 339.870597 -226.347214) (xy 339.844634 -226.347782) (xy 339.820779 -226.347358) (xy 339.773566 -226.340488)
			(xy 339.727832 -226.326901) (xy 339.684526 -226.306877) (xy 339.644551 -226.280835) (xy 339.608735 -226.249315)
			(xy 339.59292 -226.23145) (xy 339.57768 -226.21367) (xy 339.503512 -226.21367) (xy 339.503512 -226.308666)
			(xy 339.495211 -226.313062) (xy 339.482405 -226.326783) (xy 339.475509 -226.34424) (xy 339.475064 -226.353624)
			(xy 339.475064 -226.481386) (xy 339.505036 -226.526852) (xy 339.517736 -226.532948) (xy 339.541448 -226.54491)
			(xy 339.585044 -226.575237) (xy 339.623231 -226.612143) (xy 339.65503 -226.654677) (xy 339.679622 -226.701746)
			(xy 339.696376 -226.752141) (xy 339.70486 -226.804566) (xy 339.704857 -226.857111) (xy 339.984589 -226.857111)
			(xy 339.984589 -226.805177) (xy 339.992714 -226.753882) (xy 340.008762 -226.704489) (xy 340.03234 -226.658215)
			(xy 340.062866 -226.616199) (xy 340.099589 -226.579476) (xy 340.141605 -226.54895) (xy 340.187879 -226.525372)
			(xy 340.237272 -226.509324) (xy 340.288567 -226.501199) (xy 340.340501 -226.501199) (xy 340.391796 -226.509324)
			(xy 340.441189 -226.525372) (xy 340.487463 -226.54895) (xy 340.529479 -226.579476) (xy 340.566202 -226.616199)
			(xy 340.596728 -226.658215) (xy 340.620306 -226.704489) (xy 340.636354 -226.753882) (xy 340.644479 -226.805177)
			(xy 340.644988 -226.831144) (xy 340.644479 -226.857111) (xy 340.924389 -226.857111) (xy 340.924389 -226.805177)
			(xy 340.932514 -226.753882) (xy 340.948562 -226.704489) (xy 340.97214 -226.658215) (xy 341.002666 -226.616199)
			(xy 341.039389 -226.579476) (xy 341.081405 -226.54895) (xy 341.127679 -226.525372) (xy 341.177072 -226.509324)
			(xy 341.228367 -226.501199) (xy 341.280301 -226.501199) (xy 341.331596 -226.509324) (xy 341.380989 -226.525372)
			(xy 341.427263 -226.54895) (xy 341.469279 -226.579476) (xy 341.506002 -226.616199) (xy 341.536528 -226.658215)
			(xy 341.560106 -226.704489) (xy 341.576154 -226.753882) (xy 341.584279 -226.805177) (xy 341.584788 -226.831144)
			(xy 341.584279 -226.857111) (xy 341.863935 -226.857111) (xy 341.863935 -226.805177) (xy 341.87206 -226.753882)
			(xy 341.888108 -226.704489) (xy 341.911686 -226.658215) (xy 341.942212 -226.616199) (xy 341.978935 -226.579476)
			(xy 342.020951 -226.54895) (xy 342.067225 -226.525372) (xy 342.116618 -226.509324) (xy 342.167913 -226.501199)
			(xy 342.219847 -226.501199) (xy 342.271142 -226.509324) (xy 342.320535 -226.525372) (xy 342.366809 -226.54895)
			(xy 342.408825 -226.579476) (xy 342.445548 -226.616199) (xy 342.476074 -226.658215) (xy 342.499652 -226.704489)
			(xy 342.5157 -226.753882) (xy 342.523825 -226.805177) (xy 342.524334 -226.831144) (xy 342.523825 -226.857111)
			(xy 342.803735 -226.857111) (xy 342.803735 -226.805177) (xy 342.81186 -226.753882) (xy 342.827908 -226.704489)
			(xy 342.851486 -226.658215) (xy 342.882012 -226.616199) (xy 342.918735 -226.579476) (xy 342.960751 -226.54895)
			(xy 343.007025 -226.525372) (xy 343.056418 -226.509324) (xy 343.107713 -226.501199) (xy 343.159647 -226.501199)
			(xy 343.210942 -226.509324) (xy 343.260335 -226.525372) (xy 343.306609 -226.54895) (xy 343.348625 -226.579476)
			(xy 343.385348 -226.616199) (xy 343.415874 -226.658215) (xy 343.439452 -226.704489) (xy 343.4555 -226.753882)
			(xy 343.463625 -226.805177) (xy 343.464134 -226.831144) (xy 343.463625 -226.857111) (xy 343.743789 -226.857111)
			(xy 343.743789 -226.805177) (xy 343.751914 -226.753882) (xy 343.767962 -226.704489) (xy 343.79154 -226.658215)
			(xy 343.822066 -226.616199) (xy 343.858789 -226.579476) (xy 343.900805 -226.54895) (xy 343.947079 -226.525372)
			(xy 343.996472 -226.509324) (xy 344.047767 -226.501199) (xy 344.099701 -226.501199) (xy 344.150996 -226.509324)
			(xy 344.200389 -226.525372) (xy 344.246663 -226.54895) (xy 344.288679 -226.579476) (xy 344.325402 -226.616199)
			(xy 344.355928 -226.658215) (xy 344.379506 -226.704489) (xy 344.395554 -226.753882) (xy 344.403679 -226.805177)
			(xy 344.404188 -226.831144) (xy 344.403679 -226.857111) (xy 344.683335 -226.857111) (xy 344.683335 -226.805177)
			(xy 344.69146 -226.753882) (xy 344.707508 -226.704489) (xy 344.731086 -226.658215) (xy 344.761612 -226.616199)
			(xy 344.798335 -226.579476) (xy 344.840351 -226.54895) (xy 344.886625 -226.525372) (xy 344.936018 -226.509324)
			(xy 344.987313 -226.501199) (xy 345.039247 -226.501199) (xy 345.090542 -226.509324) (xy 345.139935 -226.525372)
			(xy 345.186209 -226.54895) (xy 345.228225 -226.579476) (xy 345.264948 -226.616199) (xy 345.295474 -226.658215)
			(xy 345.319052 -226.704489) (xy 345.3351 -226.753882) (xy 345.343225 -226.805177) (xy 345.343734 -226.831144)
			(xy 345.343225 -226.857111) (xy 345.623135 -226.857111) (xy 345.623135 -226.805177) (xy 345.63126 -226.753882)
			(xy 345.647308 -226.704489) (xy 345.670886 -226.658215) (xy 345.701412 -226.616199) (xy 345.738135 -226.579476)
			(xy 345.780151 -226.54895) (xy 345.826425 -226.525372) (xy 345.875818 -226.509324) (xy 345.927113 -226.501199)
			(xy 345.979047 -226.501199) (xy 346.030342 -226.509324) (xy 346.079735 -226.525372) (xy 346.126009 -226.54895)
			(xy 346.168025 -226.579476) (xy 346.204748 -226.616199) (xy 346.235274 -226.658215) (xy 346.258852 -226.704489)
			(xy 346.2749 -226.753882) (xy 346.283025 -226.805177) (xy 346.283534 -226.831144) (xy 346.283025 -226.857111)
			(xy 346.563189 -226.857111) (xy 346.563189 -226.805177) (xy 346.571314 -226.753882) (xy 346.587362 -226.704489)
			(xy 346.61094 -226.658215) (xy 346.641466 -226.616199) (xy 346.678189 -226.579476) (xy 346.720205 -226.54895)
			(xy 346.766479 -226.525372) (xy 346.815872 -226.509324) (xy 346.867167 -226.501199) (xy 346.919101 -226.501199)
			(xy 346.970396 -226.509324) (xy 347.019789 -226.525372) (xy 347.066063 -226.54895) (xy 347.108079 -226.579476)
			(xy 347.144802 -226.616199) (xy 347.175328 -226.658215) (xy 347.198906 -226.704489) (xy 347.214954 -226.753882)
			(xy 347.223079 -226.805177) (xy 347.223588 -226.831144) (xy 347.223079 -226.857111) (xy 347.502989 -226.857111)
			(xy 347.502989 -226.805177) (xy 347.511114 -226.753882) (xy 347.527162 -226.704489) (xy 347.55074 -226.658215)
			(xy 347.581266 -226.616199) (xy 347.617989 -226.579476) (xy 347.660005 -226.54895) (xy 347.706279 -226.525372)
			(xy 347.755672 -226.509324) (xy 347.806967 -226.501199) (xy 347.858901 -226.501199) (xy 347.910196 -226.509324)
			(xy 347.959589 -226.525372) (xy 348.005863 -226.54895) (xy 348.047879 -226.579476) (xy 348.084602 -226.616199)
			(xy 348.115128 -226.658215) (xy 348.138706 -226.704489) (xy 348.154754 -226.753882) (xy 348.162879 -226.805177)
			(xy 348.163388 -226.831144) (xy 348.162879 -226.857111) (xy 348.442789 -226.857111) (xy 348.442789 -226.805177)
			(xy 348.450914 -226.753882) (xy 348.466962 -226.704489) (xy 348.49054 -226.658215) (xy 348.521066 -226.616199)
			(xy 348.557789 -226.579476) (xy 348.599805 -226.54895) (xy 348.646079 -226.525372) (xy 348.695472 -226.509324)
			(xy 348.746767 -226.501199) (xy 348.798701 -226.501199) (xy 348.849996 -226.509324) (xy 348.899389 -226.525372)
			(xy 348.945663 -226.54895) (xy 348.987679 -226.579476) (xy 349.024402 -226.616199) (xy 349.054928 -226.658215)
			(xy 349.078506 -226.704489) (xy 349.094554 -226.753882) (xy 349.102679 -226.805177) (xy 349.103188 -226.831144)
			(xy 349.102679 -226.857111) (xy 349.094554 -226.908406) (xy 349.078506 -226.957799) (xy 349.054928 -227.004073)
			(xy 349.024402 -227.046089) (xy 348.987679 -227.082812) (xy 348.945663 -227.113338) (xy 348.899389 -227.136916)
			(xy 348.849996 -227.152964) (xy 348.798701 -227.161089) (xy 348.746767 -227.161089) (xy 348.695472 -227.152964)
			(xy 348.646079 -227.136916) (xy 348.599805 -227.113338) (xy 348.557789 -227.082812) (xy 348.521066 -227.046089)
			(xy 348.49054 -227.004073) (xy 348.466962 -226.957799) (xy 348.450914 -226.908406) (xy 348.442789 -226.857111)
			(xy 348.162879 -226.857111) (xy 348.154754 -226.908406) (xy 348.138706 -226.957799) (xy 348.115128 -227.004073)
			(xy 348.084602 -227.046089) (xy 348.047879 -227.082812) (xy 348.005863 -227.113338) (xy 347.959589 -227.136916)
			(xy 347.910196 -227.152964) (xy 347.858901 -227.161089) (xy 347.806967 -227.161089) (xy 347.755672 -227.152964)
			(xy 347.706279 -227.136916) (xy 347.660005 -227.113338) (xy 347.617989 -227.082812) (xy 347.581266 -227.046089)
			(xy 347.55074 -227.004073) (xy 347.527162 -226.957799) (xy 347.511114 -226.908406) (xy 347.502989 -226.857111)
			(xy 347.223079 -226.857111) (xy 347.214954 -226.908406) (xy 347.198906 -226.957799) (xy 347.175328 -227.004073)
			(xy 347.144802 -227.046089) (xy 347.108079 -227.082812) (xy 347.066063 -227.113338) (xy 347.019789 -227.136916)
			(xy 346.970396 -227.152964) (xy 346.919101 -227.161089) (xy 346.867167 -227.161089) (xy 346.815872 -227.152964)
			(xy 346.766479 -227.136916) (xy 346.720205 -227.113338) (xy 346.678189 -227.082812) (xy 346.641466 -227.046089)
			(xy 346.61094 -227.004073) (xy 346.587362 -226.957799) (xy 346.571314 -226.908406) (xy 346.563189 -226.857111)
			(xy 346.283025 -226.857111) (xy 346.2749 -226.908406) (xy 346.258852 -226.957799) (xy 346.235274 -227.004073)
			(xy 346.204748 -227.046089) (xy 346.168025 -227.082812) (xy 346.126009 -227.113338) (xy 346.079735 -227.136916)
			(xy 346.030342 -227.152964) (xy 345.979047 -227.161089) (xy 345.927113 -227.161089) (xy 345.875818 -227.152964)
			(xy 345.826425 -227.136916) (xy 345.780151 -227.113338) (xy 345.738135 -227.082812) (xy 345.701412 -227.046089)
			(xy 345.670886 -227.004073) (xy 345.647308 -226.957799) (xy 345.63126 -226.908406) (xy 345.623135 -226.857111)
			(xy 345.343225 -226.857111) (xy 345.3351 -226.908406) (xy 345.319052 -226.957799) (xy 345.295474 -227.004073)
			(xy 345.264948 -227.046089) (xy 345.228225 -227.082812) (xy 345.186209 -227.113338) (xy 345.139935 -227.136916)
			(xy 345.090542 -227.152964) (xy 345.039247 -227.161089) (xy 344.987313 -227.161089) (xy 344.936018 -227.152964)
			(xy 344.886625 -227.136916) (xy 344.840351 -227.113338) (xy 344.798335 -227.082812) (xy 344.761612 -227.046089)
			(xy 344.731086 -227.004073) (xy 344.707508 -226.957799) (xy 344.69146 -226.908406) (xy 344.683335 -226.857111)
			(xy 344.403679 -226.857111) (xy 344.395554 -226.908406) (xy 344.379506 -226.957799) (xy 344.355928 -227.004073)
			(xy 344.325402 -227.046089) (xy 344.288679 -227.082812) (xy 344.246663 -227.113338) (xy 344.200389 -227.136916)
			(xy 344.150996 -227.152964) (xy 344.099701 -227.161089) (xy 344.047767 -227.161089) (xy 343.996472 -227.152964)
			(xy 343.947079 -227.136916) (xy 343.900805 -227.113338) (xy 343.858789 -227.082812) (xy 343.822066 -227.046089)
			(xy 343.79154 -227.004073) (xy 343.767962 -226.957799) (xy 343.751914 -226.908406) (xy 343.743789 -226.857111)
			(xy 343.463625 -226.857111) (xy 343.4555 -226.908406) (xy 343.439452 -226.957799) (xy 343.415874 -227.004073)
			(xy 343.385348 -227.046089) (xy 343.348625 -227.082812) (xy 343.306609 -227.113338) (xy 343.260335 -227.136916)
			(xy 343.210942 -227.152964) (xy 343.159647 -227.161089) (xy 343.107713 -227.161089) (xy 343.056418 -227.152964)
			(xy 343.007025 -227.136916) (xy 342.960751 -227.113338) (xy 342.918735 -227.082812) (xy 342.882012 -227.046089)
			(xy 342.851486 -227.004073) (xy 342.827908 -226.957799) (xy 342.81186 -226.908406) (xy 342.803735 -226.857111)
			(xy 342.523825 -226.857111) (xy 342.5157 -226.908406) (xy 342.499652 -226.957799) (xy 342.476074 -227.004073)
			(xy 342.445548 -227.046089) (xy 342.408825 -227.082812) (xy 342.366809 -227.113338) (xy 342.320535 -227.136916)
			(xy 342.271142 -227.152964) (xy 342.219847 -227.161089) (xy 342.167913 -227.161089) (xy 342.116618 -227.152964)
			(xy 342.067225 -227.136916) (xy 342.020951 -227.113338) (xy 341.978935 -227.082812) (xy 341.942212 -227.046089)
			(xy 341.911686 -227.004073) (xy 341.888108 -226.957799) (xy 341.87206 -226.908406) (xy 341.863935 -226.857111)
			(xy 341.584279 -226.857111) (xy 341.576154 -226.908406) (xy 341.560106 -226.957799) (xy 341.536528 -227.004073)
			(xy 341.506002 -227.046089) (xy 341.469279 -227.082812) (xy 341.427263 -227.113338) (xy 341.380989 -227.136916)
			(xy 341.331596 -227.152964) (xy 341.280301 -227.161089) (xy 341.228367 -227.161089) (xy 341.177072 -227.152964)
			(xy 341.127679 -227.136916) (xy 341.081405 -227.113338) (xy 341.039389 -227.082812) (xy 341.002666 -227.046089)
			(xy 340.97214 -227.004073) (xy 340.948562 -226.957799) (xy 340.932514 -226.908406) (xy 340.924389 -226.857111)
			(xy 340.644479 -226.857111) (xy 340.636354 -226.908406) (xy 340.620306 -226.957799) (xy 340.596728 -227.004073)
			(xy 340.566202 -227.046089) (xy 340.529479 -227.082812) (xy 340.487463 -227.113338) (xy 340.441189 -227.136916)
			(xy 340.391796 -227.152964) (xy 340.340501 -227.161089) (xy 340.288567 -227.161089) (xy 340.237272 -227.152964)
			(xy 340.187879 -227.136916) (xy 340.141605 -227.113338) (xy 340.099589 -227.082812) (xy 340.062866 -227.046089)
			(xy 340.03234 -227.004073) (xy 340.008762 -226.957799) (xy 339.992714 -226.908406) (xy 339.984589 -226.857111)
			(xy 339.704857 -226.857111) (xy 339.704857 -226.857672) (xy 339.696367 -226.910096) (xy 339.679608 -226.960489)
			(xy 339.65501 -227.007555) (xy 339.623206 -227.050086) (xy 339.585014 -227.086987) (xy 339.541415 -227.11731)
			(xy 339.517736 -227.12934) (xy 339.505036 -227.135436) (xy 339.475064 -227.180902) (xy 339.475064 -227.30841)
			(xy 339.475525 -227.317591) (xy 339.482178 -227.33471) (xy 339.494496 -227.348334) (xy 339.502496 -227.35286)
			(xy 339.583014 -227.391722) (xy 339.591553 -227.394971) (xy 339.60979 -227.395756) (xy 339.618574 -227.393246)
			(xy 339.637624 -227.386642) (xy 339.643974 -227.381816) (xy 339.665721 -227.365933) (xy 339.713289 -227.340698)
			(xy 339.764317 -227.323499) (xy 339.817456 -227.314791) (xy 339.84438 -227.314252) (xy 339.870373 -227.314734)
			(xy 339.921721 -227.322863) (xy 339.971164 -227.338926) (xy 340.017485 -227.362525) (xy 340.059545 -227.393081)
			(xy 340.096306 -227.42984) (xy 340.126864 -227.471898) (xy 340.150466 -227.518218) (xy 340.166532 -227.56766)
			(xy 340.174665 -227.619007) (xy 340.174665 -227.670927) (xy 340.454489 -227.670927) (xy 340.454489 -227.618993)
			(xy 340.462614 -227.567698) (xy 340.478662 -227.518305) (xy 340.50224 -227.472031) (xy 340.532766 -227.430015)
			(xy 340.569489 -227.393292) (xy 340.611505 -227.362766) (xy 340.657779 -227.339188) (xy 340.707172 -227.32314)
			(xy 340.758467 -227.315015) (xy 340.810401 -227.315015) (xy 340.861696 -227.32314) (xy 340.911089 -227.339188)
			(xy 340.957363 -227.362766) (xy 340.999379 -227.393292) (xy 341.036102 -227.430015) (xy 341.066628 -227.472031)
			(xy 341.090206 -227.518305) (xy 341.106254 -227.567698) (xy 341.114379 -227.618993) (xy 341.114888 -227.64496)
			(xy 341.114379 -227.670927) (xy 341.394289 -227.670927) (xy 341.394289 -227.618993) (xy 341.402414 -227.567698)
			(xy 341.418462 -227.518305) (xy 341.44204 -227.472031) (xy 341.472566 -227.430015) (xy 341.509289 -227.393292)
			(xy 341.551305 -227.362766) (xy 341.597579 -227.339188) (xy 341.646972 -227.32314) (xy 341.698267 -227.315015)
			(xy 341.750201 -227.315015) (xy 341.801496 -227.32314) (xy 341.850889 -227.339188) (xy 341.897163 -227.362766)
			(xy 341.939179 -227.393292) (xy 341.975902 -227.430015) (xy 342.006428 -227.472031) (xy 342.030006 -227.518305)
			(xy 342.046054 -227.567698) (xy 342.054179 -227.618993) (xy 342.054688 -227.64496) (xy 342.054179 -227.670927)
			(xy 342.334089 -227.670927) (xy 342.334089 -227.618993) (xy 342.342214 -227.567698) (xy 342.358262 -227.518305)
			(xy 342.38184 -227.472031) (xy 342.412366 -227.430015) (xy 342.449089 -227.393292) (xy 342.491105 -227.362766)
			(xy 342.537379 -227.339188) (xy 342.586772 -227.32314) (xy 342.638067 -227.315015) (xy 342.690001 -227.315015)
			(xy 342.741296 -227.32314) (xy 342.790689 -227.339188) (xy 342.836963 -227.362766) (xy 342.878979 -227.393292)
			(xy 342.915702 -227.430015) (xy 342.946228 -227.472031) (xy 342.969806 -227.518305) (xy 342.985854 -227.567698)
			(xy 342.993979 -227.618993) (xy 342.994488 -227.64496) (xy 342.993979 -227.670927) (xy 343.273889 -227.670927)
			(xy 343.273889 -227.618993) (xy 343.282014 -227.567698) (xy 343.298062 -227.518305) (xy 343.32164 -227.472031)
			(xy 343.352166 -227.430015) (xy 343.388889 -227.393292) (xy 343.430905 -227.362766) (xy 343.477179 -227.339188)
			(xy 343.526572 -227.32314) (xy 343.577867 -227.315015) (xy 343.629801 -227.315015) (xy 343.681096 -227.32314)
			(xy 343.730489 -227.339188) (xy 343.776763 -227.362766) (xy 343.818779 -227.393292) (xy 343.855502 -227.430015)
			(xy 343.886028 -227.472031) (xy 343.909606 -227.518305) (xy 343.925654 -227.567698) (xy 343.933779 -227.618993)
			(xy 343.934288 -227.64496) (xy 343.933779 -227.670927) (xy 344.213689 -227.670927) (xy 344.213689 -227.618993)
			(xy 344.221814 -227.567698) (xy 344.237862 -227.518305) (xy 344.26144 -227.472031) (xy 344.291966 -227.430015)
			(xy 344.328689 -227.393292) (xy 344.370705 -227.362766) (xy 344.416979 -227.339188) (xy 344.466372 -227.32314)
			(xy 344.517667 -227.315015) (xy 344.569601 -227.315015) (xy 344.620896 -227.32314) (xy 344.670289 -227.339188)
			(xy 344.716563 -227.362766) (xy 344.758579 -227.393292) (xy 344.795302 -227.430015) (xy 344.825828 -227.472031)
			(xy 344.849406 -227.518305) (xy 344.865454 -227.567698) (xy 344.873579 -227.618993) (xy 344.874088 -227.64496)
			(xy 344.873579 -227.670927) (xy 345.153489 -227.670927) (xy 345.153489 -227.618993) (xy 345.161614 -227.567698)
			(xy 345.177662 -227.518305) (xy 345.20124 -227.472031) (xy 345.231766 -227.430015) (xy 345.268489 -227.393292)
			(xy 345.310505 -227.362766) (xy 345.356779 -227.339188) (xy 345.406172 -227.32314) (xy 345.457467 -227.315015)
			(xy 345.509401 -227.315015) (xy 345.560696 -227.32314) (xy 345.610089 -227.339188) (xy 345.656363 -227.362766)
			(xy 345.698379 -227.393292) (xy 345.735102 -227.430015) (xy 345.765628 -227.472031) (xy 345.789206 -227.518305)
			(xy 345.805254 -227.567698) (xy 345.813379 -227.618993) (xy 345.813888 -227.64496) (xy 345.813379 -227.670927)
			(xy 346.093289 -227.670927) (xy 346.093289 -227.618993) (xy 346.101414 -227.567698) (xy 346.117462 -227.518305)
			(xy 346.14104 -227.472031) (xy 346.171566 -227.430015) (xy 346.208289 -227.393292) (xy 346.250305 -227.362766)
			(xy 346.296579 -227.339188) (xy 346.345972 -227.32314) (xy 346.397267 -227.315015) (xy 346.449201 -227.315015)
			(xy 346.500496 -227.32314) (xy 346.549889 -227.339188) (xy 346.596163 -227.362766) (xy 346.638179 -227.393292)
			(xy 346.674902 -227.430015) (xy 346.705428 -227.472031) (xy 346.729006 -227.518305) (xy 346.745054 -227.567698)
			(xy 346.753179 -227.618993) (xy 346.753688 -227.64496) (xy 346.753179 -227.670927) (xy 347.032835 -227.670927)
			(xy 347.032835 -227.618993) (xy 347.04096 -227.567698) (xy 347.057008 -227.518305) (xy 347.080586 -227.472031)
			(xy 347.111112 -227.430015) (xy 347.147835 -227.393292) (xy 347.189851 -227.362766) (xy 347.236125 -227.339188)
			(xy 347.285518 -227.32314) (xy 347.336813 -227.315015) (xy 347.388747 -227.315015) (xy 347.440042 -227.32314)
			(xy 347.489435 -227.339188) (xy 347.535709 -227.362766) (xy 347.577725 -227.393292) (xy 347.614448 -227.430015)
			(xy 347.644974 -227.472031) (xy 347.668552 -227.518305) (xy 347.6846 -227.567698) (xy 347.692725 -227.618993)
			(xy 347.693234 -227.64496) (xy 347.692725 -227.670927) (xy 347.972889 -227.670927) (xy 347.972889 -227.618993)
			(xy 347.981014 -227.567698) (xy 347.997062 -227.518305) (xy 348.02064 -227.472031) (xy 348.051166 -227.430015)
			(xy 348.087889 -227.393292) (xy 348.129905 -227.362766) (xy 348.176179 -227.339188) (xy 348.225572 -227.32314)
			(xy 348.276867 -227.315015) (xy 348.328801 -227.315015) (xy 348.380096 -227.32314) (xy 348.429489 -227.339188)
			(xy 348.475763 -227.362766) (xy 348.517779 -227.393292) (xy 348.554502 -227.430015) (xy 348.585028 -227.472031)
			(xy 348.608606 -227.518305) (xy 348.624654 -227.567698) (xy 348.632779 -227.618993) (xy 348.633288 -227.64496)
			(xy 348.632779 -227.670927) (xy 348.624654 -227.722222) (xy 348.608606 -227.771615) (xy 348.585028 -227.817889)
			(xy 348.554502 -227.859905) (xy 348.517779 -227.896628) (xy 348.475763 -227.927154) (xy 348.429489 -227.950732)
			(xy 348.380096 -227.96678) (xy 348.328801 -227.974905) (xy 348.276867 -227.974905) (xy 348.225572 -227.96678)
			(xy 348.176179 -227.950732) (xy 348.129905 -227.927154) (xy 348.087889 -227.896628) (xy 348.051166 -227.859905)
			(xy 348.02064 -227.817889) (xy 347.997062 -227.771615) (xy 347.981014 -227.722222) (xy 347.972889 -227.670927)
			(xy 347.692725 -227.670927) (xy 347.6846 -227.722222) (xy 347.668552 -227.771615) (xy 347.644974 -227.817889)
			(xy 347.614448 -227.859905) (xy 347.577725 -227.896628) (xy 347.535709 -227.927154) (xy 347.489435 -227.950732)
			(xy 347.440042 -227.96678) (xy 347.388747 -227.974905) (xy 347.336813 -227.974905) (xy 347.285518 -227.96678)
			(xy 347.236125 -227.950732) (xy 347.189851 -227.927154) (xy 347.147835 -227.896628) (xy 347.111112 -227.859905)
			(xy 347.080586 -227.817889) (xy 347.057008 -227.771615) (xy 347.04096 -227.722222) (xy 347.032835 -227.670927)
			(xy 346.753179 -227.670927) (xy 346.745054 -227.722222) (xy 346.729006 -227.771615) (xy 346.705428 -227.817889)
			(xy 346.674902 -227.859905) (xy 346.638179 -227.896628) (xy 346.596163 -227.927154) (xy 346.549889 -227.950732)
			(xy 346.500496 -227.96678) (xy 346.449201 -227.974905) (xy 346.397267 -227.974905) (xy 346.345972 -227.96678)
			(xy 346.296579 -227.950732) (xy 346.250305 -227.927154) (xy 346.208289 -227.896628) (xy 346.171566 -227.859905)
			(xy 346.14104 -227.817889) (xy 346.117462 -227.771615) (xy 346.101414 -227.722222) (xy 346.093289 -227.670927)
			(xy 345.813379 -227.670927) (xy 345.805254 -227.722222) (xy 345.789206 -227.771615) (xy 345.765628 -227.817889)
			(xy 345.735102 -227.859905) (xy 345.698379 -227.896628) (xy 345.656363 -227.927154) (xy 345.610089 -227.950732)
			(xy 345.560696 -227.96678) (xy 345.509401 -227.974905) (xy 345.457467 -227.974905) (xy 345.406172 -227.96678)
			(xy 345.356779 -227.950732) (xy 345.310505 -227.927154) (xy 345.268489 -227.896628) (xy 345.231766 -227.859905)
			(xy 345.20124 -227.817889) (xy 345.177662 -227.771615) (xy 345.161614 -227.722222) (xy 345.153489 -227.670927)
			(xy 344.873579 -227.670927) (xy 344.865454 -227.722222) (xy 344.849406 -227.771615) (xy 344.825828 -227.817889)
			(xy 344.795302 -227.859905) (xy 344.758579 -227.896628) (xy 344.716563 -227.927154) (xy 344.670289 -227.950732)
			(xy 344.620896 -227.96678) (xy 344.569601 -227.974905) (xy 344.517667 -227.974905) (xy 344.466372 -227.96678)
			(xy 344.416979 -227.950732) (xy 344.370705 -227.927154) (xy 344.328689 -227.896628) (xy 344.291966 -227.859905)
			(xy 344.26144 -227.817889) (xy 344.237862 -227.771615) (xy 344.221814 -227.722222) (xy 344.213689 -227.670927)
			(xy 343.933779 -227.670927) (xy 343.925654 -227.722222) (xy 343.909606 -227.771615) (xy 343.886028 -227.817889)
			(xy 343.855502 -227.859905) (xy 343.818779 -227.896628) (xy 343.776763 -227.927154) (xy 343.730489 -227.950732)
			(xy 343.681096 -227.96678) (xy 343.629801 -227.974905) (xy 343.577867 -227.974905) (xy 343.526572 -227.96678)
			(xy 343.477179 -227.950732) (xy 343.430905 -227.927154) (xy 343.388889 -227.896628) (xy 343.352166 -227.859905)
			(xy 343.32164 -227.817889) (xy 343.298062 -227.771615) (xy 343.282014 -227.722222) (xy 343.273889 -227.670927)
			(xy 342.993979 -227.670927) (xy 342.985854 -227.722222) (xy 342.969806 -227.771615) (xy 342.946228 -227.817889)
			(xy 342.915702 -227.859905) (xy 342.878979 -227.896628) (xy 342.836963 -227.927154) (xy 342.790689 -227.950732)
			(xy 342.741296 -227.96678) (xy 342.690001 -227.974905) (xy 342.638067 -227.974905) (xy 342.586772 -227.96678)
			(xy 342.537379 -227.950732) (xy 342.491105 -227.927154) (xy 342.449089 -227.896628) (xy 342.412366 -227.859905)
			(xy 342.38184 -227.817889) (xy 342.358262 -227.771615) (xy 342.342214 -227.722222) (xy 342.334089 -227.670927)
			(xy 342.054179 -227.670927) (xy 342.046054 -227.722222) (xy 342.030006 -227.771615) (xy 342.006428 -227.817889)
			(xy 341.975902 -227.859905) (xy 341.939179 -227.896628) (xy 341.897163 -227.927154) (xy 341.850889 -227.950732)
			(xy 341.801496 -227.96678) (xy 341.750201 -227.974905) (xy 341.698267 -227.974905) (xy 341.646972 -227.96678)
			(xy 341.597579 -227.950732) (xy 341.551305 -227.927154) (xy 341.509289 -227.896628) (xy 341.472566 -227.859905)
			(xy 341.44204 -227.817889) (xy 341.418462 -227.771615) (xy 341.402414 -227.722222) (xy 341.394289 -227.670927)
			(xy 341.114379 -227.670927) (xy 341.106254 -227.722222) (xy 341.090206 -227.771615) (xy 341.066628 -227.817889)
			(xy 341.036102 -227.859905) (xy 340.999379 -227.896628) (xy 340.957363 -227.927154) (xy 340.911089 -227.950732)
			(xy 340.861696 -227.96678) (xy 340.810401 -227.974905) (xy 340.758467 -227.974905) (xy 340.707172 -227.96678)
			(xy 340.657779 -227.950732) (xy 340.611505 -227.927154) (xy 340.569489 -227.896628) (xy 340.532766 -227.859905)
			(xy 340.50224 -227.817889) (xy 340.478662 -227.771615) (xy 340.462614 -227.722222) (xy 340.454489 -227.670927)
			(xy 340.174665 -227.670927) (xy 340.174665 -227.670993) (xy 340.166532 -227.72234) (xy 340.150466 -227.771782)
			(xy 340.126864 -227.818102) (xy 340.096306 -227.86016) (xy 340.059545 -227.896919) (xy 340.017485 -227.927475)
			(xy 339.971164 -227.951074) (xy 339.921721 -227.967137) (xy 339.870373 -227.975266) (xy 339.84438 -227.975668)
			(xy 339.817456 -227.975139) (xy 339.764318 -227.966421) (xy 339.713292 -227.949219) (xy 339.665722 -227.923985)
			(xy 339.643974 -227.908104) (xy 339.637624 -227.903278) (xy 339.618574 -227.896674) (xy 339.609788 -227.89418)
			(xy 339.591554 -227.894961) (xy 339.583014 -227.898198) (xy 339.502496 -227.93706) (xy 339.494484 -227.941571)
			(xy 339.482151 -227.955189) (xy 339.475528 -227.972325) (xy 339.475064 -227.98151) (xy 339.475064 -228.109272)
			(xy 339.505036 -228.154738) (xy 339.517736 -228.160834) (xy 339.54145 -228.172796) (xy 339.585047 -228.203124)
			(xy 339.623237 -228.24003) (xy 339.655038 -228.282565) (xy 339.679632 -228.329636) (xy 339.696387 -228.380032)
			(xy 339.704873 -228.432459) (xy 339.704871 -228.484997) (xy 339.984335 -228.484997) (xy 339.984335 -228.433063)
			(xy 339.99246 -228.381768) (xy 340.008508 -228.332375) (xy 340.032086 -228.286101) (xy 340.062612 -228.244085)
			(xy 340.099335 -228.207362) (xy 340.141351 -228.176836) (xy 340.187625 -228.153258) (xy 340.237018 -228.13721)
			(xy 340.288313 -228.129085) (xy 340.340247 -228.129085) (xy 340.391542 -228.13721) (xy 340.440935 -228.153258)
			(xy 340.487209 -228.176836) (xy 340.529225 -228.207362) (xy 340.565948 -228.244085) (xy 340.596474 -228.286101)
			(xy 340.620052 -228.332375) (xy 340.6361 -228.381768) (xy 340.644225 -228.433063) (xy 340.644734 -228.45903)
			(xy 340.644225 -228.484997) (xy 340.924135 -228.484997) (xy 340.924135 -228.433063) (xy 340.93226 -228.381768)
			(xy 340.948308 -228.332375) (xy 340.971886 -228.286101) (xy 341.002412 -228.244085) (xy 341.039135 -228.207362)
			(xy 341.081151 -228.176836) (xy 341.127425 -228.153258) (xy 341.176818 -228.13721) (xy 341.228113 -228.129085)
			(xy 341.280047 -228.129085) (xy 341.331342 -228.13721) (xy 341.380735 -228.153258) (xy 341.427009 -228.176836)
			(xy 341.469025 -228.207362) (xy 341.505748 -228.244085) (xy 341.536274 -228.286101) (xy 341.559852 -228.332375)
			(xy 341.5759 -228.381768) (xy 341.584025 -228.433063) (xy 341.584534 -228.45903) (xy 341.584025 -228.484997)
			(xy 341.863935 -228.484997) (xy 341.863935 -228.433063) (xy 341.87206 -228.381768) (xy 341.888108 -228.332375)
			(xy 341.911686 -228.286101) (xy 341.942212 -228.244085) (xy 341.978935 -228.207362) (xy 342.020951 -228.176836)
			(xy 342.067225 -228.153258) (xy 342.116618 -228.13721) (xy 342.167913 -228.129085) (xy 342.219847 -228.129085)
			(xy 342.271142 -228.13721) (xy 342.320535 -228.153258) (xy 342.366809 -228.176836) (xy 342.408825 -228.207362)
			(xy 342.445548 -228.244085) (xy 342.476074 -228.286101) (xy 342.499652 -228.332375) (xy 342.5157 -228.381768)
			(xy 342.523825 -228.433063) (xy 342.524334 -228.45903) (xy 342.523825 -228.484997) (xy 342.803735 -228.484997)
			(xy 342.803735 -228.433063) (xy 342.81186 -228.381768) (xy 342.827908 -228.332375) (xy 342.851486 -228.286101)
			(xy 342.882012 -228.244085) (xy 342.918735 -228.207362) (xy 342.960751 -228.176836) (xy 343.007025 -228.153258)
			(xy 343.056418 -228.13721) (xy 343.107713 -228.129085) (xy 343.159647 -228.129085) (xy 343.210942 -228.13721)
			(xy 343.260335 -228.153258) (xy 343.306609 -228.176836) (xy 343.348625 -228.207362) (xy 343.385348 -228.244085)
			(xy 343.415874 -228.286101) (xy 343.439452 -228.332375) (xy 343.4555 -228.381768) (xy 343.463625 -228.433063)
			(xy 343.464134 -228.45903) (xy 343.463625 -228.484997) (xy 343.743535 -228.484997) (xy 343.743535 -228.433063)
			(xy 343.75166 -228.381768) (xy 343.767708 -228.332375) (xy 343.791286 -228.286101) (xy 343.821812 -228.244085)
			(xy 343.858535 -228.207362) (xy 343.900551 -228.176836) (xy 343.946825 -228.153258) (xy 343.996218 -228.13721)
			(xy 344.047513 -228.129085) (xy 344.099447 -228.129085) (xy 344.150742 -228.13721) (xy 344.200135 -228.153258)
			(xy 344.246409 -228.176836) (xy 344.288425 -228.207362) (xy 344.325148 -228.244085) (xy 344.355674 -228.286101)
			(xy 344.379252 -228.332375) (xy 344.3953 -228.381768) (xy 344.403425 -228.433063) (xy 344.403934 -228.45903)
			(xy 344.403425 -228.484997) (xy 344.683335 -228.484997) (xy 344.683335 -228.433063) (xy 344.69146 -228.381768)
			(xy 344.707508 -228.332375) (xy 344.731086 -228.286101) (xy 344.761612 -228.244085) (xy 344.798335 -228.207362)
			(xy 344.840351 -228.176836) (xy 344.886625 -228.153258) (xy 344.936018 -228.13721) (xy 344.987313 -228.129085)
			(xy 345.039247 -228.129085) (xy 345.090542 -228.13721) (xy 345.139935 -228.153258) (xy 345.186209 -228.176836)
			(xy 345.228225 -228.207362) (xy 345.264948 -228.244085) (xy 345.295474 -228.286101) (xy 345.319052 -228.332375)
			(xy 345.3351 -228.381768) (xy 345.343225 -228.433063) (xy 345.343734 -228.45903) (xy 345.343225 -228.484997)
			(xy 345.623389 -228.484997) (xy 345.623389 -228.433063) (xy 345.631514 -228.381768) (xy 345.647562 -228.332375)
			(xy 345.67114 -228.286101) (xy 345.701666 -228.244085) (xy 345.738389 -228.207362) (xy 345.780405 -228.176836)
			(xy 345.826679 -228.153258) (xy 345.876072 -228.13721) (xy 345.927367 -228.129085) (xy 345.979301 -228.129085)
			(xy 346.030596 -228.13721) (xy 346.079989 -228.153258) (xy 346.126263 -228.176836) (xy 346.168279 -228.207362)
			(xy 346.205002 -228.244085) (xy 346.235528 -228.286101) (xy 346.259106 -228.332375) (xy 346.275154 -228.381768)
			(xy 346.283279 -228.433063) (xy 346.283788 -228.45903) (xy 346.283279 -228.484997) (xy 346.562935 -228.484997)
			(xy 346.562935 -228.433063) (xy 346.57106 -228.381768) (xy 346.587108 -228.332375) (xy 346.610686 -228.286101)
			(xy 346.641212 -228.244085) (xy 346.677935 -228.207362) (xy 346.719951 -228.176836) (xy 346.766225 -228.153258)
			(xy 346.815618 -228.13721) (xy 346.866913 -228.129085) (xy 346.918847 -228.129085) (xy 346.970142 -228.13721)
			(xy 347.019535 -228.153258) (xy 347.065809 -228.176836) (xy 347.107825 -228.207362) (xy 347.144548 -228.244085)
			(xy 347.175074 -228.286101) (xy 347.198652 -228.332375) (xy 347.2147 -228.381768) (xy 347.222825 -228.433063)
			(xy 347.223334 -228.45903) (xy 347.222825 -228.484997) (xy 347.502735 -228.484997) (xy 347.502735 -228.433063)
			(xy 347.51086 -228.381768) (xy 347.526908 -228.332375) (xy 347.550486 -228.286101) (xy 347.581012 -228.244085)
			(xy 347.617735 -228.207362) (xy 347.659751 -228.176836) (xy 347.706025 -228.153258) (xy 347.755418 -228.13721)
			(xy 347.806713 -228.129085) (xy 347.858647 -228.129085) (xy 347.909942 -228.13721) (xy 347.959335 -228.153258)
			(xy 348.005609 -228.176836) (xy 348.047625 -228.207362) (xy 348.084348 -228.244085) (xy 348.114874 -228.286101)
			(xy 348.138452 -228.332375) (xy 348.1545 -228.381768) (xy 348.162625 -228.433063) (xy 348.163134 -228.45903)
			(xy 348.162625 -228.484997) (xy 348.442535 -228.484997) (xy 348.442535 -228.433063) (xy 348.45066 -228.381768)
			(xy 348.466708 -228.332375) (xy 348.490286 -228.286101) (xy 348.520812 -228.244085) (xy 348.557535 -228.207362)
			(xy 348.599551 -228.176836) (xy 348.645825 -228.153258) (xy 348.695218 -228.13721) (xy 348.746513 -228.129085)
			(xy 348.798447 -228.129085) (xy 348.849742 -228.13721) (xy 348.899135 -228.153258) (xy 348.945409 -228.176836)
			(xy 348.987425 -228.207362) (xy 349.024148 -228.244085) (xy 349.054674 -228.286101) (xy 349.078252 -228.332375)
			(xy 349.0943 -228.381768) (xy 349.102425 -228.433063) (xy 349.102934 -228.45903) (xy 349.102425 -228.484997)
			(xy 349.0943 -228.536292) (xy 349.078252 -228.585685) (xy 349.054674 -228.631959) (xy 349.024148 -228.673975)
			(xy 348.987425 -228.710698) (xy 348.945409 -228.741224) (xy 348.899135 -228.764802) (xy 348.849742 -228.78085)
			(xy 348.798447 -228.788975) (xy 348.746513 -228.788975) (xy 348.695218 -228.78085) (xy 348.645825 -228.764802)
			(xy 348.599551 -228.741224) (xy 348.557535 -228.710698) (xy 348.520812 -228.673975) (xy 348.490286 -228.631959)
			(xy 348.466708 -228.585685) (xy 348.45066 -228.536292) (xy 348.442535 -228.484997) (xy 348.162625 -228.484997)
			(xy 348.1545 -228.536292) (xy 348.138452 -228.585685) (xy 348.114874 -228.631959) (xy 348.084348 -228.673975)
			(xy 348.047625 -228.710698) (xy 348.005609 -228.741224) (xy 347.959335 -228.764802) (xy 347.909942 -228.78085)
			(xy 347.858647 -228.788975) (xy 347.806713 -228.788975) (xy 347.755418 -228.78085) (xy 347.706025 -228.764802)
			(xy 347.659751 -228.741224) (xy 347.617735 -228.710698) (xy 347.581012 -228.673975) (xy 347.550486 -228.631959)
			(xy 347.526908 -228.585685) (xy 347.51086 -228.536292) (xy 347.502735 -228.484997) (xy 347.222825 -228.484997)
			(xy 347.2147 -228.536292) (xy 347.198652 -228.585685) (xy 347.175074 -228.631959) (xy 347.144548 -228.673975)
			(xy 347.107825 -228.710698) (xy 347.065809 -228.741224) (xy 347.019535 -228.764802) (xy 346.970142 -228.78085)
			(xy 346.918847 -228.788975) (xy 346.866913 -228.788975) (xy 346.815618 -228.78085) (xy 346.766225 -228.764802)
			(xy 346.719951 -228.741224) (xy 346.677935 -228.710698) (xy 346.641212 -228.673975) (xy 346.610686 -228.631959)
			(xy 346.587108 -228.585685) (xy 346.57106 -228.536292) (xy 346.562935 -228.484997) (xy 346.283279 -228.484997)
			(xy 346.275154 -228.536292) (xy 346.259106 -228.585685) (xy 346.235528 -228.631959) (xy 346.205002 -228.673975)
			(xy 346.168279 -228.710698) (xy 346.126263 -228.741224) (xy 346.079989 -228.764802) (xy 346.030596 -228.78085)
			(xy 345.979301 -228.788975) (xy 345.927367 -228.788975) (xy 345.876072 -228.78085) (xy 345.826679 -228.764802)
			(xy 345.780405 -228.741224) (xy 345.738389 -228.710698) (xy 345.701666 -228.673975) (xy 345.67114 -228.631959)
			(xy 345.647562 -228.585685) (xy 345.631514 -228.536292) (xy 345.623389 -228.484997) (xy 345.343225 -228.484997)
			(xy 345.3351 -228.536292) (xy 345.319052 -228.585685) (xy 345.295474 -228.631959) (xy 345.264948 -228.673975)
			(xy 345.228225 -228.710698) (xy 345.186209 -228.741224) (xy 345.139935 -228.764802) (xy 345.090542 -228.78085)
			(xy 345.039247 -228.788975) (xy 344.987313 -228.788975) (xy 344.936018 -228.78085) (xy 344.886625 -228.764802)
			(xy 344.840351 -228.741224) (xy 344.798335 -228.710698) (xy 344.761612 -228.673975) (xy 344.731086 -228.631959)
			(xy 344.707508 -228.585685) (xy 344.69146 -228.536292) (xy 344.683335 -228.484997) (xy 344.403425 -228.484997)
			(xy 344.3953 -228.536292) (xy 344.379252 -228.585685) (xy 344.355674 -228.631959) (xy 344.325148 -228.673975)
			(xy 344.288425 -228.710698) (xy 344.246409 -228.741224) (xy 344.200135 -228.764802) (xy 344.150742 -228.78085)
			(xy 344.099447 -228.788975) (xy 344.047513 -228.788975) (xy 343.996218 -228.78085) (xy 343.946825 -228.764802)
			(xy 343.900551 -228.741224) (xy 343.858535 -228.710698) (xy 343.821812 -228.673975) (xy 343.791286 -228.631959)
			(xy 343.767708 -228.585685) (xy 343.75166 -228.536292) (xy 343.743535 -228.484997) (xy 343.463625 -228.484997)
			(xy 343.4555 -228.536292) (xy 343.439452 -228.585685) (xy 343.415874 -228.631959) (xy 343.385348 -228.673975)
			(xy 343.348625 -228.710698) (xy 343.306609 -228.741224) (xy 343.260335 -228.764802) (xy 343.210942 -228.78085)
			(xy 343.159647 -228.788975) (xy 343.107713 -228.788975) (xy 343.056418 -228.78085) (xy 343.007025 -228.764802)
			(xy 342.960751 -228.741224) (xy 342.918735 -228.710698) (xy 342.882012 -228.673975) (xy 342.851486 -228.631959)
			(xy 342.827908 -228.585685) (xy 342.81186 -228.536292) (xy 342.803735 -228.484997) (xy 342.523825 -228.484997)
			(xy 342.5157 -228.536292) (xy 342.499652 -228.585685) (xy 342.476074 -228.631959) (xy 342.445548 -228.673975)
			(xy 342.408825 -228.710698) (xy 342.366809 -228.741224) (xy 342.320535 -228.764802) (xy 342.271142 -228.78085)
			(xy 342.219847 -228.788975) (xy 342.167913 -228.788975) (xy 342.116618 -228.78085) (xy 342.067225 -228.764802)
			(xy 342.020951 -228.741224) (xy 341.978935 -228.710698) (xy 341.942212 -228.673975) (xy 341.911686 -228.631959)
			(xy 341.888108 -228.585685) (xy 341.87206 -228.536292) (xy 341.863935 -228.484997) (xy 341.584025 -228.484997)
			(xy 341.5759 -228.536292) (xy 341.559852 -228.585685) (xy 341.536274 -228.631959) (xy 341.505748 -228.673975)
			(xy 341.469025 -228.710698) (xy 341.427009 -228.741224) (xy 341.380735 -228.764802) (xy 341.331342 -228.78085)
			(xy 341.280047 -228.788975) (xy 341.228113 -228.788975) (xy 341.176818 -228.78085) (xy 341.127425 -228.764802)
			(xy 341.081151 -228.741224) (xy 341.039135 -228.710698) (xy 341.002412 -228.673975) (xy 340.971886 -228.631959)
			(xy 340.948308 -228.585685) (xy 340.93226 -228.536292) (xy 340.924135 -228.484997) (xy 340.644225 -228.484997)
			(xy 340.6361 -228.536292) (xy 340.620052 -228.585685) (xy 340.596474 -228.631959) (xy 340.565948 -228.673975)
			(xy 340.529225 -228.710698) (xy 340.487209 -228.741224) (xy 340.440935 -228.764802) (xy 340.391542 -228.78085)
			(xy 340.340247 -228.788975) (xy 340.288313 -228.788975) (xy 340.237018 -228.78085) (xy 340.187625 -228.764802)
			(xy 340.141351 -228.741224) (xy 340.099335 -228.710698) (xy 340.062612 -228.673975) (xy 340.032086 -228.631959)
			(xy 340.008508 -228.585685) (xy 339.99246 -228.536292) (xy 339.984335 -228.484997) (xy 339.704871 -228.484997)
			(xy 339.704871 -228.485567) (xy 339.696381 -228.537993) (xy 339.679622 -228.588388) (xy 339.655024 -228.635457)
			(xy 339.62322 -228.67799) (xy 339.585027 -228.714893) (xy 339.541427 -228.745218) (xy 339.517736 -228.757226)
			(xy 339.505036 -228.763322) (xy 339.475064 -228.808788) (xy 339.475064 -228.93655) (xy 339.475476 -228.945449)
			(xy 339.481738 -228.962115) (xy 339.493368 -228.975594) (xy 339.500972 -228.980238) (xy 339.584284 -229.020116)
			(xy 339.5923 -229.023011) (xy 339.609314 -229.023799) (xy 339.617558 -229.02164) (xy 339.638132 -229.014274)
			(xy 339.64118 -229.012242) (xy 339.644736 -229.009448) (xy 339.666443 -228.993637) (xy 339.713902 -228.968516)
			(xy 339.764795 -228.951383) (xy 339.817785 -228.94269) (xy 339.844634 -228.942138) (xy 339.870616 -228.94265)
			(xy 339.921939 -228.950784) (xy 339.971358 -228.966846) (xy 340.017656 -228.99044) (xy 340.059694 -229.020986)
			(xy 340.096436 -229.057732) (xy 340.126978 -229.099773) (xy 340.150567 -229.146073) (xy 340.166624 -229.195494)
			(xy 340.174752 -229.246818) (xy 340.174752 -229.298782) (xy 340.174747 -229.298813) (xy 340.454489 -229.298813)
			(xy 340.454489 -229.246879) (xy 340.462614 -229.195584) (xy 340.478662 -229.146191) (xy 340.50224 -229.099917)
			(xy 340.532766 -229.057901) (xy 340.569489 -229.021178) (xy 340.611505 -228.990652) (xy 340.657779 -228.967074)
			(xy 340.707172 -228.951026) (xy 340.758467 -228.942901) (xy 340.810401 -228.942901) (xy 340.861696 -228.951026)
			(xy 340.911089 -228.967074) (xy 340.957363 -228.990652) (xy 340.999379 -229.021178) (xy 341.036102 -229.057901)
			(xy 341.066628 -229.099917) (xy 341.090206 -229.146191) (xy 341.106254 -229.195584) (xy 341.114379 -229.246879)
			(xy 341.114888 -229.272846) (xy 341.114379 -229.298813) (xy 341.394289 -229.298813) (xy 341.394289 -229.246879)
			(xy 341.402414 -229.195584) (xy 341.418462 -229.146191) (xy 341.44204 -229.099917) (xy 341.472566 -229.057901)
			(xy 341.509289 -229.021178) (xy 341.551305 -228.990652) (xy 341.597579 -228.967074) (xy 341.646972 -228.951026)
			(xy 341.698267 -228.942901) (xy 341.750201 -228.942901) (xy 341.801496 -228.951026) (xy 341.850889 -228.967074)
			(xy 341.897163 -228.990652) (xy 341.939179 -229.021178) (xy 341.975902 -229.057901) (xy 342.006428 -229.099917)
			(xy 342.030006 -229.146191) (xy 342.046054 -229.195584) (xy 342.054179 -229.246879) (xy 342.054688 -229.272846)
			(xy 342.054179 -229.298813) (xy 342.333835 -229.298813) (xy 342.333835 -229.246879) (xy 342.34196 -229.195584)
			(xy 342.358008 -229.146191) (xy 342.381586 -229.099917) (xy 342.412112 -229.057901) (xy 342.448835 -229.021178)
			(xy 342.490851 -228.990652) (xy 342.537125 -228.967074) (xy 342.586518 -228.951026) (xy 342.637813 -228.942901)
			(xy 342.689747 -228.942901) (xy 342.741042 -228.951026) (xy 342.790435 -228.967074) (xy 342.836709 -228.990652)
			(xy 342.878725 -229.021178) (xy 342.915448 -229.057901) (xy 342.945974 -229.099917) (xy 342.969552 -229.146191)
			(xy 342.9856 -229.195584) (xy 342.993725 -229.246879) (xy 342.994234 -229.272846) (xy 342.993725 -229.298813)
			(xy 343.273889 -229.298813) (xy 343.273889 -229.246879) (xy 343.282014 -229.195584) (xy 343.298062 -229.146191)
			(xy 343.32164 -229.099917) (xy 343.352166 -229.057901) (xy 343.388889 -229.021178) (xy 343.430905 -228.990652)
			(xy 343.477179 -228.967074) (xy 343.526572 -228.951026) (xy 343.577867 -228.942901) (xy 343.629801 -228.942901)
			(xy 343.681096 -228.951026) (xy 343.730489 -228.967074) (xy 343.776763 -228.990652) (xy 343.818779 -229.021178)
			(xy 343.855502 -229.057901) (xy 343.886028 -229.099917) (xy 343.909606 -229.146191) (xy 343.925654 -229.195584)
			(xy 343.933779 -229.246879) (xy 343.934288 -229.272846) (xy 343.933779 -229.298813) (xy 344.213689 -229.298813)
			(xy 344.213689 -229.246879) (xy 344.221814 -229.195584) (xy 344.237862 -229.146191) (xy 344.26144 -229.099917)
			(xy 344.291966 -229.057901) (xy 344.328689 -229.021178) (xy 344.370705 -228.990652) (xy 344.416979 -228.967074)
			(xy 344.466372 -228.951026) (xy 344.517667 -228.942901) (xy 344.569601 -228.942901) (xy 344.620896 -228.951026)
			(xy 344.670289 -228.967074) (xy 344.716563 -228.990652) (xy 344.758579 -229.021178) (xy 344.795302 -229.057901)
			(xy 344.825828 -229.099917) (xy 344.849406 -229.146191) (xy 344.865454 -229.195584) (xy 344.873579 -229.246879)
			(xy 344.874088 -229.272846) (xy 344.873579 -229.298813) (xy 345.153489 -229.298813) (xy 345.153489 -229.246879)
			(xy 345.161614 -229.195584) (xy 345.177662 -229.146191) (xy 345.20124 -229.099917) (xy 345.231766 -229.057901)
			(xy 345.268489 -229.021178) (xy 345.310505 -228.990652) (xy 345.356779 -228.967074) (xy 345.406172 -228.951026)
			(xy 345.457467 -228.942901) (xy 345.509401 -228.942901) (xy 345.560696 -228.951026) (xy 345.610089 -228.967074)
			(xy 345.656363 -228.990652) (xy 345.698379 -229.021178) (xy 345.735102 -229.057901) (xy 345.765628 -229.099917)
			(xy 345.789206 -229.146191) (xy 345.805254 -229.195584) (xy 345.813379 -229.246879) (xy 345.813888 -229.272846)
			(xy 345.813379 -229.298813) (xy 346.093289 -229.298813) (xy 346.093289 -229.246879) (xy 346.101414 -229.195584)
			(xy 346.117462 -229.146191) (xy 346.14104 -229.099917) (xy 346.171566 -229.057901) (xy 346.208289 -229.021178)
			(xy 346.250305 -228.990652) (xy 346.296579 -228.967074) (xy 346.345972 -228.951026) (xy 346.397267 -228.942901)
			(xy 346.449201 -228.942901) (xy 346.500496 -228.951026) (xy 346.549889 -228.967074) (xy 346.596163 -228.990652)
			(xy 346.638179 -229.021178) (xy 346.674902 -229.057901) (xy 346.705428 -229.099917) (xy 346.729006 -229.146191)
			(xy 346.745054 -229.195584) (xy 346.753179 -229.246879) (xy 346.753688 -229.272846) (xy 346.753179 -229.298813)
			(xy 347.033089 -229.298813) (xy 347.033089 -229.246879) (xy 347.041214 -229.195584) (xy 347.057262 -229.146191)
			(xy 347.08084 -229.099917) (xy 347.111366 -229.057901) (xy 347.148089 -229.021178) (xy 347.190105 -228.990652)
			(xy 347.236379 -228.967074) (xy 347.285772 -228.951026) (xy 347.337067 -228.942901) (xy 347.389001 -228.942901)
			(xy 347.440296 -228.951026) (xy 347.489689 -228.967074) (xy 347.535963 -228.990652) (xy 347.577979 -229.021178)
			(xy 347.614702 -229.057901) (xy 347.645228 -229.099917) (xy 347.668806 -229.146191) (xy 347.684854 -229.195584)
			(xy 347.692979 -229.246879) (xy 347.693488 -229.272846) (xy 347.692979 -229.298813) (xy 347.972889 -229.298813)
			(xy 347.972889 -229.246879) (xy 347.981014 -229.195584) (xy 347.997062 -229.146191) (xy 348.02064 -229.099917)
			(xy 348.051166 -229.057901) (xy 348.087889 -229.021178) (xy 348.129905 -228.990652) (xy 348.176179 -228.967074)
			(xy 348.225572 -228.951026) (xy 348.276867 -228.942901) (xy 348.328801 -228.942901) (xy 348.380096 -228.951026)
			(xy 348.429489 -228.967074) (xy 348.475763 -228.990652) (xy 348.517779 -229.021178) (xy 348.554502 -229.057901)
			(xy 348.585028 -229.099917) (xy 348.608606 -229.146191) (xy 348.624654 -229.195584) (xy 348.632779 -229.246879)
			(xy 348.633288 -229.272846) (xy 348.632779 -229.298813) (xy 348.912435 -229.298813) (xy 348.912435 -229.246879)
			(xy 348.92056 -229.195584) (xy 348.936608 -229.146191) (xy 348.960186 -229.099917) (xy 348.990712 -229.057901)
			(xy 349.027435 -229.021178) (xy 349.069451 -228.990652) (xy 349.115725 -228.967074) (xy 349.165118 -228.951026)
			(xy 349.216413 -228.942901) (xy 349.268347 -228.942901) (xy 349.319642 -228.951026) (xy 349.369035 -228.967074)
			(xy 349.415309 -228.990652) (xy 349.457325 -229.021178) (xy 349.494048 -229.057901) (xy 349.524574 -229.099917)
			(xy 349.548152 -229.146191) (xy 349.5642 -229.195584) (xy 349.572325 -229.246879) (xy 349.572834 -229.272846)
			(xy 349.572325 -229.298813) (xy 349.5642 -229.350108) (xy 349.548152 -229.399501) (xy 349.524574 -229.445775)
			(xy 349.494048 -229.487791) (xy 349.457325 -229.524514) (xy 349.415309 -229.55504) (xy 349.369035 -229.578618)
			(xy 349.319642 -229.594666) (xy 349.268347 -229.602791) (xy 349.216413 -229.602791) (xy 349.165118 -229.594666)
			(xy 349.115725 -229.578618) (xy 349.069451 -229.55504) (xy 349.027435 -229.524514) (xy 348.990712 -229.487791)
			(xy 348.960186 -229.445775) (xy 348.936608 -229.399501) (xy 348.92056 -229.350108) (xy 348.912435 -229.298813)
			(xy 348.632779 -229.298813) (xy 348.624654 -229.350108) (xy 348.608606 -229.399501) (xy 348.585028 -229.445775)
			(xy 348.554502 -229.487791) (xy 348.517779 -229.524514) (xy 348.475763 -229.55504) (xy 348.429489 -229.578618)
			(xy 348.380096 -229.594666) (xy 348.328801 -229.602791) (xy 348.276867 -229.602791) (xy 348.225572 -229.594666)
			(xy 348.176179 -229.578618) (xy 348.129905 -229.55504) (xy 348.087889 -229.524514) (xy 348.051166 -229.487791)
			(xy 348.02064 -229.445775) (xy 347.997062 -229.399501) (xy 347.981014 -229.350108) (xy 347.972889 -229.298813)
			(xy 347.692979 -229.298813) (xy 347.684854 -229.350108) (xy 347.668806 -229.399501) (xy 347.645228 -229.445775)
			(xy 347.614702 -229.487791) (xy 347.577979 -229.524514) (xy 347.535963 -229.55504) (xy 347.489689 -229.578618)
			(xy 347.440296 -229.594666) (xy 347.389001 -229.602791) (xy 347.337067 -229.602791) (xy 347.285772 -229.594666)
			(xy 347.236379 -229.578618) (xy 347.190105 -229.55504) (xy 347.148089 -229.524514) (xy 347.111366 -229.487791)
			(xy 347.08084 -229.445775) (xy 347.057262 -229.399501) (xy 347.041214 -229.350108) (xy 347.033089 -229.298813)
			(xy 346.753179 -229.298813) (xy 346.745054 -229.350108) (xy 346.729006 -229.399501) (xy 346.705428 -229.445775)
			(xy 346.674902 -229.487791) (xy 346.638179 -229.524514) (xy 346.596163 -229.55504) (xy 346.549889 -229.578618)
			(xy 346.500496 -229.594666) (xy 346.449201 -229.602791) (xy 346.397267 -229.602791) (xy 346.345972 -229.594666)
			(xy 346.296579 -229.578618) (xy 346.250305 -229.55504) (xy 346.208289 -229.524514) (xy 346.171566 -229.487791)
			(xy 346.14104 -229.445775) (xy 346.117462 -229.399501) (xy 346.101414 -229.350108) (xy 346.093289 -229.298813)
			(xy 345.813379 -229.298813) (xy 345.805254 -229.350108) (xy 345.789206 -229.399501) (xy 345.765628 -229.445775)
			(xy 345.735102 -229.487791) (xy 345.698379 -229.524514) (xy 345.656363 -229.55504) (xy 345.610089 -229.578618)
			(xy 345.560696 -229.594666) (xy 345.509401 -229.602791) (xy 345.457467 -229.602791) (xy 345.406172 -229.594666)
			(xy 345.356779 -229.578618) (xy 345.310505 -229.55504) (xy 345.268489 -229.524514) (xy 345.231766 -229.487791)
			(xy 345.20124 -229.445775) (xy 345.177662 -229.399501) (xy 345.161614 -229.350108) (xy 345.153489 -229.298813)
			(xy 344.873579 -229.298813) (xy 344.865454 -229.350108) (xy 344.849406 -229.399501) (xy 344.825828 -229.445775)
			(xy 344.795302 -229.487791) (xy 344.758579 -229.524514) (xy 344.716563 -229.55504) (xy 344.670289 -229.578618)
			(xy 344.620896 -229.594666) (xy 344.569601 -229.602791) (xy 344.517667 -229.602791) (xy 344.466372 -229.594666)
			(xy 344.416979 -229.578618) (xy 344.370705 -229.55504) (xy 344.328689 -229.524514) (xy 344.291966 -229.487791)
			(xy 344.26144 -229.445775) (xy 344.237862 -229.399501) (xy 344.221814 -229.350108) (xy 344.213689 -229.298813)
			(xy 343.933779 -229.298813) (xy 343.925654 -229.350108) (xy 343.909606 -229.399501) (xy 343.886028 -229.445775)
			(xy 343.855502 -229.487791) (xy 343.818779 -229.524514) (xy 343.776763 -229.55504) (xy 343.730489 -229.578618)
			(xy 343.681096 -229.594666) (xy 343.629801 -229.602791) (xy 343.577867 -229.602791) (xy 343.526572 -229.594666)
			(xy 343.477179 -229.578618) (xy 343.430905 -229.55504) (xy 343.388889 -229.524514) (xy 343.352166 -229.487791)
			(xy 343.32164 -229.445775) (xy 343.298062 -229.399501) (xy 343.282014 -229.350108) (xy 343.273889 -229.298813)
			(xy 342.993725 -229.298813) (xy 342.9856 -229.350108) (xy 342.969552 -229.399501) (xy 342.945974 -229.445775)
			(xy 342.915448 -229.487791) (xy 342.878725 -229.524514) (xy 342.836709 -229.55504) (xy 342.790435 -229.578618)
			(xy 342.741042 -229.594666) (xy 342.689747 -229.602791) (xy 342.637813 -229.602791) (xy 342.586518 -229.594666)
			(xy 342.537125 -229.578618) (xy 342.490851 -229.55504) (xy 342.448835 -229.524514) (xy 342.412112 -229.487791)
			(xy 342.381586 -229.445775) (xy 342.358008 -229.399501) (xy 342.34196 -229.350108) (xy 342.333835 -229.298813)
			(xy 342.054179 -229.298813) (xy 342.046054 -229.350108) (xy 342.030006 -229.399501) (xy 342.006428 -229.445775)
			(xy 341.975902 -229.487791) (xy 341.939179 -229.524514) (xy 341.897163 -229.55504) (xy 341.850889 -229.578618)
			(xy 341.801496 -229.594666) (xy 341.750201 -229.602791) (xy 341.698267 -229.602791) (xy 341.646972 -229.594666)
			(xy 341.597579 -229.578618) (xy 341.551305 -229.55504) (xy 341.509289 -229.524514) (xy 341.472566 -229.487791)
			(xy 341.44204 -229.445775) (xy 341.418462 -229.399501) (xy 341.402414 -229.350108) (xy 341.394289 -229.298813)
			(xy 341.114379 -229.298813) (xy 341.106254 -229.350108) (xy 341.090206 -229.399501) (xy 341.066628 -229.445775)
			(xy 341.036102 -229.487791) (xy 340.999379 -229.524514) (xy 340.957363 -229.55504) (xy 340.911089 -229.578618)
			(xy 340.861696 -229.594666) (xy 340.810401 -229.602791) (xy 340.758467 -229.602791) (xy 340.707172 -229.594666)
			(xy 340.657779 -229.578618) (xy 340.611505 -229.55504) (xy 340.569489 -229.524514) (xy 340.532766 -229.487791)
			(xy 340.50224 -229.445775) (xy 340.478662 -229.399501) (xy 340.462614 -229.350108) (xy 340.454489 -229.298813)
			(xy 340.174747 -229.298813) (xy 340.166624 -229.350106) (xy 340.150567 -229.399527) (xy 340.126978 -229.445827)
			(xy 340.096436 -229.487868) (xy 340.059694 -229.524614) (xy 340.017656 -229.55516) (xy 339.971358 -229.578754)
			(xy 339.921939 -229.594816) (xy 339.870616 -229.60295) (xy 339.844634 -229.603554) (xy 339.817668 -229.603017)
			(xy 339.764452 -229.594259) (xy 339.71336 -229.576986) (xy 339.665747 -229.551655) (xy 339.643974 -229.535736)
			(xy 339.637878 -229.531164) (xy 339.619844 -229.524814) (xy 339.61112 -229.522135) (xy 339.59289 -229.522537)
			(xy 339.584284 -229.525576) (xy 339.500972 -229.565454) (xy 339.493337 -229.570056) (xy 339.48169 -229.583536)
			(xy 339.475483 -229.600234) (xy 339.475064 -229.609142) (xy 339.475064 -229.736904) (xy 339.505036 -229.78237)
			(xy 339.517736 -229.788466) (xy 339.541443 -229.800437) (xy 339.585028 -229.830781) (xy 339.623205 -229.867697)
			(xy 339.654995 -229.910238) (xy 339.679581 -229.95731) (xy 339.696333 -230.007706) (xy 339.704819 -230.06013)
			(xy 339.704821 -230.112629) (xy 339.984335 -230.112629) (xy 339.984335 -230.060695) (xy 339.99246 -230.0094)
			(xy 340.008508 -229.960007) (xy 340.032086 -229.913733) (xy 340.062612 -229.871717) (xy 340.099335 -229.834994)
			(xy 340.141351 -229.804468) (xy 340.187625 -229.78089) (xy 340.237018 -229.764842) (xy 340.288313 -229.756717)
			(xy 340.340247 -229.756717) (xy 340.391542 -229.764842) (xy 340.440935 -229.78089) (xy 340.487209 -229.804468)
			(xy 340.529225 -229.834994) (xy 340.565948 -229.871717) (xy 340.596474 -229.913733) (xy 340.620052 -229.960007)
			(xy 340.6361 -230.0094) (xy 340.644225 -230.060695) (xy 340.644734 -230.086662) (xy 340.644225 -230.112629)
			(xy 340.924135 -230.112629) (xy 340.924135 -230.060695) (xy 340.93226 -230.0094) (xy 340.948308 -229.960007)
			(xy 340.971886 -229.913733) (xy 341.002412 -229.871717) (xy 341.039135 -229.834994) (xy 341.081151 -229.804468)
			(xy 341.127425 -229.78089) (xy 341.176818 -229.764842) (xy 341.228113 -229.756717) (xy 341.280047 -229.756717)
			(xy 341.331342 -229.764842) (xy 341.380735 -229.78089) (xy 341.427009 -229.804468) (xy 341.469025 -229.834994)
			(xy 341.505748 -229.871717) (xy 341.536274 -229.913733) (xy 341.559852 -229.960007) (xy 341.5759 -230.0094)
			(xy 341.584025 -230.060695) (xy 341.584534 -230.086662) (xy 341.584025 -230.112629) (xy 341.863935 -230.112629)
			(xy 341.863935 -230.060695) (xy 341.87206 -230.0094) (xy 341.888108 -229.960007) (xy 341.911686 -229.913733)
			(xy 341.942212 -229.871717) (xy 341.978935 -229.834994) (xy 342.020951 -229.804468) (xy 342.067225 -229.78089)
			(xy 342.116618 -229.764842) (xy 342.167913 -229.756717) (xy 342.219847 -229.756717) (xy 342.271142 -229.764842)
			(xy 342.320535 -229.78089) (xy 342.366809 -229.804468) (xy 342.408825 -229.834994) (xy 342.445548 -229.871717)
			(xy 342.476074 -229.913733) (xy 342.499652 -229.960007) (xy 342.5157 -230.0094) (xy 342.523825 -230.060695)
			(xy 342.524334 -230.086662) (xy 342.523825 -230.112629) (xy 342.803735 -230.112629) (xy 342.803735 -230.060695)
			(xy 342.81186 -230.0094) (xy 342.827908 -229.960007) (xy 342.851486 -229.913733) (xy 342.882012 -229.871717)
			(xy 342.918735 -229.834994) (xy 342.960751 -229.804468) (xy 343.007025 -229.78089) (xy 343.056418 -229.764842)
			(xy 343.107713 -229.756717) (xy 343.159647 -229.756717) (xy 343.210942 -229.764842) (xy 343.260335 -229.78089)
			(xy 343.306609 -229.804468) (xy 343.348625 -229.834994) (xy 343.385348 -229.871717) (xy 343.415874 -229.913733)
			(xy 343.439452 -229.960007) (xy 343.4555 -230.0094) (xy 343.463625 -230.060695) (xy 343.464134 -230.086662)
			(xy 343.463625 -230.112629) (xy 343.743535 -230.112629) (xy 343.743535 -230.060695) (xy 343.75166 -230.0094)
			(xy 343.767708 -229.960007) (xy 343.791286 -229.913733) (xy 343.821812 -229.871717) (xy 343.858535 -229.834994)
			(xy 343.900551 -229.804468) (xy 343.946825 -229.78089) (xy 343.996218 -229.764842) (xy 344.047513 -229.756717)
			(xy 344.099447 -229.756717) (xy 344.150742 -229.764842) (xy 344.200135 -229.78089) (xy 344.246409 -229.804468)
			(xy 344.288425 -229.834994) (xy 344.325148 -229.871717) (xy 344.355674 -229.913733) (xy 344.379252 -229.960007)
			(xy 344.3953 -230.0094) (xy 344.403425 -230.060695) (xy 344.403934 -230.086662) (xy 344.403425 -230.112629)
			(xy 344.683589 -230.112629) (xy 344.683589 -230.060695) (xy 344.691714 -230.0094) (xy 344.707762 -229.960007)
			(xy 344.73134 -229.913733) (xy 344.761866 -229.871717) (xy 344.798589 -229.834994) (xy 344.840605 -229.804468)
			(xy 344.886879 -229.78089) (xy 344.936272 -229.764842) (xy 344.987567 -229.756717) (xy 345.039501 -229.756717)
			(xy 345.090796 -229.764842) (xy 345.140189 -229.78089) (xy 345.186463 -229.804468) (xy 345.228479 -229.834994)
			(xy 345.265202 -229.871717) (xy 345.295728 -229.913733) (xy 345.319306 -229.960007) (xy 345.335354 -230.0094)
			(xy 345.343479 -230.060695) (xy 345.343988 -230.086662) (xy 345.343479 -230.112629) (xy 345.623135 -230.112629)
			(xy 345.623135 -230.060695) (xy 345.63126 -230.0094) (xy 345.647308 -229.960007) (xy 345.670886 -229.913733)
			(xy 345.701412 -229.871717) (xy 345.738135 -229.834994) (xy 345.780151 -229.804468) (xy 345.826425 -229.78089)
			(xy 345.875818 -229.764842) (xy 345.927113 -229.756717) (xy 345.979047 -229.756717) (xy 346.030342 -229.764842)
			(xy 346.079735 -229.78089) (xy 346.126009 -229.804468) (xy 346.168025 -229.834994) (xy 346.204748 -229.871717)
			(xy 346.235274 -229.913733) (xy 346.258852 -229.960007) (xy 346.2749 -230.0094) (xy 346.283025 -230.060695)
			(xy 346.283534 -230.086662) (xy 346.283025 -230.112629) (xy 346.562935 -230.112629) (xy 346.562935 -230.060695)
			(xy 346.57106 -230.0094) (xy 346.587108 -229.960007) (xy 346.610686 -229.913733) (xy 346.641212 -229.871717)
			(xy 346.677935 -229.834994) (xy 346.719951 -229.804468) (xy 346.766225 -229.78089) (xy 346.815618 -229.764842)
			(xy 346.866913 -229.756717) (xy 346.918847 -229.756717) (xy 346.970142 -229.764842) (xy 347.019535 -229.78089)
			(xy 347.065809 -229.804468) (xy 347.107825 -229.834994) (xy 347.144548 -229.871717) (xy 347.175074 -229.913733)
			(xy 347.198652 -229.960007) (xy 347.2147 -230.0094) (xy 347.222825 -230.060695) (xy 347.223334 -230.086662)
			(xy 347.222825 -230.112629) (xy 347.502735 -230.112629) (xy 347.502735 -230.060695) (xy 347.51086 -230.0094)
			(xy 347.526908 -229.960007) (xy 347.550486 -229.913733) (xy 347.581012 -229.871717) (xy 347.617735 -229.834994)
			(xy 347.659751 -229.804468) (xy 347.706025 -229.78089) (xy 347.755418 -229.764842) (xy 347.806713 -229.756717)
			(xy 347.858647 -229.756717) (xy 347.909942 -229.764842) (xy 347.959335 -229.78089) (xy 348.005609 -229.804468)
			(xy 348.047625 -229.834994) (xy 348.084348 -229.871717) (xy 348.114874 -229.913733) (xy 348.138452 -229.960007)
			(xy 348.1545 -230.0094) (xy 348.162625 -230.060695) (xy 348.163134 -230.086662) (xy 348.162625 -230.112629)
			(xy 348.442535 -230.112629) (xy 348.442535 -230.060695) (xy 348.45066 -230.0094) (xy 348.466708 -229.960007)
			(xy 348.490286 -229.913733) (xy 348.520812 -229.871717) (xy 348.557535 -229.834994) (xy 348.599551 -229.804468)
			(xy 348.645825 -229.78089) (xy 348.695218 -229.764842) (xy 348.746513 -229.756717) (xy 348.798447 -229.756717)
			(xy 348.849742 -229.764842) (xy 348.899135 -229.78089) (xy 348.945409 -229.804468) (xy 348.987425 -229.834994)
			(xy 349.024148 -229.871717) (xy 349.054674 -229.913733) (xy 349.078252 -229.960007) (xy 349.0943 -230.0094)
			(xy 349.102425 -230.060695) (xy 349.102934 -230.086662) (xy 349.102425 -230.112629) (xy 349.0943 -230.163924)
			(xy 349.078252 -230.213317) (xy 349.054674 -230.259591) (xy 349.024148 -230.301607) (xy 348.987425 -230.33833)
			(xy 348.945409 -230.368856) (xy 348.899135 -230.392434) (xy 348.849742 -230.408482) (xy 348.798447 -230.416607)
			(xy 348.746513 -230.416607) (xy 348.695218 -230.408482) (xy 348.645825 -230.392434) (xy 348.599551 -230.368856)
			(xy 348.557535 -230.33833) (xy 348.520812 -230.301607) (xy 348.490286 -230.259591) (xy 348.466708 -230.213317)
			(xy 348.45066 -230.163924) (xy 348.442535 -230.112629) (xy 348.162625 -230.112629) (xy 348.1545 -230.163924)
			(xy 348.138452 -230.213317) (xy 348.114874 -230.259591) (xy 348.084348 -230.301607) (xy 348.047625 -230.33833)
			(xy 348.005609 -230.368856) (xy 347.959335 -230.392434) (xy 347.909942 -230.408482) (xy 347.858647 -230.416607)
			(xy 347.806713 -230.416607) (xy 347.755418 -230.408482) (xy 347.706025 -230.392434) (xy 347.659751 -230.368856)
			(xy 347.617735 -230.33833) (xy 347.581012 -230.301607) (xy 347.550486 -230.259591) (xy 347.526908 -230.213317)
			(xy 347.51086 -230.163924) (xy 347.502735 -230.112629) (xy 347.222825 -230.112629) (xy 347.2147 -230.163924)
			(xy 347.198652 -230.213317) (xy 347.175074 -230.259591) (xy 347.144548 -230.301607) (xy 347.107825 -230.33833)
			(xy 347.065809 -230.368856) (xy 347.019535 -230.392434) (xy 346.970142 -230.408482) (xy 346.918847 -230.416607)
			(xy 346.866913 -230.416607) (xy 346.815618 -230.408482) (xy 346.766225 -230.392434) (xy 346.719951 -230.368856)
			(xy 346.677935 -230.33833) (xy 346.641212 -230.301607) (xy 346.610686 -230.259591) (xy 346.587108 -230.213317)
			(xy 346.57106 -230.163924) (xy 346.562935 -230.112629) (xy 346.283025 -230.112629) (xy 346.2749 -230.163924)
			(xy 346.258852 -230.213317) (xy 346.235274 -230.259591) (xy 346.204748 -230.301607) (xy 346.168025 -230.33833)
			(xy 346.126009 -230.368856) (xy 346.079735 -230.392434) (xy 346.030342 -230.408482) (xy 345.979047 -230.416607)
			(xy 345.927113 -230.416607) (xy 345.875818 -230.408482) (xy 345.826425 -230.392434) (xy 345.780151 -230.368856)
			(xy 345.738135 -230.33833) (xy 345.701412 -230.301607) (xy 345.670886 -230.259591) (xy 345.647308 -230.213317)
			(xy 345.63126 -230.163924) (xy 345.623135 -230.112629) (xy 345.343479 -230.112629) (xy 345.335354 -230.163924)
			(xy 345.319306 -230.213317) (xy 345.295728 -230.259591) (xy 345.265202 -230.301607) (xy 345.228479 -230.33833)
			(xy 345.186463 -230.368856) (xy 345.140189 -230.392434) (xy 345.090796 -230.408482) (xy 345.039501 -230.416607)
			(xy 344.987567 -230.416607) (xy 344.936272 -230.408482) (xy 344.886879 -230.392434) (xy 344.840605 -230.368856)
			(xy 344.798589 -230.33833) (xy 344.761866 -230.301607) (xy 344.73134 -230.259591) (xy 344.707762 -230.213317)
			(xy 344.691714 -230.163924) (xy 344.683589 -230.112629) (xy 344.403425 -230.112629) (xy 344.3953 -230.163924)
			(xy 344.379252 -230.213317) (xy 344.355674 -230.259591) (xy 344.325148 -230.301607) (xy 344.288425 -230.33833)
			(xy 344.246409 -230.368856) (xy 344.200135 -230.392434) (xy 344.150742 -230.408482) (xy 344.099447 -230.416607)
			(xy 344.047513 -230.416607) (xy 343.996218 -230.408482) (xy 343.946825 -230.392434) (xy 343.900551 -230.368856)
			(xy 343.858535 -230.33833) (xy 343.821812 -230.301607) (xy 343.791286 -230.259591) (xy 343.767708 -230.213317)
			(xy 343.75166 -230.163924) (xy 343.743535 -230.112629) (xy 343.463625 -230.112629) (xy 343.4555 -230.163924)
			(xy 343.439452 -230.213317) (xy 343.415874 -230.259591) (xy 343.385348 -230.301607) (xy 343.348625 -230.33833)
			(xy 343.306609 -230.368856) (xy 343.260335 -230.392434) (xy 343.210942 -230.408482) (xy 343.159647 -230.416607)
			(xy 343.107713 -230.416607) (xy 343.056418 -230.408482) (xy 343.007025 -230.392434) (xy 342.960751 -230.368856)
			(xy 342.918735 -230.33833) (xy 342.882012 -230.301607) (xy 342.851486 -230.259591) (xy 342.827908 -230.213317)
			(xy 342.81186 -230.163924) (xy 342.803735 -230.112629) (xy 342.523825 -230.112629) (xy 342.5157 -230.163924)
			(xy 342.499652 -230.213317) (xy 342.476074 -230.259591) (xy 342.445548 -230.301607) (xy 342.408825 -230.33833)
			(xy 342.366809 -230.368856) (xy 342.320535 -230.392434) (xy 342.271142 -230.408482) (xy 342.219847 -230.416607)
			(xy 342.167913 -230.416607) (xy 342.116618 -230.408482) (xy 342.067225 -230.392434) (xy 342.020951 -230.368856)
			(xy 341.978935 -230.33833) (xy 341.942212 -230.301607) (xy 341.911686 -230.259591) (xy 341.888108 -230.213317)
			(xy 341.87206 -230.163924) (xy 341.863935 -230.112629) (xy 341.584025 -230.112629) (xy 341.5759 -230.163924)
			(xy 341.559852 -230.213317) (xy 341.536274 -230.259591) (xy 341.505748 -230.301607) (xy 341.469025 -230.33833)
			(xy 341.427009 -230.368856) (xy 341.380735 -230.392434) (xy 341.331342 -230.408482) (xy 341.280047 -230.416607)
			(xy 341.228113 -230.416607) (xy 341.176818 -230.408482) (xy 341.127425 -230.392434) (xy 341.081151 -230.368856)
			(xy 341.039135 -230.33833) (xy 341.002412 -230.301607) (xy 340.971886 -230.259591) (xy 340.948308 -230.213317)
			(xy 340.93226 -230.163924) (xy 340.924135 -230.112629) (xy 340.644225 -230.112629) (xy 340.6361 -230.163924)
			(xy 340.620052 -230.213317) (xy 340.596474 -230.259591) (xy 340.565948 -230.301607) (xy 340.529225 -230.33833)
			(xy 340.487209 -230.368856) (xy 340.440935 -230.392434) (xy 340.391542 -230.408482) (xy 340.340247 -230.416607)
			(xy 340.288313 -230.416607) (xy 340.237018 -230.408482) (xy 340.187625 -230.392434) (xy 340.141351 -230.368856)
			(xy 340.099335 -230.33833) (xy 340.062612 -230.301607) (xy 340.032086 -230.259591) (xy 340.008508 -230.213317)
			(xy 339.99246 -230.163924) (xy 339.984335 -230.112629) (xy 339.704821 -230.112629) (xy 339.704821 -230.113237)
			(xy 339.696341 -230.165662) (xy 339.679594 -230.216059) (xy 339.655013 -230.263134) (xy 339.623227 -230.305678)
			(xy 339.585053 -230.342598) (xy 339.541472 -230.372946) (xy 339.517736 -230.384858) (xy 339.505036 -230.390954)
			(xy 339.475064 -230.43642) (xy 339.475064 -230.564182) (xy 339.475481 -230.573078) (xy 339.48175 -230.589735)
			(xy 339.493383 -230.603206) (xy 339.500972 -230.60787) (xy 339.584284 -230.647748) (xy 339.5923 -230.650646)
			(xy 339.609314 -230.651435) (xy 339.617558 -230.649272) (xy 339.638132 -230.641906) (xy 339.64118 -230.639874)
			(xy 339.644736 -230.63708) (xy 339.666444 -230.621272) (xy 339.713905 -230.596156) (xy 339.764797 -230.579027)
			(xy 339.817786 -230.570335) (xy 339.844634 -230.56977) (xy 339.870621 -230.570282) (xy 339.921955 -230.578417)
			(xy 339.971384 -230.594483) (xy 340.017692 -230.618082) (xy 340.059738 -230.648634) (xy 340.096488 -230.685388)
			(xy 340.127036 -230.727437) (xy 340.150631 -230.773747) (xy 340.16669 -230.823178) (xy 340.174821 -230.874513)
			(xy 340.174821 -230.926445) (xy 340.454489 -230.926445) (xy 340.454489 -230.874511) (xy 340.462614 -230.823216)
			(xy 340.478662 -230.773823) (xy 340.50224 -230.727549) (xy 340.532766 -230.685533) (xy 340.569489 -230.64881)
			(xy 340.611505 -230.618284) (xy 340.657779 -230.594706) (xy 340.707172 -230.578658) (xy 340.758467 -230.570533)
			(xy 340.810401 -230.570533) (xy 340.861696 -230.578658) (xy 340.911089 -230.594706) (xy 340.957363 -230.618284)
			(xy 340.999379 -230.64881) (xy 341.036102 -230.685533) (xy 341.066628 -230.727549) (xy 341.090206 -230.773823)
			(xy 341.106254 -230.823216) (xy 341.114379 -230.874511) (xy 341.114888 -230.900478) (xy 341.114379 -230.926445)
			(xy 341.394289 -230.926445) (xy 341.394289 -230.874511) (xy 341.402414 -230.823216) (xy 341.418462 -230.773823)
			(xy 341.44204 -230.727549) (xy 341.472566 -230.685533) (xy 341.509289 -230.64881) (xy 341.551305 -230.618284)
			(xy 341.597579 -230.594706) (xy 341.646972 -230.578658) (xy 341.698267 -230.570533) (xy 341.750201 -230.570533)
			(xy 341.801496 -230.578658) (xy 341.850889 -230.594706) (xy 341.897163 -230.618284) (xy 341.939179 -230.64881)
			(xy 341.975902 -230.685533) (xy 342.006428 -230.727549) (xy 342.030006 -230.773823) (xy 342.046054 -230.823216)
			(xy 342.054179 -230.874511) (xy 342.054688 -230.900478) (xy 342.054179 -230.926445) (xy 342.334089 -230.926445)
			(xy 342.334089 -230.874511) (xy 342.342214 -230.823216) (xy 342.358262 -230.773823) (xy 342.38184 -230.727549)
			(xy 342.412366 -230.685533) (xy 342.449089 -230.64881) (xy 342.491105 -230.618284) (xy 342.537379 -230.594706)
			(xy 342.586772 -230.578658) (xy 342.638067 -230.570533) (xy 342.690001 -230.570533) (xy 342.741296 -230.578658)
			(xy 342.790689 -230.594706) (xy 342.836963 -230.618284) (xy 342.878979 -230.64881) (xy 342.915702 -230.685533)
			(xy 342.946228 -230.727549) (xy 342.969806 -230.773823) (xy 342.985854 -230.823216) (xy 342.993979 -230.874511)
			(xy 342.994488 -230.900478) (xy 342.993979 -230.926445) (xy 343.273889 -230.926445) (xy 343.273889 -230.874511)
			(xy 343.282014 -230.823216) (xy 343.298062 -230.773823) (xy 343.32164 -230.727549) (xy 343.352166 -230.685533)
			(xy 343.388889 -230.64881) (xy 343.430905 -230.618284) (xy 343.477179 -230.594706) (xy 343.526572 -230.578658)
			(xy 343.577867 -230.570533) (xy 343.629801 -230.570533) (xy 343.681096 -230.578658) (xy 343.730489 -230.594706)
			(xy 343.776763 -230.618284) (xy 343.818779 -230.64881) (xy 343.855502 -230.685533) (xy 343.886028 -230.727549)
			(xy 343.909606 -230.773823) (xy 343.925654 -230.823216) (xy 343.933779 -230.874511) (xy 343.934288 -230.900478)
			(xy 343.933779 -230.926445) (xy 344.213689 -230.926445) (xy 344.213689 -230.874511) (xy 344.221814 -230.823216)
			(xy 344.237862 -230.773823) (xy 344.26144 -230.727549) (xy 344.291966 -230.685533) (xy 344.328689 -230.64881)
			(xy 344.370705 -230.618284) (xy 344.416979 -230.594706) (xy 344.466372 -230.578658) (xy 344.517667 -230.570533)
			(xy 344.569601 -230.570533) (xy 344.620896 -230.578658) (xy 344.670289 -230.594706) (xy 344.716563 -230.618284)
			(xy 344.758579 -230.64881) (xy 344.795302 -230.685533) (xy 344.825828 -230.727549) (xy 344.849406 -230.773823)
			(xy 344.865454 -230.823216) (xy 344.873579 -230.874511) (xy 344.874088 -230.900478) (xy 344.873579 -230.926445)
			(xy 345.153235 -230.926445) (xy 345.153235 -230.874511) (xy 345.16136 -230.823216) (xy 345.177408 -230.773823)
			(xy 345.200986 -230.727549) (xy 345.231512 -230.685533) (xy 345.268235 -230.64881) (xy 345.310251 -230.618284)
			(xy 345.356525 -230.594706) (xy 345.405918 -230.578658) (xy 345.457213 -230.570533) (xy 345.509147 -230.570533)
			(xy 345.560442 -230.578658) (xy 345.609835 -230.594706) (xy 345.656109 -230.618284) (xy 345.698125 -230.64881)
			(xy 345.734848 -230.685533) (xy 345.765374 -230.727549) (xy 345.788952 -230.773823) (xy 345.805 -230.823216)
			(xy 345.813125 -230.874511) (xy 345.813634 -230.900478) (xy 345.813125 -230.926445) (xy 346.093289 -230.926445)
			(xy 346.093289 -230.874511) (xy 346.101414 -230.823216) (xy 346.117462 -230.773823) (xy 346.14104 -230.727549)
			(xy 346.171566 -230.685533) (xy 346.208289 -230.64881) (xy 346.250305 -230.618284) (xy 346.296579 -230.594706)
			(xy 346.345972 -230.578658) (xy 346.397267 -230.570533) (xy 346.449201 -230.570533) (xy 346.500496 -230.578658)
			(xy 346.549889 -230.594706) (xy 346.596163 -230.618284) (xy 346.638179 -230.64881) (xy 346.674902 -230.685533)
			(xy 346.705428 -230.727549) (xy 346.729006 -230.773823) (xy 346.745054 -230.823216) (xy 346.753179 -230.874511)
			(xy 346.753688 -230.900478) (xy 346.753179 -230.926445) (xy 347.033089 -230.926445) (xy 347.033089 -230.874511)
			(xy 347.041214 -230.823216) (xy 347.057262 -230.773823) (xy 347.08084 -230.727549) (xy 347.111366 -230.685533)
			(xy 347.148089 -230.64881) (xy 347.190105 -230.618284) (xy 347.236379 -230.594706) (xy 347.285772 -230.578658)
			(xy 347.337067 -230.570533) (xy 347.389001 -230.570533) (xy 347.440296 -230.578658) (xy 347.489689 -230.594706)
			(xy 347.535963 -230.618284) (xy 347.577979 -230.64881) (xy 347.614702 -230.685533) (xy 347.645228 -230.727549)
			(xy 347.668806 -230.773823) (xy 347.684854 -230.823216) (xy 347.692979 -230.874511) (xy 347.693488 -230.900478)
			(xy 347.692979 -230.926445) (xy 347.972889 -230.926445) (xy 347.972889 -230.874511) (xy 347.981014 -230.823216)
			(xy 347.997062 -230.773823) (xy 348.02064 -230.727549) (xy 348.051166 -230.685533) (xy 348.087889 -230.64881)
			(xy 348.129905 -230.618284) (xy 348.176179 -230.594706) (xy 348.225572 -230.578658) (xy 348.276867 -230.570533)
			(xy 348.328801 -230.570533) (xy 348.380096 -230.578658) (xy 348.429489 -230.594706) (xy 348.475763 -230.618284)
			(xy 348.517779 -230.64881) (xy 348.554502 -230.685533) (xy 348.585028 -230.727549) (xy 348.608606 -230.773823)
			(xy 348.624654 -230.823216) (xy 348.632779 -230.874511) (xy 348.633288 -230.900478) (xy 348.632779 -230.926445)
			(xy 348.624654 -230.97774) (xy 348.608606 -231.027133) (xy 348.585028 -231.073407) (xy 348.554502 -231.115423)
			(xy 348.517779 -231.152146) (xy 348.475763 -231.182672) (xy 348.429489 -231.20625) (xy 348.380096 -231.222298)
			(xy 348.328801 -231.230423) (xy 348.276867 -231.230423) (xy 348.225572 -231.222298) (xy 348.176179 -231.20625)
			(xy 348.129905 -231.182672) (xy 348.087889 -231.152146) (xy 348.051166 -231.115423) (xy 348.02064 -231.073407)
			(xy 347.997062 -231.027133) (xy 347.981014 -230.97774) (xy 347.972889 -230.926445) (xy 347.692979 -230.926445)
			(xy 347.684854 -230.97774) (xy 347.668806 -231.027133) (xy 347.645228 -231.073407) (xy 347.614702 -231.115423)
			(xy 347.577979 -231.152146) (xy 347.535963 -231.182672) (xy 347.489689 -231.20625) (xy 347.440296 -231.222298)
			(xy 347.389001 -231.230423) (xy 347.337067 -231.230423) (xy 347.285772 -231.222298) (xy 347.236379 -231.20625)
			(xy 347.190105 -231.182672) (xy 347.148089 -231.152146) (xy 347.111366 -231.115423) (xy 347.08084 -231.073407)
			(xy 347.057262 -231.027133) (xy 347.041214 -230.97774) (xy 347.033089 -230.926445) (xy 346.753179 -230.926445)
			(xy 346.745054 -230.97774) (xy 346.729006 -231.027133) (xy 346.705428 -231.073407) (xy 346.674902 -231.115423)
			(xy 346.638179 -231.152146) (xy 346.596163 -231.182672) (xy 346.549889 -231.20625) (xy 346.500496 -231.222298)
			(xy 346.449201 -231.230423) (xy 346.397267 -231.230423) (xy 346.345972 -231.222298) (xy 346.296579 -231.20625)
			(xy 346.250305 -231.182672) (xy 346.208289 -231.152146) (xy 346.171566 -231.115423) (xy 346.14104 -231.073407)
			(xy 346.117462 -231.027133) (xy 346.101414 -230.97774) (xy 346.093289 -230.926445) (xy 345.813125 -230.926445)
			(xy 345.805 -230.97774) (xy 345.788952 -231.027133) (xy 345.765374 -231.073407) (xy 345.734848 -231.115423)
			(xy 345.698125 -231.152146) (xy 345.656109 -231.182672) (xy 345.609835 -231.20625) (xy 345.560442 -231.222298)
			(xy 345.509147 -231.230423) (xy 345.457213 -231.230423) (xy 345.405918 -231.222298) (xy 345.356525 -231.20625)
			(xy 345.310251 -231.182672) (xy 345.268235 -231.152146) (xy 345.231512 -231.115423) (xy 345.200986 -231.073407)
			(xy 345.177408 -231.027133) (xy 345.16136 -230.97774) (xy 345.153235 -230.926445) (xy 344.873579 -230.926445)
			(xy 344.865454 -230.97774) (xy 344.849406 -231.027133) (xy 344.825828 -231.073407) (xy 344.795302 -231.115423)
			(xy 344.758579 -231.152146) (xy 344.716563 -231.182672) (xy 344.670289 -231.20625) (xy 344.620896 -231.222298)
			(xy 344.569601 -231.230423) (xy 344.517667 -231.230423) (xy 344.466372 -231.222298) (xy 344.416979 -231.20625)
			(xy 344.370705 -231.182672) (xy 344.328689 -231.152146) (xy 344.291966 -231.115423) (xy 344.26144 -231.073407)
			(xy 344.237862 -231.027133) (xy 344.221814 -230.97774) (xy 344.213689 -230.926445) (xy 343.933779 -230.926445)
			(xy 343.925654 -230.97774) (xy 343.909606 -231.027133) (xy 343.886028 -231.073407) (xy 343.855502 -231.115423)
			(xy 343.818779 -231.152146) (xy 343.776763 -231.182672) (xy 343.730489 -231.20625) (xy 343.681096 -231.222298)
			(xy 343.629801 -231.230423) (xy 343.577867 -231.230423) (xy 343.526572 -231.222298) (xy 343.477179 -231.20625)
			(xy 343.430905 -231.182672) (xy 343.388889 -231.152146) (xy 343.352166 -231.115423) (xy 343.32164 -231.073407)
			(xy 343.298062 -231.027133) (xy 343.282014 -230.97774) (xy 343.273889 -230.926445) (xy 342.993979 -230.926445)
			(xy 342.985854 -230.97774) (xy 342.969806 -231.027133) (xy 342.946228 -231.073407) (xy 342.915702 -231.115423)
			(xy 342.878979 -231.152146) (xy 342.836963 -231.182672) (xy 342.790689 -231.20625) (xy 342.741296 -231.222298)
			(xy 342.690001 -231.230423) (xy 342.638067 -231.230423) (xy 342.586772 -231.222298) (xy 342.537379 -231.20625)
			(xy 342.491105 -231.182672) (xy 342.449089 -231.152146) (xy 342.412366 -231.115423) (xy 342.38184 -231.073407)
			(xy 342.358262 -231.027133) (xy 342.342214 -230.97774) (xy 342.334089 -230.926445) (xy 342.054179 -230.926445)
			(xy 342.046054 -230.97774) (xy 342.030006 -231.027133) (xy 342.006428 -231.073407) (xy 341.975902 -231.115423)
			(xy 341.939179 -231.152146) (xy 341.897163 -231.182672) (xy 341.850889 -231.20625) (xy 341.801496 -231.222298)
			(xy 341.750201 -231.230423) (xy 341.698267 -231.230423) (xy 341.646972 -231.222298) (xy 341.597579 -231.20625)
			(xy 341.551305 -231.182672) (xy 341.509289 -231.152146) (xy 341.472566 -231.115423) (xy 341.44204 -231.073407)
			(xy 341.418462 -231.027133) (xy 341.402414 -230.97774) (xy 341.394289 -230.926445) (xy 341.114379 -230.926445)
			(xy 341.106254 -230.97774) (xy 341.090206 -231.027133) (xy 341.066628 -231.073407) (xy 341.036102 -231.115423)
			(xy 340.999379 -231.152146) (xy 340.957363 -231.182672) (xy 340.911089 -231.20625) (xy 340.861696 -231.222298)
			(xy 340.810401 -231.230423) (xy 340.758467 -231.230423) (xy 340.707172 -231.222298) (xy 340.657779 -231.20625)
			(xy 340.611505 -231.182672) (xy 340.569489 -231.152146) (xy 340.532766 -231.115423) (xy 340.50224 -231.073407)
			(xy 340.478662 -231.027133) (xy 340.462614 -230.97774) (xy 340.454489 -230.926445) (xy 340.174821 -230.926445)
			(xy 340.174821 -230.926487) (xy 340.16669 -230.977822) (xy 340.150631 -231.027253) (xy 340.127036 -231.073563)
			(xy 340.096488 -231.115612) (xy 340.059738 -231.152366) (xy 340.017692 -231.182918) (xy 339.971384 -231.206517)
			(xy 339.921955 -231.222583) (xy 339.870621 -231.230718) (xy 339.844634 -231.231186) (xy 339.817668 -231.230649)
			(xy 339.764453 -231.221889) (xy 339.713364 -231.204613) (xy 339.665753 -231.179278) (xy 339.643974 -231.163368)
			(xy 339.637878 -231.158796) (xy 339.619844 -231.152446) (xy 339.61112 -231.149766) (xy 339.59289 -231.150169)
			(xy 339.584284 -231.153208) (xy 339.500972 -231.193086) (xy 339.49333 -231.197685) (xy 339.481664 -231.211162)
			(xy 339.475435 -231.227862) (xy 339.475064 -231.236774) (xy 339.475064 -231.36479) (xy 339.505036 -231.410256)
			(xy 339.517736 -231.416352) (xy 339.541437 -231.428323) (xy 339.585007 -231.458665) (xy 339.623171 -231.495576)
			(xy 339.654949 -231.538111) (xy 339.679525 -231.585175) (xy 339.696266 -231.635561) (xy 339.704744 -231.687974)
			(xy 339.704741 -231.740515) (xy 339.984335 -231.740515) (xy 339.984335 -231.688581) (xy 339.99246 -231.637286)
			(xy 340.008508 -231.587893) (xy 340.032086 -231.541619) (xy 340.062612 -231.499603) (xy 340.099335 -231.46288)
			(xy 340.141351 -231.432354) (xy 340.187625 -231.408776) (xy 340.237018 -231.392728) (xy 340.288313 -231.384603)
			(xy 340.340247 -231.384603) (xy 340.391542 -231.392728) (xy 340.440935 -231.408776) (xy 340.487209 -231.432354)
			(xy 340.529225 -231.46288) (xy 340.565948 -231.499603) (xy 340.596474 -231.541619) (xy 340.620052 -231.587893)
			(xy 340.6361 -231.637286) (xy 340.644225 -231.688581) (xy 340.644734 -231.714548) (xy 340.644225 -231.740515)
			(xy 340.924135 -231.740515) (xy 340.924135 -231.688581) (xy 340.93226 -231.637286) (xy 340.948308 -231.587893)
			(xy 340.971886 -231.541619) (xy 341.002412 -231.499603) (xy 341.039135 -231.46288) (xy 341.081151 -231.432354)
			(xy 341.127425 -231.408776) (xy 341.176818 -231.392728) (xy 341.228113 -231.384603) (xy 341.280047 -231.384603)
			(xy 341.331342 -231.392728) (xy 341.380735 -231.408776) (xy 341.427009 -231.432354) (xy 341.469025 -231.46288)
			(xy 341.505748 -231.499603) (xy 341.536274 -231.541619) (xy 341.559852 -231.587893) (xy 341.5759 -231.637286)
			(xy 341.584025 -231.688581) (xy 341.584534 -231.714548) (xy 341.584025 -231.740515) (xy 341.864189 -231.740515)
			(xy 341.864189 -231.688581) (xy 341.872314 -231.637286) (xy 341.888362 -231.587893) (xy 341.91194 -231.541619)
			(xy 341.942466 -231.499603) (xy 341.979189 -231.46288) (xy 342.021205 -231.432354) (xy 342.067479 -231.408776)
			(xy 342.116872 -231.392728) (xy 342.168167 -231.384603) (xy 342.220101 -231.384603) (xy 342.271396 -231.392728)
			(xy 342.320789 -231.408776) (xy 342.367063 -231.432354) (xy 342.409079 -231.46288) (xy 342.445802 -231.499603)
			(xy 342.476328 -231.541619) (xy 342.499906 -231.587893) (xy 342.515954 -231.637286) (xy 342.524079 -231.688581)
			(xy 342.524588 -231.714548) (xy 342.524079 -231.740515) (xy 342.803735 -231.740515) (xy 342.803735 -231.688581)
			(xy 342.81186 -231.637286) (xy 342.827908 -231.587893) (xy 342.851486 -231.541619) (xy 342.882012 -231.499603)
			(xy 342.918735 -231.46288) (xy 342.960751 -231.432354) (xy 343.007025 -231.408776) (xy 343.056418 -231.392728)
			(xy 343.107713 -231.384603) (xy 343.159647 -231.384603) (xy 343.210942 -231.392728) (xy 343.260335 -231.408776)
			(xy 343.306609 -231.432354) (xy 343.348625 -231.46288) (xy 343.385348 -231.499603) (xy 343.415874 -231.541619)
			(xy 343.439452 -231.587893) (xy 343.4555 -231.637286) (xy 343.463625 -231.688581) (xy 343.464134 -231.714548)
			(xy 343.463625 -231.740515) (xy 343.743535 -231.740515) (xy 343.743535 -231.688581) (xy 343.75166 -231.637286)
			(xy 343.767708 -231.587893) (xy 343.791286 -231.541619) (xy 343.821812 -231.499603) (xy 343.858535 -231.46288)
			(xy 343.900551 -231.432354) (xy 343.946825 -231.408776) (xy 343.996218 -231.392728) (xy 344.047513 -231.384603)
			(xy 344.099447 -231.384603) (xy 344.150742 -231.392728) (xy 344.200135 -231.408776) (xy 344.246409 -231.432354)
			(xy 344.288425 -231.46288) (xy 344.325148 -231.499603) (xy 344.355674 -231.541619) (xy 344.379252 -231.587893)
			(xy 344.3953 -231.637286) (xy 344.403425 -231.688581) (xy 344.403934 -231.714548) (xy 344.403425 -231.740515)
			(xy 344.683335 -231.740515) (xy 344.683335 -231.688581) (xy 344.69146 -231.637286) (xy 344.707508 -231.587893)
			(xy 344.731086 -231.541619) (xy 344.761612 -231.499603) (xy 344.798335 -231.46288) (xy 344.840351 -231.432354)
			(xy 344.886625 -231.408776) (xy 344.936018 -231.392728) (xy 344.987313 -231.384603) (xy 345.039247 -231.384603)
			(xy 345.090542 -231.392728) (xy 345.139935 -231.408776) (xy 345.186209 -231.432354) (xy 345.228225 -231.46288)
			(xy 345.264948 -231.499603) (xy 345.295474 -231.541619) (xy 345.319052 -231.587893) (xy 345.3351 -231.637286)
			(xy 345.343225 -231.688581) (xy 345.343734 -231.714548) (xy 345.343225 -231.740515) (xy 345.623135 -231.740515)
			(xy 345.623135 -231.688581) (xy 345.63126 -231.637286) (xy 345.647308 -231.587893) (xy 345.670886 -231.541619)
			(xy 345.701412 -231.499603) (xy 345.738135 -231.46288) (xy 345.780151 -231.432354) (xy 345.826425 -231.408776)
			(xy 345.875818 -231.392728) (xy 345.927113 -231.384603) (xy 345.979047 -231.384603) (xy 346.030342 -231.392728)
			(xy 346.079735 -231.408776) (xy 346.126009 -231.432354) (xy 346.168025 -231.46288) (xy 346.204748 -231.499603)
			(xy 346.235274 -231.541619) (xy 346.258852 -231.587893) (xy 346.2749 -231.637286) (xy 346.283025 -231.688581)
			(xy 346.283534 -231.714548) (xy 346.283025 -231.740515) (xy 346.562935 -231.740515) (xy 346.562935 -231.688581)
			(xy 346.57106 -231.637286) (xy 346.587108 -231.587893) (xy 346.610686 -231.541619) (xy 346.641212 -231.499603)
			(xy 346.677935 -231.46288) (xy 346.719951 -231.432354) (xy 346.766225 -231.408776) (xy 346.815618 -231.392728)
			(xy 346.866913 -231.384603) (xy 346.918847 -231.384603) (xy 346.970142 -231.392728) (xy 347.019535 -231.408776)
			(xy 347.065809 -231.432354) (xy 347.107825 -231.46288) (xy 347.144548 -231.499603) (xy 347.175074 -231.541619)
			(xy 347.198652 -231.587893) (xy 347.2147 -231.637286) (xy 347.222825 -231.688581) (xy 347.223334 -231.714548)
			(xy 347.222825 -231.740515) (xy 347.502735 -231.740515) (xy 347.502735 -231.688581) (xy 347.51086 -231.637286)
			(xy 347.526908 -231.587893) (xy 347.550486 -231.541619) (xy 347.581012 -231.499603) (xy 347.617735 -231.46288)
			(xy 347.659751 -231.432354) (xy 347.706025 -231.408776) (xy 347.755418 -231.392728) (xy 347.806713 -231.384603)
			(xy 347.858647 -231.384603) (xy 347.909942 -231.392728) (xy 347.959335 -231.408776) (xy 348.005609 -231.432354)
			(xy 348.047625 -231.46288) (xy 348.084348 -231.499603) (xy 348.114874 -231.541619) (xy 348.138452 -231.587893)
			(xy 348.1545 -231.637286) (xy 348.162625 -231.688581) (xy 348.163134 -231.714548) (xy 348.162625 -231.740515)
			(xy 348.442789 -231.740515) (xy 348.442789 -231.688581) (xy 348.450914 -231.637286) (xy 348.466962 -231.587893)
			(xy 348.49054 -231.541619) (xy 348.521066 -231.499603) (xy 348.557789 -231.46288) (xy 348.599805 -231.432354)
			(xy 348.646079 -231.408776) (xy 348.695472 -231.392728) (xy 348.746767 -231.384603) (xy 348.798701 -231.384603)
			(xy 348.849996 -231.392728) (xy 348.899389 -231.408776) (xy 348.945663 -231.432354) (xy 348.987679 -231.46288)
			(xy 349.024402 -231.499603) (xy 349.054928 -231.541619) (xy 349.078506 -231.587893) (xy 349.094554 -231.637286)
			(xy 349.102679 -231.688581) (xy 349.103188 -231.714548) (xy 349.102679 -231.740515) (xy 349.094554 -231.79181)
			(xy 349.078506 -231.841203) (xy 349.054928 -231.887477) (xy 349.024402 -231.929493) (xy 348.987679 -231.966216)
			(xy 348.945663 -231.996742) (xy 348.899389 -232.02032) (xy 348.849996 -232.036368) (xy 348.798701 -232.044493)
			(xy 348.746767 -232.044493) (xy 348.695472 -232.036368) (xy 348.646079 -232.02032) (xy 348.599805 -231.996742)
			(xy 348.557789 -231.966216) (xy 348.521066 -231.929493) (xy 348.49054 -231.887477) (xy 348.466962 -231.841203)
			(xy 348.450914 -231.79181) (xy 348.442789 -231.740515) (xy 348.162625 -231.740515) (xy 348.1545 -231.79181)
			(xy 348.138452 -231.841203) (xy 348.114874 -231.887477) (xy 348.084348 -231.929493) (xy 348.047625 -231.966216)
			(xy 348.005609 -231.996742) (xy 347.959335 -232.02032) (xy 347.909942 -232.036368) (xy 347.858647 -232.044493)
			(xy 347.806713 -232.044493) (xy 347.755418 -232.036368) (xy 347.706025 -232.02032) (xy 347.659751 -231.996742)
			(xy 347.617735 -231.966216) (xy 347.581012 -231.929493) (xy 347.550486 -231.887477) (xy 347.526908 -231.841203)
			(xy 347.51086 -231.79181) (xy 347.502735 -231.740515) (xy 347.222825 -231.740515) (xy 347.2147 -231.79181)
			(xy 347.198652 -231.841203) (xy 347.175074 -231.887477) (xy 347.144548 -231.929493) (xy 347.107825 -231.966216)
			(xy 347.065809 -231.996742) (xy 347.019535 -232.02032) (xy 346.970142 -232.036368) (xy 346.918847 -232.044493)
			(xy 346.866913 -232.044493) (xy 346.815618 -232.036368) (xy 346.766225 -232.02032) (xy 346.719951 -231.996742)
			(xy 346.677935 -231.966216) (xy 346.641212 -231.929493) (xy 346.610686 -231.887477) (xy 346.587108 -231.841203)
			(xy 346.57106 -231.79181) (xy 346.562935 -231.740515) (xy 346.283025 -231.740515) (xy 346.2749 -231.79181)
			(xy 346.258852 -231.841203) (xy 346.235274 -231.887477) (xy 346.204748 -231.929493) (xy 346.168025 -231.966216)
			(xy 346.126009 -231.996742) (xy 346.079735 -232.02032) (xy 346.030342 -232.036368) (xy 345.979047 -232.044493)
			(xy 345.927113 -232.044493) (xy 345.875818 -232.036368) (xy 345.826425 -232.02032) (xy 345.780151 -231.996742)
			(xy 345.738135 -231.966216) (xy 345.701412 -231.929493) (xy 345.670886 -231.887477) (xy 345.647308 -231.841203)
			(xy 345.63126 -231.79181) (xy 345.623135 -231.740515) (xy 345.343225 -231.740515) (xy 345.3351 -231.79181)
			(xy 345.319052 -231.841203) (xy 345.295474 -231.887477) (xy 345.264948 -231.929493) (xy 345.228225 -231.966216)
			(xy 345.186209 -231.996742) (xy 345.139935 -232.02032) (xy 345.090542 -232.036368) (xy 345.039247 -232.044493)
			(xy 344.987313 -232.044493) (xy 344.936018 -232.036368) (xy 344.886625 -232.02032) (xy 344.840351 -231.996742)
			(xy 344.798335 -231.966216) (xy 344.761612 -231.929493) (xy 344.731086 -231.887477) (xy 344.707508 -231.841203)
			(xy 344.69146 -231.79181) (xy 344.683335 -231.740515) (xy 344.403425 -231.740515) (xy 344.3953 -231.79181)
			(xy 344.379252 -231.841203) (xy 344.355674 -231.887477) (xy 344.325148 -231.929493) (xy 344.288425 -231.966216)
			(xy 344.246409 -231.996742) (xy 344.200135 -232.02032) (xy 344.150742 -232.036368) (xy 344.099447 -232.044493)
			(xy 344.047513 -232.044493) (xy 343.996218 -232.036368) (xy 343.946825 -232.02032) (xy 343.900551 -231.996742)
			(xy 343.858535 -231.966216) (xy 343.821812 -231.929493) (xy 343.791286 -231.887477) (xy 343.767708 -231.841203)
			(xy 343.75166 -231.79181) (xy 343.743535 -231.740515) (xy 343.463625 -231.740515) (xy 343.4555 -231.79181)
			(xy 343.439452 -231.841203) (xy 343.415874 -231.887477) (xy 343.385348 -231.929493) (xy 343.348625 -231.966216)
			(xy 343.306609 -231.996742) (xy 343.260335 -232.02032) (xy 343.210942 -232.036368) (xy 343.159647 -232.044493)
			(xy 343.107713 -232.044493) (xy 343.056418 -232.036368) (xy 343.007025 -232.02032) (xy 342.960751 -231.996742)
			(xy 342.918735 -231.966216) (xy 342.882012 -231.929493) (xy 342.851486 -231.887477) (xy 342.827908 -231.841203)
			(xy 342.81186 -231.79181) (xy 342.803735 -231.740515) (xy 342.524079 -231.740515) (xy 342.515954 -231.79181)
			(xy 342.499906 -231.841203) (xy 342.476328 -231.887477) (xy 342.445802 -231.929493) (xy 342.409079 -231.966216)
			(xy 342.367063 -231.996742) (xy 342.320789 -232.02032) (xy 342.271396 -232.036368) (xy 342.220101 -232.044493)
			(xy 342.168167 -232.044493) (xy 342.116872 -232.036368) (xy 342.067479 -232.02032) (xy 342.021205 -231.996742)
			(xy 341.979189 -231.966216) (xy 341.942466 -231.929493) (xy 341.91194 -231.887477) (xy 341.888362 -231.841203)
			(xy 341.872314 -231.79181) (xy 341.864189 -231.740515) (xy 341.584025 -231.740515) (xy 341.5759 -231.79181)
			(xy 341.559852 -231.841203) (xy 341.536274 -231.887477) (xy 341.505748 -231.929493) (xy 341.469025 -231.966216)
			(xy 341.427009 -231.996742) (xy 341.380735 -232.02032) (xy 341.331342 -232.036368) (xy 341.280047 -232.044493)
			(xy 341.228113 -232.044493) (xy 341.176818 -232.036368) (xy 341.127425 -232.02032) (xy 341.081151 -231.996742)
			(xy 341.039135 -231.966216) (xy 341.002412 -231.929493) (xy 340.971886 -231.887477) (xy 340.948308 -231.841203)
			(xy 340.93226 -231.79181) (xy 340.924135 -231.740515) (xy 340.644225 -231.740515) (xy 340.6361 -231.79181)
			(xy 340.620052 -231.841203) (xy 340.596474 -231.887477) (xy 340.565948 -231.929493) (xy 340.529225 -231.966216)
			(xy 340.487209 -231.996742) (xy 340.440935 -232.02032) (xy 340.391542 -232.036368) (xy 340.340247 -232.044493)
			(xy 340.288313 -232.044493) (xy 340.237018 -232.036368) (xy 340.187625 -232.02032) (xy 340.141351 -231.996742)
			(xy 340.099335 -231.966216) (xy 340.062612 -231.929493) (xy 340.032086 -231.887477) (xy 340.008508 -231.841203)
			(xy 339.99246 -231.79181) (xy 339.984335 -231.740515) (xy 339.704741 -231.740515) (xy 339.704741 -231.741068)
			(xy 339.696256 -231.79348) (xy 339.679508 -231.843863) (xy 339.654927 -231.890925) (xy 339.623144 -231.933455)
			(xy 339.584975 -231.970362) (xy 339.541401 -232.000698) (xy 339.517736 -232.012744) (xy 339.505036 -232.01884)
			(xy 339.475064 -232.064306) (xy 339.475064 -232.191814) (xy 339.475525 -232.200994) (xy 339.482179 -232.218113)
			(xy 339.494497 -232.231735) (xy 339.502496 -232.236264) (xy 339.583014 -232.275126) (xy 339.591553 -232.278375)
			(xy 339.60979 -232.27916) (xy 339.618574 -232.27665) (xy 339.637624 -232.270046) (xy 339.643974 -232.26522)
			(xy 339.665723 -232.249342) (xy 339.713293 -232.224113) (xy 339.764319 -232.20692) (xy 339.817457 -232.198215)
			(xy 339.84438 -232.197656) (xy 339.870373 -232.198138) (xy 339.92172 -232.206267) (xy 339.971162 -232.22233)
			(xy 340.017483 -232.245929) (xy 340.059542 -232.276484) (xy 340.096303 -232.313243) (xy 340.126861 -232.3553)
			(xy 340.150463 -232.401619) (xy 340.166528 -232.451061) (xy 340.174661 -232.502407) (xy 340.174661 -232.554331)
			(xy 340.454489 -232.554331) (xy 340.454489 -232.502397) (xy 340.462614 -232.451102) (xy 340.478662 -232.401709)
			(xy 340.50224 -232.355435) (xy 340.532766 -232.313419) (xy 340.569489 -232.276696) (xy 340.611505 -232.24617)
			(xy 340.657779 -232.222592) (xy 340.707172 -232.206544) (xy 340.758467 -232.198419) (xy 340.810401 -232.198419)
			(xy 340.861696 -232.206544) (xy 340.911089 -232.222592) (xy 340.957363 -232.24617) (xy 340.999379 -232.276696)
			(xy 341.036102 -232.313419) (xy 341.066628 -232.355435) (xy 341.090206 -232.401709) (xy 341.106254 -232.451102)
			(xy 341.114379 -232.502397) (xy 341.114888 -232.528364) (xy 341.114379 -232.554331) (xy 341.394289 -232.554331)
			(xy 341.394289 -232.502397) (xy 341.402414 -232.451102) (xy 341.418462 -232.401709) (xy 341.44204 -232.355435)
			(xy 341.472566 -232.313419) (xy 341.509289 -232.276696) (xy 341.551305 -232.24617) (xy 341.597579 -232.222592)
			(xy 341.646972 -232.206544) (xy 341.698267 -232.198419) (xy 341.750201 -232.198419) (xy 341.801496 -232.206544)
			(xy 341.850889 -232.222592) (xy 341.897163 -232.24617) (xy 341.939179 -232.276696) (xy 341.975902 -232.313419)
			(xy 342.006428 -232.355435) (xy 342.030006 -232.401709) (xy 342.046054 -232.451102) (xy 342.054179 -232.502397)
			(xy 342.054688 -232.528364) (xy 342.054179 -232.554331) (xy 342.334089 -232.554331) (xy 342.334089 -232.502397)
			(xy 342.342214 -232.451102) (xy 342.358262 -232.401709) (xy 342.38184 -232.355435) (xy 342.412366 -232.313419)
			(xy 342.449089 -232.276696) (xy 342.491105 -232.24617) (xy 342.537379 -232.222592) (xy 342.586772 -232.206544)
			(xy 342.638067 -232.198419) (xy 342.690001 -232.198419) (xy 342.741296 -232.206544) (xy 342.790689 -232.222592)
			(xy 342.836963 -232.24617) (xy 342.878979 -232.276696) (xy 342.915702 -232.313419) (xy 342.946228 -232.355435)
			(xy 342.969806 -232.401709) (xy 342.985854 -232.451102) (xy 342.993979 -232.502397) (xy 342.994488 -232.528364)
			(xy 342.993979 -232.554331) (xy 343.273889 -232.554331) (xy 343.273889 -232.502397) (xy 343.282014 -232.451102)
			(xy 343.298062 -232.401709) (xy 343.32164 -232.355435) (xy 343.352166 -232.313419) (xy 343.388889 -232.276696)
			(xy 343.430905 -232.24617) (xy 343.477179 -232.222592) (xy 343.526572 -232.206544) (xy 343.577867 -232.198419)
			(xy 343.629801 -232.198419) (xy 343.681096 -232.206544) (xy 343.730489 -232.222592) (xy 343.776763 -232.24617)
			(xy 343.818779 -232.276696) (xy 343.855502 -232.313419) (xy 343.886028 -232.355435) (xy 343.909606 -232.401709)
			(xy 343.925654 -232.451102) (xy 343.933779 -232.502397) (xy 343.934288 -232.528364) (xy 343.933779 -232.554331)
			(xy 344.213689 -232.554331) (xy 344.213689 -232.502397) (xy 344.221814 -232.451102) (xy 344.237862 -232.401709)
			(xy 344.26144 -232.355435) (xy 344.291966 -232.313419) (xy 344.328689 -232.276696) (xy 344.370705 -232.24617)
			(xy 344.416979 -232.222592) (xy 344.466372 -232.206544) (xy 344.517667 -232.198419) (xy 344.569601 -232.198419)
			(xy 344.620896 -232.206544) (xy 344.670289 -232.222592) (xy 344.716563 -232.24617) (xy 344.758579 -232.276696)
			(xy 344.795302 -232.313419) (xy 344.825828 -232.355435) (xy 344.849406 -232.401709) (xy 344.865454 -232.451102)
			(xy 344.873579 -232.502397) (xy 344.874088 -232.528364) (xy 344.873579 -232.554331) (xy 345.153489 -232.554331)
			(xy 345.153489 -232.502397) (xy 345.161614 -232.451102) (xy 345.177662 -232.401709) (xy 345.20124 -232.355435)
			(xy 345.231766 -232.313419) (xy 345.268489 -232.276696) (xy 345.310505 -232.24617) (xy 345.356779 -232.222592)
			(xy 345.406172 -232.206544) (xy 345.457467 -232.198419) (xy 345.509401 -232.198419) (xy 345.560696 -232.206544)
			(xy 345.610089 -232.222592) (xy 345.656363 -232.24617) (xy 345.698379 -232.276696) (xy 345.735102 -232.313419)
			(xy 345.765628 -232.355435) (xy 345.789206 -232.401709) (xy 345.805254 -232.451102) (xy 345.813379 -232.502397)
			(xy 345.813888 -232.528364) (xy 345.813379 -232.554331) (xy 346.093035 -232.554331) (xy 346.093035 -232.502397)
			(xy 346.10116 -232.451102) (xy 346.117208 -232.401709) (xy 346.140786 -232.355435) (xy 346.171312 -232.313419)
			(xy 346.208035 -232.276696) (xy 346.250051 -232.24617) (xy 346.296325 -232.222592) (xy 346.345718 -232.206544)
			(xy 346.397013 -232.198419) (xy 346.448947 -232.198419) (xy 346.500242 -232.206544) (xy 346.549635 -232.222592)
			(xy 346.595909 -232.24617) (xy 346.637925 -232.276696) (xy 346.674648 -232.313419) (xy 346.705174 -232.355435)
			(xy 346.728752 -232.401709) (xy 346.7448 -232.451102) (xy 346.752925 -232.502397) (xy 346.753434 -232.528364)
			(xy 346.752925 -232.554331) (xy 347.033089 -232.554331) (xy 347.033089 -232.502397) (xy 347.041214 -232.451102)
			(xy 347.057262 -232.401709) (xy 347.08084 -232.355435) (xy 347.111366 -232.313419) (xy 347.148089 -232.276696)
			(xy 347.190105 -232.24617) (xy 347.236379 -232.222592) (xy 347.285772 -232.206544) (xy 347.337067 -232.198419)
			(xy 347.389001 -232.198419) (xy 347.440296 -232.206544) (xy 347.489689 -232.222592) (xy 347.535963 -232.24617)
			(xy 347.577979 -232.276696) (xy 347.614702 -232.313419) (xy 347.645228 -232.355435) (xy 347.668806 -232.401709)
			(xy 347.684854 -232.451102) (xy 347.692979 -232.502397) (xy 347.693488 -232.528364) (xy 347.692979 -232.554331)
			(xy 347.972889 -232.554331) (xy 347.972889 -232.502397) (xy 347.981014 -232.451102) (xy 347.997062 -232.401709)
			(xy 348.02064 -232.355435) (xy 348.051166 -232.313419) (xy 348.087889 -232.276696) (xy 348.129905 -232.24617)
			(xy 348.176179 -232.222592) (xy 348.225572 -232.206544) (xy 348.276867 -232.198419) (xy 348.328801 -232.198419)
			(xy 348.380096 -232.206544) (xy 348.429489 -232.222592) (xy 348.475763 -232.24617) (xy 348.517779 -232.276696)
			(xy 348.554502 -232.313419) (xy 348.585028 -232.355435) (xy 348.608606 -232.401709) (xy 348.624654 -232.451102)
			(xy 348.632779 -232.502397) (xy 348.633288 -232.528364) (xy 348.632779 -232.554331) (xy 348.624654 -232.605626)
			(xy 348.608606 -232.655019) (xy 348.585028 -232.701293) (xy 348.554502 -232.743309) (xy 348.517779 -232.780032)
			(xy 348.475763 -232.810558) (xy 348.429489 -232.834136) (xy 348.380096 -232.850184) (xy 348.328801 -232.858309)
			(xy 348.276867 -232.858309) (xy 348.225572 -232.850184) (xy 348.176179 -232.834136) (xy 348.129905 -232.810558)
			(xy 348.087889 -232.780032) (xy 348.051166 -232.743309) (xy 348.02064 -232.701293) (xy 347.997062 -232.655019)
			(xy 347.981014 -232.605626) (xy 347.972889 -232.554331) (xy 347.692979 -232.554331) (xy 347.684854 -232.605626)
			(xy 347.668806 -232.655019) (xy 347.645228 -232.701293) (xy 347.614702 -232.743309) (xy 347.577979 -232.780032)
			(xy 347.535963 -232.810558) (xy 347.489689 -232.834136) (xy 347.440296 -232.850184) (xy 347.389001 -232.858309)
			(xy 347.337067 -232.858309) (xy 347.285772 -232.850184) (xy 347.236379 -232.834136) (xy 347.190105 -232.810558)
			(xy 347.148089 -232.780032) (xy 347.111366 -232.743309) (xy 347.08084 -232.701293) (xy 347.057262 -232.655019)
			(xy 347.041214 -232.605626) (xy 347.033089 -232.554331) (xy 346.752925 -232.554331) (xy 346.7448 -232.605626)
			(xy 346.728752 -232.655019) (xy 346.705174 -232.701293) (xy 346.674648 -232.743309) (xy 346.637925 -232.780032)
			(xy 346.595909 -232.810558) (xy 346.549635 -232.834136) (xy 346.500242 -232.850184) (xy 346.448947 -232.858309)
			(xy 346.397013 -232.858309) (xy 346.345718 -232.850184) (xy 346.296325 -232.834136) (xy 346.250051 -232.810558)
			(xy 346.208035 -232.780032) (xy 346.171312 -232.743309) (xy 346.140786 -232.701293) (xy 346.117208 -232.655019)
			(xy 346.10116 -232.605626) (xy 346.093035 -232.554331) (xy 345.813379 -232.554331) (xy 345.805254 -232.605626)
			(xy 345.789206 -232.655019) (xy 345.765628 -232.701293) (xy 345.735102 -232.743309) (xy 345.698379 -232.780032)
			(xy 345.656363 -232.810558) (xy 345.610089 -232.834136) (xy 345.560696 -232.850184) (xy 345.509401 -232.858309)
			(xy 345.457467 -232.858309) (xy 345.406172 -232.850184) (xy 345.356779 -232.834136) (xy 345.310505 -232.810558)
			(xy 345.268489 -232.780032) (xy 345.231766 -232.743309) (xy 345.20124 -232.701293) (xy 345.177662 -232.655019)
			(xy 345.161614 -232.605626) (xy 345.153489 -232.554331) (xy 344.873579 -232.554331) (xy 344.865454 -232.605626)
			(xy 344.849406 -232.655019) (xy 344.825828 -232.701293) (xy 344.795302 -232.743309) (xy 344.758579 -232.780032)
			(xy 344.716563 -232.810558) (xy 344.670289 -232.834136) (xy 344.620896 -232.850184) (xy 344.569601 -232.858309)
			(xy 344.517667 -232.858309) (xy 344.466372 -232.850184) (xy 344.416979 -232.834136) (xy 344.370705 -232.810558)
			(xy 344.328689 -232.780032) (xy 344.291966 -232.743309) (xy 344.26144 -232.701293) (xy 344.237862 -232.655019)
			(xy 344.221814 -232.605626) (xy 344.213689 -232.554331) (xy 343.933779 -232.554331) (xy 343.925654 -232.605626)
			(xy 343.909606 -232.655019) (xy 343.886028 -232.701293) (xy 343.855502 -232.743309) (xy 343.818779 -232.780032)
			(xy 343.776763 -232.810558) (xy 343.730489 -232.834136) (xy 343.681096 -232.850184) (xy 343.629801 -232.858309)
			(xy 343.577867 -232.858309) (xy 343.526572 -232.850184) (xy 343.477179 -232.834136) (xy 343.430905 -232.810558)
			(xy 343.388889 -232.780032) (xy 343.352166 -232.743309) (xy 343.32164 -232.701293) (xy 343.298062 -232.655019)
			(xy 343.282014 -232.605626) (xy 343.273889 -232.554331) (xy 342.993979 -232.554331) (xy 342.985854 -232.605626)
			(xy 342.969806 -232.655019) (xy 342.946228 -232.701293) (xy 342.915702 -232.743309) (xy 342.878979 -232.780032)
			(xy 342.836963 -232.810558) (xy 342.790689 -232.834136) (xy 342.741296 -232.850184) (xy 342.690001 -232.858309)
			(xy 342.638067 -232.858309) (xy 342.586772 -232.850184) (xy 342.537379 -232.834136) (xy 342.491105 -232.810558)
			(xy 342.449089 -232.780032) (xy 342.412366 -232.743309) (xy 342.38184 -232.701293) (xy 342.358262 -232.655019)
			(xy 342.342214 -232.605626) (xy 342.334089 -232.554331) (xy 342.054179 -232.554331) (xy 342.046054 -232.605626)
			(xy 342.030006 -232.655019) (xy 342.006428 -232.701293) (xy 341.975902 -232.743309) (xy 341.939179 -232.780032)
			(xy 341.897163 -232.810558) (xy 341.850889 -232.834136) (xy 341.801496 -232.850184) (xy 341.750201 -232.858309)
			(xy 341.698267 -232.858309) (xy 341.646972 -232.850184) (xy 341.597579 -232.834136) (xy 341.551305 -232.810558)
			(xy 341.509289 -232.780032) (xy 341.472566 -232.743309) (xy 341.44204 -232.701293) (xy 341.418462 -232.655019)
			(xy 341.402414 -232.605626) (xy 341.394289 -232.554331) (xy 341.114379 -232.554331) (xy 341.106254 -232.605626)
			(xy 341.090206 -232.655019) (xy 341.066628 -232.701293) (xy 341.036102 -232.743309) (xy 340.999379 -232.780032)
			(xy 340.957363 -232.810558) (xy 340.911089 -232.834136) (xy 340.861696 -232.850184) (xy 340.810401 -232.858309)
			(xy 340.758467 -232.858309) (xy 340.707172 -232.850184) (xy 340.657779 -232.834136) (xy 340.611505 -232.810558)
			(xy 340.569489 -232.780032) (xy 340.532766 -232.743309) (xy 340.50224 -232.701293) (xy 340.478662 -232.655019)
			(xy 340.462614 -232.605626) (xy 340.454489 -232.554331) (xy 340.174661 -232.554331) (xy 340.174661 -232.554393)
			(xy 340.166528 -232.605739) (xy 340.150463 -232.655181) (xy 340.126861 -232.7015) (xy 340.096303 -232.743557)
			(xy 340.059542 -232.780316) (xy 340.017483 -232.810871) (xy 339.971162 -232.83447) (xy 339.92172 -232.850533)
			(xy 339.870373 -232.858662) (xy 339.84438 -232.859072) (xy 339.817456 -232.858543) (xy 339.764318 -232.849825)
			(xy 339.713291 -232.832623) (xy 339.665721 -232.80739) (xy 339.643974 -232.791508) (xy 339.637624 -232.786682)
			(xy 339.618574 -232.780078) (xy 339.609788 -232.777584) (xy 339.591554 -232.778364) (xy 339.583014 -232.781602)
			(xy 339.502496 -232.820464) (xy 339.494484 -232.824976) (xy 339.482153 -232.838593) (xy 339.47553 -232.855729)
			(xy 339.475064 -232.864914) (xy 339.475064 -232.992422) (xy 339.505036 -233.037888) (xy 339.517736 -233.043984)
			(xy 339.541454 -233.055946) (xy 339.585059 -233.086275) (xy 339.623256 -233.123184) (xy 339.655064 -233.165723)
			(xy 339.679665 -233.212798) (xy 339.696426 -233.2632) (xy 339.704916 -233.315633) (xy 339.704917 -233.368147)
			(xy 339.984335 -233.368147) (xy 339.984335 -233.316213) (xy 339.99246 -233.264918) (xy 340.008508 -233.215525)
			(xy 340.032086 -233.169251) (xy 340.062612 -233.127235) (xy 340.099335 -233.090512) (xy 340.141351 -233.059986)
			(xy 340.187625 -233.036408) (xy 340.237018 -233.02036) (xy 340.288313 -233.012235) (xy 340.340247 -233.012235)
			(xy 340.391542 -233.02036) (xy 340.440935 -233.036408) (xy 340.487209 -233.059986) (xy 340.529225 -233.090512)
			(xy 340.565948 -233.127235) (xy 340.596474 -233.169251) (xy 340.620052 -233.215525) (xy 340.6361 -233.264918)
			(xy 340.644225 -233.316213) (xy 340.644734 -233.34218) (xy 340.644225 -233.368147) (xy 340.924135 -233.368147)
			(xy 340.924135 -233.316213) (xy 340.93226 -233.264918) (xy 340.948308 -233.215525) (xy 340.971886 -233.169251)
			(xy 341.002412 -233.127235) (xy 341.039135 -233.090512) (xy 341.081151 -233.059986) (xy 341.127425 -233.036408)
			(xy 341.176818 -233.02036) (xy 341.228113 -233.012235) (xy 341.280047 -233.012235) (xy 341.331342 -233.02036)
			(xy 341.380735 -233.036408) (xy 341.427009 -233.059986) (xy 341.469025 -233.090512) (xy 341.505748 -233.127235)
			(xy 341.536274 -233.169251) (xy 341.559852 -233.215525) (xy 341.5759 -233.264918) (xy 341.584025 -233.316213)
			(xy 341.584534 -233.34218) (xy 341.584025 -233.368147) (xy 341.863935 -233.368147) (xy 341.863935 -233.316213)
			(xy 341.87206 -233.264918) (xy 341.888108 -233.215525) (xy 341.911686 -233.169251) (xy 341.942212 -233.127235)
			(xy 341.978935 -233.090512) (xy 342.020951 -233.059986) (xy 342.067225 -233.036408) (xy 342.116618 -233.02036)
			(xy 342.167913 -233.012235) (xy 342.219847 -233.012235) (xy 342.271142 -233.02036) (xy 342.320535 -233.036408)
			(xy 342.366809 -233.059986) (xy 342.408825 -233.090512) (xy 342.445548 -233.127235) (xy 342.476074 -233.169251)
			(xy 342.499652 -233.215525) (xy 342.5157 -233.264918) (xy 342.523825 -233.316213) (xy 342.524334 -233.34218)
			(xy 342.523825 -233.368147) (xy 342.803735 -233.368147) (xy 342.803735 -233.316213) (xy 342.81186 -233.264918)
			(xy 342.827908 -233.215525) (xy 342.851486 -233.169251) (xy 342.882012 -233.127235) (xy 342.918735 -233.090512)
			(xy 342.960751 -233.059986) (xy 343.007025 -233.036408) (xy 343.056418 -233.02036) (xy 343.107713 -233.012235)
			(xy 343.159647 -233.012235) (xy 343.210942 -233.02036) (xy 343.260335 -233.036408) (xy 343.306609 -233.059986)
			(xy 343.348625 -233.090512) (xy 343.385348 -233.127235) (xy 343.415874 -233.169251) (xy 343.439452 -233.215525)
			(xy 343.4555 -233.264918) (xy 343.463625 -233.316213) (xy 343.464134 -233.34218) (xy 343.463625 -233.368147)
			(xy 343.743535 -233.368147) (xy 343.743535 -233.316213) (xy 343.75166 -233.264918) (xy 343.767708 -233.215525)
			(xy 343.791286 -233.169251) (xy 343.821812 -233.127235) (xy 343.858535 -233.090512) (xy 343.900551 -233.059986)
			(xy 343.946825 -233.036408) (xy 343.996218 -233.02036) (xy 344.047513 -233.012235) (xy 344.099447 -233.012235)
			(xy 344.150742 -233.02036) (xy 344.200135 -233.036408) (xy 344.246409 -233.059986) (xy 344.288425 -233.090512)
			(xy 344.325148 -233.127235) (xy 344.355674 -233.169251) (xy 344.379252 -233.215525) (xy 344.3953 -233.264918)
			(xy 344.403425 -233.316213) (xy 344.403934 -233.34218) (xy 344.403425 -233.368147) (xy 344.683335 -233.368147)
			(xy 344.683335 -233.316213) (xy 344.69146 -233.264918) (xy 344.707508 -233.215525) (xy 344.731086 -233.169251)
			(xy 344.761612 -233.127235) (xy 344.798335 -233.090512) (xy 344.840351 -233.059986) (xy 344.886625 -233.036408)
			(xy 344.936018 -233.02036) (xy 344.987313 -233.012235) (xy 345.039247 -233.012235) (xy 345.090542 -233.02036)
			(xy 345.139935 -233.036408) (xy 345.186209 -233.059986) (xy 345.228225 -233.090512) (xy 345.264948 -233.127235)
			(xy 345.295474 -233.169251) (xy 345.319052 -233.215525) (xy 345.3351 -233.264918) (xy 345.343225 -233.316213)
			(xy 345.343734 -233.34218) (xy 345.343225 -233.368147) (xy 345.623389 -233.368147) (xy 345.623389 -233.316213)
			(xy 345.631514 -233.264918) (xy 345.647562 -233.215525) (xy 345.67114 -233.169251) (xy 345.701666 -233.127235)
			(xy 345.738389 -233.090512) (xy 345.780405 -233.059986) (xy 345.826679 -233.036408) (xy 345.876072 -233.02036)
			(xy 345.927367 -233.012235) (xy 345.979301 -233.012235) (xy 346.030596 -233.02036) (xy 346.079989 -233.036408)
			(xy 346.126263 -233.059986) (xy 346.168279 -233.090512) (xy 346.205002 -233.127235) (xy 346.235528 -233.169251)
			(xy 346.259106 -233.215525) (xy 346.275154 -233.264918) (xy 346.283279 -233.316213) (xy 346.283788 -233.34218)
			(xy 346.283279 -233.368147) (xy 346.562935 -233.368147) (xy 346.562935 -233.316213) (xy 346.57106 -233.264918)
			(xy 346.587108 -233.215525) (xy 346.610686 -233.169251) (xy 346.641212 -233.127235) (xy 346.677935 -233.090512)
			(xy 346.719951 -233.059986) (xy 346.766225 -233.036408) (xy 346.815618 -233.02036) (xy 346.866913 -233.012235)
			(xy 346.918847 -233.012235) (xy 346.970142 -233.02036) (xy 347.019535 -233.036408) (xy 347.065809 -233.059986)
			(xy 347.107825 -233.090512) (xy 347.144548 -233.127235) (xy 347.175074 -233.169251) (xy 347.198652 -233.215525)
			(xy 347.2147 -233.264918) (xy 347.222825 -233.316213) (xy 347.223334 -233.34218) (xy 347.222825 -233.368147)
			(xy 347.502735 -233.368147) (xy 347.502735 -233.316213) (xy 347.51086 -233.264918) (xy 347.526908 -233.215525)
			(xy 347.550486 -233.169251) (xy 347.581012 -233.127235) (xy 347.617735 -233.090512) (xy 347.659751 -233.059986)
			(xy 347.706025 -233.036408) (xy 347.755418 -233.02036) (xy 347.806713 -233.012235) (xy 347.858647 -233.012235)
			(xy 347.909942 -233.02036) (xy 347.959335 -233.036408) (xy 348.005609 -233.059986) (xy 348.047625 -233.090512)
			(xy 348.084348 -233.127235) (xy 348.114874 -233.169251) (xy 348.138452 -233.215525) (xy 348.1545 -233.264918)
			(xy 348.162625 -233.316213) (xy 348.163134 -233.34218) (xy 348.162625 -233.368147) (xy 348.442535 -233.368147)
			(xy 348.442535 -233.316213) (xy 348.45066 -233.264918) (xy 348.466708 -233.215525) (xy 348.490286 -233.169251)
			(xy 348.520812 -233.127235) (xy 348.557535 -233.090512) (xy 348.599551 -233.059986) (xy 348.645825 -233.036408)
			(xy 348.695218 -233.02036) (xy 348.746513 -233.012235) (xy 348.798447 -233.012235) (xy 348.849742 -233.02036)
			(xy 348.899135 -233.036408) (xy 348.945409 -233.059986) (xy 348.987425 -233.090512) (xy 349.024148 -233.127235)
			(xy 349.054674 -233.169251) (xy 349.078252 -233.215525) (xy 349.0943 -233.264918) (xy 349.102425 -233.316213)
			(xy 349.102934 -233.34218) (xy 349.102425 -233.368147) (xy 349.0943 -233.419442) (xy 349.078252 -233.468835)
			(xy 349.054674 -233.515109) (xy 349.024148 -233.557125) (xy 348.987425 -233.593848) (xy 348.945409 -233.624374)
			(xy 348.899135 -233.647952) (xy 348.849742 -233.664) (xy 348.798447 -233.672125) (xy 348.746513 -233.672125)
			(xy 348.695218 -233.664) (xy 348.645825 -233.647952) (xy 348.599551 -233.624374) (xy 348.557535 -233.593848)
			(xy 348.520812 -233.557125) (xy 348.490286 -233.515109) (xy 348.466708 -233.468835) (xy 348.45066 -233.419442)
			(xy 348.442535 -233.368147) (xy 348.162625 -233.368147) (xy 348.1545 -233.419442) (xy 348.138452 -233.468835)
			(xy 348.114874 -233.515109) (xy 348.084348 -233.557125) (xy 348.047625 -233.593848) (xy 348.005609 -233.624374)
			(xy 347.959335 -233.647952) (xy 347.909942 -233.664) (xy 347.858647 -233.672125) (xy 347.806713 -233.672125)
			(xy 347.755418 -233.664) (xy 347.706025 -233.647952) (xy 347.659751 -233.624374) (xy 347.617735 -233.593848)
			(xy 347.581012 -233.557125) (xy 347.550486 -233.515109) (xy 347.526908 -233.468835) (xy 347.51086 -233.419442)
			(xy 347.502735 -233.368147) (xy 347.222825 -233.368147) (xy 347.2147 -233.419442) (xy 347.198652 -233.468835)
			(xy 347.175074 -233.515109) (xy 347.144548 -233.557125) (xy 347.107825 -233.593848) (xy 347.065809 -233.624374)
			(xy 347.019535 -233.647952) (xy 346.970142 -233.664) (xy 346.918847 -233.672125) (xy 346.866913 -233.672125)
			(xy 346.815618 -233.664) (xy 346.766225 -233.647952) (xy 346.719951 -233.624374) (xy 346.677935 -233.593848)
			(xy 346.641212 -233.557125) (xy 346.610686 -233.515109) (xy 346.587108 -233.468835) (xy 346.57106 -233.419442)
			(xy 346.562935 -233.368147) (xy 346.283279 -233.368147) (xy 346.275154 -233.419442) (xy 346.259106 -233.468835)
			(xy 346.235528 -233.515109) (xy 346.205002 -233.557125) (xy 346.168279 -233.593848) (xy 346.126263 -233.624374)
			(xy 346.079989 -233.647952) (xy 346.030596 -233.664) (xy 345.979301 -233.672125) (xy 345.927367 -233.672125)
			(xy 345.876072 -233.664) (xy 345.826679 -233.647952) (xy 345.780405 -233.624374) (xy 345.738389 -233.593848)
			(xy 345.701666 -233.557125) (xy 345.67114 -233.515109) (xy 345.647562 -233.468835) (xy 345.631514 -233.419442)
			(xy 345.623389 -233.368147) (xy 345.343225 -233.368147) (xy 345.3351 -233.419442) (xy 345.319052 -233.468835)
			(xy 345.295474 -233.515109) (xy 345.264948 -233.557125) (xy 345.228225 -233.593848) (xy 345.186209 -233.624374)
			(xy 345.139935 -233.647952) (xy 345.090542 -233.664) (xy 345.039247 -233.672125) (xy 344.987313 -233.672125)
			(xy 344.936018 -233.664) (xy 344.886625 -233.647952) (xy 344.840351 -233.624374) (xy 344.798335 -233.593848)
			(xy 344.761612 -233.557125) (xy 344.731086 -233.515109) (xy 344.707508 -233.468835) (xy 344.69146 -233.419442)
			(xy 344.683335 -233.368147) (xy 344.403425 -233.368147) (xy 344.3953 -233.419442) (xy 344.379252 -233.468835)
			(xy 344.355674 -233.515109) (xy 344.325148 -233.557125) (xy 344.288425 -233.593848) (xy 344.246409 -233.624374)
			(xy 344.200135 -233.647952) (xy 344.150742 -233.664) (xy 344.099447 -233.672125) (xy 344.047513 -233.672125)
			(xy 343.996218 -233.664) (xy 343.946825 -233.647952) (xy 343.900551 -233.624374) (xy 343.858535 -233.593848)
			(xy 343.821812 -233.557125) (xy 343.791286 -233.515109) (xy 343.767708 -233.468835) (xy 343.75166 -233.419442)
			(xy 343.743535 -233.368147) (xy 343.463625 -233.368147) (xy 343.4555 -233.419442) (xy 343.439452 -233.468835)
			(xy 343.415874 -233.515109) (xy 343.385348 -233.557125) (xy 343.348625 -233.593848) (xy 343.306609 -233.624374)
			(xy 343.260335 -233.647952) (xy 343.210942 -233.664) (xy 343.159647 -233.672125) (xy 343.107713 -233.672125)
			(xy 343.056418 -233.664) (xy 343.007025 -233.647952) (xy 342.960751 -233.624374) (xy 342.918735 -233.593848)
			(xy 342.882012 -233.557125) (xy 342.851486 -233.515109) (xy 342.827908 -233.468835) (xy 342.81186 -233.419442)
			(xy 342.803735 -233.368147) (xy 342.523825 -233.368147) (xy 342.5157 -233.419442) (xy 342.499652 -233.468835)
			(xy 342.476074 -233.515109) (xy 342.445548 -233.557125) (xy 342.408825 -233.593848) (xy 342.366809 -233.624374)
			(xy 342.320535 -233.647952) (xy 342.271142 -233.664) (xy 342.219847 -233.672125) (xy 342.167913 -233.672125)
			(xy 342.116618 -233.664) (xy 342.067225 -233.647952) (xy 342.020951 -233.624374) (xy 341.978935 -233.593848)
			(xy 341.942212 -233.557125) (xy 341.911686 -233.515109) (xy 341.888108 -233.468835) (xy 341.87206 -233.419442)
			(xy 341.863935 -233.368147) (xy 341.584025 -233.368147) (xy 341.5759 -233.419442) (xy 341.559852 -233.468835)
			(xy 341.536274 -233.515109) (xy 341.505748 -233.557125) (xy 341.469025 -233.593848) (xy 341.427009 -233.624374)
			(xy 341.380735 -233.647952) (xy 341.331342 -233.664) (xy 341.280047 -233.672125) (xy 341.228113 -233.672125)
			(xy 341.176818 -233.664) (xy 341.127425 -233.647952) (xy 341.081151 -233.624374) (xy 341.039135 -233.593848)
			(xy 341.002412 -233.557125) (xy 340.971886 -233.515109) (xy 340.948308 -233.468835) (xy 340.93226 -233.419442)
			(xy 340.924135 -233.368147) (xy 340.644225 -233.368147) (xy 340.6361 -233.419442) (xy 340.620052 -233.468835)
			(xy 340.596474 -233.515109) (xy 340.565948 -233.557125) (xy 340.529225 -233.593848) (xy 340.487209 -233.624374)
			(xy 340.440935 -233.647952) (xy 340.391542 -233.664) (xy 340.340247 -233.672125) (xy 340.288313 -233.672125)
			(xy 340.237018 -233.664) (xy 340.187625 -233.647952) (xy 340.141351 -233.624374) (xy 340.099335 -233.593848)
			(xy 340.062612 -233.557125) (xy 340.032086 -233.515109) (xy 340.008508 -233.468835) (xy 339.99246 -233.419442)
			(xy 339.984335 -233.368147) (xy 339.704917 -233.368147) (xy 339.704917 -233.368749) (xy 339.69643 -233.421183)
			(xy 339.679671 -233.471586) (xy 339.655073 -233.518663) (xy 339.623268 -233.561203) (xy 339.585072 -233.598114)
			(xy 339.541468 -233.628446) (xy 339.517736 -233.640376) (xy 339.505036 -233.646472) (xy 339.475064 -233.691938)
			(xy 339.475064 -233.819954) (xy 339.475477 -233.828853) (xy 339.48174 -233.845517) (xy 339.49337 -233.858996)
			(xy 339.500972 -233.863642) (xy 339.584284 -233.90352) (xy 339.5923 -233.906415) (xy 339.609314 -233.907203)
			(xy 339.617558 -233.905044) (xy 339.638132 -233.897678) (xy 339.64118 -233.895646) (xy 339.644736 -233.892852)
			(xy 339.666442 -233.877041) (xy 339.713902 -233.851919) (xy 339.764795 -233.834787) (xy 339.817785 -233.826093)
			(xy 339.844634 -233.825542) (xy 339.870615 -233.826054) (xy 339.921938 -233.834188) (xy 339.971356 -233.85025)
			(xy 340.017654 -233.873844) (xy 340.059691 -233.904389) (xy 340.096433 -233.941135) (xy 340.126974 -233.983175)
			(xy 340.150564 -234.029475) (xy 340.16662 -234.078895) (xy 340.174748 -234.130218) (xy 340.174748 -234.182182)
			(xy 340.174742 -234.182217) (xy 340.454489 -234.182217) (xy 340.454489 -234.130283) (xy 340.462614 -234.078988)
			(xy 340.478662 -234.029595) (xy 340.50224 -233.983321) (xy 340.532766 -233.941305) (xy 340.569489 -233.904582)
			(xy 340.611505 -233.874056) (xy 340.657779 -233.850478) (xy 340.707172 -233.83443) (xy 340.758467 -233.826305)
			(xy 340.810401 -233.826305) (xy 340.861696 -233.83443) (xy 340.911089 -233.850478) (xy 340.957363 -233.874056)
			(xy 340.999379 -233.904582) (xy 341.036102 -233.941305) (xy 341.066628 -233.983321) (xy 341.090206 -234.029595)
			(xy 341.106254 -234.078988) (xy 341.114379 -234.130283) (xy 341.114888 -234.15625) (xy 341.114379 -234.182217)
			(xy 341.394289 -234.182217) (xy 341.394289 -234.130283) (xy 341.402414 -234.078988) (xy 341.418462 -234.029595)
			(xy 341.44204 -233.983321) (xy 341.472566 -233.941305) (xy 341.509289 -233.904582) (xy 341.551305 -233.874056)
			(xy 341.597579 -233.850478) (xy 341.646972 -233.83443) (xy 341.698267 -233.826305) (xy 341.750201 -233.826305)
			(xy 341.801496 -233.83443) (xy 341.850889 -233.850478) (xy 341.897163 -233.874056) (xy 341.939179 -233.904582)
			(xy 341.975902 -233.941305) (xy 342.006428 -233.983321) (xy 342.030006 -234.029595) (xy 342.046054 -234.078988)
			(xy 342.054179 -234.130283) (xy 342.054688 -234.15625) (xy 342.054179 -234.182217) (xy 342.333835 -234.182217)
			(xy 342.333835 -234.130283) (xy 342.34196 -234.078988) (xy 342.358008 -234.029595) (xy 342.381586 -233.983321)
			(xy 342.412112 -233.941305) (xy 342.448835 -233.904582) (xy 342.490851 -233.874056) (xy 342.537125 -233.850478)
			(xy 342.586518 -233.83443) (xy 342.637813 -233.826305) (xy 342.689747 -233.826305) (xy 342.741042 -233.83443)
			(xy 342.790435 -233.850478) (xy 342.836709 -233.874056) (xy 342.878725 -233.904582) (xy 342.915448 -233.941305)
			(xy 342.945974 -233.983321) (xy 342.969552 -234.029595) (xy 342.9856 -234.078988) (xy 342.993725 -234.130283)
			(xy 342.994234 -234.15625) (xy 342.993725 -234.182217) (xy 343.273889 -234.182217) (xy 343.273889 -234.130283)
			(xy 343.282014 -234.078988) (xy 343.298062 -234.029595) (xy 343.32164 -233.983321) (xy 343.352166 -233.941305)
			(xy 343.388889 -233.904582) (xy 343.430905 -233.874056) (xy 343.477179 -233.850478) (xy 343.526572 -233.83443)
			(xy 343.577867 -233.826305) (xy 343.629801 -233.826305) (xy 343.681096 -233.83443) (xy 343.730489 -233.850478)
			(xy 343.776763 -233.874056) (xy 343.818779 -233.904582) (xy 343.855502 -233.941305) (xy 343.886028 -233.983321)
			(xy 343.909606 -234.029595) (xy 343.925654 -234.078988) (xy 343.933779 -234.130283) (xy 343.934288 -234.15625)
			(xy 343.933779 -234.182217) (xy 344.213689 -234.182217) (xy 344.213689 -234.130283) (xy 344.221814 -234.078988)
			(xy 344.237862 -234.029595) (xy 344.26144 -233.983321) (xy 344.291966 -233.941305) (xy 344.328689 -233.904582)
			(xy 344.370705 -233.874056) (xy 344.416979 -233.850478) (xy 344.466372 -233.83443) (xy 344.517667 -233.826305)
			(xy 344.569601 -233.826305) (xy 344.620896 -233.83443) (xy 344.670289 -233.850478) (xy 344.716563 -233.874056)
			(xy 344.758579 -233.904582) (xy 344.795302 -233.941305) (xy 344.825828 -233.983321) (xy 344.849406 -234.029595)
			(xy 344.865454 -234.078988) (xy 344.873579 -234.130283) (xy 344.874088 -234.15625) (xy 344.873579 -234.182217)
			(xy 345.153489 -234.182217) (xy 345.153489 -234.130283) (xy 345.161614 -234.078988) (xy 345.177662 -234.029595)
			(xy 345.20124 -233.983321) (xy 345.231766 -233.941305) (xy 345.268489 -233.904582) (xy 345.310505 -233.874056)
			(xy 345.356779 -233.850478) (xy 345.406172 -233.83443) (xy 345.457467 -233.826305) (xy 345.509401 -233.826305)
			(xy 345.560696 -233.83443) (xy 345.610089 -233.850478) (xy 345.656363 -233.874056) (xy 345.698379 -233.904582)
			(xy 345.735102 -233.941305) (xy 345.765628 -233.983321) (xy 345.789206 -234.029595) (xy 345.805254 -234.078988)
			(xy 345.813379 -234.130283) (xy 345.813888 -234.15625) (xy 345.813379 -234.182217) (xy 346.093289 -234.182217)
			(xy 346.093289 -234.130283) (xy 346.101414 -234.078988) (xy 346.117462 -234.029595) (xy 346.14104 -233.983321)
			(xy 346.171566 -233.941305) (xy 346.208289 -233.904582) (xy 346.250305 -233.874056) (xy 346.296579 -233.850478)
			(xy 346.345972 -233.83443) (xy 346.397267 -233.826305) (xy 346.449201 -233.826305) (xy 346.500496 -233.83443)
			(xy 346.549889 -233.850478) (xy 346.596163 -233.874056) (xy 346.638179 -233.904582) (xy 346.674902 -233.941305)
			(xy 346.705428 -233.983321) (xy 346.729006 -234.029595) (xy 346.745054 -234.078988) (xy 346.753179 -234.130283)
			(xy 346.753688 -234.15625) (xy 346.753179 -234.182217) (xy 347.033089 -234.182217) (xy 347.033089 -234.130283)
			(xy 347.041214 -234.078988) (xy 347.057262 -234.029595) (xy 347.08084 -233.983321) (xy 347.111366 -233.941305)
			(xy 347.148089 -233.904582) (xy 347.190105 -233.874056) (xy 347.236379 -233.850478) (xy 347.285772 -233.83443)
			(xy 347.337067 -233.826305) (xy 347.389001 -233.826305) (xy 347.440296 -233.83443) (xy 347.489689 -233.850478)
			(xy 347.535963 -233.874056) (xy 347.577979 -233.904582) (xy 347.614702 -233.941305) (xy 347.645228 -233.983321)
			(xy 347.668806 -234.029595) (xy 347.684854 -234.078988) (xy 347.692979 -234.130283) (xy 347.693488 -234.15625)
			(xy 347.692979 -234.182217) (xy 347.972889 -234.182217) (xy 347.972889 -234.130283) (xy 347.981014 -234.078988)
			(xy 347.997062 -234.029595) (xy 348.02064 -233.983321) (xy 348.051166 -233.941305) (xy 348.087889 -233.904582)
			(xy 348.129905 -233.874056) (xy 348.176179 -233.850478) (xy 348.225572 -233.83443) (xy 348.276867 -233.826305)
			(xy 348.328801 -233.826305) (xy 348.380096 -233.83443) (xy 348.429489 -233.850478) (xy 348.475763 -233.874056)
			(xy 348.517779 -233.904582) (xy 348.554502 -233.941305) (xy 348.585028 -233.983321) (xy 348.608606 -234.029595)
			(xy 348.624654 -234.078988) (xy 348.632779 -234.130283) (xy 348.633288 -234.15625) (xy 348.632779 -234.182217)
			(xy 348.624654 -234.233512) (xy 348.608606 -234.282905) (xy 348.585028 -234.329179) (xy 348.554502 -234.371195)
			(xy 348.517779 -234.407918) (xy 348.475763 -234.438444) (xy 348.429489 -234.462022) (xy 348.380096 -234.47807)
			(xy 348.328801 -234.486195) (xy 348.276867 -234.486195) (xy 348.225572 -234.47807) (xy 348.176179 -234.462022)
			(xy 348.129905 -234.438444) (xy 348.087889 -234.407918) (xy 348.051166 -234.371195) (xy 348.02064 -234.329179)
			(xy 347.997062 -234.282905) (xy 347.981014 -234.233512) (xy 347.972889 -234.182217) (xy 347.692979 -234.182217)
			(xy 347.684854 -234.233512) (xy 347.668806 -234.282905) (xy 347.645228 -234.329179) (xy 347.614702 -234.371195)
			(xy 347.577979 -234.407918) (xy 347.535963 -234.438444) (xy 347.489689 -234.462022) (xy 347.440296 -234.47807)
			(xy 347.389001 -234.486195) (xy 347.337067 -234.486195) (xy 347.285772 -234.47807) (xy 347.236379 -234.462022)
			(xy 347.190105 -234.438444) (xy 347.148089 -234.407918) (xy 347.111366 -234.371195) (xy 347.08084 -234.329179)
			(xy 347.057262 -234.282905) (xy 347.041214 -234.233512) (xy 347.033089 -234.182217) (xy 346.753179 -234.182217)
			(xy 346.745054 -234.233512) (xy 346.729006 -234.282905) (xy 346.705428 -234.329179) (xy 346.674902 -234.371195)
			(xy 346.638179 -234.407918) (xy 346.596163 -234.438444) (xy 346.549889 -234.462022) (xy 346.500496 -234.47807)
			(xy 346.449201 -234.486195) (xy 346.397267 -234.486195) (xy 346.345972 -234.47807) (xy 346.296579 -234.462022)
			(xy 346.250305 -234.438444) (xy 346.208289 -234.407918) (xy 346.171566 -234.371195) (xy 346.14104 -234.329179)
			(xy 346.117462 -234.282905) (xy 346.101414 -234.233512) (xy 346.093289 -234.182217) (xy 345.813379 -234.182217)
			(xy 345.805254 -234.233512) (xy 345.789206 -234.282905) (xy 345.765628 -234.329179) (xy 345.735102 -234.371195)
			(xy 345.698379 -234.407918) (xy 345.656363 -234.438444) (xy 345.610089 -234.462022) (xy 345.560696 -234.47807)
			(xy 345.509401 -234.486195) (xy 345.457467 -234.486195) (xy 345.406172 -234.47807) (xy 345.356779 -234.462022)
			(xy 345.310505 -234.438444) (xy 345.268489 -234.407918) (xy 345.231766 -234.371195) (xy 345.20124 -234.329179)
			(xy 345.177662 -234.282905) (xy 345.161614 -234.233512) (xy 345.153489 -234.182217) (xy 344.873579 -234.182217)
			(xy 344.865454 -234.233512) (xy 344.849406 -234.282905) (xy 344.825828 -234.329179) (xy 344.795302 -234.371195)
			(xy 344.758579 -234.407918) (xy 344.716563 -234.438444) (xy 344.670289 -234.462022) (xy 344.620896 -234.47807)
			(xy 344.569601 -234.486195) (xy 344.517667 -234.486195) (xy 344.466372 -234.47807) (xy 344.416979 -234.462022)
			(xy 344.370705 -234.438444) (xy 344.328689 -234.407918) (xy 344.291966 -234.371195) (xy 344.26144 -234.329179)
			(xy 344.237862 -234.282905) (xy 344.221814 -234.233512) (xy 344.213689 -234.182217) (xy 343.933779 -234.182217)
			(xy 343.925654 -234.233512) (xy 343.909606 -234.282905) (xy 343.886028 -234.329179) (xy 343.855502 -234.371195)
			(xy 343.818779 -234.407918) (xy 343.776763 -234.438444) (xy 343.730489 -234.462022) (xy 343.681096 -234.47807)
			(xy 343.629801 -234.486195) (xy 343.577867 -234.486195) (xy 343.526572 -234.47807) (xy 343.477179 -234.462022)
			(xy 343.430905 -234.438444) (xy 343.388889 -234.407918) (xy 343.352166 -234.371195) (xy 343.32164 -234.329179)
			(xy 343.298062 -234.282905) (xy 343.282014 -234.233512) (xy 343.273889 -234.182217) (xy 342.993725 -234.182217)
			(xy 342.9856 -234.233512) (xy 342.969552 -234.282905) (xy 342.945974 -234.329179) (xy 342.915448 -234.371195)
			(xy 342.878725 -234.407918) (xy 342.836709 -234.438444) (xy 342.790435 -234.462022) (xy 342.741042 -234.47807)
			(xy 342.689747 -234.486195) (xy 342.637813 -234.486195) (xy 342.586518 -234.47807) (xy 342.537125 -234.462022)
			(xy 342.490851 -234.438444) (xy 342.448835 -234.407918) (xy 342.412112 -234.371195) (xy 342.381586 -234.329179)
			(xy 342.358008 -234.282905) (xy 342.34196 -234.233512) (xy 342.333835 -234.182217) (xy 342.054179 -234.182217)
			(xy 342.046054 -234.233512) (xy 342.030006 -234.282905) (xy 342.006428 -234.329179) (xy 341.975902 -234.371195)
			(xy 341.939179 -234.407918) (xy 341.897163 -234.438444) (xy 341.850889 -234.462022) (xy 341.801496 -234.47807)
			(xy 341.750201 -234.486195) (xy 341.698267 -234.486195) (xy 341.646972 -234.47807) (xy 341.597579 -234.462022)
			(xy 341.551305 -234.438444) (xy 341.509289 -234.407918) (xy 341.472566 -234.371195) (xy 341.44204 -234.329179)
			(xy 341.418462 -234.282905) (xy 341.402414 -234.233512) (xy 341.394289 -234.182217) (xy 341.114379 -234.182217)
			(xy 341.106254 -234.233512) (xy 341.090206 -234.282905) (xy 341.066628 -234.329179) (xy 341.036102 -234.371195)
			(xy 340.999379 -234.407918) (xy 340.957363 -234.438444) (xy 340.911089 -234.462022) (xy 340.861696 -234.47807)
			(xy 340.810401 -234.486195) (xy 340.758467 -234.486195) (xy 340.707172 -234.47807) (xy 340.657779 -234.462022)
			(xy 340.611505 -234.438444) (xy 340.569489 -234.407918) (xy 340.532766 -234.371195) (xy 340.50224 -234.329179)
			(xy 340.478662 -234.282905) (xy 340.462614 -234.233512) (xy 340.454489 -234.182217) (xy 340.174742 -234.182217)
			(xy 340.16662 -234.233505) (xy 340.150564 -234.282925) (xy 340.126974 -234.329225) (xy 340.096433 -234.371265)
			(xy 340.059691 -234.408011) (xy 340.017654 -234.438556) (xy 339.971356 -234.46215) (xy 339.921938 -234.478212)
			(xy 339.870615 -234.486346) (xy 339.844634 -234.486958) (xy 339.817668 -234.486421) (xy 339.764452 -234.477663)
			(xy 339.71336 -234.46039) (xy 339.665747 -234.435059) (xy 339.643974 -234.41914) (xy 339.637878 -234.414568)
			(xy 339.619844 -234.408218) (xy 339.61112 -234.405538) (xy 339.59289 -234.405941) (xy 339.584284 -234.40898)
			(xy 339.500972 -234.448858) (xy 339.493326 -234.453456) (xy 339.481653 -234.466931) (xy 339.475415 -234.483632)
			(xy 339.475064 -234.492546) (xy 339.475064 -234.620308) (xy 339.505036 -234.665774) (xy 339.517736 -234.67187)
			(xy 339.541443 -234.683841) (xy 339.585027 -234.714185) (xy 339.623203 -234.751101) (xy 339.654993 -234.793641)
			(xy 339.679579 -234.840713) (xy 339.69633 -234.891109) (xy 339.704815 -234.943532) (xy 339.704818 -234.996033)
			(xy 339.984335 -234.996033) (xy 339.984335 -234.944099) (xy 339.99246 -234.892804) (xy 340.008508 -234.843411)
			(xy 340.032086 -234.797137) (xy 340.062612 -234.755121) (xy 340.099335 -234.718398) (xy 340.141351 -234.687872)
			(xy 340.187625 -234.664294) (xy 340.237018 -234.648246) (xy 340.288313 -234.640121) (xy 340.340247 -234.640121)
			(xy 340.391542 -234.648246) (xy 340.440935 -234.664294) (xy 340.487209 -234.687872) (xy 340.529225 -234.718398)
			(xy 340.565948 -234.755121) (xy 340.596474 -234.797137) (xy 340.620052 -234.843411) (xy 340.6361 -234.892804)
			(xy 340.644225 -234.944099) (xy 340.644734 -234.970066) (xy 340.644225 -234.996033) (xy 340.924135 -234.996033)
			(xy 340.924135 -234.944099) (xy 340.93226 -234.892804) (xy 340.948308 -234.843411) (xy 340.971886 -234.797137)
			(xy 341.002412 -234.755121) (xy 341.039135 -234.718398) (xy 341.081151 -234.687872) (xy 341.127425 -234.664294)
			(xy 341.176818 -234.648246) (xy 341.228113 -234.640121) (xy 341.280047 -234.640121) (xy 341.331342 -234.648246)
			(xy 341.380735 -234.664294) (xy 341.427009 -234.687872) (xy 341.469025 -234.718398) (xy 341.505748 -234.755121)
			(xy 341.536274 -234.797137) (xy 341.559852 -234.843411) (xy 341.5759 -234.892804) (xy 341.584025 -234.944099)
			(xy 341.584534 -234.970066) (xy 341.584025 -234.996033) (xy 341.863935 -234.996033) (xy 341.863935 -234.944099)
			(xy 341.87206 -234.892804) (xy 341.888108 -234.843411) (xy 341.911686 -234.797137) (xy 341.942212 -234.755121)
			(xy 341.978935 -234.718398) (xy 342.020951 -234.687872) (xy 342.067225 -234.664294) (xy 342.116618 -234.648246)
			(xy 342.167913 -234.640121) (xy 342.219847 -234.640121) (xy 342.271142 -234.648246) (xy 342.320535 -234.664294)
			(xy 342.366809 -234.687872) (xy 342.408825 -234.718398) (xy 342.445548 -234.755121) (xy 342.476074 -234.797137)
			(xy 342.499652 -234.843411) (xy 342.5157 -234.892804) (xy 342.523825 -234.944099) (xy 342.524334 -234.970066)
			(xy 342.523825 -234.996033) (xy 342.803735 -234.996033) (xy 342.803735 -234.944099) (xy 342.81186 -234.892804)
			(xy 342.827908 -234.843411) (xy 342.851486 -234.797137) (xy 342.882012 -234.755121) (xy 342.918735 -234.718398)
			(xy 342.960751 -234.687872) (xy 343.007025 -234.664294) (xy 343.056418 -234.648246) (xy 343.107713 -234.640121)
			(xy 343.159647 -234.640121) (xy 343.210942 -234.648246) (xy 343.260335 -234.664294) (xy 343.306609 -234.687872)
			(xy 343.348625 -234.718398) (xy 343.385348 -234.755121) (xy 343.415874 -234.797137) (xy 343.439452 -234.843411)
			(xy 343.4555 -234.892804) (xy 343.463625 -234.944099) (xy 343.464134 -234.970066) (xy 343.463625 -234.996033)
			(xy 343.743535 -234.996033) (xy 343.743535 -234.944099) (xy 343.75166 -234.892804) (xy 343.767708 -234.843411)
			(xy 343.791286 -234.797137) (xy 343.821812 -234.755121) (xy 343.858535 -234.718398) (xy 343.900551 -234.687872)
			(xy 343.946825 -234.664294) (xy 343.996218 -234.648246) (xy 344.047513 -234.640121) (xy 344.099447 -234.640121)
			(xy 344.150742 -234.648246) (xy 344.200135 -234.664294) (xy 344.246409 -234.687872) (xy 344.288425 -234.718398)
			(xy 344.325148 -234.755121) (xy 344.355674 -234.797137) (xy 344.379252 -234.843411) (xy 344.3953 -234.892804)
			(xy 344.403425 -234.944099) (xy 344.403934 -234.970066) (xy 344.403425 -234.996033) (xy 344.683589 -234.996033)
			(xy 344.683589 -234.944099) (xy 344.691714 -234.892804) (xy 344.707762 -234.843411) (xy 344.73134 -234.797137)
			(xy 344.761866 -234.755121) (xy 344.798589 -234.718398) (xy 344.840605 -234.687872) (xy 344.886879 -234.664294)
			(xy 344.936272 -234.648246) (xy 344.987567 -234.640121) (xy 345.039501 -234.640121) (xy 345.090796 -234.648246)
			(xy 345.140189 -234.664294) (xy 345.186463 -234.687872) (xy 345.228479 -234.718398) (xy 345.265202 -234.755121)
			(xy 345.295728 -234.797137) (xy 345.319306 -234.843411) (xy 345.335354 -234.892804) (xy 345.343479 -234.944099)
			(xy 345.343988 -234.970066) (xy 345.343479 -234.996033) (xy 345.623135 -234.996033) (xy 345.623135 -234.944099)
			(xy 345.63126 -234.892804) (xy 345.647308 -234.843411) (xy 345.670886 -234.797137) (xy 345.701412 -234.755121)
			(xy 345.738135 -234.718398) (xy 345.780151 -234.687872) (xy 345.826425 -234.664294) (xy 345.875818 -234.648246)
			(xy 345.927113 -234.640121) (xy 345.979047 -234.640121) (xy 346.030342 -234.648246) (xy 346.079735 -234.664294)
			(xy 346.126009 -234.687872) (xy 346.168025 -234.718398) (xy 346.204748 -234.755121) (xy 346.235274 -234.797137)
			(xy 346.258852 -234.843411) (xy 346.2749 -234.892804) (xy 346.283025 -234.944099) (xy 346.283534 -234.970066)
			(xy 346.283025 -234.996033) (xy 346.562935 -234.996033) (xy 346.562935 -234.944099) (xy 346.57106 -234.892804)
			(xy 346.587108 -234.843411) (xy 346.610686 -234.797137) (xy 346.641212 -234.755121) (xy 346.677935 -234.718398)
			(xy 346.719951 -234.687872) (xy 346.766225 -234.664294) (xy 346.815618 -234.648246) (xy 346.866913 -234.640121)
			(xy 346.918847 -234.640121) (xy 346.970142 -234.648246) (xy 347.019535 -234.664294) (xy 347.065809 -234.687872)
			(xy 347.107825 -234.718398) (xy 347.144548 -234.755121) (xy 347.175074 -234.797137) (xy 347.198652 -234.843411)
			(xy 347.2147 -234.892804) (xy 347.222825 -234.944099) (xy 347.223334 -234.970066) (xy 347.222825 -234.996033)
			(xy 347.502735 -234.996033) (xy 347.502735 -234.944099) (xy 347.51086 -234.892804) (xy 347.526908 -234.843411)
			(xy 347.550486 -234.797137) (xy 347.581012 -234.755121) (xy 347.617735 -234.718398) (xy 347.659751 -234.687872)
			(xy 347.706025 -234.664294) (xy 347.755418 -234.648246) (xy 347.806713 -234.640121) (xy 347.858647 -234.640121)
			(xy 347.909942 -234.648246) (xy 347.959335 -234.664294) (xy 348.005609 -234.687872) (xy 348.047625 -234.718398)
			(xy 348.084348 -234.755121) (xy 348.114874 -234.797137) (xy 348.138452 -234.843411) (xy 348.1545 -234.892804)
			(xy 348.162625 -234.944099) (xy 348.163134 -234.970066) (xy 348.162625 -234.996033) (xy 348.442535 -234.996033)
			(xy 348.442535 -234.944099) (xy 348.45066 -234.892804) (xy 348.466708 -234.843411) (xy 348.490286 -234.797137)
			(xy 348.520812 -234.755121) (xy 348.557535 -234.718398) (xy 348.599551 -234.687872) (xy 348.645825 -234.664294)
			(xy 348.695218 -234.648246) (xy 348.746513 -234.640121) (xy 348.798447 -234.640121) (xy 348.849742 -234.648246)
			(xy 348.899135 -234.664294) (xy 348.945409 -234.687872) (xy 348.987425 -234.718398) (xy 349.024148 -234.755121)
			(xy 349.054674 -234.797137) (xy 349.078252 -234.843411) (xy 349.0943 -234.892804) (xy 349.102425 -234.944099)
			(xy 349.102934 -234.970066) (xy 349.102425 -234.996033) (xy 349.0943 -235.047328) (xy 349.078252 -235.096721)
			(xy 349.054674 -235.142995) (xy 349.024148 -235.185011) (xy 348.987425 -235.221734) (xy 348.945409 -235.25226)
			(xy 348.899135 -235.275838) (xy 348.849742 -235.291886) (xy 348.798447 -235.300011) (xy 348.746513 -235.300011)
			(xy 348.695218 -235.291886) (xy 348.645825 -235.275838) (xy 348.599551 -235.25226) (xy 348.557535 -235.221734)
			(xy 348.520812 -235.185011) (xy 348.490286 -235.142995) (xy 348.466708 -235.096721) (xy 348.45066 -235.047328)
			(xy 348.442535 -234.996033) (xy 348.162625 -234.996033) (xy 348.1545 -235.047328) (xy 348.138452 -235.096721)
			(xy 348.114874 -235.142995) (xy 348.084348 -235.185011) (xy 348.047625 -235.221734) (xy 348.005609 -235.25226)
			(xy 347.959335 -235.275838) (xy 347.909942 -235.291886) (xy 347.858647 -235.300011) (xy 347.806713 -235.300011)
			(xy 347.755418 -235.291886) (xy 347.706025 -235.275838) (xy 347.659751 -235.25226) (xy 347.617735 -235.221734)
			(xy 347.581012 -235.185011) (xy 347.550486 -235.142995) (xy 347.526908 -235.096721) (xy 347.51086 -235.047328)
			(xy 347.502735 -234.996033) (xy 347.222825 -234.996033) (xy 347.2147 -235.047328) (xy 347.198652 -235.096721)
			(xy 347.175074 -235.142995) (xy 347.144548 -235.185011) (xy 347.107825 -235.221734) (xy 347.065809 -235.25226)
			(xy 347.019535 -235.275838) (xy 346.970142 -235.291886) (xy 346.918847 -235.300011) (xy 346.866913 -235.300011)
			(xy 346.815618 -235.291886) (xy 346.766225 -235.275838) (xy 346.719951 -235.25226) (xy 346.677935 -235.221734)
			(xy 346.641212 -235.185011) (xy 346.610686 -235.142995) (xy 346.587108 -235.096721) (xy 346.57106 -235.047328)
			(xy 346.562935 -234.996033) (xy 346.283025 -234.996033) (xy 346.2749 -235.047328) (xy 346.258852 -235.096721)
			(xy 346.235274 -235.142995) (xy 346.204748 -235.185011) (xy 346.168025 -235.221734) (xy 346.126009 -235.25226)
			(xy 346.079735 -235.275838) (xy 346.030342 -235.291886) (xy 345.979047 -235.300011) (xy 345.927113 -235.300011)
			(xy 345.875818 -235.291886) (xy 345.826425 -235.275838) (xy 345.780151 -235.25226) (xy 345.738135 -235.221734)
			(xy 345.701412 -235.185011) (xy 345.670886 -235.142995) (xy 345.647308 -235.096721) (xy 345.63126 -235.047328)
			(xy 345.623135 -234.996033) (xy 345.343479 -234.996033) (xy 345.335354 -235.047328) (xy 345.319306 -235.096721)
			(xy 345.295728 -235.142995) (xy 345.265202 -235.185011) (xy 345.228479 -235.221734) (xy 345.186463 -235.25226)
			(xy 345.140189 -235.275838) (xy 345.090796 -235.291886) (xy 345.039501 -235.300011) (xy 344.987567 -235.300011)
			(xy 344.936272 -235.291886) (xy 344.886879 -235.275838) (xy 344.840605 -235.25226) (xy 344.798589 -235.221734)
			(xy 344.761866 -235.185011) (xy 344.73134 -235.142995) (xy 344.707762 -235.096721) (xy 344.691714 -235.047328)
			(xy 344.683589 -234.996033) (xy 344.403425 -234.996033) (xy 344.3953 -235.047328) (xy 344.379252 -235.096721)
			(xy 344.355674 -235.142995) (xy 344.325148 -235.185011) (xy 344.288425 -235.221734) (xy 344.246409 -235.25226)
			(xy 344.200135 -235.275838) (xy 344.150742 -235.291886) (xy 344.099447 -235.300011) (xy 344.047513 -235.300011)
			(xy 343.996218 -235.291886) (xy 343.946825 -235.275838) (xy 343.900551 -235.25226) (xy 343.858535 -235.221734)
			(xy 343.821812 -235.185011) (xy 343.791286 -235.142995) (xy 343.767708 -235.096721) (xy 343.75166 -235.047328)
			(xy 343.743535 -234.996033) (xy 343.463625 -234.996033) (xy 343.4555 -235.047328) (xy 343.439452 -235.096721)
			(xy 343.415874 -235.142995) (xy 343.385348 -235.185011) (xy 343.348625 -235.221734) (xy 343.306609 -235.25226)
			(xy 343.260335 -235.275838) (xy 343.210942 -235.291886) (xy 343.159647 -235.300011) (xy 343.107713 -235.300011)
			(xy 343.056418 -235.291886) (xy 343.007025 -235.275838) (xy 342.960751 -235.25226) (xy 342.918735 -235.221734)
			(xy 342.882012 -235.185011) (xy 342.851486 -235.142995) (xy 342.827908 -235.096721) (xy 342.81186 -235.047328)
			(xy 342.803735 -234.996033) (xy 342.523825 -234.996033) (xy 342.5157 -235.047328) (xy 342.499652 -235.096721)
			(xy 342.476074 -235.142995) (xy 342.445548 -235.185011) (xy 342.408825 -235.221734) (xy 342.366809 -235.25226)
			(xy 342.320535 -235.275838) (xy 342.271142 -235.291886) (xy 342.219847 -235.300011) (xy 342.167913 -235.300011)
			(xy 342.116618 -235.291886) (xy 342.067225 -235.275838) (xy 342.020951 -235.25226) (xy 341.978935 -235.221734)
			(xy 341.942212 -235.185011) (xy 341.911686 -235.142995) (xy 341.888108 -235.096721) (xy 341.87206 -235.047328)
			(xy 341.863935 -234.996033) (xy 341.584025 -234.996033) (xy 341.5759 -235.047328) (xy 341.559852 -235.096721)
			(xy 341.536274 -235.142995) (xy 341.505748 -235.185011) (xy 341.469025 -235.221734) (xy 341.427009 -235.25226)
			(xy 341.380735 -235.275838) (xy 341.331342 -235.291886) (xy 341.280047 -235.300011) (xy 341.228113 -235.300011)
			(xy 341.176818 -235.291886) (xy 341.127425 -235.275838) (xy 341.081151 -235.25226) (xy 341.039135 -235.221734)
			(xy 341.002412 -235.185011) (xy 340.971886 -235.142995) (xy 340.948308 -235.096721) (xy 340.93226 -235.047328)
			(xy 340.924135 -234.996033) (xy 340.644225 -234.996033) (xy 340.6361 -235.047328) (xy 340.620052 -235.096721)
			(xy 340.596474 -235.142995) (xy 340.565948 -235.185011) (xy 340.529225 -235.221734) (xy 340.487209 -235.25226)
			(xy 340.440935 -235.275838) (xy 340.391542 -235.291886) (xy 340.340247 -235.300011) (xy 340.288313 -235.300011)
			(xy 340.237018 -235.291886) (xy 340.187625 -235.275838) (xy 340.141351 -235.25226) (xy 340.099335 -235.221734)
			(xy 340.062612 -235.185011) (xy 340.032086 -235.142995) (xy 340.008508 -235.096721) (xy 339.99246 -235.047328)
			(xy 339.984335 -234.996033) (xy 339.704818 -234.996033) (xy 339.704818 -234.996638) (xy 339.696337 -235.049063)
			(xy 339.67959 -235.099459) (xy 339.655009 -235.146534) (xy 339.623223 -235.189077) (xy 339.585049 -235.225996)
			(xy 339.541469 -235.256344) (xy 339.517736 -235.268262) (xy 339.505036 -235.274358) (xy 339.475064 -235.319824)
			(xy 339.475064 -235.447586) (xy 339.475482 -235.456482) (xy 339.481752 -235.473138) (xy 339.493384 -235.486607)
			(xy 339.500972 -235.491274) (xy 339.584284 -235.531152) (xy 339.5923 -235.53405) (xy 339.609314 -235.534839)
			(xy 339.617558 -235.532676) (xy 339.638132 -235.52531) (xy 339.64118 -235.523278) (xy 339.644736 -235.520484)
			(xy 339.666444 -235.504676) (xy 339.713905 -235.479559) (xy 339.764797 -235.46243) (xy 339.817786 -235.453739)
			(xy 339.844634 -235.453174) (xy 339.870621 -235.453686) (xy 339.921954 -235.461821) (xy 339.971383 -235.477886)
			(xy 340.01769 -235.501485) (xy 340.059736 -235.532037) (xy 340.096485 -235.56879) (xy 340.127033 -235.610839)
			(xy 340.150627 -235.657149) (xy 340.166687 -235.706579) (xy 340.174817 -235.757913) (xy 340.174817 -235.809849)
			(xy 340.454489 -235.809849) (xy 340.454489 -235.757915) (xy 340.462614 -235.70662) (xy 340.478662 -235.657227)
			(xy 340.50224 -235.610953) (xy 340.532766 -235.568937) (xy 340.569489 -235.532214) (xy 340.611505 -235.501688)
			(xy 340.657779 -235.47811) (xy 340.707172 -235.462062) (xy 340.758467 -235.453937) (xy 340.810401 -235.453937)
			(xy 340.861696 -235.462062) (xy 340.911089 -235.47811) (xy 340.957363 -235.501688) (xy 340.999379 -235.532214)
			(xy 341.036102 -235.568937) (xy 341.066628 -235.610953) (xy 341.090206 -235.657227) (xy 341.106254 -235.70662)
			(xy 341.114379 -235.757915) (xy 341.114888 -235.783882) (xy 341.114379 -235.809849) (xy 341.394289 -235.809849)
			(xy 341.394289 -235.757915) (xy 341.402414 -235.70662) (xy 341.418462 -235.657227) (xy 341.44204 -235.610953)
			(xy 341.472566 -235.568937) (xy 341.509289 -235.532214) (xy 341.551305 -235.501688) (xy 341.597579 -235.47811)
			(xy 341.646972 -235.462062) (xy 341.698267 -235.453937) (xy 341.750201 -235.453937) (xy 341.801496 -235.462062)
			(xy 341.850889 -235.47811) (xy 341.897163 -235.501688) (xy 341.939179 -235.532214) (xy 341.975902 -235.568937)
			(xy 342.006428 -235.610953) (xy 342.030006 -235.657227) (xy 342.046054 -235.70662) (xy 342.054179 -235.757915)
			(xy 342.054688 -235.783882) (xy 342.054179 -235.809849) (xy 342.334089 -235.809849) (xy 342.334089 -235.757915)
			(xy 342.342214 -235.70662) (xy 342.358262 -235.657227) (xy 342.38184 -235.610953) (xy 342.412366 -235.568937)
			(xy 342.449089 -235.532214) (xy 342.491105 -235.501688) (xy 342.537379 -235.47811) (xy 342.586772 -235.462062)
			(xy 342.638067 -235.453937) (xy 342.690001 -235.453937) (xy 342.741296 -235.462062) (xy 342.790689 -235.47811)
			(xy 342.836963 -235.501688) (xy 342.878979 -235.532214) (xy 342.915702 -235.568937) (xy 342.946228 -235.610953)
			(xy 342.969806 -235.657227) (xy 342.985854 -235.70662) (xy 342.993979 -235.757915) (xy 342.994488 -235.783882)
			(xy 342.993979 -235.809849) (xy 343.273889 -235.809849) (xy 343.273889 -235.757915) (xy 343.282014 -235.70662)
			(xy 343.298062 -235.657227) (xy 343.32164 -235.610953) (xy 343.352166 -235.568937) (xy 343.388889 -235.532214)
			(xy 343.430905 -235.501688) (xy 343.477179 -235.47811) (xy 343.526572 -235.462062) (xy 343.577867 -235.453937)
			(xy 343.629801 -235.453937) (xy 343.681096 -235.462062) (xy 343.730489 -235.47811) (xy 343.776763 -235.501688)
			(xy 343.818779 -235.532214) (xy 343.855502 -235.568937) (xy 343.886028 -235.610953) (xy 343.909606 -235.657227)
			(xy 343.925654 -235.70662) (xy 343.933779 -235.757915) (xy 343.934288 -235.783882) (xy 343.933779 -235.809849)
			(xy 344.213689 -235.809849) (xy 344.213689 -235.757915) (xy 344.221814 -235.70662) (xy 344.237862 -235.657227)
			(xy 344.26144 -235.610953) (xy 344.291966 -235.568937) (xy 344.328689 -235.532214) (xy 344.370705 -235.501688)
			(xy 344.416979 -235.47811) (xy 344.466372 -235.462062) (xy 344.517667 -235.453937) (xy 344.569601 -235.453937)
			(xy 344.620896 -235.462062) (xy 344.670289 -235.47811) (xy 344.716563 -235.501688) (xy 344.758579 -235.532214)
			(xy 344.795302 -235.568937) (xy 344.825828 -235.610953) (xy 344.849406 -235.657227) (xy 344.865454 -235.70662)
			(xy 344.873579 -235.757915) (xy 344.874088 -235.783882) (xy 344.873579 -235.809849) (xy 345.153235 -235.809849)
			(xy 345.153235 -235.757915) (xy 345.16136 -235.70662) (xy 345.177408 -235.657227) (xy 345.200986 -235.610953)
			(xy 345.231512 -235.568937) (xy 345.268235 -235.532214) (xy 345.310251 -235.501688) (xy 345.356525 -235.47811)
			(xy 345.405918 -235.462062) (xy 345.457213 -235.453937) (xy 345.509147 -235.453937) (xy 345.560442 -235.462062)
			(xy 345.609835 -235.47811) (xy 345.656109 -235.501688) (xy 345.698125 -235.532214) (xy 345.734848 -235.568937)
			(xy 345.765374 -235.610953) (xy 345.788952 -235.657227) (xy 345.805 -235.70662) (xy 345.813125 -235.757915)
			(xy 345.813634 -235.783882) (xy 345.813125 -235.809849) (xy 346.093289 -235.809849) (xy 346.093289 -235.757915)
			(xy 346.101414 -235.70662) (xy 346.117462 -235.657227) (xy 346.14104 -235.610953) (xy 346.171566 -235.568937)
			(xy 346.208289 -235.532214) (xy 346.250305 -235.501688) (xy 346.296579 -235.47811) (xy 346.345972 -235.462062)
			(xy 346.397267 -235.453937) (xy 346.449201 -235.453937) (xy 346.500496 -235.462062) (xy 346.549889 -235.47811)
			(xy 346.596163 -235.501688) (xy 346.638179 -235.532214) (xy 346.674902 -235.568937) (xy 346.705428 -235.610953)
			(xy 346.729006 -235.657227) (xy 346.745054 -235.70662) (xy 346.753179 -235.757915) (xy 346.753688 -235.783882)
			(xy 346.753179 -235.809849) (xy 347.033089 -235.809849) (xy 347.033089 -235.757915) (xy 347.041214 -235.70662)
			(xy 347.057262 -235.657227) (xy 347.08084 -235.610953) (xy 347.111366 -235.568937) (xy 347.148089 -235.532214)
			(xy 347.190105 -235.501688) (xy 347.236379 -235.47811) (xy 347.285772 -235.462062) (xy 347.337067 -235.453937)
			(xy 347.389001 -235.453937) (xy 347.440296 -235.462062) (xy 347.489689 -235.47811) (xy 347.535963 -235.501688)
			(xy 347.577979 -235.532214) (xy 347.614702 -235.568937) (xy 347.645228 -235.610953) (xy 347.668806 -235.657227)
			(xy 347.684854 -235.70662) (xy 347.692979 -235.757915) (xy 347.693488 -235.783882) (xy 347.692979 -235.809849)
			(xy 347.972889 -235.809849) (xy 347.972889 -235.757915) (xy 347.981014 -235.70662) (xy 347.997062 -235.657227)
			(xy 348.02064 -235.610953) (xy 348.051166 -235.568937) (xy 348.087889 -235.532214) (xy 348.129905 -235.501688)
			(xy 348.176179 -235.47811) (xy 348.225572 -235.462062) (xy 348.276867 -235.453937) (xy 348.328801 -235.453937)
			(xy 348.380096 -235.462062) (xy 348.429489 -235.47811) (xy 348.475763 -235.501688) (xy 348.517779 -235.532214)
			(xy 348.554502 -235.568937) (xy 348.585028 -235.610953) (xy 348.608606 -235.657227) (xy 348.624654 -235.70662)
			(xy 348.632779 -235.757915) (xy 348.633288 -235.783882) (xy 348.632779 -235.809849) (xy 348.912689 -235.809849)
			(xy 348.912689 -235.757915) (xy 348.920814 -235.70662) (xy 348.936862 -235.657227) (xy 348.96044 -235.610953)
			(xy 348.990966 -235.568937) (xy 349.027689 -235.532214) (xy 349.069705 -235.501688) (xy 349.115979 -235.47811)
			(xy 349.165372 -235.462062) (xy 349.216667 -235.453937) (xy 349.268601 -235.453937) (xy 349.319896 -235.462062)
			(xy 349.369289 -235.47811) (xy 349.415563 -235.501688) (xy 349.457579 -235.532214) (xy 349.494302 -235.568937)
			(xy 349.524828 -235.610953) (xy 349.548406 -235.657227) (xy 349.564454 -235.70662) (xy 349.572579 -235.757915)
			(xy 349.573088 -235.783882) (xy 349.572579 -235.809849) (xy 349.564454 -235.861144) (xy 349.548406 -235.910537)
			(xy 349.524828 -235.956811) (xy 349.494302 -235.998827) (xy 349.457579 -236.03555) (xy 349.415563 -236.066076)
			(xy 349.369289 -236.089654) (xy 349.319896 -236.105702) (xy 349.268601 -236.113827) (xy 349.216667 -236.113827)
			(xy 349.165372 -236.105702) (xy 349.115979 -236.089654) (xy 349.069705 -236.066076) (xy 349.027689 -236.03555)
			(xy 348.990966 -235.998827) (xy 348.96044 -235.956811) (xy 348.936862 -235.910537) (xy 348.920814 -235.861144)
			(xy 348.912689 -235.809849) (xy 348.632779 -235.809849) (xy 348.624654 -235.861144) (xy 348.608606 -235.910537)
			(xy 348.585028 -235.956811) (xy 348.554502 -235.998827) (xy 348.517779 -236.03555) (xy 348.475763 -236.066076)
			(xy 348.429489 -236.089654) (xy 348.380096 -236.105702) (xy 348.328801 -236.113827) (xy 348.276867 -236.113827)
			(xy 348.225572 -236.105702) (xy 348.176179 -236.089654) (xy 348.129905 -236.066076) (xy 348.087889 -236.03555)
			(xy 348.051166 -235.998827) (xy 348.02064 -235.956811) (xy 347.997062 -235.910537) (xy 347.981014 -235.861144)
			(xy 347.972889 -235.809849) (xy 347.692979 -235.809849) (xy 347.684854 -235.861144) (xy 347.668806 -235.910537)
			(xy 347.645228 -235.956811) (xy 347.614702 -235.998827) (xy 347.577979 -236.03555) (xy 347.535963 -236.066076)
			(xy 347.489689 -236.089654) (xy 347.440296 -236.105702) (xy 347.389001 -236.113827) (xy 347.337067 -236.113827)
			(xy 347.285772 -236.105702) (xy 347.236379 -236.089654) (xy 347.190105 -236.066076) (xy 347.148089 -236.03555)
			(xy 347.111366 -235.998827) (xy 347.08084 -235.956811) (xy 347.057262 -235.910537) (xy 347.041214 -235.861144)
			(xy 347.033089 -235.809849) (xy 346.753179 -235.809849) (xy 346.745054 -235.861144) (xy 346.729006 -235.910537)
			(xy 346.705428 -235.956811) (xy 346.674902 -235.998827) (xy 346.638179 -236.03555) (xy 346.596163 -236.066076)
			(xy 346.549889 -236.089654) (xy 346.500496 -236.105702) (xy 346.449201 -236.113827) (xy 346.397267 -236.113827)
			(xy 346.345972 -236.105702) (xy 346.296579 -236.089654) (xy 346.250305 -236.066076) (xy 346.208289 -236.03555)
			(xy 346.171566 -235.998827) (xy 346.14104 -235.956811) (xy 346.117462 -235.910537) (xy 346.101414 -235.861144)
			(xy 346.093289 -235.809849) (xy 345.813125 -235.809849) (xy 345.805 -235.861144) (xy 345.788952 -235.910537)
			(xy 345.765374 -235.956811) (xy 345.734848 -235.998827) (xy 345.698125 -236.03555) (xy 345.656109 -236.066076)
			(xy 345.609835 -236.089654) (xy 345.560442 -236.105702) (xy 345.509147 -236.113827) (xy 345.457213 -236.113827)
			(xy 345.405918 -236.105702) (xy 345.356525 -236.089654) (xy 345.310251 -236.066076) (xy 345.268235 -236.03555)
			(xy 345.231512 -235.998827) (xy 345.200986 -235.956811) (xy 345.177408 -235.910537) (xy 345.16136 -235.861144)
			(xy 345.153235 -235.809849) (xy 344.873579 -235.809849) (xy 344.865454 -235.861144) (xy 344.849406 -235.910537)
			(xy 344.825828 -235.956811) (xy 344.795302 -235.998827) (xy 344.758579 -236.03555) (xy 344.716563 -236.066076)
			(xy 344.670289 -236.089654) (xy 344.620896 -236.105702) (xy 344.569601 -236.113827) (xy 344.517667 -236.113827)
			(xy 344.466372 -236.105702) (xy 344.416979 -236.089654) (xy 344.370705 -236.066076) (xy 344.328689 -236.03555)
			(xy 344.291966 -235.998827) (xy 344.26144 -235.956811) (xy 344.237862 -235.910537) (xy 344.221814 -235.861144)
			(xy 344.213689 -235.809849) (xy 343.933779 -235.809849) (xy 343.925654 -235.861144) (xy 343.909606 -235.910537)
			(xy 343.886028 -235.956811) (xy 343.855502 -235.998827) (xy 343.818779 -236.03555) (xy 343.776763 -236.066076)
			(xy 343.730489 -236.089654) (xy 343.681096 -236.105702) (xy 343.629801 -236.113827) (xy 343.577867 -236.113827)
			(xy 343.526572 -236.105702) (xy 343.477179 -236.089654) (xy 343.430905 -236.066076) (xy 343.388889 -236.03555)
			(xy 343.352166 -235.998827) (xy 343.32164 -235.956811) (xy 343.298062 -235.910537) (xy 343.282014 -235.861144)
			(xy 343.273889 -235.809849) (xy 342.993979 -235.809849) (xy 342.985854 -235.861144) (xy 342.969806 -235.910537)
			(xy 342.946228 -235.956811) (xy 342.915702 -235.998827) (xy 342.878979 -236.03555) (xy 342.836963 -236.066076)
			(xy 342.790689 -236.089654) (xy 342.741296 -236.105702) (xy 342.690001 -236.113827) (xy 342.638067 -236.113827)
			(xy 342.586772 -236.105702) (xy 342.537379 -236.089654) (xy 342.491105 -236.066076) (xy 342.449089 -236.03555)
			(xy 342.412366 -235.998827) (xy 342.38184 -235.956811) (xy 342.358262 -235.910537) (xy 342.342214 -235.861144)
			(xy 342.334089 -235.809849) (xy 342.054179 -235.809849) (xy 342.046054 -235.861144) (xy 342.030006 -235.910537)
			(xy 342.006428 -235.956811) (xy 341.975902 -235.998827) (xy 341.939179 -236.03555) (xy 341.897163 -236.066076)
			(xy 341.850889 -236.089654) (xy 341.801496 -236.105702) (xy 341.750201 -236.113827) (xy 341.698267 -236.113827)
			(xy 341.646972 -236.105702) (xy 341.597579 -236.089654) (xy 341.551305 -236.066076) (xy 341.509289 -236.03555)
			(xy 341.472566 -235.998827) (xy 341.44204 -235.956811) (xy 341.418462 -235.910537) (xy 341.402414 -235.861144)
			(xy 341.394289 -235.809849) (xy 341.114379 -235.809849) (xy 341.106254 -235.861144) (xy 341.090206 -235.910537)
			(xy 341.066628 -235.956811) (xy 341.036102 -235.998827) (xy 340.999379 -236.03555) (xy 340.957363 -236.066076)
			(xy 340.911089 -236.089654) (xy 340.861696 -236.105702) (xy 340.810401 -236.113827) (xy 340.758467 -236.113827)
			(xy 340.707172 -236.105702) (xy 340.657779 -236.089654) (xy 340.611505 -236.066076) (xy 340.569489 -236.03555)
			(xy 340.532766 -235.998827) (xy 340.50224 -235.956811) (xy 340.478662 -235.910537) (xy 340.462614 -235.861144)
			(xy 340.454489 -235.809849) (xy 340.174817 -235.809849) (xy 340.174817 -235.809887) (xy 340.166687 -235.861221)
			(xy 340.150627 -235.910651) (xy 340.127033 -235.956961) (xy 340.096485 -235.99901) (xy 340.059736 -236.035763)
			(xy 340.01769 -236.066315) (xy 339.971383 -236.089914) (xy 339.921954 -236.105979) (xy 339.870621 -236.114114)
			(xy 339.844634 -236.11459) (xy 339.817668 -236.114053) (xy 339.764453 -236.105293) (xy 339.713363 -236.088017)
			(xy 339.665753 -236.062683) (xy 339.643974 -236.046772) (xy 339.637878 -236.0422) (xy 339.619844 -236.03585)
			(xy 339.61112 -236.03317) (xy 339.59289 -236.033572) (xy 339.584284 -236.036612) (xy 339.500972 -236.07649)
			(xy 339.49333 -236.081089) (xy 339.481666 -236.094566) (xy 339.475438 -236.111266) (xy 339.475064 -236.120178)
			(xy 339.475064 -236.248194) (xy 339.505036 -236.29366) (xy 339.517736 -236.299756) (xy 339.541444 -236.311727)
			(xy 339.58503 -236.342071) (xy 339.623209 -236.378988) (xy 339.655 -236.421529) (xy 339.679588 -236.468603)
			(xy 339.69634 -236.519) (xy 339.704827 -236.571425) (xy 339.704831 -236.623919) (xy 339.984335 -236.623919)
			(xy 339.984335 -236.571985) (xy 339.99246 -236.52069) (xy 340.008508 -236.471297) (xy 340.032086 -236.425023)
			(xy 340.062612 -236.383007) (xy 340.099335 -236.346284) (xy 340.141351 -236.315758) (xy 340.187625 -236.29218)
			(xy 340.237018 -236.276132) (xy 340.288313 -236.268007) (xy 340.340247 -236.268007) (xy 340.391542 -236.276132)
			(xy 340.440935 -236.29218) (xy 340.487209 -236.315758) (xy 340.529225 -236.346284) (xy 340.565948 -236.383007)
			(xy 340.596474 -236.425023) (xy 340.620052 -236.471297) (xy 340.6361 -236.52069) (xy 340.644225 -236.571985)
			(xy 340.644734 -236.597952) (xy 340.644225 -236.623919) (xy 340.924135 -236.623919) (xy 340.924135 -236.571985)
			(xy 340.93226 -236.52069) (xy 340.948308 -236.471297) (xy 340.971886 -236.425023) (xy 341.002412 -236.383007)
			(xy 341.039135 -236.346284) (xy 341.081151 -236.315758) (xy 341.127425 -236.29218) (xy 341.176818 -236.276132)
			(xy 341.228113 -236.268007) (xy 341.280047 -236.268007) (xy 341.331342 -236.276132) (xy 341.380735 -236.29218)
			(xy 341.427009 -236.315758) (xy 341.469025 -236.346284) (xy 341.505748 -236.383007) (xy 341.536274 -236.425023)
			(xy 341.559852 -236.471297) (xy 341.5759 -236.52069) (xy 341.584025 -236.571985) (xy 341.584534 -236.597952)
			(xy 341.584025 -236.623919) (xy 341.864189 -236.623919) (xy 341.864189 -236.571985) (xy 341.872314 -236.52069)
			(xy 341.888362 -236.471297) (xy 341.91194 -236.425023) (xy 341.942466 -236.383007) (xy 341.979189 -236.346284)
			(xy 342.021205 -236.315758) (xy 342.067479 -236.29218) (xy 342.116872 -236.276132) (xy 342.168167 -236.268007)
			(xy 342.220101 -236.268007) (xy 342.271396 -236.276132) (xy 342.320789 -236.29218) (xy 342.367063 -236.315758)
			(xy 342.409079 -236.346284) (xy 342.445802 -236.383007) (xy 342.476328 -236.425023) (xy 342.499906 -236.471297)
			(xy 342.515954 -236.52069) (xy 342.524079 -236.571985) (xy 342.524588 -236.597952) (xy 342.524079 -236.623919)
			(xy 342.803735 -236.623919) (xy 342.803735 -236.571985) (xy 342.81186 -236.52069) (xy 342.827908 -236.471297)
			(xy 342.851486 -236.425023) (xy 342.882012 -236.383007) (xy 342.918735 -236.346284) (xy 342.960751 -236.315758)
			(xy 343.007025 -236.29218) (xy 343.056418 -236.276132) (xy 343.107713 -236.268007) (xy 343.159647 -236.268007)
			(xy 343.210942 -236.276132) (xy 343.260335 -236.29218) (xy 343.306609 -236.315758) (xy 343.348625 -236.346284)
			(xy 343.385348 -236.383007) (xy 343.415874 -236.425023) (xy 343.439452 -236.471297) (xy 343.4555 -236.52069)
			(xy 343.463625 -236.571985) (xy 343.464134 -236.597952) (xy 343.463625 -236.623919) (xy 343.743535 -236.623919)
			(xy 343.743535 -236.571985) (xy 343.75166 -236.52069) (xy 343.767708 -236.471297) (xy 343.791286 -236.425023)
			(xy 343.821812 -236.383007) (xy 343.858535 -236.346284) (xy 343.900551 -236.315758) (xy 343.946825 -236.29218)
			(xy 343.996218 -236.276132) (xy 344.047513 -236.268007) (xy 344.099447 -236.268007) (xy 344.150742 -236.276132)
			(xy 344.200135 -236.29218) (xy 344.246409 -236.315758) (xy 344.288425 -236.346284) (xy 344.325148 -236.383007)
			(xy 344.355674 -236.425023) (xy 344.379252 -236.471297) (xy 344.3953 -236.52069) (xy 344.403425 -236.571985)
			(xy 344.403934 -236.597952) (xy 344.403425 -236.623919) (xy 344.683335 -236.623919) (xy 344.683335 -236.571985)
			(xy 344.69146 -236.52069) (xy 344.707508 -236.471297) (xy 344.731086 -236.425023) (xy 344.761612 -236.383007)
			(xy 344.798335 -236.346284) (xy 344.840351 -236.315758) (xy 344.886625 -236.29218) (xy 344.936018 -236.276132)
			(xy 344.987313 -236.268007) (xy 345.039247 -236.268007) (xy 345.090542 -236.276132) (xy 345.139935 -236.29218)
			(xy 345.186209 -236.315758) (xy 345.228225 -236.346284) (xy 345.264948 -236.383007) (xy 345.295474 -236.425023)
			(xy 345.319052 -236.471297) (xy 345.3351 -236.52069) (xy 345.343225 -236.571985) (xy 345.343734 -236.597952)
			(xy 345.343225 -236.623919) (xy 345.623135 -236.623919) (xy 345.623135 -236.571985) (xy 345.63126 -236.52069)
			(xy 345.647308 -236.471297) (xy 345.670886 -236.425023) (xy 345.701412 -236.383007) (xy 345.738135 -236.346284)
			(xy 345.780151 -236.315758) (xy 345.826425 -236.29218) (xy 345.875818 -236.276132) (xy 345.927113 -236.268007)
			(xy 345.979047 -236.268007) (xy 346.030342 -236.276132) (xy 346.079735 -236.29218) (xy 346.126009 -236.315758)
			(xy 346.168025 -236.346284) (xy 346.204748 -236.383007) (xy 346.235274 -236.425023) (xy 346.258852 -236.471297)
			(xy 346.2749 -236.52069) (xy 346.283025 -236.571985) (xy 346.283534 -236.597952) (xy 346.283025 -236.623919)
			(xy 346.562935 -236.623919) (xy 346.562935 -236.571985) (xy 346.57106 -236.52069) (xy 346.587108 -236.471297)
			(xy 346.610686 -236.425023) (xy 346.641212 -236.383007) (xy 346.677935 -236.346284) (xy 346.719951 -236.315758)
			(xy 346.766225 -236.29218) (xy 346.815618 -236.276132) (xy 346.866913 -236.268007) (xy 346.918847 -236.268007)
			(xy 346.970142 -236.276132) (xy 347.019535 -236.29218) (xy 347.065809 -236.315758) (xy 347.107825 -236.346284)
			(xy 347.144548 -236.383007) (xy 347.175074 -236.425023) (xy 347.198652 -236.471297) (xy 347.2147 -236.52069)
			(xy 347.222825 -236.571985) (xy 347.223334 -236.597952) (xy 347.222825 -236.623919) (xy 347.502735 -236.623919)
			(xy 347.502735 -236.571985) (xy 347.51086 -236.52069) (xy 347.526908 -236.471297) (xy 347.550486 -236.425023)
			(xy 347.581012 -236.383007) (xy 347.617735 -236.346284) (xy 347.659751 -236.315758) (xy 347.706025 -236.29218)
			(xy 347.755418 -236.276132) (xy 347.806713 -236.268007) (xy 347.858647 -236.268007) (xy 347.909942 -236.276132)
			(xy 347.959335 -236.29218) (xy 348.005609 -236.315758) (xy 348.047625 -236.346284) (xy 348.084348 -236.383007)
			(xy 348.114874 -236.425023) (xy 348.138452 -236.471297) (xy 348.1545 -236.52069) (xy 348.162625 -236.571985)
			(xy 348.163134 -236.597952) (xy 348.162625 -236.623919) (xy 348.442535 -236.623919) (xy 348.442535 -236.571985)
			(xy 348.45066 -236.52069) (xy 348.466708 -236.471297) (xy 348.490286 -236.425023) (xy 348.520812 -236.383007)
			(xy 348.557535 -236.346284) (xy 348.599551 -236.315758) (xy 348.645825 -236.29218) (xy 348.695218 -236.276132)
			(xy 348.746513 -236.268007) (xy 348.798447 -236.268007) (xy 348.849742 -236.276132) (xy 348.899135 -236.29218)
			(xy 348.945409 -236.315758) (xy 348.987425 -236.346284) (xy 349.024148 -236.383007) (xy 349.054674 -236.425023)
			(xy 349.078252 -236.471297) (xy 349.0943 -236.52069) (xy 349.102425 -236.571985) (xy 349.102934 -236.597952)
			(xy 349.102425 -236.623919) (xy 349.382335 -236.623919) (xy 349.382335 -236.571985) (xy 349.39046 -236.52069)
			(xy 349.406508 -236.471297) (xy 349.430086 -236.425023) (xy 349.460612 -236.383007) (xy 349.497335 -236.346284)
			(xy 349.539351 -236.315758) (xy 349.585625 -236.29218) (xy 349.635018 -236.276132) (xy 349.686313 -236.268007)
			(xy 349.738247 -236.268007) (xy 349.789542 -236.276132) (xy 349.838935 -236.29218) (xy 349.885209 -236.315758)
			(xy 349.927225 -236.346284) (xy 349.963948 -236.383007) (xy 349.994474 -236.425023) (xy 350.018052 -236.471297)
			(xy 350.0341 -236.52069) (xy 350.042225 -236.571985) (xy 350.042734 -236.597952) (xy 350.042225 -236.623919)
			(xy 350.0341 -236.675214) (xy 350.018052 -236.724607) (xy 349.994474 -236.770881) (xy 349.963948 -236.812897)
			(xy 349.927225 -236.84962) (xy 349.885209 -236.880146) (xy 349.838935 -236.903724) (xy 349.789542 -236.919772)
			(xy 349.738247 -236.927897) (xy 349.686313 -236.927897) (xy 349.635018 -236.919772) (xy 349.585625 -236.903724)
			(xy 349.539351 -236.880146) (xy 349.497335 -236.84962) (xy 349.460612 -236.812897) (xy 349.430086 -236.770881)
			(xy 349.406508 -236.724607) (xy 349.39046 -236.675214) (xy 349.382335 -236.623919) (xy 349.102425 -236.623919)
			(xy 349.0943 -236.675214) (xy 349.078252 -236.724607) (xy 349.054674 -236.770881) (xy 349.024148 -236.812897)
			(xy 348.987425 -236.84962) (xy 348.945409 -236.880146) (xy 348.899135 -236.903724) (xy 348.849742 -236.919772)
			(xy 348.798447 -236.927897) (xy 348.746513 -236.927897) (xy 348.695218 -236.919772) (xy 348.645825 -236.903724)
			(xy 348.599551 -236.880146) (xy 348.557535 -236.84962) (xy 348.520812 -236.812897) (xy 348.490286 -236.770881)
			(xy 348.466708 -236.724607) (xy 348.45066 -236.675214) (xy 348.442535 -236.623919) (xy 348.162625 -236.623919)
			(xy 348.1545 -236.675214) (xy 348.138452 -236.724607) (xy 348.114874 -236.770881) (xy 348.084348 -236.812897)
			(xy 348.047625 -236.84962) (xy 348.005609 -236.880146) (xy 347.959335 -236.903724) (xy 347.909942 -236.919772)
			(xy 347.858647 -236.927897) (xy 347.806713 -236.927897) (xy 347.755418 -236.919772) (xy 347.706025 -236.903724)
			(xy 347.659751 -236.880146) (xy 347.617735 -236.84962) (xy 347.581012 -236.812897) (xy 347.550486 -236.770881)
			(xy 347.526908 -236.724607) (xy 347.51086 -236.675214) (xy 347.502735 -236.623919) (xy 347.222825 -236.623919)
			(xy 347.2147 -236.675214) (xy 347.198652 -236.724607) (xy 347.175074 -236.770881) (xy 347.144548 -236.812897)
			(xy 347.107825 -236.84962) (xy 347.065809 -236.880146) (xy 347.019535 -236.903724) (xy 346.970142 -236.919772)
			(xy 346.918847 -236.927897) (xy 346.866913 -236.927897) (xy 346.815618 -236.919772) (xy 346.766225 -236.903724)
			(xy 346.719951 -236.880146) (xy 346.677935 -236.84962) (xy 346.641212 -236.812897) (xy 346.610686 -236.770881)
			(xy 346.587108 -236.724607) (xy 346.57106 -236.675214) (xy 346.562935 -236.623919) (xy 346.283025 -236.623919)
			(xy 346.2749 -236.675214) (xy 346.258852 -236.724607) (xy 346.235274 -236.770881) (xy 346.204748 -236.812897)
			(xy 346.168025 -236.84962) (xy 346.126009 -236.880146) (xy 346.079735 -236.903724) (xy 346.030342 -236.919772)
			(xy 345.979047 -236.927897) (xy 345.927113 -236.927897) (xy 345.875818 -236.919772) (xy 345.826425 -236.903724)
			(xy 345.780151 -236.880146) (xy 345.738135 -236.84962) (xy 345.701412 -236.812897) (xy 345.670886 -236.770881)
			(xy 345.647308 -236.724607) (xy 345.63126 -236.675214) (xy 345.623135 -236.623919) (xy 345.343225 -236.623919)
			(xy 345.3351 -236.675214) (xy 345.319052 -236.724607) (xy 345.295474 -236.770881) (xy 345.264948 -236.812897)
			(xy 345.228225 -236.84962) (xy 345.186209 -236.880146) (xy 345.139935 -236.903724) (xy 345.090542 -236.919772)
			(xy 345.039247 -236.927897) (xy 344.987313 -236.927897) (xy 344.936018 -236.919772) (xy 344.886625 -236.903724)
			(xy 344.840351 -236.880146) (xy 344.798335 -236.84962) (xy 344.761612 -236.812897) (xy 344.731086 -236.770881)
			(xy 344.707508 -236.724607) (xy 344.69146 -236.675214) (xy 344.683335 -236.623919) (xy 344.403425 -236.623919)
			(xy 344.3953 -236.675214) (xy 344.379252 -236.724607) (xy 344.355674 -236.770881) (xy 344.325148 -236.812897)
			(xy 344.288425 -236.84962) (xy 344.246409 -236.880146) (xy 344.200135 -236.903724) (xy 344.150742 -236.919772)
			(xy 344.099447 -236.927897) (xy 344.047513 -236.927897) (xy 343.996218 -236.919772) (xy 343.946825 -236.903724)
			(xy 343.900551 -236.880146) (xy 343.858535 -236.84962) (xy 343.821812 -236.812897) (xy 343.791286 -236.770881)
			(xy 343.767708 -236.724607) (xy 343.75166 -236.675214) (xy 343.743535 -236.623919) (xy 343.463625 -236.623919)
			(xy 343.4555 -236.675214) (xy 343.439452 -236.724607) (xy 343.415874 -236.770881) (xy 343.385348 -236.812897)
			(xy 343.348625 -236.84962) (xy 343.306609 -236.880146) (xy 343.260335 -236.903724) (xy 343.210942 -236.919772)
			(xy 343.159647 -236.927897) (xy 343.107713 -236.927897) (xy 343.056418 -236.919772) (xy 343.007025 -236.903724)
			(xy 342.960751 -236.880146) (xy 342.918735 -236.84962) (xy 342.882012 -236.812897) (xy 342.851486 -236.770881)
			(xy 342.827908 -236.724607) (xy 342.81186 -236.675214) (xy 342.803735 -236.623919) (xy 342.524079 -236.623919)
			(xy 342.515954 -236.675214) (xy 342.499906 -236.724607) (xy 342.476328 -236.770881) (xy 342.445802 -236.812897)
			(xy 342.409079 -236.84962) (xy 342.367063 -236.880146) (xy 342.320789 -236.903724) (xy 342.271396 -236.919772)
			(xy 342.220101 -236.927897) (xy 342.168167 -236.927897) (xy 342.116872 -236.919772) (xy 342.067479 -236.903724)
			(xy 342.021205 -236.880146) (xy 341.979189 -236.84962) (xy 341.942466 -236.812897) (xy 341.91194 -236.770881)
			(xy 341.888362 -236.724607) (xy 341.872314 -236.675214) (xy 341.864189 -236.623919) (xy 341.584025 -236.623919)
			(xy 341.5759 -236.675214) (xy 341.559852 -236.724607) (xy 341.536274 -236.770881) (xy 341.505748 -236.812897)
			(xy 341.469025 -236.84962) (xy 341.427009 -236.880146) (xy 341.380735 -236.903724) (xy 341.331342 -236.919772)
			(xy 341.280047 -236.927897) (xy 341.228113 -236.927897) (xy 341.176818 -236.919772) (xy 341.127425 -236.903724)
			(xy 341.081151 -236.880146) (xy 341.039135 -236.84962) (xy 341.002412 -236.812897) (xy 340.971886 -236.770881)
			(xy 340.948308 -236.724607) (xy 340.93226 -236.675214) (xy 340.924135 -236.623919) (xy 340.644225 -236.623919)
			(xy 340.6361 -236.675214) (xy 340.620052 -236.724607) (xy 340.596474 -236.770881) (xy 340.565948 -236.812897)
			(xy 340.529225 -236.84962) (xy 340.487209 -236.880146) (xy 340.440935 -236.903724) (xy 340.391542 -236.919772)
			(xy 340.340247 -236.927897) (xy 340.288313 -236.927897) (xy 340.237018 -236.919772) (xy 340.187625 -236.903724)
			(xy 340.141351 -236.880146) (xy 340.099335 -236.84962) (xy 340.062612 -236.812897) (xy 340.032086 -236.770881)
			(xy 340.008508 -236.724607) (xy 339.99246 -236.675214) (xy 339.984335 -236.623919) (xy 339.704831 -236.623919)
			(xy 339.704831 -236.624533) (xy 339.69635 -236.67696) (xy 339.679604 -236.727359) (xy 339.655023 -236.774435)
			(xy 339.623236 -236.816981) (xy 339.585062 -236.853902) (xy 339.54148 -236.884252) (xy 339.517736 -236.896148)
			(xy 339.505036 -236.902244) (xy 339.475064 -236.94771) (xy 339.475064 -237.074964) (xy 339.475517 -237.084149)
			(xy 339.48216 -237.101281) (xy 339.494476 -237.114918) (xy 339.502496 -237.119414) (xy 339.583014 -237.158276)
			(xy 339.591552 -237.161527) (xy 339.60979 -237.162313) (xy 339.618574 -237.1598) (xy 339.637624 -237.153196)
			(xy 339.643974 -237.14837) (xy 339.665722 -237.13249) (xy 339.713291 -237.107257) (xy 339.764318 -237.090061)
			(xy 339.817456 -237.081355) (xy 339.84438 -237.080806) (xy 339.870369 -237.081288) (xy 339.921708 -237.089416)
			(xy 339.971143 -237.105476) (xy 340.017457 -237.129071) (xy 340.05951 -237.159622) (xy 340.096265 -237.196375)
			(xy 340.126818 -237.238426) (xy 340.150417 -237.284738) (xy 340.166479 -237.334173) (xy 340.174611 -237.385511)
			(xy 340.174611 -237.437481) (xy 340.454489 -237.437481) (xy 340.454489 -237.385547) (xy 340.462614 -237.334252)
			(xy 340.478662 -237.284859) (xy 340.50224 -237.238585) (xy 340.532766 -237.196569) (xy 340.569489 -237.159846)
			(xy 340.611505 -237.12932) (xy 340.657779 -237.105742) (xy 340.707172 -237.089694) (xy 340.758467 -237.081569)
			(xy 340.810401 -237.081569) (xy 340.861696 -237.089694) (xy 340.911089 -237.105742) (xy 340.957363 -237.12932)
			(xy 340.999379 -237.159846) (xy 341.036102 -237.196569) (xy 341.066628 -237.238585) (xy 341.090206 -237.284859)
			(xy 341.106254 -237.334252) (xy 341.114379 -237.385547) (xy 341.114888 -237.411514) (xy 341.114379 -237.437481)
			(xy 341.394289 -237.437481) (xy 341.394289 -237.385547) (xy 341.402414 -237.334252) (xy 341.418462 -237.284859)
			(xy 341.44204 -237.238585) (xy 341.472566 -237.196569) (xy 341.509289 -237.159846) (xy 341.551305 -237.12932)
			(xy 341.597579 -237.105742) (xy 341.646972 -237.089694) (xy 341.698267 -237.081569) (xy 341.750201 -237.081569)
			(xy 341.801496 -237.089694) (xy 341.850889 -237.105742) (xy 341.897163 -237.12932) (xy 341.939179 -237.159846)
			(xy 341.975902 -237.196569) (xy 342.006428 -237.238585) (xy 342.030006 -237.284859) (xy 342.046054 -237.334252)
			(xy 342.054179 -237.385547) (xy 342.054688 -237.411514) (xy 342.054179 -237.437481) (xy 342.334089 -237.437481)
			(xy 342.334089 -237.385547) (xy 342.342214 -237.334252) (xy 342.358262 -237.284859) (xy 342.38184 -237.238585)
			(xy 342.412366 -237.196569) (xy 342.449089 -237.159846) (xy 342.491105 -237.12932) (xy 342.537379 -237.105742)
			(xy 342.586772 -237.089694) (xy 342.638067 -237.081569) (xy 342.690001 -237.081569) (xy 342.741296 -237.089694)
			(xy 342.790689 -237.105742) (xy 342.836963 -237.12932) (xy 342.878979 -237.159846) (xy 342.915702 -237.196569)
			(xy 342.946228 -237.238585) (xy 342.969806 -237.284859) (xy 342.985854 -237.334252) (xy 342.993979 -237.385547)
			(xy 342.994488 -237.411514) (xy 342.993979 -237.437481) (xy 343.273889 -237.437481) (xy 343.273889 -237.385547)
			(xy 343.282014 -237.334252) (xy 343.298062 -237.284859) (xy 343.32164 -237.238585) (xy 343.352166 -237.196569)
			(xy 343.388889 -237.159846) (xy 343.430905 -237.12932) (xy 343.477179 -237.105742) (xy 343.526572 -237.089694)
			(xy 343.577867 -237.081569) (xy 343.629801 -237.081569) (xy 343.681096 -237.089694) (xy 343.730489 -237.105742)
			(xy 343.776763 -237.12932) (xy 343.818779 -237.159846) (xy 343.855502 -237.196569) (xy 343.886028 -237.238585)
			(xy 343.909606 -237.284859) (xy 343.925654 -237.334252) (xy 343.933779 -237.385547) (xy 343.934288 -237.411514)
			(xy 343.933779 -237.437481) (xy 344.213689 -237.437481) (xy 344.213689 -237.385547) (xy 344.221814 -237.334252)
			(xy 344.237862 -237.284859) (xy 344.26144 -237.238585) (xy 344.291966 -237.196569) (xy 344.328689 -237.159846)
			(xy 344.370705 -237.12932) (xy 344.416979 -237.105742) (xy 344.466372 -237.089694) (xy 344.517667 -237.081569)
			(xy 344.569601 -237.081569) (xy 344.620896 -237.089694) (xy 344.670289 -237.105742) (xy 344.716563 -237.12932)
			(xy 344.758579 -237.159846) (xy 344.795302 -237.196569) (xy 344.825828 -237.238585) (xy 344.849406 -237.284859)
			(xy 344.865454 -237.334252) (xy 344.873579 -237.385547) (xy 344.874088 -237.411514) (xy 344.873579 -237.437481)
			(xy 345.153489 -237.437481) (xy 345.153489 -237.385547) (xy 345.161614 -237.334252) (xy 345.177662 -237.284859)
			(xy 345.20124 -237.238585) (xy 345.231766 -237.196569) (xy 345.268489 -237.159846) (xy 345.310505 -237.12932)
			(xy 345.356779 -237.105742) (xy 345.406172 -237.089694) (xy 345.457467 -237.081569) (xy 345.509401 -237.081569)
			(xy 345.560696 -237.089694) (xy 345.610089 -237.105742) (xy 345.656363 -237.12932) (xy 345.698379 -237.159846)
			(xy 345.735102 -237.196569) (xy 345.765628 -237.238585) (xy 345.789206 -237.284859) (xy 345.805254 -237.334252)
			(xy 345.813379 -237.385547) (xy 345.813888 -237.411514) (xy 345.813379 -237.437481) (xy 346.093035 -237.437481)
			(xy 346.093035 -237.385547) (xy 346.10116 -237.334252) (xy 346.117208 -237.284859) (xy 346.140786 -237.238585)
			(xy 346.171312 -237.196569) (xy 346.208035 -237.159846) (xy 346.250051 -237.12932) (xy 346.296325 -237.105742)
			(xy 346.345718 -237.089694) (xy 346.397013 -237.081569) (xy 346.448947 -237.081569) (xy 346.500242 -237.089694)
			(xy 346.549635 -237.105742) (xy 346.595909 -237.12932) (xy 346.637925 -237.159846) (xy 346.674648 -237.196569)
			(xy 346.705174 -237.238585) (xy 346.728752 -237.284859) (xy 346.7448 -237.334252) (xy 346.752925 -237.385547)
			(xy 346.753434 -237.411514) (xy 346.752925 -237.437481) (xy 347.033089 -237.437481) (xy 347.033089 -237.385547)
			(xy 347.041214 -237.334252) (xy 347.057262 -237.284859) (xy 347.08084 -237.238585) (xy 347.111366 -237.196569)
			(xy 347.148089 -237.159846) (xy 347.190105 -237.12932) (xy 347.236379 -237.105742) (xy 347.285772 -237.089694)
			(xy 347.337067 -237.081569) (xy 347.389001 -237.081569) (xy 347.440296 -237.089694) (xy 347.489689 -237.105742)
			(xy 347.535963 -237.12932) (xy 347.577979 -237.159846) (xy 347.614702 -237.196569) (xy 347.645228 -237.238585)
			(xy 347.668806 -237.284859) (xy 347.684854 -237.334252) (xy 347.692979 -237.385547) (xy 347.693488 -237.411514)
			(xy 347.692979 -237.437481) (xy 347.972889 -237.437481) (xy 347.972889 -237.385547) (xy 347.981014 -237.334252)
			(xy 347.997062 -237.284859) (xy 348.02064 -237.238585) (xy 348.051166 -237.196569) (xy 348.087889 -237.159846)
			(xy 348.129905 -237.12932) (xy 348.176179 -237.105742) (xy 348.225572 -237.089694) (xy 348.276867 -237.081569)
			(xy 348.328801 -237.081569) (xy 348.380096 -237.089694) (xy 348.429489 -237.105742) (xy 348.475763 -237.12932)
			(xy 348.517779 -237.159846) (xy 348.554502 -237.196569) (xy 348.585028 -237.238585) (xy 348.608606 -237.284859)
			(xy 348.624654 -237.334252) (xy 348.632779 -237.385547) (xy 348.633288 -237.411514) (xy 348.632779 -237.437481)
			(xy 348.912689 -237.437481) (xy 348.912689 -237.385547) (xy 348.920814 -237.334252) (xy 348.936862 -237.284859)
			(xy 348.96044 -237.238585) (xy 348.990966 -237.196569) (xy 349.027689 -237.159846) (xy 349.069705 -237.12932)
			(xy 349.115979 -237.105742) (xy 349.165372 -237.089694) (xy 349.216667 -237.081569) (xy 349.268601 -237.081569)
			(xy 349.319896 -237.089694) (xy 349.369289 -237.105742) (xy 349.415563 -237.12932) (xy 349.457579 -237.159846)
			(xy 349.494302 -237.196569) (xy 349.524828 -237.238585) (xy 349.548406 -237.284859) (xy 349.564454 -237.334252)
			(xy 349.572579 -237.385547) (xy 349.573088 -237.411514) (xy 349.572579 -237.43747) (xy 349.852443 -237.43747)
			(xy 349.852443 -237.38553) (xy 349.860569 -237.33423) (xy 349.87662 -237.284833) (xy 349.900202 -237.238555)
			(xy 349.930733 -237.196536) (xy 349.967462 -237.159811) (xy 350.009484 -237.129284) (xy 350.055764 -237.105707)
			(xy 350.105163 -237.089661) (xy 350.156464 -237.08154) (xy 350.182434 -237.08106) (xy 350.20683 -237.081418)
			(xy 350.255092 -237.088583) (xy 350.301776 -237.102769) (xy 350.345867 -237.123665) (xy 350.386405 -237.150818)
			(xy 350.422509 -237.183637) (xy 350.453394 -237.221409) (xy 350.478389 -237.263313) (xy 350.49695 -237.308436)
			(xy 350.503236 -237.332012) (xy 350.506895 -237.345059) (xy 350.520075 -237.368722) (xy 350.539019 -237.388082)
			(xy 350.562391 -237.401772) (xy 350.588542 -237.408828) (xy 350.615628 -237.408752) (xy 350.641739 -237.401549)
			(xy 350.653604 -237.395004) (xy 350.67928 -237.380514) (xy 350.73452 -237.359929) (xy 350.792531 -237.349445)
			(xy 350.822006 -237.348776) (xy 350.847977 -237.349223) (xy 350.899279 -237.35735) (xy 350.948678 -237.373403)
			(xy 350.994958 -237.396986) (xy 351.036978 -237.427518) (xy 351.04694 -237.437481) (xy 357.370889 -237.437481)
			(xy 357.370889 -237.385547) (xy 357.379014 -237.334252) (xy 357.395062 -237.284859) (xy 357.41864 -237.238585)
			(xy 357.449166 -237.196569) (xy 357.485889 -237.159846) (xy 357.527905 -237.12932) (xy 357.574179 -237.105742)
			(xy 357.623572 -237.089694) (xy 357.674867 -237.081569) (xy 357.726801 -237.081569) (xy 357.778096 -237.089694)
			(xy 357.827489 -237.105742) (xy 357.873763 -237.12932) (xy 357.915779 -237.159846) (xy 357.952502 -237.196569)
			(xy 357.983028 -237.238585) (xy 358.006606 -237.284859) (xy 358.022654 -237.334252) (xy 358.030779 -237.385547)
			(xy 358.031288 -237.411514) (xy 358.030779 -237.437481) (xy 358.310689 -237.437481) (xy 358.310689 -237.385547)
			(xy 358.318814 -237.334252) (xy 358.334862 -237.284859) (xy 358.35844 -237.238585) (xy 358.388966 -237.196569)
			(xy 358.425689 -237.159846) (xy 358.467705 -237.12932) (xy 358.513979 -237.105742) (xy 358.563372 -237.089694)
			(xy 358.614667 -237.081569) (xy 358.666601 -237.081569) (xy 358.717896 -237.089694) (xy 358.767289 -237.105742)
			(xy 358.813563 -237.12932) (xy 358.855579 -237.159846) (xy 358.892302 -237.196569) (xy 358.922828 -237.238585)
			(xy 358.946406 -237.284859) (xy 358.962454 -237.334252) (xy 358.970579 -237.385547) (xy 358.971088 -237.411514)
			(xy 358.970579 -237.437481) (xy 359.250489 -237.437481) (xy 359.250489 -237.385547) (xy 359.258614 -237.334252)
			(xy 359.274662 -237.284859) (xy 359.29824 -237.238585) (xy 359.328766 -237.196569) (xy 359.365489 -237.159846)
			(xy 359.407505 -237.12932) (xy 359.453779 -237.105742) (xy 359.503172 -237.089694) (xy 359.554467 -237.081569)
			(xy 359.606401 -237.081569) (xy 359.657696 -237.089694) (xy 359.707089 -237.105742) (xy 359.753363 -237.12932)
			(xy 359.795379 -237.159846) (xy 359.832102 -237.196569) (xy 359.862628 -237.238585) (xy 359.886206 -237.284859)
			(xy 359.902254 -237.334252) (xy 359.910379 -237.385547) (xy 359.910888 -237.411514) (xy 359.910379 -237.437481)
			(xy 360.190289 -237.437481) (xy 360.190289 -237.385547) (xy 360.198414 -237.334252) (xy 360.214462 -237.284859)
			(xy 360.23804 -237.238585) (xy 360.268566 -237.196569) (xy 360.305289 -237.159846) (xy 360.347305 -237.12932)
			(xy 360.393579 -237.105742) (xy 360.442972 -237.089694) (xy 360.494267 -237.081569) (xy 360.546201 -237.081569)
			(xy 360.597496 -237.089694) (xy 360.646889 -237.105742) (xy 360.693163 -237.12932) (xy 360.735179 -237.159846)
			(xy 360.771902 -237.196569) (xy 360.802428 -237.238585) (xy 360.826006 -237.284859) (xy 360.842054 -237.334252)
			(xy 360.850179 -237.385547) (xy 360.850688 -237.411514) (xy 360.850179 -237.437481) (xy 361.130089 -237.437481)
			(xy 361.130089 -237.385547) (xy 361.138214 -237.334252) (xy 361.154262 -237.284859) (xy 361.17784 -237.238585)
			(xy 361.208366 -237.196569) (xy 361.245089 -237.159846) (xy 361.287105 -237.12932) (xy 361.333379 -237.105742)
			(xy 361.382772 -237.089694) (xy 361.434067 -237.081569) (xy 361.486001 -237.081569) (xy 361.537296 -237.089694)
			(xy 361.586689 -237.105742) (xy 361.632963 -237.12932) (xy 361.660232 -237.149132) (xy 362.951522 -237.149132)
			(xy 362.951522 -237.148878) (xy 362.951981 -237.124352) (xy 362.959245 -237.07584) (xy 362.973596 -237.028934)
			(xy 362.994719 -236.984662) (xy 363.02215 -236.943997) (xy 363.03839 -236.925612) (xy 363.048161 -236.914098)
			(xy 363.061176 -236.886869) (xy 363.06565 -236.857024) (xy 363.06119 -236.827176) (xy 363.048188 -236.799941)
			(xy 363.03839 -236.788452) (xy 363.022148 -236.770067) (xy 362.994702 -236.729409) (xy 362.973572 -236.685138)
			(xy 362.959222 -236.638229) (xy 362.951969 -236.589713) (xy 362.951522 -236.565186) (xy 362.951522 -236.564932)
			(xy 362.952031 -236.538965) (xy 362.960156 -236.48767) (xy 362.976204 -236.438277) (xy 362.999782 -236.392003)
			(xy 363.030308 -236.349987) (xy 363.067031 -236.313264) (xy 363.109047 -236.282738) (xy 363.155321 -236.25916)
			(xy 363.204714 -236.243112) (xy 363.256009 -236.234987) (xy 363.307943 -236.234987) (xy 363.359238 -236.243112)
			(xy 363.408631 -236.25916) (xy 363.454905 -236.282738) (xy 363.496921 -236.313264) (xy 363.533644 -236.349987)
			(xy 363.56417 -236.392003) (xy 363.587748 -236.438277) (xy 363.603796 -236.48767) (xy 363.611921 -236.538965)
			(xy 363.61243 -236.564932) (xy 363.61243 -236.565186) (xy 363.611962 -236.589712) (xy 363.604702 -236.638224)
			(xy 363.590354 -236.68513) (xy 363.569233 -236.729402) (xy 363.541802 -236.770068) (xy 363.525562 -236.788452)
			(xy 363.515724 -236.799915) (xy 363.502709 -236.827161) (xy 363.498245 -236.857024) (xy 363.502723 -236.886884)
			(xy 363.515751 -236.914124) (xy 363.525562 -236.925612) (xy 363.541826 -236.943978) (xy 363.569271 -236.984641)
			(xy 363.590398 -237.028916) (xy 363.604742 -237.07583) (xy 363.611988 -237.124349) (xy 363.61243 -237.148878)
			(xy 363.61243 -237.149132) (xy 363.611921 -237.175099) (xy 363.603796 -237.226394) (xy 363.587748 -237.275787)
			(xy 363.56417 -237.322061) (xy 363.533644 -237.364077) (xy 363.496921 -237.4008) (xy 363.454905 -237.431326)
			(xy 363.425876 -237.446117) (xy 368.586259 -237.446117) (xy 368.586259 -237.394183) (xy 368.594384 -237.342888)
			(xy 368.610432 -237.293495) (xy 368.63401 -237.247221) (xy 368.664536 -237.205205) (xy 368.701259 -237.168482)
			(xy 368.743275 -237.137956) (xy 368.789549 -237.114378) (xy 368.838942 -237.09833) (xy 368.890237 -237.090205)
			(xy 368.942171 -237.090205) (xy 368.993466 -237.09833) (xy 369.042859 -237.114378) (xy 369.089133 -237.137956)
			(xy 369.131149 -237.168482) (xy 369.167872 -237.205205) (xy 369.198398 -237.247221) (xy 369.221976 -237.293495)
			(xy 369.238024 -237.342888) (xy 369.246149 -237.394183) (xy 369.246658 -237.42015) (xy 369.246318 -237.437481)
			(xy 369.588289 -237.437481) (xy 369.588289 -237.385547) (xy 369.596414 -237.334252) (xy 369.612462 -237.284859)
			(xy 369.63604 -237.238585) (xy 369.666566 -237.196569) (xy 369.703289 -237.159846) (xy 369.745305 -237.12932)
			(xy 369.791579 -237.105742) (xy 369.840972 -237.089694) (xy 369.892267 -237.081569) (xy 369.944201 -237.081569)
			(xy 369.995496 -237.089694) (xy 370.044889 -237.105742) (xy 370.091163 -237.12932) (xy 370.133179 -237.159846)
			(xy 370.169902 -237.196569) (xy 370.200428 -237.238585) (xy 370.224006 -237.284859) (xy 370.240054 -237.334252)
			(xy 370.248179 -237.385547) (xy 370.248688 -237.411514) (xy 370.248179 -237.437481) (xy 370.528089 -237.437481)
			(xy 370.528089 -237.385547) (xy 370.536214 -237.334252) (xy 370.552262 -237.284859) (xy 370.57584 -237.238585)
			(xy 370.606366 -237.196569) (xy 370.643089 -237.159846) (xy 370.685105 -237.12932) (xy 370.731379 -237.105742)
			(xy 370.780772 -237.089694) (xy 370.832067 -237.081569) (xy 370.884001 -237.081569) (xy 370.935296 -237.089694)
			(xy 370.984689 -237.105742) (xy 371.030963 -237.12932) (xy 371.072979 -237.159846) (xy 371.109702 -237.196569)
			(xy 371.140228 -237.238585) (xy 371.163806 -237.284859) (xy 371.179854 -237.334252) (xy 371.187979 -237.385547)
			(xy 371.188488 -237.411514) (xy 371.187979 -237.437481) (xy 371.467889 -237.437481) (xy 371.467889 -237.385547)
			(xy 371.476014 -237.334252) (xy 371.492062 -237.284859) (xy 371.51564 -237.238585) (xy 371.546166 -237.196569)
			(xy 371.582889 -237.159846) (xy 371.624905 -237.12932) (xy 371.671179 -237.105742) (xy 371.720572 -237.089694)
			(xy 371.771867 -237.081569) (xy 371.823801 -237.081569) (xy 371.875096 -237.089694) (xy 371.924489 -237.105742)
			(xy 371.970763 -237.12932) (xy 372.012779 -237.159846) (xy 372.049502 -237.196569) (xy 372.080028 -237.238585)
			(xy 372.103606 -237.284859) (xy 372.119654 -237.334252) (xy 372.127779 -237.385547) (xy 372.128288 -237.411514)
			(xy 372.127779 -237.437481) (xy 372.407689 -237.437481) (xy 372.407689 -237.385547) (xy 372.415814 -237.334252)
			(xy 372.431862 -237.284859) (xy 372.45544 -237.238585) (xy 372.485966 -237.196569) (xy 372.522689 -237.159846)
			(xy 372.564705 -237.12932) (xy 372.610979 -237.105742) (xy 372.660372 -237.089694) (xy 372.711667 -237.081569)
			(xy 372.763601 -237.081569) (xy 372.814896 -237.089694) (xy 372.864289 -237.105742) (xy 372.910563 -237.12932)
			(xy 372.952579 -237.159846) (xy 372.989302 -237.196569) (xy 373.019828 -237.238585) (xy 373.043406 -237.284859)
			(xy 373.059454 -237.334252) (xy 373.067579 -237.385547) (xy 373.068088 -237.411514) (xy 373.067579 -237.437481)
			(xy 373.347489 -237.437481) (xy 373.347489 -237.385547) (xy 373.355614 -237.334252) (xy 373.371662 -237.284859)
			(xy 373.39524 -237.238585) (xy 373.425766 -237.196569) (xy 373.462489 -237.159846) (xy 373.504505 -237.12932)
			(xy 373.550779 -237.105742) (xy 373.600172 -237.089694) (xy 373.651467 -237.081569) (xy 373.703401 -237.081569)
			(xy 373.754696 -237.089694) (xy 373.804089 -237.105742) (xy 373.850363 -237.12932) (xy 373.892379 -237.159846)
			(xy 373.929102 -237.196569) (xy 373.959628 -237.238585) (xy 373.983206 -237.284859) (xy 373.999254 -237.334252)
			(xy 374.007379 -237.385547) (xy 374.007888 -237.411514) (xy 374.007379 -237.437481) (xy 374.287289 -237.437481)
			(xy 374.287289 -237.385547) (xy 374.295414 -237.334252) (xy 374.311462 -237.284859) (xy 374.33504 -237.238585)
			(xy 374.365566 -237.196569) (xy 374.402289 -237.159846) (xy 374.444305 -237.12932) (xy 374.490579 -237.105742)
			(xy 374.539972 -237.089694) (xy 374.591267 -237.081569) (xy 374.643201 -237.081569) (xy 374.694496 -237.089694)
			(xy 374.743889 -237.105742) (xy 374.790163 -237.12932) (xy 374.832179 -237.159846) (xy 374.868902 -237.196569)
			(xy 374.899428 -237.238585) (xy 374.923006 -237.284859) (xy 374.939054 -237.334252) (xy 374.947179 -237.385547)
			(xy 374.947688 -237.411514) (xy 374.947179 -237.437481) (xy 375.227089 -237.437481) (xy 375.227089 -237.385547)
			(xy 375.235214 -237.334252) (xy 375.251262 -237.284859) (xy 375.27484 -237.238585) (xy 375.305366 -237.196569)
			(xy 375.342089 -237.159846) (xy 375.384105 -237.12932) (xy 375.430379 -237.105742) (xy 375.479772 -237.089694)
			(xy 375.531067 -237.081569) (xy 375.583001 -237.081569) (xy 375.634296 -237.089694) (xy 375.683689 -237.105742)
			(xy 375.729963 -237.12932) (xy 375.771979 -237.159846) (xy 375.808702 -237.196569) (xy 375.839228 -237.238585)
			(xy 375.862806 -237.284859) (xy 375.878854 -237.334252) (xy 375.886979 -237.385547) (xy 375.887488 -237.411514)
			(xy 375.886979 -237.437481) (xy 376.166889 -237.437481) (xy 376.166889 -237.385547) (xy 376.175014 -237.334252)
			(xy 376.191062 -237.284859) (xy 376.21464 -237.238585) (xy 376.245166 -237.196569) (xy 376.281889 -237.159846)
			(xy 376.323905 -237.12932) (xy 376.370179 -237.105742) (xy 376.419572 -237.089694) (xy 376.470867 -237.081569)
			(xy 376.522801 -237.081569) (xy 376.574096 -237.089694) (xy 376.623489 -237.105742) (xy 376.669763 -237.12932)
			(xy 376.711779 -237.159846) (xy 376.748502 -237.196569) (xy 376.779028 -237.238585) (xy 376.802606 -237.284859)
			(xy 376.818654 -237.334252) (xy 376.826779 -237.385547) (xy 376.827288 -237.411514) (xy 376.826779 -237.437481)
			(xy 377.106689 -237.437481) (xy 377.106689 -237.385547) (xy 377.114814 -237.334252) (xy 377.130862 -237.284859)
			(xy 377.15444 -237.238585) (xy 377.184966 -237.196569) (xy 377.221689 -237.159846) (xy 377.263705 -237.12932)
			(xy 377.309979 -237.105742) (xy 377.359372 -237.089694) (xy 377.410667 -237.081569) (xy 377.462601 -237.081569)
			(xy 377.513896 -237.089694) (xy 377.563289 -237.105742) (xy 377.609563 -237.12932) (xy 377.651579 -237.159846)
			(xy 377.688302 -237.196569) (xy 377.718828 -237.238585) (xy 377.742406 -237.284859) (xy 377.758454 -237.334252)
			(xy 377.766579 -237.385547) (xy 377.767088 -237.411514) (xy 377.766579 -237.437481) (xy 378.046489 -237.437481)
			(xy 378.046489 -237.385547) (xy 378.054614 -237.334252) (xy 378.070662 -237.284859) (xy 378.09424 -237.238585)
			(xy 378.124766 -237.196569) (xy 378.161489 -237.159846) (xy 378.203505 -237.12932) (xy 378.249779 -237.105742)
			(xy 378.299172 -237.089694) (xy 378.350467 -237.081569) (xy 378.402401 -237.081569) (xy 378.453696 -237.089694)
			(xy 378.503089 -237.105742) (xy 378.549363 -237.12932) (xy 378.591379 -237.159846) (xy 378.628102 -237.196569)
			(xy 378.658628 -237.238585) (xy 378.682206 -237.284859) (xy 378.698254 -237.334252) (xy 378.706379 -237.385547)
			(xy 378.706888 -237.411514) (xy 378.706379 -237.437481) (xy 378.986289 -237.437481) (xy 378.986289 -237.385547)
			(xy 378.994414 -237.334252) (xy 379.010462 -237.284859) (xy 379.03404 -237.238585) (xy 379.064566 -237.196569)
			(xy 379.101289 -237.159846) (xy 379.143305 -237.12932) (xy 379.189579 -237.105742) (xy 379.238972 -237.089694)
			(xy 379.290267 -237.081569) (xy 379.342201 -237.081569) (xy 379.393496 -237.089694) (xy 379.442889 -237.105742)
			(xy 379.489163 -237.12932) (xy 379.531179 -237.159846) (xy 379.567902 -237.196569) (xy 379.598428 -237.238585)
			(xy 379.622006 -237.284859) (xy 379.638054 -237.334252) (xy 379.646179 -237.385547) (xy 379.646688 -237.411514)
			(xy 379.646179 -237.437481) (xy 379.638054 -237.488776) (xy 379.622006 -237.538169) (xy 379.598428 -237.584443)
			(xy 379.567902 -237.626459) (xy 379.531179 -237.663182) (xy 379.489163 -237.693708) (xy 379.442889 -237.717286)
			(xy 379.393496 -237.733334) (xy 379.342201 -237.741459) (xy 379.290267 -237.741459) (xy 379.238972 -237.733334)
			(xy 379.189579 -237.717286) (xy 379.143305 -237.693708) (xy 379.101289 -237.663182) (xy 379.064566 -237.626459)
			(xy 379.03404 -237.584443) (xy 379.010462 -237.538169) (xy 378.994414 -237.488776) (xy 378.986289 -237.437481)
			(xy 378.706379 -237.437481) (xy 378.698254 -237.488776) (xy 378.682206 -237.538169) (xy 378.658628 -237.584443)
			(xy 378.628102 -237.626459) (xy 378.591379 -237.663182) (xy 378.549363 -237.693708) (xy 378.503089 -237.717286)
			(xy 378.453696 -237.733334) (xy 378.402401 -237.741459) (xy 378.350467 -237.741459) (xy 378.299172 -237.733334)
			(xy 378.249779 -237.717286) (xy 378.203505 -237.693708) (xy 378.161489 -237.663182) (xy 378.124766 -237.626459)
			(xy 378.09424 -237.584443) (xy 378.070662 -237.538169) (xy 378.054614 -237.488776) (xy 378.046489 -237.437481)
			(xy 377.766579 -237.437481) (xy 377.758454 -237.488776) (xy 377.742406 -237.538169) (xy 377.718828 -237.584443)
			(xy 377.688302 -237.626459) (xy 377.651579 -237.663182) (xy 377.609563 -237.693708) (xy 377.563289 -237.717286)
			(xy 377.513896 -237.733334) (xy 377.462601 -237.741459) (xy 377.410667 -237.741459) (xy 377.359372 -237.733334)
			(xy 377.309979 -237.717286) (xy 377.263705 -237.693708) (xy 377.221689 -237.663182) (xy 377.184966 -237.626459)
			(xy 377.15444 -237.584443) (xy 377.130862 -237.538169) (xy 377.114814 -237.488776) (xy 377.106689 -237.437481)
			(xy 376.826779 -237.437481) (xy 376.818654 -237.488776) (xy 376.802606 -237.538169) (xy 376.779028 -237.584443)
			(xy 376.748502 -237.626459) (xy 376.711779 -237.663182) (xy 376.669763 -237.693708) (xy 376.623489 -237.717286)
			(xy 376.574096 -237.733334) (xy 376.522801 -237.741459) (xy 376.470867 -237.741459) (xy 376.419572 -237.733334)
			(xy 376.370179 -237.717286) (xy 376.323905 -237.693708) (xy 376.281889 -237.663182) (xy 376.245166 -237.626459)
			(xy 376.21464 -237.584443) (xy 376.191062 -237.538169) (xy 376.175014 -237.488776) (xy 376.166889 -237.437481)
			(xy 375.886979 -237.437481) (xy 375.878854 -237.488776) (xy 375.862806 -237.538169) (xy 375.839228 -237.584443)
			(xy 375.808702 -237.626459) (xy 375.771979 -237.663182) (xy 375.729963 -237.693708) (xy 375.683689 -237.717286)
			(xy 375.634296 -237.733334) (xy 375.583001 -237.741459) (xy 375.531067 -237.741459) (xy 375.479772 -237.733334)
			(xy 375.430379 -237.717286) (xy 375.384105 -237.693708) (xy 375.342089 -237.663182) (xy 375.305366 -237.626459)
			(xy 375.27484 -237.584443) (xy 375.251262 -237.538169) (xy 375.235214 -237.488776) (xy 375.227089 -237.437481)
			(xy 374.947179 -237.437481) (xy 374.939054 -237.488776) (xy 374.923006 -237.538169) (xy 374.899428 -237.584443)
			(xy 374.868902 -237.626459) (xy 374.832179 -237.663182) (xy 374.790163 -237.693708) (xy 374.743889 -237.717286)
			(xy 374.694496 -237.733334) (xy 374.643201 -237.741459) (xy 374.591267 -237.741459) (xy 374.539972 -237.733334)
			(xy 374.490579 -237.717286) (xy 374.444305 -237.693708) (xy 374.402289 -237.663182) (xy 374.365566 -237.626459)
			(xy 374.33504 -237.584443) (xy 374.311462 -237.538169) (xy 374.295414 -237.488776) (xy 374.287289 -237.437481)
			(xy 374.007379 -237.437481) (xy 373.999254 -237.488776) (xy 373.983206 -237.538169) (xy 373.959628 -237.584443)
			(xy 373.929102 -237.626459) (xy 373.892379 -237.663182) (xy 373.850363 -237.693708) (xy 373.804089 -237.717286)
			(xy 373.754696 -237.733334) (xy 373.703401 -237.741459) (xy 373.651467 -237.741459) (xy 373.600172 -237.733334)
			(xy 373.550779 -237.717286) (xy 373.504505 -237.693708) (xy 373.462489 -237.663182) (xy 373.425766 -237.626459)
			(xy 373.39524 -237.584443) (xy 373.371662 -237.538169) (xy 373.355614 -237.488776) (xy 373.347489 -237.437481)
			(xy 373.067579 -237.437481) (xy 373.059454 -237.488776) (xy 373.043406 -237.538169) (xy 373.019828 -237.584443)
			(xy 372.989302 -237.626459) (xy 372.952579 -237.663182) (xy 372.910563 -237.693708) (xy 372.864289 -237.717286)
			(xy 372.814896 -237.733334) (xy 372.763601 -237.741459) (xy 372.711667 -237.741459) (xy 372.660372 -237.733334)
			(xy 372.610979 -237.717286) (xy 372.564705 -237.693708) (xy 372.522689 -237.663182) (xy 372.485966 -237.626459)
			(xy 372.45544 -237.584443) (xy 372.431862 -237.538169) (xy 372.415814 -237.488776) (xy 372.407689 -237.437481)
			(xy 372.127779 -237.437481) (xy 372.119654 -237.488776) (xy 372.103606 -237.538169) (xy 372.080028 -237.584443)
			(xy 372.049502 -237.626459) (xy 372.012779 -237.663182) (xy 371.970763 -237.693708) (xy 371.924489 -237.717286)
			(xy 371.875096 -237.733334) (xy 371.823801 -237.741459) (xy 371.771867 -237.741459) (xy 371.720572 -237.733334)
			(xy 371.671179 -237.717286) (xy 371.624905 -237.693708) (xy 371.582889 -237.663182) (xy 371.546166 -237.626459)
			(xy 371.51564 -237.584443) (xy 371.492062 -237.538169) (xy 371.476014 -237.488776) (xy 371.467889 -237.437481)
			(xy 371.187979 -237.437481) (xy 371.179854 -237.488776) (xy 371.163806 -237.538169) (xy 371.140228 -237.584443)
			(xy 371.109702 -237.626459) (xy 371.072979 -237.663182) (xy 371.030963 -237.693708) (xy 370.984689 -237.717286)
			(xy 370.935296 -237.733334) (xy 370.884001 -237.741459) (xy 370.832067 -237.741459) (xy 370.780772 -237.733334)
			(xy 370.731379 -237.717286) (xy 370.685105 -237.693708) (xy 370.643089 -237.663182) (xy 370.606366 -237.626459)
			(xy 370.57584 -237.584443) (xy 370.552262 -237.538169) (xy 370.536214 -237.488776) (xy 370.528089 -237.437481)
			(xy 370.248179 -237.437481) (xy 370.240054 -237.488776) (xy 370.224006 -237.538169) (xy 370.200428 -237.584443)
			(xy 370.169902 -237.626459) (xy 370.133179 -237.663182) (xy 370.091163 -237.693708) (xy 370.044889 -237.717286)
			(xy 369.995496 -237.733334) (xy 369.944201 -237.741459) (xy 369.892267 -237.741459) (xy 369.840972 -237.733334)
			(xy 369.791579 -237.717286) (xy 369.745305 -237.693708) (xy 369.703289 -237.663182) (xy 369.666566 -237.626459)
			(xy 369.63604 -237.584443) (xy 369.612462 -237.538169) (xy 369.596414 -237.488776) (xy 369.588289 -237.437481)
			(xy 369.246318 -237.437481) (xy 369.246149 -237.446117) (xy 369.238024 -237.497412) (xy 369.221976 -237.546805)
			(xy 369.198398 -237.593079) (xy 369.167872 -237.635095) (xy 369.131149 -237.671818) (xy 369.089133 -237.702344)
			(xy 369.042859 -237.725922) (xy 368.993466 -237.74197) (xy 368.942171 -237.750095) (xy 368.890237 -237.750095)
			(xy 368.838942 -237.74197) (xy 368.789549 -237.725922) (xy 368.743275 -237.702344) (xy 368.701259 -237.671818)
			(xy 368.664536 -237.635095) (xy 368.63401 -237.593079) (xy 368.610432 -237.546805) (xy 368.594384 -237.497412)
			(xy 368.586259 -237.446117) (xy 363.425876 -237.446117) (xy 363.408631 -237.454904) (xy 363.359238 -237.470952)
			(xy 363.307943 -237.479077) (xy 363.256009 -237.479077) (xy 363.204714 -237.470952) (xy 363.155321 -237.454904)
			(xy 363.109047 -237.431326) (xy 363.067031 -237.4008) (xy 363.030308 -237.364077) (xy 362.999782 -237.322061)
			(xy 362.976204 -237.275787) (xy 362.960156 -237.226394) (xy 362.952031 -237.175099) (xy 362.951522 -237.149132)
			(xy 361.660232 -237.149132) (xy 361.674979 -237.159846) (xy 361.711702 -237.196569) (xy 361.742228 -237.238585)
			(xy 361.765806 -237.284859) (xy 361.781854 -237.334252) (xy 361.789979 -237.385547) (xy 361.790488 -237.411514)
			(xy 361.789979 -237.437481) (xy 361.781854 -237.488776) (xy 361.765806 -237.538169) (xy 361.742228 -237.584443)
			(xy 361.711702 -237.626459) (xy 361.674979 -237.663182) (xy 361.632963 -237.693708) (xy 361.586689 -237.717286)
			(xy 361.537296 -237.733334) (xy 361.486001 -237.741459) (xy 361.434067 -237.741459) (xy 361.382772 -237.733334)
			(xy 361.333379 -237.717286) (xy 361.287105 -237.693708) (xy 361.245089 -237.663182) (xy 361.208366 -237.626459)
			(xy 361.17784 -237.584443) (xy 361.154262 -237.538169) (xy 361.138214 -237.488776) (xy 361.130089 -237.437481)
			(xy 360.850179 -237.437481) (xy 360.842054 -237.488776) (xy 360.826006 -237.538169) (xy 360.802428 -237.584443)
			(xy 360.771902 -237.626459) (xy 360.735179 -237.663182) (xy 360.693163 -237.693708) (xy 360.646889 -237.717286)
			(xy 360.597496 -237.733334) (xy 360.546201 -237.741459) (xy 360.494267 -237.741459) (xy 360.442972 -237.733334)
			(xy 360.393579 -237.717286) (xy 360.347305 -237.693708) (xy 360.305289 -237.663182) (xy 360.268566 -237.626459)
			(xy 360.23804 -237.584443) (xy 360.214462 -237.538169) (xy 360.198414 -237.488776) (xy 360.190289 -237.437481)
			(xy 359.910379 -237.437481) (xy 359.902254 -237.488776) (xy 359.886206 -237.538169) (xy 359.862628 -237.584443)
			(xy 359.832102 -237.626459) (xy 359.795379 -237.663182) (xy 359.753363 -237.693708) (xy 359.707089 -237.717286)
			(xy 359.657696 -237.733334) (xy 359.606401 -237.741459) (xy 359.554467 -237.741459) (xy 359.503172 -237.733334)
			(xy 359.453779 -237.717286) (xy 359.407505 -237.693708) (xy 359.365489 -237.663182) (xy 359.328766 -237.626459)
			(xy 359.29824 -237.584443) (xy 359.274662 -237.538169) (xy 359.258614 -237.488776) (xy 359.250489 -237.437481)
			(xy 358.970579 -237.437481) (xy 358.962454 -237.488776) (xy 358.946406 -237.538169) (xy 358.922828 -237.584443)
			(xy 358.892302 -237.626459) (xy 358.855579 -237.663182) (xy 358.813563 -237.693708) (xy 358.767289 -237.717286)
			(xy 358.717896 -237.733334) (xy 358.666601 -237.741459) (xy 358.614667 -237.741459) (xy 358.563372 -237.733334)
			(xy 358.513979 -237.717286) (xy 358.467705 -237.693708) (xy 358.425689 -237.663182) (xy 358.388966 -237.626459)
			(xy 358.35844 -237.584443) (xy 358.334862 -237.538169) (xy 358.318814 -237.488776) (xy 358.310689 -237.437481)
			(xy 358.030779 -237.437481) (xy 358.022654 -237.488776) (xy 358.006606 -237.538169) (xy 357.983028 -237.584443)
			(xy 357.952502 -237.626459) (xy 357.915779 -237.663182) (xy 357.873763 -237.693708) (xy 357.827489 -237.717286)
			(xy 357.778096 -237.733334) (xy 357.726801 -237.741459) (xy 357.674867 -237.741459) (xy 357.623572 -237.733334)
			(xy 357.574179 -237.717286) (xy 357.527905 -237.693708) (xy 357.485889 -237.663182) (xy 357.449166 -237.626459)
			(xy 357.41864 -237.584443) (xy 357.395062 -237.538169) (xy 357.379014 -237.488776) (xy 357.370889 -237.437481)
			(xy 351.04694 -237.437481) (xy 351.073705 -237.464249) (xy 351.104233 -237.506273) (xy 351.127811 -237.552555)
			(xy 351.143858 -237.601956) (xy 351.151979 -237.653259) (xy 351.15246 -237.67923) (xy 351.15246 -237.679484)
			(xy 351.151983 -237.704009) (xy 351.144724 -237.752521) (xy 351.130377 -237.799427) (xy 351.109258 -237.843699)
			(xy 351.081831 -237.884365) (xy 351.077681 -237.889063) (xy 356.290181 -237.889063) (xy 356.290181 -237.837137)
			(xy 356.298304 -237.785849) (xy 356.314349 -237.736463) (xy 356.337922 -237.690196) (xy 356.368441 -237.648185)
			(xy 356.405157 -237.611465) (xy 356.447165 -237.58094) (xy 356.49343 -237.557363) (xy 356.542814 -237.541312)
			(xy 356.594101 -237.533184) (xy 356.620064 -237.532672) (xy 356.644864 -237.533153) (xy 356.69391 -237.540547)
			(xy 356.741299 -237.55519) (xy 356.785967 -237.576753) (xy 356.82691 -237.604751) (xy 356.863207 -237.638554)
			(xy 356.894043 -237.677403) (xy 356.918726 -237.720426) (xy 356.936699 -237.766655) (xy 356.94756 -237.815051)
			(xy 356.949756 -237.839758) (xy 356.951196 -237.853716) (xy 356.960687 -237.880112) (xy 356.977002 -237.902928)
			(xy 356.998912 -237.920443) (xy 357.02476 -237.931334) (xy 357.052598 -237.934779) (xy 357.080322 -237.930519)
			(xy 357.093266 -237.925102) (xy 357.114921 -237.915628) (xy 357.160262 -237.902272) (xy 357.207046 -237.895531)
			(xy 357.23068 -237.89513) (xy 357.256649 -237.895643) (xy 357.307948 -237.903765) (xy 357.357345 -237.919813)
			(xy 357.403623 -237.94339) (xy 357.445643 -237.973917) (xy 357.48237 -238.010642) (xy 357.512899 -238.05266)
			(xy 357.53648 -238.098937) (xy 357.55253 -238.148332) (xy 357.560655 -238.199631) (xy 357.560655 -238.251551)
			(xy 357.840535 -238.251551) (xy 357.840535 -238.199617) (xy 357.84866 -238.148322) (xy 357.864708 -238.098929)
			(xy 357.888286 -238.052655) (xy 357.918812 -238.010639) (xy 357.955535 -237.973916) (xy 357.997551 -237.94339)
			(xy 358.043825 -237.919812) (xy 358.093218 -237.903764) (xy 358.144513 -237.895639) (xy 358.196447 -237.895639)
			(xy 358.247742 -237.903764) (xy 358.297135 -237.919812) (xy 358.343409 -237.94339) (xy 358.385425 -237.973916)
			(xy 358.422148 -238.010639) (xy 358.452674 -238.052655) (xy 358.476252 -238.098929) (xy 358.4923 -238.148322)
			(xy 358.500425 -238.199617) (xy 358.500934 -238.225584) (xy 358.500425 -238.251551) (xy 358.780335 -238.251551)
			(xy 358.780335 -238.199617) (xy 358.78846 -238.148322) (xy 358.804508 -238.098929) (xy 358.828086 -238.052655)
			(xy 358.858612 -238.010639) (xy 358.895335 -237.973916) (xy 358.937351 -237.94339) (xy 358.983625 -237.919812)
			(xy 359.033018 -237.903764) (xy 359.084313 -237.895639) (xy 359.136247 -237.895639) (xy 359.187542 -237.903764)
			(xy 359.236935 -237.919812) (xy 359.283209 -237.94339) (xy 359.325225 -237.973916) (xy 359.361948 -238.010639)
			(xy 359.392474 -238.052655) (xy 359.416052 -238.098929) (xy 359.4321 -238.148322) (xy 359.440225 -238.199617)
			(xy 359.440734 -238.225584) (xy 359.440225 -238.251551) (xy 359.720135 -238.251551) (xy 359.720135 -238.199617)
			(xy 359.72826 -238.148322) (xy 359.744308 -238.098929) (xy 359.767886 -238.052655) (xy 359.798412 -238.010639)
			(xy 359.835135 -237.973916) (xy 359.877151 -237.94339) (xy 359.923425 -237.919812) (xy 359.972818 -237.903764)
			(xy 360.024113 -237.895639) (xy 360.076047 -237.895639) (xy 360.127342 -237.903764) (xy 360.176735 -237.919812)
			(xy 360.223009 -237.94339) (xy 360.265025 -237.973916) (xy 360.301748 -238.010639) (xy 360.332274 -238.052655)
			(xy 360.355852 -238.098929) (xy 360.3719 -238.148322) (xy 360.380025 -238.199617) (xy 360.380534 -238.225584)
			(xy 360.380025 -238.251551) (xy 360.659935 -238.251551) (xy 360.659935 -238.199617) (xy 360.66806 -238.148322)
			(xy 360.684108 -238.098929) (xy 360.707686 -238.052655) (xy 360.738212 -238.010639) (xy 360.774935 -237.973916)
			(xy 360.816951 -237.94339) (xy 360.863225 -237.919812) (xy 360.912618 -237.903764) (xy 360.963913 -237.895639)
			(xy 361.015847 -237.895639) (xy 361.067142 -237.903764) (xy 361.116535 -237.919812) (xy 361.162809 -237.94339)
			(xy 361.204825 -237.973916) (xy 361.241548 -238.010639) (xy 361.272074 -238.052655) (xy 361.295652 -238.098929)
			(xy 361.3117 -238.148322) (xy 361.319825 -238.199617) (xy 361.320334 -238.225584) (xy 361.319825 -238.251551)
			(xy 361.599735 -238.251551) (xy 361.599735 -238.199617) (xy 361.60786 -238.148322) (xy 361.623908 -238.098929)
			(xy 361.647486 -238.052655) (xy 361.678012 -238.010639) (xy 361.714735 -237.973916) (xy 361.756751 -237.94339)
			(xy 361.803025 -237.919812) (xy 361.852418 -237.903764) (xy 361.903713 -237.895639) (xy 361.955647 -237.895639)
			(xy 362.006942 -237.903764) (xy 362.056335 -237.919812) (xy 362.102609 -237.94339) (xy 362.144625 -237.973916)
			(xy 362.181348 -238.010639) (xy 362.211874 -238.052655) (xy 362.235452 -238.098929) (xy 362.2515 -238.148322)
			(xy 362.259625 -238.199617) (xy 362.260134 -238.225584) (xy 362.259625 -238.251551) (xy 369.118135 -238.251551)
			(xy 369.118135 -238.199617) (xy 369.12626 -238.148322) (xy 369.142308 -238.098929) (xy 369.165886 -238.052655)
			(xy 369.196412 -238.010639) (xy 369.233135 -237.973916) (xy 369.275151 -237.94339) (xy 369.321425 -237.919812)
			(xy 369.370818 -237.903764) (xy 369.422113 -237.895639) (xy 369.474047 -237.895639) (xy 369.525342 -237.903764)
			(xy 369.574735 -237.919812) (xy 369.621009 -237.94339) (xy 369.663025 -237.973916) (xy 369.699748 -238.010639)
			(xy 369.730274 -238.052655) (xy 369.753852 -238.098929) (xy 369.7699 -238.148322) (xy 369.778025 -238.199617)
			(xy 369.778534 -238.225584) (xy 369.778025 -238.251551) (xy 370.057935 -238.251551) (xy 370.057935 -238.199617)
			(xy 370.06606 -238.148322) (xy 370.082108 -238.098929) (xy 370.105686 -238.052655) (xy 370.136212 -238.010639)
			(xy 370.172935 -237.973916) (xy 370.214951 -237.94339) (xy 370.261225 -237.919812) (xy 370.310618 -237.903764)
			(xy 370.361913 -237.895639) (xy 370.413847 -237.895639) (xy 370.465142 -237.903764) (xy 370.514535 -237.919812)
			(xy 370.560809 -237.94339) (xy 370.602825 -237.973916) (xy 370.639548 -238.010639) (xy 370.670074 -238.052655)
			(xy 370.693652 -238.098929) (xy 370.7097 -238.148322) (xy 370.717825 -238.199617) (xy 370.718334 -238.225584)
			(xy 370.717825 -238.251551) (xy 370.997735 -238.251551) (xy 370.997735 -238.199617) (xy 371.00586 -238.148322)
			(xy 371.021908 -238.098929) (xy 371.045486 -238.052655) (xy 371.076012 -238.010639) (xy 371.112735 -237.973916)
			(xy 371.154751 -237.94339) (xy 371.201025 -237.919812) (xy 371.250418 -237.903764) (xy 371.301713 -237.895639)
			(xy 371.353647 -237.895639) (xy 371.404942 -237.903764) (xy 371.454335 -237.919812) (xy 371.500609 -237.94339)
			(xy 371.542625 -237.973916) (xy 371.579348 -238.010639) (xy 371.609874 -238.052655) (xy 371.633452 -238.098929)
			(xy 371.6495 -238.148322) (xy 371.657625 -238.199617) (xy 371.658134 -238.225584) (xy 371.657625 -238.251551)
			(xy 371.937535 -238.251551) (xy 371.937535 -238.199617) (xy 371.94566 -238.148322) (xy 371.961708 -238.098929)
			(xy 371.985286 -238.052655) (xy 372.015812 -238.010639) (xy 372.052535 -237.973916) (xy 372.094551 -237.94339)
			(xy 372.140825 -237.919812) (xy 372.190218 -237.903764) (xy 372.241513 -237.895639) (xy 372.293447 -237.895639)
			(xy 372.344742 -237.903764) (xy 372.394135 -237.919812) (xy 372.440409 -237.94339) (xy 372.482425 -237.973916)
			(xy 372.519148 -238.010639) (xy 372.549674 -238.052655) (xy 372.573252 -238.098929) (xy 372.5893 -238.148322)
			(xy 372.597425 -238.199617) (xy 372.597934 -238.225584) (xy 372.597425 -238.251551) (xy 372.877335 -238.251551)
			(xy 372.877335 -238.199617) (xy 372.88546 -238.148322) (xy 372.901508 -238.098929) (xy 372.925086 -238.052655)
			(xy 372.955612 -238.010639) (xy 372.992335 -237.973916) (xy 373.034351 -237.94339) (xy 373.080625 -237.919812)
			(xy 373.130018 -237.903764) (xy 373.181313 -237.895639) (xy 373.233247 -237.895639) (xy 373.284542 -237.903764)
			(xy 373.333935 -237.919812) (xy 373.380209 -237.94339) (xy 373.422225 -237.973916) (xy 373.458948 -238.010639)
			(xy 373.489474 -238.052655) (xy 373.513052 -238.098929) (xy 373.5291 -238.148322) (xy 373.537225 -238.199617)
			(xy 373.537734 -238.225584) (xy 373.537225 -238.251551) (xy 373.817389 -238.251551) (xy 373.817389 -238.199617)
			(xy 373.825514 -238.148322) (xy 373.841562 -238.098929) (xy 373.86514 -238.052655) (xy 373.895666 -238.010639)
			(xy 373.932389 -237.973916) (xy 373.974405 -237.94339) (xy 374.020679 -237.919812) (xy 374.070072 -237.903764)
			(xy 374.121367 -237.895639) (xy 374.173301 -237.895639) (xy 374.224596 -237.903764) (xy 374.273989 -237.919812)
			(xy 374.320263 -237.94339) (xy 374.362279 -237.973916) (xy 374.399002 -238.010639) (xy 374.429528 -238.052655)
			(xy 374.453106 -238.098929) (xy 374.469154 -238.148322) (xy 374.477279 -238.199617) (xy 374.477788 -238.225584)
			(xy 374.477279 -238.251551) (xy 374.756935 -238.251551) (xy 374.756935 -238.199617) (xy 374.76506 -238.148322)
			(xy 374.781108 -238.098929) (xy 374.804686 -238.052655) (xy 374.835212 -238.010639) (xy 374.871935 -237.973916)
			(xy 374.913951 -237.94339) (xy 374.960225 -237.919812) (xy 375.009618 -237.903764) (xy 375.060913 -237.895639)
			(xy 375.112847 -237.895639) (xy 375.164142 -237.903764) (xy 375.213535 -237.919812) (xy 375.259809 -237.94339)
			(xy 375.301825 -237.973916) (xy 375.338548 -238.010639) (xy 375.369074 -238.052655) (xy 375.392652 -238.098929)
			(xy 375.4087 -238.148322) (xy 375.416825 -238.199617) (xy 375.417334 -238.225584) (xy 375.416825 -238.251551)
			(xy 375.696735 -238.251551) (xy 375.696735 -238.199617) (xy 375.70486 -238.148322) (xy 375.720908 -238.098929)
			(xy 375.744486 -238.052655) (xy 375.775012 -238.010639) (xy 375.811735 -237.973916) (xy 375.853751 -237.94339)
			(xy 375.900025 -237.919812) (xy 375.949418 -237.903764) (xy 376.000713 -237.895639) (xy 376.052647 -237.895639)
			(xy 376.103942 -237.903764) (xy 376.153335 -237.919812) (xy 376.199609 -237.94339) (xy 376.241625 -237.973916)
			(xy 376.278348 -238.010639) (xy 376.308874 -238.052655) (xy 376.332452 -238.098929) (xy 376.3485 -238.148322)
			(xy 376.356625 -238.199617) (xy 376.357134 -238.225584) (xy 376.356625 -238.251551) (xy 376.636535 -238.251551)
			(xy 376.636535 -238.199617) (xy 376.64466 -238.148322) (xy 376.660708 -238.098929) (xy 376.684286 -238.052655)
			(xy 376.714812 -238.010639) (xy 376.751535 -237.973916) (xy 376.793551 -237.94339) (xy 376.839825 -237.919812)
			(xy 376.889218 -237.903764) (xy 376.940513 -237.895639) (xy 376.992447 -237.895639) (xy 377.043742 -237.903764)
			(xy 377.093135 -237.919812) (xy 377.139409 -237.94339) (xy 377.181425 -237.973916) (xy 377.218148 -238.010639)
			(xy 377.248674 -238.052655) (xy 377.272252 -238.098929) (xy 377.2883 -238.148322) (xy 377.296425 -238.199617)
			(xy 377.296934 -238.225584) (xy 377.296425 -238.251551) (xy 377.576335 -238.251551) (xy 377.576335 -238.199617)
			(xy 377.58446 -238.148322) (xy 377.600508 -238.098929) (xy 377.624086 -238.052655) (xy 377.654612 -238.010639)
			(xy 377.691335 -237.973916) (xy 377.733351 -237.94339) (xy 377.779625 -237.919812) (xy 377.829018 -237.903764)
			(xy 377.880313 -237.895639) (xy 377.932247 -237.895639) (xy 377.983542 -237.903764) (xy 378.032935 -237.919812)
			(xy 378.079209 -237.94339) (xy 378.121225 -237.973916) (xy 378.157948 -238.010639) (xy 378.188474 -238.052655)
			(xy 378.212052 -238.098929) (xy 378.2281 -238.148322) (xy 378.236225 -238.199617) (xy 378.236734 -238.225584)
			(xy 378.236225 -238.251551) (xy 378.516135 -238.251551) (xy 378.516135 -238.199617) (xy 378.52426 -238.148322)
			(xy 378.540308 -238.098929) (xy 378.563886 -238.052655) (xy 378.594412 -238.010639) (xy 378.631135 -237.973916)
			(xy 378.673151 -237.94339) (xy 378.719425 -237.919812) (xy 378.768818 -237.903764) (xy 378.820113 -237.895639)
			(xy 378.872047 -237.895639) (xy 378.923342 -237.903764) (xy 378.972735 -237.919812) (xy 379.019009 -237.94339)
			(xy 379.061025 -237.973916) (xy 379.097748 -238.010639) (xy 379.128274 -238.052655) (xy 379.151852 -238.098929)
			(xy 379.1679 -238.148322) (xy 379.176025 -238.199617) (xy 379.176534 -238.225584) (xy 379.176025 -238.251551)
			(xy 379.1679 -238.302846) (xy 379.151852 -238.352239) (xy 379.128274 -238.398513) (xy 379.097748 -238.440529)
			(xy 379.061025 -238.477252) (xy 379.019009 -238.507778) (xy 378.972735 -238.531356) (xy 378.923342 -238.547404)
			(xy 378.872047 -238.555529) (xy 378.820113 -238.555529) (xy 378.768818 -238.547404) (xy 378.719425 -238.531356)
			(xy 378.673151 -238.507778) (xy 378.631135 -238.477252) (xy 378.594412 -238.440529) (xy 378.563886 -238.398513)
			(xy 378.540308 -238.352239) (xy 378.52426 -238.302846) (xy 378.516135 -238.251551) (xy 378.236225 -238.251551)
			(xy 378.2281 -238.302846) (xy 378.212052 -238.352239) (xy 378.188474 -238.398513) (xy 378.157948 -238.440529)
			(xy 378.121225 -238.477252) (xy 378.079209 -238.507778) (xy 378.032935 -238.531356) (xy 377.983542 -238.547404)
			(xy 377.932247 -238.555529) (xy 377.880313 -238.555529) (xy 377.829018 -238.547404) (xy 377.779625 -238.531356)
			(xy 377.733351 -238.507778) (xy 377.691335 -238.477252) (xy 377.654612 -238.440529) (xy 377.624086 -238.398513)
			(xy 377.600508 -238.352239) (xy 377.58446 -238.302846) (xy 377.576335 -238.251551) (xy 377.296425 -238.251551)
			(xy 377.2883 -238.302846) (xy 377.272252 -238.352239) (xy 377.248674 -238.398513) (xy 377.218148 -238.440529)
			(xy 377.181425 -238.477252) (xy 377.139409 -238.507778) (xy 377.093135 -238.531356) (xy 377.043742 -238.547404)
			(xy 376.992447 -238.555529) (xy 376.940513 -238.555529) (xy 376.889218 -238.547404) (xy 376.839825 -238.531356)
			(xy 376.793551 -238.507778) (xy 376.751535 -238.477252) (xy 376.714812 -238.440529) (xy 376.684286 -238.398513)
			(xy 376.660708 -238.352239) (xy 376.64466 -238.302846) (xy 376.636535 -238.251551) (xy 376.356625 -238.251551)
			(xy 376.3485 -238.302846) (xy 376.332452 -238.352239) (xy 376.308874 -238.398513) (xy 376.278348 -238.440529)
			(xy 376.241625 -238.477252) (xy 376.199609 -238.507778) (xy 376.153335 -238.531356) (xy 376.103942 -238.547404)
			(xy 376.052647 -238.555529) (xy 376.000713 -238.555529) (xy 375.949418 -238.547404) (xy 375.900025 -238.531356)
			(xy 375.853751 -238.507778) (xy 375.811735 -238.477252) (xy 375.775012 -238.440529) (xy 375.744486 -238.398513)
			(xy 375.720908 -238.352239) (xy 375.70486 -238.302846) (xy 375.696735 -238.251551) (xy 375.416825 -238.251551)
			(xy 375.4087 -238.302846) (xy 375.392652 -238.352239) (xy 375.369074 -238.398513) (xy 375.338548 -238.440529)
			(xy 375.301825 -238.477252) (xy 375.259809 -238.507778) (xy 375.213535 -238.531356) (xy 375.164142 -238.547404)
			(xy 375.112847 -238.555529) (xy 375.060913 -238.555529) (xy 375.009618 -238.547404) (xy 374.960225 -238.531356)
			(xy 374.913951 -238.507778) (xy 374.871935 -238.477252) (xy 374.835212 -238.440529) (xy 374.804686 -238.398513)
			(xy 374.781108 -238.352239) (xy 374.76506 -238.302846) (xy 374.756935 -238.251551) (xy 374.477279 -238.251551)
			(xy 374.469154 -238.302846) (xy 374.453106 -238.352239) (xy 374.429528 -238.398513) (xy 374.399002 -238.440529)
			(xy 374.362279 -238.477252) (xy 374.320263 -238.507778) (xy 374.273989 -238.531356) (xy 374.224596 -238.547404)
			(xy 374.173301 -238.555529) (xy 374.121367 -238.555529) (xy 374.070072 -238.547404) (xy 374.020679 -238.531356)
			(xy 373.974405 -238.507778) (xy 373.932389 -238.477252) (xy 373.895666 -238.440529) (xy 373.86514 -238.398513)
			(xy 373.841562 -238.352239) (xy 373.825514 -238.302846) (xy 373.817389 -238.251551) (xy 373.537225 -238.251551)
			(xy 373.5291 -238.302846) (xy 373.513052 -238.352239) (xy 373.489474 -238.398513) (xy 373.458948 -238.440529)
			(xy 373.422225 -238.477252) (xy 373.380209 -238.507778) (xy 373.333935 -238.531356) (xy 373.284542 -238.547404)
			(xy 373.233247 -238.555529) (xy 373.181313 -238.555529) (xy 373.130018 -238.547404) (xy 373.080625 -238.531356)
			(xy 373.034351 -238.507778) (xy 372.992335 -238.477252) (xy 372.955612 -238.440529) (xy 372.925086 -238.398513)
			(xy 372.901508 -238.352239) (xy 372.88546 -238.302846) (xy 372.877335 -238.251551) (xy 372.597425 -238.251551)
			(xy 372.5893 -238.302846) (xy 372.573252 -238.352239) (xy 372.549674 -238.398513) (xy 372.519148 -238.440529)
			(xy 372.482425 -238.477252) (xy 372.440409 -238.507778) (xy 372.394135 -238.531356) (xy 372.344742 -238.547404)
			(xy 372.293447 -238.555529) (xy 372.241513 -238.555529) (xy 372.190218 -238.547404) (xy 372.140825 -238.531356)
			(xy 372.094551 -238.507778) (xy 372.052535 -238.477252) (xy 372.015812 -238.440529) (xy 371.985286 -238.398513)
			(xy 371.961708 -238.352239) (xy 371.94566 -238.302846) (xy 371.937535 -238.251551) (xy 371.657625 -238.251551)
			(xy 371.6495 -238.302846) (xy 371.633452 -238.352239) (xy 371.609874 -238.398513) (xy 371.579348 -238.440529)
			(xy 371.542625 -238.477252) (xy 371.500609 -238.507778) (xy 371.454335 -238.531356) (xy 371.404942 -238.547404)
			(xy 371.353647 -238.555529) (xy 371.301713 -238.555529) (xy 371.250418 -238.547404) (xy 371.201025 -238.531356)
			(xy 371.154751 -238.507778) (xy 371.112735 -238.477252) (xy 371.076012 -238.440529) (xy 371.045486 -238.398513)
			(xy 371.021908 -238.352239) (xy 371.00586 -238.302846) (xy 370.997735 -238.251551) (xy 370.717825 -238.251551)
			(xy 370.7097 -238.302846) (xy 370.693652 -238.352239) (xy 370.670074 -238.398513) (xy 370.639548 -238.440529)
			(xy 370.602825 -238.477252) (xy 370.560809 -238.507778) (xy 370.514535 -238.531356) (xy 370.465142 -238.547404)
			(xy 370.413847 -238.555529) (xy 370.361913 -238.555529) (xy 370.310618 -238.547404) (xy 370.261225 -238.531356)
			(xy 370.214951 -238.507778) (xy 370.172935 -238.477252) (xy 370.136212 -238.440529) (xy 370.105686 -238.398513)
			(xy 370.082108 -238.352239) (xy 370.06606 -238.302846) (xy 370.057935 -238.251551) (xy 369.778025 -238.251551)
			(xy 369.7699 -238.302846) (xy 369.753852 -238.352239) (xy 369.730274 -238.398513) (xy 369.699748 -238.440529)
			(xy 369.663025 -238.477252) (xy 369.621009 -238.507778) (xy 369.574735 -238.531356) (xy 369.525342 -238.547404)
			(xy 369.474047 -238.555529) (xy 369.422113 -238.555529) (xy 369.370818 -238.547404) (xy 369.321425 -238.531356)
			(xy 369.275151 -238.507778) (xy 369.233135 -238.477252) (xy 369.196412 -238.440529) (xy 369.165886 -238.398513)
			(xy 369.142308 -238.352239) (xy 369.12626 -238.302846) (xy 369.118135 -238.251551) (xy 362.259625 -238.251551)
			(xy 362.2515 -238.302846) (xy 362.235452 -238.352239) (xy 362.211874 -238.398513) (xy 362.181348 -238.440529)
			(xy 362.144625 -238.477252) (xy 362.102609 -238.507778) (xy 362.056335 -238.531356) (xy 362.006942 -238.547404)
			(xy 361.955647 -238.555529) (xy 361.903713 -238.555529) (xy 361.852418 -238.547404) (xy 361.803025 -238.531356)
			(xy 361.756751 -238.507778) (xy 361.714735 -238.477252) (xy 361.678012 -238.440529) (xy 361.647486 -238.398513)
			(xy 361.623908 -238.352239) (xy 361.60786 -238.302846) (xy 361.599735 -238.251551) (xy 361.319825 -238.251551)
			(xy 361.3117 -238.302846) (xy 361.295652 -238.352239) (xy 361.272074 -238.398513) (xy 361.241548 -238.440529)
			(xy 361.204825 -238.477252) (xy 361.162809 -238.507778) (xy 361.116535 -238.531356) (xy 361.067142 -238.547404)
			(xy 361.015847 -238.555529) (xy 360.963913 -238.555529) (xy 360.912618 -238.547404) (xy 360.863225 -238.531356)
			(xy 360.816951 -238.507778) (xy 360.774935 -238.477252) (xy 360.738212 -238.440529) (xy 360.707686 -238.398513)
			(xy 360.684108 -238.352239) (xy 360.66806 -238.302846) (xy 360.659935 -238.251551) (xy 360.380025 -238.251551)
			(xy 360.3719 -238.302846) (xy 360.355852 -238.352239) (xy 360.332274 -238.398513) (xy 360.301748 -238.440529)
			(xy 360.265025 -238.477252) (xy 360.223009 -238.507778) (xy 360.176735 -238.531356) (xy 360.127342 -238.547404)
			(xy 360.076047 -238.555529) (xy 360.024113 -238.555529) (xy 359.972818 -238.547404) (xy 359.923425 -238.531356)
			(xy 359.877151 -238.507778) (xy 359.835135 -238.477252) (xy 359.798412 -238.440529) (xy 359.767886 -238.398513)
			(xy 359.744308 -238.352239) (xy 359.72826 -238.302846) (xy 359.720135 -238.251551) (xy 359.440225 -238.251551)
			(xy 359.4321 -238.302846) (xy 359.416052 -238.352239) (xy 359.392474 -238.398513) (xy 359.361948 -238.440529)
			(xy 359.325225 -238.477252) (xy 359.283209 -238.507778) (xy 359.236935 -238.531356) (xy 359.187542 -238.547404)
			(xy 359.136247 -238.555529) (xy 359.084313 -238.555529) (xy 359.033018 -238.547404) (xy 358.983625 -238.531356)
			(xy 358.937351 -238.507778) (xy 358.895335 -238.477252) (xy 358.858612 -238.440529) (xy 358.828086 -238.398513)
			(xy 358.804508 -238.352239) (xy 358.78846 -238.302846) (xy 358.780335 -238.251551) (xy 358.500425 -238.251551)
			(xy 358.4923 -238.302846) (xy 358.476252 -238.352239) (xy 358.452674 -238.398513) (xy 358.422148 -238.440529)
			(xy 358.385425 -238.477252) (xy 358.343409 -238.507778) (xy 358.297135 -238.531356) (xy 358.247742 -238.547404)
			(xy 358.196447 -238.555529) (xy 358.144513 -238.555529) (xy 358.093218 -238.547404) (xy 358.043825 -238.531356)
			(xy 357.997551 -238.507778) (xy 357.955535 -238.477252) (xy 357.918812 -238.440529) (xy 357.888286 -238.398513)
			(xy 357.864708 -238.352239) (xy 357.84866 -238.302846) (xy 357.840535 -238.251551) (xy 357.560655 -238.251551)
			(xy 357.560655 -238.251569) (xy 357.55253 -238.302868) (xy 357.53648 -238.352263) (xy 357.512899 -238.39854)
			(xy 357.48237 -238.440558) (xy 357.445643 -238.477283) (xy 357.403623 -238.50781) (xy 357.357345 -238.531387)
			(xy 357.307948 -238.547435) (xy 357.256649 -238.555557) (xy 357.23068 -238.556038) (xy 357.205879 -238.555599)
			(xy 357.156832 -238.548197) (xy 357.109442 -238.533547) (xy 357.064775 -238.511979) (xy 357.023833 -238.483976)
			(xy 356.987537 -238.450168) (xy 356.956701 -238.411315) (xy 356.932019 -238.36829) (xy 356.914046 -238.322058)
			(xy 356.903184 -238.27366) (xy 356.900988 -238.248952) (xy 356.89948 -238.235004) (xy 356.889997 -238.208617)
			(xy 356.873692 -238.185806) (xy 356.851795 -238.168293) (xy 356.825959 -238.1574) (xy 356.798134 -238.153948)
			(xy 356.770419 -238.158198) (xy 356.757478 -238.163608) (xy 356.73583 -238.173101) (xy 356.690485 -238.18645)
			(xy 356.643699 -238.193183) (xy 356.620064 -238.19358) (xy 356.594101 -238.193016) (xy 356.542814 -238.184888)
			(xy 356.49343 -238.168837) (xy 356.447165 -238.14526) (xy 356.405157 -238.114735) (xy 356.368441 -238.078015)
			(xy 356.337922 -238.036004) (xy 356.314349 -237.989737) (xy 356.298304 -237.940351) (xy 356.290181 -237.889063)
			(xy 351.077681 -237.889063) (xy 351.065592 -237.90275) (xy 351.055762 -237.914217) (xy 351.042755 -237.941463)
			(xy 351.038294 -237.971322) (xy 351.042769 -238.00118) (xy 351.055787 -238.02842) (xy 351.065592 -238.03991)
			(xy 351.08186 -238.058273) (xy 351.109303 -238.098937) (xy 351.130429 -238.143213) (xy 351.144772 -238.190127)
			(xy 351.152018 -238.238647) (xy 351.15246 -238.263176) (xy 351.15246 -238.26343) (xy 351.151951 -238.289397)
			(xy 351.143826 -238.340692) (xy 351.127778 -238.390085) (xy 351.1042 -238.436359) (xy 351.073674 -238.478375)
			(xy 351.036951 -238.515098) (xy 350.994935 -238.545624) (xy 350.948661 -238.569202) (xy 350.899268 -238.58525)
			(xy 350.847973 -238.593375) (xy 350.796039 -238.593375) (xy 350.744744 -238.58525) (xy 350.695351 -238.569202)
			(xy 350.649077 -238.545624) (xy 350.607061 -238.515098) (xy 350.570338 -238.478375) (xy 350.539812 -238.436359)
			(xy 350.516234 -238.390085) (xy 350.500186 -238.340692) (xy 350.492061 -238.289397) (xy 350.491552 -238.26343)
			(xy 350.491552 -238.263176) (xy 350.492002 -238.238649) (xy 350.499267 -238.190137) (xy 350.51362 -238.14323)
			(xy 350.534745 -238.098959) (xy 350.562179 -238.058294) (xy 350.57842 -238.03991) (xy 350.58819 -238.028396)
			(xy 350.601202 -238.001167) (xy 350.605674 -237.971322) (xy 350.601215 -237.941475) (xy 350.588215 -237.914241)
			(xy 350.57842 -237.90275) (xy 350.560213 -237.882081) (xy 350.530235 -237.835876) (xy 350.508341 -237.785336)
			(xy 350.501204 -237.758732) (xy 350.497469 -237.745709) (xy 350.484305 -237.722048) (xy 350.465375 -237.702687)
			(xy 350.442017 -237.688994) (xy 350.415877 -237.681933) (xy 350.3888 -237.682003) (xy 350.362697 -237.689199)
			(xy 350.350836 -237.69574) (xy 350.32515 -237.71021) (xy 350.269915 -237.730803) (xy 350.211908 -237.741295)
			(xy 350.182434 -237.741968) (xy 350.156464 -237.74146) (xy 350.105163 -237.733339) (xy 350.055764 -237.717293)
			(xy 350.009484 -237.693716) (xy 349.967462 -237.663189) (xy 349.930733 -237.626464) (xy 349.900202 -237.584445)
			(xy 349.87662 -237.538167) (xy 349.860569 -237.48877) (xy 349.852443 -237.43747) (xy 349.572579 -237.43747)
			(xy 349.572579 -237.437481) (xy 349.564454 -237.488776) (xy 349.548406 -237.538169) (xy 349.524828 -237.584443)
			(xy 349.494302 -237.626459) (xy 349.457579 -237.663182) (xy 349.415563 -237.693708) (xy 349.369289 -237.717286)
			(xy 349.319896 -237.733334) (xy 349.268601 -237.741459) (xy 349.216667 -237.741459) (xy 349.165372 -237.733334)
			(xy 349.115979 -237.717286) (xy 349.069705 -237.693708) (xy 349.027689 -237.663182) (xy 348.990966 -237.626459)
			(xy 348.96044 -237.584443) (xy 348.936862 -237.538169) (xy 348.920814 -237.488776) (xy 348.912689 -237.437481)
			(xy 348.632779 -237.437481) (xy 348.624654 -237.488776) (xy 348.608606 -237.538169) (xy 348.585028 -237.584443)
			(xy 348.554502 -237.626459) (xy 348.517779 -237.663182) (xy 348.475763 -237.693708) (xy 348.429489 -237.717286)
			(xy 348.380096 -237.733334) (xy 348.328801 -237.741459) (xy 348.276867 -237.741459) (xy 348.225572 -237.733334)
			(xy 348.176179 -237.717286) (xy 348.129905 -237.693708) (xy 348.087889 -237.663182) (xy 348.051166 -237.626459)
			(xy 348.02064 -237.584443) (xy 347.997062 -237.538169) (xy 347.981014 -237.488776) (xy 347.972889 -237.437481)
			(xy 347.692979 -237.437481) (xy 347.684854 -237.488776) (xy 347.668806 -237.538169) (xy 347.645228 -237.584443)
			(xy 347.614702 -237.626459) (xy 347.577979 -237.663182) (xy 347.535963 -237.693708) (xy 347.489689 -237.717286)
			(xy 347.440296 -237.733334) (xy 347.389001 -237.741459) (xy 347.337067 -237.741459) (xy 347.285772 -237.733334)
			(xy 347.236379 -237.717286) (xy 347.190105 -237.693708) (xy 347.148089 -237.663182) (xy 347.111366 -237.626459)
			(xy 347.08084 -237.584443) (xy 347.057262 -237.538169) (xy 347.041214 -237.488776) (xy 347.033089 -237.437481)
			(xy 346.752925 -237.437481) (xy 346.7448 -237.488776) (xy 346.728752 -237.538169) (xy 346.705174 -237.584443)
			(xy 346.674648 -237.626459) (xy 346.637925 -237.663182) (xy 346.595909 -237.693708) (xy 346.549635 -237.717286)
			(xy 346.500242 -237.733334) (xy 346.448947 -237.741459) (xy 346.397013 -237.741459) (xy 346.345718 -237.733334)
			(xy 346.296325 -237.717286) (xy 346.250051 -237.693708) (xy 346.208035 -237.663182) (xy 346.171312 -237.626459)
			(xy 346.140786 -237.584443) (xy 346.117208 -237.538169) (xy 346.10116 -237.488776) (xy 346.093035 -237.437481)
			(xy 345.813379 -237.437481) (xy 345.805254 -237.488776) (xy 345.789206 -237.538169) (xy 345.765628 -237.584443)
			(xy 345.735102 -237.626459) (xy 345.698379 -237.663182) (xy 345.656363 -237.693708) (xy 345.610089 -237.717286)
			(xy 345.560696 -237.733334) (xy 345.509401 -237.741459) (xy 345.457467 -237.741459) (xy 345.406172 -237.733334)
			(xy 345.356779 -237.717286) (xy 345.310505 -237.693708) (xy 345.268489 -237.663182) (xy 345.231766 -237.626459)
			(xy 345.20124 -237.584443) (xy 345.177662 -237.538169) (xy 345.161614 -237.488776) (xy 345.153489 -237.437481)
			(xy 344.873579 -237.437481) (xy 344.865454 -237.488776) (xy 344.849406 -237.538169) (xy 344.825828 -237.584443)
			(xy 344.795302 -237.626459) (xy 344.758579 -237.663182) (xy 344.716563 -237.693708) (xy 344.670289 -237.717286)
			(xy 344.620896 -237.733334) (xy 344.569601 -237.741459) (xy 344.517667 -237.741459) (xy 344.466372 -237.733334)
			(xy 344.416979 -237.717286) (xy 344.370705 -237.693708) (xy 344.328689 -237.663182) (xy 344.291966 -237.626459)
			(xy 344.26144 -237.584443) (xy 344.237862 -237.538169) (xy 344.221814 -237.488776) (xy 344.213689 -237.437481)
			(xy 343.933779 -237.437481) (xy 343.925654 -237.488776) (xy 343.909606 -237.538169) (xy 343.886028 -237.584443)
			(xy 343.855502 -237.626459) (xy 343.818779 -237.663182) (xy 343.776763 -237.693708) (xy 343.730489 -237.717286)
			(xy 343.681096 -237.733334) (xy 343.629801 -237.741459) (xy 343.577867 -237.741459) (xy 343.526572 -237.733334)
			(xy 343.477179 -237.717286) (xy 343.430905 -237.693708) (xy 343.388889 -237.663182) (xy 343.352166 -237.626459)
			(xy 343.32164 -237.584443) (xy 343.298062 -237.538169) (xy 343.282014 -237.488776) (xy 343.273889 -237.437481)
			(xy 342.993979 -237.437481) (xy 342.985854 -237.488776) (xy 342.969806 -237.538169) (xy 342.946228 -237.584443)
			(xy 342.915702 -237.626459) (xy 342.878979 -237.663182) (xy 342.836963 -237.693708) (xy 342.790689 -237.717286)
			(xy 342.741296 -237.733334) (xy 342.690001 -237.741459) (xy 342.638067 -237.741459) (xy 342.586772 -237.733334)
			(xy 342.537379 -237.717286) (xy 342.491105 -237.693708) (xy 342.449089 -237.663182) (xy 342.412366 -237.626459)
			(xy 342.38184 -237.584443) (xy 342.358262 -237.538169) (xy 342.342214 -237.488776) (xy 342.334089 -237.437481)
			(xy 342.054179 -237.437481) (xy 342.046054 -237.488776) (xy 342.030006 -237.538169) (xy 342.006428 -237.584443)
			(xy 341.975902 -237.626459) (xy 341.939179 -237.663182) (xy 341.897163 -237.693708) (xy 341.850889 -237.717286)
			(xy 341.801496 -237.733334) (xy 341.750201 -237.741459) (xy 341.698267 -237.741459) (xy 341.646972 -237.733334)
			(xy 341.597579 -237.717286) (xy 341.551305 -237.693708) (xy 341.509289 -237.663182) (xy 341.472566 -237.626459)
			(xy 341.44204 -237.584443) (xy 341.418462 -237.538169) (xy 341.402414 -237.488776) (xy 341.394289 -237.437481)
			(xy 341.114379 -237.437481) (xy 341.106254 -237.488776) (xy 341.090206 -237.538169) (xy 341.066628 -237.584443)
			(xy 341.036102 -237.626459) (xy 340.999379 -237.663182) (xy 340.957363 -237.693708) (xy 340.911089 -237.717286)
			(xy 340.861696 -237.733334) (xy 340.810401 -237.741459) (xy 340.758467 -237.741459) (xy 340.707172 -237.733334)
			(xy 340.657779 -237.717286) (xy 340.611505 -237.693708) (xy 340.569489 -237.663182) (xy 340.532766 -237.626459)
			(xy 340.50224 -237.584443) (xy 340.478662 -237.538169) (xy 340.462614 -237.488776) (xy 340.454489 -237.437481)
			(xy 340.174611 -237.437481) (xy 340.174611 -237.437489) (xy 340.166479 -237.488827) (xy 340.150417 -237.538262)
			(xy 340.126818 -237.584574) (xy 340.096265 -237.626625) (xy 340.05951 -237.663378) (xy 340.017457 -237.693929)
			(xy 339.971143 -237.717524) (xy 339.921708 -237.733584) (xy 339.870369 -237.741712) (xy 339.84438 -237.742222)
			(xy 339.817456 -237.741693) (xy 339.764319 -237.732974) (xy 339.713294 -237.715769) (xy 339.665726 -237.690533)
			(xy 339.643974 -237.674658) (xy 339.637624 -237.669832) (xy 339.618574 -237.663228) (xy 339.609787 -237.660735)
			(xy 339.591554 -237.661515) (xy 339.583014 -237.664752) (xy 339.502496 -237.703614) (xy 339.494478 -237.708123)
			(xy 339.482134 -237.721738) (xy 339.475495 -237.738876) (xy 339.475064 -237.748064) (xy 339.475064 -237.875826)
			(xy 339.505036 -237.921292) (xy 339.517736 -237.927388) (xy 339.541453 -237.93935) (xy 339.585058 -237.969679)
			(xy 339.623255 -238.006588) (xy 339.655062 -238.049126) (xy 339.679662 -238.096201) (xy 339.696422 -238.146603)
			(xy 339.704912 -238.199035) (xy 339.704913 -238.251551) (xy 339.984335 -238.251551) (xy 339.984335 -238.199617)
			(xy 339.99246 -238.148322) (xy 340.008508 -238.098929) (xy 340.032086 -238.052655) (xy 340.062612 -238.010639)
			(xy 340.099335 -237.973916) (xy 340.141351 -237.94339) (xy 340.187625 -237.919812) (xy 340.237018 -237.903764)
			(xy 340.288313 -237.895639) (xy 340.340247 -237.895639) (xy 340.391542 -237.903764) (xy 340.440935 -237.919812)
			(xy 340.487209 -237.94339) (xy 340.529225 -237.973916) (xy 340.565948 -238.010639) (xy 340.596474 -238.052655)
			(xy 340.620052 -238.098929) (xy 340.6361 -238.148322) (xy 340.644225 -238.199617) (xy 340.644734 -238.225584)
			(xy 340.644225 -238.251551) (xy 340.924135 -238.251551) (xy 340.924135 -238.199617) (xy 340.93226 -238.148322)
			(xy 340.948308 -238.098929) (xy 340.971886 -238.052655) (xy 341.002412 -238.010639) (xy 341.039135 -237.973916)
			(xy 341.081151 -237.94339) (xy 341.127425 -237.919812) (xy 341.176818 -237.903764) (xy 341.228113 -237.895639)
			(xy 341.280047 -237.895639) (xy 341.331342 -237.903764) (xy 341.380735 -237.919812) (xy 341.427009 -237.94339)
			(xy 341.469025 -237.973916) (xy 341.505748 -238.010639) (xy 341.536274 -238.052655) (xy 341.559852 -238.098929)
			(xy 341.5759 -238.148322) (xy 341.584025 -238.199617) (xy 341.584534 -238.225584) (xy 341.584025 -238.251551)
			(xy 341.863935 -238.251551) (xy 341.863935 -238.199617) (xy 341.87206 -238.148322) (xy 341.888108 -238.098929)
			(xy 341.911686 -238.052655) (xy 341.942212 -238.010639) (xy 341.978935 -237.973916) (xy 342.020951 -237.94339)
			(xy 342.067225 -237.919812) (xy 342.116618 -237.903764) (xy 342.167913 -237.895639) (xy 342.219847 -237.895639)
			(xy 342.271142 -237.903764) (xy 342.320535 -237.919812) (xy 342.366809 -237.94339) (xy 342.408825 -237.973916)
			(xy 342.445548 -238.010639) (xy 342.476074 -238.052655) (xy 342.499652 -238.098929) (xy 342.5157 -238.148322)
			(xy 342.523825 -238.199617) (xy 342.524334 -238.225584) (xy 342.523825 -238.251551) (xy 342.803735 -238.251551)
			(xy 342.803735 -238.199617) (xy 342.81186 -238.148322) (xy 342.827908 -238.098929) (xy 342.851486 -238.052655)
			(xy 342.882012 -238.010639) (xy 342.918735 -237.973916) (xy 342.960751 -237.94339) (xy 343.007025 -237.919812)
			(xy 343.056418 -237.903764) (xy 343.107713 -237.895639) (xy 343.159647 -237.895639) (xy 343.210942 -237.903764)
			(xy 343.260335 -237.919812) (xy 343.306609 -237.94339) (xy 343.348625 -237.973916) (xy 343.385348 -238.010639)
			(xy 343.415874 -238.052655) (xy 343.439452 -238.098929) (xy 343.4555 -238.148322) (xy 343.463625 -238.199617)
			(xy 343.464134 -238.225584) (xy 343.463625 -238.251551) (xy 343.743535 -238.251551) (xy 343.743535 -238.199617)
			(xy 343.75166 -238.148322) (xy 343.767708 -238.098929) (xy 343.791286 -238.052655) (xy 343.821812 -238.010639)
			(xy 343.858535 -237.973916) (xy 343.900551 -237.94339) (xy 343.946825 -237.919812) (xy 343.996218 -237.903764)
			(xy 344.047513 -237.895639) (xy 344.099447 -237.895639) (xy 344.150742 -237.903764) (xy 344.200135 -237.919812)
			(xy 344.246409 -237.94339) (xy 344.288425 -237.973916) (xy 344.325148 -238.010639) (xy 344.355674 -238.052655)
			(xy 344.379252 -238.098929) (xy 344.3953 -238.148322) (xy 344.403425 -238.199617) (xy 344.403934 -238.225584)
			(xy 344.403425 -238.251551) (xy 344.683335 -238.251551) (xy 344.683335 -238.199617) (xy 344.69146 -238.148322)
			(xy 344.707508 -238.098929) (xy 344.731086 -238.052655) (xy 344.761612 -238.010639) (xy 344.798335 -237.973916)
			(xy 344.840351 -237.94339) (xy 344.886625 -237.919812) (xy 344.936018 -237.903764) (xy 344.987313 -237.895639)
			(xy 345.039247 -237.895639) (xy 345.090542 -237.903764) (xy 345.139935 -237.919812) (xy 345.186209 -237.94339)
			(xy 345.228225 -237.973916) (xy 345.264948 -238.010639) (xy 345.295474 -238.052655) (xy 345.319052 -238.098929)
			(xy 345.3351 -238.148322) (xy 345.343225 -238.199617) (xy 345.343734 -238.225584) (xy 345.343225 -238.251551)
			(xy 345.623389 -238.251551) (xy 345.623389 -238.199617) (xy 345.631514 -238.148322) (xy 345.647562 -238.098929)
			(xy 345.67114 -238.052655) (xy 345.701666 -238.010639) (xy 345.738389 -237.973916) (xy 345.780405 -237.94339)
			(xy 345.826679 -237.919812) (xy 345.876072 -237.903764) (xy 345.927367 -237.895639) (xy 345.979301 -237.895639)
			(xy 346.030596 -237.903764) (xy 346.079989 -237.919812) (xy 346.126263 -237.94339) (xy 346.168279 -237.973916)
			(xy 346.205002 -238.010639) (xy 346.235528 -238.052655) (xy 346.259106 -238.098929) (xy 346.275154 -238.148322)
			(xy 346.283279 -238.199617) (xy 346.283788 -238.225584) (xy 346.283279 -238.251551) (xy 346.562935 -238.251551)
			(xy 346.562935 -238.199617) (xy 346.57106 -238.148322) (xy 346.587108 -238.098929) (xy 346.610686 -238.052655)
			(xy 346.641212 -238.010639) (xy 346.677935 -237.973916) (xy 346.719951 -237.94339) (xy 346.766225 -237.919812)
			(xy 346.815618 -237.903764) (xy 346.866913 -237.895639) (xy 346.918847 -237.895639) (xy 346.970142 -237.903764)
			(xy 347.019535 -237.919812) (xy 347.065809 -237.94339) (xy 347.107825 -237.973916) (xy 347.144548 -238.010639)
			(xy 347.175074 -238.052655) (xy 347.198652 -238.098929) (xy 347.2147 -238.148322) (xy 347.222825 -238.199617)
			(xy 347.223334 -238.225584) (xy 347.222825 -238.251551) (xy 347.502735 -238.251551) (xy 347.502735 -238.199617)
			(xy 347.51086 -238.148322) (xy 347.526908 -238.098929) (xy 347.550486 -238.052655) (xy 347.581012 -238.010639)
			(xy 347.617735 -237.973916) (xy 347.659751 -237.94339) (xy 347.706025 -237.919812) (xy 347.755418 -237.903764)
			(xy 347.806713 -237.895639) (xy 347.858647 -237.895639) (xy 347.909942 -237.903764) (xy 347.959335 -237.919812)
			(xy 348.005609 -237.94339) (xy 348.047625 -237.973916) (xy 348.084348 -238.010639) (xy 348.114874 -238.052655)
			(xy 348.138452 -238.098929) (xy 348.1545 -238.148322) (xy 348.162625 -238.199617) (xy 348.163134 -238.225584)
			(xy 348.162625 -238.251551) (xy 348.442535 -238.251551) (xy 348.442535 -238.199617) (xy 348.45066 -238.148322)
			(xy 348.466708 -238.098929) (xy 348.490286 -238.052655) (xy 348.520812 -238.010639) (xy 348.557535 -237.973916)
			(xy 348.599551 -237.94339) (xy 348.645825 -237.919812) (xy 348.695218 -237.903764) (xy 348.746513 -237.895639)
			(xy 348.798447 -237.895639) (xy 348.849742 -237.903764) (xy 348.899135 -237.919812) (xy 348.945409 -237.94339)
			(xy 348.987425 -237.973916) (xy 349.024148 -238.010639) (xy 349.054674 -238.052655) (xy 349.078252 -238.098929)
			(xy 349.0943 -238.148322) (xy 349.102425 -238.199617) (xy 349.102934 -238.225584) (xy 349.102425 -238.251551)
			(xy 349.382335 -238.251551) (xy 349.382335 -238.199617) (xy 349.39046 -238.148322) (xy 349.406508 -238.098929)
			(xy 349.430086 -238.052655) (xy 349.460612 -238.010639) (xy 349.497335 -237.973916) (xy 349.539351 -237.94339)
			(xy 349.585625 -237.919812) (xy 349.635018 -237.903764) (xy 349.686313 -237.895639) (xy 349.738247 -237.895639)
			(xy 349.789542 -237.903764) (xy 349.838935 -237.919812) (xy 349.885209 -237.94339) (xy 349.927225 -237.973916)
			(xy 349.963948 -238.010639) (xy 349.994474 -238.052655) (xy 350.018052 -238.098929) (xy 350.0341 -238.148322)
			(xy 350.042225 -238.199617) (xy 350.042734 -238.225584) (xy 350.042225 -238.251551) (xy 350.0341 -238.302846)
			(xy 350.018052 -238.352239) (xy 349.994474 -238.398513) (xy 349.963948 -238.440529) (xy 349.927225 -238.477252)
			(xy 349.885209 -238.507778) (xy 349.838935 -238.531356) (xy 349.789542 -238.547404) (xy 349.738247 -238.555529)
			(xy 349.686313 -238.555529) (xy 349.635018 -238.547404) (xy 349.585625 -238.531356) (xy 349.539351 -238.507778)
			(xy 349.497335 -238.477252) (xy 349.460612 -238.440529) (xy 349.430086 -238.398513) (xy 349.406508 -238.352239)
			(xy 349.39046 -238.302846) (xy 349.382335 -238.251551) (xy 349.102425 -238.251551) (xy 349.0943 -238.302846)
			(xy 349.078252 -238.352239) (xy 349.054674 -238.398513) (xy 349.024148 -238.440529) (xy 348.987425 -238.477252)
			(xy 348.945409 -238.507778) (xy 348.899135 -238.531356) (xy 348.849742 -238.547404) (xy 348.798447 -238.555529)
			(xy 348.746513 -238.555529) (xy 348.695218 -238.547404) (xy 348.645825 -238.531356) (xy 348.599551 -238.507778)
			(xy 348.557535 -238.477252) (xy 348.520812 -238.440529) (xy 348.490286 -238.398513) (xy 348.466708 -238.352239)
			(xy 348.45066 -238.302846) (xy 348.442535 -238.251551) (xy 348.162625 -238.251551) (xy 348.1545 -238.302846)
			(xy 348.138452 -238.352239) (xy 348.114874 -238.398513) (xy 348.084348 -238.440529) (xy 348.047625 -238.477252)
			(xy 348.005609 -238.507778) (xy 347.959335 -238.531356) (xy 347.909942 -238.547404) (xy 347.858647 -238.555529)
			(xy 347.806713 -238.555529) (xy 347.755418 -238.547404) (xy 347.706025 -238.531356) (xy 347.659751 -238.507778)
			(xy 347.617735 -238.477252) (xy 347.581012 -238.440529) (xy 347.550486 -238.398513) (xy 347.526908 -238.352239)
			(xy 347.51086 -238.302846) (xy 347.502735 -238.251551) (xy 347.222825 -238.251551) (xy 347.2147 -238.302846)
			(xy 347.198652 -238.352239) (xy 347.175074 -238.398513) (xy 347.144548 -238.440529) (xy 347.107825 -238.477252)
			(xy 347.065809 -238.507778) (xy 347.019535 -238.531356) (xy 346.970142 -238.547404) (xy 346.918847 -238.555529)
			(xy 346.866913 -238.555529) (xy 346.815618 -238.547404) (xy 346.766225 -238.531356) (xy 346.719951 -238.507778)
			(xy 346.677935 -238.477252) (xy 346.641212 -238.440529) (xy 346.610686 -238.398513) (xy 346.587108 -238.352239)
			(xy 346.57106 -238.302846) (xy 346.562935 -238.251551) (xy 346.283279 -238.251551) (xy 346.275154 -238.302846)
			(xy 346.259106 -238.352239) (xy 346.235528 -238.398513) (xy 346.205002 -238.440529) (xy 346.168279 -238.477252)
			(xy 346.126263 -238.507778) (xy 346.079989 -238.531356) (xy 346.030596 -238.547404) (xy 345.979301 -238.555529)
			(xy 345.927367 -238.555529) (xy 345.876072 -238.547404) (xy 345.826679 -238.531356) (xy 345.780405 -238.507778)
			(xy 345.738389 -238.477252) (xy 345.701666 -238.440529) (xy 345.67114 -238.398513) (xy 345.647562 -238.352239)
			(xy 345.631514 -238.302846) (xy 345.623389 -238.251551) (xy 345.343225 -238.251551) (xy 345.3351 -238.302846)
			(xy 345.319052 -238.352239) (xy 345.295474 -238.398513) (xy 345.264948 -238.440529) (xy 345.228225 -238.477252)
			(xy 345.186209 -238.507778) (xy 345.139935 -238.531356) (xy 345.090542 -238.547404) (xy 345.039247 -238.555529)
			(xy 344.987313 -238.555529) (xy 344.936018 -238.547404) (xy 344.886625 -238.531356) (xy 344.840351 -238.507778)
			(xy 344.798335 -238.477252) (xy 344.761612 -238.440529) (xy 344.731086 -238.398513) (xy 344.707508 -238.352239)
			(xy 344.69146 -238.302846) (xy 344.683335 -238.251551) (xy 344.403425 -238.251551) (xy 344.3953 -238.302846)
			(xy 344.379252 -238.352239) (xy 344.355674 -238.398513) (xy 344.325148 -238.440529) (xy 344.288425 -238.477252)
			(xy 344.246409 -238.507778) (xy 344.200135 -238.531356) (xy 344.150742 -238.547404) (xy 344.099447 -238.555529)
			(xy 344.047513 -238.555529) (xy 343.996218 -238.547404) (xy 343.946825 -238.531356) (xy 343.900551 -238.507778)
			(xy 343.858535 -238.477252) (xy 343.821812 -238.440529) (xy 343.791286 -238.398513) (xy 343.767708 -238.352239)
			(xy 343.75166 -238.302846) (xy 343.743535 -238.251551) (xy 343.463625 -238.251551) (xy 343.4555 -238.302846)
			(xy 343.439452 -238.352239) (xy 343.415874 -238.398513) (xy 343.385348 -238.440529) (xy 343.348625 -238.477252)
			(xy 343.306609 -238.507778) (xy 343.260335 -238.531356) (xy 343.210942 -238.547404) (xy 343.159647 -238.555529)
			(xy 343.107713 -238.555529) (xy 343.056418 -238.547404) (xy 343.007025 -238.531356) (xy 342.960751 -238.507778)
			(xy 342.918735 -238.477252) (xy 342.882012 -238.440529) (xy 342.851486 -238.398513) (xy 342.827908 -238.352239)
			(xy 342.81186 -238.302846) (xy 342.803735 -238.251551) (xy 342.523825 -238.251551) (xy 342.5157 -238.302846)
			(xy 342.499652 -238.352239) (xy 342.476074 -238.398513) (xy 342.445548 -238.440529) (xy 342.408825 -238.477252)
			(xy 342.366809 -238.507778) (xy 342.320535 -238.531356) (xy 342.271142 -238.547404) (xy 342.219847 -238.555529)
			(xy 342.167913 -238.555529) (xy 342.116618 -238.547404) (xy 342.067225 -238.531356) (xy 342.020951 -238.507778)
			(xy 341.978935 -238.477252) (xy 341.942212 -238.440529) (xy 341.911686 -238.398513) (xy 341.888108 -238.352239)
			(xy 341.87206 -238.302846) (xy 341.863935 -238.251551) (xy 341.584025 -238.251551) (xy 341.5759 -238.302846)
			(xy 341.559852 -238.352239) (xy 341.536274 -238.398513) (xy 341.505748 -238.440529) (xy 341.469025 -238.477252)
			(xy 341.427009 -238.507778) (xy 341.380735 -238.531356) (xy 341.331342 -238.547404) (xy 341.280047 -238.555529)
			(xy 341.228113 -238.555529) (xy 341.176818 -238.547404) (xy 341.127425 -238.531356) (xy 341.081151 -238.507778)
			(xy 341.039135 -238.477252) (xy 341.002412 -238.440529) (xy 340.971886 -238.398513) (xy 340.948308 -238.352239)
			(xy 340.93226 -238.302846) (xy 340.924135 -238.251551) (xy 340.644225 -238.251551) (xy 340.6361 -238.302846)
			(xy 340.620052 -238.352239) (xy 340.596474 -238.398513) (xy 340.565948 -238.440529) (xy 340.529225 -238.477252)
			(xy 340.487209 -238.507778) (xy 340.440935 -238.531356) (xy 340.391542 -238.547404) (xy 340.340247 -238.555529)
			(xy 340.288313 -238.555529) (xy 340.237018 -238.547404) (xy 340.187625 -238.531356) (xy 340.141351 -238.507778)
			(xy 340.099335 -238.477252) (xy 340.062612 -238.440529) (xy 340.032086 -238.398513) (xy 340.008508 -238.352239)
			(xy 339.99246 -238.302846) (xy 339.984335 -238.251551) (xy 339.704913 -238.251551) (xy 339.704913 -238.252151)
			(xy 339.696426 -238.304584) (xy 339.679667 -238.354986) (xy 339.655069 -238.402062) (xy 339.623264 -238.444602)
			(xy 339.585068 -238.481512) (xy 339.541465 -238.511843) (xy 339.517736 -238.52378) (xy 339.505036 -238.529876)
			(xy 339.475064 -238.575342) (xy 339.475064 -238.703104) (xy 339.475469 -238.712007) (xy 339.481721 -238.728685)
			(xy 339.493348 -238.742177) (xy 339.500972 -238.746792) (xy 339.584284 -238.78667) (xy 339.5923 -238.789567)
			(xy 339.609314 -238.790356) (xy 339.617558 -238.788194) (xy 339.638132 -238.780828) (xy 339.64118 -238.778796)
			(xy 339.644736 -238.776002) (xy 339.666443 -238.760193) (xy 339.713904 -238.735075) (xy 339.764796 -238.717945)
			(xy 339.817785 -238.709253) (xy 339.844634 -238.708692) (xy 339.870619 -238.709204) (xy 339.92195 -238.717339)
			(xy 339.971376 -238.733403) (xy 340.017681 -238.757001) (xy 340.059724 -238.787551) (xy 340.096471 -238.824302)
			(xy 340.127017 -238.866348) (xy 340.15061 -238.912656) (xy 340.166669 -238.962083) (xy 340.174799 -239.013415)
			(xy 340.174799 -239.065367) (xy 340.454489 -239.065367) (xy 340.454489 -239.013433) (xy 340.462614 -238.962138)
			(xy 340.478662 -238.912745) (xy 340.50224 -238.866471) (xy 340.532766 -238.824455) (xy 340.569489 -238.787732)
			(xy 340.611505 -238.757206) (xy 340.657779 -238.733628) (xy 340.707172 -238.71758) (xy 340.758467 -238.709455)
			(xy 340.810401 -238.709455) (xy 340.861696 -238.71758) (xy 340.911089 -238.733628) (xy 340.957363 -238.757206)
			(xy 340.999379 -238.787732) (xy 341.036102 -238.824455) (xy 341.066628 -238.866471) (xy 341.090206 -238.912745)
			(xy 341.106254 -238.962138) (xy 341.114379 -239.013433) (xy 341.114888 -239.0394) (xy 341.114379 -239.065367)
			(xy 341.394289 -239.065367) (xy 341.394289 -239.013433) (xy 341.402414 -238.962138) (xy 341.418462 -238.912745)
			(xy 341.44204 -238.866471) (xy 341.472566 -238.824455) (xy 341.509289 -238.787732) (xy 341.551305 -238.757206)
			(xy 341.597579 -238.733628) (xy 341.646972 -238.71758) (xy 341.698267 -238.709455) (xy 341.750201 -238.709455)
			(xy 341.801496 -238.71758) (xy 341.850889 -238.733628) (xy 341.897163 -238.757206) (xy 341.939179 -238.787732)
			(xy 341.975902 -238.824455) (xy 342.006428 -238.866471) (xy 342.030006 -238.912745) (xy 342.046054 -238.962138)
			(xy 342.054179 -239.013433) (xy 342.054688 -239.0394) (xy 342.054179 -239.065367) (xy 342.333835 -239.065367)
			(xy 342.333835 -239.013433) (xy 342.34196 -238.962138) (xy 342.358008 -238.912745) (xy 342.381586 -238.866471)
			(xy 342.412112 -238.824455) (xy 342.448835 -238.787732) (xy 342.490851 -238.757206) (xy 342.537125 -238.733628)
			(xy 342.586518 -238.71758) (xy 342.637813 -238.709455) (xy 342.689747 -238.709455) (xy 342.741042 -238.71758)
			(xy 342.790435 -238.733628) (xy 342.836709 -238.757206) (xy 342.878725 -238.787732) (xy 342.915448 -238.824455)
			(xy 342.945974 -238.866471) (xy 342.969552 -238.912745) (xy 342.9856 -238.962138) (xy 342.993725 -239.013433)
			(xy 342.994234 -239.0394) (xy 342.993725 -239.065367) (xy 343.273889 -239.065367) (xy 343.273889 -239.013433)
			(xy 343.282014 -238.962138) (xy 343.298062 -238.912745) (xy 343.32164 -238.866471) (xy 343.352166 -238.824455)
			(xy 343.388889 -238.787732) (xy 343.430905 -238.757206) (xy 343.477179 -238.733628) (xy 343.526572 -238.71758)
			(xy 343.577867 -238.709455) (xy 343.629801 -238.709455) (xy 343.681096 -238.71758) (xy 343.730489 -238.733628)
			(xy 343.776763 -238.757206) (xy 343.818779 -238.787732) (xy 343.855502 -238.824455) (xy 343.886028 -238.866471)
			(xy 343.909606 -238.912745) (xy 343.925654 -238.962138) (xy 343.933779 -239.013433) (xy 343.934288 -239.0394)
			(xy 343.933779 -239.065367) (xy 344.213689 -239.065367) (xy 344.213689 -239.013433) (xy 344.221814 -238.962138)
			(xy 344.237862 -238.912745) (xy 344.26144 -238.866471) (xy 344.291966 -238.824455) (xy 344.328689 -238.787732)
			(xy 344.370705 -238.757206) (xy 344.416979 -238.733628) (xy 344.466372 -238.71758) (xy 344.517667 -238.709455)
			(xy 344.569601 -238.709455) (xy 344.620896 -238.71758) (xy 344.670289 -238.733628) (xy 344.716563 -238.757206)
			(xy 344.758579 -238.787732) (xy 344.795302 -238.824455) (xy 344.825828 -238.866471) (xy 344.849406 -238.912745)
			(xy 344.865454 -238.962138) (xy 344.873579 -239.013433) (xy 344.874088 -239.0394) (xy 344.873579 -239.065367)
			(xy 345.153489 -239.065367) (xy 345.153489 -239.013433) (xy 345.161614 -238.962138) (xy 345.177662 -238.912745)
			(xy 345.20124 -238.866471) (xy 345.231766 -238.824455) (xy 345.268489 -238.787732) (xy 345.310505 -238.757206)
			(xy 345.356779 -238.733628) (xy 345.406172 -238.71758) (xy 345.457467 -238.709455) (xy 345.509401 -238.709455)
			(xy 345.560696 -238.71758) (xy 345.610089 -238.733628) (xy 345.656363 -238.757206) (xy 345.698379 -238.787732)
			(xy 345.735102 -238.824455) (xy 345.765628 -238.866471) (xy 345.789206 -238.912745) (xy 345.805254 -238.962138)
			(xy 345.813379 -239.013433) (xy 345.813888 -239.0394) (xy 345.813379 -239.065367) (xy 346.093289 -239.065367)
			(xy 346.093289 -239.013433) (xy 346.101414 -238.962138) (xy 346.117462 -238.912745) (xy 346.14104 -238.866471)
			(xy 346.171566 -238.824455) (xy 346.208289 -238.787732) (xy 346.250305 -238.757206) (xy 346.296579 -238.733628)
			(xy 346.345972 -238.71758) (xy 346.397267 -238.709455) (xy 346.449201 -238.709455) (xy 346.500496 -238.71758)
			(xy 346.549889 -238.733628) (xy 346.596163 -238.757206) (xy 346.638179 -238.787732) (xy 346.674902 -238.824455)
			(xy 346.705428 -238.866471) (xy 346.729006 -238.912745) (xy 346.745054 -238.962138) (xy 346.753179 -239.013433)
			(xy 346.753688 -239.0394) (xy 346.753179 -239.065367) (xy 347.033089 -239.065367) (xy 347.033089 -239.013433)
			(xy 347.041214 -238.962138) (xy 347.057262 -238.912745) (xy 347.08084 -238.866471) (xy 347.111366 -238.824455)
			(xy 347.148089 -238.787732) (xy 347.190105 -238.757206) (xy 347.236379 -238.733628) (xy 347.285772 -238.71758)
			(xy 347.337067 -238.709455) (xy 347.389001 -238.709455) (xy 347.440296 -238.71758) (xy 347.489689 -238.733628)
			(xy 347.535963 -238.757206) (xy 347.577979 -238.787732) (xy 347.614702 -238.824455) (xy 347.645228 -238.866471)
			(xy 347.668806 -238.912745) (xy 347.684854 -238.962138) (xy 347.692979 -239.013433) (xy 347.693488 -239.0394)
			(xy 347.692979 -239.065367) (xy 347.972889 -239.065367) (xy 347.972889 -239.013433) (xy 347.981014 -238.962138)
			(xy 347.997062 -238.912745) (xy 348.02064 -238.866471) (xy 348.051166 -238.824455) (xy 348.087889 -238.787732)
			(xy 348.129905 -238.757206) (xy 348.176179 -238.733628) (xy 348.225572 -238.71758) (xy 348.276867 -238.709455)
			(xy 348.328801 -238.709455) (xy 348.380096 -238.71758) (xy 348.429489 -238.733628) (xy 348.475763 -238.757206)
			(xy 348.517779 -238.787732) (xy 348.554502 -238.824455) (xy 348.585028 -238.866471) (xy 348.608606 -238.912745)
			(xy 348.624654 -238.962138) (xy 348.632779 -239.013433) (xy 348.633288 -239.0394) (xy 348.632779 -239.065367)
			(xy 348.912435 -239.065367) (xy 348.912435 -239.013433) (xy 348.92056 -238.962138) (xy 348.936608 -238.912745)
			(xy 348.960186 -238.866471) (xy 348.990712 -238.824455) (xy 349.027435 -238.787732) (xy 349.069451 -238.757206)
			(xy 349.115725 -238.733628) (xy 349.165118 -238.71758) (xy 349.216413 -238.709455) (xy 349.268347 -238.709455)
			(xy 349.319642 -238.71758) (xy 349.369035 -238.733628) (xy 349.415309 -238.757206) (xy 349.457325 -238.787732)
			(xy 349.494048 -238.824455) (xy 349.524574 -238.866471) (xy 349.548152 -238.912745) (xy 349.5642 -238.962138)
			(xy 349.572325 -239.013433) (xy 349.572834 -239.0394) (xy 349.572325 -239.065367) (xy 349.5642 -239.116662)
			(xy 349.548152 -239.166055) (xy 349.524574 -239.212329) (xy 349.494048 -239.254345) (xy 349.457325 -239.291068)
			(xy 349.419474 -239.318568) (xy 352.789467 -239.318568) (xy 352.789467 -239.266632) (xy 352.797592 -239.215335)
			(xy 352.813642 -239.165941) (xy 352.837222 -239.119667) (xy 352.867752 -239.077651) (xy 352.904478 -239.040928)
			(xy 352.946497 -239.010404) (xy 352.992775 -238.986828) (xy 353.04217 -238.970784) (xy 353.093468 -238.962664)
			(xy 353.119436 -238.962184) (xy 353.11969 -238.962184) (xy 353.144216 -238.962646) (xy 353.192728 -238.969907)
			(xy 353.239635 -238.984256) (xy 353.283907 -239.005379) (xy 353.324572 -239.032811) (xy 353.342956 -239.049052)
			(xy 353.354445 -239.058855) (xy 353.381682 -239.071869) (xy 353.411536 -239.076337) (xy 353.44139 -239.071869)
			(xy 353.468627 -239.058855) (xy 353.480116 -239.049052) (xy 353.498502 -239.032772) (xy 353.539211 -239.005305)
			(xy 353.583538 -238.98417) (xy 353.630507 -238.969832) (xy 353.679081 -238.962609) (xy 353.703636 -238.962184)
			(xy 353.728188 -238.962629) (xy 353.776755 -238.969868) (xy 353.823717 -238.98421) (xy 353.868041 -239.005341)
			(xy 353.908752 -239.032795) (xy 353.927156 -239.049052) (xy 353.938645 -239.058855) (xy 353.965882 -239.071869)
			(xy 353.995736 -239.076337) (xy 354.02559 -239.071869) (xy 354.052827 -239.058855) (xy 354.064316 -239.049052)
			(xy 354.082682 -239.032788) (xy 354.123345 -239.005343) (xy 354.16762 -238.984216) (xy 354.214534 -238.969872)
			(xy 354.263053 -238.962626) (xy 354.287582 -238.962184) (xy 354.287836 -238.962184) (xy 354.313804 -238.96262)
			(xy 354.365101 -238.97075) (xy 354.414494 -238.986803) (xy 354.460769 -239.010386) (xy 354.502784 -239.040916)
			(xy 354.539507 -239.077643) (xy 354.570033 -239.119662) (xy 354.59361 -239.165939) (xy 354.609659 -239.215334)
			(xy 354.617783 -239.266632) (xy 354.617783 -239.318568) (xy 354.609659 -239.369866) (xy 354.59361 -239.419261)
			(xy 354.570033 -239.465538) (xy 354.539507 -239.507557) (xy 354.502784 -239.544284) (xy 354.460769 -239.574814)
			(xy 354.414494 -239.598397) (xy 354.365101 -239.61445) (xy 354.313804 -239.62258) (xy 354.287836 -239.623092)
			(xy 354.287582 -239.623092) (xy 354.263055 -239.622653) (xy 354.214541 -239.615387) (xy 354.167634 -239.601033)
			(xy 354.123363 -239.579905) (xy 354.082699 -239.552467) (xy 354.064316 -239.536224) (xy 354.052827 -239.526421)
			(xy 354.02559 -239.513407) (xy 353.995736 -239.508939) (xy 353.965882 -239.513407) (xy 353.938645 -239.526421)
			(xy 353.927156 -239.536224) (xy 353.908752 -239.552482) (xy 353.868047 -239.57995) (xy 353.823723 -239.601088)
			(xy 353.776759 -239.615431) (xy 353.728189 -239.622662) (xy 353.703636 -239.623092) (xy 353.679083 -239.62267)
			(xy 353.630515 -239.615427) (xy 353.583553 -239.601079) (xy 353.539229 -239.579943) (xy 353.498519 -239.552483)
			(xy 353.480116 -239.536224) (xy 353.468627 -239.526421) (xy 353.44139 -239.513407) (xy 353.411536 -239.508939)
			(xy 353.381682 -239.513407) (xy 353.354445 -239.526421) (xy 353.342956 -239.536224) (xy 353.324571 -239.552466)
			(xy 353.283913 -239.579912) (xy 353.239642 -239.601041) (xy 353.192733 -239.615391) (xy 353.144217 -239.622645)
			(xy 353.11969 -239.623092) (xy 353.119436 -239.623092) (xy 353.093468 -239.622536) (xy 353.04217 -239.614416)
			(xy 352.992775 -239.598372) (xy 352.946497 -239.574796) (xy 352.904478 -239.544272) (xy 352.867752 -239.507549)
			(xy 352.837222 -239.465533) (xy 352.813642 -239.419259) (xy 352.797592 -239.369865) (xy 352.789467 -239.318568)
			(xy 349.419474 -239.318568) (xy 349.415309 -239.321594) (xy 349.369035 -239.345172) (xy 349.319642 -239.36122)
			(xy 349.268347 -239.369345) (xy 349.216413 -239.369345) (xy 349.165118 -239.36122) (xy 349.115725 -239.345172)
			(xy 349.069451 -239.321594) (xy 349.027435 -239.291068) (xy 348.990712 -239.254345) (xy 348.960186 -239.212329)
			(xy 348.936608 -239.166055) (xy 348.92056 -239.116662) (xy 348.912435 -239.065367) (xy 348.632779 -239.065367)
			(xy 348.624654 -239.116662) (xy 348.608606 -239.166055) (xy 348.585028 -239.212329) (xy 348.554502 -239.254345)
			(xy 348.517779 -239.291068) (xy 348.475763 -239.321594) (xy 348.429489 -239.345172) (xy 348.380096 -239.36122)
			(xy 348.328801 -239.369345) (xy 348.276867 -239.369345) (xy 348.225572 -239.36122) (xy 348.176179 -239.345172)
			(xy 348.129905 -239.321594) (xy 348.087889 -239.291068) (xy 348.051166 -239.254345) (xy 348.02064 -239.212329)
			(xy 347.997062 -239.166055) (xy 347.981014 -239.116662) (xy 347.972889 -239.065367) (xy 347.692979 -239.065367)
			(xy 347.684854 -239.116662) (xy 347.668806 -239.166055) (xy 347.645228 -239.212329) (xy 347.614702 -239.254345)
			(xy 347.577979 -239.291068) (xy 347.535963 -239.321594) (xy 347.489689 -239.345172) (xy 347.440296 -239.36122)
			(xy 347.389001 -239.369345) (xy 347.337067 -239.369345) (xy 347.285772 -239.36122) (xy 347.236379 -239.345172)
			(xy 347.190105 -239.321594) (xy 347.148089 -239.291068) (xy 347.111366 -239.254345) (xy 347.08084 -239.212329)
			(xy 347.057262 -239.166055) (xy 347.041214 -239.116662) (xy 347.033089 -239.065367) (xy 346.753179 -239.065367)
			(xy 346.745054 -239.116662) (xy 346.729006 -239.166055) (xy 346.705428 -239.212329) (xy 346.674902 -239.254345)
			(xy 346.638179 -239.291068) (xy 346.596163 -239.321594) (xy 346.549889 -239.345172) (xy 346.500496 -239.36122)
			(xy 346.449201 -239.369345) (xy 346.397267 -239.369345) (xy 346.345972 -239.36122) (xy 346.296579 -239.345172)
			(xy 346.250305 -239.321594) (xy 346.208289 -239.291068) (xy 346.171566 -239.254345) (xy 346.14104 -239.212329)
			(xy 346.117462 -239.166055) (xy 346.101414 -239.116662) (xy 346.093289 -239.065367) (xy 345.813379 -239.065367)
			(xy 345.805254 -239.116662) (xy 345.789206 -239.166055) (xy 345.765628 -239.212329) (xy 345.735102 -239.254345)
			(xy 345.698379 -239.291068) (xy 345.656363 -239.321594) (xy 345.610089 -239.345172) (xy 345.560696 -239.36122)
			(xy 345.509401 -239.369345) (xy 345.457467 -239.369345) (xy 345.406172 -239.36122) (xy 345.356779 -239.345172)
			(xy 345.310505 -239.321594) (xy 345.268489 -239.291068) (xy 345.231766 -239.254345) (xy 345.20124 -239.212329)
			(xy 345.177662 -239.166055) (xy 345.161614 -239.116662) (xy 345.153489 -239.065367) (xy 344.873579 -239.065367)
			(xy 344.865454 -239.116662) (xy 344.849406 -239.166055) (xy 344.825828 -239.212329) (xy 344.795302 -239.254345)
			(xy 344.758579 -239.291068) (xy 344.716563 -239.321594) (xy 344.670289 -239.345172) (xy 344.620896 -239.36122)
			(xy 344.569601 -239.369345) (xy 344.517667 -239.369345) (xy 344.466372 -239.36122) (xy 344.416979 -239.345172)
			(xy 344.370705 -239.321594) (xy 344.328689 -239.291068) (xy 344.291966 -239.254345) (xy 344.26144 -239.212329)
			(xy 344.237862 -239.166055) (xy 344.221814 -239.116662) (xy 344.213689 -239.065367) (xy 343.933779 -239.065367)
			(xy 343.925654 -239.116662) (xy 343.909606 -239.166055) (xy 343.886028 -239.212329) (xy 343.855502 -239.254345)
			(xy 343.818779 -239.291068) (xy 343.776763 -239.321594) (xy 343.730489 -239.345172) (xy 343.681096 -239.36122)
			(xy 343.629801 -239.369345) (xy 343.577867 -239.369345) (xy 343.526572 -239.36122) (xy 343.477179 -239.345172)
			(xy 343.430905 -239.321594) (xy 343.388889 -239.291068) (xy 343.352166 -239.254345) (xy 343.32164 -239.212329)
			(xy 343.298062 -239.166055) (xy 343.282014 -239.116662) (xy 343.273889 -239.065367) (xy 342.993725 -239.065367)
			(xy 342.9856 -239.116662) (xy 342.969552 -239.166055) (xy 342.945974 -239.212329) (xy 342.915448 -239.254345)
			(xy 342.878725 -239.291068) (xy 342.836709 -239.321594) (xy 342.790435 -239.345172) (xy 342.741042 -239.36122)
			(xy 342.689747 -239.369345) (xy 342.637813 -239.369345) (xy 342.586518 -239.36122) (xy 342.537125 -239.345172)
			(xy 342.490851 -239.321594) (xy 342.448835 -239.291068) (xy 342.412112 -239.254345) (xy 342.381586 -239.212329)
			(xy 342.358008 -239.166055) (xy 342.34196 -239.116662) (xy 342.333835 -239.065367) (xy 342.054179 -239.065367)
			(xy 342.046054 -239.116662) (xy 342.030006 -239.166055) (xy 342.006428 -239.212329) (xy 341.975902 -239.254345)
			(xy 341.939179 -239.291068) (xy 341.897163 -239.321594) (xy 341.850889 -239.345172) (xy 341.801496 -239.36122)
			(xy 341.750201 -239.369345) (xy 341.698267 -239.369345) (xy 341.646972 -239.36122) (xy 341.597579 -239.345172)
			(xy 341.551305 -239.321594) (xy 341.509289 -239.291068) (xy 341.472566 -239.254345) (xy 341.44204 -239.212329)
			(xy 341.418462 -239.166055) (xy 341.402414 -239.116662) (xy 341.394289 -239.065367) (xy 341.114379 -239.065367)
			(xy 341.106254 -239.116662) (xy 341.090206 -239.166055) (xy 341.066628 -239.212329) (xy 341.036102 -239.254345)
			(xy 340.999379 -239.291068) (xy 340.957363 -239.321594) (xy 340.911089 -239.345172) (xy 340.861696 -239.36122)
			(xy 340.810401 -239.369345) (xy 340.758467 -239.369345) (xy 340.707172 -239.36122) (xy 340.657779 -239.345172)
			(xy 340.611505 -239.321594) (xy 340.569489 -239.291068) (xy 340.532766 -239.254345) (xy 340.50224 -239.212329)
			(xy 340.478662 -239.166055) (xy 340.462614 -239.116662) (xy 340.454489 -239.065367) (xy 340.174799 -239.065367)
			(xy 340.174799 -239.065385) (xy 340.166669 -239.116717) (xy 340.15061 -239.166144) (xy 340.127017 -239.212452)
			(xy 340.096471 -239.254498) (xy 340.059724 -239.291249) (xy 340.017681 -239.321799) (xy 339.971376 -239.345397)
			(xy 339.92195 -239.361461) (xy 339.870619 -239.369596) (xy 339.844634 -239.370108) (xy 339.817668 -239.369571)
			(xy 339.764453 -239.360812) (xy 339.713363 -239.343537) (xy 339.665751 -239.318203) (xy 339.643974 -239.30229)
			(xy 339.637878 -239.297718) (xy 339.619844 -239.291368) (xy 339.61112 -239.288691) (xy 339.592891 -239.289093)
			(xy 339.584284 -239.29213) (xy 339.500972 -239.332008) (xy 339.493332 -239.336608) (xy 339.481672 -239.350086)
			(xy 339.475451 -239.366785) (xy 339.475064 -239.375696) (xy 339.475064 -239.503458) (xy 339.505036 -239.548924)
			(xy 339.517736 -239.55502) (xy 339.541439 -239.566991) (xy 339.585015 -239.597334) (xy 339.623184 -239.634247)
			(xy 339.654966 -239.676784) (xy 339.679546 -239.723851) (xy 339.696291 -239.77424) (xy 339.704772 -239.826657)
			(xy 339.704771 -239.879183) (xy 339.984335 -239.879183) (xy 339.984335 -239.827249) (xy 339.99246 -239.775954)
			(xy 340.008508 -239.726561) (xy 340.032086 -239.680287) (xy 340.062612 -239.638271) (xy 340.099335 -239.601548)
			(xy 340.141351 -239.571022) (xy 340.187625 -239.547444) (xy 340.237018 -239.531396) (xy 340.288313 -239.523271)
			(xy 340.340247 -239.523271) (xy 340.391542 -239.531396) (xy 340.440935 -239.547444) (xy 340.487209 -239.571022)
			(xy 340.529225 -239.601548) (xy 340.565948 -239.638271) (xy 340.596474 -239.680287) (xy 340.620052 -239.726561)
			(xy 340.6361 -239.775954) (xy 340.644225 -239.827249) (xy 340.644734 -239.853216) (xy 340.644225 -239.879183)
			(xy 340.924135 -239.879183) (xy 340.924135 -239.827249) (xy 340.93226 -239.775954) (xy 340.948308 -239.726561)
			(xy 340.971886 -239.680287) (xy 341.002412 -239.638271) (xy 341.039135 -239.601548) (xy 341.081151 -239.571022)
			(xy 341.127425 -239.547444) (xy 341.176818 -239.531396) (xy 341.228113 -239.523271) (xy 341.280047 -239.523271)
			(xy 341.331342 -239.531396) (xy 341.380735 -239.547444) (xy 341.427009 -239.571022) (xy 341.469025 -239.601548)
			(xy 341.505748 -239.638271) (xy 341.536274 -239.680287) (xy 341.559852 -239.726561) (xy 341.5759 -239.775954)
			(xy 341.584025 -239.827249) (xy 341.584534 -239.853216) (xy 341.584025 -239.879183) (xy 341.863935 -239.879183)
			(xy 341.863935 -239.827249) (xy 341.87206 -239.775954) (xy 341.888108 -239.726561) (xy 341.911686 -239.680287)
			(xy 341.942212 -239.638271) (xy 341.978935 -239.601548) (xy 342.020951 -239.571022) (xy 342.067225 -239.547444)
			(xy 342.116618 -239.531396) (xy 342.167913 -239.523271) (xy 342.219847 -239.523271) (xy 342.271142 -239.531396)
			(xy 342.320535 -239.547444) (xy 342.366809 -239.571022) (xy 342.408825 -239.601548) (xy 342.445548 -239.638271)
			(xy 342.476074 -239.680287) (xy 342.499652 -239.726561) (xy 342.5157 -239.775954) (xy 342.523825 -239.827249)
			(xy 342.524334 -239.853216) (xy 342.523825 -239.879183) (xy 342.803735 -239.879183) (xy 342.803735 -239.827249)
			(xy 342.81186 -239.775954) (xy 342.827908 -239.726561) (xy 342.851486 -239.680287) (xy 342.882012 -239.638271)
			(xy 342.918735 -239.601548) (xy 342.960751 -239.571022) (xy 343.007025 -239.547444) (xy 343.056418 -239.531396)
			(xy 343.107713 -239.523271) (xy 343.159647 -239.523271) (xy 343.210942 -239.531396) (xy 343.260335 -239.547444)
			(xy 343.306609 -239.571022) (xy 343.348625 -239.601548) (xy 343.385348 -239.638271) (xy 343.415874 -239.680287)
			(xy 343.439452 -239.726561) (xy 343.4555 -239.775954) (xy 343.463625 -239.827249) (xy 343.464134 -239.853216)
			(xy 343.463625 -239.879183) (xy 343.743535 -239.879183) (xy 343.743535 -239.827249) (xy 343.75166 -239.775954)
			(xy 343.767708 -239.726561) (xy 343.791286 -239.680287) (xy 343.821812 -239.638271) (xy 343.858535 -239.601548)
			(xy 343.900551 -239.571022) (xy 343.946825 -239.547444) (xy 343.996218 -239.531396) (xy 344.047513 -239.523271)
			(xy 344.099447 -239.523271) (xy 344.150742 -239.531396) (xy 344.200135 -239.547444) (xy 344.246409 -239.571022)
			(xy 344.288425 -239.601548) (xy 344.325148 -239.638271) (xy 344.355674 -239.680287) (xy 344.379252 -239.726561)
			(xy 344.3953 -239.775954) (xy 344.403425 -239.827249) (xy 344.403934 -239.853216) (xy 344.403425 -239.879183)
			(xy 344.683589 -239.879183) (xy 344.683589 -239.827249) (xy 344.691714 -239.775954) (xy 344.707762 -239.726561)
			(xy 344.73134 -239.680287) (xy 344.761866 -239.638271) (xy 344.798589 -239.601548) (xy 344.840605 -239.571022)
			(xy 344.886879 -239.547444) (xy 344.936272 -239.531396) (xy 344.987567 -239.523271) (xy 345.039501 -239.523271)
			(xy 345.090796 -239.531396) (xy 345.140189 -239.547444) (xy 345.186463 -239.571022) (xy 345.228479 -239.601548)
			(xy 345.265202 -239.638271) (xy 345.295728 -239.680287) (xy 345.319306 -239.726561) (xy 345.335354 -239.775954)
			(xy 345.343479 -239.827249) (xy 345.343988 -239.853216) (xy 345.343479 -239.879183) (xy 345.623135 -239.879183)
			(xy 345.623135 -239.827249) (xy 345.63126 -239.775954) (xy 345.647308 -239.726561) (xy 345.670886 -239.680287)
			(xy 345.701412 -239.638271) (xy 345.738135 -239.601548) (xy 345.780151 -239.571022) (xy 345.826425 -239.547444)
			(xy 345.875818 -239.531396) (xy 345.927113 -239.523271) (xy 345.979047 -239.523271) (xy 346.030342 -239.531396)
			(xy 346.079735 -239.547444) (xy 346.126009 -239.571022) (xy 346.168025 -239.601548) (xy 346.204748 -239.638271)
			(xy 346.235274 -239.680287) (xy 346.258852 -239.726561) (xy 346.2749 -239.775954) (xy 346.283025 -239.827249)
			(xy 346.283534 -239.853216) (xy 346.283025 -239.879183) (xy 346.562935 -239.879183) (xy 346.562935 -239.827249)
			(xy 346.57106 -239.775954) (xy 346.587108 -239.726561) (xy 346.610686 -239.680287) (xy 346.641212 -239.638271)
			(xy 346.677935 -239.601548) (xy 346.719951 -239.571022) (xy 346.766225 -239.547444) (xy 346.815618 -239.531396)
			(xy 346.866913 -239.523271) (xy 346.918847 -239.523271) (xy 346.970142 -239.531396) (xy 347.019535 -239.547444)
			(xy 347.065809 -239.571022) (xy 347.107825 -239.601548) (xy 347.144548 -239.638271) (xy 347.175074 -239.680287)
			(xy 347.198652 -239.726561) (xy 347.2147 -239.775954) (xy 347.222825 -239.827249) (xy 347.223334 -239.853216)
			(xy 347.222825 -239.879183) (xy 347.502735 -239.879183) (xy 347.502735 -239.827249) (xy 347.51086 -239.775954)
			(xy 347.526908 -239.726561) (xy 347.550486 -239.680287) (xy 347.581012 -239.638271) (xy 347.617735 -239.601548)
			(xy 347.659751 -239.571022) (xy 347.706025 -239.547444) (xy 347.755418 -239.531396) (xy 347.806713 -239.523271)
			(xy 347.858647 -239.523271) (xy 347.909942 -239.531396) (xy 347.959335 -239.547444) (xy 348.005609 -239.571022)
			(xy 348.047625 -239.601548) (xy 348.084348 -239.638271) (xy 348.114874 -239.680287) (xy 348.138452 -239.726561)
			(xy 348.1545 -239.775954) (xy 348.162625 -239.827249) (xy 348.163134 -239.853216) (xy 348.162625 -239.879183)
			(xy 348.442535 -239.879183) (xy 348.442535 -239.827249) (xy 348.45066 -239.775954) (xy 348.466708 -239.726561)
			(xy 348.490286 -239.680287) (xy 348.520812 -239.638271) (xy 348.557535 -239.601548) (xy 348.599551 -239.571022)
			(xy 348.645825 -239.547444) (xy 348.695218 -239.531396) (xy 348.746513 -239.523271) (xy 348.798447 -239.523271)
			(xy 348.849742 -239.531396) (xy 348.899135 -239.547444) (xy 348.945409 -239.571022) (xy 348.987425 -239.601548)
			(xy 349.024148 -239.638271) (xy 349.054674 -239.680287) (xy 349.078252 -239.726561) (xy 349.0943 -239.775954)
			(xy 349.102425 -239.827249) (xy 349.102561 -239.834166) (xy 356.28961 -239.834166) (xy 356.28961 -239.833912)
			(xy 356.290066 -239.809386) (xy 356.297328 -239.760873) (xy 356.311678 -239.713966) (xy 356.332802 -239.669694)
			(xy 356.360236 -239.62903) (xy 356.376478 -239.610646) (xy 356.386314 -239.599183) (xy 356.399324 -239.571936)
			(xy 356.403786 -239.542075) (xy 356.399309 -239.512216) (xy 356.386286 -239.484975) (xy 356.376478 -239.473486)
			(xy 356.360203 -239.455129) (xy 356.332762 -239.414463) (xy 356.311639 -239.370185) (xy 356.297297 -239.32327)
			(xy 356.290052 -239.274749) (xy 356.28961 -239.25022) (xy 356.28961 -239.249966) (xy 356.290119 -239.223999)
			(xy 356.298244 -239.172704) (xy 356.314292 -239.123311) (xy 356.33787 -239.077037) (xy 356.368396 -239.035021)
			(xy 356.405119 -238.998298) (xy 356.447135 -238.967772) (xy 356.493409 -238.944194) (xy 356.542802 -238.928146)
			(xy 356.594097 -238.920021) (xy 356.646031 -238.920021) (xy 356.697326 -238.928146) (xy 356.746719 -238.944194)
			(xy 356.792993 -238.967772) (xy 356.835009 -238.998298) (xy 356.871732 -239.035021) (xy 356.893779 -239.065367)
			(xy 357.370889 -239.065367) (xy 357.370889 -239.013433) (xy 357.379014 -238.962138) (xy 357.395062 -238.912745)
			(xy 357.41864 -238.866471) (xy 357.449166 -238.824455) (xy 357.485889 -238.787732) (xy 357.527905 -238.757206)
			(xy 357.574179 -238.733628) (xy 357.623572 -238.71758) (xy 357.674867 -238.709455) (xy 357.726801 -238.709455)
			(xy 357.778096 -238.71758) (xy 357.827489 -238.733628) (xy 357.873763 -238.757206) (xy 357.915779 -238.787732)
			(xy 357.952502 -238.824455) (xy 357.983028 -238.866471) (xy 358.006606 -238.912745) (xy 358.022654 -238.962138)
			(xy 358.030779 -239.013433) (xy 358.031288 -239.0394) (xy 358.030779 -239.065367) (xy 358.310689 -239.065367)
			(xy 358.310689 -239.013433) (xy 358.318814 -238.962138) (xy 358.334862 -238.912745) (xy 358.35844 -238.866471)
			(xy 358.388966 -238.824455) (xy 358.425689 -238.787732) (xy 358.467705 -238.757206) (xy 358.513979 -238.733628)
			(xy 358.563372 -238.71758) (xy 358.614667 -238.709455) (xy 358.666601 -238.709455) (xy 358.717896 -238.71758)
			(xy 358.767289 -238.733628) (xy 358.813563 -238.757206) (xy 358.855579 -238.787732) (xy 358.892302 -238.824455)
			(xy 358.922828 -238.866471) (xy 358.946406 -238.912745) (xy 358.962454 -238.962138) (xy 358.970579 -239.013433)
			(xy 358.971088 -239.0394) (xy 358.970579 -239.065367) (xy 359.250489 -239.065367) (xy 359.250489 -239.013433)
			(xy 359.258614 -238.962138) (xy 359.274662 -238.912745) (xy 359.29824 -238.866471) (xy 359.328766 -238.824455)
			(xy 359.365489 -238.787732) (xy 359.407505 -238.757206) (xy 359.453779 -238.733628) (xy 359.503172 -238.71758)
			(xy 359.554467 -238.709455) (xy 359.606401 -238.709455) (xy 359.657696 -238.71758) (xy 359.707089 -238.733628)
			(xy 359.753363 -238.757206) (xy 359.795379 -238.787732) (xy 359.832102 -238.824455) (xy 359.862628 -238.866471)
			(xy 359.886206 -238.912745) (xy 359.902254 -238.962138) (xy 359.910379 -239.013433) (xy 359.910888 -239.0394)
			(xy 359.910379 -239.065367) (xy 360.190289 -239.065367) (xy 360.190289 -239.013433) (xy 360.198414 -238.962138)
			(xy 360.214462 -238.912745) (xy 360.23804 -238.866471) (xy 360.268566 -238.824455) (xy 360.305289 -238.787732)
			(xy 360.347305 -238.757206) (xy 360.393579 -238.733628) (xy 360.442972 -238.71758) (xy 360.494267 -238.709455)
			(xy 360.546201 -238.709455) (xy 360.597496 -238.71758) (xy 360.646889 -238.733628) (xy 360.693163 -238.757206)
			(xy 360.735179 -238.787732) (xy 360.771902 -238.824455) (xy 360.802428 -238.866471) (xy 360.826006 -238.912745)
			(xy 360.842054 -238.962138) (xy 360.850179 -239.013433) (xy 360.850688 -239.0394) (xy 360.850179 -239.065367)
			(xy 361.129835 -239.065367) (xy 361.129835 -239.013433) (xy 361.13796 -238.962138) (xy 361.154008 -238.912745)
			(xy 361.177586 -238.866471) (xy 361.208112 -238.824455) (xy 361.244835 -238.787732) (xy 361.286851 -238.757206)
			(xy 361.333125 -238.733628) (xy 361.382518 -238.71758) (xy 361.433813 -238.709455) (xy 361.485747 -238.709455)
			(xy 361.537042 -238.71758) (xy 361.586435 -238.733628) (xy 361.632709 -238.757206) (xy 361.674725 -238.787732)
			(xy 361.711448 -238.824455) (xy 361.741974 -238.866471) (xy 361.765552 -238.912745) (xy 361.7816 -238.962138)
			(xy 361.789725 -239.013433) (xy 361.790234 -239.0394) (xy 361.789725 -239.065367) (xy 362.069889 -239.065367)
			(xy 362.069889 -239.013433) (xy 362.078014 -238.962138) (xy 362.094062 -238.912745) (xy 362.11764 -238.866471)
			(xy 362.148166 -238.824455) (xy 362.184889 -238.787732) (xy 362.226905 -238.757206) (xy 362.273179 -238.733628)
			(xy 362.322572 -238.71758) (xy 362.373867 -238.709455) (xy 362.425801 -238.709455) (xy 362.477096 -238.71758)
			(xy 362.526489 -238.733628) (xy 362.572763 -238.757206) (xy 362.614779 -238.787732) (xy 362.651502 -238.824455)
			(xy 362.682028 -238.866471) (xy 362.705606 -238.912745) (xy 362.721654 -238.962138) (xy 362.729779 -239.013433)
			(xy 362.730288 -239.0394) (xy 362.729779 -239.065367) (xy 362.721654 -239.116662) (xy 362.705606 -239.166055)
			(xy 362.682028 -239.212329) (xy 362.651502 -239.254345) (xy 362.614779 -239.291068) (xy 362.572763 -239.321594)
			(xy 362.526489 -239.345172) (xy 362.477096 -239.36122) (xy 362.425801 -239.369345) (xy 362.373867 -239.369345)
			(xy 362.322572 -239.36122) (xy 362.273179 -239.345172) (xy 362.226905 -239.321594) (xy 362.184889 -239.291068)
			(xy 362.148166 -239.254345) (xy 362.11764 -239.212329) (xy 362.094062 -239.166055) (xy 362.078014 -239.116662)
			(xy 362.069889 -239.065367) (xy 361.789725 -239.065367) (xy 361.7816 -239.116662) (xy 361.765552 -239.166055)
			(xy 361.741974 -239.212329) (xy 361.711448 -239.254345) (xy 361.674725 -239.291068) (xy 361.632709 -239.321594)
			(xy 361.586435 -239.345172) (xy 361.537042 -239.36122) (xy 361.485747 -239.369345) (xy 361.433813 -239.369345)
			(xy 361.382518 -239.36122) (xy 361.333125 -239.345172) (xy 361.286851 -239.321594) (xy 361.244835 -239.291068)
			(xy 361.208112 -239.254345) (xy 361.177586 -239.212329) (xy 361.154008 -239.166055) (xy 361.13796 -239.116662)
			(xy 361.129835 -239.065367) (xy 360.850179 -239.065367) (xy 360.842054 -239.116662) (xy 360.826006 -239.166055)
			(xy 360.802428 -239.212329) (xy 360.771902 -239.254345) (xy 360.735179 -239.291068) (xy 360.693163 -239.321594)
			(xy 360.646889 -239.345172) (xy 360.597496 -239.36122) (xy 360.546201 -239.369345) (xy 360.494267 -239.369345)
			(xy 360.442972 -239.36122) (xy 360.393579 -239.345172) (xy 360.347305 -239.321594) (xy 360.305289 -239.291068)
			(xy 360.268566 -239.254345) (xy 360.23804 -239.212329) (xy 360.214462 -239.166055) (xy 360.198414 -239.116662)
			(xy 360.190289 -239.065367) (xy 359.910379 -239.065367) (xy 359.902254 -239.116662) (xy 359.886206 -239.166055)
			(xy 359.862628 -239.212329) (xy 359.832102 -239.254345) (xy 359.795379 -239.291068) (xy 359.753363 -239.321594)
			(xy 359.707089 -239.345172) (xy 359.657696 -239.36122) (xy 359.606401 -239.369345) (xy 359.554467 -239.369345)
			(xy 359.503172 -239.36122) (xy 359.453779 -239.345172) (xy 359.407505 -239.321594) (xy 359.365489 -239.291068)
			(xy 359.328766 -239.254345) (xy 359.29824 -239.212329) (xy 359.274662 -239.166055) (xy 359.258614 -239.116662)
			(xy 359.250489 -239.065367) (xy 358.970579 -239.065367) (xy 358.962454 -239.116662) (xy 358.946406 -239.166055)
			(xy 358.922828 -239.212329) (xy 358.892302 -239.254345) (xy 358.855579 -239.291068) (xy 358.813563 -239.321594)
			(xy 358.767289 -239.345172) (xy 358.717896 -239.36122) (xy 358.666601 -239.369345) (xy 358.614667 -239.369345)
			(xy 358.563372 -239.36122) (xy 358.513979 -239.345172) (xy 358.467705 -239.321594) (xy 358.425689 -239.291068)
			(xy 358.388966 -239.254345) (xy 358.35844 -239.212329) (xy 358.334862 -239.166055) (xy 358.318814 -239.116662)
			(xy 358.310689 -239.065367) (xy 358.030779 -239.065367) (xy 358.022654 -239.116662) (xy 358.006606 -239.166055)
			(xy 357.983028 -239.212329) (xy 357.952502 -239.254345) (xy 357.915779 -239.291068) (xy 357.873763 -239.321594)
			(xy 357.827489 -239.345172) (xy 357.778096 -239.36122) (xy 357.726801 -239.369345) (xy 357.674867 -239.369345)
			(xy 357.623572 -239.36122) (xy 357.574179 -239.345172) (xy 357.527905 -239.321594) (xy 357.485889 -239.291068)
			(xy 357.449166 -239.254345) (xy 357.41864 -239.212329) (xy 357.395062 -239.166055) (xy 357.379014 -239.116662)
			(xy 357.370889 -239.065367) (xy 356.893779 -239.065367) (xy 356.902258 -239.077037) (xy 356.925836 -239.123311)
			(xy 356.941884 -239.172704) (xy 356.950009 -239.223999) (xy 356.950518 -239.249966) (xy 356.950069 -239.274019)
			(xy 356.94311 -239.321618) (xy 356.92932 -239.367704) (xy 356.90899 -239.411303) (xy 356.88255 -239.45149)
			(xy 356.850561 -239.487418) (xy 356.832408 -239.503204) (xy 356.82431 -239.51083) (xy 356.814941 -239.530972)
			(xy 356.814932 -239.553185) (xy 356.824283 -239.573335) (xy 356.832408 -239.580928) (xy 356.83987 -239.587279)
			(xy 356.854103 -239.600752) (xy 356.860856 -239.607852) (xy 356.870247 -239.617341) (xy 356.892912 -239.631438)
			(xy 356.918457 -239.639174) (xy 356.945135 -239.640019) (xy 356.971119 -239.633917) (xy 356.994631 -239.621283)
			(xy 357.00462 -239.612424) (xy 357.023094 -239.595659) (xy 357.06417 -239.567347) (xy 357.109035 -239.545532)
			(xy 357.156669 -239.530709) (xy 357.20599 -239.523215) (xy 357.230934 -239.522762) (xy 357.256901 -239.523242)
			(xy 357.308194 -239.531371) (xy 357.357585 -239.547423) (xy 357.403856 -239.571004) (xy 357.445869 -239.601532)
			(xy 357.48259 -239.638257) (xy 357.513114 -239.680273) (xy 357.53669 -239.726547) (xy 357.552737 -239.775939)
			(xy 357.560861 -239.827233) (xy 357.560861 -239.879167) (xy 357.560858 -239.879183) (xy 357.840789 -239.879183)
			(xy 357.840789 -239.827249) (xy 357.848914 -239.775954) (xy 357.864962 -239.726561) (xy 357.88854 -239.680287)
			(xy 357.919066 -239.638271) (xy 357.955789 -239.601548) (xy 357.997805 -239.571022) (xy 358.044079 -239.547444)
			(xy 358.093472 -239.531396) (xy 358.144767 -239.523271) (xy 358.196701 -239.523271) (xy 358.247996 -239.531396)
			(xy 358.297389 -239.547444) (xy 358.343663 -239.571022) (xy 358.385679 -239.601548) (xy 358.422402 -239.638271)
			(xy 358.452928 -239.680287) (xy 358.476506 -239.726561) (xy 358.492554 -239.775954) (xy 358.500679 -239.827249)
			(xy 358.501188 -239.853216) (xy 358.500679 -239.879183) (xy 358.780589 -239.879183) (xy 358.780589 -239.827249)
			(xy 358.788714 -239.775954) (xy 358.804762 -239.726561) (xy 358.82834 -239.680287) (xy 358.858866 -239.638271)
			(xy 358.895589 -239.601548) (xy 358.937605 -239.571022) (xy 358.983879 -239.547444) (xy 359.033272 -239.531396)
			(xy 359.084567 -239.523271) (xy 359.136501 -239.523271) (xy 359.187796 -239.531396) (xy 359.237189 -239.547444)
			(xy 359.283463 -239.571022) (xy 359.325479 -239.601548) (xy 359.362202 -239.638271) (xy 359.392728 -239.680287)
			(xy 359.416306 -239.726561) (xy 359.432354 -239.775954) (xy 359.440479 -239.827249) (xy 359.440988 -239.853216)
			(xy 359.440479 -239.879183) (xy 359.720389 -239.879183) (xy 359.720389 -239.827249) (xy 359.728514 -239.775954)
			(xy 359.744562 -239.726561) (xy 359.76814 -239.680287) (xy 359.798666 -239.638271) (xy 359.835389 -239.601548)
			(xy 359.877405 -239.571022) (xy 359.923679 -239.547444) (xy 359.973072 -239.531396) (xy 360.024367 -239.523271)
			(xy 360.076301 -239.523271) (xy 360.127596 -239.531396) (xy 360.176989 -239.547444) (xy 360.223263 -239.571022)
			(xy 360.265279 -239.601548) (xy 360.302002 -239.638271) (xy 360.332528 -239.680287) (xy 360.356106 -239.726561)
			(xy 360.372154 -239.775954) (xy 360.380279 -239.827249) (xy 360.380788 -239.853216) (xy 360.380279 -239.879183)
			(xy 360.659935 -239.879183) (xy 360.659935 -239.827249) (xy 360.66806 -239.775954) (xy 360.684108 -239.726561)
			(xy 360.707686 -239.680287) (xy 360.738212 -239.638271) (xy 360.774935 -239.601548) (xy 360.816951 -239.571022)
			(xy 360.863225 -239.547444) (xy 360.912618 -239.531396) (xy 360.963913 -239.523271) (xy 361.015847 -239.523271)
			(xy 361.067142 -239.531396) (xy 361.116535 -239.547444) (xy 361.162809 -239.571022) (xy 361.204825 -239.601548)
			(xy 361.241548 -239.638271) (xy 361.272074 -239.680287) (xy 361.295652 -239.726561) (xy 361.3117 -239.775954)
			(xy 361.319825 -239.827249) (xy 361.320334 -239.853216) (xy 361.319825 -239.879183) (xy 361.599989 -239.879183)
			(xy 361.599989 -239.827249) (xy 361.608114 -239.775954) (xy 361.624162 -239.726561) (xy 361.64774 -239.680287)
			(xy 361.678266 -239.638271) (xy 361.714989 -239.601548) (xy 361.757005 -239.571022) (xy 361.803279 -239.547444)
			(xy 361.852672 -239.531396) (xy 361.903967 -239.523271) (xy 361.955901 -239.523271) (xy 362.007196 -239.531396)
			(xy 362.056589 -239.547444) (xy 362.102863 -239.571022) (xy 362.144879 -239.601548) (xy 362.181602 -239.638271)
			(xy 362.212128 -239.680287) (xy 362.235706 -239.726561) (xy 362.251754 -239.775954) (xy 362.259879 -239.827249)
			(xy 362.260388 -239.853216) (xy 362.259879 -239.879183) (xy 362.254618 -239.912398) (xy 362.81995 -239.912398)
			(xy 362.81995 -239.912144) (xy 362.820381 -239.887617) (xy 362.827651 -239.839104) (xy 362.842008 -239.792197)
			(xy 362.863137 -239.747926) (xy 362.890575 -239.707262) (xy 362.906818 -239.688878) (xy 362.91662 -239.677389)
			(xy 362.929628 -239.650151) (xy 362.934094 -239.620299) (xy 362.929627 -239.590446) (xy 362.916619 -239.563208)
			(xy 362.906818 -239.551718) (xy 362.890549 -239.533323) (xy 362.863081 -239.492616) (xy 362.841945 -239.448291)
			(xy 362.827605 -239.401324) (xy 362.820377 -239.352752) (xy 362.81995 -239.328198) (xy 362.820364 -239.303645)
			(xy 362.827612 -239.255077) (xy 362.841962 -239.208115) (xy 362.863099 -239.163792) (xy 362.890559 -239.123082)
			(xy 362.906818 -239.104678) (xy 362.91662 -239.093189) (xy 362.929628 -239.065951) (xy 362.934094 -239.036099)
			(xy 362.929627 -239.006246) (xy 362.916619 -238.979008) (xy 362.906818 -238.967518) (xy 362.890565 -238.949143)
			(xy 362.863119 -238.908482) (xy 362.841991 -238.864209) (xy 362.827644 -238.817298) (xy 362.820394 -238.76878)
			(xy 362.81995 -238.744252) (xy 362.81995 -238.743998) (xy 362.820459 -238.718031) (xy 362.828584 -238.666736)
			(xy 362.844632 -238.617343) (xy 362.86821 -238.571069) (xy 362.898736 -238.529053) (xy 362.935459 -238.49233)
			(xy 362.977475 -238.461804) (xy 363.023749 -238.438226) (xy 363.073142 -238.422178) (xy 363.124437 -238.414053)
			(xy 363.176371 -238.414053) (xy 363.227666 -238.422178) (xy 363.277059 -238.438226) (xy 363.323333 -238.461804)
			(xy 363.365349 -238.49233) (xy 363.402072 -238.529053) (xy 363.432598 -238.571069) (xy 363.456176 -238.617343)
			(xy 363.472224 -238.666736) (xy 363.480349 -238.718031) (xy 363.480858 -238.743998) (xy 363.480858 -238.744252)
			(xy 363.480422 -238.768779) (xy 363.473153 -238.817292) (xy 363.458797 -238.864199) (xy 363.437669 -238.90847)
			(xy 363.410233 -238.949134) (xy 363.39399 -238.967518) (xy 363.384191 -238.97901) (xy 363.371182 -239.006247)
			(xy 363.366715 -239.036099) (xy 363.371181 -239.06595) (xy 363.38419 -239.093188) (xy 363.39399 -239.104678)
			(xy 363.410259 -239.123074) (xy 363.437726 -239.16378) (xy 363.458863 -239.208106) (xy 363.473203 -239.255072)
			(xy 363.48043 -239.303644) (xy 363.480858 -239.328198) (xy 363.480787 -239.332373) (xy 365.024083 -239.332373)
			(xy 365.024083 -239.280427) (xy 365.032209 -239.22912) (xy 365.048262 -239.179716) (xy 365.071846 -239.133431)
			(xy 365.102379 -239.091406) (xy 365.139112 -239.054674) (xy 365.181138 -239.024141) (xy 365.227423 -239.000559)
			(xy 365.276827 -238.984508) (xy 365.328135 -238.976382) (xy 365.354108 -238.9759) (xy 365.354362 -238.9759)
			(xy 365.378888 -238.976375) (xy 365.4274 -238.983632) (xy 365.474306 -238.997978) (xy 365.518579 -239.019098)
			(xy 365.559244 -239.046528) (xy 365.577628 -239.062768) (xy 365.589117 -239.072571) (xy 365.616354 -239.085585)
			(xy 365.646208 -239.090053) (xy 365.676062 -239.085585) (xy 365.703299 -239.072571) (xy 365.714788 -239.062768)
			(xy 365.733188 -239.046504) (xy 365.773892 -239.019034) (xy 365.818216 -238.997895) (xy 365.865182 -238.983554)
			(xy 365.913754 -238.976327) (xy 365.938308 -238.9759) (xy 365.962859 -238.976358) (xy 366.011426 -238.983593)
			(xy 366.058388 -238.997932) (xy 366.102712 -239.01906) (xy 366.143424 -239.046512) (xy 366.161828 -239.062768)
			(xy 366.173317 -239.072571) (xy 366.200554 -239.085585) (xy 366.230408 -239.090053) (xy 366.260262 -239.085585)
			(xy 366.287499 -239.072571) (xy 366.298988 -239.062768) (xy 366.317368 -239.04652) (xy 366.358026 -239.019072)
			(xy 366.402298 -238.997942) (xy 366.449209 -238.983594) (xy 366.497726 -238.976344) (xy 366.522254 -238.9759)
			(xy 366.522508 -238.9759) (xy 366.548471 -238.976502) (xy 366.599758 -238.984626) (xy 366.649143 -239.000673)
			(xy 366.695409 -239.024248) (xy 366.737418 -239.05477) (xy 366.748015 -239.065367) (xy 369.588289 -239.065367)
			(xy 369.588289 -239.013433) (xy 369.596414 -238.962138) (xy 369.612462 -238.912745) (xy 369.63604 -238.866471)
			(xy 369.666566 -238.824455) (xy 369.703289 -238.787732) (xy 369.745305 -238.757206) (xy 369.791579 -238.733628)
			(xy 369.840972 -238.71758) (xy 369.892267 -238.709455) (xy 369.944201 -238.709455) (xy 369.995496 -238.71758)
			(xy 370.044889 -238.733628) (xy 370.091163 -238.757206) (xy 370.133179 -238.787732) (xy 370.169902 -238.824455)
			(xy 370.200428 -238.866471) (xy 370.224006 -238.912745) (xy 370.240054 -238.962138) (xy 370.248179 -239.013433)
			(xy 370.248688 -239.0394) (xy 370.248179 -239.065367) (xy 370.527835 -239.065367) (xy 370.527835 -239.013433)
			(xy 370.53596 -238.962138) (xy 370.552008 -238.912745) (xy 370.575586 -238.866471) (xy 370.606112 -238.824455)
			(xy 370.642835 -238.787732) (xy 370.684851 -238.757206) (xy 370.731125 -238.733628) (xy 370.780518 -238.71758)
			(xy 370.831813 -238.709455) (xy 370.883747 -238.709455) (xy 370.935042 -238.71758) (xy 370.984435 -238.733628)
			(xy 371.030709 -238.757206) (xy 371.072725 -238.787732) (xy 371.109448 -238.824455) (xy 371.139974 -238.866471)
			(xy 371.163552 -238.912745) (xy 371.1796 -238.962138) (xy 371.187725 -239.013433) (xy 371.188234 -239.0394)
			(xy 371.187725 -239.065367) (xy 371.467889 -239.065367) (xy 371.467889 -239.013433) (xy 371.476014 -238.962138)
			(xy 371.492062 -238.912745) (xy 371.51564 -238.866471) (xy 371.546166 -238.824455) (xy 371.582889 -238.787732)
			(xy 371.624905 -238.757206) (xy 371.671179 -238.733628) (xy 371.720572 -238.71758) (xy 371.771867 -238.709455)
			(xy 371.823801 -238.709455) (xy 371.875096 -238.71758) (xy 371.924489 -238.733628) (xy 371.970763 -238.757206)
			(xy 372.012779 -238.787732) (xy 372.049502 -238.824455) (xy 372.080028 -238.866471) (xy 372.103606 -238.912745)
			(xy 372.119654 -238.962138) (xy 372.127779 -239.013433) (xy 372.128288 -239.0394) (xy 372.127779 -239.065367)
			(xy 372.407689 -239.065367) (xy 372.407689 -239.013433) (xy 372.415814 -238.962138) (xy 372.431862 -238.912745)
			(xy 372.45544 -238.866471) (xy 372.485966 -238.824455) (xy 372.522689 -238.787732) (xy 372.564705 -238.757206)
			(xy 372.610979 -238.733628) (xy 372.660372 -238.71758) (xy 372.711667 -238.709455) (xy 372.763601 -238.709455)
			(xy 372.814896 -238.71758) (xy 372.864289 -238.733628) (xy 372.910563 -238.757206) (xy 372.952579 -238.787732)
			(xy 372.989302 -238.824455) (xy 373.019828 -238.866471) (xy 373.043406 -238.912745) (xy 373.059454 -238.962138)
			(xy 373.067579 -239.013433) (xy 373.068088 -239.0394) (xy 373.067579 -239.065367) (xy 373.347489 -239.065367)
			(xy 373.347489 -239.013433) (xy 373.355614 -238.962138) (xy 373.371662 -238.912745) (xy 373.39524 -238.866471)
			(xy 373.425766 -238.824455) (xy 373.462489 -238.787732) (xy 373.504505 -238.757206) (xy 373.550779 -238.733628)
			(xy 373.600172 -238.71758) (xy 373.651467 -238.709455) (xy 373.703401 -238.709455) (xy 373.754696 -238.71758)
			(xy 373.804089 -238.733628) (xy 373.850363 -238.757206) (xy 373.892379 -238.787732) (xy 373.929102 -238.824455)
			(xy 373.959628 -238.866471) (xy 373.983206 -238.912745) (xy 373.999254 -238.962138) (xy 374.007379 -239.013433)
			(xy 374.007888 -239.0394) (xy 374.007379 -239.065367) (xy 374.287289 -239.065367) (xy 374.287289 -239.013433)
			(xy 374.295414 -238.962138) (xy 374.311462 -238.912745) (xy 374.33504 -238.866471) (xy 374.365566 -238.824455)
			(xy 374.402289 -238.787732) (xy 374.444305 -238.757206) (xy 374.490579 -238.733628) (xy 374.539972 -238.71758)
			(xy 374.591267 -238.709455) (xy 374.643201 -238.709455) (xy 374.694496 -238.71758) (xy 374.743889 -238.733628)
			(xy 374.790163 -238.757206) (xy 374.832179 -238.787732) (xy 374.868902 -238.824455) (xy 374.899428 -238.866471)
			(xy 374.923006 -238.912745) (xy 374.939054 -238.962138) (xy 374.947179 -239.013433) (xy 374.947688 -239.0394)
			(xy 374.947179 -239.065367) (xy 375.227089 -239.065367) (xy 375.227089 -239.013433) (xy 375.235214 -238.962138)
			(xy 375.251262 -238.912745) (xy 375.27484 -238.866471) (xy 375.305366 -238.824455) (xy 375.342089 -238.787732)
			(xy 375.384105 -238.757206) (xy 375.430379 -238.733628) (xy 375.479772 -238.71758) (xy 375.531067 -238.709455)
			(xy 375.583001 -238.709455) (xy 375.634296 -238.71758) (xy 375.683689 -238.733628) (xy 375.729963 -238.757206)
			(xy 375.771979 -238.787732) (xy 375.808702 -238.824455) (xy 375.839228 -238.866471) (xy 375.862806 -238.912745)
			(xy 375.878854 -238.962138) (xy 375.886979 -239.013433) (xy 375.887488 -239.0394) (xy 375.886979 -239.065367)
			(xy 376.166889 -239.065367) (xy 376.166889 -239.013433) (xy 376.175014 -238.962138) (xy 376.191062 -238.912745)
			(xy 376.21464 -238.866471) (xy 376.245166 -238.824455) (xy 376.281889 -238.787732) (xy 376.323905 -238.757206)
			(xy 376.370179 -238.733628) (xy 376.419572 -238.71758) (xy 376.470867 -238.709455) (xy 376.522801 -238.709455)
			(xy 376.574096 -238.71758) (xy 376.623489 -238.733628) (xy 376.669763 -238.757206) (xy 376.711779 -238.787732)
			(xy 376.748502 -238.824455) (xy 376.779028 -238.866471) (xy 376.802606 -238.912745) (xy 376.818654 -238.962138)
			(xy 376.826779 -239.013433) (xy 376.827288 -239.0394) (xy 376.826779 -239.065367) (xy 377.106435 -239.065367)
			(xy 377.106435 -239.013433) (xy 377.11456 -238.962138) (xy 377.130608 -238.912745) (xy 377.154186 -238.866471)
			(xy 377.184712 -238.824455) (xy 377.221435 -238.787732) (xy 377.263451 -238.757206) (xy 377.309725 -238.733628)
			(xy 377.359118 -238.71758) (xy 377.410413 -238.709455) (xy 377.462347 -238.709455) (xy 377.513642 -238.71758)
			(xy 377.563035 -238.733628) (xy 377.609309 -238.757206) (xy 377.651325 -238.787732) (xy 377.688048 -238.824455)
			(xy 377.718574 -238.866471) (xy 377.742152 -238.912745) (xy 377.7582 -238.962138) (xy 377.766325 -239.013433)
			(xy 377.766834 -239.0394) (xy 377.766325 -239.065367) (xy 378.046489 -239.065367) (xy 378.046489 -239.013433)
			(xy 378.054614 -238.962138) (xy 378.070662 -238.912745) (xy 378.09424 -238.866471) (xy 378.124766 -238.824455)
			(xy 378.161489 -238.787732) (xy 378.203505 -238.757206) (xy 378.249779 -238.733628) (xy 378.299172 -238.71758)
			(xy 378.350467 -238.709455) (xy 378.402401 -238.709455) (xy 378.453696 -238.71758) (xy 378.503089 -238.733628)
			(xy 378.549363 -238.757206) (xy 378.591379 -238.787732) (xy 378.628102 -238.824455) (xy 378.658628 -238.866471)
			(xy 378.682206 -238.912745) (xy 378.698254 -238.962138) (xy 378.706379 -239.013433) (xy 378.706888 -239.0394)
			(xy 378.706379 -239.065367) (xy 378.986289 -239.065367) (xy 378.986289 -239.013433) (xy 378.994414 -238.962138)
			(xy 379.010462 -238.912745) (xy 379.03404 -238.866471) (xy 379.064566 -238.824455) (xy 379.101289 -238.787732)
			(xy 379.143305 -238.757206) (xy 379.189579 -238.733628) (xy 379.238972 -238.71758) (xy 379.290267 -238.709455)
			(xy 379.342201 -238.709455) (xy 379.393496 -238.71758) (xy 379.442889 -238.733628) (xy 379.489163 -238.757206)
			(xy 379.531179 -238.787732) (xy 379.567902 -238.824455) (xy 379.598428 -238.866471) (xy 379.622006 -238.912745)
			(xy 379.638054 -238.962138) (xy 379.646179 -239.013433) (xy 379.646688 -239.0394) (xy 379.646179 -239.065367)
			(xy 379.638054 -239.116662) (xy 379.622006 -239.166055) (xy 379.598428 -239.212329) (xy 379.567902 -239.254345)
			(xy 379.531179 -239.291068) (xy 379.489163 -239.321594) (xy 379.442889 -239.345172) (xy 379.393496 -239.36122)
			(xy 379.342201 -239.369345) (xy 379.290267 -239.369345) (xy 379.238972 -239.36122) (xy 379.189579 -239.345172)
			(xy 379.143305 -239.321594) (xy 379.101289 -239.291068) (xy 379.064566 -239.254345) (xy 379.03404 -239.212329)
			(xy 379.010462 -239.166055) (xy 378.994414 -239.116662) (xy 378.986289 -239.065367) (xy 378.706379 -239.065367)
			(xy 378.698254 -239.116662) (xy 378.682206 -239.166055) (xy 378.658628 -239.212329) (xy 378.628102 -239.254345)
			(xy 378.591379 -239.291068) (xy 378.549363 -239.321594) (xy 378.503089 -239.345172) (xy 378.453696 -239.36122)
			(xy 378.402401 -239.369345) (xy 378.350467 -239.369345) (xy 378.299172 -239.36122) (xy 378.249779 -239.345172)
			(xy 378.203505 -239.321594) (xy 378.161489 -239.291068) (xy 378.124766 -239.254345) (xy 378.09424 -239.212329)
			(xy 378.070662 -239.166055) (xy 378.054614 -239.116662) (xy 378.046489 -239.065367) (xy 377.766325 -239.065367)
			(xy 377.7582 -239.116662) (xy 377.742152 -239.166055) (xy 377.718574 -239.212329) (xy 377.688048 -239.254345)
			(xy 377.651325 -239.291068) (xy 377.609309 -239.321594) (xy 377.563035 -239.345172) (xy 377.513642 -239.36122)
			(xy 377.462347 -239.369345) (xy 377.410413 -239.369345) (xy 377.359118 -239.36122) (xy 377.309725 -239.345172)
			(xy 377.263451 -239.321594) (xy 377.221435 -239.291068) (xy 377.184712 -239.254345) (xy 377.154186 -239.212329)
			(xy 377.130608 -239.166055) (xy 377.11456 -239.116662) (xy 377.106435 -239.065367) (xy 376.826779 -239.065367)
			(xy 376.818654 -239.116662) (xy 376.802606 -239.166055) (xy 376.779028 -239.212329) (xy 376.748502 -239.254345)
			(xy 376.711779 -239.291068) (xy 376.669763 -239.321594) (xy 376.623489 -239.345172) (xy 376.574096 -239.36122)
			(xy 376.522801 -239.369345) (xy 376.470867 -239.369345) (xy 376.419572 -239.36122) (xy 376.370179 -239.345172)
			(xy 376.323905 -239.321594) (xy 376.281889 -239.291068) (xy 376.245166 -239.254345) (xy 376.21464 -239.212329)
			(xy 376.191062 -239.166055) (xy 376.175014 -239.116662) (xy 376.166889 -239.065367) (xy 375.886979 -239.065367)
			(xy 375.878854 -239.116662) (xy 375.862806 -239.166055) (xy 375.839228 -239.212329) (xy 375.808702 -239.254345)
			(xy 375.771979 -239.291068) (xy 375.729963 -239.321594) (xy 375.683689 -239.345172) (xy 375.634296 -239.36122)
			(xy 375.583001 -239.369345) (xy 375.531067 -239.369345) (xy 375.479772 -239.36122) (xy 375.430379 -239.345172)
			(xy 375.384105 -239.321594) (xy 375.342089 -239.291068) (xy 375.305366 -239.254345) (xy 375.27484 -239.212329)
			(xy 375.251262 -239.166055) (xy 375.235214 -239.116662) (xy 375.227089 -239.065367) (xy 374.947179 -239.065367)
			(xy 374.939054 -239.116662) (xy 374.923006 -239.166055) (xy 374.899428 -239.212329) (xy 374.868902 -239.254345)
			(xy 374.832179 -239.291068) (xy 374.790163 -239.321594) (xy 374.743889 -239.345172) (xy 374.694496 -239.36122)
			(xy 374.643201 -239.369345) (xy 374.591267 -239.369345) (xy 374.539972 -239.36122) (xy 374.490579 -239.345172)
			(xy 374.444305 -239.321594) (xy 374.402289 -239.291068) (xy 374.365566 -239.254345) (xy 374.33504 -239.212329)
			(xy 374.311462 -239.166055) (xy 374.295414 -239.116662) (xy 374.287289 -239.065367) (xy 374.007379 -239.065367)
			(xy 373.999254 -239.116662) (xy 373.983206 -239.166055) (xy 373.959628 -239.212329) (xy 373.929102 -239.254345)
			(xy 373.892379 -239.291068) (xy 373.850363 -239.321594) (xy 373.804089 -239.345172) (xy 373.754696 -239.36122)
			(xy 373.703401 -239.369345) (xy 373.651467 -239.369345) (xy 373.600172 -239.36122) (xy 373.550779 -239.345172)
			(xy 373.504505 -239.321594) (xy 373.462489 -239.291068) (xy 373.425766 -239.254345) (xy 373.39524 -239.212329)
			(xy 373.371662 -239.166055) (xy 373.355614 -239.116662) (xy 373.347489 -239.065367) (xy 373.067579 -239.065367)
			(xy 373.059454 -239.116662) (xy 373.043406 -239.166055) (xy 373.019828 -239.212329) (xy 372.989302 -239.254345)
			(xy 372.952579 -239.291068) (xy 372.910563 -239.321594) (xy 372.864289 -239.345172) (xy 372.814896 -239.36122)
			(xy 372.763601 -239.369345) (xy 372.711667 -239.369345) (xy 372.660372 -239.36122) (xy 372.610979 -239.345172)
			(xy 372.564705 -239.321594) (xy 372.522689 -239.291068) (xy 372.485966 -239.254345) (xy 372.45544 -239.212329)
			(xy 372.431862 -239.166055) (xy 372.415814 -239.116662) (xy 372.407689 -239.065367) (xy 372.127779 -239.065367)
			(xy 372.119654 -239.116662) (xy 372.103606 -239.166055) (xy 372.080028 -239.212329) (xy 372.049502 -239.254345)
			(xy 372.012779 -239.291068) (xy 371.970763 -239.321594) (xy 371.924489 -239.345172) (xy 371.875096 -239.36122)
			(xy 371.823801 -239.369345) (xy 371.771867 -239.369345) (xy 371.720572 -239.36122) (xy 371.671179 -239.345172)
			(xy 371.624905 -239.321594) (xy 371.582889 -239.291068) (xy 371.546166 -239.254345) (xy 371.51564 -239.212329)
			(xy 371.492062 -239.166055) (xy 371.476014 -239.116662) (xy 371.467889 -239.065367) (xy 371.187725 -239.065367)
			(xy 371.1796 -239.116662) (xy 371.163552 -239.166055) (xy 371.139974 -239.212329) (xy 371.109448 -239.254345)
			(xy 371.072725 -239.291068) (xy 371.030709 -239.321594) (xy 370.984435 -239.345172) (xy 370.935042 -239.36122)
			(xy 370.883747 -239.369345) (xy 370.831813 -239.369345) (xy 370.780518 -239.36122) (xy 370.731125 -239.345172)
			(xy 370.684851 -239.321594) (xy 370.642835 -239.291068) (xy 370.606112 -239.254345) (xy 370.575586 -239.212329)
			(xy 370.552008 -239.166055) (xy 370.53596 -239.116662) (xy 370.527835 -239.065367) (xy 370.248179 -239.065367)
			(xy 370.240054 -239.116662) (xy 370.224006 -239.166055) (xy 370.200428 -239.212329) (xy 370.169902 -239.254345)
			(xy 370.133179 -239.291068) (xy 370.091163 -239.321594) (xy 370.044889 -239.345172) (xy 369.995496 -239.36122)
			(xy 369.944201 -239.369345) (xy 369.892267 -239.369345) (xy 369.840972 -239.36122) (xy 369.791579 -239.345172)
			(xy 369.745305 -239.321594) (xy 369.703289 -239.291068) (xy 369.666566 -239.254345) (xy 369.63604 -239.212329)
			(xy 369.612462 -239.166055) (xy 369.596414 -239.116662) (xy 369.588289 -239.065367) (xy 366.748015 -239.065367)
			(xy 366.774135 -239.091488) (xy 366.804656 -239.133498) (xy 366.82823 -239.179765) (xy 366.844276 -239.22915)
			(xy 366.852399 -239.280437) (xy 366.852399 -239.332363) (xy 366.844276 -239.38365) (xy 366.82823 -239.433035)
			(xy 366.804656 -239.479302) (xy 366.774135 -239.521312) (xy 366.737418 -239.55803) (xy 366.695409 -239.588552)
			(xy 366.649143 -239.612127) (xy 366.599758 -239.628174) (xy 366.548471 -239.636298) (xy 366.522508 -239.636808)
			(xy 366.522254 -239.636808) (xy 366.497726 -239.636382) (xy 366.449213 -239.629112) (xy 366.402305 -239.614755)
			(xy 366.358034 -239.593624) (xy 366.317371 -239.566184) (xy 366.298988 -239.54994) (xy 366.287499 -239.540137)
			(xy 366.260262 -239.527123) (xy 366.230408 -239.522655) (xy 366.200554 -239.527123) (xy 366.173317 -239.540137)
			(xy 366.161828 -239.54994) (xy 366.143423 -239.566198) (xy 366.10272 -239.593668) (xy 366.058397 -239.614808)
			(xy 366.011432 -239.629151) (xy 365.962861 -239.63638) (xy 365.938308 -239.636808) (xy 365.913755 -239.636399)
			(xy 365.865186 -239.629152) (xy 365.818224 -239.614801) (xy 365.7739 -239.593662) (xy 365.733191 -239.5662)
			(xy 365.714788 -239.54994) (xy 365.703299 -239.540137) (xy 365.676062 -239.527123) (xy 365.646208 -239.522655)
			(xy 365.616354 -239.527123) (xy 365.589117 -239.540137) (xy 365.577628 -239.54994) (xy 365.559243 -239.566182)
			(xy 365.518586 -239.59363) (xy 365.474315 -239.614762) (xy 365.427406 -239.629111) (xy 365.37889 -239.636363)
			(xy 365.354362 -239.636808) (xy 365.354108 -239.636808) (xy 365.328135 -239.636418) (xy 365.276827 -239.628292)
			(xy 365.227423 -239.612241) (xy 365.181138 -239.588659) (xy 365.139112 -239.558126) (xy 365.102379 -239.521394)
			(xy 365.071846 -239.479369) (xy 365.048262 -239.433084) (xy 365.032209 -239.38368) (xy 365.024083 -239.332373)
			(xy 363.480787 -239.332373) (xy 363.480439 -239.352751) (xy 363.473193 -239.401318) (xy 363.458843 -239.44828)
			(xy 363.437707 -239.492604) (xy 363.410248 -239.533314) (xy 363.39399 -239.551718) (xy 363.384191 -239.56321)
			(xy 363.371182 -239.590447) (xy 363.366715 -239.620299) (xy 363.371181 -239.65015) (xy 363.38419 -239.677388)
			(xy 363.39399 -239.688878) (xy 363.410243 -239.707254) (xy 363.437688 -239.747914) (xy 363.458816 -239.792187)
			(xy 363.473163 -239.839098) (xy 363.480413 -239.887616) (xy 363.480858 -239.912144) (xy 363.480858 -239.912398)
			(xy 363.480349 -239.938365) (xy 363.472224 -239.98966) (xy 363.456176 -240.039053) (xy 363.432598 -240.085327)
			(xy 363.402072 -240.127343) (xy 363.365349 -240.164066) (xy 363.323333 -240.194592) (xy 363.277059 -240.21817)
			(xy 363.227666 -240.234218) (xy 363.176371 -240.242343) (xy 363.124437 -240.242343) (xy 363.073142 -240.234218)
			(xy 363.023749 -240.21817) (xy 362.977475 -240.194592) (xy 362.935459 -240.164066) (xy 362.898736 -240.127343)
			(xy 362.86821 -240.085327) (xy 362.844632 -240.039053) (xy 362.828584 -239.98966) (xy 362.820459 -239.938365)
			(xy 362.81995 -239.912398) (xy 362.254618 -239.912398) (xy 362.251754 -239.930478) (xy 362.235706 -239.979871)
			(xy 362.212128 -240.026145) (xy 362.181602 -240.068161) (xy 362.144879 -240.104884) (xy 362.102863 -240.13541)
			(xy 362.056589 -240.158988) (xy 362.007196 -240.175036) (xy 361.955901 -240.183161) (xy 361.903967 -240.183161)
			(xy 361.852672 -240.175036) (xy 361.803279 -240.158988) (xy 361.757005 -240.13541) (xy 361.714989 -240.104884)
			(xy 361.678266 -240.068161) (xy 361.64774 -240.026145) (xy 361.624162 -239.979871) (xy 361.608114 -239.930478)
			(xy 361.599989 -239.879183) (xy 361.319825 -239.879183) (xy 361.3117 -239.930478) (xy 361.295652 -239.979871)
			(xy 361.272074 -240.026145) (xy 361.241548 -240.068161) (xy 361.204825 -240.104884) (xy 361.162809 -240.13541)
			(xy 361.116535 -240.158988) (xy 361.067142 -240.175036) (xy 361.015847 -240.183161) (xy 360.963913 -240.183161)
			(xy 360.912618 -240.175036) (xy 360.863225 -240.158988) (xy 360.816951 -240.13541) (xy 360.774935 -240.104884)
			(xy 360.738212 -240.068161) (xy 360.707686 -240.026145) (xy 360.684108 -239.979871) (xy 360.66806 -239.930478)
			(xy 360.659935 -239.879183) (xy 360.380279 -239.879183) (xy 360.372154 -239.930478) (xy 360.356106 -239.979871)
			(xy 360.332528 -240.026145) (xy 360.302002 -240.068161) (xy 360.265279 -240.104884) (xy 360.223263 -240.13541)
			(xy 360.176989 -240.158988) (xy 360.127596 -240.175036) (xy 360.076301 -240.183161) (xy 360.024367 -240.183161)
			(xy 359.973072 -240.175036) (xy 359.923679 -240.158988) (xy 359.877405 -240.13541) (xy 359.835389 -240.104884)
			(xy 359.798666 -240.068161) (xy 359.76814 -240.026145) (xy 359.744562 -239.979871) (xy 359.728514 -239.930478)
			(xy 359.720389 -239.879183) (xy 359.440479 -239.879183) (xy 359.432354 -239.930478) (xy 359.416306 -239.979871)
			(xy 359.392728 -240.026145) (xy 359.362202 -240.068161) (xy 359.325479 -240.104884) (xy 359.283463 -240.13541)
			(xy 359.237189 -240.158988) (xy 359.187796 -240.175036) (xy 359.136501 -240.183161) (xy 359.084567 -240.183161)
			(xy 359.033272 -240.175036) (xy 358.983879 -240.158988) (xy 358.937605 -240.13541) (xy 358.895589 -240.104884)
			(xy 358.858866 -240.068161) (xy 358.82834 -240.026145) (xy 358.804762 -239.979871) (xy 358.788714 -239.930478)
			(xy 358.780589 -239.879183) (xy 358.500679 -239.879183) (xy 358.492554 -239.930478) (xy 358.476506 -239.979871)
			(xy 358.452928 -240.026145) (xy 358.422402 -240.068161) (xy 358.385679 -240.104884) (xy 358.343663 -240.13541)
			(xy 358.297389 -240.158988) (xy 358.247996 -240.175036) (xy 358.196701 -240.183161) (xy 358.144767 -240.183161)
			(xy 358.093472 -240.175036) (xy 358.044079 -240.158988) (xy 357.997805 -240.13541) (xy 357.955789 -240.104884)
			(xy 357.919066 -240.068161) (xy 357.88854 -240.026145) (xy 357.864962 -239.979871) (xy 357.848914 -239.930478)
			(xy 357.840789 -239.879183) (xy 357.560858 -239.879183) (xy 357.552737 -239.930461) (xy 357.53669 -239.979853)
			(xy 357.513114 -240.026127) (xy 357.48259 -240.068143) (xy 357.445869 -240.104868) (xy 357.403856 -240.135396)
			(xy 357.357585 -240.158977) (xy 357.308194 -240.175029) (xy 357.256901 -240.183158) (xy 357.230934 -240.18367)
			(xy 357.203941 -240.183105) (xy 357.150673 -240.174335) (xy 357.099539 -240.157023) (xy 357.0519 -240.131629)
			(xy 357.009021 -240.098829) (xy 356.990142 -240.07953) (xy 356.980752 -240.070039) (xy 356.958086 -240.055945)
			(xy 356.932541 -240.048211) (xy 356.905864 -240.047366) (xy 356.87988 -240.053468) (xy 356.856368 -240.0661)
			(xy 356.846378 -240.074958) (xy 356.827902 -240.091721) (xy 356.786827 -240.120034) (xy 356.741963 -240.14185)
			(xy 356.694329 -240.156673) (xy 356.645008 -240.164167) (xy 356.620064 -240.16462) (xy 356.594094 -240.164178)
			(xy 356.542795 -240.156047) (xy 356.493399 -240.139991) (xy 356.447122 -240.116406) (xy 356.405105 -240.085872)
			(xy 356.368382 -240.049141) (xy 356.337857 -240.007118) (xy 356.314282 -239.960837) (xy 356.298237 -239.911437)
			(xy 356.290117 -239.860136) (xy 356.28961 -239.834166) (xy 349.102561 -239.834166) (xy 349.102934 -239.853216)
			(xy 349.102425 -239.879183) (xy 349.0943 -239.930478) (xy 349.078252 -239.979871) (xy 349.054674 -240.026145)
			(xy 349.024148 -240.068161) (xy 348.987425 -240.104884) (xy 348.945409 -240.13541) (xy 348.899135 -240.158988)
			(xy 348.849742 -240.175036) (xy 348.798447 -240.183161) (xy 348.746513 -240.183161) (xy 348.695218 -240.175036)
			(xy 348.645825 -240.158988) (xy 348.599551 -240.13541) (xy 348.557535 -240.104884) (xy 348.520812 -240.068161)
			(xy 348.490286 -240.026145) (xy 348.466708 -239.979871) (xy 348.45066 -239.930478) (xy 348.442535 -239.879183)
			(xy 348.162625 -239.879183) (xy 348.1545 -239.930478) (xy 348.138452 -239.979871) (xy 348.114874 -240.026145)
			(xy 348.084348 -240.068161) (xy 348.047625 -240.104884) (xy 348.005609 -240.13541) (xy 347.959335 -240.158988)
			(xy 347.909942 -240.175036) (xy 347.858647 -240.183161) (xy 347.806713 -240.183161) (xy 347.755418 -240.175036)
			(xy 347.706025 -240.158988) (xy 347.659751 -240.13541) (xy 347.617735 -240.104884) (xy 347.581012 -240.068161)
			(xy 347.550486 -240.026145) (xy 347.526908 -239.979871) (xy 347.51086 -239.930478) (xy 347.502735 -239.879183)
			(xy 347.222825 -239.879183) (xy 347.2147 -239.930478) (xy 347.198652 -239.979871) (xy 347.175074 -240.026145)
			(xy 347.144548 -240.068161) (xy 347.107825 -240.104884) (xy 347.065809 -240.13541) (xy 347.019535 -240.158988)
			(xy 346.970142 -240.175036) (xy 346.918847 -240.183161) (xy 346.866913 -240.183161) (xy 346.815618 -240.175036)
			(xy 346.766225 -240.158988) (xy 346.719951 -240.13541) (xy 346.677935 -240.104884) (xy 346.641212 -240.068161)
			(xy 346.610686 -240.026145) (xy 346.587108 -239.979871) (xy 346.57106 -239.930478) (xy 346.562935 -239.879183)
			(xy 346.283025 -239.879183) (xy 346.2749 -239.930478) (xy 346.258852 -239.979871) (xy 346.235274 -240.026145)
			(xy 346.204748 -240.068161) (xy 346.168025 -240.104884) (xy 346.126009 -240.13541) (xy 346.079735 -240.158988)
			(xy 346.030342 -240.175036) (xy 345.979047 -240.183161) (xy 345.927113 -240.183161) (xy 345.875818 -240.175036)
			(xy 345.826425 -240.158988) (xy 345.780151 -240.13541) (xy 345.738135 -240.104884) (xy 345.701412 -240.068161)
			(xy 345.670886 -240.026145) (xy 345.647308 -239.979871) (xy 345.63126 -239.930478) (xy 345.623135 -239.879183)
			(xy 345.343479 -239.879183) (xy 345.335354 -239.930478) (xy 345.319306 -239.979871) (xy 345.295728 -240.026145)
			(xy 345.265202 -240.068161) (xy 345.228479 -240.104884) (xy 345.186463 -240.13541) (xy 345.140189 -240.158988)
			(xy 345.090796 -240.175036) (xy 345.039501 -240.183161) (xy 344.987567 -240.183161) (xy 344.936272 -240.175036)
			(xy 344.886879 -240.158988) (xy 344.840605 -240.13541) (xy 344.798589 -240.104884) (xy 344.761866 -240.068161)
			(xy 344.73134 -240.026145) (xy 344.707762 -239.979871) (xy 344.691714 -239.930478) (xy 344.683589 -239.879183)
			(xy 344.403425 -239.879183) (xy 344.3953 -239.930478) (xy 344.379252 -239.979871) (xy 344.355674 -240.026145)
			(xy 344.325148 -240.068161) (xy 344.288425 -240.104884) (xy 344.246409 -240.13541) (xy 344.200135 -240.158988)
			(xy 344.150742 -240.175036) (xy 344.099447 -240.183161) (xy 344.047513 -240.183161) (xy 343.996218 -240.175036)
			(xy 343.946825 -240.158988) (xy 343.900551 -240.13541) (xy 343.858535 -240.104884) (xy 343.821812 -240.068161)
			(xy 343.791286 -240.026145) (xy 343.767708 -239.979871) (xy 343.75166 -239.930478) (xy 343.743535 -239.879183)
			(xy 343.463625 -239.879183) (xy 343.4555 -239.930478) (xy 343.439452 -239.979871) (xy 343.415874 -240.026145)
			(xy 343.385348 -240.068161) (xy 343.348625 -240.104884) (xy 343.306609 -240.13541) (xy 343.260335 -240.158988)
			(xy 343.210942 -240.175036) (xy 343.159647 -240.183161) (xy 343.107713 -240.183161) (xy 343.056418 -240.175036)
			(xy 343.007025 -240.158988) (xy 342.960751 -240.13541) (xy 342.918735 -240.104884) (xy 342.882012 -240.068161)
			(xy 342.851486 -240.026145) (xy 342.827908 -239.979871) (xy 342.81186 -239.930478) (xy 342.803735 -239.879183)
			(xy 342.523825 -239.879183) (xy 342.5157 -239.930478) (xy 342.499652 -239.979871) (xy 342.476074 -240.026145)
			(xy 342.445548 -240.068161) (xy 342.408825 -240.104884) (xy 342.366809 -240.13541) (xy 342.320535 -240.158988)
			(xy 342.271142 -240.175036) (xy 342.219847 -240.183161) (xy 342.167913 -240.183161) (xy 342.116618 -240.175036)
			(xy 342.067225 -240.158988) (xy 342.020951 -240.13541) (xy 341.978935 -240.104884) (xy 341.942212 -240.068161)
			(xy 341.911686 -240.026145) (xy 341.888108 -239.979871) (xy 341.87206 -239.930478) (xy 341.863935 -239.879183)
			(xy 341.584025 -239.879183) (xy 341.5759 -239.930478) (xy 341.559852 -239.979871) (xy 341.536274 -240.026145)
			(xy 341.505748 -240.068161) (xy 341.469025 -240.104884) (xy 341.427009 -240.13541) (xy 341.380735 -240.158988)
			(xy 341.331342 -240.175036) (xy 341.280047 -240.183161) (xy 341.228113 -240.183161) (xy 341.176818 -240.175036)
			(xy 341.127425 -240.158988) (xy 341.081151 -240.13541) (xy 341.039135 -240.104884) (xy 341.002412 -240.068161)
			(xy 340.971886 -240.026145) (xy 340.948308 -239.979871) (xy 340.93226 -239.930478) (xy 340.924135 -239.879183)
			(xy 340.644225 -239.879183) (xy 340.6361 -239.930478) (xy 340.620052 -239.979871) (xy 340.596474 -240.026145)
			(xy 340.565948 -240.068161) (xy 340.529225 -240.104884) (xy 340.487209 -240.13541) (xy 340.440935 -240.158988)
			(xy 340.391542 -240.175036) (xy 340.340247 -240.183161) (xy 340.288313 -240.183161) (xy 340.237018 -240.175036)
			(xy 340.187625 -240.158988) (xy 340.141351 -240.13541) (xy 340.099335 -240.104884) (xy 340.062612 -240.068161)
			(xy 340.032086 -240.026145) (xy 340.008508 -239.979871) (xy 339.99246 -239.930478) (xy 339.984335 -239.879183)
			(xy 339.704771 -239.879183) (xy 339.704771 -239.879756) (xy 339.696288 -239.932173) (xy 339.67954 -239.982562)
			(xy 339.654959 -240.029628) (xy 339.623175 -240.072163) (xy 339.585004 -240.109075) (xy 339.541427 -240.139416)
			(xy 339.517736 -240.151412) (xy 339.505036 -240.157508) (xy 339.475064 -240.202974) (xy 339.475064 -240.33099)
			(xy 339.475483 -240.339885) (xy 339.481753 -240.356541) (xy 339.493386 -240.370009) (xy 339.500972 -240.374678)
			(xy 339.584284 -240.414556) (xy 339.5923 -240.417454) (xy 339.609314 -240.418243) (xy 339.617558 -240.41608)
			(xy 339.638132 -240.408714) (xy 339.64118 -240.406682) (xy 339.644736 -240.403888) (xy 339.666444 -240.38808)
			(xy 339.713904 -240.362963) (xy 339.764796 -240.345834) (xy 339.817786 -240.337142) (xy 339.844634 -240.336578)
			(xy 339.870621 -240.33709) (xy 339.921953 -240.345225) (xy 339.971381 -240.36129) (xy 340.017688 -240.384889)
			(xy 340.059733 -240.41544) (xy 340.096482 -240.452193) (xy 340.127029 -240.494241) (xy 340.150623 -240.54055)
			(xy 340.166683 -240.58998) (xy 340.174813 -240.641313) (xy 340.174813 -240.693253) (xy 340.454489 -240.693253)
			(xy 340.454489 -240.641319) (xy 340.462614 -240.590024) (xy 340.478662 -240.540631) (xy 340.50224 -240.494357)
			(xy 340.532766 -240.452341) (xy 340.569489 -240.415618) (xy 340.611505 -240.385092) (xy 340.657779 -240.361514)
			(xy 340.707172 -240.345466) (xy 340.758467 -240.337341) (xy 340.810401 -240.337341) (xy 340.861696 -240.345466)
			(xy 340.911089 -240.361514) (xy 340.957363 -240.385092) (xy 340.999379 -240.415618) (xy 341.036102 -240.452341)
			(xy 341.066628 -240.494357) (xy 341.090206 -240.540631) (xy 341.106254 -240.590024) (xy 341.114379 -240.641319)
			(xy 341.114888 -240.667286) (xy 341.114379 -240.693253) (xy 341.394289 -240.693253) (xy 341.394289 -240.641319)
			(xy 341.402414 -240.590024) (xy 341.418462 -240.540631) (xy 341.44204 -240.494357) (xy 341.472566 -240.452341)
			(xy 341.509289 -240.415618) (xy 341.551305 -240.385092) (xy 341.597579 -240.361514) (xy 341.646972 -240.345466)
			(xy 341.698267 -240.337341) (xy 341.750201 -240.337341) (xy 341.801496 -240.345466) (xy 341.850889 -240.361514)
			(xy 341.897163 -240.385092) (xy 341.939179 -240.415618) (xy 341.975902 -240.452341) (xy 342.006428 -240.494357)
			(xy 342.030006 -240.540631) (xy 342.046054 -240.590024) (xy 342.054179 -240.641319) (xy 342.054688 -240.667286)
			(xy 342.054179 -240.693253) (xy 342.334089 -240.693253) (xy 342.334089 -240.641319) (xy 342.342214 -240.590024)
			(xy 342.358262 -240.540631) (xy 342.38184 -240.494357) (xy 342.412366 -240.452341) (xy 342.449089 -240.415618)
			(xy 342.491105 -240.385092) (xy 342.537379 -240.361514) (xy 342.586772 -240.345466) (xy 342.638067 -240.337341)
			(xy 342.690001 -240.337341) (xy 342.741296 -240.345466) (xy 342.790689 -240.361514) (xy 342.836963 -240.385092)
			(xy 342.878979 -240.415618) (xy 342.915702 -240.452341) (xy 342.946228 -240.494357) (xy 342.969806 -240.540631)
			(xy 342.985854 -240.590024) (xy 342.993979 -240.641319) (xy 342.994488 -240.667286) (xy 342.993979 -240.693253)
			(xy 343.273889 -240.693253) (xy 343.273889 -240.641319) (xy 343.282014 -240.590024) (xy 343.298062 -240.540631)
			(xy 343.32164 -240.494357) (xy 343.352166 -240.452341) (xy 343.388889 -240.415618) (xy 343.430905 -240.385092)
			(xy 343.477179 -240.361514) (xy 343.526572 -240.345466) (xy 343.577867 -240.337341) (xy 343.629801 -240.337341)
			(xy 343.681096 -240.345466) (xy 343.730489 -240.361514) (xy 343.776763 -240.385092) (xy 343.818779 -240.415618)
			(xy 343.855502 -240.452341) (xy 343.886028 -240.494357) (xy 343.909606 -240.540631) (xy 343.925654 -240.590024)
			(xy 343.933779 -240.641319) (xy 343.934288 -240.667286) (xy 343.933779 -240.693253) (xy 344.213689 -240.693253)
			(xy 344.213689 -240.641319) (xy 344.221814 -240.590024) (xy 344.237862 -240.540631) (xy 344.26144 -240.494357)
			(xy 344.291966 -240.452341) (xy 344.328689 -240.415618) (xy 344.370705 -240.385092) (xy 344.416979 -240.361514)
			(xy 344.466372 -240.345466) (xy 344.517667 -240.337341) (xy 344.569601 -240.337341) (xy 344.620896 -240.345466)
			(xy 344.670289 -240.361514) (xy 344.716563 -240.385092) (xy 344.758579 -240.415618) (xy 344.795302 -240.452341)
			(xy 344.825828 -240.494357) (xy 344.849406 -240.540631) (xy 344.865454 -240.590024) (xy 344.873579 -240.641319)
			(xy 344.874088 -240.667286) (xy 344.873579 -240.693253) (xy 345.153235 -240.693253) (xy 345.153235 -240.641319)
			(xy 345.16136 -240.590024) (xy 345.177408 -240.540631) (xy 345.200986 -240.494357) (xy 345.231512 -240.452341)
			(xy 345.268235 -240.415618) (xy 345.310251 -240.385092) (xy 345.356525 -240.361514) (xy 345.405918 -240.345466)
			(xy 345.457213 -240.337341) (xy 345.509147 -240.337341) (xy 345.560442 -240.345466) (xy 345.609835 -240.361514)
			(xy 345.656109 -240.385092) (xy 345.698125 -240.415618) (xy 345.734848 -240.452341) (xy 345.765374 -240.494357)
			(xy 345.788952 -240.540631) (xy 345.805 -240.590024) (xy 345.813125 -240.641319) (xy 345.813634 -240.667286)
			(xy 345.813125 -240.693253) (xy 346.093289 -240.693253) (xy 346.093289 -240.641319) (xy 346.101414 -240.590024)
			(xy 346.117462 -240.540631) (xy 346.14104 -240.494357) (xy 346.171566 -240.452341) (xy 346.208289 -240.415618)
			(xy 346.250305 -240.385092) (xy 346.296579 -240.361514) (xy 346.345972 -240.345466) (xy 346.397267 -240.337341)
			(xy 346.449201 -240.337341) (xy 346.500496 -240.345466) (xy 346.549889 -240.361514) (xy 346.596163 -240.385092)
			(xy 346.638179 -240.415618) (xy 346.674902 -240.452341) (xy 346.705428 -240.494357) (xy 346.729006 -240.540631)
			(xy 346.745054 -240.590024) (xy 346.753179 -240.641319) (xy 346.753688 -240.667286) (xy 346.753179 -240.693253)
			(xy 347.033089 -240.693253) (xy 347.033089 -240.641319) (xy 347.041214 -240.590024) (xy 347.057262 -240.540631)
			(xy 347.08084 -240.494357) (xy 347.111366 -240.452341) (xy 347.148089 -240.415618) (xy 347.190105 -240.385092)
			(xy 347.236379 -240.361514) (xy 347.285772 -240.345466) (xy 347.337067 -240.337341) (xy 347.389001 -240.337341)
			(xy 347.440296 -240.345466) (xy 347.489689 -240.361514) (xy 347.535963 -240.385092) (xy 347.577979 -240.415618)
			(xy 347.614702 -240.452341) (xy 347.645228 -240.494357) (xy 347.668806 -240.540631) (xy 347.684854 -240.590024)
			(xy 347.692979 -240.641319) (xy 347.693488 -240.667286) (xy 347.692979 -240.693253) (xy 347.972889 -240.693253)
			(xy 347.972889 -240.641319) (xy 347.981014 -240.590024) (xy 347.997062 -240.540631) (xy 348.02064 -240.494357)
			(xy 348.051166 -240.452341) (xy 348.087889 -240.415618) (xy 348.129905 -240.385092) (xy 348.176179 -240.361514)
			(xy 348.225572 -240.345466) (xy 348.276867 -240.337341) (xy 348.328801 -240.337341) (xy 348.380096 -240.345466)
			(xy 348.429489 -240.361514) (xy 348.475763 -240.385092) (xy 348.517779 -240.415618) (xy 348.554502 -240.452341)
			(xy 348.585028 -240.494357) (xy 348.608606 -240.540631) (xy 348.624654 -240.590024) (xy 348.632779 -240.641319)
			(xy 348.633288 -240.667286) (xy 348.632779 -240.693253) (xy 348.912689 -240.693253) (xy 348.912689 -240.641319)
			(xy 348.920814 -240.590024) (xy 348.936862 -240.540631) (xy 348.96044 -240.494357) (xy 348.990966 -240.452341)
			(xy 349.027689 -240.415618) (xy 349.069705 -240.385092) (xy 349.115979 -240.361514) (xy 349.165372 -240.345466)
			(xy 349.216667 -240.337341) (xy 349.268601 -240.337341) (xy 349.319896 -240.345466) (xy 349.369289 -240.361514)
			(xy 349.415563 -240.385092) (xy 349.457579 -240.415618) (xy 349.494302 -240.452341) (xy 349.524828 -240.494357)
			(xy 349.548406 -240.540631) (xy 349.564454 -240.590024) (xy 349.572579 -240.641319) (xy 349.573088 -240.667286)
			(xy 349.572579 -240.693253) (xy 349.572576 -240.693272) (xy 349.852415 -240.693272) (xy 349.852415 -240.641328)
			(xy 349.860541 -240.590023) (xy 349.876594 -240.540622) (xy 349.900178 -240.49434) (xy 349.930711 -240.452317)
			(xy 349.967443 -240.415589) (xy 350.009469 -240.38506) (xy 350.055753 -240.361481) (xy 350.105156 -240.345433)
			(xy 350.156462 -240.337312) (xy 350.182434 -240.336832) (xy 350.206136 -240.337257) (xy 350.253054 -240.344018)
			(xy 350.298527 -240.357409) (xy 350.341621 -240.377157) (xy 350.361758 -240.389664) (xy 350.374555 -240.397338)
			(xy 350.403222 -240.405573) (xy 350.433047 -240.40518) (xy 350.461487 -240.39619) (xy 350.486119 -240.37937)
			(xy 350.504844 -240.356154) (xy 350.516068 -240.328519) (xy 350.517968 -240.313718) (xy 350.520982 -240.28675)
			(xy 350.534816 -240.234281) (xy 350.557039 -240.184778) (xy 350.587054 -240.139573) (xy 350.624053 -240.09988)
			(xy 350.667041 -240.066768) (xy 350.714862 -240.041126) (xy 350.766231 -240.023644) (xy 350.819767 -240.014792)
			(xy 350.846898 -240.014252) (xy 350.872868 -240.014731) (xy 350.924167 -240.022856) (xy 350.973564 -240.038906)
			(xy 351.019842 -240.062485) (xy 351.061862 -240.093015) (xy 351.098588 -240.129741) (xy 351.129117 -240.171761)
			(xy 351.152696 -240.21804) (xy 351.168745 -240.267437) (xy 351.17687 -240.318736) (xy 351.177352 -240.344706)
			(xy 351.177352 -240.34496) (xy 351.176863 -240.369485) (xy 351.169607 -240.417996) (xy 351.155263 -240.464902)
			(xy 351.134147 -240.509174) (xy 351.106722 -240.549841) (xy 351.090484 -240.568226) (xy 351.080678 -240.579712)
			(xy 351.06767 -240.606951) (xy 351.063205 -240.636804) (xy 351.067673 -240.666658) (xy 351.080683 -240.693896)
			(xy 351.090484 -240.705386) (xy 351.10674 -240.723759) (xy 351.134184 -240.76442) (xy 351.155313 -240.808694)
			(xy 351.169659 -240.855606) (xy 351.176908 -240.904124) (xy 351.177352 -240.928652) (xy 351.177352 -240.928906)
			(xy 351.17685 -240.954873) (xy 351.168725 -241.006169) (xy 351.152675 -241.055562) (xy 351.129097 -241.101836)
			(xy 351.09857 -241.143852) (xy 351.069929 -241.172492) (xy 356.03561 -241.172492) (xy 356.03561 -241.172238)
			(xy 356.036082 -241.147712) (xy 356.04334 -241.0992) (xy 356.057686 -241.052293) (xy 356.078807 -241.008021)
			(xy 356.106238 -240.967356) (xy 356.122478 -240.948972) (xy 356.132289 -240.937489) (xy 356.145302 -240.91025)
			(xy 356.149768 -240.880394) (xy 356.145298 -240.850539) (xy 356.132282 -240.823301) (xy 356.122478 -240.811812)
			(xy 356.106215 -240.793445) (xy 356.078773 -240.752781) (xy 356.057647 -240.708506) (xy 356.043302 -240.661593)
			(xy 356.036054 -240.613075) (xy 356.03561 -240.588546) (xy 356.03561 -240.588292) (xy 356.036119 -240.562325)
			(xy 356.044244 -240.51103) (xy 356.060292 -240.461637) (xy 356.08387 -240.415363) (xy 356.114396 -240.373347)
			(xy 356.151119 -240.336624) (xy 356.193135 -240.306098) (xy 356.239409 -240.28252) (xy 356.288802 -240.266472)
			(xy 356.340097 -240.258347) (xy 356.392031 -240.258347) (xy 356.443326 -240.266472) (xy 356.492719 -240.28252)
			(xy 356.538993 -240.306098) (xy 356.581009 -240.336624) (xy 356.617732 -240.373347) (xy 356.648258 -240.415363)
			(xy 356.671836 -240.461637) (xy 356.687884 -240.51103) (xy 356.696009 -240.562325) (xy 356.696518 -240.588292)
			(xy 356.696518 -240.588546) (xy 356.696089 -240.613073) (xy 356.68882 -240.661587) (xy 356.679128 -240.693253)
			(xy 357.370635 -240.693253) (xy 357.370635 -240.641319) (xy 357.37876 -240.590024) (xy 357.394808 -240.540631)
			(xy 357.418386 -240.494357) (xy 357.448912 -240.452341) (xy 357.485635 -240.415618) (xy 357.527651 -240.385092)
			(xy 357.573925 -240.361514) (xy 357.623318 -240.345466) (xy 357.674613 -240.337341) (xy 357.726547 -240.337341)
			(xy 357.777842 -240.345466) (xy 357.827235 -240.361514) (xy 357.873509 -240.385092) (xy 357.915525 -240.415618)
			(xy 357.952248 -240.452341) (xy 357.982774 -240.494357) (xy 358.006352 -240.540631) (xy 358.0224 -240.590024)
			(xy 358.030525 -240.641319) (xy 358.031034 -240.667286) (xy 358.030525 -240.693253) (xy 358.310689 -240.693253)
			(xy 358.310689 -240.641319) (xy 358.318814 -240.590024) (xy 358.334862 -240.540631) (xy 358.35844 -240.494357)
			(xy 358.388966 -240.452341) (xy 358.425689 -240.415618) (xy 358.467705 -240.385092) (xy 358.513979 -240.361514)
			(xy 358.563372 -240.345466) (xy 358.614667 -240.337341) (xy 358.666601 -240.337341) (xy 358.717896 -240.345466)
			(xy 358.767289 -240.361514) (xy 358.813563 -240.385092) (xy 358.855579 -240.415618) (xy 358.892302 -240.452341)
			(xy 358.922828 -240.494357) (xy 358.946406 -240.540631) (xy 358.962454 -240.590024) (xy 358.970579 -240.641319)
			(xy 358.971088 -240.667286) (xy 358.970579 -240.693253) (xy 359.250235 -240.693253) (xy 359.250235 -240.641319)
			(xy 359.25836 -240.590024) (xy 359.274408 -240.540631) (xy 359.297986 -240.494357) (xy 359.328512 -240.452341)
			(xy 359.365235 -240.415618) (xy 359.407251 -240.385092) (xy 359.453525 -240.361514) (xy 359.502918 -240.345466)
			(xy 359.554213 -240.337341) (xy 359.606147 -240.337341) (xy 359.657442 -240.345466) (xy 359.706835 -240.361514)
			(xy 359.753109 -240.385092) (xy 359.795125 -240.415618) (xy 359.831848 -240.452341) (xy 359.862374 -240.494357)
			(xy 359.885952 -240.540631) (xy 359.902 -240.590024) (xy 359.910125 -240.641319) (xy 359.910634 -240.667286)
			(xy 359.910125 -240.693253) (xy 360.190035 -240.693253) (xy 360.190035 -240.641319) (xy 360.19816 -240.590024)
			(xy 360.214208 -240.540631) (xy 360.237786 -240.494357) (xy 360.268312 -240.452341) (xy 360.305035 -240.415618)
			(xy 360.347051 -240.385092) (xy 360.393325 -240.361514) (xy 360.442718 -240.345466) (xy 360.494013 -240.337341)
			(xy 360.545947 -240.337341) (xy 360.597242 -240.345466) (xy 360.646635 -240.361514) (xy 360.692909 -240.385092)
			(xy 360.734925 -240.415618) (xy 360.771648 -240.452341) (xy 360.802174 -240.494357) (xy 360.825752 -240.540631)
			(xy 360.8418 -240.590024) (xy 360.849925 -240.641319) (xy 360.850434 -240.667286) (xy 360.849925 -240.693253)
			(xy 361.130089 -240.693253) (xy 361.130089 -240.641319) (xy 361.138214 -240.590024) (xy 361.154262 -240.540631)
			(xy 361.17784 -240.494357) (xy 361.208366 -240.452341) (xy 361.245089 -240.415618) (xy 361.287105 -240.385092)
			(xy 361.333379 -240.361514) (xy 361.382772 -240.345466) (xy 361.434067 -240.337341) (xy 361.486001 -240.337341)
			(xy 361.537296 -240.345466) (xy 361.586689 -240.361514) (xy 361.632963 -240.385092) (xy 361.674979 -240.415618)
			(xy 361.711702 -240.452341) (xy 361.742228 -240.494357) (xy 361.765806 -240.540631) (xy 361.781854 -240.590024)
			(xy 361.789979 -240.641319) (xy 361.790488 -240.667286) (xy 361.789979 -240.693253) (xy 362.069889 -240.693253)
			(xy 362.069889 -240.641319) (xy 362.078014 -240.590024) (xy 362.094062 -240.540631) (xy 362.11764 -240.494357)
			(xy 362.148166 -240.452341) (xy 362.184889 -240.415618) (xy 362.226905 -240.385092) (xy 362.273179 -240.361514)
			(xy 362.322572 -240.345466) (xy 362.373867 -240.337341) (xy 362.425801 -240.337341) (xy 362.477096 -240.345466)
			(xy 362.526489 -240.361514) (xy 362.572763 -240.385092) (xy 362.614779 -240.415618) (xy 362.651502 -240.452341)
			(xy 362.682028 -240.494357) (xy 362.705606 -240.540631) (xy 362.721654 -240.590024) (xy 362.729779 -240.641319)
			(xy 362.730288 -240.667286) (xy 362.729779 -240.693253) (xy 362.728058 -240.704116) (xy 368.55908 -240.704116)
			(xy 368.55908 -240.703862) (xy 368.559514 -240.679335) (xy 368.566782 -240.630821) (xy 368.581138 -240.583914)
			(xy 368.602267 -240.539643) (xy 368.629705 -240.498979) (xy 368.645948 -240.480596) (xy 368.655738 -240.469096)
			(xy 368.668757 -240.441863) (xy 368.67323 -240.412012) (xy 368.668764 -240.382159) (xy 368.655751 -240.354924)
			(xy 368.645948 -240.343436) (xy 368.629708 -240.325049) (xy 368.60226 -240.284392) (xy 368.581128 -240.240122)
			(xy 368.566778 -240.193213) (xy 368.559526 -240.144697) (xy 368.55908 -240.12017) (xy 368.55908 -240.119916)
			(xy 368.559544 -240.093945) (xy 368.567667 -240.042644) (xy 368.583717 -239.993244) (xy 368.607298 -239.946964)
			(xy 368.637828 -239.904944) (xy 368.674557 -239.868217) (xy 368.71658 -239.837688) (xy 368.762861 -239.81411)
			(xy 368.812261 -239.798063) (xy 368.863563 -239.789942) (xy 368.889534 -239.789462) (xy 368.890042 -239.789462)
			(xy 368.919109 -239.790115) (xy 368.97634 -239.800327) (xy 369.003834 -239.809782) (xy 369.016671 -239.814147)
			(xy 369.043676 -239.816516) (xy 369.07035 -239.811682) (xy 369.094806 -239.799988) (xy 369.115314 -239.782261)
			(xy 369.130425 -239.759754) (xy 369.135152 -239.747044) (xy 369.143893 -239.722872) (xy 369.167742 -239.677341)
			(xy 369.198352 -239.636052) (xy 369.234987 -239.6) (xy 369.276762 -239.570056) (xy 369.32267 -239.546941)
			(xy 369.371603 -239.531213) (xy 369.422381 -239.523252) (xy 369.44808 -239.522762) (xy 369.474052 -239.523211)
			(xy 369.525356 -239.531334) (xy 369.574757 -239.547383) (xy 369.62104 -239.570963) (xy 369.663064 -239.601493)
			(xy 369.699794 -239.638221) (xy 369.730327 -239.680243) (xy 369.753909 -239.726524) (xy 369.769961 -239.775925)
			(xy 369.778087 -239.827228) (xy 369.778087 -239.879172) (xy 369.778085 -239.879183) (xy 370.058189 -239.879183)
			(xy 370.058189 -239.827249) (xy 370.066314 -239.775954) (xy 370.082362 -239.726561) (xy 370.10594 -239.680287)
			(xy 370.136466 -239.638271) (xy 370.173189 -239.601548) (xy 370.215205 -239.571022) (xy 370.261479 -239.547444)
			(xy 370.310872 -239.531396) (xy 370.362167 -239.523271) (xy 370.414101 -239.523271) (xy 370.465396 -239.531396)
			(xy 370.514789 -239.547444) (xy 370.561063 -239.571022) (xy 370.603079 -239.601548) (xy 370.639802 -239.638271)
			(xy 370.670328 -239.680287) (xy 370.693906 -239.726561) (xy 370.709954 -239.775954) (xy 370.718079 -239.827249)
			(xy 370.718588 -239.853216) (xy 370.718079 -239.879183) (xy 370.997735 -239.879183) (xy 370.997735 -239.827249)
			(xy 371.00586 -239.775954) (xy 371.021908 -239.726561) (xy 371.045486 -239.680287) (xy 371.076012 -239.638271)
			(xy 371.112735 -239.601548) (xy 371.154751 -239.571022) (xy 371.201025 -239.547444) (xy 371.250418 -239.531396)
			(xy 371.301713 -239.523271) (xy 371.353647 -239.523271) (xy 371.404942 -239.531396) (xy 371.454335 -239.547444)
			(xy 371.500609 -239.571022) (xy 371.542625 -239.601548) (xy 371.579348 -239.638271) (xy 371.609874 -239.680287)
			(xy 371.633452 -239.726561) (xy 371.6495 -239.775954) (xy 371.657625 -239.827249) (xy 371.658134 -239.853216)
			(xy 371.657625 -239.879183) (xy 371.937535 -239.879183) (xy 371.937535 -239.827249) (xy 371.94566 -239.775954)
			(xy 371.961708 -239.726561) (xy 371.985286 -239.680287) (xy 372.015812 -239.638271) (xy 372.052535 -239.601548)
			(xy 372.094551 -239.571022) (xy 372.140825 -239.547444) (xy 372.190218 -239.531396) (xy 372.241513 -239.523271)
			(xy 372.293447 -239.523271) (xy 372.344742 -239.531396) (xy 372.394135 -239.547444) (xy 372.440409 -239.571022)
			(xy 372.482425 -239.601548) (xy 372.519148 -239.638271) (xy 372.549674 -239.680287) (xy 372.573252 -239.726561)
			(xy 372.5893 -239.775954) (xy 372.597425 -239.827249) (xy 372.597934 -239.853216) (xy 372.597425 -239.879183)
			(xy 372.877589 -239.879183) (xy 372.877589 -239.827249) (xy 372.885714 -239.775954) (xy 372.901762 -239.726561)
			(xy 372.92534 -239.680287) (xy 372.955866 -239.638271) (xy 372.992589 -239.601548) (xy 373.034605 -239.571022)
			(xy 373.080879 -239.547444) (xy 373.130272 -239.531396) (xy 373.181567 -239.523271) (xy 373.233501 -239.523271)
			(xy 373.284796 -239.531396) (xy 373.334189 -239.547444) (xy 373.380463 -239.571022) (xy 373.422479 -239.601548)
			(xy 373.459202 -239.638271) (xy 373.489728 -239.680287) (xy 373.513306 -239.726561) (xy 373.529354 -239.775954)
			(xy 373.537479 -239.827249) (xy 373.537988 -239.853216) (xy 373.537479 -239.879183) (xy 373.817135 -239.879183)
			(xy 373.817135 -239.827249) (xy 373.82526 -239.775954) (xy 373.841308 -239.726561) (xy 373.864886 -239.680287)
			(xy 373.895412 -239.638271) (xy 373.932135 -239.601548) (xy 373.974151 -239.571022) (xy 374.020425 -239.547444)
			(xy 374.069818 -239.531396) (xy 374.121113 -239.523271) (xy 374.173047 -239.523271) (xy 374.224342 -239.531396)
			(xy 374.273735 -239.547444) (xy 374.320009 -239.571022) (xy 374.362025 -239.601548) (xy 374.398748 -239.638271)
			(xy 374.429274 -239.680287) (xy 374.452852 -239.726561) (xy 374.4689 -239.775954) (xy 374.477025 -239.827249)
			(xy 374.477534 -239.853216) (xy 374.477025 -239.879183) (xy 374.756935 -239.879183) (xy 374.756935 -239.827249)
			(xy 374.76506 -239.775954) (xy 374.781108 -239.726561) (xy 374.804686 -239.680287) (xy 374.835212 -239.638271)
			(xy 374.871935 -239.601548) (xy 374.913951 -239.571022) (xy 374.960225 -239.547444) (xy 375.009618 -239.531396)
			(xy 375.060913 -239.523271) (xy 375.112847 -239.523271) (xy 375.164142 -239.531396) (xy 375.213535 -239.547444)
			(xy 375.259809 -239.571022) (xy 375.301825 -239.601548) (xy 375.338548 -239.638271) (xy 375.369074 -239.680287)
			(xy 375.392652 -239.726561) (xy 375.4087 -239.775954) (xy 375.416825 -239.827249) (xy 375.417334 -239.853216)
			(xy 375.416825 -239.879183) (xy 375.696735 -239.879183) (xy 375.696735 -239.827249) (xy 375.70486 -239.775954)
			(xy 375.720908 -239.726561) (xy 375.744486 -239.680287) (xy 375.775012 -239.638271) (xy 375.811735 -239.601548)
			(xy 375.853751 -239.571022) (xy 375.900025 -239.547444) (xy 375.949418 -239.531396) (xy 376.000713 -239.523271)
			(xy 376.052647 -239.523271) (xy 376.103942 -239.531396) (xy 376.153335 -239.547444) (xy 376.199609 -239.571022)
			(xy 376.241625 -239.601548) (xy 376.278348 -239.638271) (xy 376.308874 -239.680287) (xy 376.332452 -239.726561)
			(xy 376.3485 -239.775954) (xy 376.356625 -239.827249) (xy 376.357134 -239.853216) (xy 376.356625 -239.879183)
			(xy 376.636535 -239.879183) (xy 376.636535 -239.827249) (xy 376.64466 -239.775954) (xy 376.660708 -239.726561)
			(xy 376.684286 -239.680287) (xy 376.714812 -239.638271) (xy 376.751535 -239.601548) (xy 376.793551 -239.571022)
			(xy 376.839825 -239.547444) (xy 376.889218 -239.531396) (xy 376.940513 -239.523271) (xy 376.992447 -239.523271)
			(xy 377.043742 -239.531396) (xy 377.093135 -239.547444) (xy 377.139409 -239.571022) (xy 377.181425 -239.601548)
			(xy 377.218148 -239.638271) (xy 377.248674 -239.680287) (xy 377.272252 -239.726561) (xy 377.2883 -239.775954)
			(xy 377.296425 -239.827249) (xy 377.296934 -239.853216) (xy 377.296425 -239.879183) (xy 377.576335 -239.879183)
			(xy 377.576335 -239.827249) (xy 377.58446 -239.775954) (xy 377.600508 -239.726561) (xy 377.624086 -239.680287)
			(xy 377.654612 -239.638271) (xy 377.691335 -239.601548) (xy 377.733351 -239.571022) (xy 377.779625 -239.547444)
			(xy 377.829018 -239.531396) (xy 377.880313 -239.523271) (xy 377.932247 -239.523271) (xy 377.983542 -239.531396)
			(xy 378.032935 -239.547444) (xy 378.079209 -239.571022) (xy 378.121225 -239.601548) (xy 378.157948 -239.638271)
			(xy 378.188474 -239.680287) (xy 378.212052 -239.726561) (xy 378.2281 -239.775954) (xy 378.236225 -239.827249)
			(xy 378.236734 -239.853216) (xy 378.236225 -239.879183) (xy 378.516135 -239.879183) (xy 378.516135 -239.827249)
			(xy 378.52426 -239.775954) (xy 378.540308 -239.726561) (xy 378.563886 -239.680287) (xy 378.594412 -239.638271)
			(xy 378.631135 -239.601548) (xy 378.673151 -239.571022) (xy 378.719425 -239.547444) (xy 378.768818 -239.531396)
			(xy 378.820113 -239.523271) (xy 378.872047 -239.523271) (xy 378.923342 -239.531396) (xy 378.972735 -239.547444)
			(xy 379.019009 -239.571022) (xy 379.061025 -239.601548) (xy 379.097748 -239.638271) (xy 379.128274 -239.680287)
			(xy 379.151852 -239.726561) (xy 379.1679 -239.775954) (xy 379.176025 -239.827249) (xy 379.176534 -239.853216)
			(xy 379.176025 -239.879183) (xy 379.1679 -239.930478) (xy 379.151852 -239.979871) (xy 379.128274 -240.026145)
			(xy 379.097748 -240.068161) (xy 379.061025 -240.104884) (xy 379.019009 -240.13541) (xy 378.972735 -240.158988)
			(xy 378.923342 -240.175036) (xy 378.872047 -240.183161) (xy 378.820113 -240.183161) (xy 378.768818 -240.175036)
			(xy 378.719425 -240.158988) (xy 378.673151 -240.13541) (xy 378.631135 -240.104884) (xy 378.594412 -240.068161)
			(xy 378.563886 -240.026145) (xy 378.540308 -239.979871) (xy 378.52426 -239.930478) (xy 378.516135 -239.879183)
			(xy 378.236225 -239.879183) (xy 378.2281 -239.930478) (xy 378.212052 -239.979871) (xy 378.188474 -240.026145)
			(xy 378.157948 -240.068161) (xy 378.121225 -240.104884) (xy 378.079209 -240.13541) (xy 378.032935 -240.158988)
			(xy 377.983542 -240.175036) (xy 377.932247 -240.183161) (xy 377.880313 -240.183161) (xy 377.829018 -240.175036)
			(xy 377.779625 -240.158988) (xy 377.733351 -240.13541) (xy 377.691335 -240.104884) (xy 377.654612 -240.068161)
			(xy 377.624086 -240.026145) (xy 377.600508 -239.979871) (xy 377.58446 -239.930478) (xy 377.576335 -239.879183)
			(xy 377.296425 -239.879183) (xy 377.2883 -239.930478) (xy 377.272252 -239.979871) (xy 377.248674 -240.026145)
			(xy 377.218148 -240.068161) (xy 377.181425 -240.104884) (xy 377.139409 -240.13541) (xy 377.093135 -240.158988)
			(xy 377.043742 -240.175036) (xy 376.992447 -240.183161) (xy 376.940513 -240.183161) (xy 376.889218 -240.175036)
			(xy 376.839825 -240.158988) (xy 376.793551 -240.13541) (xy 376.751535 -240.104884) (xy 376.714812 -240.068161)
			(xy 376.684286 -240.026145) (xy 376.660708 -239.979871) (xy 376.64466 -239.930478) (xy 376.636535 -239.879183)
			(xy 376.356625 -239.879183) (xy 376.3485 -239.930478) (xy 376.332452 -239.979871) (xy 376.308874 -240.026145)
			(xy 376.278348 -240.068161) (xy 376.241625 -240.104884) (xy 376.199609 -240.13541) (xy 376.153335 -240.158988)
			(xy 376.103942 -240.175036) (xy 376.052647 -240.183161) (xy 376.000713 -240.183161) (xy 375.949418 -240.175036)
			(xy 375.900025 -240.158988) (xy 375.853751 -240.13541) (xy 375.811735 -240.104884) (xy 375.775012 -240.068161)
			(xy 375.744486 -240.026145) (xy 375.720908 -239.979871) (xy 375.70486 -239.930478) (xy 375.696735 -239.879183)
			(xy 375.416825 -239.879183) (xy 375.4087 -239.930478) (xy 375.392652 -239.979871) (xy 375.369074 -240.026145)
			(xy 375.338548 -240.068161) (xy 375.301825 -240.104884) (xy 375.259809 -240.13541) (xy 375.213535 -240.158988)
			(xy 375.164142 -240.175036) (xy 375.112847 -240.183161) (xy 375.060913 -240.183161) (xy 375.009618 -240.175036)
			(xy 374.960225 -240.158988) (xy 374.913951 -240.13541) (xy 374.871935 -240.104884) (xy 374.835212 -240.068161)
			(xy 374.804686 -240.026145) (xy 374.781108 -239.979871) (xy 374.76506 -239.930478) (xy 374.756935 -239.879183)
			(xy 374.477025 -239.879183) (xy 374.4689 -239.930478) (xy 374.452852 -239.979871) (xy 374.429274 -240.026145)
			(xy 374.398748 -240.068161) (xy 374.362025 -240.104884) (xy 374.320009 -240.13541) (xy 374.273735 -240.158988)
			(xy 374.224342 -240.175036) (xy 374.173047 -240.183161) (xy 374.121113 -240.183161) (xy 374.069818 -240.175036)
			(xy 374.020425 -240.158988) (xy 373.974151 -240.13541) (xy 373.932135 -240.104884) (xy 373.895412 -240.068161)
			(xy 373.864886 -240.026145) (xy 373.841308 -239.979871) (xy 373.82526 -239.930478) (xy 373.817135 -239.879183)
			(xy 373.537479 -239.879183) (xy 373.529354 -239.930478) (xy 373.513306 -239.979871) (xy 373.489728 -240.026145)
			(xy 373.459202 -240.068161) (xy 373.422479 -240.104884) (xy 373.380463 -240.13541) (xy 373.334189 -240.158988)
			(xy 373.284796 -240.175036) (xy 373.233501 -240.183161) (xy 373.181567 -240.183161) (xy 373.130272 -240.175036)
			(xy 373.080879 -240.158988) (xy 373.034605 -240.13541) (xy 372.992589 -240.104884) (xy 372.955866 -240.068161)
			(xy 372.92534 -240.026145) (xy 372.901762 -239.979871) (xy 372.885714 -239.930478) (xy 372.877589 -239.879183)
			(xy 372.597425 -239.879183) (xy 372.5893 -239.930478) (xy 372.573252 -239.979871) (xy 372.549674 -240.026145)
			(xy 372.519148 -240.068161) (xy 372.482425 -240.104884) (xy 372.440409 -240.13541) (xy 372.394135 -240.158988)
			(xy 372.344742 -240.175036) (xy 372.293447 -240.183161) (xy 372.241513 -240.183161) (xy 372.190218 -240.175036)
			(xy 372.140825 -240.158988) (xy 372.094551 -240.13541) (xy 372.052535 -240.104884) (xy 372.015812 -240.068161)
			(xy 371.985286 -240.026145) (xy 371.961708 -239.979871) (xy 371.94566 -239.930478) (xy 371.937535 -239.879183)
			(xy 371.657625 -239.879183) (xy 371.6495 -239.930478) (xy 371.633452 -239.979871) (xy 371.609874 -240.026145)
			(xy 371.579348 -240.068161) (xy 371.542625 -240.104884) (xy 371.500609 -240.13541) (xy 371.454335 -240.158988)
			(xy 371.404942 -240.175036) (xy 371.353647 -240.183161) (xy 371.301713 -240.183161) (xy 371.250418 -240.175036)
			(xy 371.201025 -240.158988) (xy 371.154751 -240.13541) (xy 371.112735 -240.104884) (xy 371.076012 -240.068161)
			(xy 371.045486 -240.026145) (xy 371.021908 -239.979871) (xy 371.00586 -239.930478) (xy 370.997735 -239.879183)
			(xy 370.718079 -239.879183) (xy 370.709954 -239.930478) (xy 370.693906 -239.979871) (xy 370.670328 -240.026145)
			(xy 370.639802 -240.068161) (xy 370.603079 -240.104884) (xy 370.561063 -240.13541) (xy 370.514789 -240.158988)
			(xy 370.465396 -240.175036) (xy 370.414101 -240.183161) (xy 370.362167 -240.183161) (xy 370.310872 -240.175036)
			(xy 370.261479 -240.158988) (xy 370.215205 -240.13541) (xy 370.173189 -240.104884) (xy 370.136466 -240.068161)
			(xy 370.10594 -240.026145) (xy 370.082362 -239.979871) (xy 370.066314 -239.930478) (xy 370.058189 -239.879183)
			(xy 369.778085 -239.879183) (xy 369.769961 -239.930475) (xy 369.753909 -239.979876) (xy 369.730327 -240.026157)
			(xy 369.699794 -240.068179) (xy 369.663064 -240.104907) (xy 369.62104 -240.135437) (xy 369.574757 -240.159017)
			(xy 369.525356 -240.175066) (xy 369.474052 -240.183189) (xy 369.44808 -240.18367) (xy 369.447572 -240.18367)
			(xy 369.418504 -240.183038) (xy 369.361273 -240.172811) (xy 369.33378 -240.16335) (xy 369.320927 -240.159044)
			(xy 369.293933 -240.156675) (xy 369.267269 -240.161503) (xy 369.24282 -240.173185) (xy 369.222312 -240.190897)
			(xy 369.207195 -240.213386) (xy 369.202462 -240.226088) (xy 369.194751 -240.247645) (xy 369.174248 -240.288578)
			(xy 369.14829 -240.32629) (xy 369.13312 -240.343436) (xy 369.123301 -240.354913) (xy 369.11029 -240.382155)
			(xy 369.105825 -240.412012) (xy 369.110297 -240.441868) (xy 369.123315 -240.469107) (xy 369.13312 -240.480596)
			(xy 369.149386 -240.49896) (xy 369.176828 -240.539624) (xy 369.197954 -240.5839) (xy 369.212298 -240.630814)
			(xy 369.219545 -240.679333) (xy 369.219796 -240.693253) (xy 369.588289 -240.693253) (xy 369.588289 -240.641319)
			(xy 369.596414 -240.590024) (xy 369.612462 -240.540631) (xy 369.63604 -240.494357) (xy 369.666566 -240.452341)
			(xy 369.703289 -240.415618) (xy 369.745305 -240.385092) (xy 369.791579 -240.361514) (xy 369.840972 -240.345466)
			(xy 369.892267 -240.337341) (xy 369.944201 -240.337341) (xy 369.995496 -240.345466) (xy 370.044889 -240.361514)
			(xy 370.091163 -240.385092) (xy 370.133179 -240.415618) (xy 370.169902 -240.452341) (xy 370.200428 -240.494357)
			(xy 370.224006 -240.540631) (xy 370.240054 -240.590024) (xy 370.248179 -240.641319) (xy 370.248688 -240.667286)
			(xy 370.248179 -240.693253) (xy 370.527835 -240.693253) (xy 370.527835 -240.641319) (xy 370.53596 -240.590024)
			(xy 370.552008 -240.540631) (xy 370.575586 -240.494357) (xy 370.606112 -240.452341) (xy 370.642835 -240.415618)
			(xy 370.684851 -240.385092) (xy 370.731125 -240.361514) (xy 370.780518 -240.345466) (xy 370.831813 -240.337341)
			(xy 370.883747 -240.337341) (xy 370.935042 -240.345466) (xy 370.984435 -240.361514) (xy 371.030709 -240.385092)
			(xy 371.072725 -240.415618) (xy 371.109448 -240.452341) (xy 371.139974 -240.494357) (xy 371.163552 -240.540631)
			(xy 371.1796 -240.590024) (xy 371.187725 -240.641319) (xy 371.188234 -240.667286) (xy 371.187725 -240.693253)
			(xy 371.467889 -240.693253) (xy 371.467889 -240.641319) (xy 371.476014 -240.590024) (xy 371.492062 -240.540631)
			(xy 371.51564 -240.494357) (xy 371.546166 -240.452341) (xy 371.582889 -240.415618) (xy 371.624905 -240.385092)
			(xy 371.671179 -240.361514) (xy 371.720572 -240.345466) (xy 371.771867 -240.337341) (xy 371.823801 -240.337341)
			(xy 371.875096 -240.345466) (xy 371.924489 -240.361514) (xy 371.970763 -240.385092) (xy 372.012779 -240.415618)
			(xy 372.049502 -240.452341) (xy 372.080028 -240.494357) (xy 372.103606 -240.540631) (xy 372.119654 -240.590024)
			(xy 372.127779 -240.641319) (xy 372.128288 -240.667286) (xy 372.127779 -240.693253) (xy 372.407689 -240.693253)
			(xy 372.407689 -240.641319) (xy 372.415814 -240.590024) (xy 372.431862 -240.540631) (xy 372.45544 -240.494357)
			(xy 372.485966 -240.452341) (xy 372.522689 -240.415618) (xy 372.564705 -240.385092) (xy 372.610979 -240.361514)
			(xy 372.660372 -240.345466) (xy 372.711667 -240.337341) (xy 372.763601 -240.337341) (xy 372.814896 -240.345466)
			(xy 372.864289 -240.361514) (xy 372.910563 -240.385092) (xy 372.952579 -240.415618) (xy 372.989302 -240.452341)
			(xy 373.019828 -240.494357) (xy 373.043406 -240.540631) (xy 373.059454 -240.590024) (xy 373.067579 -240.641319)
			(xy 373.068088 -240.667286) (xy 373.067579 -240.693253) (xy 373.347235 -240.693253) (xy 373.347235 -240.641319)
			(xy 373.35536 -240.590024) (xy 373.371408 -240.540631) (xy 373.394986 -240.494357) (xy 373.425512 -240.452341)
			(xy 373.462235 -240.415618) (xy 373.504251 -240.385092) (xy 373.550525 -240.361514) (xy 373.599918 -240.345466)
			(xy 373.651213 -240.337341) (xy 373.703147 -240.337341) (xy 373.754442 -240.345466) (xy 373.803835 -240.361514)
			(xy 373.850109 -240.385092) (xy 373.892125 -240.415618) (xy 373.928848 -240.452341) (xy 373.959374 -240.494357)
			(xy 373.982952 -240.540631) (xy 373.999 -240.590024) (xy 374.007125 -240.641319) (xy 374.007634 -240.667286)
			(xy 374.007125 -240.693253) (xy 374.287289 -240.693253) (xy 374.287289 -240.641319) (xy 374.295414 -240.590024)
			(xy 374.311462 -240.540631) (xy 374.33504 -240.494357) (xy 374.365566 -240.452341) (xy 374.402289 -240.415618)
			(xy 374.444305 -240.385092) (xy 374.490579 -240.361514) (xy 374.539972 -240.345466) (xy 374.591267 -240.337341)
			(xy 374.643201 -240.337341) (xy 374.694496 -240.345466) (xy 374.743889 -240.361514) (xy 374.790163 -240.385092)
			(xy 374.832179 -240.415618) (xy 374.868902 -240.452341) (xy 374.899428 -240.494357) (xy 374.923006 -240.540631)
			(xy 374.939054 -240.590024) (xy 374.947179 -240.641319) (xy 374.947688 -240.667286) (xy 374.947179 -240.693253)
			(xy 375.227089 -240.693253) (xy 375.227089 -240.641319) (xy 375.235214 -240.590024) (xy 375.251262 -240.540631)
			(xy 375.27484 -240.494357) (xy 375.305366 -240.452341) (xy 375.342089 -240.415618) (xy 375.384105 -240.385092)
			(xy 375.430379 -240.361514) (xy 375.479772 -240.345466) (xy 375.531067 -240.337341) (xy 375.583001 -240.337341)
			(xy 375.634296 -240.345466) (xy 375.683689 -240.361514) (xy 375.729963 -240.385092) (xy 375.771979 -240.415618)
			(xy 375.808702 -240.452341) (xy 375.839228 -240.494357) (xy 375.862806 -240.540631) (xy 375.878854 -240.590024)
			(xy 375.886979 -240.641319) (xy 375.887488 -240.667286) (xy 375.886979 -240.693253) (xy 376.166889 -240.693253)
			(xy 376.166889 -240.641319) (xy 376.175014 -240.590024) (xy 376.191062 -240.540631) (xy 376.21464 -240.494357)
			(xy 376.245166 -240.452341) (xy 376.281889 -240.415618) (xy 376.323905 -240.385092) (xy 376.370179 -240.361514)
			(xy 376.419572 -240.345466) (xy 376.470867 -240.337341) (xy 376.522801 -240.337341) (xy 376.574096 -240.345466)
			(xy 376.623489 -240.361514) (xy 376.669763 -240.385092) (xy 376.711779 -240.415618) (xy 376.748502 -240.452341)
			(xy 376.779028 -240.494357) (xy 376.802606 -240.540631) (xy 376.818654 -240.590024) (xy 376.826779 -240.641319)
			(xy 376.827288 -240.667286) (xy 376.826779 -240.693253) (xy 377.106689 -240.693253) (xy 377.106689 -240.641319)
			(xy 377.114814 -240.590024) (xy 377.130862 -240.540631) (xy 377.15444 -240.494357) (xy 377.184966 -240.452341)
			(xy 377.221689 -240.415618) (xy 377.263705 -240.385092) (xy 377.309979 -240.361514) (xy 377.359372 -240.345466)
			(xy 377.410667 -240.337341) (xy 377.462601 -240.337341) (xy 377.513896 -240.345466) (xy 377.563289 -240.361514)
			(xy 377.609563 -240.385092) (xy 377.651579 -240.415618) (xy 377.688302 -240.452341) (xy 377.718828 -240.494357)
			(xy 377.742406 -240.540631) (xy 377.758454 -240.590024) (xy 377.766579 -240.641319) (xy 377.767088 -240.667286)
			(xy 377.766579 -240.693253) (xy 378.046489 -240.693253) (xy 378.046489 -240.641319) (xy 378.054614 -240.590024)
			(xy 378.070662 -240.540631) (xy 378.09424 -240.494357) (xy 378.124766 -240.452341) (xy 378.161489 -240.415618)
			(xy 378.203505 -240.385092) (xy 378.249779 -240.361514) (xy 378.299172 -240.345466) (xy 378.350467 -240.337341)
			(xy 378.402401 -240.337341) (xy 378.453696 -240.345466) (xy 378.503089 -240.361514) (xy 378.549363 -240.385092)
			(xy 378.591379 -240.415618) (xy 378.628102 -240.452341) (xy 378.658628 -240.494357) (xy 378.682206 -240.540631)
			(xy 378.698254 -240.590024) (xy 378.706379 -240.641319) (xy 378.706888 -240.667286) (xy 378.706379 -240.693253)
			(xy 378.986289 -240.693253) (xy 378.986289 -240.641319) (xy 378.994414 -240.590024) (xy 379.010462 -240.540631)
			(xy 379.03404 -240.494357) (xy 379.064566 -240.452341) (xy 379.101289 -240.415618) (xy 379.143305 -240.385092)
			(xy 379.189579 -240.361514) (xy 379.238972 -240.345466) (xy 379.290267 -240.337341) (xy 379.342201 -240.337341)
			(xy 379.393496 -240.345466) (xy 379.442889 -240.361514) (xy 379.489163 -240.385092) (xy 379.531179 -240.415618)
			(xy 379.567902 -240.452341) (xy 379.598428 -240.494357) (xy 379.622006 -240.540631) (xy 379.638054 -240.590024)
			(xy 379.646179 -240.641319) (xy 379.646688 -240.667286) (xy 379.646179 -240.693253) (xy 379.638054 -240.744548)
			(xy 379.622006 -240.793941) (xy 379.598428 -240.840215) (xy 379.567902 -240.882231) (xy 379.531179 -240.918954)
			(xy 379.489163 -240.94948) (xy 379.442889 -240.973058) (xy 379.393496 -240.989106) (xy 379.342201 -240.997231)
			(xy 379.290267 -240.997231) (xy 379.238972 -240.989106) (xy 379.189579 -240.973058) (xy 379.143305 -240.94948)
			(xy 379.101289 -240.918954) (xy 379.064566 -240.882231) (xy 379.03404 -240.840215) (xy 379.010462 -240.793941)
			(xy 378.994414 -240.744548) (xy 378.986289 -240.693253) (xy 378.706379 -240.693253) (xy 378.698254 -240.744548)
			(xy 378.682206 -240.793941) (xy 378.658628 -240.840215) (xy 378.628102 -240.882231) (xy 378.591379 -240.918954)
			(xy 378.549363 -240.94948) (xy 378.503089 -240.973058) (xy 378.453696 -240.989106) (xy 378.402401 -240.997231)
			(xy 378.350467 -240.997231) (xy 378.299172 -240.989106) (xy 378.249779 -240.973058) (xy 378.203505 -240.94948)
			(xy 378.161489 -240.918954) (xy 378.124766 -240.882231) (xy 378.09424 -240.840215) (xy 378.070662 -240.793941)
			(xy 378.054614 -240.744548) (xy 378.046489 -240.693253) (xy 377.766579 -240.693253) (xy 377.758454 -240.744548)
			(xy 377.742406 -240.793941) (xy 377.718828 -240.840215) (xy 377.688302 -240.882231) (xy 377.651579 -240.918954)
			(xy 377.609563 -240.94948) (xy 377.563289 -240.973058) (xy 377.513896 -240.989106) (xy 377.462601 -240.997231)
			(xy 377.410667 -240.997231) (xy 377.359372 -240.989106) (xy 377.309979 -240.973058) (xy 377.263705 -240.94948)
			(xy 377.221689 -240.918954) (xy 377.184966 -240.882231) (xy 377.15444 -240.840215) (xy 377.130862 -240.793941)
			(xy 377.114814 -240.744548) (xy 377.106689 -240.693253) (xy 376.826779 -240.693253) (xy 376.818654 -240.744548)
			(xy 376.802606 -240.793941) (xy 376.779028 -240.840215) (xy 376.748502 -240.882231) (xy 376.711779 -240.918954)
			(xy 376.669763 -240.94948) (xy 376.623489 -240.973058) (xy 376.574096 -240.989106) (xy 376.522801 -240.997231)
			(xy 376.470867 -240.997231) (xy 376.419572 -240.989106) (xy 376.370179 -240.973058) (xy 376.323905 -240.94948)
			(xy 376.281889 -240.918954) (xy 376.245166 -240.882231) (xy 376.21464 -240.840215) (xy 376.191062 -240.793941)
			(xy 376.175014 -240.744548) (xy 376.166889 -240.693253) (xy 375.886979 -240.693253) (xy 375.878854 -240.744548)
			(xy 375.862806 -240.793941) (xy 375.839228 -240.840215) (xy 375.808702 -240.882231) (xy 375.771979 -240.918954)
			(xy 375.729963 -240.94948) (xy 375.683689 -240.973058) (xy 375.634296 -240.989106) (xy 375.583001 -240.997231)
			(xy 375.531067 -240.997231) (xy 375.479772 -240.989106) (xy 375.430379 -240.973058) (xy 375.384105 -240.94948)
			(xy 375.342089 -240.918954) (xy 375.305366 -240.882231) (xy 375.27484 -240.840215) (xy 375.251262 -240.793941)
			(xy 375.235214 -240.744548) (xy 375.227089 -240.693253) (xy 374.947179 -240.693253) (xy 374.939054 -240.744548)
			(xy 374.923006 -240.793941) (xy 374.899428 -240.840215) (xy 374.868902 -240.882231) (xy 374.832179 -240.918954)
			(xy 374.790163 -240.94948) (xy 374.743889 -240.973058) (xy 374.694496 -240.989106) (xy 374.643201 -240.997231)
			(xy 374.591267 -240.997231) (xy 374.539972 -240.989106) (xy 374.490579 -240.973058) (xy 374.444305 -240.94948)
			(xy 374.402289 -240.918954) (xy 374.365566 -240.882231) (xy 374.33504 -240.840215) (xy 374.311462 -240.793941)
			(xy 374.295414 -240.744548) (xy 374.287289 -240.693253) (xy 374.007125 -240.693253) (xy 373.999 -240.744548)
			(xy 373.982952 -240.793941) (xy 373.959374 -240.840215) (xy 373.928848 -240.882231) (xy 373.892125 -240.918954)
			(xy 373.850109 -240.94948) (xy 373.803835 -240.973058) (xy 373.754442 -240.989106) (xy 373.703147 -240.997231)
			(xy 373.651213 -240.997231) (xy 373.599918 -240.989106) (xy 373.550525 -240.973058) (xy 373.504251 -240.94948)
			(xy 373.462235 -240.918954) (xy 373.425512 -240.882231) (xy 373.394986 -240.840215) (xy 373.371408 -240.793941)
			(xy 373.35536 -240.744548) (xy 373.347235 -240.693253) (xy 373.067579 -240.693253) (xy 373.059454 -240.744548)
			(xy 373.043406 -240.793941) (xy 373.019828 -240.840215) (xy 372.989302 -240.882231) (xy 372.952579 -240.918954)
			(xy 372.910563 -240.94948) (xy 372.864289 -240.973058) (xy 372.814896 -240.989106) (xy 372.763601 -240.997231)
			(xy 372.711667 -240.997231) (xy 372.660372 -240.989106) (xy 372.610979 -240.973058) (xy 372.564705 -240.94948)
			(xy 372.522689 -240.918954) (xy 372.485966 -240.882231) (xy 372.45544 -240.840215) (xy 372.431862 -240.793941)
			(xy 372.415814 -240.744548) (xy 372.407689 -240.693253) (xy 372.127779 -240.693253) (xy 372.119654 -240.744548)
			(xy 372.103606 -240.793941) (xy 372.080028 -240.840215) (xy 372.049502 -240.882231) (xy 372.012779 -240.918954)
			(xy 371.970763 -240.94948) (xy 371.924489 -240.973058) (xy 371.875096 -240.989106) (xy 371.823801 -240.997231)
			(xy 371.771867 -240.997231) (xy 371.720572 -240.989106) (xy 371.671179 -240.973058) (xy 371.624905 -240.94948)
			(xy 371.582889 -240.918954) (xy 371.546166 -240.882231) (xy 371.51564 -240.840215) (xy 371.492062 -240.793941)
			(xy 371.476014 -240.744548) (xy 371.467889 -240.693253) (xy 371.187725 -240.693253) (xy 371.1796 -240.744548)
			(xy 371.163552 -240.793941) (xy 371.139974 -240.840215) (xy 371.109448 -240.882231) (xy 371.072725 -240.918954)
			(xy 371.030709 -240.94948) (xy 370.984435 -240.973058) (xy 370.935042 -240.989106) (xy 370.883747 -240.997231)
			(xy 370.831813 -240.997231) (xy 370.780518 -240.989106) (xy 370.731125 -240.973058) (xy 370.684851 -240.94948)
			(xy 370.642835 -240.918954) (xy 370.606112 -240.882231) (xy 370.575586 -240.840215) (xy 370.552008 -240.793941)
			(xy 370.53596 -240.744548) (xy 370.527835 -240.693253) (xy 370.248179 -240.693253) (xy 370.240054 -240.744548)
			(xy 370.224006 -240.793941) (xy 370.200428 -240.840215) (xy 370.169902 -240.882231) (xy 370.133179 -240.918954)
			(xy 370.091163 -240.94948) (xy 370.044889 -240.973058) (xy 369.995496 -240.989106) (xy 369.944201 -240.997231)
			(xy 369.892267 -240.997231) (xy 369.840972 -240.989106) (xy 369.791579 -240.973058) (xy 369.745305 -240.94948)
			(xy 369.703289 -240.918954) (xy 369.666566 -240.882231) (xy 369.63604 -240.840215) (xy 369.612462 -240.793941)
			(xy 369.596414 -240.744548) (xy 369.588289 -240.693253) (xy 369.219796 -240.693253) (xy 369.219988 -240.703862)
			(xy 369.219988 -240.704116) (xy 369.219479 -240.730083) (xy 369.211354 -240.781378) (xy 369.195306 -240.830771)
			(xy 369.171728 -240.877045) (xy 369.141202 -240.919061) (xy 369.104479 -240.955784) (xy 369.062463 -240.98631)
			(xy 369.016189 -241.009888) (xy 368.966796 -241.025936) (xy 368.915501 -241.034061) (xy 368.863567 -241.034061)
			(xy 368.812272 -241.025936) (xy 368.762879 -241.009888) (xy 368.716605 -240.98631) (xy 368.674589 -240.955784)
			(xy 368.637866 -240.919061) (xy 368.60734 -240.877045) (xy 368.583762 -240.830771) (xy 368.567714 -240.781378)
			(xy 368.559589 -240.730083) (xy 368.55908 -240.704116) (xy 362.728058 -240.704116) (xy 362.721654 -240.744548)
			(xy 362.705606 -240.793941) (xy 362.682028 -240.840215) (xy 362.651502 -240.882231) (xy 362.614779 -240.918954)
			(xy 362.572763 -240.94948) (xy 362.526489 -240.973058) (xy 362.477096 -240.989106) (xy 362.425801 -240.997231)
			(xy 362.373867 -240.997231) (xy 362.322572 -240.989106) (xy 362.273179 -240.973058) (xy 362.226905 -240.94948)
			(xy 362.184889 -240.918954) (xy 362.148166 -240.882231) (xy 362.11764 -240.840215) (xy 362.094062 -240.793941)
			(xy 362.078014 -240.744548) (xy 362.069889 -240.693253) (xy 361.789979 -240.693253) (xy 361.781854 -240.744548)
			(xy 361.765806 -240.793941) (xy 361.742228 -240.840215) (xy 361.711702 -240.882231) (xy 361.674979 -240.918954)
			(xy 361.632963 -240.94948) (xy 361.586689 -240.973058) (xy 361.537296 -240.989106) (xy 361.486001 -240.997231)
			(xy 361.434067 -240.997231) (xy 361.382772 -240.989106) (xy 361.333379 -240.973058) (xy 361.287105 -240.94948)
			(xy 361.245089 -240.918954) (xy 361.208366 -240.882231) (xy 361.17784 -240.840215) (xy 361.154262 -240.793941)
			(xy 361.138214 -240.744548) (xy 361.130089 -240.693253) (xy 360.849925 -240.693253) (xy 360.8418 -240.744548)
			(xy 360.825752 -240.793941) (xy 360.802174 -240.840215) (xy 360.771648 -240.882231) (xy 360.734925 -240.918954)
			(xy 360.692909 -240.94948) (xy 360.646635 -240.973058) (xy 360.597242 -240.989106) (xy 360.545947 -240.997231)
			(xy 360.494013 -240.997231) (xy 360.442718 -240.989106) (xy 360.393325 -240.973058) (xy 360.347051 -240.94948)
			(xy 360.305035 -240.918954) (xy 360.268312 -240.882231) (xy 360.237786 -240.840215) (xy 360.214208 -240.793941)
			(xy 360.19816 -240.744548) (xy 360.190035 -240.693253) (xy 359.910125 -240.693253) (xy 359.902 -240.744548)
			(xy 359.885952 -240.793941) (xy 359.862374 -240.840215) (xy 359.831848 -240.882231) (xy 359.795125 -240.918954)
			(xy 359.753109 -240.94948) (xy 359.706835 -240.973058) (xy 359.657442 -240.989106) (xy 359.606147 -240.997231)
			(xy 359.554213 -240.997231) (xy 359.502918 -240.989106) (xy 359.453525 -240.973058) (xy 359.407251 -240.94948)
			(xy 359.365235 -240.918954) (xy 359.328512 -240.882231) (xy 359.297986 -240.840215) (xy 359.274408 -240.793941)
			(xy 359.25836 -240.744548) (xy 359.250235 -240.693253) (xy 358.970579 -240.693253) (xy 358.962454 -240.744548)
			(xy 358.946406 -240.793941) (xy 358.922828 -240.840215) (xy 358.892302 -240.882231) (xy 358.855579 -240.918954)
			(xy 358.813563 -240.94948) (xy 358.767289 -240.973058) (xy 358.717896 -240.989106) (xy 358.666601 -240.997231)
			(xy 358.614667 -240.997231) (xy 358.563372 -240.989106) (xy 358.513979 -240.973058) (xy 358.467705 -240.94948)
			(xy 358.425689 -240.918954) (xy 358.388966 -240.882231) (xy 358.35844 -240.840215) (xy 358.334862 -240.793941)
			(xy 358.318814 -240.744548) (xy 358.310689 -240.693253) (xy 358.030525 -240.693253) (xy 358.0224 -240.744548)
			(xy 358.006352 -240.793941) (xy 357.982774 -240.840215) (xy 357.952248 -240.882231) (xy 357.915525 -240.918954)
			(xy 357.873509 -240.94948) (xy 357.827235 -240.973058) (xy 357.777842 -240.989106) (xy 357.726547 -240.997231)
			(xy 357.674613 -240.997231) (xy 357.623318 -240.989106) (xy 357.573925 -240.973058) (xy 357.527651 -240.94948)
			(xy 357.485635 -240.918954) (xy 357.448912 -240.882231) (xy 357.418386 -240.840215) (xy 357.394808 -240.793941)
			(xy 357.37876 -240.744548) (xy 357.370635 -240.693253) (xy 356.679128 -240.693253) (xy 356.674463 -240.708494)
			(xy 356.653333 -240.752765) (xy 356.625894 -240.793429) (xy 356.60965 -240.811812) (xy 356.599852 -240.823306)
			(xy 356.586834 -240.850541) (xy 356.582363 -240.880394) (xy 356.586831 -240.910248) (xy 356.599846 -240.937484)
			(xy 356.60965 -240.948972) (xy 356.625893 -240.967356) (xy 356.653341 -241.008013) (xy 356.674472 -241.052284)
			(xy 356.688821 -241.099194) (xy 356.696073 -241.14771) (xy 356.696518 -241.172238) (xy 356.696518 -241.172492)
			(xy 356.696009 -241.198459) (xy 356.687884 -241.249754) (xy 356.671836 -241.299147) (xy 356.648258 -241.345421)
			(xy 356.617732 -241.387437) (xy 356.581009 -241.42416) (xy 356.538993 -241.454686) (xy 356.492719 -241.478264)
			(xy 356.443326 -241.494312) (xy 356.392031 -241.502437) (xy 356.340097 -241.502437) (xy 356.288802 -241.494312)
			(xy 356.239409 -241.478264) (xy 356.193135 -241.454686) (xy 356.151119 -241.42416) (xy 356.114396 -241.387437)
			(xy 356.08387 -241.345421) (xy 356.060292 -241.299147) (xy 356.044244 -241.249754) (xy 356.036119 -241.198459)
			(xy 356.03561 -241.172492) (xy 351.069929 -241.172492) (xy 351.061846 -241.180575) (xy 351.019829 -241.211101)
			(xy 350.973554 -241.234678) (xy 350.924161 -241.250727) (xy 350.872865 -241.258851) (xy 350.846898 -241.25936)
			(xy 350.822138 -241.258972) (xy 350.773172 -241.251597) (xy 350.725854 -241.236996) (xy 350.681245 -241.215498)
			(xy 350.640344 -241.187584) (xy 350.604067 -241.153878) (xy 350.573225 -241.115136) (xy 350.548511 -241.072225)
			(xy 350.530477 -241.026107) (xy 350.524572 -241.002058) (xy 350.521041 -240.988344) (xy 350.507493 -240.963487)
			(xy 350.487639 -240.943307) (xy 350.463006 -240.929356) (xy 350.435489 -240.922707) (xy 350.407203 -240.92387)
			(xy 350.380325 -240.932756) (xy 350.368362 -240.940336) (xy 350.347686 -240.953856) (xy 350.303177 -240.975287)
			(xy 350.255976 -240.989862) (xy 350.207133 -240.997257) (xy 350.182434 -240.99774) (xy 350.156462 -240.997288)
			(xy 350.105156 -240.989167) (xy 350.055753 -240.973119) (xy 350.009469 -240.94954) (xy 349.967443 -240.919011)
			(xy 349.930711 -240.882283) (xy 349.900178 -240.84026) (xy 349.876594 -240.793978) (xy 349.860541 -240.744577)
			(xy 349.852415 -240.693272) (xy 349.572576 -240.693272) (xy 349.564454 -240.744548) (xy 349.548406 -240.793941)
			(xy 349.524828 -240.840215) (xy 349.494302 -240.882231) (xy 349.457579 -240.918954) (xy 349.415563 -240.94948)
			(xy 349.369289 -240.973058) (xy 349.319896 -240.989106) (xy 349.268601 -240.997231) (xy 349.216667 -240.997231)
			(xy 349.165372 -240.989106) (xy 349.115979 -240.973058) (xy 349.069705 -240.94948) (xy 349.027689 -240.918954)
			(xy 348.990966 -240.882231) (xy 348.96044 -240.840215) (xy 348.936862 -240.793941) (xy 348.920814 -240.744548)
			(xy 348.912689 -240.693253) (xy 348.632779 -240.693253) (xy 348.624654 -240.744548) (xy 348.608606 -240.793941)
			(xy 348.585028 -240.840215) (xy 348.554502 -240.882231) (xy 348.517779 -240.918954) (xy 348.475763 -240.94948)
			(xy 348.429489 -240.973058) (xy 348.380096 -240.989106) (xy 348.328801 -240.997231) (xy 348.276867 -240.997231)
			(xy 348.225572 -240.989106) (xy 348.176179 -240.973058) (xy 348.129905 -240.94948) (xy 348.087889 -240.918954)
			(xy 348.051166 -240.882231) (xy 348.02064 -240.840215) (xy 347.997062 -240.793941) (xy 347.981014 -240.744548)
			(xy 347.972889 -240.693253) (xy 347.692979 -240.693253) (xy 347.684854 -240.744548) (xy 347.668806 -240.793941)
			(xy 347.645228 -240.840215) (xy 347.614702 -240.882231) (xy 347.577979 -240.918954) (xy 347.535963 -240.94948)
			(xy 347.489689 -240.973058) (xy 347.440296 -240.989106) (xy 347.389001 -240.997231) (xy 347.337067 -240.997231)
			(xy 347.285772 -240.989106) (xy 347.236379 -240.973058) (xy 347.190105 -240.94948) (xy 347.148089 -240.918954)
			(xy 347.111366 -240.882231) (xy 347.08084 -240.840215) (xy 347.057262 -240.793941) (xy 347.041214 -240.744548)
			(xy 347.033089 -240.693253) (xy 346.753179 -240.693253) (xy 346.745054 -240.744548) (xy 346.729006 -240.793941)
			(xy 346.705428 -240.840215) (xy 346.674902 -240.882231) (xy 346.638179 -240.918954) (xy 346.596163 -240.94948)
			(xy 346.549889 -240.973058) (xy 346.500496 -240.989106) (xy 346.449201 -240.997231) (xy 346.397267 -240.997231)
			(xy 346.345972 -240.989106) (xy 346.296579 -240.973058) (xy 346.250305 -240.94948) (xy 346.208289 -240.918954)
			(xy 346.171566 -240.882231) (xy 346.14104 -240.840215) (xy 346.117462 -240.793941) (xy 346.101414 -240.744548)
			(xy 346.093289 -240.693253) (xy 345.813125 -240.693253) (xy 345.805 -240.744548) (xy 345.788952 -240.793941)
			(xy 345.765374 -240.840215) (xy 345.734848 -240.882231) (xy 345.698125 -240.918954) (xy 345.656109 -240.94948)
			(xy 345.609835 -240.973058) (xy 345.560442 -240.989106) (xy 345.509147 -240.997231) (xy 345.457213 -240.997231)
			(xy 345.405918 -240.989106) (xy 345.356525 -240.973058) (xy 345.310251 -240.94948) (xy 345.268235 -240.918954)
			(xy 345.231512 -240.882231) (xy 345.200986 -240.840215) (xy 345.177408 -240.793941) (xy 345.16136 -240.744548)
			(xy 345.153235 -240.693253) (xy 344.873579 -240.693253) (xy 344.865454 -240.744548) (xy 344.849406 -240.793941)
			(xy 344.825828 -240.840215) (xy 344.795302 -240.882231) (xy 344.758579 -240.918954) (xy 344.716563 -240.94948)
			(xy 344.670289 -240.973058) (xy 344.620896 -240.989106) (xy 344.569601 -240.997231) (xy 344.517667 -240.997231)
			(xy 344.466372 -240.989106) (xy 344.416979 -240.973058) (xy 344.370705 -240.94948) (xy 344.328689 -240.918954)
			(xy 344.291966 -240.882231) (xy 344.26144 -240.840215) (xy 344.237862 -240.793941) (xy 344.221814 -240.744548)
			(xy 344.213689 -240.693253) (xy 343.933779 -240.693253) (xy 343.925654 -240.744548) (xy 343.909606 -240.793941)
			(xy 343.886028 -240.840215) (xy 343.855502 -240.882231) (xy 343.818779 -240.918954) (xy 343.776763 -240.94948)
			(xy 343.730489 -240.973058) (xy 343.681096 -240.989106) (xy 343.629801 -240.997231) (xy 343.577867 -240.997231)
			(xy 343.526572 -240.989106) (xy 343.477179 -240.973058) (xy 343.430905 -240.94948) (xy 343.388889 -240.918954)
			(xy 343.352166 -240.882231) (xy 343.32164 -240.840215) (xy 343.298062 -240.793941) (xy 343.282014 -240.744548)
			(xy 343.273889 -240.693253) (xy 342.993979 -240.693253) (xy 342.985854 -240.744548) (xy 342.969806 -240.793941)
			(xy 342.946228 -240.840215) (xy 342.915702 -240.882231) (xy 342.878979 -240.918954) (xy 342.836963 -240.94948)
			(xy 342.790689 -240.973058) (xy 342.741296 -240.989106) (xy 342.690001 -240.997231) (xy 342.638067 -240.997231)
			(xy 342.586772 -240.989106) (xy 342.537379 -240.973058) (xy 342.491105 -240.94948) (xy 342.449089 -240.918954)
			(xy 342.412366 -240.882231) (xy 342.38184 -240.840215) (xy 342.358262 -240.793941) (xy 342.342214 -240.744548)
			(xy 342.334089 -240.693253) (xy 342.054179 -240.693253) (xy 342.046054 -240.744548) (xy 342.030006 -240.793941)
			(xy 342.006428 -240.840215) (xy 341.975902 -240.882231) (xy 341.939179 -240.918954) (xy 341.897163 -240.94948)
			(xy 341.850889 -240.973058) (xy 341.801496 -240.989106) (xy 341.750201 -240.997231) (xy 341.698267 -240.997231)
			(xy 341.646972 -240.989106) (xy 341.597579 -240.973058) (xy 341.551305 -240.94948) (xy 341.509289 -240.918954)
			(xy 341.472566 -240.882231) (xy 341.44204 -240.840215) (xy 341.418462 -240.793941) (xy 341.402414 -240.744548)
			(xy 341.394289 -240.693253) (xy 341.114379 -240.693253) (xy 341.106254 -240.744548) (xy 341.090206 -240.793941)
			(xy 341.066628 -240.840215) (xy 341.036102 -240.882231) (xy 340.999379 -240.918954) (xy 340.957363 -240.94948)
			(xy 340.911089 -240.973058) (xy 340.861696 -240.989106) (xy 340.810401 -240.997231) (xy 340.758467 -240.997231)
			(xy 340.707172 -240.989106) (xy 340.657779 -240.973058) (xy 340.611505 -240.94948) (xy 340.569489 -240.918954)
			(xy 340.532766 -240.882231) (xy 340.50224 -240.840215) (xy 340.478662 -240.793941) (xy 340.462614 -240.744548)
			(xy 340.454489 -240.693253) (xy 340.174813 -240.693253) (xy 340.174813 -240.693287) (xy 340.166683 -240.74462)
			(xy 340.150623 -240.79405) (xy 340.127029 -240.840359) (xy 340.096482 -240.882407) (xy 340.059733 -240.91916)
			(xy 340.017688 -240.949711) (xy 339.971381 -240.97331) (xy 339.921953 -240.989375) (xy 339.870621 -240.99751)
			(xy 339.844634 -240.997994) (xy 339.817668 -240.997457) (xy 339.764453 -240.988697) (xy 339.713363 -240.971422)
			(xy 339.665753 -240.946087) (xy 339.643974 -240.930176) (xy 339.637878 -240.925604) (xy 339.619844 -240.919254)
			(xy 339.61112 -240.916573) (xy 339.59289 -240.916976) (xy 339.584284 -240.920016) (xy 339.500972 -240.959894)
			(xy 339.49333 -240.964494) (xy 339.481667 -240.97797) (xy 339.475441 -240.994671) (xy 339.475064 -241.003582)
			(xy 339.475064 -241.131344) (xy 339.505036 -241.17681) (xy 339.517736 -241.182906) (xy 339.54144 -241.194877)
			(xy 339.585018 -241.22522) (xy 339.623189 -241.262134) (xy 339.654974 -241.304672) (xy 339.679555 -241.35174)
			(xy 339.696302 -241.402131) (xy 339.704784 -241.45455) (xy 339.704784 -241.507069) (xy 339.984335 -241.507069)
			(xy 339.984335 -241.455135) (xy 339.99246 -241.40384) (xy 340.008508 -241.354447) (xy 340.032086 -241.308173)
			(xy 340.062612 -241.266157) (xy 340.099335 -241.229434) (xy 340.141351 -241.198908) (xy 340.187625 -241.17533)
			(xy 340.237018 -241.159282) (xy 340.288313 -241.151157) (xy 340.340247 -241.151157) (xy 340.391542 -241.159282)
			(xy 340.440935 -241.17533) (xy 340.487209 -241.198908) (xy 340.529225 -241.229434) (xy 340.565948 -241.266157)
			(xy 340.596474 -241.308173) (xy 340.620052 -241.354447) (xy 340.6361 -241.40384) (xy 340.644225 -241.455135)
			(xy 340.644734 -241.481102) (xy 340.644225 -241.507069) (xy 340.924135 -241.507069) (xy 340.924135 -241.455135)
			(xy 340.93226 -241.40384) (xy 340.948308 -241.354447) (xy 340.971886 -241.308173) (xy 341.002412 -241.266157)
			(xy 341.039135 -241.229434) (xy 341.081151 -241.198908) (xy 341.127425 -241.17533) (xy 341.176818 -241.159282)
			(xy 341.228113 -241.151157) (xy 341.280047 -241.151157) (xy 341.331342 -241.159282) (xy 341.380735 -241.17533)
			(xy 341.427009 -241.198908) (xy 341.469025 -241.229434) (xy 341.505748 -241.266157) (xy 341.536274 -241.308173)
			(xy 341.559852 -241.354447) (xy 341.5759 -241.40384) (xy 341.584025 -241.455135) (xy 341.584534 -241.481102)
			(xy 341.584025 -241.507069) (xy 341.864189 -241.507069) (xy 341.864189 -241.455135) (xy 341.872314 -241.40384)
			(xy 341.888362 -241.354447) (xy 341.91194 -241.308173) (xy 341.942466 -241.266157) (xy 341.979189 -241.229434)
			(xy 342.021205 -241.198908) (xy 342.067479 -241.17533) (xy 342.116872 -241.159282) (xy 342.168167 -241.151157)
			(xy 342.220101 -241.151157) (xy 342.271396 -241.159282) (xy 342.320789 -241.17533) (xy 342.367063 -241.198908)
			(xy 342.409079 -241.229434) (xy 342.445802 -241.266157) (xy 342.476328 -241.308173) (xy 342.499906 -241.354447)
			(xy 342.515954 -241.40384) (xy 342.524079 -241.455135) (xy 342.524588 -241.481102) (xy 342.524079 -241.507069)
			(xy 342.803735 -241.507069) (xy 342.803735 -241.455135) (xy 342.81186 -241.40384) (xy 342.827908 -241.354447)
			(xy 342.851486 -241.308173) (xy 342.882012 -241.266157) (xy 342.918735 -241.229434) (xy 342.960751 -241.198908)
			(xy 343.007025 -241.17533) (xy 343.056418 -241.159282) (xy 343.107713 -241.151157) (xy 343.159647 -241.151157)
			(xy 343.210942 -241.159282) (xy 343.260335 -241.17533) (xy 343.306609 -241.198908) (xy 343.348625 -241.229434)
			(xy 343.385348 -241.266157) (xy 343.415874 -241.308173) (xy 343.439452 -241.354447) (xy 343.4555 -241.40384)
			(xy 343.463625 -241.455135) (xy 343.464134 -241.481102) (xy 343.463625 -241.507069) (xy 343.743535 -241.507069)
			(xy 343.743535 -241.455135) (xy 343.75166 -241.40384) (xy 343.767708 -241.354447) (xy 343.791286 -241.308173)
			(xy 343.821812 -241.266157) (xy 343.858535 -241.229434) (xy 343.900551 -241.198908) (xy 343.946825 -241.17533)
			(xy 343.996218 -241.159282) (xy 344.047513 -241.151157) (xy 344.099447 -241.151157) (xy 344.150742 -241.159282)
			(xy 344.200135 -241.17533) (xy 344.246409 -241.198908) (xy 344.288425 -241.229434) (xy 344.325148 -241.266157)
			(xy 344.355674 -241.308173) (xy 344.379252 -241.354447) (xy 344.3953 -241.40384) (xy 344.403425 -241.455135)
			(xy 344.403934 -241.481102) (xy 344.403425 -241.507069) (xy 344.683335 -241.507069) (xy 344.683335 -241.455135)
			(xy 344.69146 -241.40384) (xy 344.707508 -241.354447) (xy 344.731086 -241.308173) (xy 344.761612 -241.266157)
			(xy 344.798335 -241.229434) (xy 344.840351 -241.198908) (xy 344.886625 -241.17533) (xy 344.936018 -241.159282)
			(xy 344.987313 -241.151157) (xy 345.039247 -241.151157) (xy 345.090542 -241.159282) (xy 345.139935 -241.17533)
			(xy 345.186209 -241.198908) (xy 345.228225 -241.229434) (xy 345.264948 -241.266157) (xy 345.295474 -241.308173)
			(xy 345.319052 -241.354447) (xy 345.3351 -241.40384) (xy 345.343225 -241.455135) (xy 345.343734 -241.481102)
			(xy 345.343225 -241.507069) (xy 345.623135 -241.507069) (xy 345.623135 -241.455135) (xy 345.63126 -241.40384)
			(xy 345.647308 -241.354447) (xy 345.670886 -241.308173) (xy 345.701412 -241.266157) (xy 345.738135 -241.229434)
			(xy 345.780151 -241.198908) (xy 345.826425 -241.17533) (xy 345.875818 -241.159282) (xy 345.927113 -241.151157)
			(xy 345.979047 -241.151157) (xy 346.030342 -241.159282) (xy 346.079735 -241.17533) (xy 346.126009 -241.198908)
			(xy 346.168025 -241.229434) (xy 346.204748 -241.266157) (xy 346.235274 -241.308173) (xy 346.258852 -241.354447)
			(xy 346.2749 -241.40384) (xy 346.283025 -241.455135) (xy 346.283534 -241.481102) (xy 346.283025 -241.507069)
			(xy 346.562935 -241.507069) (xy 346.562935 -241.455135) (xy 346.57106 -241.40384) (xy 346.587108 -241.354447)
			(xy 346.610686 -241.308173) (xy 346.641212 -241.266157) (xy 346.677935 -241.229434) (xy 346.719951 -241.198908)
			(xy 346.766225 -241.17533) (xy 346.815618 -241.159282) (xy 346.866913 -241.151157) (xy 346.918847 -241.151157)
			(xy 346.970142 -241.159282) (xy 347.019535 -241.17533) (xy 347.065809 -241.198908) (xy 347.107825 -241.229434)
			(xy 347.144548 -241.266157) (xy 347.175074 -241.308173) (xy 347.198652 -241.354447) (xy 347.2147 -241.40384)
			(xy 347.222825 -241.455135) (xy 347.223334 -241.481102) (xy 347.222825 -241.507069) (xy 347.502735 -241.507069)
			(xy 347.502735 -241.455135) (xy 347.51086 -241.40384) (xy 347.526908 -241.354447) (xy 347.550486 -241.308173)
			(xy 347.581012 -241.266157) (xy 347.617735 -241.229434) (xy 347.659751 -241.198908) (xy 347.706025 -241.17533)
			(xy 347.755418 -241.159282) (xy 347.806713 -241.151157) (xy 347.858647 -241.151157) (xy 347.909942 -241.159282)
			(xy 347.959335 -241.17533) (xy 348.005609 -241.198908) (xy 348.047625 -241.229434) (xy 348.084348 -241.266157)
			(xy 348.114874 -241.308173) (xy 348.138452 -241.354447) (xy 348.1545 -241.40384) (xy 348.162625 -241.455135)
			(xy 348.163134 -241.481102) (xy 348.162625 -241.507069) (xy 348.442789 -241.507069) (xy 348.442789 -241.455135)
			(xy 348.450914 -241.40384) (xy 348.466962 -241.354447) (xy 348.49054 -241.308173) (xy 348.521066 -241.266157)
			(xy 348.557789 -241.229434) (xy 348.599805 -241.198908) (xy 348.646079 -241.17533) (xy 348.695472 -241.159282)
			(xy 348.746767 -241.151157) (xy 348.798701 -241.151157) (xy 348.849996 -241.159282) (xy 348.899389 -241.17533)
			(xy 348.945663 -241.198908) (xy 348.987679 -241.229434) (xy 349.024402 -241.266157) (xy 349.054928 -241.308173)
			(xy 349.078506 -241.354447) (xy 349.094554 -241.40384) (xy 349.102679 -241.455135) (xy 349.103188 -241.481102)
			(xy 349.102679 -241.507069) (xy 349.382843 -241.507069) (xy 349.382843 -241.455135) (xy 349.390968 -241.40384)
			(xy 349.407016 -241.354447) (xy 349.430594 -241.308173) (xy 349.46112 -241.266157) (xy 349.497843 -241.229434)
			(xy 349.539859 -241.198908) (xy 349.586133 -241.17533) (xy 349.635526 -241.159282) (xy 349.686821 -241.151157)
			(xy 349.738755 -241.151157) (xy 349.79005 -241.159282) (xy 349.839443 -241.17533) (xy 349.885717 -241.198908)
			(xy 349.927733 -241.229434) (xy 349.964456 -241.266157) (xy 349.994982 -241.308173) (xy 350.01856 -241.354447)
			(xy 350.034608 -241.40384) (xy 350.042733 -241.455135) (xy 350.043242 -241.481102) (xy 350.042733 -241.507069)
			(xy 356.900989 -241.507069) (xy 356.900989 -241.455135) (xy 356.909114 -241.40384) (xy 356.925162 -241.354447)
			(xy 356.94874 -241.308173) (xy 356.979266 -241.266157) (xy 357.015989 -241.229434) (xy 357.058005 -241.198908)
			(xy 357.104279 -241.17533) (xy 357.153672 -241.159282) (xy 357.204967 -241.151157) (xy 357.256901 -241.151157)
			(xy 357.308196 -241.159282) (xy 357.357589 -241.17533) (xy 357.403863 -241.198908) (xy 357.445879 -241.229434)
			(xy 357.482602 -241.266157) (xy 357.513128 -241.308173) (xy 357.536706 -241.354447) (xy 357.552754 -241.40384)
			(xy 357.560879 -241.455135) (xy 357.561388 -241.481102) (xy 357.560879 -241.507069) (xy 357.840789 -241.507069)
			(xy 357.840789 -241.455135) (xy 357.848914 -241.40384) (xy 357.864962 -241.354447) (xy 357.88854 -241.308173)
			(xy 357.919066 -241.266157) (xy 357.955789 -241.229434) (xy 357.997805 -241.198908) (xy 358.044079 -241.17533)
			(xy 358.093472 -241.159282) (xy 358.144767 -241.151157) (xy 358.196701 -241.151157) (xy 358.247996 -241.159282)
			(xy 358.297389 -241.17533) (xy 358.343663 -241.198908) (xy 358.385679 -241.229434) (xy 358.422402 -241.266157)
			(xy 358.452928 -241.308173) (xy 358.476506 -241.354447) (xy 358.492554 -241.40384) (xy 358.500679 -241.455135)
			(xy 358.501188 -241.481102) (xy 358.500679 -241.507069) (xy 358.780589 -241.507069) (xy 358.780589 -241.455135)
			(xy 358.788714 -241.40384) (xy 358.804762 -241.354447) (xy 358.82834 -241.308173) (xy 358.858866 -241.266157)
			(xy 358.895589 -241.229434) (xy 358.937605 -241.198908) (xy 358.983879 -241.17533) (xy 359.033272 -241.159282)
			(xy 359.084567 -241.151157) (xy 359.136501 -241.151157) (xy 359.187796 -241.159282) (xy 359.237189 -241.17533)
			(xy 359.283463 -241.198908) (xy 359.325479 -241.229434) (xy 359.362202 -241.266157) (xy 359.392728 -241.308173)
			(xy 359.416306 -241.354447) (xy 359.432354 -241.40384) (xy 359.440479 -241.455135) (xy 359.440988 -241.481102)
			(xy 359.440479 -241.507069) (xy 359.720389 -241.507069) (xy 359.720389 -241.455135) (xy 359.728514 -241.40384)
			(xy 359.744562 -241.354447) (xy 359.76814 -241.308173) (xy 359.798666 -241.266157) (xy 359.835389 -241.229434)
			(xy 359.877405 -241.198908) (xy 359.923679 -241.17533) (xy 359.973072 -241.159282) (xy 360.024367 -241.151157)
			(xy 360.076301 -241.151157) (xy 360.127596 -241.159282) (xy 360.176989 -241.17533) (xy 360.223263 -241.198908)
			(xy 360.265279 -241.229434) (xy 360.302002 -241.266157) (xy 360.332528 -241.308173) (xy 360.356106 -241.354447)
			(xy 360.372154 -241.40384) (xy 360.380279 -241.455135) (xy 360.380788 -241.481102) (xy 360.380279 -241.507069)
			(xy 360.659935 -241.507069) (xy 360.659935 -241.455135) (xy 360.66806 -241.40384) (xy 360.684108 -241.354447)
			(xy 360.707686 -241.308173) (xy 360.738212 -241.266157) (xy 360.774935 -241.229434) (xy 360.816951 -241.198908)
			(xy 360.863225 -241.17533) (xy 360.912618 -241.159282) (xy 360.963913 -241.151157) (xy 361.015847 -241.151157)
			(xy 361.067142 -241.159282) (xy 361.116535 -241.17533) (xy 361.162809 -241.198908) (xy 361.204825 -241.229434)
			(xy 361.241548 -241.266157) (xy 361.272074 -241.308173) (xy 361.295652 -241.354447) (xy 361.3117 -241.40384)
			(xy 361.319825 -241.455135) (xy 361.320334 -241.481102) (xy 361.319825 -241.507069) (xy 361.599989 -241.507069)
			(xy 361.599989 -241.455135) (xy 361.608114 -241.40384) (xy 361.624162 -241.354447) (xy 361.64774 -241.308173)
			(xy 361.678266 -241.266157) (xy 361.714989 -241.229434) (xy 361.757005 -241.198908) (xy 361.803279 -241.17533)
			(xy 361.852672 -241.159282) (xy 361.903967 -241.151157) (xy 361.955901 -241.151157) (xy 362.007196 -241.159282)
			(xy 362.056589 -241.17533) (xy 362.102863 -241.198908) (xy 362.144879 -241.229434) (xy 362.181602 -241.266157)
			(xy 362.212128 -241.308173) (xy 362.235706 -241.354447) (xy 362.251754 -241.40384) (xy 362.259879 -241.455135)
			(xy 362.260388 -241.481102) (xy 362.259879 -241.507069) (xy 362.251754 -241.558364) (xy 362.235706 -241.607757)
			(xy 362.212128 -241.654031) (xy 362.203976 -241.665252) (xy 363.032802 -241.665252) (xy 363.032802 -241.664998)
			(xy 363.033252 -241.640471) (xy 363.040515 -241.591958) (xy 363.054867 -241.545051) (xy 363.075993 -241.50078)
			(xy 363.103428 -241.460115) (xy 363.11967 -241.441732) (xy 363.129521 -241.43028) (xy 363.14253 -241.40303)
			(xy 363.14699 -241.373164) (xy 363.142509 -241.343302) (xy 363.129481 -241.316061) (xy 363.11967 -241.304572)
			(xy 363.103434 -241.286182) (xy 363.075988 -241.245525) (xy 363.054857 -241.201255) (xy 363.040506 -241.154347)
			(xy 363.03325 -241.105833) (xy 363.032802 -241.081306) (xy 363.032802 -241.081052) (xy 363.033311 -241.055085)
			(xy 363.041436 -241.00379) (xy 363.057484 -240.954397) (xy 363.081062 -240.908123) (xy 363.111588 -240.866107)
			(xy 363.148311 -240.829384) (xy 363.190327 -240.798858) (xy 363.236601 -240.77528) (xy 363.285994 -240.759232)
			(xy 363.337289 -240.751107) (xy 363.389223 -240.751107) (xy 363.440518 -240.759232) (xy 363.489911 -240.77528)
			(xy 363.536185 -240.798858) (xy 363.578201 -240.829384) (xy 363.614924 -240.866107) (xy 363.64545 -240.908123)
			(xy 363.669028 -240.954397) (xy 363.685076 -241.00379) (xy 363.693201 -241.055085) (xy 363.69371 -241.081052)
			(xy 363.69371 -241.081306) (xy 363.693259 -241.105833) (xy 363.685996 -241.154345) (xy 363.671644 -241.201252)
			(xy 363.650519 -241.245524) (xy 363.623084 -241.286188) (xy 363.606842 -241.304572) (xy 363.597084 -241.316097)
			(xy 363.584063 -241.343321) (xy 363.579584 -241.373164) (xy 363.584042 -241.403011) (xy 363.597044 -241.430244)
			(xy 363.606842 -241.441732) (xy 363.623065 -241.460133) (xy 363.650516 -241.500786) (xy 363.653516 -241.507069)
			(xy 369.118135 -241.507069) (xy 369.118135 -241.455135) (xy 369.12626 -241.40384) (xy 369.142308 -241.354447)
			(xy 369.165886 -241.308173) (xy 369.196412 -241.266157) (xy 369.233135 -241.229434) (xy 369.275151 -241.198908)
			(xy 369.321425 -241.17533) (xy 369.370818 -241.159282) (xy 369.422113 -241.151157) (xy 369.474047 -241.151157)
			(xy 369.525342 -241.159282) (xy 369.574735 -241.17533) (xy 369.621009 -241.198908) (xy 369.663025 -241.229434)
			(xy 369.699748 -241.266157) (xy 369.730274 -241.308173) (xy 369.753852 -241.354447) (xy 369.7699 -241.40384)
			(xy 369.778025 -241.455135) (xy 369.778534 -241.481102) (xy 369.778025 -241.507069) (xy 370.058189 -241.507069)
			(xy 370.058189 -241.455135) (xy 370.066314 -241.40384) (xy 370.082362 -241.354447) (xy 370.10594 -241.308173)
			(xy 370.136466 -241.266157) (xy 370.173189 -241.229434) (xy 370.215205 -241.198908) (xy 370.261479 -241.17533)
			(xy 370.310872 -241.159282) (xy 370.362167 -241.151157) (xy 370.414101 -241.151157) (xy 370.465396 -241.159282)
			(xy 370.514789 -241.17533) (xy 370.561063 -241.198908) (xy 370.603079 -241.229434) (xy 370.639802 -241.266157)
			(xy 370.670328 -241.308173) (xy 370.693906 -241.354447) (xy 370.709954 -241.40384) (xy 370.718079 -241.455135)
			(xy 370.718588 -241.481102) (xy 370.718079 -241.507069) (xy 370.997735 -241.507069) (xy 370.997735 -241.455135)
			(xy 371.00586 -241.40384) (xy 371.021908 -241.354447) (xy 371.045486 -241.308173) (xy 371.076012 -241.266157)
			(xy 371.112735 -241.229434) (xy 371.154751 -241.198908) (xy 371.201025 -241.17533) (xy 371.250418 -241.159282)
			(xy 371.301713 -241.151157) (xy 371.353647 -241.151157) (xy 371.404942 -241.159282) (xy 371.454335 -241.17533)
			(xy 371.500609 -241.198908) (xy 371.542625 -241.229434) (xy 371.579348 -241.266157) (xy 371.609874 -241.308173)
			(xy 371.633452 -241.354447) (xy 371.6495 -241.40384) (xy 371.657625 -241.455135) (xy 371.658134 -241.481102)
			(xy 371.657625 -241.507069) (xy 371.937535 -241.507069) (xy 371.937535 -241.455135) (xy 371.94566 -241.40384)
			(xy 371.961708 -241.354447) (xy 371.985286 -241.308173) (xy 372.015812 -241.266157) (xy 372.052535 -241.229434)
			(xy 372.094551 -241.198908) (xy 372.140825 -241.17533) (xy 372.190218 -241.159282) (xy 372.241513 -241.151157)
			(xy 372.293447 -241.151157) (xy 372.344742 -241.159282) (xy 372.394135 -241.17533) (xy 372.440409 -241.198908)
			(xy 372.482425 -241.229434) (xy 372.519148 -241.266157) (xy 372.549674 -241.308173) (xy 372.573252 -241.354447)
			(xy 372.5893 -241.40384) (xy 372.597425 -241.455135) (xy 372.597934 -241.481102) (xy 372.597425 -241.507069)
			(xy 372.877335 -241.507069) (xy 372.877335 -241.455135) (xy 372.88546 -241.40384) (xy 372.901508 -241.354447)
			(xy 372.925086 -241.308173) (xy 372.955612 -241.266157) (xy 372.992335 -241.229434) (xy 373.034351 -241.198908)
			(xy 373.080625 -241.17533) (xy 373.130018 -241.159282) (xy 373.181313 -241.151157) (xy 373.233247 -241.151157)
			(xy 373.284542 -241.159282) (xy 373.333935 -241.17533) (xy 373.380209 -241.198908) (xy 373.422225 -241.229434)
			(xy 373.458948 -241.266157) (xy 373.489474 -241.308173) (xy 373.513052 -241.354447) (xy 373.5291 -241.40384)
			(xy 373.537225 -241.455135) (xy 373.537734 -241.481102) (xy 373.537225 -241.507069) (xy 373.817135 -241.507069)
			(xy 373.817135 -241.455135) (xy 373.82526 -241.40384) (xy 373.841308 -241.354447) (xy 373.864886 -241.308173)
			(xy 373.895412 -241.266157) (xy 373.932135 -241.229434) (xy 373.974151 -241.198908) (xy 374.020425 -241.17533)
			(xy 374.069818 -241.159282) (xy 374.121113 -241.151157) (xy 374.173047 -241.151157) (xy 374.224342 -241.159282)
			(xy 374.273735 -241.17533) (xy 374.320009 -241.198908) (xy 374.362025 -241.229434) (xy 374.398748 -241.266157)
			(xy 374.429274 -241.308173) (xy 374.452852 -241.354447) (xy 374.4689 -241.40384) (xy 374.477025 -241.455135)
			(xy 374.477534 -241.481102) (xy 374.477025 -241.507069) (xy 374.756935 -241.507069) (xy 374.756935 -241.455135)
			(xy 374.76506 -241.40384) (xy 374.781108 -241.354447) (xy 374.804686 -241.308173) (xy 374.835212 -241.266157)
			(xy 374.871935 -241.229434) (xy 374.913951 -241.198908) (xy 374.960225 -241.17533) (xy 375.009618 -241.159282)
			(xy 375.060913 -241.151157) (xy 375.112847 -241.151157) (xy 375.164142 -241.159282) (xy 375.213535 -241.17533)
			(xy 375.259809 -241.198908) (xy 375.301825 -241.229434) (xy 375.338548 -241.266157) (xy 375.369074 -241.308173)
			(xy 375.392652 -241.354447) (xy 375.4087 -241.40384) (xy 375.416825 -241.455135) (xy 375.417334 -241.481102)
			(xy 375.416825 -241.507069) (xy 375.696735 -241.507069) (xy 375.696735 -241.455135) (xy 375.70486 -241.40384)
			(xy 375.720908 -241.354447) (xy 375.744486 -241.308173) (xy 375.775012 -241.266157) (xy 375.811735 -241.229434)
			(xy 375.853751 -241.198908) (xy 375.900025 -241.17533) (xy 375.949418 -241.159282) (xy 376.000713 -241.151157)
			(xy 376.052647 -241.151157) (xy 376.103942 -241.159282) (xy 376.153335 -241.17533) (xy 376.199609 -241.198908)
			(xy 376.241625 -241.229434) (xy 376.278348 -241.266157) (xy 376.308874 -241.308173) (xy 376.332452 -241.354447)
			(xy 376.3485 -241.40384) (xy 376.356625 -241.455135) (xy 376.357134 -241.481102) (xy 376.356625 -241.507069)
			(xy 376.636789 -241.507069) (xy 376.636789 -241.455135) (xy 376.644914 -241.40384) (xy 376.660962 -241.354447)
			(xy 376.68454 -241.308173) (xy 376.715066 -241.266157) (xy 376.751789 -241.229434) (xy 376.793805 -241.198908)
			(xy 376.840079 -241.17533) (xy 376.889472 -241.159282) (xy 376.940767 -241.151157) (xy 376.992701 -241.151157)
			(xy 377.043996 -241.159282) (xy 377.093389 -241.17533) (xy 377.139663 -241.198908) (xy 377.181679 -241.229434)
			(xy 377.218402 -241.266157) (xy 377.248928 -241.308173) (xy 377.272506 -241.354447) (xy 377.288554 -241.40384)
			(xy 377.296679 -241.455135) (xy 377.297188 -241.481102) (xy 377.296679 -241.507069) (xy 377.576335 -241.507069)
			(xy 377.576335 -241.455135) (xy 377.58446 -241.40384) (xy 377.600508 -241.354447) (xy 377.624086 -241.308173)
			(xy 377.654612 -241.266157) (xy 377.691335 -241.229434) (xy 377.733351 -241.198908) (xy 377.779625 -241.17533)
			(xy 377.829018 -241.159282) (xy 377.880313 -241.151157) (xy 377.932247 -241.151157) (xy 377.983542 -241.159282)
			(xy 378.032935 -241.17533) (xy 378.079209 -241.198908) (xy 378.121225 -241.229434) (xy 378.157948 -241.266157)
			(xy 378.188474 -241.308173) (xy 378.212052 -241.354447) (xy 378.2281 -241.40384) (xy 378.236225 -241.455135)
			(xy 378.236734 -241.481102) (xy 378.236225 -241.507069) (xy 378.516135 -241.507069) (xy 378.516135 -241.455135)
			(xy 378.52426 -241.40384) (xy 378.540308 -241.354447) (xy 378.563886 -241.308173) (xy 378.594412 -241.266157)
			(xy 378.631135 -241.229434) (xy 378.673151 -241.198908) (xy 378.719425 -241.17533) (xy 378.768818 -241.159282)
			(xy 378.820113 -241.151157) (xy 378.872047 -241.151157) (xy 378.923342 -241.159282) (xy 378.972735 -241.17533)
			(xy 379.019009 -241.198908) (xy 379.061025 -241.229434) (xy 379.097748 -241.266157) (xy 379.128274 -241.308173)
			(xy 379.151852 -241.354447) (xy 379.1679 -241.40384) (xy 379.176025 -241.455135) (xy 379.176534 -241.481102)
			(xy 379.176025 -241.507069) (xy 379.1679 -241.558364) (xy 379.151852 -241.607757) (xy 379.128274 -241.654031)
			(xy 379.097748 -241.696047) (xy 379.061025 -241.73277) (xy 379.019009 -241.763296) (xy 378.972735 -241.786874)
			(xy 378.923342 -241.802922) (xy 378.872047 -241.811047) (xy 378.820113 -241.811047) (xy 378.768818 -241.802922)
			(xy 378.719425 -241.786874) (xy 378.673151 -241.763296) (xy 378.631135 -241.73277) (xy 378.594412 -241.696047)
			(xy 378.563886 -241.654031) (xy 378.540308 -241.607757) (xy 378.52426 -241.558364) (xy 378.516135 -241.507069)
			(xy 378.236225 -241.507069) (xy 378.2281 -241.558364) (xy 378.212052 -241.607757) (xy 378.188474 -241.654031)
			(xy 378.157948 -241.696047) (xy 378.121225 -241.73277) (xy 378.079209 -241.763296) (xy 378.032935 -241.786874)
			(xy 377.983542 -241.802922) (xy 377.932247 -241.811047) (xy 377.880313 -241.811047) (xy 377.829018 -241.802922)
			(xy 377.779625 -241.786874) (xy 377.733351 -241.763296) (xy 377.691335 -241.73277) (xy 377.654612 -241.696047)
			(xy 377.624086 -241.654031) (xy 377.600508 -241.607757) (xy 377.58446 -241.558364) (xy 377.576335 -241.507069)
			(xy 377.296679 -241.507069) (xy 377.288554 -241.558364) (xy 377.272506 -241.607757) (xy 377.248928 -241.654031)
			(xy 377.218402 -241.696047) (xy 377.181679 -241.73277) (xy 377.139663 -241.763296) (xy 377.093389 -241.786874)
			(xy 377.043996 -241.802922) (xy 376.992701 -241.811047) (xy 376.940767 -241.811047) (xy 376.889472 -241.802922)
			(xy 376.840079 -241.786874) (xy 376.793805 -241.763296) (xy 376.751789 -241.73277) (xy 376.715066 -241.696047)
			(xy 376.68454 -241.654031) (xy 376.660962 -241.607757) (xy 376.644914 -241.558364) (xy 376.636789 -241.507069)
			(xy 376.356625 -241.507069) (xy 376.3485 -241.558364) (xy 376.332452 -241.607757) (xy 376.308874 -241.654031)
			(xy 376.278348 -241.696047) (xy 376.241625 -241.73277) (xy 376.199609 -241.763296) (xy 376.153335 -241.786874)
			(xy 376.103942 -241.802922) (xy 376.052647 -241.811047) (xy 376.000713 -241.811047) (xy 375.949418 -241.802922)
			(xy 375.900025 -241.786874) (xy 375.853751 -241.763296) (xy 375.811735 -241.73277) (xy 375.775012 -241.696047)
			(xy 375.744486 -241.654031) (xy 375.720908 -241.607757) (xy 375.70486 -241.558364) (xy 375.696735 -241.507069)
			(xy 375.416825 -241.507069) (xy 375.4087 -241.558364) (xy 375.392652 -241.607757) (xy 375.369074 -241.654031)
			(xy 375.338548 -241.696047) (xy 375.301825 -241.73277) (xy 375.259809 -241.763296) (xy 375.213535 -241.786874)
			(xy 375.164142 -241.802922) (xy 375.112847 -241.811047) (xy 375.060913 -241.811047) (xy 375.009618 -241.802922)
			(xy 374.960225 -241.786874) (xy 374.913951 -241.763296) (xy 374.871935 -241.73277) (xy 374.835212 -241.696047)
			(xy 374.804686 -241.654031) (xy 374.781108 -241.607757) (xy 374.76506 -241.558364) (xy 374.756935 -241.507069)
			(xy 374.477025 -241.507069) (xy 374.4689 -241.558364) (xy 374.452852 -241.607757) (xy 374.429274 -241.654031)
			(xy 374.398748 -241.696047) (xy 374.362025 -241.73277) (xy 374.320009 -241.763296) (xy 374.273735 -241.786874)
			(xy 374.224342 -241.802922) (xy 374.173047 -241.811047) (xy 374.121113 -241.811047) (xy 374.069818 -241.802922)
			(xy 374.020425 -241.786874) (xy 373.974151 -241.763296) (xy 373.932135 -241.73277) (xy 373.895412 -241.696047)
			(xy 373.864886 -241.654031) (xy 373.841308 -241.607757) (xy 373.82526 -241.558364) (xy 373.817135 -241.507069)
			(xy 373.537225 -241.507069) (xy 373.5291 -241.558364) (xy 373.513052 -241.607757) (xy 373.489474 -241.654031)
			(xy 373.458948 -241.696047) (xy 373.422225 -241.73277) (xy 373.380209 -241.763296) (xy 373.333935 -241.786874)
			(xy 373.284542 -241.802922) (xy 373.233247 -241.811047) (xy 373.181313 -241.811047) (xy 373.130018 -241.802922)
			(xy 373.080625 -241.786874) (xy 373.034351 -241.763296) (xy 372.992335 -241.73277) (xy 372.955612 -241.696047)
			(xy 372.925086 -241.654031) (xy 372.901508 -241.607757) (xy 372.88546 -241.558364) (xy 372.877335 -241.507069)
			(xy 372.597425 -241.507069) (xy 372.5893 -241.558364) (xy 372.573252 -241.607757) (xy 372.549674 -241.654031)
			(xy 372.519148 -241.696047) (xy 372.482425 -241.73277) (xy 372.440409 -241.763296) (xy 372.394135 -241.786874)
			(xy 372.344742 -241.802922) (xy 372.293447 -241.811047) (xy 372.241513 -241.811047) (xy 372.190218 -241.802922)
			(xy 372.140825 -241.786874) (xy 372.094551 -241.763296) (xy 372.052535 -241.73277) (xy 372.015812 -241.696047)
			(xy 371.985286 -241.654031) (xy 371.961708 -241.607757) (xy 371.94566 -241.558364) (xy 371.937535 -241.507069)
			(xy 371.657625 -241.507069) (xy 371.6495 -241.558364) (xy 371.633452 -241.607757) (xy 371.609874 -241.654031)
			(xy 371.579348 -241.696047) (xy 371.542625 -241.73277) (xy 371.500609 -241.763296) (xy 371.454335 -241.786874)
			(xy 371.404942 -241.802922) (xy 371.353647 -241.811047) (xy 371.301713 -241.811047) (xy 371.250418 -241.802922)
			(xy 371.201025 -241.786874) (xy 371.154751 -241.763296) (xy 371.112735 -241.73277) (xy 371.076012 -241.696047)
			(xy 371.045486 -241.654031) (xy 371.021908 -241.607757) (xy 371.00586 -241.558364) (xy 370.997735 -241.507069)
			(xy 370.718079 -241.507069) (xy 370.709954 -241.558364) (xy 370.693906 -241.607757) (xy 370.670328 -241.654031)
			(xy 370.639802 -241.696047) (xy 370.603079 -241.73277) (xy 370.561063 -241.763296) (xy 370.514789 -241.786874)
			(xy 370.465396 -241.802922) (xy 370.414101 -241.811047) (xy 370.362167 -241.811047) (xy 370.310872 -241.802922)
			(xy 370.261479 -241.786874) (xy 370.215205 -241.763296) (xy 370.173189 -241.73277) (xy 370.136466 -241.696047)
			(xy 370.10594 -241.654031) (xy 370.082362 -241.607757) (xy 370.066314 -241.558364) (xy 370.058189 -241.507069)
			(xy 369.778025 -241.507069) (xy 369.7699 -241.558364) (xy 369.753852 -241.607757) (xy 369.730274 -241.654031)
			(xy 369.699748 -241.696047) (xy 369.663025 -241.73277) (xy 369.621009 -241.763296) (xy 369.574735 -241.786874)
			(xy 369.525342 -241.802922) (xy 369.474047 -241.811047) (xy 369.422113 -241.811047) (xy 369.370818 -241.802922)
			(xy 369.321425 -241.786874) (xy 369.275151 -241.763296) (xy 369.233135 -241.73277) (xy 369.196412 -241.696047)
			(xy 369.165886 -241.654031) (xy 369.142308 -241.607757) (xy 369.12626 -241.558364) (xy 369.118135 -241.507069)
			(xy 363.653516 -241.507069) (xy 363.671651 -241.545052) (xy 363.686005 -241.591958) (xy 363.693262 -241.640471)
			(xy 363.69371 -241.664998) (xy 363.69371 -241.665252) (xy 363.693201 -241.691219) (xy 363.685076 -241.742514)
			(xy 363.669028 -241.791907) (xy 363.64545 -241.838181) (xy 363.614924 -241.880197) (xy 363.578201 -241.91692)
			(xy 363.536185 -241.947446) (xy 363.489911 -241.971024) (xy 363.440518 -241.987072) (xy 363.389223 -241.995197)
			(xy 363.337289 -241.995197) (xy 363.285994 -241.987072) (xy 363.236601 -241.971024) (xy 363.190327 -241.947446)
			(xy 363.148311 -241.91692) (xy 363.111588 -241.880197) (xy 363.081062 -241.838181) (xy 363.057484 -241.791907)
			(xy 363.041436 -241.742514) (xy 363.033311 -241.691219) (xy 363.032802 -241.665252) (xy 362.203976 -241.665252)
			(xy 362.181602 -241.696047) (xy 362.144879 -241.73277) (xy 362.102863 -241.763296) (xy 362.056589 -241.786874)
			(xy 362.007196 -241.802922) (xy 361.955901 -241.811047) (xy 361.903967 -241.811047) (xy 361.852672 -241.802922)
			(xy 361.803279 -241.786874) (xy 361.757005 -241.763296) (xy 361.714989 -241.73277) (xy 361.678266 -241.696047)
			(xy 361.64774 -241.654031) (xy 361.624162 -241.607757) (xy 361.608114 -241.558364) (xy 361.599989 -241.507069)
			(xy 361.319825 -241.507069) (xy 361.3117 -241.558364) (xy 361.295652 -241.607757) (xy 361.272074 -241.654031)
			(xy 361.241548 -241.696047) (xy 361.204825 -241.73277) (xy 361.162809 -241.763296) (xy 361.116535 -241.786874)
			(xy 361.067142 -241.802922) (xy 361.015847 -241.811047) (xy 360.963913 -241.811047) (xy 360.912618 -241.802922)
			(xy 360.863225 -241.786874) (xy 360.816951 -241.763296) (xy 360.774935 -241.73277) (xy 360.738212 -241.696047)
			(xy 360.707686 -241.654031) (xy 360.684108 -241.607757) (xy 360.66806 -241.558364) (xy 360.659935 -241.507069)
			(xy 360.380279 -241.507069) (xy 360.372154 -241.558364) (xy 360.356106 -241.607757) (xy 360.332528 -241.654031)
			(xy 360.302002 -241.696047) (xy 360.265279 -241.73277) (xy 360.223263 -241.763296) (xy 360.176989 -241.786874)
			(xy 360.127596 -241.802922) (xy 360.076301 -241.811047) (xy 360.024367 -241.811047) (xy 359.973072 -241.802922)
			(xy 359.923679 -241.786874) (xy 359.877405 -241.763296) (xy 359.835389 -241.73277) (xy 359.798666 -241.696047)
			(xy 359.76814 -241.654031) (xy 359.744562 -241.607757) (xy 359.728514 -241.558364) (xy 359.720389 -241.507069)
			(xy 359.440479 -241.507069) (xy 359.432354 -241.558364) (xy 359.416306 -241.607757) (xy 359.392728 -241.654031)
			(xy 359.362202 -241.696047) (xy 359.325479 -241.73277) (xy 359.283463 -241.763296) (xy 359.237189 -241.786874)
			(xy 359.187796 -241.802922) (xy 359.136501 -241.811047) (xy 359.084567 -241.811047) (xy 359.033272 -241.802922)
			(xy 358.983879 -241.786874) (xy 358.937605 -241.763296) (xy 358.895589 -241.73277) (xy 358.858866 -241.696047)
			(xy 358.82834 -241.654031) (xy 358.804762 -241.607757) (xy 358.788714 -241.558364) (xy 358.780589 -241.507069)
			(xy 358.500679 -241.507069) (xy 358.492554 -241.558364) (xy 358.476506 -241.607757) (xy 358.452928 -241.654031)
			(xy 358.422402 -241.696047) (xy 358.385679 -241.73277) (xy 358.343663 -241.763296) (xy 358.297389 -241.786874)
			(xy 358.247996 -241.802922) (xy 358.196701 -241.811047) (xy 358.144767 -241.811047) (xy 358.093472 -241.802922)
			(xy 358.044079 -241.786874) (xy 357.997805 -241.763296) (xy 357.955789 -241.73277) (xy 357.919066 -241.696047)
			(xy 357.88854 -241.654031) (xy 357.864962 -241.607757) (xy 357.848914 -241.558364) (xy 357.840789 -241.507069)
			(xy 357.560879 -241.507069) (xy 357.552754 -241.558364) (xy 357.536706 -241.607757) (xy 357.513128 -241.654031)
			(xy 357.482602 -241.696047) (xy 357.445879 -241.73277) (xy 357.403863 -241.763296) (xy 357.357589 -241.786874)
			(xy 357.308196 -241.802922) (xy 357.256901 -241.811047) (xy 357.204967 -241.811047) (xy 357.153672 -241.802922)
			(xy 357.104279 -241.786874) (xy 357.058005 -241.763296) (xy 357.015989 -241.73277) (xy 356.979266 -241.696047)
			(xy 356.94874 -241.654031) (xy 356.925162 -241.607757) (xy 356.909114 -241.558364) (xy 356.900989 -241.507069)
			(xy 350.042733 -241.507069) (xy 350.034608 -241.558364) (xy 350.01856 -241.607757) (xy 349.994982 -241.654031)
			(xy 349.964456 -241.696047) (xy 349.927733 -241.73277) (xy 349.885717 -241.763296) (xy 349.839443 -241.786874)
			(xy 349.79005 -241.802922) (xy 349.738755 -241.811047) (xy 349.686821 -241.811047) (xy 349.635526 -241.802922)
			(xy 349.586133 -241.786874) (xy 349.539859 -241.763296) (xy 349.497843 -241.73277) (xy 349.46112 -241.696047)
			(xy 349.430594 -241.654031) (xy 349.407016 -241.607757) (xy 349.390968 -241.558364) (xy 349.382843 -241.507069)
			(xy 349.102679 -241.507069) (xy 349.094554 -241.558364) (xy 349.078506 -241.607757) (xy 349.054928 -241.654031)
			(xy 349.024402 -241.696047) (xy 348.987679 -241.73277) (xy 348.945663 -241.763296) (xy 348.899389 -241.786874)
			(xy 348.849996 -241.802922) (xy 348.798701 -241.811047) (xy 348.746767 -241.811047) (xy 348.695472 -241.802922)
			(xy 348.646079 -241.786874) (xy 348.599805 -241.763296) (xy 348.557789 -241.73277) (xy 348.521066 -241.696047)
			(xy 348.49054 -241.654031) (xy 348.466962 -241.607757) (xy 348.450914 -241.558364) (xy 348.442789 -241.507069)
			(xy 348.162625 -241.507069) (xy 348.1545 -241.558364) (xy 348.138452 -241.607757) (xy 348.114874 -241.654031)
			(xy 348.084348 -241.696047) (xy 348.047625 -241.73277) (xy 348.005609 -241.763296) (xy 347.959335 -241.786874)
			(xy 347.909942 -241.802922) (xy 347.858647 -241.811047) (xy 347.806713 -241.811047) (xy 347.755418 -241.802922)
			(xy 347.706025 -241.786874) (xy 347.659751 -241.763296) (xy 347.617735 -241.73277) (xy 347.581012 -241.696047)
			(xy 347.550486 -241.654031) (xy 347.526908 -241.607757) (xy 347.51086 -241.558364) (xy 347.502735 -241.507069)
			(xy 347.222825 -241.507069) (xy 347.2147 -241.558364) (xy 347.198652 -241.607757) (xy 347.175074 -241.654031)
			(xy 347.144548 -241.696047) (xy 347.107825 -241.73277) (xy 347.065809 -241.763296) (xy 347.019535 -241.786874)
			(xy 346.970142 -241.802922) (xy 346.918847 -241.811047) (xy 346.866913 -241.811047) (xy 346.815618 -241.802922)
			(xy 346.766225 -241.786874) (xy 346.719951 -241.763296) (xy 346.677935 -241.73277) (xy 346.641212 -241.696047)
			(xy 346.610686 -241.654031) (xy 346.587108 -241.607757) (xy 346.57106 -241.558364) (xy 346.562935 -241.507069)
			(xy 346.283025 -241.507069) (xy 346.2749 -241.558364) (xy 346.258852 -241.607757) (xy 346.235274 -241.654031)
			(xy 346.204748 -241.696047) (xy 346.168025 -241.73277) (xy 346.126009 -241.763296) (xy 346.079735 -241.786874)
			(xy 346.030342 -241.802922) (xy 345.979047 -241.811047) (xy 345.927113 -241.811047) (xy 345.875818 -241.802922)
			(xy 345.826425 -241.786874) (xy 345.780151 -241.763296) (xy 345.738135 -241.73277) (xy 345.701412 -241.696047)
			(xy 345.670886 -241.654031) (xy 345.647308 -241.607757) (xy 345.63126 -241.558364) (xy 345.623135 -241.507069)
			(xy 345.343225 -241.507069) (xy 345.3351 -241.558364) (xy 345.319052 -241.607757) (xy 345.295474 -241.654031)
			(xy 345.264948 -241.696047) (xy 345.228225 -241.73277) (xy 345.186209 -241.763296) (xy 345.139935 -241.786874)
			(xy 345.090542 -241.802922) (xy 345.039247 -241.811047) (xy 344.987313 -241.811047) (xy 344.936018 -241.802922)
			(xy 344.886625 -241.786874) (xy 344.840351 -241.763296) (xy 344.798335 -241.73277) (xy 344.761612 -241.696047)
			(xy 344.731086 -241.654031) (xy 344.707508 -241.607757) (xy 344.69146 -241.558364) (xy 344.683335 -241.507069)
			(xy 344.403425 -241.507069) (xy 344.3953 -241.558364) (xy 344.379252 -241.607757) (xy 344.355674 -241.654031)
			(xy 344.325148 -241.696047) (xy 344.288425 -241.73277) (xy 344.246409 -241.763296) (xy 344.200135 -241.786874)
			(xy 344.150742 -241.802922) (xy 344.099447 -241.811047) (xy 344.047513 -241.811047) (xy 343.996218 -241.802922)
			(xy 343.946825 -241.786874) (xy 343.900551 -241.763296) (xy 343.858535 -241.73277) (xy 343.821812 -241.696047)
			(xy 343.791286 -241.654031) (xy 343.767708 -241.607757) (xy 343.75166 -241.558364) (xy 343.743535 -241.507069)
			(xy 343.463625 -241.507069) (xy 343.4555 -241.558364) (xy 343.439452 -241.607757) (xy 343.415874 -241.654031)
			(xy 343.385348 -241.696047) (xy 343.348625 -241.73277) (xy 343.306609 -241.763296) (xy 343.260335 -241.786874)
			(xy 343.210942 -241.802922) (xy 343.159647 -241.811047) (xy 343.107713 -241.811047) (xy 343.056418 -241.802922)
			(xy 343.007025 -241.786874) (xy 342.960751 -241.763296) (xy 342.918735 -241.73277) (xy 342.882012 -241.696047)
			(xy 342.851486 -241.654031) (xy 342.827908 -241.607757) (xy 342.81186 -241.558364) (xy 342.803735 -241.507069)
			(xy 342.524079 -241.507069) (xy 342.515954 -241.558364) (xy 342.499906 -241.607757) (xy 342.476328 -241.654031)
			(xy 342.445802 -241.696047) (xy 342.409079 -241.73277) (xy 342.367063 -241.763296) (xy 342.320789 -241.786874)
			(xy 342.271396 -241.802922) (xy 342.220101 -241.811047) (xy 342.168167 -241.811047) (xy 342.116872 -241.802922)
			(xy 342.067479 -241.786874) (xy 342.021205 -241.763296) (xy 341.979189 -241.73277) (xy 341.942466 -241.696047)
			(xy 341.91194 -241.654031) (xy 341.888362 -241.607757) (xy 341.872314 -241.558364) (xy 341.864189 -241.507069)
			(xy 341.584025 -241.507069) (xy 341.5759 -241.558364) (xy 341.559852 -241.607757) (xy 341.536274 -241.654031)
			(xy 341.505748 -241.696047) (xy 341.469025 -241.73277) (xy 341.427009 -241.763296) (xy 341.380735 -241.786874)
			(xy 341.331342 -241.802922) (xy 341.280047 -241.811047) (xy 341.228113 -241.811047) (xy 341.176818 -241.802922)
			(xy 341.127425 -241.786874) (xy 341.081151 -241.763296) (xy 341.039135 -241.73277) (xy 341.002412 -241.696047)
			(xy 340.971886 -241.654031) (xy 340.948308 -241.607757) (xy 340.93226 -241.558364) (xy 340.924135 -241.507069)
			(xy 340.644225 -241.507069) (xy 340.6361 -241.558364) (xy 340.620052 -241.607757) (xy 340.596474 -241.654031)
			(xy 340.565948 -241.696047) (xy 340.529225 -241.73277) (xy 340.487209 -241.763296) (xy 340.440935 -241.786874)
			(xy 340.391542 -241.802922) (xy 340.340247 -241.811047) (xy 340.288313 -241.811047) (xy 340.237018 -241.802922)
			(xy 340.187625 -241.786874) (xy 340.141351 -241.763296) (xy 340.099335 -241.73277) (xy 340.062612 -241.696047)
			(xy 340.032086 -241.654031) (xy 340.008508 -241.607757) (xy 339.99246 -241.558364) (xy 339.984335 -241.507069)
			(xy 339.704784 -241.507069) (xy 339.704784 -241.507651) (xy 339.696301 -241.56007) (xy 339.679554 -241.610461)
			(xy 339.654973 -241.65753) (xy 339.623188 -241.700067) (xy 339.585017 -241.736981) (xy 339.541439 -241.767324)
			(xy 339.517736 -241.779298) (xy 339.505036 -241.785394) (xy 339.475064 -241.83086) (xy 339.475064 -241.958622)
			(xy 339.475472 -241.967524) (xy 339.481728 -241.984197) (xy 339.493356 -241.997684) (xy 339.500972 -242.00231)
			(xy 339.584284 -242.042188) (xy 339.5923 -242.045084) (xy 339.609314 -242.045872) (xy 339.617558 -242.043712)
			(xy 339.638132 -242.036346) (xy 339.64118 -242.034314) (xy 339.644736 -242.03152) (xy 339.666443 -242.01571)
			(xy 339.713903 -241.990591) (xy 339.764796 -241.97346) (xy 339.817785 -241.964767) (xy 339.844634 -241.96421)
			(xy 339.870618 -241.964722) (xy 339.921946 -241.972856) (xy 339.971369 -241.988919) (xy 340.017671 -242.012516)
			(xy 340.059712 -242.043065) (xy 340.096458 -242.079813) (xy 340.127002 -242.121858) (xy 340.150594 -242.168163)
			(xy 340.166652 -242.217588) (xy 340.174781 -242.268916) (xy 340.174781 -242.320884) (xy 340.174781 -242.320885)
			(xy 340.454489 -242.320885) (xy 340.454489 -242.268951) (xy 340.462614 -242.217656) (xy 340.478662 -242.168263)
			(xy 340.50224 -242.121989) (xy 340.532766 -242.079973) (xy 340.569489 -242.04325) (xy 340.611505 -242.012724)
			(xy 340.657779 -241.989146) (xy 340.707172 -241.973098) (xy 340.758467 -241.964973) (xy 340.810401 -241.964973)
			(xy 340.861696 -241.973098) (xy 340.911089 -241.989146) (xy 340.957363 -242.012724) (xy 340.999379 -242.04325)
			(xy 341.036102 -242.079973) (xy 341.066628 -242.121989) (xy 341.090206 -242.168263) (xy 341.106254 -242.217656)
			(xy 341.114379 -242.268951) (xy 341.114888 -242.294918) (xy 341.114379 -242.320885) (xy 341.394289 -242.320885)
			(xy 341.394289 -242.268951) (xy 341.402414 -242.217656) (xy 341.418462 -242.168263) (xy 341.44204 -242.121989)
			(xy 341.472566 -242.079973) (xy 341.509289 -242.04325) (xy 341.551305 -242.012724) (xy 341.597579 -241.989146)
			(xy 341.646972 -241.973098) (xy 341.698267 -241.964973) (xy 341.750201 -241.964973) (xy 341.801496 -241.973098)
			(xy 341.850889 -241.989146) (xy 341.897163 -242.012724) (xy 341.939179 -242.04325) (xy 341.975902 -242.079973)
			(xy 342.006428 -242.121989) (xy 342.030006 -242.168263) (xy 342.046054 -242.217656) (xy 342.054179 -242.268951)
			(xy 342.054688 -242.294918) (xy 342.054179 -242.320885) (xy 342.334089 -242.320885) (xy 342.334089 -242.268951)
			(xy 342.342214 -242.217656) (xy 342.358262 -242.168263) (xy 342.38184 -242.121989) (xy 342.412366 -242.079973)
			(xy 342.449089 -242.04325) (xy 342.491105 -242.012724) (xy 342.537379 -241.989146) (xy 342.586772 -241.973098)
			(xy 342.638067 -241.964973) (xy 342.690001 -241.964973) (xy 342.741296 -241.973098) (xy 342.790689 -241.989146)
			(xy 342.836963 -242.012724) (xy 342.878979 -242.04325) (xy 342.915702 -242.079973) (xy 342.946228 -242.121989)
			(xy 342.969806 -242.168263) (xy 342.985854 -242.217656) (xy 342.993979 -242.268951) (xy 342.994488 -242.294918)
			(xy 342.993979 -242.320885) (xy 343.273889 -242.320885) (xy 343.273889 -242.268951) (xy 343.282014 -242.217656)
			(xy 343.298062 -242.168263) (xy 343.32164 -242.121989) (xy 343.352166 -242.079973) (xy 343.388889 -242.04325)
			(xy 343.430905 -242.012724) (xy 343.477179 -241.989146) (xy 343.526572 -241.973098) (xy 343.577867 -241.964973)
			(xy 343.629801 -241.964973) (xy 343.681096 -241.973098) (xy 343.730489 -241.989146) (xy 343.776763 -242.012724)
			(xy 343.818779 -242.04325) (xy 343.855502 -242.079973) (xy 343.886028 -242.121989) (xy 343.909606 -242.168263)
			(xy 343.925654 -242.217656) (xy 343.933779 -242.268951) (xy 343.934288 -242.294918) (xy 343.933779 -242.320885)
			(xy 344.213689 -242.320885) (xy 344.213689 -242.268951) (xy 344.221814 -242.217656) (xy 344.237862 -242.168263)
			(xy 344.26144 -242.121989) (xy 344.291966 -242.079973) (xy 344.328689 -242.04325) (xy 344.370705 -242.012724)
			(xy 344.416979 -241.989146) (xy 344.466372 -241.973098) (xy 344.517667 -241.964973) (xy 344.569601 -241.964973)
			(xy 344.620896 -241.973098) (xy 344.670289 -241.989146) (xy 344.716563 -242.012724) (xy 344.758579 -242.04325)
			(xy 344.795302 -242.079973) (xy 344.825828 -242.121989) (xy 344.849406 -242.168263) (xy 344.865454 -242.217656)
			(xy 344.873579 -242.268951) (xy 344.874088 -242.294918) (xy 344.873579 -242.320885) (xy 345.153489 -242.320885)
			(xy 345.153489 -242.268951) (xy 345.161614 -242.217656) (xy 345.177662 -242.168263) (xy 345.20124 -242.121989)
			(xy 345.231766 -242.079973) (xy 345.268489 -242.04325) (xy 345.310505 -242.012724) (xy 345.356779 -241.989146)
			(xy 345.406172 -241.973098) (xy 345.457467 -241.964973) (xy 345.509401 -241.964973) (xy 345.560696 -241.973098)
			(xy 345.610089 -241.989146) (xy 345.656363 -242.012724) (xy 345.698379 -242.04325) (xy 345.735102 -242.079973)
			(xy 345.765628 -242.121989) (xy 345.789206 -242.168263) (xy 345.805254 -242.217656) (xy 345.813379 -242.268951)
			(xy 345.813888 -242.294918) (xy 345.813379 -242.320885) (xy 346.093289 -242.320885) (xy 346.093289 -242.268951)
			(xy 346.101414 -242.217656) (xy 346.117462 -242.168263) (xy 346.14104 -242.121989) (xy 346.171566 -242.079973)
			(xy 346.208289 -242.04325) (xy 346.250305 -242.012724) (xy 346.296579 -241.989146) (xy 346.345972 -241.973098)
			(xy 346.397267 -241.964973) (xy 346.449201 -241.964973) (xy 346.500496 -241.973098) (xy 346.549889 -241.989146)
			(xy 346.596163 -242.012724) (xy 346.638179 -242.04325) (xy 346.674902 -242.079973) (xy 346.705428 -242.121989)
			(xy 346.729006 -242.168263) (xy 346.745054 -242.217656) (xy 346.753179 -242.268951) (xy 346.753688 -242.294918)
			(xy 346.753179 -242.320885) (xy 347.033089 -242.320885) (xy 347.033089 -242.268951) (xy 347.041214 -242.217656)
			(xy 347.057262 -242.168263) (xy 347.08084 -242.121989) (xy 347.111366 -242.079973) (xy 347.148089 -242.04325)
			(xy 347.190105 -242.012724) (xy 347.236379 -241.989146) (xy 347.285772 -241.973098) (xy 347.337067 -241.964973)
			(xy 347.389001 -241.964973) (xy 347.440296 -241.973098) (xy 347.489689 -241.989146) (xy 347.535963 -242.012724)
			(xy 347.577979 -242.04325) (xy 347.614702 -242.079973) (xy 347.645228 -242.121989) (xy 347.668806 -242.168263)
			(xy 347.684854 -242.217656) (xy 347.692979 -242.268951) (xy 347.693488 -242.294918) (xy 347.692979 -242.320885)
			(xy 347.972889 -242.320885) (xy 347.972889 -242.268951) (xy 347.981014 -242.217656) (xy 347.997062 -242.168263)
			(xy 348.02064 -242.121989) (xy 348.051166 -242.079973) (xy 348.087889 -242.04325) (xy 348.129905 -242.012724)
			(xy 348.176179 -241.989146) (xy 348.225572 -241.973098) (xy 348.276867 -241.964973) (xy 348.328801 -241.964973)
			(xy 348.380096 -241.973098) (xy 348.429489 -241.989146) (xy 348.475763 -242.012724) (xy 348.517779 -242.04325)
			(xy 348.554502 -242.079973) (xy 348.585028 -242.121989) (xy 348.608606 -242.168263) (xy 348.624654 -242.217656)
			(xy 348.632779 -242.268951) (xy 348.633288 -242.294918) (xy 348.632779 -242.320885) (xy 348.912689 -242.320885)
			(xy 348.912689 -242.268951) (xy 348.920814 -242.217656) (xy 348.936862 -242.168263) (xy 348.96044 -242.121989)
			(xy 348.990966 -242.079973) (xy 349.027689 -242.04325) (xy 349.069705 -242.012724) (xy 349.115979 -241.989146)
			(xy 349.165372 -241.973098) (xy 349.216667 -241.964973) (xy 349.268601 -241.964973) (xy 349.319896 -241.973098)
			(xy 349.369289 -241.989146) (xy 349.415563 -242.012724) (xy 349.457579 -242.04325) (xy 349.494302 -242.079973)
			(xy 349.524828 -242.121989) (xy 349.548406 -242.168263) (xy 349.564454 -242.217656) (xy 349.572579 -242.268951)
			(xy 349.573088 -242.294918) (xy 349.572579 -242.320885) (xy 349.852489 -242.320885) (xy 349.852489 -242.268951)
			(xy 349.860614 -242.217656) (xy 349.876662 -242.168263) (xy 349.90024 -242.121989) (xy 349.930766 -242.079973)
			(xy 349.967489 -242.04325) (xy 350.009505 -242.012724) (xy 350.055779 -241.989146) (xy 350.105172 -241.973098)
			(xy 350.156467 -241.964973) (xy 350.208401 -241.964973) (xy 350.259696 -241.973098) (xy 350.309089 -241.989146)
			(xy 350.355363 -242.012724) (xy 350.397379 -242.04325) (xy 350.434102 -242.079973) (xy 350.464628 -242.121989)
			(xy 350.488206 -242.168263) (xy 350.504254 -242.217656) (xy 350.512379 -242.268951) (xy 350.512888 -242.294918)
			(xy 350.512379 -242.320885) (xy 350.504254 -242.37218) (xy 350.488206 -242.421573) (xy 350.464628 -242.467847)
			(xy 350.434102 -242.509863) (xy 350.397379 -242.546586) (xy 350.355363 -242.577112) (xy 350.309089 -242.60069)
			(xy 350.259696 -242.616738) (xy 350.208401 -242.624863) (xy 350.156467 -242.624863) (xy 350.105172 -242.616738)
			(xy 350.055779 -242.60069) (xy 350.009505 -242.577112) (xy 349.967489 -242.546586) (xy 349.930766 -242.509863)
			(xy 349.90024 -242.467847) (xy 349.876662 -242.421573) (xy 349.860614 -242.37218) (xy 349.852489 -242.320885)
			(xy 349.572579 -242.320885) (xy 349.564454 -242.37218) (xy 349.548406 -242.421573) (xy 349.524828 -242.467847)
			(xy 349.494302 -242.509863) (xy 349.457579 -242.546586) (xy 349.415563 -242.577112) (xy 349.369289 -242.60069)
			(xy 349.319896 -242.616738) (xy 349.268601 -242.624863) (xy 349.216667 -242.624863) (xy 349.165372 -242.616738)
			(xy 349.115979 -242.60069) (xy 349.069705 -242.577112) (xy 349.027689 -242.546586) (xy 348.990966 -242.509863)
			(xy 348.96044 -242.467847) (xy 348.936862 -242.421573) (xy 348.920814 -242.37218) (xy 348.912689 -242.320885)
			(xy 348.632779 -242.320885) (xy 348.624654 -242.37218) (xy 348.608606 -242.421573) (xy 348.585028 -242.467847)
			(xy 348.554502 -242.509863) (xy 348.517779 -242.546586) (xy 348.475763 -242.577112) (xy 348.429489 -242.60069)
			(xy 348.380096 -242.616738) (xy 348.328801 -242.624863) (xy 348.276867 -242.624863) (xy 348.225572 -242.616738)
			(xy 348.176179 -242.60069) (xy 348.129905 -242.577112) (xy 348.087889 -242.546586) (xy 348.051166 -242.509863)
			(xy 348.02064 -242.467847) (xy 347.997062 -242.421573) (xy 347.981014 -242.37218) (xy 347.972889 -242.320885)
			(xy 347.692979 -242.320885) (xy 347.684854 -242.37218) (xy 347.668806 -242.421573) (xy 347.645228 -242.467847)
			(xy 347.614702 -242.509863) (xy 347.577979 -242.546586) (xy 347.535963 -242.577112) (xy 347.489689 -242.60069)
			(xy 347.440296 -242.616738) (xy 347.389001 -242.624863) (xy 347.337067 -242.624863) (xy 347.285772 -242.616738)
			(xy 347.236379 -242.60069) (xy 347.190105 -242.577112) (xy 347.148089 -242.546586) (xy 347.111366 -242.509863)
			(xy 347.08084 -242.467847) (xy 347.057262 -242.421573) (xy 347.041214 -242.37218) (xy 347.033089 -242.320885)
			(xy 346.753179 -242.320885) (xy 346.745054 -242.37218) (xy 346.729006 -242.421573) (xy 346.705428 -242.467847)
			(xy 346.674902 -242.509863) (xy 346.638179 -242.546586) (xy 346.596163 -242.577112) (xy 346.549889 -242.60069)
			(xy 346.500496 -242.616738) (xy 346.449201 -242.624863) (xy 346.397267 -242.624863) (xy 346.345972 -242.616738)
			(xy 346.296579 -242.60069) (xy 346.250305 -242.577112) (xy 346.208289 -242.546586) (xy 346.171566 -242.509863)
			(xy 346.14104 -242.467847) (xy 346.117462 -242.421573) (xy 346.101414 -242.37218) (xy 346.093289 -242.320885)
			(xy 345.813379 -242.320885) (xy 345.805254 -242.37218) (xy 345.789206 -242.421573) (xy 345.765628 -242.467847)
			(xy 345.735102 -242.509863) (xy 345.698379 -242.546586) (xy 345.656363 -242.577112) (xy 345.610089 -242.60069)
			(xy 345.560696 -242.616738) (xy 345.509401 -242.624863) (xy 345.457467 -242.624863) (xy 345.406172 -242.616738)
			(xy 345.356779 -242.60069) (xy 345.310505 -242.577112) (xy 345.268489 -242.546586) (xy 345.231766 -242.509863)
			(xy 345.20124 -242.467847) (xy 345.177662 -242.421573) (xy 345.161614 -242.37218) (xy 345.153489 -242.320885)
			(xy 344.873579 -242.320885) (xy 344.865454 -242.37218) (xy 344.849406 -242.421573) (xy 344.825828 -242.467847)
			(xy 344.795302 -242.509863) (xy 344.758579 -242.546586) (xy 344.716563 -242.577112) (xy 344.670289 -242.60069)
			(xy 344.620896 -242.616738) (xy 344.569601 -242.624863) (xy 344.517667 -242.624863) (xy 344.466372 -242.616738)
			(xy 344.416979 -242.60069) (xy 344.370705 -242.577112) (xy 344.328689 -242.546586) (xy 344.291966 -242.509863)
			(xy 344.26144 -242.467847) (xy 344.237862 -242.421573) (xy 344.221814 -242.37218) (xy 344.213689 -242.320885)
			(xy 343.933779 -242.320885) (xy 343.925654 -242.37218) (xy 343.909606 -242.421573) (xy 343.886028 -242.467847)
			(xy 343.855502 -242.509863) (xy 343.818779 -242.546586) (xy 343.776763 -242.577112) (xy 343.730489 -242.60069)
			(xy 343.681096 -242.616738) (xy 343.629801 -242.624863) (xy 343.577867 -242.624863) (xy 343.526572 -242.616738)
			(xy 343.477179 -242.60069) (xy 343.430905 -242.577112) (xy 343.388889 -242.546586) (xy 343.352166 -242.509863)
			(xy 343.32164 -242.467847) (xy 343.298062 -242.421573) (xy 343.282014 -242.37218) (xy 343.273889 -242.320885)
			(xy 342.993979 -242.320885) (xy 342.985854 -242.37218) (xy 342.969806 -242.421573) (xy 342.946228 -242.467847)
			(xy 342.915702 -242.509863) (xy 342.878979 -242.546586) (xy 342.836963 -242.577112) (xy 342.790689 -242.60069)
			(xy 342.741296 -242.616738) (xy 342.690001 -242.624863) (xy 342.638067 -242.624863) (xy 342.586772 -242.616738)
			(xy 342.537379 -242.60069) (xy 342.491105 -242.577112) (xy 342.449089 -242.546586) (xy 342.412366 -242.509863)
			(xy 342.38184 -242.467847) (xy 342.358262 -242.421573) (xy 342.342214 -242.37218) (xy 342.334089 -242.320885)
			(xy 342.054179 -242.320885) (xy 342.046054 -242.37218) (xy 342.030006 -242.421573) (xy 342.006428 -242.467847)
			(xy 341.975902 -242.509863) (xy 341.939179 -242.546586) (xy 341.897163 -242.577112) (xy 341.850889 -242.60069)
			(xy 341.801496 -242.616738) (xy 341.750201 -242.624863) (xy 341.698267 -242.624863) (xy 341.646972 -242.616738)
			(xy 341.597579 -242.60069) (xy 341.551305 -242.577112) (xy 341.509289 -242.546586) (xy 341.472566 -242.509863)
			(xy 341.44204 -242.467847) (xy 341.418462 -242.421573) (xy 341.402414 -242.37218) (xy 341.394289 -242.320885)
			(xy 341.114379 -242.320885) (xy 341.106254 -242.37218) (xy 341.090206 -242.421573) (xy 341.066628 -242.467847)
			(xy 341.036102 -242.509863) (xy 340.999379 -242.546586) (xy 340.957363 -242.577112) (xy 340.911089 -242.60069)
			(xy 340.861696 -242.616738) (xy 340.810401 -242.624863) (xy 340.758467 -242.624863) (xy 340.707172 -242.616738)
			(xy 340.657779 -242.60069) (xy 340.611505 -242.577112) (xy 340.569489 -242.546586) (xy 340.532766 -242.509863)
			(xy 340.50224 -242.467847) (xy 340.478662 -242.421573) (xy 340.462614 -242.37218) (xy 340.454489 -242.320885)
			(xy 340.174781 -242.320885) (xy 340.166652 -242.372212) (xy 340.150594 -242.421637) (xy 340.127002 -242.467942)
			(xy 340.096458 -242.509987) (xy 340.059712 -242.546735) (xy 340.017671 -242.577284) (xy 339.971369 -242.600881)
			(xy 339.921946 -242.616944) (xy 339.870618 -242.625078) (xy 339.844634 -242.625626) (xy 339.817668 -242.625089)
			(xy 339.764452 -242.61633) (xy 339.713362 -242.599056) (xy 339.66575 -242.573723) (xy 339.643974 -242.557808)
			(xy 339.637878 -242.553236) (xy 339.619844 -242.546886) (xy 339.61112 -242.544208) (xy 339.59289 -242.54461)
			(xy 339.584284 -242.547648) (xy 339.500972 -242.587526) (xy 339.493334 -242.592127) (xy 339.481679 -242.605605)
			(xy 339.475463 -242.622305) (xy 339.475064 -242.631214) (xy 339.475064 -242.75923) (xy 339.505036 -242.804696)
			(xy 339.517736 -242.810792) (xy 339.541453 -242.822754) (xy 339.585057 -242.853083) (xy 339.623253 -242.889991)
			(xy 339.65506 -242.93253) (xy 339.679659 -242.979604) (xy 339.696419 -243.030006) (xy 339.704909 -243.082437)
			(xy 339.70491 -243.134955) (xy 339.984335 -243.134955) (xy 339.984335 -243.083021) (xy 339.99246 -243.031726)
			(xy 340.008508 -242.982333) (xy 340.032086 -242.936059) (xy 340.062612 -242.894043) (xy 340.099335 -242.85732)
			(xy 340.141351 -242.826794) (xy 340.187625 -242.803216) (xy 340.237018 -242.787168) (xy 340.288313 -242.779043)
			(xy 340.340247 -242.779043) (xy 340.391542 -242.787168) (xy 340.440935 -242.803216) (xy 340.487209 -242.826794)
			(xy 340.529225 -242.85732) (xy 340.565948 -242.894043) (xy 340.596474 -242.936059) (xy 340.620052 -242.982333)
			(xy 340.6361 -243.031726) (xy 340.644225 -243.083021) (xy 340.644734 -243.108988) (xy 340.644225 -243.134955)
			(xy 340.924135 -243.134955) (xy 340.924135 -243.083021) (xy 340.93226 -243.031726) (xy 340.948308 -242.982333)
			(xy 340.971886 -242.936059) (xy 341.002412 -242.894043) (xy 341.039135 -242.85732) (xy 341.081151 -242.826794)
			(xy 341.127425 -242.803216) (xy 341.176818 -242.787168) (xy 341.228113 -242.779043) (xy 341.280047 -242.779043)
			(xy 341.331342 -242.787168) (xy 341.380735 -242.803216) (xy 341.427009 -242.826794) (xy 341.469025 -242.85732)
			(xy 341.505748 -242.894043) (xy 341.536274 -242.936059) (xy 341.559852 -242.982333) (xy 341.5759 -243.031726)
			(xy 341.584025 -243.083021) (xy 341.584534 -243.108988) (xy 341.584025 -243.134955) (xy 341.863935 -243.134955)
			(xy 341.863935 -243.083021) (xy 341.87206 -243.031726) (xy 341.888108 -242.982333) (xy 341.911686 -242.936059)
			(xy 341.942212 -242.894043) (xy 341.978935 -242.85732) (xy 342.020951 -242.826794) (xy 342.067225 -242.803216)
			(xy 342.116618 -242.787168) (xy 342.167913 -242.779043) (xy 342.219847 -242.779043) (xy 342.271142 -242.787168)
			(xy 342.320535 -242.803216) (xy 342.366809 -242.826794) (xy 342.408825 -242.85732) (xy 342.445548 -242.894043)
			(xy 342.476074 -242.936059) (xy 342.499652 -242.982333) (xy 342.5157 -243.031726) (xy 342.523825 -243.083021)
			(xy 342.524334 -243.108988) (xy 342.523825 -243.134955) (xy 342.803735 -243.134955) (xy 342.803735 -243.083021)
			(xy 342.81186 -243.031726) (xy 342.827908 -242.982333) (xy 342.851486 -242.936059) (xy 342.882012 -242.894043)
			(xy 342.918735 -242.85732) (xy 342.960751 -242.826794) (xy 343.007025 -242.803216) (xy 343.056418 -242.787168)
			(xy 343.107713 -242.779043) (xy 343.159647 -242.779043) (xy 343.210942 -242.787168) (xy 343.260335 -242.803216)
			(xy 343.306609 -242.826794) (xy 343.348625 -242.85732) (xy 343.385348 -242.894043) (xy 343.415874 -242.936059)
			(xy 343.439452 -242.982333) (xy 343.4555 -243.031726) (xy 343.463625 -243.083021) (xy 343.464134 -243.108988)
			(xy 343.463625 -243.134955) (xy 343.743535 -243.134955) (xy 343.743535 -243.083021) (xy 343.75166 -243.031726)
			(xy 343.767708 -242.982333) (xy 343.791286 -242.936059) (xy 343.821812 -242.894043) (xy 343.858535 -242.85732)
			(xy 343.900551 -242.826794) (xy 343.946825 -242.803216) (xy 343.996218 -242.787168) (xy 344.047513 -242.779043)
			(xy 344.099447 -242.779043) (xy 344.150742 -242.787168) (xy 344.200135 -242.803216) (xy 344.246409 -242.826794)
			(xy 344.288425 -242.85732) (xy 344.325148 -242.894043) (xy 344.355674 -242.936059) (xy 344.379252 -242.982333)
			(xy 344.3953 -243.031726) (xy 344.403425 -243.083021) (xy 344.403934 -243.108988) (xy 344.403425 -243.134955)
			(xy 344.683335 -243.134955) (xy 344.683335 -243.083021) (xy 344.69146 -243.031726) (xy 344.707508 -242.982333)
			(xy 344.731086 -242.936059) (xy 344.761612 -242.894043) (xy 344.798335 -242.85732) (xy 344.840351 -242.826794)
			(xy 344.886625 -242.803216) (xy 344.936018 -242.787168) (xy 344.987313 -242.779043) (xy 345.039247 -242.779043)
			(xy 345.090542 -242.787168) (xy 345.139935 -242.803216) (xy 345.186209 -242.826794) (xy 345.228225 -242.85732)
			(xy 345.264948 -242.894043) (xy 345.295474 -242.936059) (xy 345.319052 -242.982333) (xy 345.3351 -243.031726)
			(xy 345.343225 -243.083021) (xy 345.343734 -243.108988) (xy 345.343225 -243.134955) (xy 345.623389 -243.134955)
			(xy 345.623389 -243.083021) (xy 345.631514 -243.031726) (xy 345.647562 -242.982333) (xy 345.67114 -242.936059)
			(xy 345.701666 -242.894043) (xy 345.738389 -242.85732) (xy 345.780405 -242.826794) (xy 345.826679 -242.803216)
			(xy 345.876072 -242.787168) (xy 345.927367 -242.779043) (xy 345.979301 -242.779043) (xy 346.030596 -242.787168)
			(xy 346.079989 -242.803216) (xy 346.126263 -242.826794) (xy 346.168279 -242.85732) (xy 346.205002 -242.894043)
			(xy 346.235528 -242.936059) (xy 346.259106 -242.982333) (xy 346.275154 -243.031726) (xy 346.283279 -243.083021)
			(xy 346.283788 -243.108988) (xy 346.283279 -243.134955) (xy 346.562935 -243.134955) (xy 346.562935 -243.083021)
			(xy 346.57106 -243.031726) (xy 346.587108 -242.982333) (xy 346.610686 -242.936059) (xy 346.641212 -242.894043)
			(xy 346.677935 -242.85732) (xy 346.719951 -242.826794) (xy 346.766225 -242.803216) (xy 346.815618 -242.787168)
			(xy 346.866913 -242.779043) (xy 346.918847 -242.779043) (xy 346.970142 -242.787168) (xy 347.019535 -242.803216)
			(xy 347.065809 -242.826794) (xy 347.107825 -242.85732) (xy 347.144548 -242.894043) (xy 347.175074 -242.936059)
			(xy 347.198652 -242.982333) (xy 347.2147 -243.031726) (xy 347.222825 -243.083021) (xy 347.223334 -243.108988)
			(xy 347.222825 -243.134955) (xy 347.502735 -243.134955) (xy 347.502735 -243.083021) (xy 347.51086 -243.031726)
			(xy 347.526908 -242.982333) (xy 347.550486 -242.936059) (xy 347.581012 -242.894043) (xy 347.617735 -242.85732)
			(xy 347.659751 -242.826794) (xy 347.706025 -242.803216) (xy 347.755418 -242.787168) (xy 347.806713 -242.779043)
			(xy 347.858647 -242.779043) (xy 347.909942 -242.787168) (xy 347.959335 -242.803216) (xy 348.005609 -242.826794)
			(xy 348.047625 -242.85732) (xy 348.084348 -242.894043) (xy 348.114874 -242.936059) (xy 348.138452 -242.982333)
			(xy 348.1545 -243.031726) (xy 348.162625 -243.083021) (xy 348.163134 -243.108988) (xy 348.162625 -243.134955)
			(xy 348.442535 -243.134955) (xy 348.442535 -243.083021) (xy 348.45066 -243.031726) (xy 348.466708 -242.982333)
			(xy 348.490286 -242.936059) (xy 348.520812 -242.894043) (xy 348.557535 -242.85732) (xy 348.599551 -242.826794)
			(xy 348.645825 -242.803216) (xy 348.695218 -242.787168) (xy 348.746513 -242.779043) (xy 348.798447 -242.779043)
			(xy 348.849742 -242.787168) (xy 348.899135 -242.803216) (xy 348.945409 -242.826794) (xy 348.987425 -242.85732)
			(xy 349.024148 -242.894043) (xy 349.054674 -242.936059) (xy 349.078252 -242.982333) (xy 349.0943 -243.031726)
			(xy 349.102425 -243.083021) (xy 349.102934 -243.108988) (xy 349.102425 -243.134955) (xy 349.382335 -243.134955)
			(xy 349.382335 -243.083021) (xy 349.39046 -243.031726) (xy 349.406508 -242.982333) (xy 349.430086 -242.936059)
			(xy 349.460612 -242.894043) (xy 349.497335 -242.85732) (xy 349.539351 -242.826794) (xy 349.585625 -242.803216)
			(xy 349.635018 -242.787168) (xy 349.686313 -242.779043) (xy 349.738247 -242.779043) (xy 349.789542 -242.787168)
			(xy 349.838935 -242.803216) (xy 349.885209 -242.826794) (xy 349.927225 -242.85732) (xy 349.963948 -242.894043)
			(xy 349.994474 -242.936059) (xy 350.018052 -242.982333) (xy 350.026121 -243.007167) (xy 351.593655 -243.007167)
			(xy 351.593655 -242.955233) (xy 351.601779 -242.903937) (xy 351.617828 -242.854544) (xy 351.641406 -242.80827)
			(xy 351.671933 -242.766254) (xy 351.708657 -242.72953) (xy 351.750673 -242.699004) (xy 351.796948 -242.675427)
			(xy 351.846341 -242.659378) (xy 351.897637 -242.651254) (xy 351.923604 -242.650772) (xy 351.923858 -242.650772)
			(xy 351.948386 -242.651196) (xy 351.996899 -242.658467) (xy 352.043806 -242.672825) (xy 352.088078 -242.693956)
			(xy 352.128741 -242.721396) (xy 352.147124 -242.73764) (xy 352.158613 -242.747443) (xy 352.18585 -242.760457)
			(xy 352.215704 -242.764925) (xy 352.245558 -242.760457) (xy 352.272795 -242.747443) (xy 352.284284 -242.73764)
			(xy 352.302662 -242.721389) (xy 352.343321 -242.693943) (xy 352.387593 -242.672813) (xy 352.434505 -242.658466)
			(xy 352.483022 -242.651216) (xy 352.50755 -242.650772) (xy 352.507804 -242.650772) (xy 352.533773 -242.65123)
			(xy 352.585072 -242.659355) (xy 352.634468 -242.675405) (xy 352.680745 -242.698985) (xy 352.722763 -242.729514)
			(xy 352.759489 -242.76624) (xy 352.790017 -242.808259) (xy 352.813596 -242.854536) (xy 352.829646 -242.903932)
			(xy 352.837771 -242.955231) (xy 352.837771 -243.007167) (xy 353.066855 -243.007167) (xy 353.066855 -242.955233)
			(xy 353.074979 -242.903937) (xy 353.091028 -242.854544) (xy 353.114606 -242.80827) (xy 353.145133 -242.766254)
			(xy 353.181857 -242.72953) (xy 353.223873 -242.699004) (xy 353.270148 -242.675427) (xy 353.319541 -242.659378)
			(xy 353.370837 -242.651254) (xy 353.396804 -242.650772) (xy 353.424103 -242.651299) (xy 353.477957 -242.660282)
			(xy 353.529599 -242.678003) (xy 353.577623 -242.703979) (xy 353.620718 -242.737501) (xy 353.639628 -242.757198)
			(xy 353.649461 -242.767178) (xy 353.673345 -242.781804) (xy 353.700301 -242.789403) (xy 353.728307 -242.789403)
			(xy 353.755263 -242.781804) (xy 353.779147 -242.767178) (xy 353.78898 -242.757198) (xy 353.807892 -242.737505)
			(xy 353.850991 -242.703993) (xy 353.899015 -242.678027) (xy 353.950656 -242.660313) (xy 354.004507 -242.651334)
			(xy 354.031804 -242.650772) (xy 354.057773 -242.65123) (xy 354.109072 -242.659355) (xy 354.158468 -242.675405)
			(xy 354.204745 -242.698985) (xy 354.246763 -242.729514) (xy 354.283489 -242.76624) (xy 354.314017 -242.808259)
			(xy 354.337596 -242.854536) (xy 354.353646 -242.903932) (xy 354.361771 -242.955231) (xy 354.361771 -243.007167)
			(xy 354.971855 -243.007167) (xy 354.971855 -242.955233) (xy 354.979979 -242.903937) (xy 354.996028 -242.854544)
			(xy 355.019606 -242.80827) (xy 355.050133 -242.766254) (xy 355.086857 -242.72953) (xy 355.128873 -242.699004)
			(xy 355.175148 -242.675427) (xy 355.224541 -242.659378) (xy 355.275837 -242.651254) (xy 355.301804 -242.650772)
			(xy 355.329103 -242.651299) (xy 355.382957 -242.660282) (xy 355.434599 -242.678003) (xy 355.482623 -242.703979)
			(xy 355.525718 -242.737501) (xy 355.544628 -242.757198) (xy 355.554461 -242.767178) (xy 355.578345 -242.781804)
			(xy 355.605301 -242.789403) (xy 355.633307 -242.789403) (xy 355.660263 -242.781804) (xy 355.684147 -242.767178)
			(xy 355.69398 -242.757198) (xy 355.711125 -242.739253) (xy 355.749841 -242.708201) (xy 355.792768 -242.683293)
			(xy 355.838939 -242.66509) (xy 355.887314 -242.654001) (xy 355.936804 -242.650277) (xy 355.986294 -242.654001)
			(xy 356.034669 -242.66509) (xy 356.08084 -242.683293) (xy 356.123767 -242.708201) (xy 356.162483 -242.739253)
			(xy 356.179628 -242.757198) (xy 356.18896 -242.766761) (xy 356.211519 -242.781066) (xy 356.237018 -242.789024)
			(xy 356.263708 -242.79009) (xy 356.28976 -242.784192) (xy 356.313388 -242.771732) (xy 356.332972 -242.753566)
			(xy 356.34041 -242.742466) (xy 356.34847 -242.729894) (xy 356.366534 -242.70611) (xy 356.376478 -242.694968)
			(xy 356.386293 -242.683488) (xy 356.399305 -242.656248) (xy 356.403771 -242.626391) (xy 356.3993 -242.596535)
			(xy 356.386283 -242.569297) (xy 356.376478 -242.557808) (xy 356.360213 -242.539442) (xy 356.332771 -242.498779)
			(xy 356.311646 -242.454503) (xy 356.297301 -242.40759) (xy 356.290053 -242.359071) (xy 356.28961 -242.334542)
			(xy 356.28961 -242.334288) (xy 356.290119 -242.308321) (xy 356.298244 -242.257026) (xy 356.314292 -242.207633)
			(xy 356.33787 -242.161359) (xy 356.368396 -242.119343) (xy 356.405119 -242.08262) (xy 356.447135 -242.052094)
			(xy 356.493409 -242.028516) (xy 356.542802 -242.012468) (xy 356.594097 -242.004343) (xy 356.646031 -242.004343)
			(xy 356.697326 -242.012468) (xy 356.746719 -242.028516) (xy 356.792993 -242.052094) (xy 356.835009 -242.08262)
			(xy 356.871732 -242.119343) (xy 356.902258 -242.161359) (xy 356.925836 -242.207633) (xy 356.941884 -242.257026)
			(xy 356.950009 -242.308321) (xy 356.950255 -242.320885) (xy 357.370635 -242.320885) (xy 357.370635 -242.268951)
			(xy 357.37876 -242.217656) (xy 357.394808 -242.168263) (xy 357.418386 -242.121989) (xy 357.448912 -242.079973)
			(xy 357.485635 -242.04325) (xy 357.527651 -242.012724) (xy 357.573925 -241.989146) (xy 357.623318 -241.973098)
			(xy 357.674613 -241.964973) (xy 357.726547 -241.964973) (xy 357.777842 -241.973098) (xy 357.827235 -241.989146)
			(xy 357.873509 -242.012724) (xy 357.915525 -242.04325) (xy 357.952248 -242.079973) (xy 357.982774 -242.121989)
			(xy 358.006352 -242.168263) (xy 358.0224 -242.217656) (xy 358.030525 -242.268951) (xy 358.031034 -242.294918)
			(xy 358.030525 -242.320885) (xy 358.310689 -242.320885) (xy 358.310689 -242.268951) (xy 358.318814 -242.217656)
			(xy 358.334862 -242.168263) (xy 358.35844 -242.121989) (xy 358.388966 -242.079973) (xy 358.425689 -242.04325)
			(xy 358.467705 -242.012724) (xy 358.513979 -241.989146) (xy 358.563372 -241.973098) (xy 358.614667 -241.964973)
			(xy 358.666601 -241.964973) (xy 358.717896 -241.973098) (xy 358.767289 -241.989146) (xy 358.813563 -242.012724)
			(xy 358.855579 -242.04325) (xy 358.892302 -242.079973) (xy 358.922828 -242.121989) (xy 358.946406 -242.168263)
			(xy 358.962454 -242.217656) (xy 358.970579 -242.268951) (xy 358.971088 -242.294918) (xy 358.970579 -242.320885)
			(xy 359.250235 -242.320885) (xy 359.250235 -242.268951) (xy 359.25836 -242.217656) (xy 359.274408 -242.168263)
			(xy 359.297986 -242.121989) (xy 359.328512 -242.079973) (xy 359.365235 -242.04325) (xy 359.407251 -242.012724)
			(xy 359.453525 -241.989146) (xy 359.502918 -241.973098) (xy 359.554213 -241.964973) (xy 359.606147 -241.964973)
			(xy 359.657442 -241.973098) (xy 359.706835 -241.989146) (xy 359.753109 -242.012724) (xy 359.795125 -242.04325)
			(xy 359.831848 -242.079973) (xy 359.862374 -242.121989) (xy 359.885952 -242.168263) (xy 359.902 -242.217656)
			(xy 359.910125 -242.268951) (xy 359.910634 -242.294918) (xy 359.910125 -242.320885) (xy 360.190035 -242.320885)
			(xy 360.190035 -242.268951) (xy 360.19816 -242.217656) (xy 360.214208 -242.168263) (xy 360.237786 -242.121989)
			(xy 360.268312 -242.079973) (xy 360.305035 -242.04325) (xy 360.347051 -242.012724) (xy 360.393325 -241.989146)
			(xy 360.442718 -241.973098) (xy 360.494013 -241.964973) (xy 360.545947 -241.964973) (xy 360.597242 -241.973098)
			(xy 360.646635 -241.989146) (xy 360.692909 -242.012724) (xy 360.734925 -242.04325) (xy 360.771648 -242.079973)
			(xy 360.802174 -242.121989) (xy 360.825752 -242.168263) (xy 360.8418 -242.217656) (xy 360.849925 -242.268951)
			(xy 360.850434 -242.294918) (xy 360.849925 -242.320885) (xy 361.130089 -242.320885) (xy 361.130089 -242.268951)
			(xy 361.138214 -242.217656) (xy 361.154262 -242.168263) (xy 361.17784 -242.121989) (xy 361.208366 -242.079973)
			(xy 361.245089 -242.04325) (xy 361.287105 -242.012724) (xy 361.333379 -241.989146) (xy 361.382772 -241.973098)
			(xy 361.434067 -241.964973) (xy 361.486001 -241.964973) (xy 361.537296 -241.973098) (xy 361.586689 -241.989146)
			(xy 361.632963 -242.012724) (xy 361.674979 -242.04325) (xy 361.711702 -242.079973) (xy 361.742228 -242.121989)
			(xy 361.765806 -242.168263) (xy 361.781854 -242.217656) (xy 361.789979 -242.268951) (xy 361.790488 -242.294918)
			(xy 361.789979 -242.320885) (xy 362.069889 -242.320885) (xy 362.069889 -242.268951) (xy 362.078014 -242.217656)
			(xy 362.094062 -242.168263) (xy 362.11764 -242.121989) (xy 362.148166 -242.079973) (xy 362.184889 -242.04325)
			(xy 362.226905 -242.012724) (xy 362.273179 -241.989146) (xy 362.322572 -241.973098) (xy 362.373867 -241.964973)
			(xy 362.425801 -241.964973) (xy 362.477096 -241.973098) (xy 362.526489 -241.989146) (xy 362.572763 -242.012724)
			(xy 362.614779 -242.04325) (xy 362.651502 -242.079973) (xy 362.682028 -242.121989) (xy 362.705606 -242.168263)
			(xy 362.721654 -242.217656) (xy 362.729779 -242.268951) (xy 362.730288 -242.294918) (xy 362.729779 -242.320885)
			(xy 369.588289 -242.320885) (xy 369.588289 -242.268951) (xy 369.596414 -242.217656) (xy 369.612462 -242.168263)
			(xy 369.63604 -242.121989) (xy 369.666566 -242.079973) (xy 369.703289 -242.04325) (xy 369.745305 -242.012724)
			(xy 369.791579 -241.989146) (xy 369.840972 -241.973098) (xy 369.892267 -241.964973) (xy 369.944201 -241.964973)
			(xy 369.995496 -241.973098) (xy 370.044889 -241.989146) (xy 370.091163 -242.012724) (xy 370.133179 -242.04325)
			(xy 370.169902 -242.079973) (xy 370.200428 -242.121989) (xy 370.224006 -242.168263) (xy 370.240054 -242.217656)
			(xy 370.248179 -242.268951) (xy 370.248688 -242.294918) (xy 370.248179 -242.320885) (xy 370.528089 -242.320885)
			(xy 370.528089 -242.268951) (xy 370.536214 -242.217656) (xy 370.552262 -242.168263) (xy 370.57584 -242.121989)
			(xy 370.606366 -242.079973) (xy 370.643089 -242.04325) (xy 370.685105 -242.012724) (xy 370.731379 -241.989146)
			(xy 370.780772 -241.973098) (xy 370.832067 -241.964973) (xy 370.884001 -241.964973) (xy 370.935296 -241.973098)
			(xy 370.984689 -241.989146) (xy 371.030963 -242.012724) (xy 371.072979 -242.04325) (xy 371.109702 -242.079973)
			(xy 371.140228 -242.121989) (xy 371.163806 -242.168263) (xy 371.179854 -242.217656) (xy 371.187979 -242.268951)
			(xy 371.188488 -242.294918) (xy 371.187979 -242.320885) (xy 371.467889 -242.320885) (xy 371.467889 -242.268951)
			(xy 371.476014 -242.217656) (xy 371.492062 -242.168263) (xy 371.51564 -242.121989) (xy 371.546166 -242.079973)
			(xy 371.582889 -242.04325) (xy 371.624905 -242.012724) (xy 371.671179 -241.989146) (xy 371.720572 -241.973098)
			(xy 371.771867 -241.964973) (xy 371.823801 -241.964973) (xy 371.875096 -241.973098) (xy 371.924489 -241.989146)
			(xy 371.970763 -242.012724) (xy 372.012779 -242.04325) (xy 372.049502 -242.079973) (xy 372.080028 -242.121989)
			(xy 372.103606 -242.168263) (xy 372.119654 -242.217656) (xy 372.127779 -242.268951) (xy 372.128288 -242.294918)
			(xy 372.127779 -242.320885) (xy 372.407689 -242.320885) (xy 372.407689 -242.268951) (xy 372.415814 -242.217656)
			(xy 372.431862 -242.168263) (xy 372.45544 -242.121989) (xy 372.485966 -242.079973) (xy 372.522689 -242.04325)
			(xy 372.564705 -242.012724) (xy 372.610979 -241.989146) (xy 372.660372 -241.973098) (xy 372.711667 -241.964973)
			(xy 372.763601 -241.964973) (xy 372.814896 -241.973098) (xy 372.864289 -241.989146) (xy 372.910563 -242.012724)
			(xy 372.952579 -242.04325) (xy 372.989302 -242.079973) (xy 373.019828 -242.121989) (xy 373.043406 -242.168263)
			(xy 373.059454 -242.217656) (xy 373.067579 -242.268951) (xy 373.068088 -242.294918) (xy 373.067579 -242.320885)
			(xy 373.347489 -242.320885) (xy 373.347489 -242.268951) (xy 373.355614 -242.217656) (xy 373.371662 -242.168263)
			(xy 373.39524 -242.121989) (xy 373.425766 -242.079973) (xy 373.462489 -242.04325) (xy 373.504505 -242.012724)
			(xy 373.550779 -241.989146) (xy 373.600172 -241.973098) (xy 373.651467 -241.964973) (xy 373.703401 -241.964973)
			(xy 373.754696 -241.973098) (xy 373.804089 -241.989146) (xy 373.850363 -242.012724) (xy 373.892379 -242.04325)
			(xy 373.929102 -242.079973) (xy 373.959628 -242.121989) (xy 373.983206 -242.168263) (xy 373.999254 -242.217656)
			(xy 374.007379 -242.268951) (xy 374.007888 -242.294918) (xy 374.007379 -242.320885) (xy 374.287289 -242.320885)
			(xy 374.287289 -242.268951) (xy 374.295414 -242.217656) (xy 374.311462 -242.168263) (xy 374.33504 -242.121989)
			(xy 374.365566 -242.079973) (xy 374.402289 -242.04325) (xy 374.444305 -242.012724) (xy 374.490579 -241.989146)
			(xy 374.539972 -241.973098) (xy 374.591267 -241.964973) (xy 374.643201 -241.964973) (xy 374.694496 -241.973098)
			(xy 374.743889 -241.989146) (xy 374.790163 -242.012724) (xy 374.832179 -242.04325) (xy 374.868902 -242.079973)
			(xy 374.899428 -242.121989) (xy 374.923006 -242.168263) (xy 374.939054 -242.217656) (xy 374.947179 -242.268951)
			(xy 374.947688 -242.294918) (xy 374.947179 -242.320885) (xy 375.227089 -242.320885) (xy 375.227089 -242.268951)
			(xy 375.235214 -242.217656) (xy 375.251262 -242.168263) (xy 375.27484 -242.121989) (xy 375.305366 -242.079973)
			(xy 375.342089 -242.04325) (xy 375.384105 -242.012724) (xy 375.430379 -241.989146) (xy 375.479772 -241.973098)
			(xy 375.531067 -241.964973) (xy 375.583001 -241.964973) (xy 375.634296 -241.973098) (xy 375.683689 -241.989146)
			(xy 375.729963 -242.012724) (xy 375.771979 -242.04325) (xy 375.808702 -242.079973) (xy 375.839228 -242.121989)
			(xy 375.862806 -242.168263) (xy 375.878854 -242.217656) (xy 375.886979 -242.268951) (xy 375.887488 -242.294918)
			(xy 375.886979 -242.320885) (xy 376.166889 -242.320885) (xy 376.166889 -242.268951) (xy 376.175014 -242.217656)
			(xy 376.191062 -242.168263) (xy 376.21464 -242.121989) (xy 376.245166 -242.079973) (xy 376.281889 -242.04325)
			(xy 376.323905 -242.012724) (xy 376.370179 -241.989146) (xy 376.419572 -241.973098) (xy 376.470867 -241.964973)
			(xy 376.522801 -241.964973) (xy 376.574096 -241.973098) (xy 376.623489 -241.989146) (xy 376.669763 -242.012724)
			(xy 376.711779 -242.04325) (xy 376.748502 -242.079973) (xy 376.779028 -242.121989) (xy 376.802606 -242.168263)
			(xy 376.818654 -242.217656) (xy 376.826779 -242.268951) (xy 376.827288 -242.294918) (xy 376.826779 -242.320885)
			(xy 377.106689 -242.320885) (xy 377.106689 -242.268951) (xy 377.114814 -242.217656) (xy 377.130862 -242.168263)
			(xy 377.15444 -242.121989) (xy 377.184966 -242.079973) (xy 377.221689 -242.04325) (xy 377.263705 -242.012724)
			(xy 377.309979 -241.989146) (xy 377.359372 -241.973098) (xy 377.410667 -241.964973) (xy 377.462601 -241.964973)
			(xy 377.513896 -241.973098) (xy 377.563289 -241.989146) (xy 377.609563 -242.012724) (xy 377.651579 -242.04325)
			(xy 377.688302 -242.079973) (xy 377.718828 -242.121989) (xy 377.742406 -242.168263) (xy 377.758454 -242.217656)
			(xy 377.766579 -242.268951) (xy 377.767088 -242.294918) (xy 377.766579 -242.320885) (xy 378.046489 -242.320885)
			(xy 378.046489 -242.268951) (xy 378.054614 -242.217656) (xy 378.070662 -242.168263) (xy 378.09424 -242.121989)
			(xy 378.124766 -242.079973) (xy 378.161489 -242.04325) (xy 378.203505 -242.012724) (xy 378.249779 -241.989146)
			(xy 378.299172 -241.973098) (xy 378.350467 -241.964973) (xy 378.402401 -241.964973) (xy 378.453696 -241.973098)
			(xy 378.503089 -241.989146) (xy 378.549363 -242.012724) (xy 378.591379 -242.04325) (xy 378.628102 -242.079973)
			(xy 378.658628 -242.121989) (xy 378.682206 -242.168263) (xy 378.698254 -242.217656) (xy 378.706379 -242.268951)
			(xy 378.706888 -242.294918) (xy 378.706379 -242.320885) (xy 378.986289 -242.320885) (xy 378.986289 -242.268951)
			(xy 378.994414 -242.217656) (xy 379.010462 -242.168263) (xy 379.03404 -242.121989) (xy 379.064566 -242.079973)
			(xy 379.101289 -242.04325) (xy 379.143305 -242.012724) (xy 379.189579 -241.989146) (xy 379.238972 -241.973098)
			(xy 379.290267 -241.964973) (xy 379.342201 -241.964973) (xy 379.393496 -241.973098) (xy 379.442889 -241.989146)
			(xy 379.489163 -242.012724) (xy 379.531179 -242.04325) (xy 379.567902 -242.079973) (xy 379.598428 -242.121989)
			(xy 379.622006 -242.168263) (xy 379.638054 -242.217656) (xy 379.646179 -242.268951) (xy 379.646688 -242.294918)
			(xy 379.646179 -242.320885) (xy 379.638054 -242.37218) (xy 379.622006 -242.421573) (xy 379.598428 -242.467847)
			(xy 379.567902 -242.509863) (xy 379.531179 -242.546586) (xy 379.489163 -242.577112) (xy 379.442889 -242.60069)
			(xy 379.393496 -242.616738) (xy 379.342201 -242.624863) (xy 379.290267 -242.624863) (xy 379.238972 -242.616738)
			(xy 379.189579 -242.60069) (xy 379.143305 -242.577112) (xy 379.101289 -242.546586) (xy 379.064566 -242.509863)
			(xy 379.03404 -242.467847) (xy 379.010462 -242.421573) (xy 378.994414 -242.37218) (xy 378.986289 -242.320885)
			(xy 378.706379 -242.320885) (xy 378.698254 -242.37218) (xy 378.682206 -242.421573) (xy 378.658628 -242.467847)
			(xy 378.628102 -242.509863) (xy 378.591379 -242.546586) (xy 378.549363 -242.577112) (xy 378.503089 -242.60069)
			(xy 378.453696 -242.616738) (xy 378.402401 -242.624863) (xy 378.350467 -242.624863) (xy 378.299172 -242.616738)
			(xy 378.249779 -242.60069) (xy 378.203505 -242.577112) (xy 378.161489 -242.546586) (xy 378.124766 -242.509863)
			(xy 378.09424 -242.467847) (xy 378.070662 -242.421573) (xy 378.054614 -242.37218) (xy 378.046489 -242.320885)
			(xy 377.766579 -242.320885) (xy 377.758454 -242.37218) (xy 377.742406 -242.421573) (xy 377.718828 -242.467847)
			(xy 377.688302 -242.509863) (xy 377.651579 -242.546586) (xy 377.609563 -242.577112) (xy 377.563289 -242.60069)
			(xy 377.513896 -242.616738) (xy 377.462601 -242.624863) (xy 377.410667 -242.624863) (xy 377.359372 -242.616738)
			(xy 377.309979 -242.60069) (xy 377.263705 -242.577112) (xy 377.221689 -242.546586) (xy 377.184966 -242.509863)
			(xy 377.15444 -242.467847) (xy 377.130862 -242.421573) (xy 377.114814 -242.37218) (xy 377.106689 -242.320885)
			(xy 376.826779 -242.320885) (xy 376.818654 -242.37218) (xy 376.802606 -242.421573) (xy 376.779028 -242.467847)
			(xy 376.748502 -242.509863) (xy 376.711779 -242.546586) (xy 376.669763 -242.577112) (xy 376.623489 -242.60069)
			(xy 376.574096 -242.616738) (xy 376.522801 -242.624863) (xy 376.470867 -242.624863) (xy 376.419572 -242.616738)
			(xy 376.370179 -242.60069) (xy 376.323905 -242.577112) (xy 376.281889 -242.546586) (xy 376.245166 -242.509863)
			(xy 376.21464 -242.467847) (xy 376.191062 -242.421573) (xy 376.175014 -242.37218) (xy 376.166889 -242.320885)
			(xy 375.886979 -242.320885) (xy 375.878854 -242.37218) (xy 375.862806 -242.421573) (xy 375.839228 -242.467847)
			(xy 375.808702 -242.509863) (xy 375.771979 -242.546586) (xy 375.729963 -242.577112) (xy 375.683689 -242.60069)
			(xy 375.634296 -242.616738) (xy 375.583001 -242.624863) (xy 375.531067 -242.624863) (xy 375.479772 -242.616738)
			(xy 375.430379 -242.60069) (xy 375.384105 -242.577112) (xy 375.342089 -242.546586) (xy 375.305366 -242.509863)
			(xy 375.27484 -242.467847) (xy 375.251262 -242.421573) (xy 375.235214 -242.37218) (xy 375.227089 -242.320885)
			(xy 374.947179 -242.320885) (xy 374.939054 -242.37218) (xy 374.923006 -242.421573) (xy 374.899428 -242.467847)
			(xy 374.868902 -242.509863) (xy 374.832179 -242.546586) (xy 374.790163 -242.577112) (xy 374.743889 -242.60069)
			(xy 374.694496 -242.616738) (xy 374.643201 -242.624863) (xy 374.591267 -242.624863) (xy 374.539972 -242.616738)
			(xy 374.490579 -242.60069) (xy 374.444305 -242.577112) (xy 374.402289 -242.546586) (xy 374.365566 -242.509863)
			(xy 374.33504 -242.467847) (xy 374.311462 -242.421573) (xy 374.295414 -242.37218) (xy 374.287289 -242.320885)
			(xy 374.007379 -242.320885) (xy 373.999254 -242.37218) (xy 373.983206 -242.421573) (xy 373.959628 -242.467847)
			(xy 373.929102 -242.509863) (xy 373.892379 -242.546586) (xy 373.850363 -242.577112) (xy 373.804089 -242.60069)
			(xy 373.754696 -242.616738) (xy 373.703401 -242.624863) (xy 373.651467 -242.624863) (xy 373.600172 -242.616738)
			(xy 373.550779 -242.60069) (xy 373.504505 -242.577112) (xy 373.462489 -242.546586) (xy 373.425766 -242.509863)
			(xy 373.39524 -242.467847) (xy 373.371662 -242.421573) (xy 373.355614 -242.37218) (xy 373.347489 -242.320885)
			(xy 373.067579 -242.320885) (xy 373.059454 -242.37218) (xy 373.043406 -242.421573) (xy 373.019828 -242.467847)
			(xy 372.989302 -242.509863) (xy 372.952579 -242.546586) (xy 372.910563 -242.577112) (xy 372.864289 -242.60069)
			(xy 372.814896 -242.616738) (xy 372.763601 -242.624863) (xy 372.711667 -242.624863) (xy 372.660372 -242.616738)
			(xy 372.610979 -242.60069) (xy 372.564705 -242.577112) (xy 372.522689 -242.546586) (xy 372.485966 -242.509863)
			(xy 372.45544 -242.467847) (xy 372.431862 -242.421573) (xy 372.415814 -242.37218) (xy 372.407689 -242.320885)
			(xy 372.127779 -242.320885) (xy 372.119654 -242.37218) (xy 372.103606 -242.421573) (xy 372.080028 -242.467847)
			(xy 372.049502 -242.509863) (xy 372.012779 -242.546586) (xy 371.970763 -242.577112) (xy 371.924489 -242.60069)
			(xy 371.875096 -242.616738) (xy 371.823801 -242.624863) (xy 371.771867 -242.624863) (xy 371.720572 -242.616738)
			(xy 371.671179 -242.60069) (xy 371.624905 -242.577112) (xy 371.582889 -242.546586) (xy 371.546166 -242.509863)
			(xy 371.51564 -242.467847) (xy 371.492062 -242.421573) (xy 371.476014 -242.37218) (xy 371.467889 -242.320885)
			(xy 371.187979 -242.320885) (xy 371.179854 -242.37218) (xy 371.163806 -242.421573) (xy 371.140228 -242.467847)
			(xy 371.109702 -242.509863) (xy 371.072979 -242.546586) (xy 371.030963 -242.577112) (xy 370.984689 -242.60069)
			(xy 370.935296 -242.616738) (xy 370.884001 -242.624863) (xy 370.832067 -242.624863) (xy 370.780772 -242.616738)
			(xy 370.731379 -242.60069) (xy 370.685105 -242.577112) (xy 370.643089 -242.546586) (xy 370.606366 -242.509863)
			(xy 370.57584 -242.467847) (xy 370.552262 -242.421573) (xy 370.536214 -242.37218) (xy 370.528089 -242.320885)
			(xy 370.248179 -242.320885) (xy 370.240054 -242.37218) (xy 370.224006 -242.421573) (xy 370.200428 -242.467847)
			(xy 370.169902 -242.509863) (xy 370.133179 -242.546586) (xy 370.091163 -242.577112) (xy 370.044889 -242.60069)
			(xy 369.995496 -242.616738) (xy 369.944201 -242.624863) (xy 369.892267 -242.624863) (xy 369.840972 -242.616738)
			(xy 369.791579 -242.60069) (xy 369.745305 -242.577112) (xy 369.703289 -242.546586) (xy 369.666566 -242.509863)
			(xy 369.63604 -242.467847) (xy 369.612462 -242.421573) (xy 369.596414 -242.37218) (xy 369.588289 -242.320885)
			(xy 362.729779 -242.320885) (xy 362.721654 -242.37218) (xy 362.705606 -242.421573) (xy 362.682028 -242.467847)
			(xy 362.651502 -242.509863) (xy 362.614779 -242.546586) (xy 362.572763 -242.577112) (xy 362.526489 -242.60069)
			(xy 362.477096 -242.616738) (xy 362.425801 -242.624863) (xy 362.373867 -242.624863) (xy 362.322572 -242.616738)
			(xy 362.273179 -242.60069) (xy 362.226905 -242.577112) (xy 362.184889 -242.546586) (xy 362.148166 -242.509863)
			(xy 362.11764 -242.467847) (xy 362.094062 -242.421573) (xy 362.078014 -242.37218) (xy 362.069889 -242.320885)
			(xy 361.789979 -242.320885) (xy 361.781854 -242.37218) (xy 361.765806 -242.421573) (xy 361.742228 -242.467847)
			(xy 361.711702 -242.509863) (xy 361.674979 -242.546586) (xy 361.632963 -242.577112) (xy 361.586689 -242.60069)
			(xy 361.537296 -242.616738) (xy 361.486001 -242.624863) (xy 361.434067 -242.624863) (xy 361.382772 -242.616738)
			(xy 361.333379 -242.60069) (xy 361.287105 -242.577112) (xy 361.245089 -242.546586) (xy 361.208366 -242.509863)
			(xy 361.17784 -242.467847) (xy 361.154262 -242.421573) (xy 361.138214 -242.37218) (xy 361.130089 -242.320885)
			(xy 360.849925 -242.320885) (xy 360.8418 -242.37218) (xy 360.825752 -242.421573) (xy 360.802174 -242.467847)
			(xy 360.771648 -242.509863) (xy 360.734925 -242.546586) (xy 360.692909 -242.577112) (xy 360.646635 -242.60069)
			(xy 360.597242 -242.616738) (xy 360.545947 -242.624863) (xy 360.494013 -242.624863) (xy 360.442718 -242.616738)
			(xy 360.393325 -242.60069) (xy 360.347051 -242.577112) (xy 360.305035 -242.546586) (xy 360.268312 -242.509863)
			(xy 360.237786 -242.467847) (xy 360.214208 -242.421573) (xy 360.19816 -242.37218) (xy 360.190035 -242.320885)
			(xy 359.910125 -242.320885) (xy 359.902 -242.37218) (xy 359.885952 -242.421573) (xy 359.862374 -242.467847)
			(xy 359.831848 -242.509863) (xy 359.795125 -242.546586) (xy 359.753109 -242.577112) (xy 359.706835 -242.60069)
			(xy 359.657442 -242.616738) (xy 359.606147 -242.624863) (xy 359.554213 -242.624863) (xy 359.502918 -242.616738)
			(xy 359.453525 -242.60069) (xy 359.407251 -242.577112) (xy 359.365235 -242.546586) (xy 359.328512 -242.509863)
			(xy 359.297986 -242.467847) (xy 359.274408 -242.421573) (xy 359.25836 -242.37218) (xy 359.250235 -242.320885)
			(xy 358.970579 -242.320885) (xy 358.962454 -242.37218) (xy 358.946406 -242.421573) (xy 358.922828 -242.467847)
			(xy 358.892302 -242.509863) (xy 358.855579 -242.546586) (xy 358.813563 -242.577112) (xy 358.767289 -242.60069)
			(xy 358.717896 -242.616738) (xy 358.666601 -242.624863) (xy 358.614667 -242.624863) (xy 358.563372 -242.616738)
			(xy 358.513979 -242.60069) (xy 358.467705 -242.577112) (xy 358.425689 -242.546586) (xy 358.388966 -242.509863)
			(xy 358.35844 -242.467847) (xy 358.334862 -242.421573) (xy 358.318814 -242.37218) (xy 358.310689 -242.320885)
			(xy 358.030525 -242.320885) (xy 358.0224 -242.37218) (xy 358.006352 -242.421573) (xy 357.982774 -242.467847)
			(xy 357.952248 -242.509863) (xy 357.915525 -242.546586) (xy 357.873509 -242.577112) (xy 357.827235 -242.60069)
			(xy 357.777842 -242.616738) (xy 357.726547 -242.624863) (xy 357.674613 -242.624863) (xy 357.623318 -242.616738)
			(xy 357.573925 -242.60069) (xy 357.527651 -242.577112) (xy 357.485635 -242.546586) (xy 357.448912 -242.509863)
			(xy 357.418386 -242.467847) (xy 357.394808 -242.421573) (xy 357.37876 -242.37218) (xy 357.370635 -242.320885)
			(xy 356.950255 -242.320885) (xy 356.950518 -242.334288) (xy 356.950518 -242.334542) (xy 356.950087 -242.359069)
			(xy 356.942818 -242.407583) (xy 356.928462 -242.45449) (xy 356.907332 -242.498761) (xy 356.879894 -242.539425)
			(xy 356.86365 -242.557808) (xy 356.853856 -242.569305) (xy 356.840838 -242.596539) (xy 356.836366 -242.626391)
			(xy 356.840833 -242.656244) (xy 356.853846 -242.68348) (xy 356.86365 -242.694968) (xy 356.880465 -242.714063)
			(xy 356.908664 -242.756412) (xy 356.919784 -242.779296) (xy 356.926126 -242.791973) (xy 356.94462 -242.813442)
			(xy 356.968301 -242.829003) (xy 356.995347 -242.837457) (xy 357.023674 -242.838155) (xy 357.051103 -242.831041)
			(xy 357.063548 -242.824254) (xy 357.089091 -242.809917) (xy 357.144004 -242.789545) (xy 357.201649 -242.779181)
			(xy 357.230934 -242.778534) (xy 357.256899 -242.77907) (xy 357.308188 -242.787198) (xy 357.357574 -242.803249)
			(xy 357.403841 -242.826828) (xy 357.445851 -242.857354) (xy 357.482569 -242.894075) (xy 357.51309 -242.936088)
			(xy 357.536664 -242.982358) (xy 357.55271 -243.031746) (xy 357.560833 -243.083035) (xy 357.560833 -243.134955)
			(xy 357.840789 -243.134955) (xy 357.840789 -243.083021) (xy 357.848914 -243.031726) (xy 357.864962 -242.982333)
			(xy 357.88854 -242.936059) (xy 357.919066 -242.894043) (xy 357.955789 -242.85732) (xy 357.997805 -242.826794)
			(xy 358.044079 -242.803216) (xy 358.093472 -242.787168) (xy 358.144767 -242.779043) (xy 358.196701 -242.779043)
			(xy 358.247996 -242.787168) (xy 358.297389 -242.803216) (xy 358.343663 -242.826794) (xy 358.385679 -242.85732)
			(xy 358.422402 -242.894043) (xy 358.452928 -242.936059) (xy 358.476506 -242.982333) (xy 358.492554 -243.031726)
			(xy 358.500679 -243.083021) (xy 358.501188 -243.108988) (xy 358.500679 -243.134955) (xy 358.780589 -243.134955)
			(xy 358.780589 -243.083021) (xy 358.788714 -243.031726) (xy 358.804762 -242.982333) (xy 358.82834 -242.936059)
			(xy 358.858866 -242.894043) (xy 358.895589 -242.85732) (xy 358.937605 -242.826794) (xy 358.983879 -242.803216)
			(xy 359.033272 -242.787168) (xy 359.084567 -242.779043) (xy 359.136501 -242.779043) (xy 359.187796 -242.787168)
			(xy 359.237189 -242.803216) (xy 359.283463 -242.826794) (xy 359.325479 -242.85732) (xy 359.362202 -242.894043)
			(xy 359.392728 -242.936059) (xy 359.416306 -242.982333) (xy 359.432354 -243.031726) (xy 359.440479 -243.083021)
			(xy 359.440988 -243.108988) (xy 359.440479 -243.134955) (xy 359.720389 -243.134955) (xy 359.720389 -243.083021)
			(xy 359.728514 -243.031726) (xy 359.744562 -242.982333) (xy 359.76814 -242.936059) (xy 359.798666 -242.894043)
			(xy 359.835389 -242.85732) (xy 359.877405 -242.826794) (xy 359.923679 -242.803216) (xy 359.973072 -242.787168)
			(xy 360.024367 -242.779043) (xy 360.076301 -242.779043) (xy 360.127596 -242.787168) (xy 360.176989 -242.803216)
			(xy 360.223263 -242.826794) (xy 360.265279 -242.85732) (xy 360.302002 -242.894043) (xy 360.332528 -242.936059)
			(xy 360.356106 -242.982333) (xy 360.372154 -243.031726) (xy 360.380279 -243.083021) (xy 360.380788 -243.108988)
			(xy 360.380279 -243.134955) (xy 360.659935 -243.134955) (xy 360.659935 -243.083021) (xy 360.66806 -243.031726)
			(xy 360.684108 -242.982333) (xy 360.707686 -242.936059) (xy 360.738212 -242.894043) (xy 360.774935 -242.85732)
			(xy 360.816951 -242.826794) (xy 360.863225 -242.803216) (xy 360.912618 -242.787168) (xy 360.963913 -242.779043)
			(xy 361.015847 -242.779043) (xy 361.067142 -242.787168) (xy 361.116535 -242.803216) (xy 361.162809 -242.826794)
			(xy 361.204825 -242.85732) (xy 361.241548 -242.894043) (xy 361.272074 -242.936059) (xy 361.295652 -242.982333)
			(xy 361.3117 -243.031726) (xy 361.319825 -243.083021) (xy 361.320334 -243.108988) (xy 361.319825 -243.134955)
			(xy 361.599989 -243.134955) (xy 361.599989 -243.083021) (xy 361.608114 -243.031726) (xy 361.624162 -242.982333)
			(xy 361.64774 -242.936059) (xy 361.678266 -242.894043) (xy 361.714989 -242.85732) (xy 361.757005 -242.826794)
			(xy 361.803279 -242.803216) (xy 361.852672 -242.787168) (xy 361.903967 -242.779043) (xy 361.955901 -242.779043)
			(xy 362.007196 -242.787168) (xy 362.056589 -242.803216) (xy 362.102863 -242.826794) (xy 362.144879 -242.85732)
			(xy 362.181602 -242.894043) (xy 362.212128 -242.936059) (xy 362.235706 -242.982333) (xy 362.251754 -243.031726)
			(xy 362.259879 -243.083021) (xy 362.260388 -243.108988) (xy 362.259879 -243.134955) (xy 362.251754 -243.18625)
			(xy 362.235706 -243.235643) (xy 362.212128 -243.281917) (xy 362.181602 -243.323933) (xy 362.144879 -243.360656)
			(xy 362.102863 -243.391182) (xy 362.056589 -243.41476) (xy 362.007196 -243.430808) (xy 361.955901 -243.438933)
			(xy 361.903967 -243.438933) (xy 361.852672 -243.430808) (xy 361.803279 -243.41476) (xy 361.757005 -243.391182)
			(xy 361.714989 -243.360656) (xy 361.678266 -243.323933) (xy 361.64774 -243.281917) (xy 361.624162 -243.235643)
			(xy 361.608114 -243.18625) (xy 361.599989 -243.134955) (xy 361.319825 -243.134955) (xy 361.3117 -243.18625)
			(xy 361.295652 -243.235643) (xy 361.272074 -243.281917) (xy 361.241548 -243.323933) (xy 361.204825 -243.360656)
			(xy 361.162809 -243.391182) (xy 361.116535 -243.41476) (xy 361.067142 -243.430808) (xy 361.015847 -243.438933)
			(xy 360.963913 -243.438933) (xy 360.912618 -243.430808) (xy 360.863225 -243.41476) (xy 360.816951 -243.391182)
			(xy 360.774935 -243.360656) (xy 360.738212 -243.323933) (xy 360.707686 -243.281917) (xy 360.684108 -243.235643)
			(xy 360.66806 -243.18625) (xy 360.659935 -243.134955) (xy 360.380279 -243.134955) (xy 360.372154 -243.18625)
			(xy 360.356106 -243.235643) (xy 360.332528 -243.281917) (xy 360.302002 -243.323933) (xy 360.265279 -243.360656)
			(xy 360.223263 -243.391182) (xy 360.176989 -243.41476) (xy 360.127596 -243.430808) (xy 360.076301 -243.438933)
			(xy 360.024367 -243.438933) (xy 359.973072 -243.430808) (xy 359.923679 -243.41476) (xy 359.877405 -243.391182)
			(xy 359.835389 -243.360656) (xy 359.798666 -243.323933) (xy 359.76814 -243.281917) (xy 359.744562 -243.235643)
			(xy 359.728514 -243.18625) (xy 359.720389 -243.134955) (xy 359.440479 -243.134955) (xy 359.432354 -243.18625)
			(xy 359.416306 -243.235643) (xy 359.392728 -243.281917) (xy 359.362202 -243.323933) (xy 359.325479 -243.360656)
			(xy 359.283463 -243.391182) (xy 359.237189 -243.41476) (xy 359.187796 -243.430808) (xy 359.136501 -243.438933)
			(xy 359.084567 -243.438933) (xy 359.033272 -243.430808) (xy 358.983879 -243.41476) (xy 358.937605 -243.391182)
			(xy 358.895589 -243.360656) (xy 358.858866 -243.323933) (xy 358.82834 -243.281917) (xy 358.804762 -243.235643)
			(xy 358.788714 -243.18625) (xy 358.780589 -243.134955) (xy 358.500679 -243.134955) (xy 358.492554 -243.18625)
			(xy 358.476506 -243.235643) (xy 358.452928 -243.281917) (xy 358.422402 -243.323933) (xy 358.385679 -243.360656)
			(xy 358.343663 -243.391182) (xy 358.297389 -243.41476) (xy 358.247996 -243.430808) (xy 358.196701 -243.438933)
			(xy 358.144767 -243.438933) (xy 358.093472 -243.430808) (xy 358.044079 -243.41476) (xy 357.997805 -243.391182)
			(xy 357.955789 -243.360656) (xy 357.919066 -243.323933) (xy 357.88854 -243.281917) (xy 357.864962 -243.235643)
			(xy 357.848914 -243.18625) (xy 357.840789 -243.134955) (xy 357.560833 -243.134955) (xy 357.560833 -243.134965)
			(xy 357.55271 -243.186254) (xy 357.536664 -243.235642) (xy 357.51309 -243.281912) (xy 357.482569 -243.323925)
			(xy 357.445851 -243.360646) (xy 357.403841 -243.391172) (xy 357.357574 -243.414751) (xy 357.308188 -243.430802)
			(xy 357.256899 -243.43893) (xy 357.230934 -243.439442) (xy 357.204103 -243.438908) (xy 357.151145 -243.430242)
			(xy 357.100283 -243.413132) (xy 357.052855 -243.388029) (xy 357.010106 -243.355591) (xy 356.973161 -243.316672)
			(xy 356.94299 -243.272294) (xy 356.931214 -243.24818) (xy 356.924851 -243.235512) (xy 356.906368 -243.214034)
			(xy 356.882692 -243.198466) (xy 356.855648 -243.190008) (xy 356.82732 -243.189311) (xy 356.799893 -243.196431)
			(xy 356.78745 -243.203222) (xy 356.761906 -243.217557) (xy 356.706994 -243.237931) (xy 356.649349 -243.248295)
			(xy 356.620064 -243.248942) (xy 356.592767 -243.248365) (xy 356.538916 -243.239394) (xy 356.487274 -243.221684)
			(xy 356.43925 -243.19572) (xy 356.396152 -243.162207) (xy 356.37724 -243.142516) (xy 356.367943 -243.132915)
			(xy 356.345376 -243.11861) (xy 356.319868 -243.110654) (xy 356.29317 -243.109592) (xy 356.267111 -243.115498)
			(xy 356.24348 -243.127966) (xy 356.223895 -243.146142) (xy 356.216458 -243.157248) (xy 356.201148 -243.180463)
			(xy 356.164076 -243.221907) (xy 356.120589 -243.256559) (xy 356.071915 -243.283443) (xy 356.019427 -243.301798)
			(xy 355.964606 -243.311107) (xy 355.936804 -243.31168) (xy 355.909506 -243.311131) (xy 355.855654 -243.302151)
			(xy 355.804013 -243.284434) (xy 355.755989 -243.258464) (xy 355.712892 -243.224947) (xy 355.69398 -243.205254)
			(xy 355.684147 -243.195274) (xy 355.660263 -243.180648) (xy 355.633307 -243.173049) (xy 355.605301 -243.173049)
			(xy 355.578345 -243.180648) (xy 355.554461 -243.195274) (xy 355.544628 -243.205254) (xy 355.525722 -243.224953)
			(xy 355.482621 -243.258461) (xy 355.434595 -243.284426) (xy 355.382953 -243.302139) (xy 355.329101 -243.311118)
			(xy 355.301804 -243.31168) (xy 355.275837 -243.311146) (xy 355.224541 -243.303022) (xy 355.175148 -243.286973)
			(xy 355.128873 -243.263396) (xy 355.086857 -243.23287) (xy 355.050133 -243.196146) (xy 355.019606 -243.15413)
			(xy 354.996028 -243.107856) (xy 354.979979 -243.058463) (xy 354.971855 -243.007167) (xy 354.361771 -243.007167)
			(xy 354.361771 -243.007169) (xy 354.353646 -243.058468) (xy 354.337596 -243.107864) (xy 354.314017 -243.154141)
			(xy 354.283489 -243.19616) (xy 354.246763 -243.232886) (xy 354.204745 -243.263415) (xy 354.158468 -243.286995)
			(xy 354.109072 -243.303045) (xy 354.057773 -243.31117) (xy 354.031804 -243.31168) (xy 354.004506 -243.311131)
			(xy 353.950654 -243.302151) (xy 353.899013 -243.284434) (xy 353.850989 -243.258464) (xy 353.807892 -243.224947)
			(xy 353.78898 -243.205254) (xy 353.779147 -243.195274) (xy 353.755263 -243.180648) (xy 353.728307 -243.173049)
			(xy 353.700301 -243.173049) (xy 353.673345 -243.180648) (xy 353.649461 -243.195274) (xy 353.639628 -243.205254)
			(xy 353.620722 -243.224953) (xy 353.577621 -243.258461) (xy 353.529595 -243.284426) (xy 353.477953 -243.302139)
			(xy 353.424101 -243.311118) (xy 353.396804 -243.31168) (xy 353.370837 -243.311146) (xy 353.319541 -243.303022)
			(xy 353.270148 -243.286973) (xy 353.223873 -243.263396) (xy 353.181857 -243.23287) (xy 353.145133 -243.196146)
			(xy 353.114606 -243.15413) (xy 353.091028 -243.107856) (xy 353.074979 -243.058463) (xy 353.066855 -243.007167)
			(xy 352.837771 -243.007167) (xy 352.837771 -243.007169) (xy 352.829646 -243.058468) (xy 352.813596 -243.107864)
			(xy 352.790017 -243.154141) (xy 352.759489 -243.19616) (xy 352.722763 -243.232886) (xy 352.680745 -243.263415)
			(xy 352.634468 -243.286995) (xy 352.585072 -243.303045) (xy 352.533773 -243.31117) (xy 352.507804 -243.31168)
			(xy 352.50755 -243.31168) (xy 352.483023 -243.311238) (xy 352.434511 -243.303969) (xy 352.387604 -243.289614)
			(xy 352.343333 -243.268488) (xy 352.302668 -243.241053) (xy 352.284284 -243.224812) (xy 352.272795 -243.215009)
			(xy 352.245558 -243.201995) (xy 352.215704 -243.197527) (xy 352.18585 -243.201995) (xy 352.158613 -243.215009)
			(xy 352.147124 -243.224812) (xy 352.128751 -243.241067) (xy 352.088089 -243.268511) (xy 352.043815 -243.289639)
			(xy 351.996904 -243.303985) (xy 351.948386 -243.311235) (xy 351.923858 -243.31168) (xy 351.923604 -243.31168)
			(xy 351.897637 -243.311146) (xy 351.846341 -243.303022) (xy 351.796948 -243.286973) (xy 351.750673 -243.263396)
			(xy 351.708657 -243.23287) (xy 351.671933 -243.196146) (xy 351.641406 -243.15413) (xy 351.617828 -243.107856)
			(xy 351.601779 -243.058463) (xy 351.593655 -243.007167) (xy 350.026121 -243.007167) (xy 350.0341 -243.031726)
			(xy 350.042225 -243.083021) (xy 350.042734 -243.108988) (xy 350.042225 -243.134955) (xy 350.0341 -243.18625)
			(xy 350.018052 -243.235643) (xy 349.994474 -243.281917) (xy 349.963948 -243.323933) (xy 349.927225 -243.360656)
			(xy 349.885209 -243.391182) (xy 349.838935 -243.41476) (xy 349.789542 -243.430808) (xy 349.738247 -243.438933)
			(xy 349.686313 -243.438933) (xy 349.635018 -243.430808) (xy 349.585625 -243.41476) (xy 349.539351 -243.391182)
			(xy 349.497335 -243.360656) (xy 349.460612 -243.323933) (xy 349.430086 -243.281917) (xy 349.406508 -243.235643)
			(xy 349.39046 -243.18625) (xy 349.382335 -243.134955) (xy 349.102425 -243.134955) (xy 349.0943 -243.18625)
			(xy 349.078252 -243.235643) (xy 349.054674 -243.281917) (xy 349.024148 -243.323933) (xy 348.987425 -243.360656)
			(xy 348.945409 -243.391182) (xy 348.899135 -243.41476) (xy 348.849742 -243.430808) (xy 348.798447 -243.438933)
			(xy 348.746513 -243.438933) (xy 348.695218 -243.430808) (xy 348.645825 -243.41476) (xy 348.599551 -243.391182)
			(xy 348.557535 -243.360656) (xy 348.520812 -243.323933) (xy 348.490286 -243.281917) (xy 348.466708 -243.235643)
			(xy 348.45066 -243.18625) (xy 348.442535 -243.134955) (xy 348.162625 -243.134955) (xy 348.1545 -243.18625)
			(xy 348.138452 -243.235643) (xy 348.114874 -243.281917) (xy 348.084348 -243.323933) (xy 348.047625 -243.360656)
			(xy 348.005609 -243.391182) (xy 347.959335 -243.41476) (xy 347.909942 -243.430808) (xy 347.858647 -243.438933)
			(xy 347.806713 -243.438933) (xy 347.755418 -243.430808) (xy 347.706025 -243.41476) (xy 347.659751 -243.391182)
			(xy 347.617735 -243.360656) (xy 347.581012 -243.323933) (xy 347.550486 -243.281917) (xy 347.526908 -243.235643)
			(xy 347.51086 -243.18625) (xy 347.502735 -243.134955) (xy 347.222825 -243.134955) (xy 347.2147 -243.18625)
			(xy 347.198652 -243.235643) (xy 347.175074 -243.281917) (xy 347.144548 -243.323933) (xy 347.107825 -243.360656)
			(xy 347.065809 -243.391182) (xy 347.019535 -243.41476) (xy 346.970142 -243.430808) (xy 346.918847 -243.438933)
			(xy 346.866913 -243.438933) (xy 346.815618 -243.430808) (xy 346.766225 -243.41476) (xy 346.719951 -243.391182)
			(xy 346.677935 -243.360656) (xy 346.641212 -243.323933) (xy 346.610686 -243.281917) (xy 346.587108 -243.235643)
			(xy 346.57106 -243.18625) (xy 346.562935 -243.134955) (xy 346.283279 -243.134955) (xy 346.275154 -243.18625)
			(xy 346.259106 -243.235643) (xy 346.235528 -243.281917) (xy 346.205002 -243.323933) (xy 346.168279 -243.360656)
			(xy 346.126263 -243.391182) (xy 346.079989 -243.41476) (xy 346.030596 -243.430808) (xy 345.979301 -243.438933)
			(xy 345.927367 -243.438933) (xy 345.876072 -243.430808) (xy 345.826679 -243.41476) (xy 345.780405 -243.391182)
			(xy 345.738389 -243.360656) (xy 345.701666 -243.323933) (xy 345.67114 -243.281917) (xy 345.647562 -243.235643)
			(xy 345.631514 -243.18625) (xy 345.623389 -243.134955) (xy 345.343225 -243.134955) (xy 345.3351 -243.18625)
			(xy 345.319052 -243.235643) (xy 345.295474 -243.281917) (xy 345.264948 -243.323933) (xy 345.228225 -243.360656)
			(xy 345.186209 -243.391182) (xy 345.139935 -243.41476) (xy 345.090542 -243.430808) (xy 345.039247 -243.438933)
			(xy 344.987313 -243.438933) (xy 344.936018 -243.430808) (xy 344.886625 -243.41476) (xy 344.840351 -243.391182)
			(xy 344.798335 -243.360656) (xy 344.761612 -243.323933) (xy 344.731086 -243.281917) (xy 344.707508 -243.235643)
			(xy 344.69146 -243.18625) (xy 344.683335 -243.134955) (xy 344.403425 -243.134955) (xy 344.3953 -243.18625)
			(xy 344.379252 -243.235643) (xy 344.355674 -243.281917) (xy 344.325148 -243.323933) (xy 344.288425 -243.360656)
			(xy 344.246409 -243.391182) (xy 344.200135 -243.41476) (xy 344.150742 -243.430808) (xy 344.099447 -243.438933)
			(xy 344.047513 -243.438933) (xy 343.996218 -243.430808) (xy 343.946825 -243.41476) (xy 343.900551 -243.391182)
			(xy 343.858535 -243.360656) (xy 343.821812 -243.323933) (xy 343.791286 -243.281917) (xy 343.767708 -243.235643)
			(xy 343.75166 -243.18625) (xy 343.743535 -243.134955) (xy 343.463625 -243.134955) (xy 343.4555 -243.18625)
			(xy 343.439452 -243.235643) (xy 343.415874 -243.281917) (xy 343.385348 -243.323933) (xy 343.348625 -243.360656)
			(xy 343.306609 -243.391182) (xy 343.260335 -243.41476) (xy 343.210942 -243.430808) (xy 343.159647 -243.438933)
			(xy 343.107713 -243.438933) (xy 343.056418 -243.430808) (xy 343.007025 -243.41476) (xy 342.960751 -243.391182)
			(xy 342.918735 -243.360656) (xy 342.882012 -243.323933) (xy 342.851486 -243.281917) (xy 342.827908 -243.235643)
			(xy 342.81186 -243.18625) (xy 342.803735 -243.134955) (xy 342.523825 -243.134955) (xy 342.5157 -243.18625)
			(xy 342.499652 -243.235643) (xy 342.476074 -243.281917) (xy 342.445548 -243.323933) (xy 342.408825 -243.360656)
			(xy 342.366809 -243.391182) (xy 342.320535 -243.41476) (xy 342.271142 -243.430808) (xy 342.219847 -243.438933)
			(xy 342.167913 -243.438933) (xy 342.116618 -243.430808) (xy 342.067225 -243.41476) (xy 342.020951 -243.391182)
			(xy 341.978935 -243.360656) (xy 341.942212 -243.323933) (xy 341.911686 -243.281917) (xy 341.888108 -243.235643)
			(xy 341.87206 -243.18625) (xy 341.863935 -243.134955) (xy 341.584025 -243.134955) (xy 341.5759 -243.18625)
			(xy 341.559852 -243.235643) (xy 341.536274 -243.281917) (xy 341.505748 -243.323933) (xy 341.469025 -243.360656)
			(xy 341.427009 -243.391182) (xy 341.380735 -243.41476) (xy 341.331342 -243.430808) (xy 341.280047 -243.438933)
			(xy 341.228113 -243.438933) (xy 341.176818 -243.430808) (xy 341.127425 -243.41476) (xy 341.081151 -243.391182)
			(xy 341.039135 -243.360656) (xy 341.002412 -243.323933) (xy 340.971886 -243.281917) (xy 340.948308 -243.235643)
			(xy 340.93226 -243.18625) (xy 340.924135 -243.134955) (xy 340.644225 -243.134955) (xy 340.6361 -243.18625)
			(xy 340.620052 -243.235643) (xy 340.596474 -243.281917) (xy 340.565948 -243.323933) (xy 340.529225 -243.360656)
			(xy 340.487209 -243.391182) (xy 340.440935 -243.41476) (xy 340.391542 -243.430808) (xy 340.340247 -243.438933)
			(xy 340.288313 -243.438933) (xy 340.237018 -243.430808) (xy 340.187625 -243.41476) (xy 340.141351 -243.391182)
			(xy 340.099335 -243.360656) (xy 340.062612 -243.323933) (xy 340.032086 -243.281917) (xy 340.008508 -243.235643)
			(xy 339.99246 -243.18625) (xy 339.984335 -243.134955) (xy 339.70491 -243.134955) (xy 339.70491 -243.135552)
			(xy 339.696422 -243.187984) (xy 339.679663 -243.238386) (xy 339.655065 -243.285462) (xy 339.62326 -243.328001)
			(xy 339.585065 -243.36491) (xy 339.541462 -243.395241) (xy 339.517736 -243.407184) (xy 339.505036 -243.41328)
			(xy 339.475064 -243.458746) (xy 339.475064 -243.586508) (xy 339.47547 -243.595411) (xy 339.481722 -243.612088)
			(xy 339.49335 -243.625579) (xy 339.500972 -243.630196) (xy 339.584284 -243.670074) (xy 339.5923 -243.672971)
			(xy 339.609314 -243.673759) (xy 339.617558 -243.671598) (xy 339.638132 -243.664232) (xy 339.64118 -243.6622)
			(xy 339.644736 -243.659406) (xy 339.666443 -243.643597) (xy 339.713904 -243.618479) (xy 339.764796 -243.601349)
			(xy 339.817785 -243.592656) (xy 339.844634 -243.592096) (xy 339.870619 -243.592608) (xy 339.921949 -243.600743)
			(xy 339.971374 -243.616807) (xy 340.017678 -243.640404) (xy 340.059722 -243.670954) (xy 340.096468 -243.707704)
			(xy 340.127014 -243.749751) (xy 340.150606 -243.796057) (xy 340.166665 -243.845484) (xy 340.174795 -243.896815)
			(xy 340.174795 -243.948771) (xy 340.454489 -243.948771) (xy 340.454489 -243.896837) (xy 340.462614 -243.845542)
			(xy 340.478662 -243.796149) (xy 340.50224 -243.749875) (xy 340.532766 -243.707859) (xy 340.569489 -243.671136)
			(xy 340.611505 -243.64061) (xy 340.657779 -243.617032) (xy 340.707172 -243.600984) (xy 340.758467 -243.592859)
			(xy 340.810401 -243.592859) (xy 340.861696 -243.600984) (xy 340.911089 -243.617032) (xy 340.957363 -243.64061)
			(xy 340.999379 -243.671136) (xy 341.036102 -243.707859) (xy 341.066628 -243.749875) (xy 341.090206 -243.796149)
			(xy 341.106254 -243.845542) (xy 341.114379 -243.896837) (xy 341.114888 -243.922804) (xy 341.114379 -243.948771)
			(xy 341.394289 -243.948771) (xy 341.394289 -243.896837) (xy 341.402414 -243.845542) (xy 341.418462 -243.796149)
			(xy 341.44204 -243.749875) (xy 341.472566 -243.707859) (xy 341.509289 -243.671136) (xy 341.551305 -243.64061)
			(xy 341.597579 -243.617032) (xy 341.646972 -243.600984) (xy 341.698267 -243.592859) (xy 341.750201 -243.592859)
			(xy 341.801496 -243.600984) (xy 341.850889 -243.617032) (xy 341.897163 -243.64061) (xy 341.939179 -243.671136)
			(xy 341.975902 -243.707859) (xy 342.006428 -243.749875) (xy 342.030006 -243.796149) (xy 342.046054 -243.845542)
			(xy 342.054179 -243.896837) (xy 342.054688 -243.922804) (xy 342.054179 -243.948771) (xy 342.333835 -243.948771)
			(xy 342.333835 -243.896837) (xy 342.34196 -243.845542) (xy 342.358008 -243.796149) (xy 342.381586 -243.749875)
			(xy 342.412112 -243.707859) (xy 342.448835 -243.671136) (xy 342.490851 -243.64061) (xy 342.537125 -243.617032)
			(xy 342.586518 -243.600984) (xy 342.637813 -243.592859) (xy 342.689747 -243.592859) (xy 342.741042 -243.600984)
			(xy 342.790435 -243.617032) (xy 342.836709 -243.64061) (xy 342.878725 -243.671136) (xy 342.915448 -243.707859)
			(xy 342.945974 -243.749875) (xy 342.969552 -243.796149) (xy 342.9856 -243.845542) (xy 342.993725 -243.896837)
			(xy 342.994234 -243.922804) (xy 342.993725 -243.948771) (xy 343.273889 -243.948771) (xy 343.273889 -243.896837)
			(xy 343.282014 -243.845542) (xy 343.298062 -243.796149) (xy 343.32164 -243.749875) (xy 343.352166 -243.707859)
			(xy 343.388889 -243.671136) (xy 343.430905 -243.64061) (xy 343.477179 -243.617032) (xy 343.526572 -243.600984)
			(xy 343.577867 -243.592859) (xy 343.629801 -243.592859) (xy 343.681096 -243.600984) (xy 343.730489 -243.617032)
			(xy 343.776763 -243.64061) (xy 343.818779 -243.671136) (xy 343.855502 -243.707859) (xy 343.886028 -243.749875)
			(xy 343.909606 -243.796149) (xy 343.925654 -243.845542) (xy 343.933779 -243.896837) (xy 343.934288 -243.922804)
			(xy 343.933779 -243.948771) (xy 344.213689 -243.948771) (xy 344.213689 -243.896837) (xy 344.221814 -243.845542)
			(xy 344.237862 -243.796149) (xy 344.26144 -243.749875) (xy 344.291966 -243.707859) (xy 344.328689 -243.671136)
			(xy 344.370705 -243.64061) (xy 344.416979 -243.617032) (xy 344.466372 -243.600984) (xy 344.517667 -243.592859)
			(xy 344.569601 -243.592859) (xy 344.620896 -243.600984) (xy 344.670289 -243.617032) (xy 344.716563 -243.64061)
			(xy 344.758579 -243.671136) (xy 344.795302 -243.707859) (xy 344.825828 -243.749875) (xy 344.849406 -243.796149)
			(xy 344.865454 -243.845542) (xy 344.873579 -243.896837) (xy 344.874088 -243.922804) (xy 344.873579 -243.948771)
			(xy 345.153489 -243.948771) (xy 345.153489 -243.896837) (xy 345.161614 -243.845542) (xy 345.177662 -243.796149)
			(xy 345.20124 -243.749875) (xy 345.231766 -243.707859) (xy 345.268489 -243.671136) (xy 345.310505 -243.64061)
			(xy 345.356779 -243.617032) (xy 345.406172 -243.600984) (xy 345.457467 -243.592859) (xy 345.509401 -243.592859)
			(xy 345.560696 -243.600984) (xy 345.610089 -243.617032) (xy 345.656363 -243.64061) (xy 345.698379 -243.671136)
			(xy 345.735102 -243.707859) (xy 345.765628 -243.749875) (xy 345.789206 -243.796149) (xy 345.805254 -243.845542)
			(xy 345.813379 -243.896837) (xy 345.813888 -243.922804) (xy 345.813379 -243.948771) (xy 346.093289 -243.948771)
			(xy 346.093289 -243.896837) (xy 346.101414 -243.845542) (xy 346.117462 -243.796149) (xy 346.14104 -243.749875)
			(xy 346.171566 -243.707859) (xy 346.208289 -243.671136) (xy 346.250305 -243.64061) (xy 346.296579 -243.617032)
			(xy 346.345972 -243.600984) (xy 346.397267 -243.592859) (xy 346.449201 -243.592859) (xy 346.500496 -243.600984)
			(xy 346.549889 -243.617032) (xy 346.596163 -243.64061) (xy 346.638179 -243.671136) (xy 346.674902 -243.707859)
			(xy 346.705428 -243.749875) (xy 346.729006 -243.796149) (xy 346.745054 -243.845542) (xy 346.753179 -243.896837)
			(xy 346.753688 -243.922804) (xy 346.753179 -243.948771) (xy 347.033089 -243.948771) (xy 347.033089 -243.896837)
			(xy 347.041214 -243.845542) (xy 347.057262 -243.796149) (xy 347.08084 -243.749875) (xy 347.111366 -243.707859)
			(xy 347.148089 -243.671136) (xy 347.190105 -243.64061) (xy 347.236379 -243.617032) (xy 347.285772 -243.600984)
			(xy 347.337067 -243.592859) (xy 347.389001 -243.592859) (xy 347.440296 -243.600984) (xy 347.489689 -243.617032)
			(xy 347.535963 -243.64061) (xy 347.577979 -243.671136) (xy 347.614702 -243.707859) (xy 347.645228 -243.749875)
			(xy 347.668806 -243.796149) (xy 347.684854 -243.845542) (xy 347.692979 -243.896837) (xy 347.693488 -243.922804)
			(xy 347.692979 -243.948771) (xy 347.972889 -243.948771) (xy 347.972889 -243.896837) (xy 347.981014 -243.845542)
			(xy 347.997062 -243.796149) (xy 348.02064 -243.749875) (xy 348.051166 -243.707859) (xy 348.087889 -243.671136)
			(xy 348.129905 -243.64061) (xy 348.176179 -243.617032) (xy 348.225572 -243.600984) (xy 348.276867 -243.592859)
			(xy 348.328801 -243.592859) (xy 348.380096 -243.600984) (xy 348.429489 -243.617032) (xy 348.475763 -243.64061)
			(xy 348.517779 -243.671136) (xy 348.554502 -243.707859) (xy 348.585028 -243.749875) (xy 348.608606 -243.796149)
			(xy 348.624654 -243.845542) (xy 348.632779 -243.896837) (xy 348.633288 -243.922804) (xy 348.632779 -243.948771)
			(xy 348.912435 -243.948771) (xy 348.912435 -243.896837) (xy 348.92056 -243.845542) (xy 348.936608 -243.796149)
			(xy 348.960186 -243.749875) (xy 348.990712 -243.707859) (xy 349.027435 -243.671136) (xy 349.069451 -243.64061)
			(xy 349.115725 -243.617032) (xy 349.165118 -243.600984) (xy 349.216413 -243.592859) (xy 349.268347 -243.592859)
			(xy 349.319642 -243.600984) (xy 349.369035 -243.617032) (xy 349.415309 -243.64061) (xy 349.457325 -243.671136)
			(xy 349.494048 -243.707859) (xy 349.524574 -243.749875) (xy 349.548152 -243.796149) (xy 349.5642 -243.845542)
			(xy 349.572325 -243.896837) (xy 349.572834 -243.922804) (xy 349.572325 -243.948771) (xy 349.852489 -243.948771)
			(xy 349.852489 -243.896837) (xy 349.860614 -243.845542) (xy 349.876662 -243.796149) (xy 349.90024 -243.749875)
			(xy 349.930766 -243.707859) (xy 349.967489 -243.671136) (xy 350.009505 -243.64061) (xy 350.055779 -243.617032)
			(xy 350.105172 -243.600984) (xy 350.156467 -243.592859) (xy 350.208401 -243.592859) (xy 350.259696 -243.600984)
			(xy 350.309089 -243.617032) (xy 350.355363 -243.64061) (xy 350.397379 -243.671136) (xy 350.434102 -243.707859)
			(xy 350.464628 -243.749875) (xy 350.488206 -243.796149) (xy 350.504254 -243.845542) (xy 350.512379 -243.896837)
			(xy 350.512888 -243.922804) (xy 350.512379 -243.948771) (xy 357.370635 -243.948771) (xy 357.370635 -243.896837)
			(xy 357.37876 -243.845542) (xy 357.394808 -243.796149) (xy 357.418386 -243.749875) (xy 357.448912 -243.707859)
			(xy 357.485635 -243.671136) (xy 357.527651 -243.64061) (xy 357.573925 -243.617032) (xy 357.623318 -243.600984)
			(xy 357.674613 -243.592859) (xy 357.726547 -243.592859) (xy 357.777842 -243.600984) (xy 357.827235 -243.617032)
			(xy 357.873509 -243.64061) (xy 357.915525 -243.671136) (xy 357.952248 -243.707859) (xy 357.982774 -243.749875)
			(xy 358.006352 -243.796149) (xy 358.0224 -243.845542) (xy 358.030525 -243.896837) (xy 358.031034 -243.922804)
			(xy 358.030525 -243.948771) (xy 358.310689 -243.948771) (xy 358.310689 -243.896837) (xy 358.318814 -243.845542)
			(xy 358.334862 -243.796149) (xy 358.35844 -243.749875) (xy 358.388966 -243.707859) (xy 358.425689 -243.671136)
			(xy 358.467705 -243.64061) (xy 358.513979 -243.617032) (xy 358.563372 -243.600984) (xy 358.614667 -243.592859)
			(xy 358.666601 -243.592859) (xy 358.717896 -243.600984) (xy 358.767289 -243.617032) (xy 358.813563 -243.64061)
			(xy 358.855579 -243.671136) (xy 358.892302 -243.707859) (xy 358.922828 -243.749875) (xy 358.946406 -243.796149)
			(xy 358.962454 -243.845542) (xy 358.970579 -243.896837) (xy 358.971088 -243.922804) (xy 358.970579 -243.948771)
			(xy 359.250235 -243.948771) (xy 359.250235 -243.896837) (xy 359.25836 -243.845542) (xy 359.274408 -243.796149)
			(xy 359.297986 -243.749875) (xy 359.328512 -243.707859) (xy 359.365235 -243.671136) (xy 359.407251 -243.64061)
			(xy 359.453525 -243.617032) (xy 359.502918 -243.600984) (xy 359.554213 -243.592859) (xy 359.606147 -243.592859)
			(xy 359.657442 -243.600984) (xy 359.706835 -243.617032) (xy 359.753109 -243.64061) (xy 359.795125 -243.671136)
			(xy 359.831848 -243.707859) (xy 359.862374 -243.749875) (xy 359.885952 -243.796149) (xy 359.902 -243.845542)
			(xy 359.910125 -243.896837) (xy 359.910634 -243.922804) (xy 359.910125 -243.948771) (xy 360.190035 -243.948771)
			(xy 360.190035 -243.896837) (xy 360.19816 -243.845542) (xy 360.214208 -243.796149) (xy 360.237786 -243.749875)
			(xy 360.268312 -243.707859) (xy 360.305035 -243.671136) (xy 360.347051 -243.64061) (xy 360.393325 -243.617032)
			(xy 360.442718 -243.600984) (xy 360.494013 -243.592859) (xy 360.545947 -243.592859) (xy 360.597242 -243.600984)
			(xy 360.646635 -243.617032) (xy 360.692909 -243.64061) (xy 360.734925 -243.671136) (xy 360.771648 -243.707859)
			(xy 360.802174 -243.749875) (xy 360.825752 -243.796149) (xy 360.8418 -243.845542) (xy 360.849925 -243.896837)
			(xy 360.850434 -243.922804) (xy 360.849925 -243.948771) (xy 361.130089 -243.948771) (xy 361.130089 -243.896837)
			(xy 361.138214 -243.845542) (xy 361.154262 -243.796149) (xy 361.17784 -243.749875) (xy 361.208366 -243.707859)
			(xy 361.245089 -243.671136) (xy 361.287105 -243.64061) (xy 361.333379 -243.617032) (xy 361.382772 -243.600984)
			(xy 361.434067 -243.592859) (xy 361.486001 -243.592859) (xy 361.537296 -243.600984) (xy 361.586689 -243.617032)
			(xy 361.632963 -243.64061) (xy 361.674979 -243.671136) (xy 361.711702 -243.707859) (xy 361.742228 -243.749875)
			(xy 361.765806 -243.796149) (xy 361.781854 -243.845542) (xy 361.789979 -243.896837) (xy 361.790488 -243.922804)
			(xy 361.789979 -243.948771) (xy 362.069833 -243.948771) (xy 362.069833 -243.896829) (xy 362.077959 -243.845528)
			(xy 362.094011 -243.796129) (xy 362.117593 -243.749849) (xy 362.148125 -243.707829) (xy 362.184855 -243.671103)
			(xy 362.226878 -243.640575) (xy 362.27316 -243.616998) (xy 362.322561 -243.600951) (xy 362.373863 -243.59283)
			(xy 362.399834 -243.59235) (xy 362.428724 -243.592926) (xy 362.485625 -243.602976) (xy 362.539912 -243.622764)
			(xy 362.589933 -243.651686) (xy 362.612432 -243.66982) (xy 362.622925 -243.678193) (xy 362.647253 -243.689529)
			(xy 362.673695 -243.694128) (xy 362.700422 -243.69167) (xy 362.725583 -243.682327) (xy 362.747436 -243.666745)
			(xy 362.764468 -243.646003) (xy 362.775501 -243.621536) (xy 362.77804 -243.608352) (xy 362.782341 -243.584748)
			(xy 362.79681 -243.539005) (xy 362.817743 -243.495836) (xy 362.8447 -243.456148) (xy 362.86059 -243.438172)
			(xy 362.8704 -243.426688) (xy 362.883411 -243.399449) (xy 362.887877 -243.369594) (xy 362.883407 -243.33974)
			(xy 362.870393 -243.312502) (xy 362.86059 -243.301012) (xy 362.844329 -243.282643) (xy 362.816886 -243.24198)
			(xy 362.795759 -243.197706) (xy 362.781414 -243.150793) (xy 362.774166 -243.102275) (xy 362.773722 -243.077746)
			(xy 362.773722 -243.077492) (xy 362.774231 -243.051525) (xy 362.782356 -243.00023) (xy 362.798404 -242.950837)
			(xy 362.821982 -242.904563) (xy 362.852508 -242.862547) (xy 362.889231 -242.825824) (xy 362.931247 -242.795298)
			(xy 362.977521 -242.77172) (xy 363.026914 -242.755672) (xy 363.078209 -242.747547) (xy 363.130143 -242.747547)
			(xy 363.181438 -242.755672) (xy 363.230831 -242.77172) (xy 363.277105 -242.795298) (xy 363.319121 -242.825824)
			(xy 363.355844 -242.862547) (xy 363.38637 -242.904563) (xy 363.409948 -242.950837) (xy 363.425996 -243.00023)
			(xy 363.427099 -243.007193) (xy 364.044485 -243.007193) (xy 364.044485 -242.955259) (xy 364.05261 -242.903964)
			(xy 364.068658 -242.854571) (xy 364.092236 -242.808297) (xy 364.122762 -242.766281) (xy 364.159485 -242.729558)
			(xy 364.201501 -242.699032) (xy 364.247775 -242.675454) (xy 364.297168 -242.659406) (xy 364.348463 -242.651281)
			(xy 364.400397 -242.651281) (xy 364.451692 -242.659406) (xy 364.501085 -242.675454) (xy 364.547359 -242.699032)
			(xy 364.589375 -242.729558) (xy 364.626098 -242.766281) (xy 364.656624 -242.808297) (xy 364.680202 -242.854571)
			(xy 364.69625 -242.903964) (xy 364.704375 -242.955259) (xy 364.704884 -242.981226) (xy 364.704375 -243.007168)
			(xy 364.811555 -243.007168) (xy 364.811555 -242.955232) (xy 364.819679 -242.903936) (xy 364.835729 -242.854543)
			(xy 364.859307 -242.808268) (xy 364.889835 -242.766252) (xy 364.926559 -242.729528) (xy 364.968577 -242.699002)
			(xy 365.014852 -242.675425) (xy 365.064246 -242.659377) (xy 365.115542 -242.651254) (xy 365.14151 -242.650772)
			(xy 365.167048 -242.651236) (xy 365.217514 -242.659103) (xy 365.266173 -242.674631) (xy 365.311866 -242.697453)
			(xy 365.353509 -242.727027) (xy 365.372142 -242.744498) (xy 365.382265 -242.753647) (xy 365.406162 -242.766789)
			(xy 365.432685 -242.773139) (xy 365.459943 -242.772247) (xy 365.485994 -242.764174) (xy 365.50898 -242.749497)
			(xy 365.518446 -242.739672) (xy 365.537376 -242.719473) (xy 365.580764 -242.685099) (xy 365.629275 -242.658439)
			(xy 365.681553 -242.640241) (xy 365.736133 -242.631014) (xy 365.76381 -242.630452) (xy 365.789671 -242.630958)
			(xy 365.840762 -242.639005) (xy 365.889975 -242.654916) (xy 365.936106 -242.678303) (xy 365.978029 -242.708593)
			(xy 365.996728 -242.726464) (xy 366.006443 -242.735509) (xy 366.029452 -242.748721) (xy 366.055089 -242.755558)
			(xy 366.081623 -242.755558) (xy 366.10726 -242.748721) (xy 366.130269 -242.735509) (xy 366.139984 -242.726464)
			(xy 366.158664 -242.708574) (xy 366.200598 -242.678296) (xy 366.246735 -242.654916) (xy 366.295949 -242.639006)
			(xy 366.347041 -242.630952) (xy 366.372902 -242.630452) (xy 366.398132 -242.63095) (xy 366.448007 -242.638603)
			(xy 366.496141 -242.653745) (xy 366.541415 -242.676026) (xy 366.582777 -242.704928) (xy 366.619267 -242.739779)
			(xy 366.63503 -242.759484) (xy 366.644606 -242.771024) (xy 366.669011 -242.788423) (xy 366.697413 -242.797995)
			(xy 366.727371 -242.798916) (xy 366.756309 -242.791108) (xy 366.781737 -242.775241) (xy 366.792002 -242.76431)
			(xy 366.810975 -242.743335) (xy 366.854836 -242.70763) (xy 366.904129 -242.679901) (xy 366.957418 -242.660956)
			(xy 367.013152 -242.651346) (xy 367.04143 -242.650772) (xy 367.068727 -242.651348) (xy 367.122579 -242.660319)
			(xy 367.17422 -242.678029) (xy 367.222244 -242.703994) (xy 367.265342 -242.737506) (xy 367.284254 -242.757198)
			(xy 367.294087 -242.767178) (xy 367.317971 -242.781804) (xy 367.344927 -242.789403) (xy 367.372933 -242.789403)
			(xy 367.399889 -242.781804) (xy 367.423773 -242.767178) (xy 367.433606 -242.757198) (xy 367.452505 -242.737493)
			(xy 367.495608 -242.703982) (xy 367.543635 -242.678018) (xy 367.595278 -242.660307) (xy 367.649132 -242.651332)
			(xy 367.67643 -242.650772) (xy 367.702398 -242.651232) (xy 367.753693 -242.65936) (xy 367.803086 -242.675413)
			(xy 367.849359 -242.698994) (xy 367.891374 -242.729523) (xy 367.928096 -242.766249) (xy 367.958622 -242.808267)
			(xy 367.982199 -242.854542) (xy 367.998247 -242.903936) (xy 368.006371 -242.955232) (xy 368.006371 -243.007168)
			(xy 367.998247 -243.058464) (xy 367.982199 -243.107858) (xy 367.968393 -243.134955) (xy 369.118135 -243.134955)
			(xy 369.118135 -243.083021) (xy 369.12626 -243.031726) (xy 369.142308 -242.982333) (xy 369.165886 -242.936059)
			(xy 369.196412 -242.894043) (xy 369.233135 -242.85732) (xy 369.275151 -242.826794) (xy 369.321425 -242.803216)
			(xy 369.370818 -242.787168) (xy 369.422113 -242.779043) (xy 369.474047 -242.779043) (xy 369.525342 -242.787168)
			(xy 369.574735 -242.803216) (xy 369.621009 -242.826794) (xy 369.663025 -242.85732) (xy 369.699748 -242.894043)
			(xy 369.730274 -242.936059) (xy 369.753852 -242.982333) (xy 369.7699 -243.031726) (xy 369.778025 -243.083021)
			(xy 369.778534 -243.108988) (xy 369.778025 -243.134955) (xy 370.057935 -243.134955) (xy 370.057935 -243.083021)
			(xy 370.06606 -243.031726) (xy 370.082108 -242.982333) (xy 370.105686 -242.936059) (xy 370.136212 -242.894043)
			(xy 370.172935 -242.85732) (xy 370.214951 -242.826794) (xy 370.261225 -242.803216) (xy 370.310618 -242.787168)
			(xy 370.361913 -242.779043) (xy 370.413847 -242.779043) (xy 370.465142 -242.787168) (xy 370.514535 -242.803216)
			(xy 370.560809 -242.826794) (xy 370.602825 -242.85732) (xy 370.639548 -242.894043) (xy 370.670074 -242.936059)
			(xy 370.693652 -242.982333) (xy 370.7097 -243.031726) (xy 370.717825 -243.083021) (xy 370.718334 -243.108988)
			(xy 370.717825 -243.134955) (xy 370.997735 -243.134955) (xy 370.997735 -243.083021) (xy 371.00586 -243.031726)
			(xy 371.021908 -242.982333) (xy 371.045486 -242.936059) (xy 371.076012 -242.894043) (xy 371.112735 -242.85732)
			(xy 371.154751 -242.826794) (xy 371.201025 -242.803216) (xy 371.250418 -242.787168) (xy 371.301713 -242.779043)
			(xy 371.353647 -242.779043) (xy 371.404942 -242.787168) (xy 371.454335 -242.803216) (xy 371.500609 -242.826794)
			(xy 371.542625 -242.85732) (xy 371.579348 -242.894043) (xy 371.609874 -242.936059) (xy 371.633452 -242.982333)
			(xy 371.6495 -243.031726) (xy 371.657625 -243.083021) (xy 371.658134 -243.108988) (xy 371.657625 -243.134955)
			(xy 371.937535 -243.134955) (xy 371.937535 -243.083021) (xy 371.94566 -243.031726) (xy 371.961708 -242.982333)
			(xy 371.985286 -242.936059) (xy 372.015812 -242.894043) (xy 372.052535 -242.85732) (xy 372.094551 -242.826794)
			(xy 372.140825 -242.803216) (xy 372.190218 -242.787168) (xy 372.241513 -242.779043) (xy 372.293447 -242.779043)
			(xy 372.344742 -242.787168) (xy 372.394135 -242.803216) (xy 372.440409 -242.826794) (xy 372.482425 -242.85732)
			(xy 372.519148 -242.894043) (xy 372.549674 -242.936059) (xy 372.573252 -242.982333) (xy 372.5893 -243.031726)
			(xy 372.597425 -243.083021) (xy 372.597934 -243.108988) (xy 372.597425 -243.134955) (xy 372.877335 -243.134955)
			(xy 372.877335 -243.083021) (xy 372.88546 -243.031726) (xy 372.901508 -242.982333) (xy 372.925086 -242.936059)
			(xy 372.955612 -242.894043) (xy 372.992335 -242.85732) (xy 373.034351 -242.826794) (xy 373.080625 -242.803216)
			(xy 373.130018 -242.787168) (xy 373.181313 -242.779043) (xy 373.233247 -242.779043) (xy 373.284542 -242.787168)
			(xy 373.333935 -242.803216) (xy 373.380209 -242.826794) (xy 373.422225 -242.85732) (xy 373.458948 -242.894043)
			(xy 373.489474 -242.936059) (xy 373.513052 -242.982333) (xy 373.5291 -243.031726) (xy 373.537225 -243.083021)
			(xy 373.537734 -243.108988) (xy 373.537225 -243.134955) (xy 373.817389 -243.134955) (xy 373.817389 -243.083021)
			(xy 373.825514 -243.031726) (xy 373.841562 -242.982333) (xy 373.86514 -242.936059) (xy 373.895666 -242.894043)
			(xy 373.932389 -242.85732) (xy 373.974405 -242.826794) (xy 374.020679 -242.803216) (xy 374.070072 -242.787168)
			(xy 374.121367 -242.779043) (xy 374.173301 -242.779043) (xy 374.224596 -242.787168) (xy 374.273989 -242.803216)
			(xy 374.320263 -242.826794) (xy 374.362279 -242.85732) (xy 374.399002 -242.894043) (xy 374.429528 -242.936059)
			(xy 374.453106 -242.982333) (xy 374.469154 -243.031726) (xy 374.477279 -243.083021) (xy 374.477788 -243.108988)
			(xy 374.477279 -243.134955) (xy 374.756935 -243.134955) (xy 374.756935 -243.083021) (xy 374.76506 -243.031726)
			(xy 374.781108 -242.982333) (xy 374.804686 -242.936059) (xy 374.835212 -242.894043) (xy 374.871935 -242.85732)
			(xy 374.913951 -242.826794) (xy 374.960225 -242.803216) (xy 375.009618 -242.787168) (xy 375.060913 -242.779043)
			(xy 375.112847 -242.779043) (xy 375.164142 -242.787168) (xy 375.213535 -242.803216) (xy 375.259809 -242.826794)
			(xy 375.301825 -242.85732) (xy 375.338548 -242.894043) (xy 375.369074 -242.936059) (xy 375.392652 -242.982333)
			(xy 375.4087 -243.031726) (xy 375.416825 -243.083021) (xy 375.417334 -243.108988) (xy 375.416825 -243.134955)
			(xy 375.696735 -243.134955) (xy 375.696735 -243.083021) (xy 375.70486 -243.031726) (xy 375.720908 -242.982333)
			(xy 375.744486 -242.936059) (xy 375.775012 -242.894043) (xy 375.811735 -242.85732) (xy 375.853751 -242.826794)
			(xy 375.900025 -242.803216) (xy 375.949418 -242.787168) (xy 376.000713 -242.779043) (xy 376.052647 -242.779043)
			(xy 376.103942 -242.787168) (xy 376.153335 -242.803216) (xy 376.199609 -242.826794) (xy 376.241625 -242.85732)
			(xy 376.278348 -242.894043) (xy 376.308874 -242.936059) (xy 376.332452 -242.982333) (xy 376.3485 -243.031726)
			(xy 376.356625 -243.083021) (xy 376.357134 -243.108988) (xy 376.356625 -243.134955) (xy 376.636535 -243.134955)
			(xy 376.636535 -243.083021) (xy 376.64466 -243.031726) (xy 376.660708 -242.982333) (xy 376.684286 -242.936059)
			(xy 376.714812 -242.894043) (xy 376.751535 -242.85732) (xy 376.793551 -242.826794) (xy 376.839825 -242.803216)
			(xy 376.889218 -242.787168) (xy 376.940513 -242.779043) (xy 376.992447 -242.779043) (xy 377.043742 -242.787168)
			(xy 377.093135 -242.803216) (xy 377.139409 -242.826794) (xy 377.181425 -242.85732) (xy 377.218148 -242.894043)
			(xy 377.248674 -242.936059) (xy 377.272252 -242.982333) (xy 377.2883 -243.031726) (xy 377.296425 -243.083021)
			(xy 377.296934 -243.108988) (xy 377.296425 -243.134955) (xy 377.576335 -243.134955) (xy 377.576335 -243.083021)
			(xy 377.58446 -243.031726) (xy 377.600508 -242.982333) (xy 377.624086 -242.936059) (xy 377.654612 -242.894043)
			(xy 377.691335 -242.85732) (xy 377.733351 -242.826794) (xy 377.779625 -242.803216) (xy 377.829018 -242.787168)
			(xy 377.880313 -242.779043) (xy 377.932247 -242.779043) (xy 377.983542 -242.787168) (xy 378.032935 -242.803216)
			(xy 378.079209 -242.826794) (xy 378.121225 -242.85732) (xy 378.157948 -242.894043) (xy 378.188474 -242.936059)
			(xy 378.212052 -242.982333) (xy 378.2281 -243.031726) (xy 378.236225 -243.083021) (xy 378.236734 -243.108988)
			(xy 378.236225 -243.134955) (xy 378.516135 -243.134955) (xy 378.516135 -243.083021) (xy 378.52426 -243.031726)
			(xy 378.540308 -242.982333) (xy 378.563886 -242.936059) (xy 378.594412 -242.894043) (xy 378.631135 -242.85732)
			(xy 378.673151 -242.826794) (xy 378.719425 -242.803216) (xy 378.768818 -242.787168) (xy 378.820113 -242.779043)
			(xy 378.872047 -242.779043) (xy 378.923342 -242.787168) (xy 378.972735 -242.803216) (xy 379.019009 -242.826794)
			(xy 379.061025 -242.85732) (xy 379.097748 -242.894043) (xy 379.128274 -242.936059) (xy 379.151852 -242.982333)
			(xy 379.1679 -243.031726) (xy 379.176025 -243.083021) (xy 379.176534 -243.108988) (xy 379.176025 -243.134955)
			(xy 379.1679 -243.18625) (xy 379.151852 -243.235643) (xy 379.128274 -243.281917) (xy 379.097748 -243.323933)
			(xy 379.061025 -243.360656) (xy 379.019009 -243.391182) (xy 378.972735 -243.41476) (xy 378.923342 -243.430808)
			(xy 378.872047 -243.438933) (xy 378.820113 -243.438933) (xy 378.768818 -243.430808) (xy 378.719425 -243.41476)
			(xy 378.673151 -243.391182) (xy 378.631135 -243.360656) (xy 378.594412 -243.323933) (xy 378.563886 -243.281917)
			(xy 378.540308 -243.235643) (xy 378.52426 -243.18625) (xy 378.516135 -243.134955) (xy 378.236225 -243.134955)
			(xy 378.2281 -243.18625) (xy 378.212052 -243.235643) (xy 378.188474 -243.281917) (xy 378.157948 -243.323933)
			(xy 378.121225 -243.360656) (xy 378.079209 -243.391182) (xy 378.032935 -243.41476) (xy 377.983542 -243.430808)
			(xy 377.932247 -243.438933) (xy 377.880313 -243.438933) (xy 377.829018 -243.430808) (xy 377.779625 -243.41476)
			(xy 377.733351 -243.391182) (xy 377.691335 -243.360656) (xy 377.654612 -243.323933) (xy 377.624086 -243.281917)
			(xy 377.600508 -243.235643) (xy 377.58446 -243.18625) (xy 377.576335 -243.134955) (xy 377.296425 -243.134955)
			(xy 377.2883 -243.18625) (xy 377.272252 -243.235643) (xy 377.248674 -243.281917) (xy 377.218148 -243.323933)
			(xy 377.181425 -243.360656) (xy 377.139409 -243.391182) (xy 377.093135 -243.41476) (xy 377.043742 -243.430808)
			(xy 376.992447 -243.438933) (xy 376.940513 -243.438933) (xy 376.889218 -243.430808) (xy 376.839825 -243.41476)
			(xy 376.793551 -243.391182) (xy 376.751535 -243.360656) (xy 376.714812 -243.323933) (xy 376.684286 -243.281917)
			(xy 376.660708 -243.235643) (xy 376.64466 -243.18625) (xy 376.636535 -243.134955) (xy 376.356625 -243.134955)
			(xy 376.3485 -243.18625) (xy 376.332452 -243.235643) (xy 376.308874 -243.281917) (xy 376.278348 -243.323933)
			(xy 376.241625 -243.360656) (xy 376.199609 -243.391182) (xy 376.153335 -243.41476) (xy 376.103942 -243.430808)
			(xy 376.052647 -243.438933) (xy 376.000713 -243.438933) (xy 375.949418 -243.430808) (xy 375.900025 -243.41476)
			(xy 375.853751 -243.391182) (xy 375.811735 -243.360656) (xy 375.775012 -243.323933) (xy 375.744486 -243.281917)
			(xy 375.720908 -243.235643) (xy 375.70486 -243.18625) (xy 375.696735 -243.134955) (xy 375.416825 -243.134955)
			(xy 375.4087 -243.18625) (xy 375.392652 -243.235643) (xy 375.369074 -243.281917) (xy 375.338548 -243.323933)
			(xy 375.301825 -243.360656) (xy 375.259809 -243.391182) (xy 375.213535 -243.41476) (xy 375.164142 -243.430808)
			(xy 375.112847 -243.438933) (xy 375.060913 -243.438933) (xy 375.009618 -243.430808) (xy 374.960225 -243.41476)
			(xy 374.913951 -243.391182) (xy 374.871935 -243.360656) (xy 374.835212 -243.323933) (xy 374.804686 -243.281917)
			(xy 374.781108 -243.235643) (xy 374.76506 -243.18625) (xy 374.756935 -243.134955) (xy 374.477279 -243.134955)
			(xy 374.469154 -243.18625) (xy 374.453106 -243.235643) (xy 374.429528 -243.281917) (xy 374.399002 -243.323933)
			(xy 374.362279 -243.360656) (xy 374.320263 -243.391182) (xy 374.273989 -243.41476) (xy 374.224596 -243.430808)
			(xy 374.173301 -243.438933) (xy 374.121367 -243.438933) (xy 374.070072 -243.430808) (xy 374.020679 -243.41476)
			(xy 373.974405 -243.391182) (xy 373.932389 -243.360656) (xy 373.895666 -243.323933) (xy 373.86514 -243.281917)
			(xy 373.841562 -243.235643) (xy 373.825514 -243.18625) (xy 373.817389 -243.134955) (xy 373.537225 -243.134955)
			(xy 373.5291 -243.18625) (xy 373.513052 -243.235643) (xy 373.489474 -243.281917) (xy 373.458948 -243.323933)
			(xy 373.422225 -243.360656) (xy 373.380209 -243.391182) (xy 373.333935 -243.41476) (xy 373.284542 -243.430808)
			(xy 373.233247 -243.438933) (xy 373.181313 -243.438933) (xy 373.130018 -243.430808) (xy 373.080625 -243.41476)
			(xy 373.034351 -243.391182) (xy 372.992335 -243.360656) (xy 372.955612 -243.323933) (xy 372.925086 -243.281917)
			(xy 372.901508 -243.235643) (xy 372.88546 -243.18625) (xy 372.877335 -243.134955) (xy 372.597425 -243.134955)
			(xy 372.5893 -243.18625) (xy 372.573252 -243.235643) (xy 372.549674 -243.281917) (xy 372.519148 -243.323933)
			(xy 372.482425 -243.360656) (xy 372.440409 -243.391182) (xy 372.394135 -243.41476) (xy 372.344742 -243.430808)
			(xy 372.293447 -243.438933) (xy 372.241513 -243.438933) (xy 372.190218 -243.430808) (xy 372.140825 -243.41476)
			(xy 372.094551 -243.391182) (xy 372.052535 -243.360656) (xy 372.015812 -243.323933) (xy 371.985286 -243.281917)
			(xy 371.961708 -243.235643) (xy 371.94566 -243.18625) (xy 371.937535 -243.134955) (xy 371.657625 -243.134955)
			(xy 371.6495 -243.18625) (xy 371.633452 -243.235643) (xy 371.609874 -243.281917) (xy 371.579348 -243.323933)
			(xy 371.542625 -243.360656) (xy 371.500609 -243.391182) (xy 371.454335 -243.41476) (xy 371.404942 -243.430808)
			(xy 371.353647 -243.438933) (xy 371.301713 -243.438933) (xy 371.250418 -243.430808) (xy 371.201025 -243.41476)
			(xy 371.154751 -243.391182) (xy 371.112735 -243.360656) (xy 371.076012 -243.323933) (xy 371.045486 -243.281917)
			(xy 371.021908 -243.235643) (xy 371.00586 -243.18625) (xy 370.997735 -243.134955) (xy 370.717825 -243.134955)
			(xy 370.7097 -243.18625) (xy 370.693652 -243.235643) (xy 370.670074 -243.281917) (xy 370.639548 -243.323933)
			(xy 370.602825 -243.360656) (xy 370.560809 -243.391182) (xy 370.514535 -243.41476) (xy 370.465142 -243.430808)
			(xy 370.413847 -243.438933) (xy 370.361913 -243.438933) (xy 370.310618 -243.430808) (xy 370.261225 -243.41476)
			(xy 370.214951 -243.391182) (xy 370.172935 -243.360656) (xy 370.136212 -243.323933) (xy 370.105686 -243.281917)
			(xy 370.082108 -243.235643) (xy 370.06606 -243.18625) (xy 370.057935 -243.134955) (xy 369.778025 -243.134955)
			(xy 369.7699 -243.18625) (xy 369.753852 -243.235643) (xy 369.730274 -243.281917) (xy 369.699748 -243.323933)
			(xy 369.663025 -243.360656) (xy 369.621009 -243.391182) (xy 369.574735 -243.41476) (xy 369.525342 -243.430808)
			(xy 369.474047 -243.438933) (xy 369.422113 -243.438933) (xy 369.370818 -243.430808) (xy 369.321425 -243.41476)
			(xy 369.275151 -243.391182) (xy 369.233135 -243.360656) (xy 369.196412 -243.323933) (xy 369.165886 -243.281917)
			(xy 369.142308 -243.235643) (xy 369.12626 -243.18625) (xy 369.118135 -243.134955) (xy 367.968393 -243.134955)
			(xy 367.958622 -243.154133) (xy 367.928096 -243.196151) (xy 367.891374 -243.232877) (xy 367.849359 -243.263406)
			(xy 367.803086 -243.286987) (xy 367.753693 -243.30304) (xy 367.702398 -243.311168) (xy 367.67643 -243.31168)
			(xy 367.649133 -243.311114) (xy 367.595281 -243.302138) (xy 367.54364 -243.284425) (xy 367.495616 -243.258459)
			(xy 367.452518 -243.224946) (xy 367.433606 -243.205254) (xy 367.423773 -243.195274) (xy 367.399889 -243.180648)
			(xy 367.372933 -243.173049) (xy 367.344927 -243.173049) (xy 367.317971 -243.180648) (xy 367.294087 -243.195274)
			(xy 367.284254 -243.205254) (xy 367.265336 -243.22494) (xy 367.222237 -243.25845) (xy 367.174215 -243.284417)
			(xy 367.122576 -243.302133) (xy 367.068727 -243.311116) (xy 367.04143 -243.31168) (xy 367.0162 -243.311185)
			(xy 366.966323 -243.303536) (xy 366.918188 -243.288394) (xy 366.872914 -243.266113) (xy 366.831552 -243.237209)
			(xy 366.795063 -243.202355) (xy 366.779302 -243.182648) (xy 366.769692 -243.171137) (xy 366.745298 -243.153732)
			(xy 366.716903 -243.144154) (xy 366.686951 -243.143227) (xy 366.658018 -243.15103) (xy 366.632594 -243.166893)
			(xy 366.62233 -243.177822) (xy 366.603326 -243.198768) (xy 366.559475 -243.23448) (xy 366.510191 -243.262215)
			(xy 366.456908 -243.281167) (xy 366.401178 -243.290783) (xy 366.372902 -243.29136) (xy 366.347042 -243.290843)
			(xy 366.295951 -243.282798) (xy 366.246739 -243.26689) (xy 366.200607 -243.243506) (xy 366.158683 -243.213218)
			(xy 366.139984 -243.195348) (xy 366.130269 -243.186303) (xy 366.10726 -243.173091) (xy 366.081623 -243.166254)
			(xy 366.055089 -243.166254) (xy 366.029452 -243.173091) (xy 366.006443 -243.186303) (xy 365.996728 -243.195348)
			(xy 365.978028 -243.213217) (xy 365.936101 -243.243502) (xy 365.88997 -243.266887) (xy 365.840759 -243.282802)
			(xy 365.78967 -243.290859) (xy 365.76381 -243.29136) (xy 365.738273 -243.290874) (xy 365.687808 -243.283012)
			(xy 365.63915 -243.267488) (xy 365.593456 -243.244671) (xy 365.551812 -243.215103) (xy 365.533178 -243.197634)
			(xy 365.523126 -243.188399) (xy 365.499208 -243.175259) (xy 365.472666 -243.168918) (xy 365.445391 -243.169826)
			(xy 365.419329 -243.17792) (xy 365.396339 -243.192622) (xy 365.386874 -243.20246) (xy 365.367941 -243.222655)
			(xy 365.324553 -243.257029) (xy 365.276042 -243.283688) (xy 365.223766 -243.301887) (xy 365.169187 -243.311117)
			(xy 365.14151 -243.31168) (xy 365.115542 -243.311146) (xy 365.064246 -243.303023) (xy 365.014852 -243.286975)
			(xy 364.968577 -243.263398) (xy 364.926559 -243.232872) (xy 364.889835 -243.196148) (xy 364.859307 -243.154132)
			(xy 364.835729 -243.107857) (xy 364.819679 -243.058464) (xy 364.811555 -243.007168) (xy 364.704375 -243.007168)
			(xy 364.704375 -243.007193) (xy 364.69625 -243.058488) (xy 364.680202 -243.107881) (xy 364.656624 -243.154155)
			(xy 364.626098 -243.196171) (xy 364.589375 -243.232894) (xy 364.547359 -243.26342) (xy 364.501085 -243.286998)
			(xy 364.451692 -243.303046) (xy 364.400397 -243.311171) (xy 364.348463 -243.311171) (xy 364.297168 -243.303046)
			(xy 364.247775 -243.286998) (xy 364.201501 -243.26342) (xy 364.159485 -243.232894) (xy 364.122762 -243.196171)
			(xy 364.092236 -243.154155) (xy 364.068658 -243.107881) (xy 364.05261 -243.058488) (xy 364.044485 -243.007193)
			(xy 363.427099 -243.007193) (xy 363.434121 -243.051525) (xy 363.43463 -243.077492) (xy 363.43463 -243.077746)
			(xy 363.434198 -243.102273) (xy 363.426929 -243.150787) (xy 363.412573 -243.197694) (xy 363.391443 -243.241965)
			(xy 363.364005 -243.282629) (xy 363.347762 -243.301012) (xy 363.337963 -243.312506) (xy 363.324944 -243.33974)
			(xy 363.320472 -243.369594) (xy 363.32494 -243.399448) (xy 363.337957 -243.426684) (xy 363.347762 -243.438172)
			(xy 363.364007 -243.456554) (xy 363.391455 -243.497212) (xy 363.412585 -243.541484) (xy 363.426934 -243.588394)
			(xy 363.434185 -243.63691) (xy 363.43463 -243.661438) (xy 363.43463 -243.661692) (xy 363.434164 -243.687662)
			(xy 363.426039 -243.738963) (xy 363.409989 -243.788362) (xy 363.386408 -243.834641) (xy 363.355878 -243.876661)
			(xy 363.319149 -243.913388) (xy 363.277127 -243.943917) (xy 363.230847 -243.967495) (xy 363.181448 -243.983543)
			(xy 363.130146 -243.991665) (xy 363.104176 -243.992146) (xy 363.075286 -243.991565) (xy 363.018386 -243.981517)
			(xy 362.964098 -243.961731) (xy 362.914077 -243.932809) (xy 362.891578 -243.914676) (xy 362.881074 -243.906318)
			(xy 362.856749 -243.894981) (xy 362.830309 -243.890382) (xy 362.803585 -243.892838) (xy 362.778426 -243.902179)
			(xy 362.756575 -243.917758) (xy 362.739543 -243.938498) (xy 362.72851 -243.962962) (xy 362.72597 -243.976144)
			(xy 362.721254 -244.00159) (xy 362.705044 -244.050732) (xy 362.681372 -244.096747) (xy 362.650817 -244.13851)
			(xy 362.614126 -244.175) (xy 362.572196 -244.205324) (xy 362.526052 -244.228743) (xy 362.476821 -244.244682)
			(xy 362.425707 -244.252753) (xy 362.399834 -244.253258) (xy 362.373863 -244.25277) (xy 362.322561 -244.244649)
			(xy 362.27316 -244.228602) (xy 362.226878 -244.205025) (xy 362.184855 -244.174497) (xy 362.148125 -244.137771)
			(xy 362.117593 -244.095751) (xy 362.094011 -244.049471) (xy 362.077959 -244.000072) (xy 362.069833 -243.948771)
			(xy 361.789979 -243.948771) (xy 361.781854 -244.000066) (xy 361.765806 -244.049459) (xy 361.742228 -244.095733)
			(xy 361.711702 -244.137749) (xy 361.674979 -244.174472) (xy 361.632963 -244.204998) (xy 361.586689 -244.228576)
			(xy 361.537296 -244.244624) (xy 361.486001 -244.252749) (xy 361.434067 -244.252749) (xy 361.382772 -244.244624)
			(xy 361.333379 -244.228576) (xy 361.287105 -244.204998) (xy 361.245089 -244.174472) (xy 361.208366 -244.137749)
			(xy 361.17784 -244.095733) (xy 361.154262 -244.049459) (xy 361.138214 -244.000066) (xy 361.130089 -243.948771)
			(xy 360.849925 -243.948771) (xy 360.8418 -244.000066) (xy 360.825752 -244.049459) (xy 360.802174 -244.095733)
			(xy 360.771648 -244.137749) (xy 360.734925 -244.174472) (xy 360.692909 -244.204998) (xy 360.646635 -244.228576)
			(xy 360.597242 -244.244624) (xy 360.545947 -244.252749) (xy 360.494013 -244.252749) (xy 360.442718 -244.244624)
			(xy 360.393325 -244.228576) (xy 360.347051 -244.204998) (xy 360.305035 -244.174472) (xy 360.268312 -244.137749)
			(xy 360.237786 -244.095733) (xy 360.214208 -244.049459) (xy 360.19816 -244.000066) (xy 360.190035 -243.948771)
			(xy 359.910125 -243.948771) (xy 359.902 -244.000066) (xy 359.885952 -244.049459) (xy 359.862374 -244.095733)
			(xy 359.831848 -244.137749) (xy 359.795125 -244.174472) (xy 359.753109 -244.204998) (xy 359.706835 -244.228576)
			(xy 359.657442 -244.244624) (xy 359.606147 -244.252749) (xy 359.554213 -244.252749) (xy 359.502918 -244.244624)
			(xy 359.453525 -244.228576) (xy 359.407251 -244.204998) (xy 359.365235 -244.174472) (xy 359.328512 -244.137749)
			(xy 359.297986 -244.095733) (xy 359.274408 -244.049459) (xy 359.25836 -244.000066) (xy 359.250235 -243.948771)
			(xy 358.970579 -243.948771) (xy 358.962454 -244.000066) (xy 358.946406 -244.049459) (xy 358.922828 -244.095733)
			(xy 358.892302 -244.137749) (xy 358.855579 -244.174472) (xy 358.813563 -244.204998) (xy 358.767289 -244.228576)
			(xy 358.717896 -244.244624) (xy 358.666601 -244.252749) (xy 358.614667 -244.252749) (xy 358.563372 -244.244624)
			(xy 358.513979 -244.228576) (xy 358.467705 -244.204998) (xy 358.425689 -244.174472) (xy 358.388966 -244.137749)
			(xy 358.35844 -244.095733) (xy 358.334862 -244.049459) (xy 358.318814 -244.000066) (xy 358.310689 -243.948771)
			(xy 358.030525 -243.948771) (xy 358.0224 -244.000066) (xy 358.006352 -244.049459) (xy 357.982774 -244.095733)
			(xy 357.952248 -244.137749) (xy 357.915525 -244.174472) (xy 357.873509 -244.204998) (xy 357.827235 -244.228576)
			(xy 357.777842 -244.244624) (xy 357.726547 -244.252749) (xy 357.674613 -244.252749) (xy 357.623318 -244.244624)
			(xy 357.573925 -244.228576) (xy 357.527651 -244.204998) (xy 357.485635 -244.174472) (xy 357.448912 -244.137749)
			(xy 357.418386 -244.095733) (xy 357.394808 -244.049459) (xy 357.37876 -244.000066) (xy 357.370635 -243.948771)
			(xy 350.512379 -243.948771) (xy 350.504254 -244.000066) (xy 350.488206 -244.049459) (xy 350.464628 -244.095733)
			(xy 350.434102 -244.137749) (xy 350.397379 -244.174472) (xy 350.355363 -244.204998) (xy 350.309089 -244.228576)
			(xy 350.259696 -244.244624) (xy 350.208401 -244.252749) (xy 350.156467 -244.252749) (xy 350.105172 -244.244624)
			(xy 350.055779 -244.228576) (xy 350.009505 -244.204998) (xy 349.967489 -244.174472) (xy 349.930766 -244.137749)
			(xy 349.90024 -244.095733) (xy 349.876662 -244.049459) (xy 349.860614 -244.000066) (xy 349.852489 -243.948771)
			(xy 349.572325 -243.948771) (xy 349.5642 -244.000066) (xy 349.548152 -244.049459) (xy 349.524574 -244.095733)
			(xy 349.494048 -244.137749) (xy 349.457325 -244.174472) (xy 349.415309 -244.204998) (xy 349.369035 -244.228576)
			(xy 349.319642 -244.244624) (xy 349.268347 -244.252749) (xy 349.216413 -244.252749) (xy 349.165118 -244.244624)
			(xy 349.115725 -244.228576) (xy 349.069451 -244.204998) (xy 349.027435 -244.174472) (xy 348.990712 -244.137749)
			(xy 348.960186 -244.095733) (xy 348.936608 -244.049459) (xy 348.92056 -244.000066) (xy 348.912435 -243.948771)
			(xy 348.632779 -243.948771) (xy 348.624654 -244.000066) (xy 348.608606 -244.049459) (xy 348.585028 -244.095733)
			(xy 348.554502 -244.137749) (xy 348.517779 -244.174472) (xy 348.475763 -244.204998) (xy 348.429489 -244.228576)
			(xy 348.380096 -244.244624) (xy 348.328801 -244.252749) (xy 348.276867 -244.252749) (xy 348.225572 -244.244624)
			(xy 348.176179 -244.228576) (xy 348.129905 -244.204998) (xy 348.087889 -244.174472) (xy 348.051166 -244.137749)
			(xy 348.02064 -244.095733) (xy 347.997062 -244.049459) (xy 347.981014 -244.000066) (xy 347.972889 -243.948771)
			(xy 347.692979 -243.948771) (xy 347.684854 -244.000066) (xy 347.668806 -244.049459) (xy 347.645228 -244.095733)
			(xy 347.614702 -244.137749) (xy 347.577979 -244.174472) (xy 347.535963 -244.204998) (xy 347.489689 -244.228576)
			(xy 347.440296 -244.244624) (xy 347.389001 -244.252749) (xy 347.337067 -244.252749) (xy 347.285772 -244.244624)
			(xy 347.236379 -244.228576) (xy 347.190105 -244.204998) (xy 347.148089 -244.174472) (xy 347.111366 -244.137749)
			(xy 347.08084 -244.095733) (xy 347.057262 -244.049459) (xy 347.041214 -244.000066) (xy 347.033089 -243.948771)
			(xy 346.753179 -243.948771) (xy 346.745054 -244.000066) (xy 346.729006 -244.049459) (xy 346.705428 -244.095733)
			(xy 346.674902 -244.137749) (xy 346.638179 -244.174472) (xy 346.596163 -244.204998) (xy 346.549889 -244.228576)
			(xy 346.500496 -244.244624) (xy 346.449201 -244.252749) (xy 346.397267 -244.252749) (xy 346.345972 -244.244624)
			(xy 346.296579 -244.228576) (xy 346.250305 -244.204998) (xy 346.208289 -244.174472) (xy 346.171566 -244.137749)
			(xy 346.14104 -244.095733) (xy 346.117462 -244.049459) (xy 346.101414 -244.000066) (xy 346.093289 -243.948771)
			(xy 345.813379 -243.948771) (xy 345.805254 -244.000066) (xy 345.789206 -244.049459) (xy 345.765628 -244.095733)
			(xy 345.735102 -244.137749) (xy 345.698379 -244.174472) (xy 345.656363 -244.204998) (xy 345.610089 -244.228576)
			(xy 345.560696 -244.244624) (xy 345.509401 -244.252749) (xy 345.457467 -244.252749) (xy 345.406172 -244.244624)
			(xy 345.356779 -244.228576) (xy 345.310505 -244.204998) (xy 345.268489 -244.174472) (xy 345.231766 -244.137749)
			(xy 345.20124 -244.095733) (xy 345.177662 -244.049459) (xy 345.161614 -244.000066) (xy 345.153489 -243.948771)
			(xy 344.873579 -243.948771) (xy 344.865454 -244.000066) (xy 344.849406 -244.049459) (xy 344.825828 -244.095733)
			(xy 344.795302 -244.137749) (xy 344.758579 -244.174472) (xy 344.716563 -244.204998) (xy 344.670289 -244.228576)
			(xy 344.620896 -244.244624) (xy 344.569601 -244.252749) (xy 344.517667 -244.252749) (xy 344.466372 -244.244624)
			(xy 344.416979 -244.228576) (xy 344.370705 -244.204998) (xy 344.328689 -244.174472) (xy 344.291966 -244.137749)
			(xy 344.26144 -244.095733) (xy 344.237862 -244.049459) (xy 344.221814 -244.000066) (xy 344.213689 -243.948771)
			(xy 343.933779 -243.948771) (xy 343.925654 -244.000066) (xy 343.909606 -244.049459) (xy 343.886028 -244.095733)
			(xy 343.855502 -244.137749) (xy 343.818779 -244.174472) (xy 343.776763 -244.204998) (xy 343.730489 -244.228576)
			(xy 343.681096 -244.244624) (xy 343.629801 -244.252749) (xy 343.577867 -244.252749) (xy 343.526572 -244.244624)
			(xy 343.477179 -244.228576) (xy 343.430905 -244.204998) (xy 343.388889 -244.174472) (xy 343.352166 -244.137749)
			(xy 343.32164 -244.095733) (xy 343.298062 -244.049459) (xy 343.282014 -244.000066) (xy 343.273889 -243.948771)
			(xy 342.993725 -243.948771) (xy 342.9856 -244.000066) (xy 342.969552 -244.049459) (xy 342.945974 -244.095733)
			(xy 342.915448 -244.137749) (xy 342.878725 -244.174472) (xy 342.836709 -244.204998) (xy 342.790435 -244.228576)
			(xy 342.741042 -244.244624) (xy 342.689747 -244.252749) (xy 342.637813 -244.252749) (xy 342.586518 -244.244624)
			(xy 342.537125 -244.228576) (xy 342.490851 -244.204998) (xy 342.448835 -244.174472) (xy 342.412112 -244.137749)
			(xy 342.381586 -244.095733) (xy 342.358008 -244.049459) (xy 342.34196 -244.000066) (xy 342.333835 -243.948771)
			(xy 342.054179 -243.948771) (xy 342.046054 -244.000066) (xy 342.030006 -244.049459) (xy 342.006428 -244.095733)
			(xy 341.975902 -244.137749) (xy 341.939179 -244.174472) (xy 341.897163 -244.204998) (xy 341.850889 -244.228576)
			(xy 341.801496 -244.244624) (xy 341.750201 -244.252749) (xy 341.698267 -244.252749) (xy 341.646972 -244.244624)
			(xy 341.597579 -244.228576) (xy 341.551305 -244.204998) (xy 341.509289 -244.174472) (xy 341.472566 -244.137749)
			(xy 341.44204 -244.095733) (xy 341.418462 -244.049459) (xy 341.402414 -244.000066) (xy 341.394289 -243.948771)
			(xy 341.114379 -243.948771) (xy 341.106254 -244.000066) (xy 341.090206 -244.049459) (xy 341.066628 -244.095733)
			(xy 341.036102 -244.137749) (xy 340.999379 -244.174472) (xy 340.957363 -244.204998) (xy 340.911089 -244.228576)
			(xy 340.861696 -244.244624) (xy 340.810401 -244.252749) (xy 340.758467 -244.252749) (xy 340.707172 -244.244624)
			(xy 340.657779 -244.228576) (xy 340.611505 -244.204998) (xy 340.569489 -244.174472) (xy 340.532766 -244.137749)
			(xy 340.50224 -244.095733) (xy 340.478662 -244.049459) (xy 340.462614 -244.000066) (xy 340.454489 -243.948771)
			(xy 340.174795 -243.948771) (xy 340.174795 -243.948785) (xy 340.166665 -244.000116) (xy 340.150606 -244.049543)
			(xy 340.127014 -244.095849) (xy 340.096468 -244.137896) (xy 340.059722 -244.174646) (xy 340.017678 -244.205196)
			(xy 339.971374 -244.228793) (xy 339.921949 -244.244857) (xy 339.870619 -244.252992) (xy 339.844634 -244.253512)
			(xy 339.818161 -244.252987) (xy 339.765892 -244.244548) (xy 339.715633 -244.227897) (xy 339.668665 -244.203458)
			(xy 339.626186 -244.171854) (xy 339.58928 -244.133891) (xy 339.573616 -244.112542) (xy 339.566758 -244.102636)
			(xy 339.550248 -244.093492) (xy 339.540737 -244.088901) (xy 339.519719 -244.087085) (xy 339.499743 -244.093867)
			(xy 339.484175 -244.108104) (xy 339.475639 -244.127396) (xy 339.475064 -244.137942) (xy 339.475064 -244.192552)
			(xy 339.475578 -244.202303) (xy 339.483024 -244.220334) (xy 339.489542 -244.227604) (xy 339.8647 -244.602762)
			(xy 339.872917 -244.610062) (xy 339.893596 -244.617437) (xy 339.904578 -244.616986) (xy 339.986874 -244.605048)
			(xy 340.02345 -244.579648) (xy 340.025482 -244.576092) (xy 340.038082 -244.554327) (xy 340.068843 -244.514544)
			(xy 340.105279 -244.479884) (xy 340.146548 -244.451147) (xy 340.191696 -244.428998) (xy 340.239679 -244.413948)
			(xy 340.28939 -244.406346) (xy 340.314534 -244.405912) (xy 340.340519 -244.406424) (xy 340.391848 -244.414559)
			(xy 340.441273 -244.430623) (xy 340.487576 -244.454221) (xy 340.529618 -244.484772) (xy 340.566363 -244.521523)
			(xy 340.596907 -244.56357) (xy 340.620497 -244.609877) (xy 340.636554 -244.659305) (xy 340.64468 -244.710635)
			(xy 340.645242 -244.73662) (xy 340.644771 -244.761761) (xy 340.644644 -244.762587) (xy 340.924135 -244.762587)
			(xy 340.924135 -244.710653) (xy 340.93226 -244.659358) (xy 340.948308 -244.609965) (xy 340.971886 -244.563691)
			(xy 341.002412 -244.521675) (xy 341.039135 -244.484952) (xy 341.081151 -244.454426) (xy 341.127425 -244.430848)
			(xy 341.176818 -244.4148) (xy 341.228113 -244.406675) (xy 341.280047 -244.406675) (xy 341.331342 -244.4148)
			(xy 341.380735 -244.430848) (xy 341.427009 -244.454426) (xy 341.469025 -244.484952) (xy 341.505748 -244.521675)
			(xy 341.536274 -244.563691) (xy 341.559852 -244.609965) (xy 341.5759 -244.659358) (xy 341.584025 -244.710653)
			(xy 341.584534 -244.73662) (xy 341.584025 -244.762587) (xy 341.863935 -244.762587) (xy 341.863935 -244.710653)
			(xy 341.87206 -244.659358) (xy 341.888108 -244.609965) (xy 341.911686 -244.563691) (xy 341.942212 -244.521675)
			(xy 341.978935 -244.484952) (xy 342.020951 -244.454426) (xy 342.067225 -244.430848) (xy 342.116618 -244.4148)
			(xy 342.167913 -244.406675) (xy 342.219847 -244.406675) (xy 342.271142 -244.4148) (xy 342.320535 -244.430848)
			(xy 342.366809 -244.454426) (xy 342.408825 -244.484952) (xy 342.445548 -244.521675) (xy 342.476074 -244.563691)
			(xy 342.499652 -244.609965) (xy 342.5157 -244.659358) (xy 342.523825 -244.710653) (xy 342.524334 -244.73662)
			(xy 342.523825 -244.762587) (xy 342.803735 -244.762587) (xy 342.803735 -244.710653) (xy 342.81186 -244.659358)
			(xy 342.827908 -244.609965) (xy 342.851486 -244.563691) (xy 342.882012 -244.521675) (xy 342.918735 -244.484952)
			(xy 342.960751 -244.454426) (xy 343.007025 -244.430848) (xy 343.056418 -244.4148) (xy 343.107713 -244.406675)
			(xy 343.159647 -244.406675) (xy 343.210942 -244.4148) (xy 343.260335 -244.430848) (xy 343.306609 -244.454426)
			(xy 343.348625 -244.484952) (xy 343.385348 -244.521675) (xy 343.415874 -244.563691) (xy 343.439452 -244.609965)
			(xy 343.4555 -244.659358) (xy 343.463625 -244.710653) (xy 343.464134 -244.73662) (xy 343.463625 -244.762587)
			(xy 343.743535 -244.762587) (xy 343.743535 -244.710653) (xy 343.75166 -244.659358) (xy 343.767708 -244.609965)
			(xy 343.791286 -244.563691) (xy 343.821812 -244.521675) (xy 343.858535 -244.484952) (xy 343.900551 -244.454426)
			(xy 343.946825 -244.430848) (xy 343.996218 -244.4148) (xy 344.047513 -244.406675) (xy 344.099447 -244.406675)
			(xy 344.150742 -244.4148) (xy 344.200135 -244.430848) (xy 344.246409 -244.454426) (xy 344.288425 -244.484952)
			(xy 344.325148 -244.521675) (xy 344.355674 -244.563691) (xy 344.379252 -244.609965) (xy 344.3953 -244.659358)
			(xy 344.403425 -244.710653) (xy 344.403934 -244.73662) (xy 344.403425 -244.762587) (xy 344.683589 -244.762587)
			(xy 344.683589 -244.710653) (xy 344.691714 -244.659358) (xy 344.707762 -244.609965) (xy 344.73134 -244.563691)
			(xy 344.761866 -244.521675) (xy 344.798589 -244.484952) (xy 344.840605 -244.454426) (xy 344.886879 -244.430848)
			(xy 344.936272 -244.4148) (xy 344.987567 -244.406675) (xy 345.039501 -244.406675) (xy 345.090796 -244.4148)
			(xy 345.140189 -244.430848) (xy 345.186463 -244.454426) (xy 345.228479 -244.484952) (xy 345.265202 -244.521675)
			(xy 345.295728 -244.563691) (xy 345.319306 -244.609965) (xy 345.335354 -244.659358) (xy 345.343479 -244.710653)
			(xy 345.343988 -244.73662) (xy 345.343479 -244.762587) (xy 345.623135 -244.762587) (xy 345.623135 -244.710653)
			(xy 345.63126 -244.659358) (xy 345.647308 -244.609965) (xy 345.670886 -244.563691) (xy 345.701412 -244.521675)
			(xy 345.738135 -244.484952) (xy 345.780151 -244.454426) (xy 345.826425 -244.430848) (xy 345.875818 -244.4148)
			(xy 345.927113 -244.406675) (xy 345.979047 -244.406675) (xy 346.030342 -244.4148) (xy 346.079735 -244.430848)
			(xy 346.126009 -244.454426) (xy 346.168025 -244.484952) (xy 346.204748 -244.521675) (xy 346.235274 -244.563691)
			(xy 346.258852 -244.609965) (xy 346.2749 -244.659358) (xy 346.283025 -244.710653) (xy 346.283534 -244.73662)
			(xy 346.283025 -244.762587) (xy 346.562935 -244.762587) (xy 346.562935 -244.710653) (xy 346.57106 -244.659358)
			(xy 346.587108 -244.609965) (xy 346.610686 -244.563691) (xy 346.641212 -244.521675) (xy 346.677935 -244.484952)
			(xy 346.719951 -244.454426) (xy 346.766225 -244.430848) (xy 346.815618 -244.4148) (xy 346.866913 -244.406675)
			(xy 346.918847 -244.406675) (xy 346.970142 -244.4148) (xy 347.019535 -244.430848) (xy 347.065809 -244.454426)
			(xy 347.107825 -244.484952) (xy 347.144548 -244.521675) (xy 347.175074 -244.563691) (xy 347.198652 -244.609965)
			(xy 347.2147 -244.659358) (xy 347.222825 -244.710653) (xy 347.223334 -244.73662) (xy 347.222825 -244.762587)
			(xy 347.502735 -244.762587) (xy 347.502735 -244.710653) (xy 347.51086 -244.659358) (xy 347.526908 -244.609965)
			(xy 347.550486 -244.563691) (xy 347.581012 -244.521675) (xy 347.617735 -244.484952) (xy 347.659751 -244.454426)
			(xy 347.706025 -244.430848) (xy 347.755418 -244.4148) (xy 347.806713 -244.406675) (xy 347.858647 -244.406675)
			(xy 347.909942 -244.4148) (xy 347.959335 -244.430848) (xy 348.005609 -244.454426) (xy 348.047625 -244.484952)
			(xy 348.084348 -244.521675) (xy 348.114874 -244.563691) (xy 348.138452 -244.609965) (xy 348.1545 -244.659358)
			(xy 348.162625 -244.710653) (xy 348.163134 -244.73662) (xy 348.162625 -244.762587) (xy 348.442535 -244.762587)
			(xy 348.442535 -244.710653) (xy 348.45066 -244.659358) (xy 348.466708 -244.609965) (xy 348.490286 -244.563691)
			(xy 348.520812 -244.521675) (xy 348.557535 -244.484952) (xy 348.599551 -244.454426) (xy 348.645825 -244.430848)
			(xy 348.695218 -244.4148) (xy 348.746513 -244.406675) (xy 348.798447 -244.406675) (xy 348.849742 -244.4148)
			(xy 348.899135 -244.430848) (xy 348.945409 -244.454426) (xy 348.987425 -244.484952) (xy 349.024148 -244.521675)
			(xy 349.054674 -244.563691) (xy 349.078252 -244.609965) (xy 349.0943 -244.659358) (xy 349.102425 -244.710653)
			(xy 349.102934 -244.73662) (xy 349.102425 -244.762587) (xy 349.382335 -244.762587) (xy 349.382335 -244.710653)
			(xy 349.39046 -244.659358) (xy 349.406508 -244.609965) (xy 349.430086 -244.563691) (xy 349.460612 -244.521675)
			(xy 349.497335 -244.484952) (xy 349.539351 -244.454426) (xy 349.585625 -244.430848) (xy 349.635018 -244.4148)
			(xy 349.686313 -244.406675) (xy 349.738247 -244.406675) (xy 349.789542 -244.4148) (xy 349.838935 -244.430848)
			(xy 349.885209 -244.454426) (xy 349.927225 -244.484952) (xy 349.963948 -244.521675) (xy 349.994474 -244.563691)
			(xy 350.018052 -244.609965) (xy 350.0341 -244.659358) (xy 350.042225 -244.710653) (xy 350.042734 -244.73662)
			(xy 350.042225 -244.762587) (xy 350.0341 -244.813882) (xy 350.018052 -244.863275) (xy 349.994474 -244.909549)
			(xy 349.963948 -244.951565) (xy 349.927225 -244.988288) (xy 349.885209 -245.018814) (xy 349.838935 -245.042392)
			(xy 349.789542 -245.05844) (xy 349.738247 -245.066565) (xy 349.686313 -245.066565) (xy 349.635018 -245.05844)
			(xy 349.585625 -245.042392) (xy 349.539351 -245.018814) (xy 349.497335 -244.988288) (xy 349.460612 -244.951565)
			(xy 349.430086 -244.909549) (xy 349.406508 -244.863275) (xy 349.39046 -244.813882) (xy 349.382335 -244.762587)
			(xy 349.102425 -244.762587) (xy 349.0943 -244.813882) (xy 349.078252 -244.863275) (xy 349.054674 -244.909549)
			(xy 349.024148 -244.951565) (xy 348.987425 -244.988288) (xy 348.945409 -245.018814) (xy 348.899135 -245.042392)
			(xy 348.849742 -245.05844) (xy 348.798447 -245.066565) (xy 348.746513 -245.066565) (xy 348.695218 -245.05844)
			(xy 348.645825 -245.042392) (xy 348.599551 -245.018814) (xy 348.557535 -244.988288) (xy 348.520812 -244.951565)
			(xy 348.490286 -244.909549) (xy 348.466708 -244.863275) (xy 348.45066 -244.813882) (xy 348.442535 -244.762587)
			(xy 348.162625 -244.762587) (xy 348.1545 -244.813882) (xy 348.138452 -244.863275) (xy 348.114874 -244.909549)
			(xy 348.084348 -244.951565) (xy 348.047625 -244.988288) (xy 348.005609 -245.018814) (xy 347.959335 -245.042392)
			(xy 347.909942 -245.05844) (xy 347.858647 -245.066565) (xy 347.806713 -245.066565) (xy 347.755418 -245.05844)
			(xy 347.706025 -245.042392) (xy 347.659751 -245.018814) (xy 347.617735 -244.988288) (xy 347.581012 -244.951565)
			(xy 347.550486 -244.909549) (xy 347.526908 -244.863275) (xy 347.51086 -244.813882) (xy 347.502735 -244.762587)
			(xy 347.222825 -244.762587) (xy 347.2147 -244.813882) (xy 347.198652 -244.863275) (xy 347.175074 -244.909549)
			(xy 347.144548 -244.951565) (xy 347.107825 -244.988288) (xy 347.065809 -245.018814) (xy 347.019535 -245.042392)
			(xy 346.970142 -245.05844) (xy 346.918847 -245.066565) (xy 346.866913 -245.066565) (xy 346.815618 -245.05844)
			(xy 346.766225 -245.042392) (xy 346.719951 -245.018814) (xy 346.677935 -244.988288) (xy 346.641212 -244.951565)
			(xy 346.610686 -244.909549) (xy 346.587108 -244.863275) (xy 346.57106 -244.813882) (xy 346.562935 -244.762587)
			(xy 346.283025 -244.762587) (xy 346.2749 -244.813882) (xy 346.258852 -244.863275) (xy 346.235274 -244.909549)
			(xy 346.204748 -244.951565) (xy 346.168025 -244.988288) (xy 346.126009 -245.018814) (xy 346.079735 -245.042392)
			(xy 346.030342 -245.05844) (xy 345.979047 -245.066565) (xy 345.927113 -245.066565) (xy 345.875818 -245.05844)
			(xy 345.826425 -245.042392) (xy 345.780151 -245.018814) (xy 345.738135 -244.988288) (xy 345.701412 -244.951565)
			(xy 345.670886 -244.909549) (xy 345.647308 -244.863275) (xy 345.63126 -244.813882) (xy 345.623135 -244.762587)
			(xy 345.343479 -244.762587) (xy 345.335354 -244.813882) (xy 345.319306 -244.863275) (xy 345.295728 -244.909549)
			(xy 345.265202 -244.951565) (xy 345.228479 -244.988288) (xy 345.186463 -245.018814) (xy 345.140189 -245.042392)
			(xy 345.090796 -245.05844) (xy 345.039501 -245.066565) (xy 344.987567 -245.066565) (xy 344.936272 -245.05844)
			(xy 344.886879 -245.042392) (xy 344.840605 -245.018814) (xy 344.798589 -244.988288) (xy 344.761866 -244.951565)
			(xy 344.73134 -244.909549) (xy 344.707762 -244.863275) (xy 344.691714 -244.813882) (xy 344.683589 -244.762587)
			(xy 344.403425 -244.762587) (xy 344.3953 -244.813882) (xy 344.379252 -244.863275) (xy 344.355674 -244.909549)
			(xy 344.325148 -244.951565) (xy 344.288425 -244.988288) (xy 344.246409 -245.018814) (xy 344.200135 -245.042392)
			(xy 344.150742 -245.05844) (xy 344.099447 -245.066565) (xy 344.047513 -245.066565) (xy 343.996218 -245.05844)
			(xy 343.946825 -245.042392) (xy 343.900551 -245.018814) (xy 343.858535 -244.988288) (xy 343.821812 -244.951565)
			(xy 343.791286 -244.909549) (xy 343.767708 -244.863275) (xy 343.75166 -244.813882) (xy 343.743535 -244.762587)
			(xy 343.463625 -244.762587) (xy 343.4555 -244.813882) (xy 343.439452 -244.863275) (xy 343.415874 -244.909549)
			(xy 343.385348 -244.951565) (xy 343.348625 -244.988288) (xy 343.306609 -245.018814) (xy 343.260335 -245.042392)
			(xy 343.210942 -245.05844) (xy 343.159647 -245.066565) (xy 343.107713 -245.066565) (xy 343.056418 -245.05844)
			(xy 343.007025 -245.042392) (xy 342.960751 -245.018814) (xy 342.918735 -244.988288) (xy 342.882012 -244.951565)
			(xy 342.851486 -244.909549) (xy 342.827908 -244.863275) (xy 342.81186 -244.813882) (xy 342.803735 -244.762587)
			(xy 342.523825 -244.762587) (xy 342.5157 -244.813882) (xy 342.499652 -244.863275) (xy 342.476074 -244.909549)
			(xy 342.445548 -244.951565) (xy 342.408825 -244.988288) (xy 342.366809 -245.018814) (xy 342.320535 -245.042392)
			(xy 342.271142 -245.05844) (xy 342.219847 -245.066565) (xy 342.167913 -245.066565) (xy 342.116618 -245.05844)
			(xy 342.067225 -245.042392) (xy 342.020951 -245.018814) (xy 341.978935 -244.988288) (xy 341.942212 -244.951565)
			(xy 341.911686 -244.909549) (xy 341.888108 -244.863275) (xy 341.87206 -244.813882) (xy 341.863935 -244.762587)
			(xy 341.584025 -244.762587) (xy 341.5759 -244.813882) (xy 341.559852 -244.863275) (xy 341.536274 -244.909549)
			(xy 341.505748 -244.951565) (xy 341.469025 -244.988288) (xy 341.427009 -245.018814) (xy 341.380735 -245.042392)
			(xy 341.331342 -245.05844) (xy 341.280047 -245.066565) (xy 341.228113 -245.066565) (xy 341.176818 -245.05844)
			(xy 341.127425 -245.042392) (xy 341.081151 -245.018814) (xy 341.039135 -244.988288) (xy 341.002412 -244.951565)
			(xy 340.971886 -244.909549) (xy 340.948308 -244.863275) (xy 340.93226 -244.813882) (xy 340.924135 -244.762587)
			(xy 340.644644 -244.762587) (xy 340.637155 -244.811464) (xy 340.6221 -244.85944) (xy 340.599955 -244.904583)
			(xy 340.57123 -244.945853) (xy 340.536587 -244.982298) (xy 340.496826 -245.013078) (xy 340.475062 -245.025672)
			(xy 340.471506 -245.027704) (xy 340.446106 -245.06428) (xy 340.434168 -245.146576) (xy 340.433654 -245.15757)
			(xy 340.441023 -245.178281) (xy 340.448392 -245.186454) (xy 340.533736 -245.271798) (xy 340.540975 -245.278509)
			(xy 340.55918 -245.286096) (xy 340.569042 -245.28653) (xy 340.597236 -245.27764) (xy 340.603078 -245.27383)
			(xy 340.623373 -245.261085) (xy 340.666858 -245.240946) (xy 340.712794 -245.22729) (xy 340.760219 -245.220403)
			(xy 340.78418 -245.219982) (xy 340.788752 -245.219982) (xy 340.814277 -245.220807) (xy 340.864626 -245.229351)
			(xy 340.913064 -245.245532) (xy 340.958439 -245.268965) (xy 340.999673 -245.299095) (xy 341.035785 -245.335204)
			(xy 341.065919 -245.376435) (xy 341.089357 -245.421808) (xy 341.105542 -245.470244) (xy 341.11409 -245.520592)
			(xy 341.114888 -245.546118) (xy 341.114888 -245.55069) (xy 341.114484 -245.574653) (xy 341.114193 -245.576657)
			(xy 341.394289 -245.576657) (xy 341.394289 -245.524723) (xy 341.402414 -245.473428) (xy 341.418462 -245.424035)
			(xy 341.44204 -245.377761) (xy 341.472566 -245.335745) (xy 341.509289 -245.299022) (xy 341.551305 -245.268496)
			(xy 341.597579 -245.244918) (xy 341.646972 -245.22887) (xy 341.698267 -245.220745) (xy 341.750201 -245.220745)
			(xy 341.801496 -245.22887) (xy 341.850889 -245.244918) (xy 341.897163 -245.268496) (xy 341.939179 -245.299022)
			(xy 341.975902 -245.335745) (xy 342.006428 -245.377761) (xy 342.030006 -245.424035) (xy 342.046054 -245.473428)
			(xy 342.054179 -245.524723) (xy 342.054688 -245.55069) (xy 342.054179 -245.576657) (xy 342.334089 -245.576657)
			(xy 342.334089 -245.524723) (xy 342.342214 -245.473428) (xy 342.358262 -245.424035) (xy 342.38184 -245.377761)
			(xy 342.412366 -245.335745) (xy 342.449089 -245.299022) (xy 342.491105 -245.268496) (xy 342.537379 -245.244918)
			(xy 342.586772 -245.22887) (xy 342.638067 -245.220745) (xy 342.690001 -245.220745) (xy 342.741296 -245.22887)
			(xy 342.790689 -245.244918) (xy 342.836963 -245.268496) (xy 342.878979 -245.299022) (xy 342.915702 -245.335745)
			(xy 342.946228 -245.377761) (xy 342.969806 -245.424035) (xy 342.985854 -245.473428) (xy 342.993979 -245.524723)
			(xy 342.994488 -245.55069) (xy 342.993979 -245.576657) (xy 343.273889 -245.576657) (xy 343.273889 -245.524723)
			(xy 343.282014 -245.473428) (xy 343.298062 -245.424035) (xy 343.32164 -245.377761) (xy 343.352166 -245.335745)
			(xy 343.388889 -245.299022) (xy 343.430905 -245.268496) (xy 343.477179 -245.244918) (xy 343.526572 -245.22887)
			(xy 343.577867 -245.220745) (xy 343.629801 -245.220745) (xy 343.681096 -245.22887) (xy 343.730489 -245.244918)
			(xy 343.776763 -245.268496) (xy 343.818779 -245.299022) (xy 343.855502 -245.335745) (xy 343.886028 -245.377761)
			(xy 343.909606 -245.424035) (xy 343.925654 -245.473428) (xy 343.933779 -245.524723) (xy 343.934288 -245.55069)
			(xy 343.933779 -245.576657) (xy 344.213689 -245.576657) (xy 344.213689 -245.524723) (xy 344.221814 -245.473428)
			(xy 344.237862 -245.424035) (xy 344.26144 -245.377761) (xy 344.291966 -245.335745) (xy 344.328689 -245.299022)
			(xy 344.370705 -245.268496) (xy 344.416979 -245.244918) (xy 344.466372 -245.22887) (xy 344.517667 -245.220745)
			(xy 344.569601 -245.220745) (xy 344.620896 -245.22887) (xy 344.670289 -245.244918) (xy 344.716563 -245.268496)
			(xy 344.758579 -245.299022) (xy 344.795302 -245.335745) (xy 344.825828 -245.377761) (xy 344.849406 -245.424035)
			(xy 344.865454 -245.473428) (xy 344.873579 -245.524723) (xy 344.874088 -245.55069) (xy 344.873579 -245.576657)
			(xy 345.153235 -245.576657) (xy 345.153235 -245.524723) (xy 345.16136 -245.473428) (xy 345.177408 -245.424035)
			(xy 345.200986 -245.377761) (xy 345.231512 -245.335745) (xy 345.268235 -245.299022) (xy 345.310251 -245.268496)
			(xy 345.356525 -245.244918) (xy 345.405918 -245.22887) (xy 345.457213 -245.220745) (xy 345.509147 -245.220745)
			(xy 345.560442 -245.22887) (xy 345.609835 -245.244918) (xy 345.656109 -245.268496) (xy 345.698125 -245.299022)
			(xy 345.734848 -245.335745) (xy 345.765374 -245.377761) (xy 345.788952 -245.424035) (xy 345.805 -245.473428)
			(xy 345.813125 -245.524723) (xy 345.813634 -245.55069) (xy 345.813125 -245.576657) (xy 346.093289 -245.576657)
			(xy 346.093289 -245.524723) (xy 346.101414 -245.473428) (xy 346.117462 -245.424035) (xy 346.14104 -245.377761)
			(xy 346.171566 -245.335745) (xy 346.208289 -245.299022) (xy 346.250305 -245.268496) (xy 346.296579 -245.244918)
			(xy 346.345972 -245.22887) (xy 346.397267 -245.220745) (xy 346.449201 -245.220745) (xy 346.500496 -245.22887)
			(xy 346.549889 -245.244918) (xy 346.596163 -245.268496) (xy 346.638179 -245.299022) (xy 346.674902 -245.335745)
			(xy 346.705428 -245.377761) (xy 346.729006 -245.424035) (xy 346.745054 -245.473428) (xy 346.753179 -245.524723)
			(xy 346.753688 -245.55069) (xy 346.753179 -245.576657) (xy 347.033089 -245.576657) (xy 347.033089 -245.524723)
			(xy 347.041214 -245.473428) (xy 347.057262 -245.424035) (xy 347.08084 -245.377761) (xy 347.111366 -245.335745)
			(xy 347.148089 -245.299022) (xy 347.190105 -245.268496) (xy 347.236379 -245.244918) (xy 347.285772 -245.22887)
			(xy 347.337067 -245.220745) (xy 347.389001 -245.220745) (xy 347.440296 -245.22887) (xy 347.489689 -245.244918)
			(xy 347.535963 -245.268496) (xy 347.577979 -245.299022) (xy 347.614702 -245.335745) (xy 347.645228 -245.377761)
			(xy 347.668806 -245.424035) (xy 347.684854 -245.473428) (xy 347.692979 -245.524723) (xy 347.693488 -245.55069)
			(xy 347.692979 -245.576657) (xy 347.972889 -245.576657) (xy 347.972889 -245.524723) (xy 347.981014 -245.473428)
			(xy 347.997062 -245.424035) (xy 348.02064 -245.377761) (xy 348.051166 -245.335745) (xy 348.087889 -245.299022)
			(xy 348.129905 -245.268496) (xy 348.176179 -245.244918) (xy 348.225572 -245.22887) (xy 348.276867 -245.220745)
			(xy 348.328801 -245.220745) (xy 348.380096 -245.22887) (xy 348.429489 -245.244918) (xy 348.475763 -245.268496)
			(xy 348.517779 -245.299022) (xy 348.554502 -245.335745) (xy 348.585028 -245.377761) (xy 348.608606 -245.424035)
			(xy 348.624654 -245.473428) (xy 348.632779 -245.524723) (xy 348.633288 -245.55069) (xy 348.632779 -245.576657)
			(xy 348.912689 -245.576657) (xy 348.912689 -245.524723) (xy 348.920814 -245.473428) (xy 348.936862 -245.424035)
			(xy 348.96044 -245.377761) (xy 348.990966 -245.335745) (xy 349.027689 -245.299022) (xy 349.069705 -245.268496)
			(xy 349.115979 -245.244918) (xy 349.165372 -245.22887) (xy 349.216667 -245.220745) (xy 349.268601 -245.220745)
			(xy 349.319896 -245.22887) (xy 349.369289 -245.244918) (xy 349.415563 -245.268496) (xy 349.457579 -245.299022)
			(xy 349.494302 -245.335745) (xy 349.524828 -245.377761) (xy 349.548406 -245.424035) (xy 349.564454 -245.473428)
			(xy 349.572579 -245.524723) (xy 349.573088 -245.55069) (xy 349.572579 -245.576657) (xy 349.572577 -245.576672)
			(xy 349.852419 -245.576672) (xy 349.852419 -245.524728) (xy 349.860545 -245.473424) (xy 349.876598 -245.424023)
			(xy 349.900181 -245.377742) (xy 349.930714 -245.33572) (xy 349.967446 -245.298992) (xy 350.009471 -245.268463)
			(xy 350.055755 -245.244885) (xy 350.105157 -245.228837) (xy 350.156462 -245.220716) (xy 350.182434 -245.220236)
			(xy 350.182688 -245.220236) (xy 350.208125 -245.22071) (xy 350.258399 -245.228507) (xy 350.306879 -245.243932)
			(xy 350.352414 -245.26662) (xy 350.373442 -245.280942) (xy 350.3847 -245.288444) (xy 350.410078 -245.297789)
			(xy 350.43702 -245.300131) (xy 350.46363 -245.295306) (xy 350.488035 -245.283655) (xy 350.508517 -245.265996)
			(xy 350.523636 -245.243573) (xy 350.528382 -245.230904) (xy 350.536056 -245.209436) (xy 350.556509 -245.168691)
			(xy 350.582366 -245.131142) (xy 350.59747 -245.114064) (xy 350.60729 -245.102587) (xy 350.620302 -245.075346)
			(xy 350.624768 -245.045488) (xy 350.620295 -245.015631) (xy 350.607276 -244.988393) (xy 350.59747 -244.976904)
			(xy 350.581202 -244.958541) (xy 350.553761 -244.917876) (xy 350.532636 -244.8736) (xy 350.518292 -244.826686)
			(xy 350.511045 -244.778167) (xy 350.510602 -244.753638) (xy 350.510602 -244.753384) (xy 350.511111 -244.727417)
			(xy 350.519236 -244.676122) (xy 350.535284 -244.626729) (xy 350.558862 -244.580455) (xy 350.589388 -244.538439)
			(xy 350.626111 -244.501716) (xy 350.668127 -244.47119) (xy 350.714401 -244.447612) (xy 350.763794 -244.431564)
			(xy 350.815089 -244.423439) (xy 350.867023 -244.423439) (xy 350.918318 -244.431564) (xy 350.967711 -244.447612)
			(xy 351.013985 -244.47119) (xy 351.056001 -244.501716) (xy 351.092724 -244.538439) (xy 351.12325 -244.580455)
			(xy 351.146828 -244.626729) (xy 351.162876 -244.676122) (xy 351.171001 -244.727417) (xy 351.17151 -244.753384)
			(xy 351.17151 -244.753638) (xy 351.171079 -244.778165) (xy 351.16381 -244.826679) (xy 351.149454 -244.873586)
			(xy 351.128324 -244.917857) (xy 351.100886 -244.958521) (xy 351.084642 -244.976904) (xy 351.074853 -244.988405)
			(xy 351.061835 -245.015637) (xy 351.057363 -245.045488) (xy 351.061828 -245.07534) (xy 351.074839 -245.102576)
			(xy 351.084642 -245.114064) (xy 351.10088 -245.132452) (xy 351.128329 -245.173108) (xy 351.149461 -245.217378)
			(xy 351.163812 -245.264287) (xy 351.171064 -245.312803) (xy 351.17151 -245.33733) (xy 351.17151 -245.337584)
			(xy 351.171341 -245.347236) (xy 356.04323 -245.347236) (xy 356.04323 -245.346982) (xy 356.043689 -245.322456)
			(xy 356.050953 -245.273944) (xy 356.065304 -245.227038) (xy 356.086427 -245.182766) (xy 356.113858 -245.142101)
			(xy 356.130098 -245.123716) (xy 356.139864 -245.112198) (xy 356.152879 -245.084971) (xy 356.157353 -245.055127)
			(xy 356.152895 -245.02528) (xy 356.139894 -244.998046) (xy 356.130098 -244.986556) (xy 356.113859 -244.968168)
			(xy 356.086413 -244.927511) (xy 356.065282 -244.883241) (xy 356.050931 -244.836332) (xy 356.043677 -244.787817)
			(xy 356.04323 -244.76329) (xy 356.04323 -244.763036) (xy 356.043739 -244.737069) (xy 356.051864 -244.685774)
			(xy 356.067912 -244.636381) (xy 356.09149 -244.590107) (xy 356.122016 -244.548091) (xy 356.158739 -244.511368)
			(xy 356.200755 -244.480842) (xy 356.247029 -244.457264) (xy 356.296422 -244.441216) (xy 356.347717 -244.433091)
			(xy 356.399651 -244.433091) (xy 356.450946 -244.441216) (xy 356.500339 -244.457264) (xy 356.546613 -244.480842)
			(xy 356.588629 -244.511368) (xy 356.625352 -244.548091) (xy 356.655878 -244.590107) (xy 356.679456 -244.636381)
			(xy 356.695504 -244.685774) (xy 356.703629 -244.737069) (xy 356.704129 -244.762587) (xy 356.900989 -244.762587)
			(xy 356.900989 -244.710653) (xy 356.909114 -244.659358) (xy 356.925162 -244.609965) (xy 356.94874 -244.563691)
			(xy 356.979266 -244.521675) (xy 357.015989 -244.484952) (xy 357.058005 -244.454426) (xy 357.104279 -244.430848)
			(xy 357.153672 -244.4148) (xy 357.204967 -244.406675) (xy 357.256901 -244.406675) (xy 357.308196 -244.4148)
			(xy 357.357589 -244.430848) (xy 357.403863 -244.454426) (xy 357.445879 -244.484952) (xy 357.482602 -244.521675)
			(xy 357.513128 -244.563691) (xy 357.536706 -244.609965) (xy 357.552754 -244.659358) (xy 357.560879 -244.710653)
			(xy 357.561388 -244.73662) (xy 357.560879 -244.762587) (xy 357.840789 -244.762587) (xy 357.840789 -244.710653)
			(xy 357.848914 -244.659358) (xy 357.864962 -244.609965) (xy 357.88854 -244.563691) (xy 357.919066 -244.521675)
			(xy 357.955789 -244.484952) (xy 357.997805 -244.454426) (xy 358.044079 -244.430848) (xy 358.093472 -244.4148)
			(xy 358.144767 -244.406675) (xy 358.196701 -244.406675) (xy 358.247996 -244.4148) (xy 358.297389 -244.430848)
			(xy 358.343663 -244.454426) (xy 358.385679 -244.484952) (xy 358.422402 -244.521675) (xy 358.452928 -244.563691)
			(xy 358.476506 -244.609965) (xy 358.492554 -244.659358) (xy 358.500679 -244.710653) (xy 358.501188 -244.73662)
			(xy 358.500679 -244.762587) (xy 358.780589 -244.762587) (xy 358.780589 -244.710653) (xy 358.788714 -244.659358)
			(xy 358.804762 -244.609965) (xy 358.82834 -244.563691) (xy 358.858866 -244.521675) (xy 358.895589 -244.484952)
			(xy 358.937605 -244.454426) (xy 358.983879 -244.430848) (xy 359.033272 -244.4148) (xy 359.084567 -244.406675)
			(xy 359.136501 -244.406675) (xy 359.187796 -244.4148) (xy 359.237189 -244.430848) (xy 359.283463 -244.454426)
			(xy 359.325479 -244.484952) (xy 359.362202 -244.521675) (xy 359.392728 -244.563691) (xy 359.416306 -244.609965)
			(xy 359.432354 -244.659358) (xy 359.440479 -244.710653) (xy 359.440988 -244.73662) (xy 359.440479 -244.762587)
			(xy 359.720389 -244.762587) (xy 359.720389 -244.710653) (xy 359.728514 -244.659358) (xy 359.744562 -244.609965)
			(xy 359.76814 -244.563691) (xy 359.798666 -244.521675) (xy 359.835389 -244.484952) (xy 359.877405 -244.454426)
			(xy 359.923679 -244.430848) (xy 359.973072 -244.4148) (xy 360.024367 -244.406675) (xy 360.076301 -244.406675)
			(xy 360.127596 -244.4148) (xy 360.176989 -244.430848) (xy 360.223263 -244.454426) (xy 360.265279 -244.484952)
			(xy 360.302002 -244.521675) (xy 360.332528 -244.563691) (xy 360.356106 -244.609965) (xy 360.372154 -244.659358)
			(xy 360.380279 -244.710653) (xy 360.380788 -244.73662) (xy 360.380279 -244.762587) (xy 360.659935 -244.762587)
			(xy 360.659935 -244.710653) (xy 360.66806 -244.659358) (xy 360.684108 -244.609965) (xy 360.707686 -244.563691)
			(xy 360.738212 -244.521675) (xy 360.774935 -244.484952) (xy 360.816951 -244.454426) (xy 360.863225 -244.430848)
			(xy 360.912618 -244.4148) (xy 360.963913 -244.406675) (xy 361.015847 -244.406675) (xy 361.067142 -244.4148)
			(xy 361.116535 -244.430848) (xy 361.162809 -244.454426) (xy 361.204825 -244.484952) (xy 361.241548 -244.521675)
			(xy 361.272074 -244.563691) (xy 361.295652 -244.609965) (xy 361.3117 -244.659358) (xy 361.319825 -244.710653)
			(xy 361.320334 -244.73662) (xy 361.319825 -244.762587) (xy 361.599989 -244.762587) (xy 361.599989 -244.710653)
			(xy 361.608114 -244.659358) (xy 361.624162 -244.609965) (xy 361.64774 -244.563691) (xy 361.678266 -244.521675)
			(xy 361.714989 -244.484952) (xy 361.757005 -244.454426) (xy 361.803279 -244.430848) (xy 361.852672 -244.4148)
			(xy 361.903967 -244.406675) (xy 361.955901 -244.406675) (xy 362.007196 -244.4148) (xy 362.056589 -244.430848)
			(xy 362.102863 -244.454426) (xy 362.144879 -244.484952) (xy 362.181602 -244.521675) (xy 362.212128 -244.563691)
			(xy 362.235706 -244.609965) (xy 362.251754 -244.659358) (xy 362.259879 -244.710653) (xy 362.260388 -244.73662)
			(xy 362.259879 -244.762587) (xy 362.251754 -244.813882) (xy 362.235706 -244.863275) (xy 362.212128 -244.909549)
			(xy 362.181602 -244.951565) (xy 362.144879 -244.988288) (xy 362.102863 -245.018814) (xy 362.056589 -245.042392)
			(xy 362.007196 -245.05844) (xy 361.955901 -245.066565) (xy 361.903967 -245.066565) (xy 361.852672 -245.05844)
			(xy 361.803279 -245.042392) (xy 361.757005 -245.018814) (xy 361.714989 -244.988288) (xy 361.678266 -244.951565)
			(xy 361.64774 -244.909549) (xy 361.624162 -244.863275) (xy 361.608114 -244.813882) (xy 361.599989 -244.762587)
			(xy 361.319825 -244.762587) (xy 361.3117 -244.813882) (xy 361.295652 -244.863275) (xy 361.272074 -244.909549)
			(xy 361.241548 -244.951565) (xy 361.204825 -244.988288) (xy 361.162809 -245.018814) (xy 361.116535 -245.042392)
			(xy 361.067142 -245.05844) (xy 361.015847 -245.066565) (xy 360.963913 -245.066565) (xy 360.912618 -245.05844)
			(xy 360.863225 -245.042392) (xy 360.816951 -245.018814) (xy 360.774935 -244.988288) (xy 360.738212 -244.951565)
			(xy 360.707686 -244.909549) (xy 360.684108 -244.863275) (xy 360.66806 -244.813882) (xy 360.659935 -244.762587)
			(xy 360.380279 -244.762587) (xy 360.372154 -244.813882) (xy 360.356106 -244.863275) (xy 360.332528 -244.909549)
			(xy 360.302002 -244.951565) (xy 360.265279 -244.988288) (xy 360.223263 -245.018814) (xy 360.176989 -245.042392)
			(xy 360.127596 -245.05844) (xy 360.076301 -245.066565) (xy 360.024367 -245.066565) (xy 359.973072 -245.05844)
			(xy 359.923679 -245.042392) (xy 359.877405 -245.018814) (xy 359.835389 -244.988288) (xy 359.798666 -244.951565)
			(xy 359.76814 -244.909549) (xy 359.744562 -244.863275) (xy 359.728514 -244.813882) (xy 359.720389 -244.762587)
			(xy 359.440479 -244.762587) (xy 359.432354 -244.813882) (xy 359.416306 -244.863275) (xy 359.392728 -244.909549)
			(xy 359.362202 -244.951565) (xy 359.325479 -244.988288) (xy 359.283463 -245.018814) (xy 359.237189 -245.042392)
			(xy 359.187796 -245.05844) (xy 359.136501 -245.066565) (xy 359.084567 -245.066565) (xy 359.033272 -245.05844)
			(xy 358.983879 -245.042392) (xy 358.937605 -245.018814) (xy 358.895589 -244.988288) (xy 358.858866 -244.951565)
			(xy 358.82834 -244.909549) (xy 358.804762 -244.863275) (xy 358.788714 -244.813882) (xy 358.780589 -244.762587)
			(xy 358.500679 -244.762587) (xy 358.492554 -244.813882) (xy 358.476506 -244.863275) (xy 358.452928 -244.909549)
			(xy 358.422402 -244.951565) (xy 358.385679 -244.988288) (xy 358.343663 -245.018814) (xy 358.297389 -245.042392)
			(xy 358.247996 -245.05844) (xy 358.196701 -245.066565) (xy 358.144767 -245.066565) (xy 358.093472 -245.05844)
			(xy 358.044079 -245.042392) (xy 357.997805 -245.018814) (xy 357.955789 -244.988288) (xy 357.919066 -244.951565)
			(xy 357.88854 -244.909549) (xy 357.864962 -244.863275) (xy 357.848914 -244.813882) (xy 357.840789 -244.762587)
			(xy 357.560879 -244.762587) (xy 357.552754 -244.813882) (xy 357.536706 -244.863275) (xy 357.513128 -244.909549)
			(xy 357.482602 -244.951565) (xy 357.445879 -244.988288) (xy 357.403863 -245.018814) (xy 357.357589 -245.042392)
			(xy 357.308196 -245.05844) (xy 357.256901 -245.066565) (xy 357.204967 -245.066565) (xy 357.153672 -245.05844)
			(xy 357.104279 -245.042392) (xy 357.058005 -245.018814) (xy 357.015989 -244.988288) (xy 356.979266 -244.951565)
			(xy 356.94874 -244.909549) (xy 356.925162 -244.863275) (xy 356.909114 -244.813882) (xy 356.900989 -244.762587)
			(xy 356.704129 -244.762587) (xy 356.704138 -244.763036) (xy 356.704138 -244.76329) (xy 356.70367 -244.787816)
			(xy 356.69641 -244.836328) (xy 356.682062 -244.883234) (xy 356.66094 -244.927506) (xy 356.63351 -244.968171)
			(xy 356.61727 -244.986556) (xy 356.607428 -244.998016) (xy 356.594412 -245.025263) (xy 356.589948 -245.055127)
			(xy 356.594428 -245.084988) (xy 356.607457 -245.112228) (xy 356.61727 -245.123716) (xy 356.633538 -245.142079)
			(xy 356.660981 -245.182743) (xy 356.682107 -245.227019) (xy 356.696451 -245.273933) (xy 356.703696 -245.322453)
			(xy 356.704138 -245.346982) (xy 356.704138 -245.347236) (xy 356.703629 -245.373203) (xy 356.695504 -245.424498)
			(xy 356.679456 -245.473891) (xy 356.655878 -245.520165) (xy 356.625352 -245.562181) (xy 356.610876 -245.576657)
			(xy 357.370635 -245.576657) (xy 357.370635 -245.524723) (xy 357.37876 -245.473428) (xy 357.394808 -245.424035)
			(xy 357.418386 -245.377761) (xy 357.448912 -245.335745) (xy 357.485635 -245.299022) (xy 357.527651 -245.268496)
			(xy 357.573925 -245.244918) (xy 357.623318 -245.22887) (xy 357.674613 -245.220745) (xy 357.726547 -245.220745)
			(xy 357.777842 -245.22887) (xy 357.827235 -245.244918) (xy 357.873509 -245.268496) (xy 357.915525 -245.299022)
			(xy 357.952248 -245.335745) (xy 357.982774 -245.377761) (xy 358.006352 -245.424035) (xy 358.0224 -245.473428)
			(xy 358.030525 -245.524723) (xy 358.031034 -245.55069) (xy 358.030525 -245.576657) (xy 358.310689 -245.576657)
			(xy 358.310689 -245.524723) (xy 358.318814 -245.473428) (xy 358.334862 -245.424035) (xy 358.35844 -245.377761)
			(xy 358.388966 -245.335745) (xy 358.425689 -245.299022) (xy 358.467705 -245.268496) (xy 358.513979 -245.244918)
			(xy 358.563372 -245.22887) (xy 358.614667 -245.220745) (xy 358.666601 -245.220745) (xy 358.717896 -245.22887)
			(xy 358.767289 -245.244918) (xy 358.813563 -245.268496) (xy 358.855579 -245.299022) (xy 358.892302 -245.335745)
			(xy 358.922828 -245.377761) (xy 358.946406 -245.424035) (xy 358.962454 -245.473428) (xy 358.970579 -245.524723)
			(xy 358.971088 -245.55069) (xy 358.970579 -245.576657) (xy 359.250235 -245.576657) (xy 359.250235 -245.524723)
			(xy 359.25836 -245.473428) (xy 359.274408 -245.424035) (xy 359.297986 -245.377761) (xy 359.328512 -245.335745)
			(xy 359.365235 -245.299022) (xy 359.407251 -245.268496) (xy 359.453525 -245.244918) (xy 359.502918 -245.22887)
			(xy 359.554213 -245.220745) (xy 359.606147 -245.220745) (xy 359.657442 -245.22887) (xy 359.706835 -245.244918)
			(xy 359.753109 -245.268496) (xy 359.795125 -245.299022) (xy 359.831848 -245.335745) (xy 359.862374 -245.377761)
			(xy 359.885952 -245.424035) (xy 359.902 -245.473428) (xy 359.910125 -245.524723) (xy 359.910634 -245.55069)
			(xy 359.910125 -245.576657) (xy 360.190035 -245.576657) (xy 360.190035 -245.524723) (xy 360.19816 -245.473428)
			(xy 360.214208 -245.424035) (xy 360.237786 -245.377761) (xy 360.268312 -245.335745) (xy 360.305035 -245.299022)
			(xy 360.347051 -245.268496) (xy 360.393325 -245.244918) (xy 360.442718 -245.22887) (xy 360.494013 -245.220745)
			(xy 360.545947 -245.220745) (xy 360.597242 -245.22887) (xy 360.646635 -245.244918) (xy 360.692909 -245.268496)
			(xy 360.734925 -245.299022) (xy 360.771648 -245.335745) (xy 360.802174 -245.377761) (xy 360.825752 -245.424035)
			(xy 360.8418 -245.473428) (xy 360.849925 -245.524723) (xy 360.850434 -245.55069) (xy 360.849925 -245.576657)
			(xy 361.130089 -245.576657) (xy 361.130089 -245.524723) (xy 361.138214 -245.473428) (xy 361.154262 -245.424035)
			(xy 361.17784 -245.377761) (xy 361.208366 -245.335745) (xy 361.245089 -245.299022) (xy 361.287105 -245.268496)
			(xy 361.333379 -245.244918) (xy 361.382772 -245.22887) (xy 361.434067 -245.220745) (xy 361.486001 -245.220745)
			(xy 361.537296 -245.22887) (xy 361.586689 -245.244918) (xy 361.632963 -245.268496) (xy 361.674979 -245.299022)
			(xy 361.711702 -245.335745) (xy 361.742228 -245.377761) (xy 361.765806 -245.424035) (xy 361.781854 -245.473428)
			(xy 361.789979 -245.524723) (xy 361.790488 -245.55069) (xy 361.789979 -245.576657) (xy 362.069889 -245.576657)
			(xy 362.069889 -245.524723) (xy 362.078014 -245.473428) (xy 362.094062 -245.424035) (xy 362.11764 -245.377761)
			(xy 362.148166 -245.335745) (xy 362.184889 -245.299022) (xy 362.226905 -245.268496) (xy 362.273179 -245.244918)
			(xy 362.322572 -245.22887) (xy 362.373867 -245.220745) (xy 362.425801 -245.220745) (xy 362.477096 -245.22887)
			(xy 362.526489 -245.244918) (xy 362.572763 -245.268496) (xy 362.614779 -245.299022) (xy 362.651502 -245.335745)
			(xy 362.682028 -245.377761) (xy 362.691582 -245.396512) (xy 363.025182 -245.396512) (xy 363.025182 -245.396258)
			(xy 363.025613 -245.371731) (xy 363.032882 -245.323217) (xy 363.047238 -245.27631) (xy 363.068368 -245.232039)
			(xy 363.095806 -245.191375) (xy 363.11205 -245.172992) (xy 363.121844 -245.161495) (xy 363.134862 -245.134261)
			(xy 363.139334 -245.104409) (xy 363.134867 -245.074556) (xy 363.121854 -245.04732) (xy 363.11205 -245.035832)
			(xy 363.095808 -245.017447) (xy 363.06836 -244.976789) (xy 363.047229 -244.932519) (xy 363.032879 -244.88561)
			(xy 363.025627 -244.837094) (xy 363.025182 -244.812566) (xy 363.025182 -244.812312) (xy 363.025691 -244.786345)
			(xy 363.033816 -244.73505) (xy 363.049864 -244.685657) (xy 363.073442 -244.639383) (xy 363.103968 -244.597367)
			(xy 363.140691 -244.560644) (xy 363.182707 -244.530118) (xy 363.228981 -244.50654) (xy 363.278374 -244.490492)
			(xy 363.329669 -244.482367) (xy 363.381603 -244.482367) (xy 363.432898 -244.490492) (xy 363.482291 -244.50654)
			(xy 363.528565 -244.530118) (xy 363.570581 -244.560644) (xy 363.607304 -244.597367) (xy 363.63783 -244.639383)
			(xy 363.661408 -244.685657) (xy 363.677456 -244.73505) (xy 363.685581 -244.786345) (xy 363.68609 -244.812312)
			(xy 363.68609 -244.812566) (xy 363.68562 -244.837092) (xy 363.678362 -244.885604) (xy 363.664015 -244.932511)
			(xy 363.642894 -244.976783) (xy 363.615463 -245.017448) (xy 363.599222 -245.035832) (xy 363.589407 -245.047312)
			(xy 363.576395 -245.074552) (xy 363.571929 -245.104409) (xy 363.5764 -245.134265) (xy 363.589417 -245.161503)
			(xy 363.599222 -245.172992) (xy 363.615487 -245.191358) (xy 363.642929 -245.232021) (xy 363.664054 -245.276297)
			(xy 363.678399 -245.32321) (xy 363.685647 -245.371729) (xy 363.68609 -245.396258) (xy 363.68609 -245.396512)
			(xy 363.685581 -245.422479) (xy 363.677456 -245.473774) (xy 363.661408 -245.523167) (xy 363.63783 -245.569441)
			(xy 363.616391 -245.59895) (xy 368.58575 -245.59895) (xy 368.58575 -245.598696) (xy 368.586212 -245.57417)
			(xy 368.593475 -245.525658) (xy 368.607824 -245.478752) (xy 368.628947 -245.43448) (xy 368.656378 -245.393815)
			(xy 368.672618 -245.37543) (xy 368.682369 -245.363901) (xy 368.695383 -245.336677) (xy 368.699859 -245.306837)
			(xy 368.695404 -245.276993) (xy 368.682411 -245.24976) (xy 368.672618 -245.23827) (xy 368.656373 -245.219854)
			(xy 368.628903 -245.179153) (xy 368.607761 -245.134833) (xy 368.593415 -245.087871) (xy 368.586181 -245.039302)
			(xy 368.58575 -245.01475) (xy 368.586195 -244.990198) (xy 368.593435 -244.941632) (xy 368.607778 -244.89467)
			(xy 368.628909 -244.850346) (xy 368.656362 -244.809635) (xy 368.672618 -244.79123) (xy 368.682369 -244.779701)
			(xy 368.695383 -244.752477) (xy 368.699859 -244.722637) (xy 368.695404 -244.692793) (xy 368.682411 -244.66556)
			(xy 368.672618 -244.65407) (xy 368.656373 -244.635654) (xy 368.628903 -244.594953) (xy 368.607761 -244.550633)
			(xy 368.593415 -244.503671) (xy 368.586181 -244.455102) (xy 368.58575 -244.43055) (xy 368.586195 -244.405998)
			(xy 368.593435 -244.357432) (xy 368.607778 -244.31047) (xy 368.628909 -244.266146) (xy 368.656362 -244.225435)
			(xy 368.672618 -244.20703) (xy 368.682369 -244.195501) (xy 368.695383 -244.168277) (xy 368.699859 -244.138437)
			(xy 368.695404 -244.108593) (xy 368.682411 -244.08136) (xy 368.672618 -244.06987) (xy 368.656389 -244.051474)
			(xy 368.62894 -244.010819) (xy 368.607807 -243.966551) (xy 368.593455 -243.919645) (xy 368.586198 -243.871131)
			(xy 368.58575 -243.846604) (xy 368.58575 -243.84635) (xy 368.586259 -243.820383) (xy 368.594384 -243.769088)
			(xy 368.610432 -243.719695) (xy 368.63401 -243.673421) (xy 368.664536 -243.631405) (xy 368.701259 -243.594682)
			(xy 368.743275 -243.564156) (xy 368.789549 -243.540578) (xy 368.838942 -243.52453) (xy 368.890237 -243.516405)
			(xy 368.942171 -243.516405) (xy 368.993466 -243.52453) (xy 369.042859 -243.540578) (xy 369.089133 -243.564156)
			(xy 369.131149 -243.594682) (xy 369.167872 -243.631405) (xy 369.198398 -243.673421) (xy 369.221976 -243.719695)
			(xy 369.238024 -243.769088) (xy 369.246149 -243.820383) (xy 369.246658 -243.84635) (xy 369.246658 -243.846604)
			(xy 369.246194 -243.87113) (xy 369.238931 -243.919642) (xy 369.23002 -243.948771) (xy 369.588035 -243.948771)
			(xy 369.588035 -243.896837) (xy 369.59616 -243.845542) (xy 369.612208 -243.796149) (xy 369.635786 -243.749875)
			(xy 369.666312 -243.707859) (xy 369.703035 -243.671136) (xy 369.745051 -243.64061) (xy 369.791325 -243.617032)
			(xy 369.840718 -243.600984) (xy 369.892013 -243.592859) (xy 369.943947 -243.592859) (xy 369.995242 -243.600984)
			(xy 370.044635 -243.617032) (xy 370.090909 -243.64061) (xy 370.132925 -243.671136) (xy 370.169648 -243.707859)
			(xy 370.200174 -243.749875) (xy 370.223752 -243.796149) (xy 370.2398 -243.845542) (xy 370.247925 -243.896837)
			(xy 370.248434 -243.922804) (xy 370.247925 -243.948771) (xy 370.527835 -243.948771) (xy 370.527835 -243.896837)
			(xy 370.53596 -243.845542) (xy 370.552008 -243.796149) (xy 370.575586 -243.749875) (xy 370.606112 -243.707859)
			(xy 370.642835 -243.671136) (xy 370.684851 -243.64061) (xy 370.731125 -243.617032) (xy 370.780518 -243.600984)
			(xy 370.831813 -243.592859) (xy 370.883747 -243.592859) (xy 370.935042 -243.600984) (xy 370.984435 -243.617032)
			(xy 371.030709 -243.64061) (xy 371.072725 -243.671136) (xy 371.109448 -243.707859) (xy 371.139974 -243.749875)
			(xy 371.163552 -243.796149) (xy 371.1796 -243.845542) (xy 371.187725 -243.896837) (xy 371.188234 -243.922804)
			(xy 371.187725 -243.948771) (xy 371.467889 -243.948771) (xy 371.467889 -243.896837) (xy 371.476014 -243.845542)
			(xy 371.492062 -243.796149) (xy 371.51564 -243.749875) (xy 371.546166 -243.707859) (xy 371.582889 -243.671136)
			(xy 371.624905 -243.64061) (xy 371.671179 -243.617032) (xy 371.720572 -243.600984) (xy 371.771867 -243.592859)
			(xy 371.823801 -243.592859) (xy 371.875096 -243.600984) (xy 371.924489 -243.617032) (xy 371.970763 -243.64061)
			(xy 372.012779 -243.671136) (xy 372.049502 -243.707859) (xy 372.080028 -243.749875) (xy 372.103606 -243.796149)
			(xy 372.119654 -243.845542) (xy 372.127779 -243.896837) (xy 372.128288 -243.922804) (xy 372.127779 -243.948771)
			(xy 372.407689 -243.948771) (xy 372.407689 -243.896837) (xy 372.415814 -243.845542) (xy 372.431862 -243.796149)
			(xy 372.45544 -243.749875) (xy 372.485966 -243.707859) (xy 372.522689 -243.671136) (xy 372.564705 -243.64061)
			(xy 372.610979 -243.617032) (xy 372.660372 -243.600984) (xy 372.711667 -243.592859) (xy 372.763601 -243.592859)
			(xy 372.814896 -243.600984) (xy 372.864289 -243.617032) (xy 372.910563 -243.64061) (xy 372.952579 -243.671136)
			(xy 372.989302 -243.707859) (xy 373.019828 -243.749875) (xy 373.043406 -243.796149) (xy 373.059454 -243.845542)
			(xy 373.067579 -243.896837) (xy 373.068088 -243.922804) (xy 373.067579 -243.948771) (xy 373.347489 -243.948771)
			(xy 373.347489 -243.896837) (xy 373.355614 -243.845542) (xy 373.371662 -243.796149) (xy 373.39524 -243.749875)
			(xy 373.425766 -243.707859) (xy 373.462489 -243.671136) (xy 373.504505 -243.64061) (xy 373.550779 -243.617032)
			(xy 373.600172 -243.600984) (xy 373.651467 -243.592859) (xy 373.703401 -243.592859) (xy 373.754696 -243.600984)
			(xy 373.804089 -243.617032) (xy 373.850363 -243.64061) (xy 373.892379 -243.671136) (xy 373.929102 -243.707859)
			(xy 373.959628 -243.749875) (xy 373.983206 -243.796149) (xy 373.999254 -243.845542) (xy 374.007379 -243.896837)
			(xy 374.007888 -243.922804) (xy 374.007379 -243.948771) (xy 374.287289 -243.948771) (xy 374.287289 -243.896837)
			(xy 374.295414 -243.845542) (xy 374.311462 -243.796149) (xy 374.33504 -243.749875) (xy 374.365566 -243.707859)
			(xy 374.402289 -243.671136) (xy 374.444305 -243.64061) (xy 374.490579 -243.617032) (xy 374.539972 -243.600984)
			(xy 374.591267 -243.592859) (xy 374.643201 -243.592859) (xy 374.694496 -243.600984) (xy 374.743889 -243.617032)
			(xy 374.790163 -243.64061) (xy 374.832179 -243.671136) (xy 374.868902 -243.707859) (xy 374.899428 -243.749875)
			(xy 374.923006 -243.796149) (xy 374.939054 -243.845542) (xy 374.947179 -243.896837) (xy 374.947688 -243.922804)
			(xy 374.947179 -243.948771) (xy 375.227089 -243.948771) (xy 375.227089 -243.896837) (xy 375.235214 -243.845542)
			(xy 375.251262 -243.796149) (xy 375.27484 -243.749875) (xy 375.305366 -243.707859) (xy 375.342089 -243.671136)
			(xy 375.384105 -243.64061) (xy 375.430379 -243.617032) (xy 375.479772 -243.600984) (xy 375.531067 -243.592859)
			(xy 375.583001 -243.592859) (xy 375.634296 -243.600984) (xy 375.683689 -243.617032) (xy 375.729963 -243.64061)
			(xy 375.771979 -243.671136) (xy 375.808702 -243.707859) (xy 375.839228 -243.749875) (xy 375.862806 -243.796149)
			(xy 375.878854 -243.845542) (xy 375.886979 -243.896837) (xy 375.887488 -243.922804) (xy 375.886979 -243.948771)
			(xy 376.166889 -243.948771) (xy 376.166889 -243.896837) (xy 376.175014 -243.845542) (xy 376.191062 -243.796149)
			(xy 376.21464 -243.749875) (xy 376.245166 -243.707859) (xy 376.281889 -243.671136) (xy 376.323905 -243.64061)
			(xy 376.370179 -243.617032) (xy 376.419572 -243.600984) (xy 376.470867 -243.592859) (xy 376.522801 -243.592859)
			(xy 376.574096 -243.600984) (xy 376.623489 -243.617032) (xy 376.669763 -243.64061) (xy 376.711779 -243.671136)
			(xy 376.748502 -243.707859) (xy 376.779028 -243.749875) (xy 376.802606 -243.796149) (xy 376.818654 -243.845542)
			(xy 376.826779 -243.896837) (xy 376.827288 -243.922804) (xy 376.826779 -243.948771) (xy 377.106435 -243.948771)
			(xy 377.106435 -243.896837) (xy 377.11456 -243.845542) (xy 377.130608 -243.796149) (xy 377.154186 -243.749875)
			(xy 377.184712 -243.707859) (xy 377.221435 -243.671136) (xy 377.263451 -243.64061) (xy 377.309725 -243.617032)
			(xy 377.359118 -243.600984) (xy 377.410413 -243.592859) (xy 377.462347 -243.592859) (xy 377.513642 -243.600984)
			(xy 377.563035 -243.617032) (xy 377.609309 -243.64061) (xy 377.651325 -243.671136) (xy 377.688048 -243.707859)
			(xy 377.718574 -243.749875) (xy 377.742152 -243.796149) (xy 377.7582 -243.845542) (xy 377.766325 -243.896837)
			(xy 377.766834 -243.922804) (xy 377.766325 -243.948771) (xy 378.046489 -243.948771) (xy 378.046489 -243.896837)
			(xy 378.054614 -243.845542) (xy 378.070662 -243.796149) (xy 378.09424 -243.749875) (xy 378.124766 -243.707859)
			(xy 378.161489 -243.671136) (xy 378.203505 -243.64061) (xy 378.249779 -243.617032) (xy 378.299172 -243.600984)
			(xy 378.350467 -243.592859) (xy 378.402401 -243.592859) (xy 378.453696 -243.600984) (xy 378.503089 -243.617032)
			(xy 378.549363 -243.64061) (xy 378.591379 -243.671136) (xy 378.628102 -243.707859) (xy 378.658628 -243.749875)
			(xy 378.682206 -243.796149) (xy 378.698254 -243.845542) (xy 378.706379 -243.896837) (xy 378.706888 -243.922804)
			(xy 378.706379 -243.948771) (xy 378.986289 -243.948771) (xy 378.986289 -243.896837) (xy 378.994414 -243.845542)
			(xy 379.010462 -243.796149) (xy 379.03404 -243.749875) (xy 379.064566 -243.707859) (xy 379.101289 -243.671136)
			(xy 379.143305 -243.64061) (xy 379.189579 -243.617032) (xy 379.238972 -243.600984) (xy 379.290267 -243.592859)
			(xy 379.342201 -243.592859) (xy 379.393496 -243.600984) (xy 379.442889 -243.617032) (xy 379.489163 -243.64061)
			(xy 379.531179 -243.671136) (xy 379.567902 -243.707859) (xy 379.598428 -243.749875) (xy 379.622006 -243.796149)
			(xy 379.638054 -243.845542) (xy 379.646179 -243.896837) (xy 379.646688 -243.922804) (xy 379.646179 -243.948771)
			(xy 379.638054 -244.000066) (xy 379.622006 -244.049459) (xy 379.598428 -244.095733) (xy 379.567902 -244.137749)
			(xy 379.531179 -244.174472) (xy 379.489163 -244.204998) (xy 379.442889 -244.228576) (xy 379.393496 -244.244624)
			(xy 379.342201 -244.252749) (xy 379.290267 -244.252749) (xy 379.238972 -244.244624) (xy 379.189579 -244.228576)
			(xy 379.143305 -244.204998) (xy 379.101289 -244.174472) (xy 379.064566 -244.137749) (xy 379.03404 -244.095733)
			(xy 379.010462 -244.049459) (xy 378.994414 -244.000066) (xy 378.986289 -243.948771) (xy 378.706379 -243.948771)
			(xy 378.698254 -244.000066) (xy 378.682206 -244.049459) (xy 378.658628 -244.095733) (xy 378.628102 -244.137749)
			(xy 378.591379 -244.174472) (xy 378.549363 -244.204998) (xy 378.503089 -244.228576) (xy 378.453696 -244.244624)
			(xy 378.402401 -244.252749) (xy 378.350467 -244.252749) (xy 378.299172 -244.244624) (xy 378.249779 -244.228576)
			(xy 378.203505 -244.204998) (xy 378.161489 -244.174472) (xy 378.124766 -244.137749) (xy 378.09424 -244.095733)
			(xy 378.070662 -244.049459) (xy 378.054614 -244.000066) (xy 378.046489 -243.948771) (xy 377.766325 -243.948771)
			(xy 377.7582 -244.000066) (xy 377.742152 -244.049459) (xy 377.718574 -244.095733) (xy 377.688048 -244.137749)
			(xy 377.651325 -244.174472) (xy 377.609309 -244.204998) (xy 377.563035 -244.228576) (xy 377.513642 -244.244624)
			(xy 377.462347 -244.252749) (xy 377.410413 -244.252749) (xy 377.359118 -244.244624) (xy 377.309725 -244.228576)
			(xy 377.263451 -244.204998) (xy 377.221435 -244.174472) (xy 377.184712 -244.137749) (xy 377.154186 -244.095733)
			(xy 377.130608 -244.049459) (xy 377.11456 -244.000066) (xy 377.106435 -243.948771) (xy 376.826779 -243.948771)
			(xy 376.818654 -244.000066) (xy 376.802606 -244.049459) (xy 376.779028 -244.095733) (xy 376.748502 -244.137749)
			(xy 376.711779 -244.174472) (xy 376.669763 -244.204998) (xy 376.623489 -244.228576) (xy 376.574096 -244.244624)
			(xy 376.522801 -244.252749) (xy 376.470867 -244.252749) (xy 376.419572 -244.244624) (xy 376.370179 -244.228576)
			(xy 376.323905 -244.204998) (xy 376.281889 -244.174472) (xy 376.245166 -244.137749) (xy 376.21464 -244.095733)
			(xy 376.191062 -244.049459) (xy 376.175014 -244.000066) (xy 376.166889 -243.948771) (xy 375.886979 -243.948771)
			(xy 375.878854 -244.000066) (xy 375.862806 -244.049459) (xy 375.839228 -244.095733) (xy 375.808702 -244.137749)
			(xy 375.771979 -244.174472) (xy 375.729963 -244.204998) (xy 375.683689 -244.228576) (xy 375.634296 -244.244624)
			(xy 375.583001 -244.252749) (xy 375.531067 -244.252749) (xy 375.479772 -244.244624) (xy 375.430379 -244.228576)
			(xy 375.384105 -244.204998) (xy 375.342089 -244.174472) (xy 375.305366 -244.137749) (xy 375.27484 -244.095733)
			(xy 375.251262 -244.049459) (xy 375.235214 -244.000066) (xy 375.227089 -243.948771) (xy 374.947179 -243.948771)
			(xy 374.939054 -244.000066) (xy 374.923006 -244.049459) (xy 374.899428 -244.095733) (xy 374.868902 -244.137749)
			(xy 374.832179 -244.174472) (xy 374.790163 -244.204998) (xy 374.743889 -244.228576) (xy 374.694496 -244.244624)
			(xy 374.643201 -244.252749) (xy 374.591267 -244.252749) (xy 374.539972 -244.244624) (xy 374.490579 -244.228576)
			(xy 374.444305 -244.204998) (xy 374.402289 -244.174472) (xy 374.365566 -244.137749) (xy 374.33504 -244.095733)
			(xy 374.311462 -244.049459) (xy 374.295414 -244.000066) (xy 374.287289 -243.948771) (xy 374.007379 -243.948771)
			(xy 373.999254 -244.000066) (xy 373.983206 -244.049459) (xy 373.959628 -244.095733) (xy 373.929102 -244.137749)
			(xy 373.892379 -244.174472) (xy 373.850363 -244.204998) (xy 373.804089 -244.228576) (xy 373.754696 -244.244624)
			(xy 373.703401 -244.252749) (xy 373.651467 -244.252749) (xy 373.600172 -244.244624) (xy 373.550779 -244.228576)
			(xy 373.504505 -244.204998) (xy 373.462489 -244.174472) (xy 373.425766 -244.137749) (xy 373.39524 -244.095733)
			(xy 373.371662 -244.049459) (xy 373.355614 -244.000066) (xy 373.347489 -243.948771) (xy 373.067579 -243.948771)
			(xy 373.059454 -244.000066) (xy 373.043406 -244.049459) (xy 373.019828 -244.095733) (xy 372.989302 -244.137749)
			(xy 372.952579 -244.174472) (xy 372.910563 -244.204998) (xy 372.864289 -244.228576) (xy 372.814896 -244.244624)
			(xy 372.763601 -244.252749) (xy 372.711667 -244.252749) (xy 372.660372 -244.244624) (xy 372.610979 -244.228576)
			(xy 372.564705 -244.204998) (xy 372.522689 -244.174472) (xy 372.485966 -244.137749) (xy 372.45544 -244.095733)
			(xy 372.431862 -244.049459) (xy 372.415814 -244.000066) (xy 372.407689 -243.948771) (xy 372.127779 -243.948771)
			(xy 372.119654 -244.000066) (xy 372.103606 -244.049459) (xy 372.080028 -244.095733) (xy 372.049502 -244.137749)
			(xy 372.012779 -244.174472) (xy 371.970763 -244.204998) (xy 371.924489 -244.228576) (xy 371.875096 -244.244624)
			(xy 371.823801 -244.252749) (xy 371.771867 -244.252749) (xy 371.720572 -244.244624) (xy 371.671179 -244.228576)
			(xy 371.624905 -244.204998) (xy 371.582889 -244.174472) (xy 371.546166 -244.137749) (xy 371.51564 -244.095733)
			(xy 371.492062 -244.049459) (xy 371.476014 -244.000066) (xy 371.467889 -243.948771) (xy 371.187725 -243.948771)
			(xy 371.1796 -244.000066) (xy 371.163552 -244.049459) (xy 371.139974 -244.095733) (xy 371.109448 -244.137749)
			(xy 371.072725 -244.174472) (xy 371.030709 -244.204998) (xy 370.984435 -244.228576) (xy 370.935042 -244.244624)
			(xy 370.883747 -244.252749) (xy 370.831813 -244.252749) (xy 370.780518 -244.244624) (xy 370.731125 -244.228576)
			(xy 370.684851 -244.204998) (xy 370.642835 -244.174472) (xy 370.606112 -244.137749) (xy 370.575586 -244.095733)
			(xy 370.552008 -244.049459) (xy 370.53596 -244.000066) (xy 370.527835 -243.948771) (xy 370.247925 -243.948771)
			(xy 370.2398 -244.000066) (xy 370.223752 -244.049459) (xy 370.200174 -244.095733) (xy 370.169648 -244.137749)
			(xy 370.132925 -244.174472) (xy 370.090909 -244.204998) (xy 370.044635 -244.228576) (xy 369.995242 -244.244624)
			(xy 369.943947 -244.252749) (xy 369.892013 -244.252749) (xy 369.840718 -244.244624) (xy 369.791325 -244.228576)
			(xy 369.745051 -244.204998) (xy 369.703035 -244.174472) (xy 369.666312 -244.137749) (xy 369.635786 -244.095733)
			(xy 369.612208 -244.049459) (xy 369.59616 -244.000066) (xy 369.588035 -243.948771) (xy 369.23002 -243.948771)
			(xy 369.224582 -243.966548) (xy 369.20346 -244.01082) (xy 369.17603 -244.051485) (xy 369.15979 -244.06987)
			(xy 369.14994 -244.081322) (xy 369.136937 -244.108573) (xy 369.132479 -244.138437) (xy 369.136958 -244.168298)
			(xy 369.149982 -244.195539) (xy 369.15979 -244.20703) (xy 369.177453 -244.227015) (xy 369.206727 -244.271599)
			(xy 369.228443 -244.320312) (xy 369.235736 -244.345968) (xy 369.23952 -244.358821) (xy 369.252854 -244.38205)
			(xy 369.271786 -244.400997) (xy 369.295005 -244.41435) (xy 369.320903 -244.421184) (xy 369.347687 -244.421026)
			(xy 369.360704 -244.41785) (xy 369.38201 -244.412414) (xy 369.425587 -244.406548) (xy 369.447572 -244.406166)
			(xy 369.44808 -244.406166) (xy 369.474052 -244.406607) (xy 369.525357 -244.41473) (xy 369.574759 -244.430779)
			(xy 369.621042 -244.454359) (xy 369.663066 -244.48489) (xy 369.699797 -244.521618) (xy 369.73033 -244.563641)
			(xy 369.753913 -244.609923) (xy 369.769965 -244.659324) (xy 369.778091 -244.710628) (xy 369.778091 -244.762333)
			(xy 370.057935 -244.762333) (xy 370.057935 -244.710399) (xy 370.06606 -244.659104) (xy 370.082108 -244.609711)
			(xy 370.105686 -244.563437) (xy 370.136212 -244.521421) (xy 370.172935 -244.484698) (xy 370.214951 -244.454172)
			(xy 370.261225 -244.430594) (xy 370.310618 -244.414546) (xy 370.361913 -244.406421) (xy 370.413847 -244.406421)
			(xy 370.465142 -244.414546) (xy 370.514535 -244.430594) (xy 370.560809 -244.454172) (xy 370.602825 -244.484698)
			(xy 370.639548 -244.521421) (xy 370.670074 -244.563437) (xy 370.693652 -244.609711) (xy 370.7097 -244.659104)
			(xy 370.717825 -244.710399) (xy 370.718334 -244.736366) (xy 370.717825 -244.762333) (xy 370.717785 -244.762587)
			(xy 370.997735 -244.762587) (xy 370.997735 -244.710653) (xy 371.00586 -244.659358) (xy 371.021908 -244.609965)
			(xy 371.045486 -244.563691) (xy 371.076012 -244.521675) (xy 371.112735 -244.484952) (xy 371.154751 -244.454426)
			(xy 371.201025 -244.430848) (xy 371.250418 -244.4148) (xy 371.301713 -244.406675) (xy 371.353647 -244.406675)
			(xy 371.404942 -244.4148) (xy 371.454335 -244.430848) (xy 371.500609 -244.454426) (xy 371.542625 -244.484952)
			(xy 371.579348 -244.521675) (xy 371.609874 -244.563691) (xy 371.633452 -244.609965) (xy 371.6495 -244.659358)
			(xy 371.657625 -244.710653) (xy 371.658134 -244.73662) (xy 371.657625 -244.762587) (xy 371.937535 -244.762587)
			(xy 371.937535 -244.710653) (xy 371.94566 -244.659358) (xy 371.961708 -244.609965) (xy 371.985286 -244.563691)
			(xy 372.015812 -244.521675) (xy 372.052535 -244.484952) (xy 372.094551 -244.454426) (xy 372.140825 -244.430848)
			(xy 372.190218 -244.4148) (xy 372.241513 -244.406675) (xy 372.293447 -244.406675) (xy 372.344742 -244.4148)
			(xy 372.394135 -244.430848) (xy 372.440409 -244.454426) (xy 372.482425 -244.484952) (xy 372.519148 -244.521675)
			(xy 372.549674 -244.563691) (xy 372.573252 -244.609965) (xy 372.5893 -244.659358) (xy 372.597425 -244.710653)
			(xy 372.597934 -244.73662) (xy 372.597425 -244.762587) (xy 372.877589 -244.762587) (xy 372.877589 -244.710653)
			(xy 372.885714 -244.659358) (xy 372.901762 -244.609965) (xy 372.92534 -244.563691) (xy 372.955866 -244.521675)
			(xy 372.992589 -244.484952) (xy 373.034605 -244.454426) (xy 373.080879 -244.430848) (xy 373.130272 -244.4148)
			(xy 373.181567 -244.406675) (xy 373.233501 -244.406675) (xy 373.284796 -244.4148) (xy 373.334189 -244.430848)
			(xy 373.380463 -244.454426) (xy 373.422479 -244.484952) (xy 373.459202 -244.521675) (xy 373.489728 -244.563691)
			(xy 373.513306 -244.609965) (xy 373.529354 -244.659358) (xy 373.537479 -244.710653) (xy 373.537988 -244.73662)
			(xy 373.537479 -244.762587) (xy 373.817135 -244.762587) (xy 373.817135 -244.710653) (xy 373.82526 -244.659358)
			(xy 373.841308 -244.609965) (xy 373.864886 -244.563691) (xy 373.895412 -244.521675) (xy 373.932135 -244.484952)
			(xy 373.974151 -244.454426) (xy 374.020425 -244.430848) (xy 374.069818 -244.4148) (xy 374.121113 -244.406675)
			(xy 374.173047 -244.406675) (xy 374.224342 -244.4148) (xy 374.273735 -244.430848) (xy 374.320009 -244.454426)
			(xy 374.362025 -244.484952) (xy 374.398748 -244.521675) (xy 374.429274 -244.563691) (xy 374.452852 -244.609965)
			(xy 374.4689 -244.659358) (xy 374.477025 -244.710653) (xy 374.477534 -244.73662) (xy 374.477025 -244.762587)
			(xy 374.757189 -244.762587) (xy 374.757189 -244.710653) (xy 374.765314 -244.659358) (xy 374.781362 -244.609965)
			(xy 374.80494 -244.563691) (xy 374.835466 -244.521675) (xy 374.872189 -244.484952) (xy 374.914205 -244.454426)
			(xy 374.960479 -244.430848) (xy 375.009872 -244.4148) (xy 375.061167 -244.406675) (xy 375.113101 -244.406675)
			(xy 375.164396 -244.4148) (xy 375.213789 -244.430848) (xy 375.260063 -244.454426) (xy 375.302079 -244.484952)
			(xy 375.338802 -244.521675) (xy 375.369328 -244.563691) (xy 375.392906 -244.609965) (xy 375.408954 -244.659358)
			(xy 375.417079 -244.710653) (xy 375.417588 -244.73662) (xy 375.417079 -244.762587) (xy 375.696735 -244.762587)
			(xy 375.696735 -244.710653) (xy 375.70486 -244.659358) (xy 375.720908 -244.609965) (xy 375.744486 -244.563691)
			(xy 375.775012 -244.521675) (xy 375.811735 -244.484952) (xy 375.853751 -244.454426) (xy 375.900025 -244.430848)
			(xy 375.949418 -244.4148) (xy 376.000713 -244.406675) (xy 376.052647 -244.406675) (xy 376.103942 -244.4148)
			(xy 376.153335 -244.430848) (xy 376.199609 -244.454426) (xy 376.241625 -244.484952) (xy 376.278348 -244.521675)
			(xy 376.308874 -244.563691) (xy 376.332452 -244.609965) (xy 376.3485 -244.659358) (xy 376.356625 -244.710653)
			(xy 376.357134 -244.73662) (xy 376.356625 -244.762587) (xy 376.636535 -244.762587) (xy 376.636535 -244.710653)
			(xy 376.64466 -244.659358) (xy 376.660708 -244.609965) (xy 376.684286 -244.563691) (xy 376.714812 -244.521675)
			(xy 376.751535 -244.484952) (xy 376.793551 -244.454426) (xy 376.839825 -244.430848) (xy 376.889218 -244.4148)
			(xy 376.940513 -244.406675) (xy 376.992447 -244.406675) (xy 377.043742 -244.4148) (xy 377.093135 -244.430848)
			(xy 377.139409 -244.454426) (xy 377.181425 -244.484952) (xy 377.218148 -244.521675) (xy 377.248674 -244.563691)
			(xy 377.272252 -244.609965) (xy 377.2883 -244.659358) (xy 377.296425 -244.710653) (xy 377.296934 -244.73662)
			(xy 377.296425 -244.762587) (xy 377.576335 -244.762587) (xy 377.576335 -244.710653) (xy 377.58446 -244.659358)
			(xy 377.600508 -244.609965) (xy 377.624086 -244.563691) (xy 377.654612 -244.521675) (xy 377.691335 -244.484952)
			(xy 377.733351 -244.454426) (xy 377.779625 -244.430848) (xy 377.829018 -244.4148) (xy 377.880313 -244.406675)
			(xy 377.932247 -244.406675) (xy 377.983542 -244.4148) (xy 378.032935 -244.430848) (xy 378.079209 -244.454426)
			(xy 378.121225 -244.484952) (xy 378.157948 -244.521675) (xy 378.188474 -244.563691) (xy 378.212052 -244.609965)
			(xy 378.2281 -244.659358) (xy 378.236225 -244.710653) (xy 378.236734 -244.73662) (xy 378.236225 -244.762587)
			(xy 378.516135 -244.762587) (xy 378.516135 -244.710653) (xy 378.52426 -244.659358) (xy 378.540308 -244.609965)
			(xy 378.563886 -244.563691) (xy 378.594412 -244.521675) (xy 378.631135 -244.484952) (xy 378.673151 -244.454426)
			(xy 378.719425 -244.430848) (xy 378.768818 -244.4148) (xy 378.820113 -244.406675) (xy 378.872047 -244.406675)
			(xy 378.923342 -244.4148) (xy 378.972735 -244.430848) (xy 379.019009 -244.454426) (xy 379.061025 -244.484952)
			(xy 379.097748 -244.521675) (xy 379.128274 -244.563691) (xy 379.151852 -244.609965) (xy 379.1679 -244.659358)
			(xy 379.176025 -244.710653) (xy 379.176534 -244.73662) (xy 379.176025 -244.762587) (xy 379.1679 -244.813882)
			(xy 379.151852 -244.863275) (xy 379.128274 -244.909549) (xy 379.097748 -244.951565) (xy 379.061025 -244.988288)
			(xy 379.019009 -245.018814) (xy 378.972735 -245.042392) (xy 378.923342 -245.05844) (xy 378.872047 -245.066565)
			(xy 378.820113 -245.066565) (xy 378.768818 -245.05844) (xy 378.719425 -245.042392) (xy 378.673151 -245.018814)
			(xy 378.631135 -244.988288) (xy 378.594412 -244.951565) (xy 378.563886 -244.909549) (xy 378.540308 -244.863275)
			(xy 378.52426 -244.813882) (xy 378.516135 -244.762587) (xy 378.236225 -244.762587) (xy 378.2281 -244.813882)
			(xy 378.212052 -244.863275) (xy 378.188474 -244.909549) (xy 378.157948 -244.951565) (xy 378.121225 -244.988288)
			(xy 378.079209 -245.018814) (xy 378.032935 -245.042392) (xy 377.983542 -245.05844) (xy 377.932247 -245.066565)
			(xy 377.880313 -245.066565) (xy 377.829018 -245.05844) (xy 377.779625 -245.042392) (xy 377.733351 -245.018814)
			(xy 377.691335 -244.988288) (xy 377.654612 -244.951565) (xy 377.624086 -244.909549) (xy 377.600508 -244.863275)
			(xy 377.58446 -244.813882) (xy 377.576335 -244.762587) (xy 377.296425 -244.762587) (xy 377.2883 -244.813882)
			(xy 377.272252 -244.863275) (xy 377.248674 -244.909549) (xy 377.218148 -244.951565) (xy 377.181425 -244.988288)
			(xy 377.139409 -245.018814) (xy 377.093135 -245.042392) (xy 377.043742 -245.05844) (xy 376.992447 -245.066565)
			(xy 376.940513 -245.066565) (xy 376.889218 -245.05844) (xy 376.839825 -245.042392) (xy 376.793551 -245.018814)
			(xy 376.751535 -244.988288) (xy 376.714812 -244.951565) (xy 376.684286 -244.909549) (xy 376.660708 -244.863275)
			(xy 376.64466 -244.813882) (xy 376.636535 -244.762587) (xy 376.356625 -244.762587) (xy 376.3485 -244.813882)
			(xy 376.332452 -244.863275) (xy 376.308874 -244.909549) (xy 376.278348 -244.951565) (xy 376.241625 -244.988288)
			(xy 376.199609 -245.018814) (xy 376.153335 -245.042392) (xy 376.103942 -245.05844) (xy 376.052647 -245.066565)
			(xy 376.000713 -245.066565) (xy 375.949418 -245.05844) (xy 375.900025 -245.042392) (xy 375.853751 -245.018814)
			(xy 375.811735 -244.988288) (xy 375.775012 -244.951565) (xy 375.744486 -244.909549) (xy 375.720908 -244.863275)
			(xy 375.70486 -244.813882) (xy 375.696735 -244.762587) (xy 375.417079 -244.762587) (xy 375.408954 -244.813882)
			(xy 375.392906 -244.863275) (xy 375.369328 -244.909549) (xy 375.338802 -244.951565) (xy 375.302079 -244.988288)
			(xy 375.260063 -245.018814) (xy 375.213789 -245.042392) (xy 375.164396 -245.05844) (xy 375.113101 -245.066565)
			(xy 375.061167 -245.066565) (xy 375.009872 -245.05844) (xy 374.960479 -245.042392) (xy 374.914205 -245.018814)
			(xy 374.872189 -244.988288) (xy 374.835466 -244.951565) (xy 374.80494 -244.909549) (xy 374.781362 -244.863275)
			(xy 374.765314 -244.813882) (xy 374.757189 -244.762587) (xy 374.477025 -244.762587) (xy 374.4689 -244.813882)
			(xy 374.452852 -244.863275) (xy 374.429274 -244.909549) (xy 374.398748 -244.951565) (xy 374.362025 -244.988288)
			(xy 374.320009 -245.018814) (xy 374.273735 -245.042392) (xy 374.224342 -245.05844) (xy 374.173047 -245.066565)
			(xy 374.121113 -245.066565) (xy 374.069818 -245.05844) (xy 374.020425 -245.042392) (xy 373.974151 -245.018814)
			(xy 373.932135 -244.988288) (xy 373.895412 -244.951565) (xy 373.864886 -244.909549) (xy 373.841308 -244.863275)
			(xy 373.82526 -244.813882) (xy 373.817135 -244.762587) (xy 373.537479 -244.762587) (xy 373.529354 -244.813882)
			(xy 373.513306 -244.863275) (xy 373.489728 -244.909549) (xy 373.459202 -244.951565) (xy 373.422479 -244.988288)
			(xy 373.380463 -245.018814) (xy 373.334189 -245.042392) (xy 373.284796 -245.05844) (xy 373.233501 -245.066565)
			(xy 373.181567 -245.066565) (xy 373.130272 -245.05844) (xy 373.080879 -245.042392) (xy 373.034605 -245.018814)
			(xy 372.992589 -244.988288) (xy 372.955866 -244.951565) (xy 372.92534 -244.909549) (xy 372.901762 -244.863275)
			(xy 372.885714 -244.813882) (xy 372.877589 -244.762587) (xy 372.597425 -244.762587) (xy 372.5893 -244.813882)
			(xy 372.573252 -244.863275) (xy 372.549674 -244.909549) (xy 372.519148 -244.951565) (xy 372.482425 -244.988288)
			(xy 372.440409 -245.018814) (xy 372.394135 -245.042392) (xy 372.344742 -245.05844) (xy 372.293447 -245.066565)
			(xy 372.241513 -245.066565) (xy 372.190218 -245.05844) (xy 372.140825 -245.042392) (xy 372.094551 -245.018814)
			(xy 372.052535 -244.988288) (xy 372.015812 -244.951565) (xy 371.985286 -244.909549) (xy 371.961708 -244.863275)
			(xy 371.94566 -244.813882) (xy 371.937535 -244.762587) (xy 371.657625 -244.762587) (xy 371.6495 -244.813882)
			(xy 371.633452 -244.863275) (xy 371.609874 -244.909549) (xy 371.579348 -244.951565) (xy 371.542625 -244.988288)
			(xy 371.500609 -245.018814) (xy 371.454335 -245.042392) (xy 371.404942 -245.05844) (xy 371.353647 -245.066565)
			(xy 371.301713 -245.066565) (xy 371.250418 -245.05844) (xy 371.201025 -245.042392) (xy 371.154751 -245.018814)
			(xy 371.112735 -244.988288) (xy 371.076012 -244.951565) (xy 371.045486 -244.909549) (xy 371.021908 -244.863275)
			(xy 371.00586 -244.813882) (xy 370.997735 -244.762587) (xy 370.717785 -244.762587) (xy 370.7097 -244.813628)
			(xy 370.693652 -244.863021) (xy 370.670074 -244.909295) (xy 370.639548 -244.951311) (xy 370.602825 -244.988034)
			(xy 370.560809 -245.01856) (xy 370.514535 -245.042138) (xy 370.465142 -245.058186) (xy 370.413847 -245.066311)
			(xy 370.361913 -245.066311) (xy 370.310618 -245.058186) (xy 370.261225 -245.042138) (xy 370.214951 -245.01856)
			(xy 370.172935 -244.988034) (xy 370.136212 -244.951311) (xy 370.105686 -244.909295) (xy 370.082108 -244.863021)
			(xy 370.06606 -244.813628) (xy 370.057935 -244.762333) (xy 369.778091 -244.762333) (xy 369.778091 -244.762572)
			(xy 369.769965 -244.813876) (xy 369.753913 -244.863277) (xy 369.73033 -244.909559) (xy 369.699797 -244.951582)
			(xy 369.663066 -244.98831) (xy 369.621042 -245.018841) (xy 369.574759 -245.04242) (xy 369.525357 -245.05847)
			(xy 369.474052 -245.066593) (xy 369.44808 -245.067074) (xy 369.424441 -245.066668) (xy 369.377649 -245.059912)
			(xy 369.354862 -245.053612) (xy 369.339705 -245.049717) (xy 369.308432 -245.050409) (xy 369.278833 -245.06053)
			(xy 369.253685 -245.079133) (xy 369.235344 -245.104473) (xy 369.229894 -245.119144) (xy 369.222179 -245.141047)
			(xy 369.201495 -245.182623) (xy 369.175197 -245.220896) (xy 369.15979 -245.23827) (xy 369.14994 -245.249722)
			(xy 369.136937 -245.276973) (xy 369.132479 -245.306837) (xy 369.136958 -245.336698) (xy 369.149982 -245.363939)
			(xy 369.15979 -245.37543) (xy 369.17602 -245.393825) (xy 369.203468 -245.43448) (xy 369.224601 -245.478748)
			(xy 369.238954 -245.525655) (xy 369.24621 -245.574169) (xy 369.246255 -245.576657) (xy 369.588289 -245.576657)
			(xy 369.588289 -245.524723) (xy 369.596414 -245.473428) (xy 369.612462 -245.424035) (xy 369.63604 -245.377761)
			(xy 369.666566 -245.335745) (xy 369.703289 -245.299022) (xy 369.745305 -245.268496) (xy 369.791579 -245.244918)
			(xy 369.840972 -245.22887) (xy 369.892267 -245.220745) (xy 369.944201 -245.220745) (xy 369.995496 -245.22887)
			(xy 370.044889 -245.244918) (xy 370.091163 -245.268496) (xy 370.133179 -245.299022) (xy 370.169902 -245.335745)
			(xy 370.200428 -245.377761) (xy 370.224006 -245.424035) (xy 370.240054 -245.473428) (xy 370.248179 -245.524723)
			(xy 370.248688 -245.55069) (xy 370.248179 -245.576657) (xy 370.528089 -245.576657) (xy 370.528089 -245.524723)
			(xy 370.536214 -245.473428) (xy 370.552262 -245.424035) (xy 370.57584 -245.377761) (xy 370.606366 -245.335745)
			(xy 370.643089 -245.299022) (xy 370.685105 -245.268496) (xy 370.731379 -245.244918) (xy 370.780772 -245.22887)
			(xy 370.832067 -245.220745) (xy 370.884001 -245.220745) (xy 370.935296 -245.22887) (xy 370.984689 -245.244918)
			(xy 371.030963 -245.268496) (xy 371.072979 -245.299022) (xy 371.109702 -245.335745) (xy 371.140228 -245.377761)
			(xy 371.163806 -245.424035) (xy 371.179854 -245.473428) (xy 371.187979 -245.524723) (xy 371.188488 -245.55069)
			(xy 371.187979 -245.576657) (xy 371.467889 -245.576657) (xy 371.467889 -245.524723) (xy 371.476014 -245.473428)
			(xy 371.492062 -245.424035) (xy 371.51564 -245.377761) (xy 371.546166 -245.335745) (xy 371.582889 -245.299022)
			(xy 371.624905 -245.268496) (xy 371.671179 -245.244918) (xy 371.720572 -245.22887) (xy 371.771867 -245.220745)
			(xy 371.823801 -245.220745) (xy 371.875096 -245.22887) (xy 371.924489 -245.244918) (xy 371.970763 -245.268496)
			(xy 372.012779 -245.299022) (xy 372.049502 -245.335745) (xy 372.080028 -245.377761) (xy 372.103606 -245.424035)
			(xy 372.119654 -245.473428) (xy 372.127779 -245.524723) (xy 372.128288 -245.55069) (xy 372.127779 -245.576657)
			(xy 372.407689 -245.576657) (xy 372.407689 -245.524723) (xy 372.415814 -245.473428) (xy 372.431862 -245.424035)
			(xy 372.45544 -245.377761) (xy 372.485966 -245.335745) (xy 372.522689 -245.299022) (xy 372.564705 -245.268496)
			(xy 372.610979 -245.244918) (xy 372.660372 -245.22887) (xy 372.711667 -245.220745) (xy 372.763601 -245.220745)
			(xy 372.814896 -245.22887) (xy 372.864289 -245.244918) (xy 372.910563 -245.268496) (xy 372.952579 -245.299022)
			(xy 372.989302 -245.335745) (xy 373.019828 -245.377761) (xy 373.043406 -245.424035) (xy 373.059454 -245.473428)
			(xy 373.067579 -245.524723) (xy 373.068088 -245.55069) (xy 373.067579 -245.576657) (xy 373.347235 -245.576657)
			(xy 373.347235 -245.524723) (xy 373.35536 -245.473428) (xy 373.371408 -245.424035) (xy 373.394986 -245.377761)
			(xy 373.425512 -245.335745) (xy 373.462235 -245.299022) (xy 373.504251 -245.268496) (xy 373.550525 -245.244918)
			(xy 373.599918 -245.22887) (xy 373.651213 -245.220745) (xy 373.703147 -245.220745) (xy 373.754442 -245.22887)
			(xy 373.803835 -245.244918) (xy 373.850109 -245.268496) (xy 373.892125 -245.299022) (xy 373.928848 -245.335745)
			(xy 373.959374 -245.377761) (xy 373.982952 -245.424035) (xy 373.999 -245.473428) (xy 374.007125 -245.524723)
			(xy 374.007634 -245.55069) (xy 374.007125 -245.576657) (xy 374.287289 -245.576657) (xy 374.287289 -245.524723)
			(xy 374.295414 -245.473428) (xy 374.311462 -245.424035) (xy 374.33504 -245.377761) (xy 374.365566 -245.335745)
			(xy 374.402289 -245.299022) (xy 374.444305 -245.268496) (xy 374.490579 -245.244918) (xy 374.539972 -245.22887)
			(xy 374.591267 -245.220745) (xy 374.643201 -245.220745) (xy 374.694496 -245.22887) (xy 374.743889 -245.244918)
			(xy 374.790163 -245.268496) (xy 374.832179 -245.299022) (xy 374.868902 -245.335745) (xy 374.899428 -245.377761)
			(xy 374.923006 -245.424035) (xy 374.939054 -245.473428) (xy 374.947179 -245.524723) (xy 374.947688 -245.55069)
			(xy 374.947179 -245.576657) (xy 375.226835 -245.576657) (xy 375.226835 -245.524723) (xy 375.23496 -245.473428)
			(xy 375.251008 -245.424035) (xy 375.274586 -245.377761) (xy 375.305112 -245.335745) (xy 375.341835 -245.299022)
			(xy 375.383851 -245.268496) (xy 375.430125 -245.244918) (xy 375.479518 -245.22887) (xy 375.530813 -245.220745)
			(xy 375.582747 -245.220745) (xy 375.634042 -245.22887) (xy 375.683435 -245.244918) (xy 375.729709 -245.268496)
			(xy 375.771725 -245.299022) (xy 375.808448 -245.335745) (xy 375.838974 -245.377761) (xy 375.862552 -245.424035)
			(xy 375.8786 -245.473428) (xy 375.886725 -245.524723) (xy 375.887234 -245.55069) (xy 375.886725 -245.576657)
			(xy 376.166889 -245.576657) (xy 376.166889 -245.524723) (xy 376.175014 -245.473428) (xy 376.191062 -245.424035)
			(xy 376.21464 -245.377761) (xy 376.245166 -245.335745) (xy 376.281889 -245.299022) (xy 376.323905 -245.268496)
			(xy 376.370179 -245.244918) (xy 376.419572 -245.22887) (xy 376.470867 -245.220745) (xy 376.522801 -245.220745)
			(xy 376.574096 -245.22887) (xy 376.623489 -245.244918) (xy 376.669763 -245.268496) (xy 376.711779 -245.299022)
			(xy 376.748502 -245.335745) (xy 376.779028 -245.377761) (xy 376.802606 -245.424035) (xy 376.818654 -245.473428)
			(xy 376.826779 -245.524723) (xy 376.827288 -245.55069) (xy 376.826779 -245.576657) (xy 377.106689 -245.576657)
			(xy 377.106689 -245.524723) (xy 377.114814 -245.473428) (xy 377.130862 -245.424035) (xy 377.15444 -245.377761)
			(xy 377.184966 -245.335745) (xy 377.221689 -245.299022) (xy 377.263705 -245.268496) (xy 377.309979 -245.244918)
			(xy 377.359372 -245.22887) (xy 377.410667 -245.220745) (xy 377.462601 -245.220745) (xy 377.513896 -245.22887)
			(xy 377.563289 -245.244918) (xy 377.609563 -245.268496) (xy 377.651579 -245.299022) (xy 377.688302 -245.335745)
			(xy 377.718828 -245.377761) (xy 377.742406 -245.424035) (xy 377.758454 -245.473428) (xy 377.766579 -245.524723)
			(xy 377.767088 -245.55069) (xy 377.766579 -245.576657) (xy 378.046489 -245.576657) (xy 378.046489 -245.524723)
			(xy 378.054614 -245.473428) (xy 378.070662 -245.424035) (xy 378.09424 -245.377761) (xy 378.124766 -245.335745)
			(xy 378.161489 -245.299022) (xy 378.203505 -245.268496) (xy 378.249779 -245.244918) (xy 378.299172 -245.22887)
			(xy 378.350467 -245.220745) (xy 378.402401 -245.220745) (xy 378.453696 -245.22887) (xy 378.503089 -245.244918)
			(xy 378.549363 -245.268496) (xy 378.591379 -245.299022) (xy 378.628102 -245.335745) (xy 378.658628 -245.377761)
			(xy 378.682206 -245.424035) (xy 378.698254 -245.473428) (xy 378.706379 -245.524723) (xy 378.706888 -245.55069)
			(xy 378.706379 -245.576657) (xy 378.986289 -245.576657) (xy 378.986289 -245.524723) (xy 378.994414 -245.473428)
			(xy 379.010462 -245.424035) (xy 379.03404 -245.377761) (xy 379.064566 -245.335745) (xy 379.101289 -245.299022)
			(xy 379.143305 -245.268496) (xy 379.189579 -245.244918) (xy 379.238972 -245.22887) (xy 379.290267 -245.220745)
			(xy 379.342201 -245.220745) (xy 379.393496 -245.22887) (xy 379.442889 -245.244918) (xy 379.489163 -245.268496)
			(xy 379.531179 -245.299022) (xy 379.567902 -245.335745) (xy 379.598428 -245.377761) (xy 379.622006 -245.424035)
			(xy 379.638054 -245.473428) (xy 379.646179 -245.524723) (xy 379.646688 -245.55069) (xy 379.646179 -245.576657)
			(xy 379.638054 -245.627952) (xy 379.622006 -245.677345) (xy 379.598428 -245.723619) (xy 379.567902 -245.765635)
			(xy 379.531179 -245.802358) (xy 379.489163 -245.832884) (xy 379.442889 -245.856462) (xy 379.393496 -245.87251)
			(xy 379.342201 -245.880635) (xy 379.290267 -245.880635) (xy 379.238972 -245.87251) (xy 379.189579 -245.856462)
			(xy 379.143305 -245.832884) (xy 379.101289 -245.802358) (xy 379.064566 -245.765635) (xy 379.03404 -245.723619)
			(xy 379.010462 -245.677345) (xy 378.994414 -245.627952) (xy 378.986289 -245.576657) (xy 378.706379 -245.576657)
			(xy 378.698254 -245.627952) (xy 378.682206 -245.677345) (xy 378.658628 -245.723619) (xy 378.628102 -245.765635)
			(xy 378.591379 -245.802358) (xy 378.549363 -245.832884) (xy 378.503089 -245.856462) (xy 378.453696 -245.87251)
			(xy 378.402401 -245.880635) (xy 378.350467 -245.880635) (xy 378.299172 -245.87251) (xy 378.249779 -245.856462)
			(xy 378.203505 -245.832884) (xy 378.161489 -245.802358) (xy 378.124766 -245.765635) (xy 378.09424 -245.723619)
			(xy 378.070662 -245.677345) (xy 378.054614 -245.627952) (xy 378.046489 -245.576657) (xy 377.766579 -245.576657)
			(xy 377.758454 -245.627952) (xy 377.742406 -245.677345) (xy 377.718828 -245.723619) (xy 377.688302 -245.765635)
			(xy 377.651579 -245.802358) (xy 377.609563 -245.832884) (xy 377.563289 -245.856462) (xy 377.513896 -245.87251)
			(xy 377.462601 -245.880635) (xy 377.410667 -245.880635) (xy 377.359372 -245.87251) (xy 377.309979 -245.856462)
			(xy 377.263705 -245.832884) (xy 377.221689 -245.802358) (xy 377.184966 -245.765635) (xy 377.15444 -245.723619)
			(xy 377.130862 -245.677345) (xy 377.114814 -245.627952) (xy 377.106689 -245.576657) (xy 376.826779 -245.576657)
			(xy 376.818654 -245.627952) (xy 376.802606 -245.677345) (xy 376.779028 -245.723619) (xy 376.748502 -245.765635)
			(xy 376.711779 -245.802358) (xy 376.669763 -245.832884) (xy 376.623489 -245.856462) (xy 376.574096 -245.87251)
			(xy 376.522801 -245.880635) (xy 376.470867 -245.880635) (xy 376.419572 -245.87251) (xy 376.370179 -245.856462)
			(xy 376.323905 -245.832884) (xy 376.281889 -245.802358) (xy 376.245166 -245.765635) (xy 376.21464 -245.723619)
			(xy 376.191062 -245.677345) (xy 376.175014 -245.627952) (xy 376.166889 -245.576657) (xy 375.886725 -245.576657)
			(xy 375.8786 -245.627952) (xy 375.862552 -245.677345) (xy 375.838974 -245.723619) (xy 375.808448 -245.765635)
			(xy 375.771725 -245.802358) (xy 375.729709 -245.832884) (xy 375.683435 -245.856462) (xy 375.634042 -245.87251)
			(xy 375.582747 -245.880635) (xy 375.530813 -245.880635) (xy 375.479518 -245.87251) (xy 375.430125 -245.856462)
			(xy 375.383851 -245.832884) (xy 375.341835 -245.802358) (xy 375.305112 -245.765635) (xy 375.274586 -245.723619)
			(xy 375.251008 -245.677345) (xy 375.23496 -245.627952) (xy 375.226835 -245.576657) (xy 374.947179 -245.576657)
			(xy 374.939054 -245.627952) (xy 374.923006 -245.677345) (xy 374.899428 -245.723619) (xy 374.868902 -245.765635)
			(xy 374.832179 -245.802358) (xy 374.790163 -245.832884) (xy 374.743889 -245.856462) (xy 374.694496 -245.87251)
			(xy 374.643201 -245.880635) (xy 374.591267 -245.880635) (xy 374.539972 -245.87251) (xy 374.490579 -245.856462)
			(xy 374.444305 -245.832884) (xy 374.402289 -245.802358) (xy 374.365566 -245.765635) (xy 374.33504 -245.723619)
			(xy 374.311462 -245.677345) (xy 374.295414 -245.627952) (xy 374.287289 -245.576657) (xy 374.007125 -245.576657)
			(xy 373.999 -245.627952) (xy 373.982952 -245.677345) (xy 373.959374 -245.723619) (xy 373.928848 -245.765635)
			(xy 373.892125 -245.802358) (xy 373.850109 -245.832884) (xy 373.803835 -245.856462) (xy 373.754442 -245.87251)
			(xy 373.703147 -245.880635) (xy 373.651213 -245.880635) (xy 373.599918 -245.87251) (xy 373.550525 -245.856462)
			(xy 373.504251 -245.832884) (xy 373.462235 -245.802358) (xy 373.425512 -245.765635) (xy 373.394986 -245.723619)
			(xy 373.371408 -245.677345) (xy 373.35536 -245.627952) (xy 373.347235 -245.576657) (xy 373.067579 -245.576657)
			(xy 373.059454 -245.627952) (xy 373.043406 -245.677345) (xy 373.019828 -245.723619) (xy 372.989302 -245.765635)
			(xy 372.952579 -245.802358) (xy 372.910563 -245.832884) (xy 372.864289 -245.856462) (xy 372.814896 -245.87251)
			(xy 372.763601 -245.880635) (xy 372.711667 -245.880635) (xy 372.660372 -245.87251) (xy 372.610979 -245.856462)
			(xy 372.564705 -245.832884) (xy 372.522689 -245.802358) (xy 372.485966 -245.765635) (xy 372.45544 -245.723619)
			(xy 372.431862 -245.677345) (xy 372.415814 -245.627952) (xy 372.407689 -245.576657) (xy 372.127779 -245.576657)
			(xy 372.119654 -245.627952) (xy 372.103606 -245.677345) (xy 372.080028 -245.723619) (xy 372.049502 -245.765635)
			(xy 372.012779 -245.802358) (xy 371.970763 -245.832884) (xy 371.924489 -245.856462) (xy 371.875096 -245.87251)
			(xy 371.823801 -245.880635) (xy 371.771867 -245.880635) (xy 371.720572 -245.87251) (xy 371.671179 -245.856462)
			(xy 371.624905 -245.832884) (xy 371.582889 -245.802358) (xy 371.546166 -245.765635) (xy 371.51564 -245.723619)
			(xy 371.492062 -245.677345) (xy 371.476014 -245.627952) (xy 371.467889 -245.576657) (xy 371.187979 -245.576657)
			(xy 371.179854 -245.627952) (xy 371.163806 -245.677345) (xy 371.140228 -245.723619) (xy 371.109702 -245.765635)
			(xy 371.072979 -245.802358) (xy 371.030963 -245.832884) (xy 370.984689 -245.856462) (xy 370.935296 -245.87251)
			(xy 370.884001 -245.880635) (xy 370.832067 -245.880635) (xy 370.780772 -245.87251) (xy 370.731379 -245.856462)
			(xy 370.685105 -245.832884) (xy 370.643089 -245.802358) (xy 370.606366 -245.765635) (xy 370.57584 -245.723619)
			(xy 370.552262 -245.677345) (xy 370.536214 -245.627952) (xy 370.528089 -245.576657) (xy 370.248179 -245.576657)
			(xy 370.240054 -245.627952) (xy 370.224006 -245.677345) (xy 370.200428 -245.723619) (xy 370.169902 -245.765635)
			(xy 370.133179 -245.802358) (xy 370.091163 -245.832884) (xy 370.044889 -245.856462) (xy 369.995496 -245.87251)
			(xy 369.944201 -245.880635) (xy 369.892267 -245.880635) (xy 369.840972 -245.87251) (xy 369.791579 -245.856462)
			(xy 369.745305 -245.832884) (xy 369.703289 -245.802358) (xy 369.666566 -245.765635) (xy 369.63604 -245.723619)
			(xy 369.612462 -245.677345) (xy 369.596414 -245.627952) (xy 369.588289 -245.576657) (xy 369.246255 -245.576657)
			(xy 369.246658 -245.598696) (xy 369.246658 -245.59895) (xy 369.246149 -245.624917) (xy 369.238024 -245.676212)
			(xy 369.221976 -245.725605) (xy 369.198398 -245.771879) (xy 369.167872 -245.813895) (xy 369.131149 -245.850618)
			(xy 369.089133 -245.881144) (xy 369.042859 -245.904722) (xy 368.993466 -245.92077) (xy 368.942171 -245.928895)
			(xy 368.890237 -245.928895) (xy 368.838942 -245.92077) (xy 368.789549 -245.904722) (xy 368.743275 -245.881144)
			(xy 368.701259 -245.850618) (xy 368.664536 -245.813895) (xy 368.63401 -245.771879) (xy 368.610432 -245.725605)
			(xy 368.594384 -245.676212) (xy 368.586259 -245.624917) (xy 368.58575 -245.59895) (xy 363.616391 -245.59895)
			(xy 363.607304 -245.611457) (xy 363.570581 -245.64818) (xy 363.528565 -245.678706) (xy 363.482291 -245.702284)
			(xy 363.432898 -245.718332) (xy 363.381603 -245.726457) (xy 363.329669 -245.726457) (xy 363.278374 -245.718332)
			(xy 363.228981 -245.702284) (xy 363.182707 -245.678706) (xy 363.140691 -245.64818) (xy 363.103968 -245.611457)
			(xy 363.073442 -245.569441) (xy 363.049864 -245.523167) (xy 363.033816 -245.473774) (xy 363.025691 -245.422479)
			(xy 363.025182 -245.396512) (xy 362.691582 -245.396512) (xy 362.705606 -245.424035) (xy 362.721654 -245.473428)
			(xy 362.729779 -245.524723) (xy 362.730288 -245.55069) (xy 362.729779 -245.576657) (xy 362.721654 -245.627952)
			(xy 362.705606 -245.677345) (xy 362.682028 -245.723619) (xy 362.651502 -245.765635) (xy 362.614779 -245.802358)
			(xy 362.572763 -245.832884) (xy 362.526489 -245.856462) (xy 362.477096 -245.87251) (xy 362.425801 -245.880635)
			(xy 362.373867 -245.880635) (xy 362.322572 -245.87251) (xy 362.273179 -245.856462) (xy 362.226905 -245.832884)
			(xy 362.184889 -245.802358) (xy 362.148166 -245.765635) (xy 362.11764 -245.723619) (xy 362.094062 -245.677345)
			(xy 362.078014 -245.627952) (xy 362.069889 -245.576657) (xy 361.789979 -245.576657) (xy 361.781854 -245.627952)
			(xy 361.765806 -245.677345) (xy 361.742228 -245.723619) (xy 361.711702 -245.765635) (xy 361.674979 -245.802358)
			(xy 361.632963 -245.832884) (xy 361.586689 -245.856462) (xy 361.537296 -245.87251) (xy 361.486001 -245.880635)
			(xy 361.434067 -245.880635) (xy 361.382772 -245.87251) (xy 361.333379 -245.856462) (xy 361.287105 -245.832884)
			(xy 361.245089 -245.802358) (xy 361.208366 -245.765635) (xy 361.17784 -245.723619) (xy 361.154262 -245.677345)
			(xy 361.138214 -245.627952) (xy 361.130089 -245.576657) (xy 360.849925 -245.576657) (xy 360.8418 -245.627952)
			(xy 360.825752 -245.677345) (xy 360.802174 -245.723619) (xy 360.771648 -245.765635) (xy 360.734925 -245.802358)
			(xy 360.692909 -245.832884) (xy 360.646635 -245.856462) (xy 360.597242 -245.87251) (xy 360.545947 -245.880635)
			(xy 360.494013 -245.880635) (xy 360.442718 -245.87251) (xy 360.393325 -245.856462) (xy 360.347051 -245.832884)
			(xy 360.305035 -245.802358) (xy 360.268312 -245.765635) (xy 360.237786 -245.723619) (xy 360.214208 -245.677345)
			(xy 360.19816 -245.627952) (xy 360.190035 -245.576657) (xy 359.910125 -245.576657) (xy 359.902 -245.627952)
			(xy 359.885952 -245.677345) (xy 359.862374 -245.723619) (xy 359.831848 -245.765635) (xy 359.795125 -245.802358)
			(xy 359.753109 -245.832884) (xy 359.706835 -245.856462) (xy 359.657442 -245.87251) (xy 359.606147 -245.880635)
			(xy 359.554213 -245.880635) (xy 359.502918 -245.87251) (xy 359.453525 -245.856462) (xy 359.407251 -245.832884)
			(xy 359.365235 -245.802358) (xy 359.328512 -245.765635) (xy 359.297986 -245.723619) (xy 359.274408 -245.677345)
			(xy 359.25836 -245.627952) (xy 359.250235 -245.576657) (xy 358.970579 -245.576657) (xy 358.962454 -245.627952)
			(xy 358.946406 -245.677345) (xy 358.922828 -245.723619) (xy 358.892302 -245.765635) (xy 358.855579 -245.802358)
			(xy 358.813563 -245.832884) (xy 358.767289 -245.856462) (xy 358.717896 -245.87251) (xy 358.666601 -245.880635)
			(xy 358.614667 -245.880635) (xy 358.563372 -245.87251) (xy 358.513979 -245.856462) (xy 358.467705 -245.832884)
			(xy 358.425689 -245.802358) (xy 358.388966 -245.765635) (xy 358.35844 -245.723619) (xy 358.334862 -245.677345)
			(xy 358.318814 -245.627952) (xy 358.310689 -245.576657) (xy 358.030525 -245.576657) (xy 358.0224 -245.627952)
			(xy 358.006352 -245.677345) (xy 357.982774 -245.723619) (xy 357.952248 -245.765635) (xy 357.915525 -245.802358)
			(xy 357.873509 -245.832884) (xy 357.827235 -245.856462) (xy 357.777842 -245.87251) (xy 357.726547 -245.880635)
			(xy 357.674613 -245.880635) (xy 357.623318 -245.87251) (xy 357.573925 -245.856462) (xy 357.527651 -245.832884)
			(xy 357.485635 -245.802358) (xy 357.448912 -245.765635) (xy 357.418386 -245.723619) (xy 357.394808 -245.677345)
			(xy 357.37876 -245.627952) (xy 357.370635 -245.576657) (xy 356.610876 -245.576657) (xy 356.588629 -245.598904)
			(xy 356.546613 -245.62943) (xy 356.500339 -245.653008) (xy 356.450946 -245.669056) (xy 356.399651 -245.677181)
			(xy 356.347717 -245.677181) (xy 356.296422 -245.669056) (xy 356.247029 -245.653008) (xy 356.200755 -245.62943)
			(xy 356.158739 -245.598904) (xy 356.122016 -245.562181) (xy 356.09149 -245.520165) (xy 356.067912 -245.473891)
			(xy 356.051864 -245.424498) (xy 356.043739 -245.373203) (xy 356.04323 -245.347236) (xy 351.171341 -245.347236)
			(xy 351.171056 -245.363555) (xy 351.162932 -245.414858) (xy 351.146882 -245.464258) (xy 351.1233 -245.510538)
			(xy 351.092769 -245.55256) (xy 351.056038 -245.589287) (xy 351.014015 -245.619815) (xy 350.967732 -245.643393)
			(xy 350.918331 -245.659439) (xy 350.867027 -245.667558) (xy 350.841056 -245.668038) (xy 350.840802 -245.668038)
			(xy 350.815364 -245.667574) (xy 350.76509 -245.659775) (xy 350.71661 -245.644347) (xy 350.671075 -245.621656)
			(xy 350.650048 -245.607332) (xy 350.638818 -245.599781) (xy 350.613431 -245.590428) (xy 350.586477 -245.588084)
			(xy 350.559856 -245.592913) (xy 350.535444 -245.604576) (xy 350.51496 -245.622251) (xy 350.499848 -245.644693)
			(xy 350.495108 -245.65737) (xy 350.486375 -245.681508) (xy 350.462509 -245.72695) (xy 350.431899 -245.768152)
			(xy 350.395284 -245.804123) (xy 350.353543 -245.833995) (xy 350.307684 -245.857049) (xy 350.25881 -245.872731)
			(xy 350.208098 -245.880662) (xy 350.182434 -245.881144) (xy 350.156462 -245.880684) (xy 350.105157 -245.872563)
			(xy 350.055755 -245.856515) (xy 350.009471 -245.832937) (xy 349.967446 -245.802408) (xy 349.930714 -245.76568)
			(xy 349.900181 -245.723658) (xy 349.876598 -245.677377) (xy 349.860545 -245.627976) (xy 349.852419 -245.576672)
			(xy 349.572577 -245.576672) (xy 349.564454 -245.627952) (xy 349.548406 -245.677345) (xy 349.524828 -245.723619)
			(xy 349.494302 -245.765635) (xy 349.457579 -245.802358) (xy 349.415563 -245.832884) (xy 349.369289 -245.856462)
			(xy 349.319896 -245.87251) (xy 349.268601 -245.880635) (xy 349.216667 -245.880635) (xy 349.165372 -245.87251)
			(xy 349.115979 -245.856462) (xy 349.069705 -245.832884) (xy 349.027689 -245.802358) (xy 348.990966 -245.765635)
			(xy 348.96044 -245.723619) (xy 348.936862 -245.677345) (xy 348.920814 -245.627952) (xy 348.912689 -245.576657)
			(xy 348.632779 -245.576657) (xy 348.624654 -245.627952) (xy 348.608606 -245.677345) (xy 348.585028 -245.723619)
			(xy 348.554502 -245.765635) (xy 348.517779 -245.802358) (xy 348.475763 -245.832884) (xy 348.429489 -245.856462)
			(xy 348.380096 -245.87251) (xy 348.328801 -245.880635) (xy 348.276867 -245.880635) (xy 348.225572 -245.87251)
			(xy 348.176179 -245.856462) (xy 348.129905 -245.832884) (xy 348.087889 -245.802358) (xy 348.051166 -245.765635)
			(xy 348.02064 -245.723619) (xy 347.997062 -245.677345) (xy 347.981014 -245.627952) (xy 347.972889 -245.576657)
			(xy 347.692979 -245.576657) (xy 347.684854 -245.627952) (xy 347.668806 -245.677345) (xy 347.645228 -245.723619)
			(xy 347.614702 -245.765635) (xy 347.577979 -245.802358) (xy 347.535963 -245.832884) (xy 347.489689 -245.856462)
			(xy 347.440296 -245.87251) (xy 347.389001 -245.880635) (xy 347.337067 -245.880635) (xy 347.285772 -245.87251)
			(xy 347.236379 -245.856462) (xy 347.190105 -245.832884) (xy 347.148089 -245.802358) (xy 347.111366 -245.765635)
			(xy 347.08084 -245.723619) (xy 347.057262 -245.677345) (xy 347.041214 -245.627952) (xy 347.033089 -245.576657)
			(xy 346.753179 -245.576657) (xy 346.745054 -245.627952) (xy 346.729006 -245.677345) (xy 346.705428 -245.723619)
			(xy 346.674902 -245.765635) (xy 346.638179 -245.802358) (xy 346.596163 -245.832884) (xy 346.549889 -245.856462)
			(xy 346.500496 -245.87251) (xy 346.449201 -245.880635) (xy 346.397267 -245.880635) (xy 346.345972 -245.87251)
			(xy 346.296579 -245.856462) (xy 346.250305 -245.832884) (xy 346.208289 -245.802358) (xy 346.171566 -245.765635)
			(xy 346.14104 -245.723619) (xy 346.117462 -245.677345) (xy 346.101414 -245.627952) (xy 346.093289 -245.576657)
			(xy 345.813125 -245.576657) (xy 345.805 -245.627952) (xy 345.788952 -245.677345) (xy 345.765374 -245.723619)
			(xy 345.734848 -245.765635) (xy 345.698125 -245.802358) (xy 345.656109 -245.832884) (xy 345.609835 -245.856462)
			(xy 345.560442 -245.87251) (xy 345.509147 -245.880635) (xy 345.457213 -245.880635) (xy 345.405918 -245.87251)
			(xy 345.356525 -245.856462) (xy 345.310251 -245.832884) (xy 345.268235 -245.802358) (xy 345.231512 -245.765635)
			(xy 345.200986 -245.723619) (xy 345.177408 -245.677345) (xy 345.16136 -245.627952) (xy 345.153235 -245.576657)
			(xy 344.873579 -245.576657) (xy 344.865454 -245.627952) (xy 344.849406 -245.677345) (xy 344.825828 -245.723619)
			(xy 344.795302 -245.765635) (xy 344.758579 -245.802358) (xy 344.716563 -245.832884) (xy 344.670289 -245.856462)
			(xy 344.620896 -245.87251) (xy 344.569601 -245.880635) (xy 344.517667 -245.880635) (xy 344.466372 -245.87251)
			(xy 344.416979 -245.856462) (xy 344.370705 -245.832884) (xy 344.328689 -245.802358) (xy 344.291966 -245.765635)
			(xy 344.26144 -245.723619) (xy 344.237862 -245.677345) (xy 344.221814 -245.627952) (xy 344.213689 -245.576657)
			(xy 343.933779 -245.576657) (xy 343.925654 -245.627952) (xy 343.909606 -245.677345) (xy 343.886028 -245.723619)
			(xy 343.855502 -245.765635) (xy 343.818779 -245.802358) (xy 343.776763 -245.832884) (xy 343.730489 -245.856462)
			(xy 343.681096 -245.87251) (xy 343.629801 -245.880635) (xy 343.577867 -245.880635) (xy 343.526572 -245.87251)
			(xy 343.477179 -245.856462) (xy 343.430905 -245.832884) (xy 343.388889 -245.802358) (xy 343.352166 -245.765635)
			(xy 343.32164 -245.723619) (xy 343.298062 -245.677345) (xy 343.282014 -245.627952) (xy 343.273889 -245.576657)
			(xy 342.993979 -245.576657) (xy 342.985854 -245.627952) (xy 342.969806 -245.677345) (xy 342.946228 -245.723619)
			(xy 342.915702 -245.765635) (xy 342.878979 -245.802358) (xy 342.836963 -245.832884) (xy 342.790689 -245.856462)
			(xy 342.741296 -245.87251) (xy 342.690001 -245.880635) (xy 342.638067 -245.880635) (xy 342.586772 -245.87251)
			(xy 342.537379 -245.856462) (xy 342.491105 -245.832884) (xy 342.449089 -245.802358) (xy 342.412366 -245.765635)
			(xy 342.38184 -245.723619) (xy 342.358262 -245.677345) (xy 342.342214 -245.627952) (xy 342.334089 -245.576657)
			(xy 342.054179 -245.576657) (xy 342.046054 -245.627952) (xy 342.030006 -245.677345) (xy 342.006428 -245.723619)
			(xy 341.975902 -245.765635) (xy 341.939179 -245.802358) (xy 341.897163 -245.832884) (xy 341.850889 -245.856462)
			(xy 341.801496 -245.87251) (xy 341.750201 -245.880635) (xy 341.698267 -245.880635) (xy 341.646972 -245.87251)
			(xy 341.597579 -245.856462) (xy 341.551305 -245.832884) (xy 341.509289 -245.802358) (xy 341.472566 -245.765635)
			(xy 341.44204 -245.723619) (xy 341.418462 -245.677345) (xy 341.402414 -245.627952) (xy 341.394289 -245.576657)
			(xy 341.114193 -245.576657) (xy 341.107606 -245.622082) (xy 341.093949 -245.668021) (xy 341.073801 -245.711505)
			(xy 341.06104 -245.731792) (xy 341.05723 -245.737634) (xy 341.04834 -245.765828) (xy 341.048867 -245.77567)
			(xy 341.056436 -245.793848) (xy 341.063072 -245.801134) (xy 341.2871 -246.025162) (xy 341.313008 -246.039132)
			(xy 341.313516 -246.039132) (xy 341.317834 -246.039894) (xy 341.320374 -246.040402) (xy 341.343942 -246.045669)
			(xy 341.389345 -246.06212) (xy 341.431874 -246.084998) (xy 341.470624 -246.113817) (xy 341.504772 -246.147963)
			(xy 341.533593 -246.186712) (xy 341.556473 -246.229239) (xy 341.572926 -246.274642) (xy 341.578184 -246.298212)
			(xy 341.578692 -246.300752) (xy 341.579454 -246.30507) (xy 341.579454 -246.305578) (xy 341.593424 -246.331486)
			(xy 341.69223 -246.430292) (xy 341.699064 -246.436506) (xy 341.71594 -246.443974) (xy 341.734371 -246.444915)
			(xy 341.743284 -246.442484) (xy 341.827358 -246.408448) (xy 341.832184 -246.406416) (xy 341.840967 -246.402396)
			(xy 341.854841 -246.388983) (xy 341.862663 -246.371341) (xy 341.863426 -246.361712) (xy 341.863426 -246.360188)
			(xy 341.864255 -246.334423) (xy 341.872916 -246.28361) (xy 341.889356 -246.234756) (xy 341.913177 -246.189044)
			(xy 341.943802 -246.147582) (xy 341.98049 -246.111373) (xy 342.022351 -246.081296) (xy 342.068372 -246.058077)
			(xy 342.117438 -246.042281) (xy 342.168361 -246.034288) (xy 342.194134 -246.033798) (xy 342.220119 -246.03431)
			(xy 342.271449 -246.042445) (xy 342.320875 -246.058509) (xy 342.367179 -246.082107) (xy 342.409222 -246.112657)
			(xy 342.445969 -246.149408) (xy 342.476514 -246.191455) (xy 342.500106 -246.237762) (xy 342.516164 -246.28719)
			(xy 342.524293 -246.338521) (xy 342.524842 -246.364506) (xy 342.524349 -246.390278) (xy 342.524318 -246.390473)
			(xy 342.803735 -246.390473) (xy 342.803735 -246.338539) (xy 342.81186 -246.287244) (xy 342.827908 -246.237851)
			(xy 342.851486 -246.191577) (xy 342.882012 -246.149561) (xy 342.918735 -246.112838) (xy 342.960751 -246.082312)
			(xy 343.007025 -246.058734) (xy 343.056418 -246.042686) (xy 343.107713 -246.034561) (xy 343.159647 -246.034561)
			(xy 343.210942 -246.042686) (xy 343.260335 -246.058734) (xy 343.306609 -246.082312) (xy 343.348625 -246.112838)
			(xy 343.385348 -246.149561) (xy 343.415874 -246.191577) (xy 343.439452 -246.237851) (xy 343.4555 -246.287244)
			(xy 343.463625 -246.338539) (xy 343.464134 -246.364506) (xy 343.463625 -246.390473) (xy 343.743535 -246.390473)
			(xy 343.743535 -246.338539) (xy 343.75166 -246.287244) (xy 343.767708 -246.237851) (xy 343.791286 -246.191577)
			(xy 343.821812 -246.149561) (xy 343.858535 -246.112838) (xy 343.900551 -246.082312) (xy 343.946825 -246.058734)
			(xy 343.996218 -246.042686) (xy 344.047513 -246.034561) (xy 344.099447 -246.034561) (xy 344.150742 -246.042686)
			(xy 344.200135 -246.058734) (xy 344.246409 -246.082312) (xy 344.288425 -246.112838) (xy 344.325148 -246.149561)
			(xy 344.355674 -246.191577) (xy 344.379252 -246.237851) (xy 344.3953 -246.287244) (xy 344.403425 -246.338539)
			(xy 344.403934 -246.364506) (xy 344.403425 -246.390473) (xy 344.683335 -246.390473) (xy 344.683335 -246.338539)
			(xy 344.69146 -246.287244) (xy 344.707508 -246.237851) (xy 344.731086 -246.191577) (xy 344.761612 -246.149561)
			(xy 344.798335 -246.112838) (xy 344.840351 -246.082312) (xy 344.886625 -246.058734) (xy 344.936018 -246.042686)
			(xy 344.987313 -246.034561) (xy 345.039247 -246.034561) (xy 345.090542 -246.042686) (xy 345.139935 -246.058734)
			(xy 345.186209 -246.082312) (xy 345.228225 -246.112838) (xy 345.264948 -246.149561) (xy 345.295474 -246.191577)
			(xy 345.319052 -246.237851) (xy 345.3351 -246.287244) (xy 345.343225 -246.338539) (xy 345.343734 -246.364506)
			(xy 345.343225 -246.390473) (xy 345.623135 -246.390473) (xy 345.623135 -246.338539) (xy 345.63126 -246.287244)
			(xy 345.647308 -246.237851) (xy 345.670886 -246.191577) (xy 345.701412 -246.149561) (xy 345.738135 -246.112838)
			(xy 345.780151 -246.082312) (xy 345.826425 -246.058734) (xy 345.875818 -246.042686) (xy 345.927113 -246.034561)
			(xy 345.979047 -246.034561) (xy 346.030342 -246.042686) (xy 346.079735 -246.058734) (xy 346.126009 -246.082312)
			(xy 346.168025 -246.112838) (xy 346.204748 -246.149561) (xy 346.235274 -246.191577) (xy 346.258852 -246.237851)
			(xy 346.2749 -246.287244) (xy 346.283025 -246.338539) (xy 346.283534 -246.364506) (xy 346.283025 -246.390473)
			(xy 346.562935 -246.390473) (xy 346.562935 -246.338539) (xy 346.57106 -246.287244) (xy 346.587108 -246.237851)
			(xy 346.610686 -246.191577) (xy 346.641212 -246.149561) (xy 346.677935 -246.112838) (xy 346.719951 -246.082312)
			(xy 346.766225 -246.058734) (xy 346.815618 -246.042686) (xy 346.866913 -246.034561) (xy 346.918847 -246.034561)
			(xy 346.970142 -246.042686) (xy 347.019535 -246.058734) (xy 347.065809 -246.082312) (xy 347.107825 -246.112838)
			(xy 347.144548 -246.149561) (xy 347.175074 -246.191577) (xy 347.198652 -246.237851) (xy 347.2147 -246.287244)
			(xy 347.222825 -246.338539) (xy 347.223334 -246.364506) (xy 347.222825 -246.390473) (xy 347.502735 -246.390473)
			(xy 347.502735 -246.338539) (xy 347.51086 -246.287244) (xy 347.526908 -246.237851) (xy 347.550486 -246.191577)
			(xy 347.581012 -246.149561) (xy 347.617735 -246.112838) (xy 347.659751 -246.082312) (xy 347.706025 -246.058734)
			(xy 347.755418 -246.042686) (xy 347.806713 -246.034561) (xy 347.858647 -246.034561) (xy 347.909942 -246.042686)
			(xy 347.959335 -246.058734) (xy 348.005609 -246.082312) (xy 348.047625 -246.112838) (xy 348.084348 -246.149561)
			(xy 348.114874 -246.191577) (xy 348.138452 -246.237851) (xy 348.1545 -246.287244) (xy 348.162625 -246.338539)
			(xy 348.163134 -246.364506) (xy 348.162625 -246.390473) (xy 348.442789 -246.390473) (xy 348.442789 -246.338539)
			(xy 348.450914 -246.287244) (xy 348.466962 -246.237851) (xy 348.49054 -246.191577) (xy 348.521066 -246.149561)
			(xy 348.557789 -246.112838) (xy 348.599805 -246.082312) (xy 348.646079 -246.058734) (xy 348.695472 -246.042686)
			(xy 348.746767 -246.034561) (xy 348.798701 -246.034561) (xy 348.849996 -246.042686) (xy 348.899389 -246.058734)
			(xy 348.945663 -246.082312) (xy 348.987679 -246.112838) (xy 349.024402 -246.149561) (xy 349.054928 -246.191577)
			(xy 349.078506 -246.237851) (xy 349.094554 -246.287244) (xy 349.102679 -246.338539) (xy 349.103188 -246.364506)
			(xy 349.102679 -246.390473) (xy 349.382335 -246.390473) (xy 349.382335 -246.338539) (xy 349.39046 -246.287244)
			(xy 349.406508 -246.237851) (xy 349.430086 -246.191577) (xy 349.460612 -246.149561) (xy 349.497335 -246.112838)
			(xy 349.539351 -246.082312) (xy 349.585625 -246.058734) (xy 349.635018 -246.042686) (xy 349.686313 -246.034561)
			(xy 349.738247 -246.034561) (xy 349.789542 -246.042686) (xy 349.838935 -246.058734) (xy 349.885209 -246.082312)
			(xy 349.927225 -246.112838) (xy 349.963948 -246.149561) (xy 349.994474 -246.191577) (xy 350.018052 -246.237851)
			(xy 350.0341 -246.287244) (xy 350.042225 -246.338539) (xy 350.042734 -246.364506) (xy 350.042225 -246.390473)
			(xy 350.0341 -246.441768) (xy 350.018052 -246.491161) (xy 349.994474 -246.537435) (xy 349.963948 -246.579451)
			(xy 349.927225 -246.616174) (xy 349.885209 -246.6467) (xy 349.838935 -246.670278) (xy 349.79342 -246.685066)
			(xy 350.425275 -246.685066) (xy 350.425275 -246.633134) (xy 350.433399 -246.581842) (xy 350.449447 -246.532452)
			(xy 350.473023 -246.48618) (xy 350.503548 -246.444167) (xy 350.54027 -246.407446) (xy 350.582284 -246.376921)
			(xy 350.628555 -246.353345) (xy 350.677946 -246.337298) (xy 350.729238 -246.329174) (xy 350.755204 -246.328692)
			(xy 350.755458 -246.328692) (xy 350.779986 -246.329111) (xy 350.8285 -246.336382) (xy 350.875407 -246.350741)
			(xy 350.919678 -246.371874) (xy 350.960341 -246.399315) (xy 350.978724 -246.41556) (xy 350.990213 -246.425363)
			(xy 351.01745 -246.438377) (xy 351.047304 -246.442845) (xy 351.077158 -246.438377) (xy 351.104395 -246.425363)
			(xy 351.115884 -246.41556) (xy 351.134284 -246.399297) (xy 351.174989 -246.371827) (xy 351.219313 -246.350688)
			(xy 351.266279 -246.336347) (xy 351.31485 -246.329119) (xy 351.339404 -246.328692) (xy 351.363958 -246.329094)
			(xy 351.412526 -246.336343) (xy 351.459489 -246.350695) (xy 351.503812 -246.371836) (xy 351.544521 -246.399299)
			(xy 351.562924 -246.41556) (xy 351.574413 -246.425363) (xy 351.60165 -246.438377) (xy 351.631504 -246.442845)
			(xy 351.661358 -246.438377) (xy 351.688595 -246.425363) (xy 351.700084 -246.41556) (xy 351.718484 -246.399297)
			(xy 351.759189 -246.371827) (xy 351.803513 -246.350688) (xy 351.850479 -246.336347) (xy 351.89905 -246.329119)
			(xy 351.923604 -246.328692) (xy 351.948158 -246.329094) (xy 351.996726 -246.336343) (xy 352.043689 -246.350695)
			(xy 352.088012 -246.371836) (xy 352.128721 -246.399299) (xy 352.147124 -246.41556) (xy 352.158613 -246.425363)
			(xy 352.18585 -246.438377) (xy 352.215704 -246.442845) (xy 352.245558 -246.438377) (xy 352.272795 -246.425363)
			(xy 352.284284 -246.41556) (xy 352.302664 -246.399312) (xy 352.343323 -246.371865) (xy 352.387594 -246.350735)
			(xy 352.434505 -246.336386) (xy 352.483022 -246.329136) (xy 352.50755 -246.328692) (xy 352.507804 -246.328692)
			(xy 352.533212 -246.329206) (xy 352.583429 -246.336991) (xy 352.631865 -246.352364) (xy 352.677381 -246.374961)
			(xy 352.718907 -246.404252) (xy 352.755466 -246.439547) (xy 352.771202 -246.459502) (xy 352.780911 -246.471461)
			(xy 352.805961 -246.489366) (xy 352.835206 -246.498999) (xy 352.865993 -246.499487) (xy 352.895528 -246.490785)
			(xy 352.921132 -246.473683) (xy 352.931222 -246.462042) (xy 352.947026 -246.443195) (xy 352.983204 -246.409877)
			(xy 353.023921 -246.382291) (xy 353.068279 -246.361046) (xy 353.115296 -246.346613) (xy 353.163933 -246.33931)
			(xy 353.188524 -246.338852) (xy 353.214278 -246.339335) (xy 353.265163 -246.347318) (xy 353.314192 -246.363101)
			(xy 353.360178 -246.386303) (xy 353.402006 -246.41636) (xy 353.42068 -246.434102) (xy 353.43037 -246.443095)
			(xy 353.453302 -246.456227) (xy 353.478841 -246.463022) (xy 353.505267 -246.463022) (xy 353.530806 -246.456227)
			(xy 353.553738 -246.443095) (xy 353.563428 -246.434102) (xy 353.582096 -246.416355) (xy 353.623931 -246.386311)
			(xy 353.66992 -246.363117) (xy 353.718948 -246.347334) (xy 353.769831 -246.339345) (xy 353.795584 -246.338852)
			(xy 353.821555 -246.339322) (xy 353.872857 -246.347445) (xy 353.922256 -246.363494) (xy 353.968537 -246.387073)
			(xy 354.010559 -246.417602) (xy 354.047288 -246.454329) (xy 354.077819 -246.496349) (xy 354.1014 -246.542629)
			(xy 354.117451 -246.592028) (xy 354.125577 -246.643329) (xy 354.125577 -246.685063) (xy 354.342001 -246.685063)
			(xy 354.342001 -246.633137) (xy 354.350124 -246.581851) (xy 354.366169 -246.532466) (xy 354.389742 -246.4862)
			(xy 354.420263 -246.444191) (xy 354.456979 -246.407473) (xy 354.498986 -246.376951) (xy 354.545252 -246.353375)
			(xy 354.594635 -246.337327) (xy 354.645921 -246.329202) (xy 354.671884 -246.328692) (xy 354.698878 -246.329226)
			(xy 354.752149 -246.338001) (xy 354.803284 -246.355319) (xy 354.850923 -246.38072) (xy 354.893799 -246.413528)
			(xy 354.912676 -246.432832) (xy 354.922501 -246.44265) (xy 354.946227 -246.457067) (xy 354.972962 -246.464553)
			(xy 355.000726 -246.464553) (xy 355.027461 -246.457067) (xy 355.051187 -246.44265) (xy 355.061012 -246.432832)
			(xy 355.079895 -246.413535) (xy 355.12277 -246.380726) (xy 355.170407 -246.355324) (xy 355.221541 -246.338005)
			(xy 355.27481 -246.329228) (xy 355.301804 -246.328692) (xy 355.327775 -246.32911) (xy 355.379076 -246.337236)
			(xy 355.428475 -246.353287) (xy 355.474755 -246.376868) (xy 355.516776 -246.407399) (xy 355.553504 -246.444127)
			(xy 355.584034 -246.486148) (xy 355.607615 -246.532429) (xy 355.623665 -246.581828) (xy 355.631791 -246.633129)
			(xy 355.631791 -246.685071) (xy 355.629179 -246.701564) (xy 356.28961 -246.701564) (xy 356.28961 -246.70131)
			(xy 356.290065 -246.676783) (xy 356.297327 -246.628271) (xy 356.311677 -246.581363) (xy 356.332802 -246.537092)
			(xy 356.360236 -246.496428) (xy 356.376478 -246.478044) (xy 356.386317 -246.466583) (xy 356.399326 -246.439335)
			(xy 356.403788 -246.409473) (xy 356.399311 -246.379614) (xy 356.386287 -246.352373) (xy 356.376478 -246.340884)
			(xy 356.360202 -246.322528) (xy 356.332761 -246.281862) (xy 356.311638 -246.237584) (xy 356.297296 -246.190668)
			(xy 356.290052 -246.142147) (xy 356.28961 -246.117618) (xy 356.28961 -246.117364) (xy 356.290122 -246.091398)
			(xy 356.29825 -246.040105) (xy 356.314302 -245.990715) (xy 356.337881 -245.944443) (xy 356.368407 -245.902429)
			(xy 356.405129 -245.865707) (xy 356.447143 -245.835181) (xy 356.493415 -245.811602) (xy 356.542805 -245.79555)
			(xy 356.594098 -245.787422) (xy 356.620064 -245.78691) (xy 356.645928 -245.787458) (xy 356.697029 -245.795492)
			(xy 356.74625 -245.8114) (xy 356.792387 -245.834793) (xy 356.834309 -245.865097) (xy 356.870989 -245.901571)
			(xy 356.90153 -245.943321) (xy 356.925183 -245.989324) (xy 356.933754 -246.013732) (xy 356.938859 -246.027559)
			(xy 356.955681 -246.051744) (xy 356.978702 -246.070126) (xy 357.006011 -246.081179) (xy 357.035337 -246.083982)
			(xy 357.064245 -246.078305) (xy 357.077518 -246.071898) (xy 357.101332 -246.060019) (xy 357.151808 -246.043173)
			(xy 357.204328 -246.034611) (xy 357.230934 -246.034052) (xy 357.2569 -246.034552) (xy 357.308192 -246.042681)
			(xy 357.357581 -246.058732) (xy 357.403851 -246.082312) (xy 357.445863 -246.11284) (xy 357.482582 -246.149563)
			(xy 357.513105 -246.191578) (xy 357.536681 -246.237851) (xy 357.552727 -246.287241) (xy 357.560851 -246.338534)
			(xy 357.560851 -246.390466) (xy 357.56085 -246.390473) (xy 357.840789 -246.390473) (xy 357.840789 -246.338539)
			(xy 357.848914 -246.287244) (xy 357.864962 -246.237851) (xy 357.88854 -246.191577) (xy 357.919066 -246.149561)
			(xy 357.955789 -246.112838) (xy 357.997805 -246.082312) (xy 358.044079 -246.058734) (xy 358.093472 -246.042686)
			(xy 358.144767 -246.034561) (xy 358.196701 -246.034561) (xy 358.247996 -246.042686) (xy 358.297389 -246.058734)
			(xy 358.343663 -246.082312) (xy 358.385679 -246.112838) (xy 358.422402 -246.149561) (xy 358.452928 -246.191577)
			(xy 358.476506 -246.237851) (xy 358.492554 -246.287244) (xy 358.500679 -246.338539) (xy 358.501188 -246.364506)
			(xy 358.500679 -246.390473) (xy 358.780589 -246.390473) (xy 358.780589 -246.338539) (xy 358.788714 -246.287244)
			(xy 358.804762 -246.237851) (xy 358.82834 -246.191577) (xy 358.858866 -246.149561) (xy 358.895589 -246.112838)
			(xy 358.937605 -246.082312) (xy 358.983879 -246.058734) (xy 359.033272 -246.042686) (xy 359.084567 -246.034561)
			(xy 359.136501 -246.034561) (xy 359.187796 -246.042686) (xy 359.237189 -246.058734) (xy 359.283463 -246.082312)
			(xy 359.325479 -246.112838) (xy 359.362202 -246.149561) (xy 359.392728 -246.191577) (xy 359.416306 -246.237851)
			(xy 359.432354 -246.287244) (xy 359.440479 -246.338539) (xy 359.440988 -246.364506) (xy 359.440479 -246.390473)
			(xy 359.720389 -246.390473) (xy 359.720389 -246.338539) (xy 359.728514 -246.287244) (xy 359.744562 -246.237851)
			(xy 359.76814 -246.191577) (xy 359.798666 -246.149561) (xy 359.835389 -246.112838) (xy 359.877405 -246.082312)
			(xy 359.923679 -246.058734) (xy 359.973072 -246.042686) (xy 360.024367 -246.034561) (xy 360.076301 -246.034561)
			(xy 360.127596 -246.042686) (xy 360.176989 -246.058734) (xy 360.223263 -246.082312) (xy 360.265279 -246.112838)
			(xy 360.302002 -246.149561) (xy 360.332528 -246.191577) (xy 360.356106 -246.237851) (xy 360.372154 -246.287244)
			(xy 360.380279 -246.338539) (xy 360.380788 -246.364506) (xy 360.380279 -246.390473) (xy 360.659935 -246.390473)
			(xy 360.659935 -246.338539) (xy 360.66806 -246.287244) (xy 360.684108 -246.237851) (xy 360.707686 -246.191577)
			(xy 360.738212 -246.149561) (xy 360.774935 -246.112838) (xy 360.816951 -246.082312) (xy 360.863225 -246.058734)
			(xy 360.912618 -246.042686) (xy 360.963913 -246.034561) (xy 361.015847 -246.034561) (xy 361.067142 -246.042686)
			(xy 361.116535 -246.058734) (xy 361.162809 -246.082312) (xy 361.204825 -246.112838) (xy 361.241548 -246.149561)
			(xy 361.272074 -246.191577) (xy 361.295652 -246.237851) (xy 361.3117 -246.287244) (xy 361.319825 -246.338539)
			(xy 361.320334 -246.364506) (xy 361.319825 -246.390473) (xy 361.599989 -246.390473) (xy 361.599989 -246.338539)
			(xy 361.608114 -246.287244) (xy 361.624162 -246.237851) (xy 361.64774 -246.191577) (xy 361.678266 -246.149561)
			(xy 361.714989 -246.112838) (xy 361.757005 -246.082312) (xy 361.803279 -246.058734) (xy 361.852672 -246.042686)
			(xy 361.903967 -246.034561) (xy 361.955901 -246.034561) (xy 362.007196 -246.042686) (xy 362.056589 -246.058734)
			(xy 362.102863 -246.082312) (xy 362.144879 -246.112838) (xy 362.181602 -246.149561) (xy 362.212128 -246.191577)
			(xy 362.235706 -246.237851) (xy 362.251754 -246.287244) (xy 362.259879 -246.338539) (xy 362.260388 -246.364506)
			(xy 362.259879 -246.390473) (xy 362.251754 -246.441768) (xy 362.235706 -246.491161) (xy 362.212128 -246.537435)
			(xy 362.181602 -246.579451) (xy 362.144879 -246.616174) (xy 362.102863 -246.6467) (xy 362.056589 -246.670278)
			(xy 362.007196 -246.686326) (xy 361.955901 -246.694451) (xy 361.903967 -246.694451) (xy 361.852672 -246.686326)
			(xy 361.803279 -246.670278) (xy 361.757005 -246.6467) (xy 361.714989 -246.616174) (xy 361.678266 -246.579451)
			(xy 361.64774 -246.537435) (xy 361.624162 -246.491161) (xy 361.608114 -246.441768) (xy 361.599989 -246.390473)
			(xy 361.319825 -246.390473) (xy 361.3117 -246.441768) (xy 361.295652 -246.491161) (xy 361.272074 -246.537435)
			(xy 361.241548 -246.579451) (xy 361.204825 -246.616174) (xy 361.162809 -246.6467) (xy 361.116535 -246.670278)
			(xy 361.067142 -246.686326) (xy 361.015847 -246.694451) (xy 360.963913 -246.694451) (xy 360.912618 -246.686326)
			(xy 360.863225 -246.670278) (xy 360.816951 -246.6467) (xy 360.774935 -246.616174) (xy 360.738212 -246.579451)
			(xy 360.707686 -246.537435) (xy 360.684108 -246.491161) (xy 360.66806 -246.441768) (xy 360.659935 -246.390473)
			(xy 360.380279 -246.390473) (xy 360.372154 -246.441768) (xy 360.356106 -246.491161) (xy 360.332528 -246.537435)
			(xy 360.302002 -246.579451) (xy 360.265279 -246.616174) (xy 360.223263 -246.6467) (xy 360.176989 -246.670278)
			(xy 360.127596 -246.686326) (xy 360.076301 -246.694451) (xy 360.024367 -246.694451) (xy 359.973072 -246.686326)
			(xy 359.923679 -246.670278) (xy 359.877405 -246.6467) (xy 359.835389 -246.616174) (xy 359.798666 -246.579451)
			(xy 359.76814 -246.537435) (xy 359.744562 -246.491161) (xy 359.728514 -246.441768) (xy 359.720389 -246.390473)
			(xy 359.440479 -246.390473) (xy 359.432354 -246.441768) (xy 359.416306 -246.491161) (xy 359.392728 -246.537435)
			(xy 359.362202 -246.579451) (xy 359.325479 -246.616174) (xy 359.283463 -246.6467) (xy 359.237189 -246.670278)
			(xy 359.187796 -246.686326) (xy 359.136501 -246.694451) (xy 359.084567 -246.694451) (xy 359.033272 -246.686326)
			(xy 358.983879 -246.670278) (xy 358.937605 -246.6467) (xy 358.895589 -246.616174) (xy 358.858866 -246.579451)
			(xy 358.82834 -246.537435) (xy 358.804762 -246.491161) (xy 358.788714 -246.441768) (xy 358.780589 -246.390473)
			(xy 358.500679 -246.390473) (xy 358.492554 -246.441768) (xy 358.476506 -246.491161) (xy 358.452928 -246.537435)
			(xy 358.422402 -246.579451) (xy 358.385679 -246.616174) (xy 358.343663 -246.6467) (xy 358.297389 -246.670278)
			(xy 358.247996 -246.686326) (xy 358.196701 -246.694451) (xy 358.144767 -246.694451) (xy 358.093472 -246.686326)
			(xy 358.044079 -246.670278) (xy 357.997805 -246.6467) (xy 357.955789 -246.616174) (xy 357.919066 -246.579451)
			(xy 357.88854 -246.537435) (xy 357.864962 -246.491161) (xy 357.848914 -246.441768) (xy 357.840789 -246.390473)
			(xy 357.56085 -246.390473) (xy 357.552727 -246.441759) (xy 357.536681 -246.491149) (xy 357.513105 -246.537422)
			(xy 357.482582 -246.579437) (xy 357.445863 -246.61616) (xy 357.403851 -246.646688) (xy 357.357581 -246.670268)
			(xy 357.308192 -246.686319) (xy 357.2569 -246.694448) (xy 357.230934 -246.69496) (xy 357.230426 -246.69496)
			(xy 357.206512 -246.694517) (xy 357.159187 -246.687593) (xy 357.113356 -246.673915) (xy 357.091488 -246.664226)
			(xy 357.078951 -246.658789) (xy 357.052011 -246.654254) (xy 357.024832 -246.657032) (xy 356.999366 -246.666924)
			(xy 356.977439 -246.683221) (xy 356.960625 -246.704754) (xy 356.950129 -246.729977) (xy 356.947978 -246.743474)
			(xy 356.944052 -246.76971) (xy 356.929 -246.820573) (xy 356.906018 -246.868379) (xy 356.875695 -246.911901)
			(xy 356.838811 -246.950022) (xy 356.796312 -246.981763) (xy 356.749289 -247.006308) (xy 356.69895 -247.023028)
			(xy 356.646586 -247.031494) (xy 356.620064 -247.032018) (xy 356.594094 -247.031578) (xy 356.542794 -247.023447)
			(xy 356.493398 -247.007391) (xy 356.447122 -246.983806) (xy 356.405105 -246.953272) (xy 356.368381 -246.916541)
			(xy 356.337856 -246.874517) (xy 356.314281 -246.828235) (xy 356.298236 -246.778836) (xy 356.290117 -246.727534)
			(xy 356.28961 -246.701564) (xy 355.629179 -246.701564) (xy 355.623665 -246.736372) (xy 355.607615 -246.785772)
			(xy 355.584034 -246.832052) (xy 355.553504 -246.874073) (xy 355.516776 -246.910801) (xy 355.474755 -246.941332)
			(xy 355.428475 -246.964913) (xy 355.379076 -246.980964) (xy 355.327775 -246.98909) (xy 355.301804 -246.9896)
			(xy 355.274811 -246.989046) (xy 355.221543 -246.980272) (xy 355.170409 -246.962957) (xy 355.122769 -246.937561)
			(xy 355.079891 -246.90476) (xy 355.061012 -246.88546) (xy 355.051187 -246.875642) (xy 355.027461 -246.861225)
			(xy 355.000726 -246.853739) (xy 354.972962 -246.853739) (xy 354.946227 -246.861225) (xy 354.922501 -246.875642)
			(xy 354.912676 -246.88546) (xy 354.893797 -246.904761) (xy 354.850922 -246.93757) (xy 354.803283 -246.962971)
			(xy 354.752148 -246.98029) (xy 354.698878 -246.989065) (xy 354.671884 -246.9896) (xy 354.645921 -246.988998)
			(xy 354.594635 -246.980873) (xy 354.545252 -246.964825) (xy 354.498986 -246.941249) (xy 354.456979 -246.910727)
			(xy 354.420263 -246.874009) (xy 354.389742 -246.832) (xy 354.366169 -246.785734) (xy 354.350124 -246.736349)
			(xy 354.342001 -246.685063) (xy 354.125577 -246.685063) (xy 354.125577 -246.695271) (xy 354.117451 -246.746572)
			(xy 354.1014 -246.795971) (xy 354.077819 -246.842251) (xy 354.047288 -246.884271) (xy 354.010559 -246.920998)
			(xy 353.968537 -246.951527) (xy 353.922256 -246.975106) (xy 353.872857 -246.991155) (xy 353.821555 -246.999278)
			(xy 353.795584 -246.99976) (xy 353.769829 -246.999296) (xy 353.718942 -246.991313) (xy 353.669911 -246.975526)
			(xy 353.623926 -246.95232) (xy 353.5821 -246.922255) (xy 353.563428 -246.90451) (xy 353.553738 -246.895517)
			(xy 353.530806 -246.882385) (xy 353.505267 -246.87559) (xy 353.478841 -246.87559) (xy 353.453302 -246.882385)
			(xy 353.43037 -246.895517) (xy 353.42068 -246.90451) (xy 353.40201 -246.922255) (xy 353.360175 -246.952299)
			(xy 353.314187 -246.975493) (xy 353.265159 -246.991276) (xy 353.214277 -246.999266) (xy 353.188524 -246.99976)
			(xy 353.163113 -246.999317) (xy 353.112892 -246.991519) (xy 353.064454 -246.976134) (xy 353.018937 -246.953524)
			(xy 352.977414 -246.92422) (xy 352.940859 -246.888911) (xy 352.925126 -246.86895) (xy 352.915388 -246.857014)
			(xy 352.890349 -246.8391) (xy 352.861109 -246.829459) (xy 352.830326 -246.828966) (xy 352.800793 -246.837666)
			(xy 352.775192 -246.854769) (xy 352.765106 -246.86641) (xy 352.749354 -246.885302) (xy 352.713164 -246.918615)
			(xy 352.672435 -246.946194) (xy 352.628068 -246.96743) (xy 352.581042 -246.981854) (xy 352.532398 -246.989147)
			(xy 352.507804 -246.9896) (xy 352.50755 -246.9896) (xy 352.483022 -246.989178) (xy 352.434508 -246.981908)
			(xy 352.387601 -246.96755) (xy 352.34333 -246.946418) (xy 352.302667 -246.918977) (xy 352.284284 -246.902732)
			(xy 352.272795 -246.892929) (xy 352.245558 -246.879915) (xy 352.215704 -246.875447) (xy 352.18585 -246.879915)
			(xy 352.158613 -246.892929) (xy 352.147124 -246.902732) (xy 352.128719 -246.91899) (xy 352.088016 -246.946461)
			(xy 352.043693 -246.967601) (xy 351.996728 -246.981943) (xy 351.948157 -246.989172) (xy 351.923604 -246.9896)
			(xy 351.899051 -246.989195) (xy 351.850482 -246.981947) (xy 351.803519 -246.967596) (xy 351.759196 -246.946456)
			(xy 351.718487 -246.918993) (xy 351.700084 -246.902732) (xy 351.688595 -246.892929) (xy 351.661358 -246.879915)
			(xy 351.631504 -246.875447) (xy 351.60165 -246.879915) (xy 351.574413 -246.892929) (xy 351.562924 -246.902732)
			(xy 351.544519 -246.91899) (xy 351.503816 -246.946461) (xy 351.459493 -246.967601) (xy 351.412528 -246.981943)
			(xy 351.363957 -246.989172) (xy 351.339404 -246.9896) (xy 351.314851 -246.989195) (xy 351.266282 -246.981947)
			(xy 351.219319 -246.967596) (xy 351.174996 -246.946456) (xy 351.134287 -246.918993) (xy 351.115884 -246.902732)
			(xy 351.104395 -246.892929) (xy 351.077158 -246.879915) (xy 351.047304 -246.875447) (xy 351.01745 -246.879915)
			(xy 350.990213 -246.892929) (xy 350.978724 -246.902732) (xy 350.960339 -246.918974) (xy 350.919682 -246.946423)
			(xy 350.875412 -246.967555) (xy 350.828502 -246.981904) (xy 350.779986 -246.989155) (xy 350.755458 -246.9896)
			(xy 350.755204 -246.9896) (xy 350.729238 -246.989026) (xy 350.677946 -246.980902) (xy 350.628555 -246.964855)
			(xy 350.582284 -246.941279) (xy 350.54027 -246.910754) (xy 350.503548 -246.874033) (xy 350.473023 -246.83202)
			(xy 350.449447 -246.785748) (xy 350.433399 -246.736358) (xy 350.425275 -246.685066) (xy 349.79342 -246.685066)
			(xy 349.789542 -246.686326) (xy 349.738247 -246.694451) (xy 349.686313 -246.694451) (xy 349.635018 -246.686326)
			(xy 349.585625 -246.670278) (xy 349.539351 -246.6467) (xy 349.497335 -246.616174) (xy 349.460612 -246.579451)
			(xy 349.430086 -246.537435) (xy 349.406508 -246.491161) (xy 349.39046 -246.441768) (xy 349.382335 -246.390473)
			(xy 349.102679 -246.390473) (xy 349.094554 -246.441768) (xy 349.078506 -246.491161) (xy 349.054928 -246.537435)
			(xy 349.024402 -246.579451) (xy 348.987679 -246.616174) (xy 348.945663 -246.6467) (xy 348.899389 -246.670278)
			(xy 348.849996 -246.686326) (xy 348.798701 -246.694451) (xy 348.746767 -246.694451) (xy 348.695472 -246.686326)
			(xy 348.646079 -246.670278) (xy 348.599805 -246.6467) (xy 348.557789 -246.616174) (xy 348.521066 -246.579451)
			(xy 348.49054 -246.537435) (xy 348.466962 -246.491161) (xy 348.450914 -246.441768) (xy 348.442789 -246.390473)
			(xy 348.162625 -246.390473) (xy 348.1545 -246.441768) (xy 348.138452 -246.491161) (xy 348.114874 -246.537435)
			(xy 348.084348 -246.579451) (xy 348.047625 -246.616174) (xy 348.005609 -246.6467) (xy 347.959335 -246.670278)
			(xy 347.909942 -246.686326) (xy 347.858647 -246.694451) (xy 347.806713 -246.694451) (xy 347.755418 -246.686326)
			(xy 347.706025 -246.670278) (xy 347.659751 -246.6467) (xy 347.617735 -246.616174) (xy 347.581012 -246.579451)
			(xy 347.550486 -246.537435) (xy 347.526908 -246.491161) (xy 347.51086 -246.441768) (xy 347.502735 -246.390473)
			(xy 347.222825 -246.390473) (xy 347.2147 -246.441768) (xy 347.198652 -246.491161) (xy 347.175074 -246.537435)
			(xy 347.144548 -246.579451) (xy 347.107825 -246.616174) (xy 347.065809 -246.6467) (xy 347.019535 -246.670278)
			(xy 346.970142 -246.686326) (xy 346.918847 -246.694451) (xy 346.866913 -246.694451) (xy 346.815618 -246.686326)
			(xy 346.766225 -246.670278) (xy 346.719951 -246.6467) (xy 346.677935 -246.616174) (xy 346.641212 -246.579451)
			(xy 346.610686 -246.537435) (xy 346.587108 -246.491161) (xy 346.57106 -246.441768) (xy 346.562935 -246.390473)
			(xy 346.283025 -246.390473) (xy 346.2749 -246.441768) (xy 346.258852 -246.491161) (xy 346.235274 -246.537435)
			(xy 346.204748 -246.579451) (xy 346.168025 -246.616174) (xy 346.126009 -246.6467) (xy 346.079735 -246.670278)
			(xy 346.030342 -246.686326) (xy 345.979047 -246.694451) (xy 345.927113 -246.694451) (xy 345.875818 -246.686326)
			(xy 345.826425 -246.670278) (xy 345.780151 -246.6467) (xy 345.738135 -246.616174) (xy 345.701412 -246.579451)
			(xy 345.670886 -246.537435) (xy 345.647308 -246.491161) (xy 345.63126 -246.441768) (xy 345.623135 -246.390473)
			(xy 345.343225 -246.390473) (xy 345.3351 -246.441768) (xy 345.319052 -246.491161) (xy 345.295474 -246.537435)
			(xy 345.264948 -246.579451) (xy 345.228225 -246.616174) (xy 345.186209 -246.6467) (xy 345.139935 -246.670278)
			(xy 345.090542 -246.686326) (xy 345.039247 -246.694451) (xy 344.987313 -246.694451) (xy 344.936018 -246.686326)
			(xy 344.886625 -246.670278) (xy 344.840351 -246.6467) (xy 344.798335 -246.616174) (xy 344.761612 -246.579451)
			(xy 344.731086 -246.537435) (xy 344.707508 -246.491161) (xy 344.69146 -246.441768) (xy 344.683335 -246.390473)
			(xy 344.403425 -246.390473) (xy 344.3953 -246.441768) (xy 344.379252 -246.491161) (xy 344.355674 -246.537435)
			(xy 344.325148 -246.579451) (xy 344.288425 -246.616174) (xy 344.246409 -246.6467) (xy 344.200135 -246.670278)
			(xy 344.150742 -246.686326) (xy 344.099447 -246.694451) (xy 344.047513 -246.694451) (xy 343.996218 -246.686326)
			(xy 343.946825 -246.670278) (xy 343.900551 -246.6467) (xy 343.858535 -246.616174) (xy 343.821812 -246.579451)
			(xy 343.791286 -246.537435) (xy 343.767708 -246.491161) (xy 343.75166 -246.441768) (xy 343.743535 -246.390473)
			(xy 343.463625 -246.390473) (xy 343.4555 -246.441768) (xy 343.439452 -246.491161) (xy 343.415874 -246.537435)
			(xy 343.385348 -246.579451) (xy 343.348625 -246.616174) (xy 343.306609 -246.6467) (xy 343.260335 -246.670278)
			(xy 343.210942 -246.686326) (xy 343.159647 -246.694451) (xy 343.107713 -246.694451) (xy 343.056418 -246.686326)
			(xy 343.007025 -246.670278) (xy 342.960751 -246.6467) (xy 342.918735 -246.616174) (xy 342.882012 -246.579451)
			(xy 342.851486 -246.537435) (xy 342.827908 -246.491161) (xy 342.81186 -246.441768) (xy 342.803735 -246.390473)
			(xy 342.524318 -246.390473) (xy 342.516352 -246.441199) (xy 342.500552 -246.490262) (xy 342.477332 -246.53628)
			(xy 342.447254 -246.578139) (xy 342.411047 -246.614825) (xy 342.369587 -246.64545) (xy 342.323878 -246.669273)
			(xy 342.275026 -246.685716) (xy 342.224216 -246.694382) (xy 342.198452 -246.695214) (xy 342.196928 -246.695214)
			(xy 342.187309 -246.696003) (xy 342.169693 -246.703849) (xy 342.15627 -246.717693) (xy 342.152224 -246.726456)
			(xy 342.150192 -246.731282) (xy 342.116156 -246.815356) (xy 342.113579 -246.824253) (xy 342.114478 -246.842742)
			(xy 342.122019 -246.859647) (xy 342.128348 -246.86641) (xy 342.250268 -246.98833) (xy 342.258071 -246.995336)
			(xy 342.277629 -247.002836) (xy 342.288114 -247.002808) (xy 342.366092 -246.997474) (xy 342.370655 -246.99694)
			(xy 342.379481 -246.994391) (xy 342.383618 -246.992394) (xy 342.394286 -246.986552) (xy 342.40089 -246.977916)
			(xy 342.416657 -246.958039) (xy 342.453213 -246.922861) (xy 342.494707 -246.893671) (xy 342.540168 -246.871153)
			(xy 342.588533 -246.855832) (xy 342.638668 -246.848068) (xy 342.664034 -246.847614) (xy 342.690019 -246.848126)
			(xy 342.741348 -246.856261) (xy 342.790772 -246.872325) (xy 342.837076 -246.895923) (xy 342.879117 -246.926474)
			(xy 342.915862 -246.963225) (xy 342.946406 -247.005272) (xy 342.969996 -247.051579) (xy 342.986052 -247.101007)
			(xy 342.994178 -247.152337) (xy 342.994742 -247.178322) (xy 342.994742 -247.178576) (xy 342.994653 -247.189788)
			(xy 342.993666 -247.204289) (xy 343.273889 -247.204289) (xy 343.273889 -247.152355) (xy 343.282014 -247.10106)
			(xy 343.298062 -247.051667) (xy 343.32164 -247.005393) (xy 343.352166 -246.963377) (xy 343.388889 -246.926654)
			(xy 343.430905 -246.896128) (xy 343.477179 -246.87255) (xy 343.526572 -246.856502) (xy 343.577867 -246.848377)
			(xy 343.629801 -246.848377) (xy 343.681096 -246.856502) (xy 343.730489 -246.87255) (xy 343.776763 -246.896128)
			(xy 343.818779 -246.926654) (xy 343.855502 -246.963377) (xy 343.886028 -247.005393) (xy 343.909606 -247.051667)
			(xy 343.925654 -247.10106) (xy 343.933779 -247.152355) (xy 343.934288 -247.178322) (xy 343.933779 -247.204289)
			(xy 344.213435 -247.204289) (xy 344.213435 -247.152355) (xy 344.22156 -247.10106) (xy 344.237608 -247.051667)
			(xy 344.261186 -247.005393) (xy 344.291712 -246.963377) (xy 344.328435 -246.926654) (xy 344.370451 -246.896128)
			(xy 344.416725 -246.87255) (xy 344.466118 -246.856502) (xy 344.517413 -246.848377) (xy 344.569347 -246.848377)
			(xy 344.620642 -246.856502) (xy 344.670035 -246.87255) (xy 344.716309 -246.896128) (xy 344.758325 -246.926654)
			(xy 344.795048 -246.963377) (xy 344.825574 -247.005393) (xy 344.849152 -247.051667) (xy 344.8652 -247.10106)
			(xy 344.873325 -247.152355) (xy 344.873834 -247.178322) (xy 344.873325 -247.204289) (xy 345.153489 -247.204289)
			(xy 345.153489 -247.152355) (xy 345.161614 -247.10106) (xy 345.177662 -247.051667) (xy 345.20124 -247.005393)
			(xy 345.231766 -246.963377) (xy 345.268489 -246.926654) (xy 345.310505 -246.896128) (xy 345.356779 -246.87255)
			(xy 345.406172 -246.856502) (xy 345.457467 -246.848377) (xy 345.509401 -246.848377) (xy 345.560696 -246.856502)
			(xy 345.610089 -246.87255) (xy 345.656363 -246.896128) (xy 345.698379 -246.926654) (xy 345.735102 -246.963377)
			(xy 345.765628 -247.005393) (xy 345.789206 -247.051667) (xy 345.805254 -247.10106) (xy 345.813379 -247.152355)
			(xy 345.813888 -247.178322) (xy 345.813379 -247.204289) (xy 346.093035 -247.204289) (xy 346.093035 -247.152355)
			(xy 346.10116 -247.10106) (xy 346.117208 -247.051667) (xy 346.140786 -247.005393) (xy 346.171312 -246.963377)
			(xy 346.208035 -246.926654) (xy 346.250051 -246.896128) (xy 346.296325 -246.87255) (xy 346.345718 -246.856502)
			(xy 346.397013 -246.848377) (xy 346.448947 -246.848377) (xy 346.500242 -246.856502) (xy 346.549635 -246.87255)
			(xy 346.595909 -246.896128) (xy 346.637925 -246.926654) (xy 346.674648 -246.963377) (xy 346.705174 -247.005393)
			(xy 346.728752 -247.051667) (xy 346.7448 -247.10106) (xy 346.752925 -247.152355) (xy 346.753434 -247.178322)
			(xy 346.752925 -247.204289) (xy 347.033089 -247.204289) (xy 347.033089 -247.152355) (xy 347.041214 -247.10106)
			(xy 347.057262 -247.051667) (xy 347.08084 -247.005393) (xy 347.111366 -246.963377) (xy 347.148089 -246.926654)
			(xy 347.190105 -246.896128) (xy 347.236379 -246.87255) (xy 347.285772 -246.856502) (xy 347.337067 -246.848377)
			(xy 347.389001 -246.848377) (xy 347.440296 -246.856502) (xy 347.489689 -246.87255) (xy 347.535963 -246.896128)
			(xy 347.577979 -246.926654) (xy 347.614702 -246.963377) (xy 347.645228 -247.005393) (xy 347.668806 -247.051667)
			(xy 347.684854 -247.10106) (xy 347.692979 -247.152355) (xy 347.693488 -247.178322) (xy 347.692979 -247.204289)
			(xy 347.972889 -247.204289) (xy 347.972889 -247.152355) (xy 347.981014 -247.10106) (xy 347.997062 -247.051667)
			(xy 348.02064 -247.005393) (xy 348.051166 -246.963377) (xy 348.087889 -246.926654) (xy 348.129905 -246.896128)
			(xy 348.176179 -246.87255) (xy 348.225572 -246.856502) (xy 348.276867 -246.848377) (xy 348.328801 -246.848377)
			(xy 348.380096 -246.856502) (xy 348.429489 -246.87255) (xy 348.475763 -246.896128) (xy 348.517779 -246.926654)
			(xy 348.554502 -246.963377) (xy 348.585028 -247.005393) (xy 348.608606 -247.051667) (xy 348.624654 -247.10106)
			(xy 348.632779 -247.152355) (xy 348.633288 -247.178322) (xy 348.632779 -247.204289) (xy 348.912689 -247.204289)
			(xy 348.912689 -247.152355) (xy 348.920814 -247.10106) (xy 348.936862 -247.051667) (xy 348.96044 -247.005393)
			(xy 348.990966 -246.963377) (xy 349.027689 -246.926654) (xy 349.069705 -246.896128) (xy 349.115979 -246.87255)
			(xy 349.165372 -246.856502) (xy 349.216667 -246.848377) (xy 349.268601 -246.848377) (xy 349.319896 -246.856502)
			(xy 349.369289 -246.87255) (xy 349.415563 -246.896128) (xy 349.457579 -246.926654) (xy 349.494302 -246.963377)
			(xy 349.524828 -247.005393) (xy 349.548406 -247.051667) (xy 349.564454 -247.10106) (xy 349.572579 -247.152355)
			(xy 349.573088 -247.178322) (xy 349.572579 -247.204289) (xy 349.852489 -247.204289) (xy 349.852489 -247.152355)
			(xy 349.860614 -247.10106) (xy 349.876662 -247.051667) (xy 349.90024 -247.005393) (xy 349.930766 -246.963377)
			(xy 349.967489 -246.926654) (xy 350.009505 -246.896128) (xy 350.055779 -246.87255) (xy 350.105172 -246.856502)
			(xy 350.156467 -246.848377) (xy 350.208401 -246.848377) (xy 350.259696 -246.856502) (xy 350.309089 -246.87255)
			(xy 350.355363 -246.896128) (xy 350.397379 -246.926654) (xy 350.434102 -246.963377) (xy 350.464628 -247.005393)
			(xy 350.488206 -247.051667) (xy 350.504254 -247.10106) (xy 350.512379 -247.152355) (xy 350.512888 -247.178322)
			(xy 350.512379 -247.204289) (xy 357.370635 -247.204289) (xy 357.370635 -247.152355) (xy 357.37876 -247.10106)
			(xy 357.394808 -247.051667) (xy 357.418386 -247.005393) (xy 357.448912 -246.963377) (xy 357.485635 -246.926654)
			(xy 357.527651 -246.896128) (xy 357.573925 -246.87255) (xy 357.623318 -246.856502) (xy 357.674613 -246.848377)
			(xy 357.726547 -246.848377) (xy 357.777842 -246.856502) (xy 357.827235 -246.87255) (xy 357.873509 -246.896128)
			(xy 357.915525 -246.926654) (xy 357.952248 -246.963377) (xy 357.982774 -247.005393) (xy 358.006352 -247.051667)
			(xy 358.0224 -247.10106) (xy 358.030525 -247.152355) (xy 358.031034 -247.178322) (xy 358.030525 -247.204289)
			(xy 358.310689 -247.204289) (xy 358.310689 -247.152355) (xy 358.318814 -247.10106) (xy 358.334862 -247.051667)
			(xy 358.35844 -247.005393) (xy 358.388966 -246.963377) (xy 358.425689 -246.926654) (xy 358.467705 -246.896128)
			(xy 358.513979 -246.87255) (xy 358.563372 -246.856502) (xy 358.614667 -246.848377) (xy 358.666601 -246.848377)
			(xy 358.717896 -246.856502) (xy 358.767289 -246.87255) (xy 358.813563 -246.896128) (xy 358.855579 -246.926654)
			(xy 358.892302 -246.963377) (xy 358.922828 -247.005393) (xy 358.946406 -247.051667) (xy 358.962454 -247.10106)
			(xy 358.970579 -247.152355) (xy 358.971088 -247.178322) (xy 358.970579 -247.204289) (xy 359.250235 -247.204289)
			(xy 359.250235 -247.152355) (xy 359.25836 -247.10106) (xy 359.274408 -247.051667) (xy 359.297986 -247.005393)
			(xy 359.328512 -246.963377) (xy 359.365235 -246.926654) (xy 359.407251 -246.896128) (xy 359.453525 -246.87255)
			(xy 359.502918 -246.856502) (xy 359.554213 -246.848377) (xy 359.606147 -246.848377) (xy 359.657442 -246.856502)
			(xy 359.706835 -246.87255) (xy 359.753109 -246.896128) (xy 359.795125 -246.926654) (xy 359.831848 -246.963377)
			(xy 359.862374 -247.005393) (xy 359.885952 -247.051667) (xy 359.902 -247.10106) (xy 359.910125 -247.152355)
			(xy 359.910634 -247.178322) (xy 359.910125 -247.204289) (xy 360.190035 -247.204289) (xy 360.190035 -247.152355)
			(xy 360.19816 -247.10106) (xy 360.214208 -247.051667) (xy 360.237786 -247.005393) (xy 360.268312 -246.963377)
			(xy 360.305035 -246.926654) (xy 360.347051 -246.896128) (xy 360.393325 -246.87255) (xy 360.442718 -246.856502)
			(xy 360.494013 -246.848377) (xy 360.545947 -246.848377) (xy 360.597242 -246.856502) (xy 360.646635 -246.87255)
			(xy 360.692909 -246.896128) (xy 360.734925 -246.926654) (xy 360.771648 -246.963377) (xy 360.802174 -247.005393)
			(xy 360.825752 -247.051667) (xy 360.8418 -247.10106) (xy 360.849925 -247.152355) (xy 360.850434 -247.178322)
			(xy 360.849925 -247.204289) (xy 361.130089 -247.204289) (xy 361.130089 -247.152355) (xy 361.138214 -247.10106)
			(xy 361.154262 -247.051667) (xy 361.17784 -247.005393) (xy 361.208366 -246.963377) (xy 361.245089 -246.926654)
			(xy 361.287105 -246.896128) (xy 361.333379 -246.87255) (xy 361.382772 -246.856502) (xy 361.434067 -246.848377)
			(xy 361.486001 -246.848377) (xy 361.537296 -246.856502) (xy 361.586689 -246.87255) (xy 361.632963 -246.896128)
			(xy 361.674979 -246.926654) (xy 361.711702 -246.963377) (xy 361.742228 -247.005393) (xy 361.765806 -247.051667)
			(xy 361.781854 -247.10106) (xy 361.789979 -247.152355) (xy 361.790488 -247.178322) (xy 361.789979 -247.204269)
			(xy 362.069851 -247.204269) (xy 362.069851 -247.152331) (xy 362.077976 -247.101032) (xy 362.094027 -247.051636)
			(xy 362.117608 -247.005359) (xy 362.148139 -246.963341) (xy 362.184867 -246.926617) (xy 362.226888 -246.896091)
			(xy 362.273167 -246.872514) (xy 362.322565 -246.856468) (xy 362.373865 -246.848348) (xy 362.399834 -246.847868)
			(xy 362.425637 -246.84839) (xy 362.476617 -246.856403) (xy 362.525731 -246.872245) (xy 362.571785 -246.89553)
			(xy 362.613659 -246.925693) (xy 362.650334 -246.961999) (xy 362.666026 -246.982488) (xy 362.674557 -246.99342)
			(xy 362.696357 -247.010546) (xy 362.721962 -247.021171) (xy 362.749482 -247.024512) (xy 362.776885 -247.02032)
			(xy 362.802148 -247.008906) (xy 362.823406 -246.991113) (xy 362.831634 -246.979948) (xy 362.838296 -246.970361)
			(xy 362.852789 -246.952057) (xy 362.86059 -246.943372) (xy 362.8704 -246.931888) (xy 362.883411 -246.904649)
			(xy 362.887877 -246.874794) (xy 362.883407 -246.84494) (xy 362.870393 -246.817702) (xy 362.86059 -246.806212)
			(xy 362.844329 -246.787843) (xy 362.816886 -246.74718) (xy 362.795759 -246.702906) (xy 362.781414 -246.655993)
			(xy 362.774166 -246.607475) (xy 362.773722 -246.582946) (xy 362.773722 -246.582692) (xy 362.774231 -246.556725)
			(xy 362.782356 -246.50543) (xy 362.798404 -246.456037) (xy 362.821982 -246.409763) (xy 362.852508 -246.367747)
			(xy 362.889231 -246.331024) (xy 362.931247 -246.300498) (xy 362.977521 -246.27692) (xy 363.026914 -246.260872)
			(xy 363.078209 -246.252747) (xy 363.130143 -246.252747) (xy 363.181438 -246.260872) (xy 363.230831 -246.27692)
			(xy 363.277105 -246.300498) (xy 363.319121 -246.331024) (xy 363.355844 -246.367747) (xy 363.38637 -246.409763)
			(xy 363.409948 -246.456037) (xy 363.425996 -246.50543) (xy 363.434121 -246.556725) (xy 363.43463 -246.582692)
			(xy 363.43463 -246.582946) (xy 363.434198 -246.607473) (xy 363.426929 -246.655987) (xy 363.418015 -246.685113)
			(xy 364.044485 -246.685113) (xy 364.044485 -246.633179) (xy 364.05261 -246.581884) (xy 364.068658 -246.532491)
			(xy 364.092236 -246.486217) (xy 364.122762 -246.444201) (xy 364.159485 -246.407478) (xy 364.201501 -246.376952)
			(xy 364.247775 -246.353374) (xy 364.297168 -246.337326) (xy 364.348463 -246.329201) (xy 364.400397 -246.329201)
			(xy 364.451692 -246.337326) (xy 364.501085 -246.353374) (xy 364.547359 -246.376952) (xy 364.589375 -246.407478)
			(xy 364.626098 -246.444201) (xy 364.656624 -246.486217) (xy 364.680202 -246.532491) (xy 364.69625 -246.581884)
			(xy 364.704375 -246.633179) (xy 364.704884 -246.659146) (xy 364.704375 -246.685113) (xy 364.702766 -246.695269)
			(xy 364.811535 -246.695269) (xy 364.811535 -246.643331) (xy 364.81966 -246.592032) (xy 364.83571 -246.542635)
			(xy 364.85929 -246.496358) (xy 364.88982 -246.454339) (xy 364.926546 -246.417613) (xy 364.968566 -246.387085)
			(xy 365.014844 -246.363506) (xy 365.064241 -246.347458) (xy 365.115541 -246.339334) (xy 365.14151 -246.338852)
			(xy 365.168091 -246.33939) (xy 365.220567 -246.347895) (xy 365.271007 -246.364684) (xy 365.318113 -246.389325)
			(xy 365.36067 -246.421184) (xy 365.379508 -246.439944) (xy 365.389279 -246.449469) (xy 365.412721 -246.463413)
			(xy 365.439022 -246.470643) (xy 365.466298 -246.470643) (xy 365.492599 -246.463413) (xy 365.516041 -246.449469)
			(xy 365.525812 -246.439944) (xy 365.544654 -246.421187) (xy 365.587208 -246.389323) (xy 365.634312 -246.364677)
			(xy 365.684752 -246.347886) (xy 365.737229 -246.339382) (xy 365.76381 -246.338852) (xy 365.789131 -246.339362)
			(xy 365.839183 -246.347072) (xy 365.887474 -246.362324) (xy 365.932874 -246.384763) (xy 365.974321 -246.413862)
			(xy 365.992918 -246.431054) (xy 366.00276 -246.439978) (xy 366.025974 -246.452879) (xy 366.051735 -246.459337)
			(xy 366.078289 -246.458913) (xy 366.10383 -246.451636) (xy 366.12662 -246.438) (xy 366.136174 -246.428768)
			(xy 366.15495 -246.410186) (xy 366.197343 -246.378672) (xy 366.244205 -246.354294) (xy 366.294346 -246.337673)
			(xy 366.346491 -246.329232) (xy 366.372902 -246.328692) (xy 366.398873 -246.32911) (xy 366.450175 -246.337235)
			(xy 366.499574 -246.353286) (xy 366.545854 -246.376867) (xy 366.587875 -246.407398) (xy 366.624603 -246.444126)
			(xy 366.655134 -246.486148) (xy 366.678714 -246.532428) (xy 366.694765 -246.581827) (xy 366.702891 -246.633129)
			(xy 366.702891 -246.685067) (xy 366.813075 -246.685067) (xy 366.813075 -246.633133) (xy 366.8212 -246.581838)
			(xy 366.837249 -246.532446) (xy 366.860828 -246.486172) (xy 366.891356 -246.444158) (xy 366.928081 -246.407436)
			(xy 366.970098 -246.376912) (xy 367.016373 -246.353338) (xy 367.065767 -246.337293) (xy 367.117063 -246.329172)
			(xy 367.14303 -246.328692) (xy 367.143284 -246.328692) (xy 367.16781 -246.329155) (xy 367.216322 -246.336416)
			(xy 367.263229 -246.350765) (xy 367.307501 -246.371887) (xy 367.348166 -246.399319) (xy 367.36655 -246.41556)
			(xy 367.378039 -246.425363) (xy 367.405276 -246.438377) (xy 367.43513 -246.442845) (xy 367.464984 -246.438377)
			(xy 367.492221 -246.425363) (xy 367.50371 -246.41556) (xy 367.5221 -246.399284) (xy 367.562807 -246.371816)
			(xy 367.607134 -246.35068) (xy 367.654102 -246.336342) (xy 367.702676 -246.329117) (xy 367.72723 -246.328692)
			(xy 367.751782 -246.329139) (xy 367.800349 -246.336377) (xy 367.847311 -246.350719) (xy 367.891635 -246.371849)
			(xy 367.932346 -246.399303) (xy 367.95075 -246.41556) (xy 367.962239 -246.425363) (xy 367.989476 -246.438377)
			(xy 368.01933 -246.442845) (xy 368.049184 -246.438377) (xy 368.076421 -246.425363) (xy 368.08791 -246.41556)
			(xy 368.10628 -246.3993) (xy 368.146941 -246.371854) (xy 368.191215 -246.350726) (xy 368.238128 -246.336381)
			(xy 368.286647 -246.329134) (xy 368.311176 -246.328692) (xy 368.31143 -246.328692) (xy 368.338102 -246.329243)
			(xy 368.390755 -246.337795) (xy 368.441353 -246.354688) (xy 368.488583 -246.379484) (xy 368.53122 -246.411541)
			(xy 368.568158 -246.450025) (xy 368.583718 -246.471694) (xy 368.591627 -246.482549) (xy 368.612064 -246.499962)
			(xy 368.636334 -246.511447) (xy 368.662758 -246.516209) (xy 368.68951 -246.513919) (xy 368.714741 -246.504735)
			(xy 368.725958 -246.497348) (xy 368.746937 -246.483086) (xy 368.792367 -246.460517) (xy 368.840714 -246.44516)
			(xy 368.890841 -246.437374) (xy 368.916204 -246.436896) (xy 368.935567 -246.437193) (xy 368.974021 -246.441782)
			(xy 368.992912 -246.44604) (xy 369.007617 -246.448981) (xy 369.037536 -246.447237) (xy 369.065659 -246.43688)
			(xy 369.089562 -246.418803) (xy 369.107186 -246.394563) (xy 369.117012 -246.36625) (xy 369.118134 -246.351298)
			(xy 369.11961 -246.32603) (xy 369.129321 -246.276356) (xy 369.146493 -246.228743) (xy 369.170725 -246.184307)
			(xy 369.201451 -246.144085) (xy 369.23795 -246.10902) (xy 369.27937 -246.07993) (xy 369.324742 -246.057497)
			(xy 369.373004 -246.042246) (xy 369.423027 -246.034532) (xy 369.448334 -246.034052) (xy 369.4743 -246.034552)
			(xy 369.525592 -246.042681) (xy 369.574981 -246.058732) (xy 369.621251 -246.082312) (xy 369.663263 -246.11284)
			(xy 369.699982 -246.149563) (xy 369.730505 -246.191578) (xy 369.754081 -246.237851) (xy 369.770127 -246.287241)
			(xy 369.778251 -246.338534) (xy 369.778251 -246.390466) (xy 369.77825 -246.390473) (xy 370.058189 -246.390473)
			(xy 370.058189 -246.338539) (xy 370.066314 -246.287244) (xy 370.082362 -246.237851) (xy 370.10594 -246.191577)
			(xy 370.136466 -246.149561) (xy 370.173189 -246.112838) (xy 370.215205 -246.082312) (xy 370.261479 -246.058734)
			(xy 370.310872 -246.042686) (xy 370.362167 -246.034561) (xy 370.414101 -246.034561) (xy 370.465396 -246.042686)
			(xy 370.514789 -246.058734) (xy 370.561063 -246.082312) (xy 370.603079 -246.112838) (xy 370.639802 -246.149561)
			(xy 370.670328 -246.191577) (xy 370.693906 -246.237851) (xy 370.709954 -246.287244) (xy 370.718079 -246.338539)
			(xy 370.718588 -246.364506) (xy 370.718079 -246.390473) (xy 370.997735 -246.390473) (xy 370.997735 -246.338539)
			(xy 371.00586 -246.287244) (xy 371.021908 -246.237851) (xy 371.045486 -246.191577) (xy 371.076012 -246.149561)
			(xy 371.112735 -246.112838) (xy 371.154751 -246.082312) (xy 371.201025 -246.058734) (xy 371.250418 -246.042686)
			(xy 371.301713 -246.034561) (xy 371.353647 -246.034561) (xy 371.404942 -246.042686) (xy 371.454335 -246.058734)
			(xy 371.500609 -246.082312) (xy 371.542625 -246.112838) (xy 371.579348 -246.149561) (xy 371.609874 -246.191577)
			(xy 371.633452 -246.237851) (xy 371.6495 -246.287244) (xy 371.657625 -246.338539) (xy 371.658134 -246.364506)
			(xy 371.657625 -246.390473) (xy 371.937535 -246.390473) (xy 371.937535 -246.338539) (xy 371.94566 -246.287244)
			(xy 371.961708 -246.237851) (xy 371.985286 -246.191577) (xy 372.015812 -246.149561) (xy 372.052535 -246.112838)
			(xy 372.094551 -246.082312) (xy 372.140825 -246.058734) (xy 372.190218 -246.042686) (xy 372.241513 -246.034561)
			(xy 372.293447 -246.034561) (xy 372.344742 -246.042686) (xy 372.394135 -246.058734) (xy 372.440409 -246.082312)
			(xy 372.482425 -246.112838) (xy 372.519148 -246.149561) (xy 372.549674 -246.191577) (xy 372.573252 -246.237851)
			(xy 372.5893 -246.287244) (xy 372.597425 -246.338539) (xy 372.597934 -246.364506) (xy 372.597425 -246.390473)
			(xy 372.877335 -246.390473) (xy 372.877335 -246.338539) (xy 372.88546 -246.287244) (xy 372.901508 -246.237851)
			(xy 372.925086 -246.191577) (xy 372.955612 -246.149561) (xy 372.992335 -246.112838) (xy 373.034351 -246.082312)
			(xy 373.080625 -246.058734) (xy 373.130018 -246.042686) (xy 373.181313 -246.034561) (xy 373.233247 -246.034561)
			(xy 373.284542 -246.042686) (xy 373.333935 -246.058734) (xy 373.380209 -246.082312) (xy 373.422225 -246.112838)
			(xy 373.458948 -246.149561) (xy 373.489474 -246.191577) (xy 373.513052 -246.237851) (xy 373.5291 -246.287244)
			(xy 373.537225 -246.338539) (xy 373.537734 -246.364506) (xy 373.537225 -246.390473) (xy 373.817135 -246.390473)
			(xy 373.817135 -246.338539) (xy 373.82526 -246.287244) (xy 373.841308 -246.237851) (xy 373.864886 -246.191577)
			(xy 373.895412 -246.149561) (xy 373.932135 -246.112838) (xy 373.974151 -246.082312) (xy 374.020425 -246.058734)
			(xy 374.069818 -246.042686) (xy 374.121113 -246.034561) (xy 374.173047 -246.034561) (xy 374.224342 -246.042686)
			(xy 374.273735 -246.058734) (xy 374.320009 -246.082312) (xy 374.362025 -246.112838) (xy 374.398748 -246.149561)
			(xy 374.429274 -246.191577) (xy 374.452852 -246.237851) (xy 374.4689 -246.287244) (xy 374.477025 -246.338539)
			(xy 374.477534 -246.364506) (xy 374.477025 -246.390473) (xy 374.756935 -246.390473) (xy 374.756935 -246.338539)
			(xy 374.76506 -246.287244) (xy 374.781108 -246.237851) (xy 374.804686 -246.191577) (xy 374.835212 -246.149561)
			(xy 374.871935 -246.112838) (xy 374.913951 -246.082312) (xy 374.960225 -246.058734) (xy 375.009618 -246.042686)
			(xy 375.060913 -246.034561) (xy 375.112847 -246.034561) (xy 375.164142 -246.042686) (xy 375.213535 -246.058734)
			(xy 375.259809 -246.082312) (xy 375.301825 -246.112838) (xy 375.338548 -246.149561) (xy 375.369074 -246.191577)
			(xy 375.392652 -246.237851) (xy 375.4087 -246.287244) (xy 375.416825 -246.338539) (xy 375.417334 -246.364506)
			(xy 375.416825 -246.390473) (xy 375.696735 -246.390473) (xy 375.696735 -246.338539) (xy 375.70486 -246.287244)
			(xy 375.720908 -246.237851) (xy 375.744486 -246.191577) (xy 375.775012 -246.149561) (xy 375.811735 -246.112838)
			(xy 375.853751 -246.082312) (xy 375.900025 -246.058734) (xy 375.949418 -246.042686) (xy 376.000713 -246.034561)
			(xy 376.052647 -246.034561) (xy 376.103942 -246.042686) (xy 376.153335 -246.058734) (xy 376.199609 -246.082312)
			(xy 376.241625 -246.112838) (xy 376.278348 -246.149561) (xy 376.308874 -246.191577) (xy 376.332452 -246.237851)
			(xy 376.3485 -246.287244) (xy 376.356625 -246.338539) (xy 376.357134 -246.364506) (xy 376.356625 -246.390473)
			(xy 376.636789 -246.390473) (xy 376.636789 -246.338539) (xy 376.644914 -246.287244) (xy 376.660962 -246.237851)
			(xy 376.68454 -246.191577) (xy 376.715066 -246.149561) (xy 376.751789 -246.112838) (xy 376.793805 -246.082312)
			(xy 376.840079 -246.058734) (xy 376.889472 -246.042686) (xy 376.940767 -246.034561) (xy 376.992701 -246.034561)
			(xy 377.043996 -246.042686) (xy 377.093389 -246.058734) (xy 377.139663 -246.082312) (xy 377.181679 -246.112838)
			(xy 377.218402 -246.149561) (xy 377.248928 -246.191577) (xy 377.272506 -246.237851) (xy 377.288554 -246.287244)
			(xy 377.296679 -246.338539) (xy 377.297188 -246.364506) (xy 377.296679 -246.390473) (xy 377.576335 -246.390473)
			(xy 377.576335 -246.338539) (xy 377.58446 -246.287244) (xy 377.600508 -246.237851) (xy 377.624086 -246.191577)
			(xy 377.654612 -246.149561) (xy 377.691335 -246.112838) (xy 377.733351 -246.082312) (xy 377.779625 -246.058734)
			(xy 377.829018 -246.042686) (xy 377.880313 -246.034561) (xy 377.932247 -246.034561) (xy 377.983542 -246.042686)
			(xy 378.032935 -246.058734) (xy 378.079209 -246.082312) (xy 378.121225 -246.112838) (xy 378.157948 -246.149561)
			(xy 378.188474 -246.191577) (xy 378.212052 -246.237851) (xy 378.2281 -246.287244) (xy 378.236225 -246.338539)
			(xy 378.236734 -246.364506) (xy 378.236225 -246.390473) (xy 378.516135 -246.390473) (xy 378.516135 -246.338539)
			(xy 378.52426 -246.287244) (xy 378.540308 -246.237851) (xy 378.563886 -246.191577) (xy 378.594412 -246.149561)
			(xy 378.631135 -246.112838) (xy 378.673151 -246.082312) (xy 378.719425 -246.058734) (xy 378.768818 -246.042686)
			(xy 378.820113 -246.034561) (xy 378.872047 -246.034561) (xy 378.923342 -246.042686) (xy 378.972735 -246.058734)
			(xy 379.019009 -246.082312) (xy 379.061025 -246.112838) (xy 379.097748 -246.149561) (xy 379.128274 -246.191577)
			(xy 379.151852 -246.237851) (xy 379.1679 -246.287244) (xy 379.176025 -246.338539) (xy 379.176534 -246.364506)
			(xy 379.176025 -246.390473) (xy 379.1679 -246.441768) (xy 379.151852 -246.491161) (xy 379.128274 -246.537435)
			(xy 379.097748 -246.579451) (xy 379.061025 -246.616174) (xy 379.019009 -246.6467) (xy 378.972735 -246.670278)
			(xy 378.923342 -246.686326) (xy 378.872047 -246.694451) (xy 378.820113 -246.694451) (xy 378.768818 -246.686326)
			(xy 378.719425 -246.670278) (xy 378.673151 -246.6467) (xy 378.631135 -246.616174) (xy 378.594412 -246.579451)
			(xy 378.563886 -246.537435) (xy 378.540308 -246.491161) (xy 378.52426 -246.441768) (xy 378.516135 -246.390473)
			(xy 378.236225 -246.390473) (xy 378.2281 -246.441768) (xy 378.212052 -246.491161) (xy 378.188474 -246.537435)
			(xy 378.157948 -246.579451) (xy 378.121225 -246.616174) (xy 378.079209 -246.6467) (xy 378.032935 -246.670278)
			(xy 377.983542 -246.686326) (xy 377.932247 -246.694451) (xy 377.880313 -246.694451) (xy 377.829018 -246.686326)
			(xy 377.779625 -246.670278) (xy 377.733351 -246.6467) (xy 377.691335 -246.616174) (xy 377.654612 -246.579451)
			(xy 377.624086 -246.537435) (xy 377.600508 -246.491161) (xy 377.58446 -246.441768) (xy 377.576335 -246.390473)
			(xy 377.296679 -246.390473) (xy 377.288554 -246.441768) (xy 377.272506 -246.491161) (xy 377.248928 -246.537435)
			(xy 377.218402 -246.579451) (xy 377.181679 -246.616174) (xy 377.139663 -246.6467) (xy 377.093389 -246.670278)
			(xy 377.043996 -246.686326) (xy 376.992701 -246.694451) (xy 376.940767 -246.694451) (xy 376.889472 -246.686326)
			(xy 376.840079 -246.670278) (xy 376.793805 -246.6467) (xy 376.751789 -246.616174) (xy 376.715066 -246.579451)
			(xy 376.68454 -246.537435) (xy 376.660962 -246.491161) (xy 376.644914 -246.441768) (xy 376.636789 -246.390473)
			(xy 376.356625 -246.390473) (xy 376.3485 -246.441768) (xy 376.332452 -246.491161) (xy 376.308874 -246.537435)
			(xy 376.278348 -246.579451) (xy 376.241625 -246.616174) (xy 376.199609 -246.6467) (xy 376.153335 -246.670278)
			(xy 376.103942 -246.686326) (xy 376.052647 -246.694451) (xy 376.000713 -246.694451) (xy 375.949418 -246.686326)
			(xy 375.900025 -246.670278) (xy 375.853751 -246.6467) (xy 375.811735 -246.616174) (xy 375.775012 -246.579451)
			(xy 375.744486 -246.537435) (xy 375.720908 -246.491161) (xy 375.70486 -246.441768) (xy 375.696735 -246.390473)
			(xy 375.416825 -246.390473) (xy 375.4087 -246.441768) (xy 375.392652 -246.491161) (xy 375.369074 -246.537435)
			(xy 375.338548 -246.579451) (xy 375.301825 -246.616174) (xy 375.259809 -246.6467) (xy 375.213535 -246.670278)
			(xy 375.164142 -246.686326) (xy 375.112847 -246.694451) (xy 375.060913 -246.694451) (xy 375.009618 -246.686326)
			(xy 374.960225 -246.670278) (xy 374.913951 -246.6467) (xy 374.871935 -246.616174) (xy 374.835212 -246.579451)
			(xy 374.804686 -246.537435) (xy 374.781108 -246.491161) (xy 374.76506 -246.441768) (xy 374.756935 -246.390473)
			(xy 374.477025 -246.390473) (xy 374.4689 -246.441768) (xy 374.452852 -246.491161) (xy 374.429274 -246.537435)
			(xy 374.398748 -246.579451) (xy 374.362025 -246.616174) (xy 374.320009 -246.6467) (xy 374.273735 -246.670278)
			(xy 374.224342 -246.686326) (xy 374.173047 -246.694451) (xy 374.121113 -246.694451) (xy 374.069818 -246.686326)
			(xy 374.020425 -246.670278) (xy 373.974151 -246.6467) (xy 373.932135 -246.616174) (xy 373.895412 -246.579451)
			(xy 373.864886 -246.537435) (xy 373.841308 -246.491161) (xy 373.82526 -246.441768) (xy 373.817135 -246.390473)
			(xy 373.537225 -246.390473) (xy 373.5291 -246.441768) (xy 373.513052 -246.491161) (xy 373.489474 -246.537435)
			(xy 373.458948 -246.579451) (xy 373.422225 -246.616174) (xy 373.380209 -246.6467) (xy 373.333935 -246.670278)
			(xy 373.284542 -246.686326) (xy 373.233247 -246.694451) (xy 373.181313 -246.694451) (xy 373.130018 -246.686326)
			(xy 373.080625 -246.670278) (xy 373.034351 -246.6467) (xy 372.992335 -246.616174) (xy 372.955612 -246.579451)
			(xy 372.925086 -246.537435) (xy 372.901508 -246.491161) (xy 372.88546 -246.441768) (xy 372.877335 -246.390473)
			(xy 372.597425 -246.390473) (xy 372.5893 -246.441768) (xy 372.573252 -246.491161) (xy 372.549674 -246.537435)
			(xy 372.519148 -246.579451) (xy 372.482425 -246.616174) (xy 372.440409 -246.6467) (xy 372.394135 -246.670278)
			(xy 372.344742 -246.686326) (xy 372.293447 -246.694451) (xy 372.241513 -246.694451) (xy 372.190218 -246.686326)
			(xy 372.140825 -246.670278) (xy 372.094551 -246.6467) (xy 372.052535 -246.616174) (xy 372.015812 -246.579451)
			(xy 371.985286 -246.537435) (xy 371.961708 -246.491161) (xy 371.94566 -246.441768) (xy 371.937535 -246.390473)
			(xy 371.657625 -246.390473) (xy 371.6495 -246.441768) (xy 371.633452 -246.491161) (xy 371.609874 -246.537435)
			(xy 371.579348 -246.579451) (xy 371.542625 -246.616174) (xy 371.500609 -246.6467) (xy 371.454335 -246.670278)
			(xy 371.404942 -246.686326) (xy 371.353647 -246.694451) (xy 371.301713 -246.694451) (xy 371.250418 -246.686326)
			(xy 371.201025 -246.670278) (xy 371.154751 -246.6467) (xy 371.112735 -246.616174) (xy 371.076012 -246.579451)
			(xy 371.045486 -246.537435) (xy 371.021908 -246.491161) (xy 371.00586 -246.441768) (xy 370.997735 -246.390473)
			(xy 370.718079 -246.390473) (xy 370.709954 -246.441768) (xy 370.693906 -246.491161) (xy 370.670328 -246.537435)
			(xy 370.639802 -246.579451) (xy 370.603079 -246.616174) (xy 370.561063 -246.6467) (xy 370.514789 -246.670278)
			(xy 370.465396 -246.686326) (xy 370.414101 -246.694451) (xy 370.362167 -246.694451) (xy 370.310872 -246.686326)
			(xy 370.261479 -246.670278) (xy 370.215205 -246.6467) (xy 370.173189 -246.616174) (xy 370.136466 -246.579451)
			(xy 370.10594 -246.537435) (xy 370.082362 -246.491161) (xy 370.066314 -246.441768) (xy 370.058189 -246.390473)
			(xy 369.77825 -246.390473) (xy 369.770127 -246.441759) (xy 369.754081 -246.491149) (xy 369.730505 -246.537422)
			(xy 369.699982 -246.579437) (xy 369.663263 -246.61616) (xy 369.621251 -246.646688) (xy 369.574981 -246.670268)
			(xy 369.525592 -246.686319) (xy 369.4743 -246.694448) (xy 369.448334 -246.69496) (xy 369.428971 -246.694657)
			(xy 369.390518 -246.690072) (xy 369.371626 -246.685816) (xy 369.356927 -246.68285) (xy 369.327009 -246.684609)
			(xy 369.29889 -246.694975) (xy 369.274989 -246.713056) (xy 369.257363 -246.737295) (xy 369.247531 -246.765606)
			(xy 369.246404 -246.780558) (xy 369.245079 -246.803753) (xy 369.236764 -246.849461) (xy 369.222133 -246.893555)
			(xy 369.201473 -246.935167) (xy 369.175192 -246.973477) (xy 369.15979 -246.99087) (xy 369.14994 -247.002322)
			(xy 369.136937 -247.029573) (xy 369.132479 -247.059437) (xy 369.136958 -247.089298) (xy 369.149982 -247.116539)
			(xy 369.15979 -247.12803) (xy 369.17602 -247.146425) (xy 369.203468 -247.18708) (xy 369.211683 -247.204289)
			(xy 369.588289 -247.204289) (xy 369.588289 -247.152355) (xy 369.596414 -247.10106) (xy 369.612462 -247.051667)
			(xy 369.63604 -247.005393) (xy 369.666566 -246.963377) (xy 369.703289 -246.926654) (xy 369.745305 -246.896128)
			(xy 369.791579 -246.87255) (xy 369.840972 -246.856502) (xy 369.892267 -246.848377) (xy 369.944201 -246.848377)
			(xy 369.995496 -246.856502) (xy 370.044889 -246.87255) (xy 370.091163 -246.896128) (xy 370.133179 -246.926654)
			(xy 370.169902 -246.963377) (xy 370.200428 -247.005393) (xy 370.224006 -247.051667) (xy 370.240054 -247.10106)
			(xy 370.248179 -247.152355) (xy 370.248688 -247.178322) (xy 370.248179 -247.204289) (xy 370.528089 -247.204289)
			(xy 370.528089 -247.152355) (xy 370.536214 -247.10106) (xy 370.552262 -247.051667) (xy 370.57584 -247.005393)
			(xy 370.606366 -246.963377) (xy 370.643089 -246.926654) (xy 370.685105 -246.896128) (xy 370.731379 -246.87255)
			(xy 370.780772 -246.856502) (xy 370.832067 -246.848377) (xy 370.884001 -246.848377) (xy 370.935296 -246.856502)
			(xy 370.984689 -246.87255) (xy 371.030963 -246.896128) (xy 371.072979 -246.926654) (xy 371.109702 -246.963377)
			(xy 371.140228 -247.005393) (xy 371.163806 -247.051667) (xy 371.179854 -247.10106) (xy 371.187979 -247.152355)
			(xy 371.188488 -247.178322) (xy 371.187979 -247.204289) (xy 371.467889 -247.204289) (xy 371.467889 -247.152355)
			(xy 371.476014 -247.10106) (xy 371.492062 -247.051667) (xy 371.51564 -247.005393) (xy 371.546166 -246.963377)
			(xy 371.582889 -246.926654) (xy 371.624905 -246.896128) (xy 371.671179 -246.87255) (xy 371.720572 -246.856502)
			(xy 371.771867 -246.848377) (xy 371.823801 -246.848377) (xy 371.875096 -246.856502) (xy 371.924489 -246.87255)
			(xy 371.970763 -246.896128) (xy 372.012779 -246.926654) (xy 372.049502 -246.963377) (xy 372.080028 -247.005393)
			(xy 372.103606 -247.051667) (xy 372.119654 -247.10106) (xy 372.127779 -247.152355) (xy 372.128288 -247.178322)
			(xy 372.127779 -247.204289) (xy 372.407689 -247.204289) (xy 372.407689 -247.152355) (xy 372.415814 -247.10106)
			(xy 372.431862 -247.051667) (xy 372.45544 -247.005393) (xy 372.485966 -246.963377) (xy 372.522689 -246.926654)
			(xy 372.564705 -246.896128) (xy 372.610979 -246.87255) (xy 372.660372 -246.856502) (xy 372.711667 -246.848377)
			(xy 372.763601 -246.848377) (xy 372.814896 -246.856502) (xy 372.864289 -246.87255) (xy 372.910563 -246.896128)
			(xy 372.952579 -246.926654) (xy 372.989302 -246.963377) (xy 373.019828 -247.005393) (xy 373.043406 -247.051667)
			(xy 373.059454 -247.10106) (xy 373.067579 -247.152355) (xy 373.068088 -247.178322) (xy 373.067579 -247.204289)
			(xy 373.347489 -247.204289) (xy 373.347489 -247.152355) (xy 373.355614 -247.10106) (xy 373.371662 -247.051667)
			(xy 373.39524 -247.005393) (xy 373.425766 -246.963377) (xy 373.462489 -246.926654) (xy 373.504505 -246.896128)
			(xy 373.550779 -246.87255) (xy 373.600172 -246.856502) (xy 373.651467 -246.848377) (xy 373.703401 -246.848377)
			(xy 373.754696 -246.856502) (xy 373.804089 -246.87255) (xy 373.850363 -246.896128) (xy 373.892379 -246.926654)
			(xy 373.929102 -246.963377) (xy 373.959628 -247.005393) (xy 373.983206 -247.051667) (xy 373.999254 -247.10106)
			(xy 374.007379 -247.152355) (xy 374.007888 -247.178322) (xy 374.007379 -247.204289) (xy 374.287035 -247.204289)
			(xy 374.287035 -247.152355) (xy 374.29516 -247.10106) (xy 374.311208 -247.051667) (xy 374.334786 -247.005393)
			(xy 374.365312 -246.963377) (xy 374.402035 -246.926654) (xy 374.444051 -246.896128) (xy 374.490325 -246.87255)
			(xy 374.539718 -246.856502) (xy 374.591013 -246.848377) (xy 374.642947 -246.848377) (xy 374.694242 -246.856502)
			(xy 374.743635 -246.87255) (xy 374.789909 -246.896128) (xy 374.831925 -246.926654) (xy 374.868648 -246.963377)
			(xy 374.899174 -247.005393) (xy 374.922752 -247.051667) (xy 374.9388 -247.10106) (xy 374.946925 -247.152355)
			(xy 374.947434 -247.178322) (xy 374.946925 -247.204289) (xy 375.227089 -247.204289) (xy 375.227089 -247.152355)
			(xy 375.235214 -247.10106) (xy 375.251262 -247.051667) (xy 375.27484 -247.005393) (xy 375.305366 -246.963377)
			(xy 375.342089 -246.926654) (xy 375.384105 -246.896128) (xy 375.430379 -246.87255) (xy 375.479772 -246.856502)
			(xy 375.531067 -246.848377) (xy 375.583001 -246.848377) (xy 375.634296 -246.856502) (xy 375.683689 -246.87255)
			(xy 375.729963 -246.896128) (xy 375.771979 -246.926654) (xy 375.808702 -246.963377) (xy 375.839228 -247.005393)
			(xy 375.862806 -247.051667) (xy 375.878854 -247.10106) (xy 375.886979 -247.152355) (xy 375.887488 -247.178322)
			(xy 375.886979 -247.204289) (xy 376.166889 -247.204289) (xy 376.166889 -247.152355) (xy 376.175014 -247.10106)
			(xy 376.191062 -247.051667) (xy 376.21464 -247.005393) (xy 376.245166 -246.963377) (xy 376.281889 -246.926654)
			(xy 376.323905 -246.896128) (xy 376.370179 -246.87255) (xy 376.419572 -246.856502) (xy 376.470867 -246.848377)
			(xy 376.522801 -246.848377) (xy 376.574096 -246.856502) (xy 376.623489 -246.87255) (xy 376.669763 -246.896128)
			(xy 376.711779 -246.926654) (xy 376.748502 -246.963377) (xy 376.779028 -247.005393) (xy 376.802606 -247.051667)
			(xy 376.818654 -247.10106) (xy 376.826779 -247.152355) (xy 376.827288 -247.178322) (xy 376.826779 -247.204289)
			(xy 377.106689 -247.204289) (xy 377.106689 -247.152355) (xy 377.114814 -247.10106) (xy 377.130862 -247.051667)
			(xy 377.15444 -247.005393) (xy 377.184966 -246.963377) (xy 377.221689 -246.926654) (xy 377.263705 -246.896128)
			(xy 377.309979 -246.87255) (xy 377.359372 -246.856502) (xy 377.410667 -246.848377) (xy 377.462601 -246.848377)
			(xy 377.513896 -246.856502) (xy 377.563289 -246.87255) (xy 377.609563 -246.896128) (xy 377.651579 -246.926654)
			(xy 377.688302 -246.963377) (xy 377.718828 -247.005393) (xy 377.742406 -247.051667) (xy 377.758454 -247.10106)
			(xy 377.766579 -247.152355) (xy 377.767088 -247.178322) (xy 377.766579 -247.204289) (xy 378.046489 -247.204289)
			(xy 378.046489 -247.152355) (xy 378.054614 -247.10106) (xy 378.070662 -247.051667) (xy 378.09424 -247.005393)
			(xy 378.124766 -246.963377) (xy 378.161489 -246.926654) (xy 378.203505 -246.896128) (xy 378.249779 -246.87255)
			(xy 378.299172 -246.856502) (xy 378.350467 -246.848377) (xy 378.402401 -246.848377) (xy 378.453696 -246.856502)
			(xy 378.503089 -246.87255) (xy 378.549363 -246.896128) (xy 378.591379 -246.926654) (xy 378.628102 -246.963377)
			(xy 378.658628 -247.005393) (xy 378.682206 -247.051667) (xy 378.698254 -247.10106) (xy 378.706379 -247.152355)
			(xy 378.706888 -247.178322) (xy 378.706379 -247.204289) (xy 378.986035 -247.204289) (xy 378.986035 -247.152355)
			(xy 378.99416 -247.10106) (xy 379.010208 -247.051667) (xy 379.033786 -247.005393) (xy 379.064312 -246.963377)
			(xy 379.101035 -246.926654) (xy 379.143051 -246.896128) (xy 379.189325 -246.87255) (xy 379.238718 -246.856502)
			(xy 379.290013 -246.848377) (xy 379.341947 -246.848377) (xy 379.393242 -246.856502) (xy 379.442635 -246.87255)
			(xy 379.488909 -246.896128) (xy 379.530925 -246.926654) (xy 379.567648 -246.963377) (xy 379.598174 -247.005393)
			(xy 379.621752 -247.051667) (xy 379.6378 -247.10106) (xy 379.645925 -247.152355) (xy 379.646434 -247.178322)
			(xy 379.645925 -247.204289) (xy 379.6378 -247.255584) (xy 379.621752 -247.304977) (xy 379.598174 -247.351251)
			(xy 379.567648 -247.393267) (xy 379.530925 -247.42999) (xy 379.488909 -247.460516) (xy 379.442635 -247.484094)
			(xy 379.393242 -247.500142) (xy 379.341947 -247.508267) (xy 379.290013 -247.508267) (xy 379.238718 -247.500142)
			(xy 379.189325 -247.484094) (xy 379.143051 -247.460516) (xy 379.101035 -247.42999) (xy 379.064312 -247.393267)
			(xy 379.033786 -247.351251) (xy 379.010208 -247.304977) (xy 378.99416 -247.255584) (xy 378.986035 -247.204289)
			(xy 378.706379 -247.204289) (xy 378.698254 -247.255584) (xy 378.682206 -247.304977) (xy 378.658628 -247.351251)
			(xy 378.628102 -247.393267) (xy 378.591379 -247.42999) (xy 378.549363 -247.460516) (xy 378.503089 -247.484094)
			(xy 378.453696 -247.500142) (xy 378.402401 -247.508267) (xy 378.350467 -247.508267) (xy 378.299172 -247.500142)
			(xy 378.249779 -247.484094) (xy 378.203505 -247.460516) (xy 378.161489 -247.42999) (xy 378.124766 -247.393267)
			(xy 378.09424 -247.351251) (xy 378.070662 -247.304977) (xy 378.054614 -247.255584) (xy 378.046489 -247.204289)
			(xy 377.766579 -247.204289) (xy 377.758454 -247.255584) (xy 377.742406 -247.304977) (xy 377.718828 -247.351251)
			(xy 377.688302 -247.393267) (xy 377.651579 -247.42999) (xy 377.609563 -247.460516) (xy 377.563289 -247.484094)
			(xy 377.513896 -247.500142) (xy 377.462601 -247.508267) (xy 377.410667 -247.508267) (xy 377.359372 -247.500142)
			(xy 377.309979 -247.484094) (xy 377.263705 -247.460516) (xy 377.221689 -247.42999) (xy 377.184966 -247.393267)
			(xy 377.15444 -247.351251) (xy 377.130862 -247.304977) (xy 377.114814 -247.255584) (xy 377.106689 -247.204289)
			(xy 376.826779 -247.204289) (xy 376.818654 -247.255584) (xy 376.802606 -247.304977) (xy 376.779028 -247.351251)
			(xy 376.748502 -247.393267) (xy 376.711779 -247.42999) (xy 376.669763 -247.460516) (xy 376.623489 -247.484094)
			(xy 376.574096 -247.500142) (xy 376.522801 -247.508267) (xy 376.470867 -247.508267) (xy 376.419572 -247.500142)
			(xy 376.370179 -247.484094) (xy 376.323905 -247.460516) (xy 376.281889 -247.42999) (xy 376.245166 -247.393267)
			(xy 376.21464 -247.351251) (xy 376.191062 -247.304977) (xy 376.175014 -247.255584) (xy 376.166889 -247.204289)
			(xy 375.886979 -247.204289) (xy 375.878854 -247.255584) (xy 375.862806 -247.304977) (xy 375.839228 -247.351251)
			(xy 375.808702 -247.393267) (xy 375.771979 -247.42999) (xy 375.729963 -247.460516) (xy 375.683689 -247.484094)
			(xy 375.634296 -247.500142) (xy 375.583001 -247.508267) (xy 375.531067 -247.508267) (xy 375.479772 -247.500142)
			(xy 375.430379 -247.484094) (xy 375.384105 -247.460516) (xy 375.342089 -247.42999) (xy 375.305366 -247.393267)
			(xy 375.27484 -247.351251) (xy 375.251262 -247.304977) (xy 375.235214 -247.255584) (xy 375.227089 -247.204289)
			(xy 374.946925 -247.204289) (xy 374.9388 -247.255584) (xy 374.922752 -247.304977) (xy 374.899174 -247.351251)
			(xy 374.868648 -247.393267) (xy 374.831925 -247.42999) (xy 374.789909 -247.460516) (xy 374.743635 -247.484094)
			(xy 374.694242 -247.500142) (xy 374.642947 -247.508267) (xy 374.591013 -247.508267) (xy 374.539718 -247.500142)
			(xy 374.490325 -247.484094) (xy 374.444051 -247.460516) (xy 374.402035 -247.42999) (xy 374.365312 -247.393267)
			(xy 374.334786 -247.351251) (xy 374.311208 -247.304977) (xy 374.29516 -247.255584) (xy 374.287035 -247.204289)
			(xy 374.007379 -247.204289) (xy 373.999254 -247.255584) (xy 373.983206 -247.304977) (xy 373.959628 -247.351251)
			(xy 373.929102 -247.393267) (xy 373.892379 -247.42999) (xy 373.850363 -247.460516) (xy 373.804089 -247.484094)
			(xy 373.754696 -247.500142) (xy 373.703401 -247.508267) (xy 373.651467 -247.508267) (xy 373.600172 -247.500142)
			(xy 373.550779 -247.484094) (xy 373.504505 -247.460516) (xy 373.462489 -247.42999) (xy 373.425766 -247.393267)
			(xy 373.39524 -247.351251) (xy 373.371662 -247.304977) (xy 373.355614 -247.255584) (xy 373.347489 -247.204289)
			(xy 373.067579 -247.204289) (xy 373.059454 -247.255584) (xy 373.043406 -247.304977) (xy 373.019828 -247.351251)
			(xy 372.989302 -247.393267) (xy 372.952579 -247.42999) (xy 372.910563 -247.460516) (xy 372.864289 -247.484094)
			(xy 372.814896 -247.500142) (xy 372.763601 -247.508267) (xy 372.711667 -247.508267) (xy 372.660372 -247.500142)
			(xy 372.610979 -247.484094) (xy 372.564705 -247.460516) (xy 372.522689 -247.42999) (xy 372.485966 -247.393267)
			(xy 372.45544 -247.351251) (xy 372.431862 -247.304977) (xy 372.415814 -247.255584) (xy 372.407689 -247.204289)
			(xy 372.127779 -247.204289) (xy 372.119654 -247.255584) (xy 372.103606 -247.304977) (xy 372.080028 -247.351251)
			(xy 372.049502 -247.393267) (xy 372.012779 -247.42999) (xy 371.970763 -247.460516) (xy 371.924489 -247.484094)
			(xy 371.875096 -247.500142) (xy 371.823801 -247.508267) (xy 371.771867 -247.508267) (xy 371.720572 -247.500142)
			(xy 371.671179 -247.484094) (xy 371.624905 -247.460516) (xy 371.582889 -247.42999) (xy 371.546166 -247.393267)
			(xy 371.51564 -247.351251) (xy 371.492062 -247.304977) (xy 371.476014 -247.255584) (xy 371.467889 -247.204289)
			(xy 371.187979 -247.204289) (xy 371.179854 -247.255584) (xy 371.163806 -247.304977) (xy 371.140228 -247.351251)
			(xy 371.109702 -247.393267) (xy 371.072979 -247.42999) (xy 371.030963 -247.460516) (xy 370.984689 -247.484094)
			(xy 370.935296 -247.500142) (xy 370.884001 -247.508267) (xy 370.832067 -247.508267) (xy 370.780772 -247.500142)
			(xy 370.731379 -247.484094) (xy 370.685105 -247.460516) (xy 370.643089 -247.42999) (xy 370.606366 -247.393267)
			(xy 370.57584 -247.351251) (xy 370.552262 -247.304977) (xy 370.536214 -247.255584) (xy 370.528089 -247.204289)
			(xy 370.248179 -247.204289) (xy 370.240054 -247.255584) (xy 370.224006 -247.304977) (xy 370.200428 -247.351251)
			(xy 370.169902 -247.393267) (xy 370.133179 -247.42999) (xy 370.091163 -247.460516) (xy 370.044889 -247.484094)
			(xy 369.995496 -247.500142) (xy 369.944201 -247.508267) (xy 369.892267 -247.508267) (xy 369.840972 -247.500142)
			(xy 369.791579 -247.484094) (xy 369.745305 -247.460516) (xy 369.703289 -247.42999) (xy 369.666566 -247.393267)
			(xy 369.63604 -247.351251) (xy 369.612462 -247.304977) (xy 369.596414 -247.255584) (xy 369.588289 -247.204289)
			(xy 369.211683 -247.204289) (xy 369.224601 -247.231348) (xy 369.238954 -247.278255) (xy 369.24621 -247.326769)
			(xy 369.246658 -247.351296) (xy 369.246658 -247.35155) (xy 369.246149 -247.377517) (xy 369.238024 -247.428812)
			(xy 369.221976 -247.478205) (xy 369.198398 -247.524479) (xy 369.167872 -247.566495) (xy 369.131149 -247.603218)
			(xy 369.089133 -247.633744) (xy 369.042859 -247.657322) (xy 368.993466 -247.67337) (xy 368.942171 -247.681495)
			(xy 368.890237 -247.681495) (xy 368.838942 -247.67337) (xy 368.789549 -247.657322) (xy 368.743275 -247.633744)
			(xy 368.701259 -247.603218) (xy 368.664536 -247.566495) (xy 368.63401 -247.524479) (xy 368.610432 -247.478205)
			(xy 368.594384 -247.428812) (xy 368.586259 -247.377517) (xy 368.58575 -247.35155) (xy 368.58575 -247.351296)
			(xy 368.586212 -247.32677) (xy 368.593475 -247.278258) (xy 368.607824 -247.231352) (xy 368.628947 -247.18708)
			(xy 368.656378 -247.146415) (xy 368.672618 -247.12803) (xy 368.682369 -247.116501) (xy 368.695383 -247.089277)
			(xy 368.699859 -247.059437) (xy 368.695404 -247.029593) (xy 368.682411 -247.00236) (xy 368.672618 -246.99087)
			(xy 368.664894 -246.982303) (xy 368.650531 -246.964252) (xy 368.643916 -246.954802) (xy 368.635972 -246.943975)
			(xy 368.615543 -246.926562) (xy 368.591282 -246.915076) (xy 368.564865 -246.910309) (xy 368.538119 -246.912592)
			(xy 368.512893 -246.921766) (xy 368.501676 -246.929148) (xy 368.480687 -246.943395) (xy 368.43526 -246.965967)
			(xy 368.386917 -246.981329) (xy 368.336793 -246.989119) (xy 368.31143 -246.9896) (xy 368.311176 -246.9896)
			(xy 368.286649 -246.989163) (xy 368.238135 -246.981896) (xy 368.191228 -246.967541) (xy 368.146957 -246.946413)
			(xy 368.106293 -246.918975) (xy 368.08791 -246.902732) (xy 368.076421 -246.892929) (xy 368.049184 -246.879915)
			(xy 368.01933 -246.875447) (xy 367.989476 -246.879915) (xy 367.962239 -246.892929) (xy 367.95075 -246.902732)
			(xy 367.932335 -246.918978) (xy 367.891634 -246.94645) (xy 367.847314 -246.967593) (xy 367.800352 -246.981938)
			(xy 367.751783 -246.98917) (xy 367.72723 -246.9896) (xy 367.702677 -246.98918) (xy 367.654109 -246.981936)
			(xy 367.607147 -246.967588) (xy 367.562823 -246.946451) (xy 367.522113 -246.918991) (xy 367.50371 -246.902732)
			(xy 367.492221 -246.892929) (xy 367.464984 -246.879915) (xy 367.43513 -246.875447) (xy 367.405276 -246.879915)
			(xy 367.378039 -246.892929) (xy 367.36655 -246.902732) (xy 367.348155 -246.918962) (xy 367.307501 -246.946412)
			(xy 367.263233 -246.967546) (xy 367.216325 -246.981899) (xy 367.167811 -246.989153) (xy 367.143284 -246.9896)
			(xy 367.14303 -246.9896) (xy 367.117063 -246.989028) (xy 367.065767 -246.980907) (xy 367.016373 -246.964862)
			(xy 366.970098 -246.941288) (xy 366.928081 -246.910764) (xy 366.891356 -246.874042) (xy 366.860828 -246.832028)
			(xy 366.837249 -246.785754) (xy 366.8212 -246.736362) (xy 366.813075 -246.685067) (xy 366.702891 -246.685067)
			(xy 366.702891 -246.685071) (xy 366.694765 -246.736373) (xy 366.678714 -246.785772) (xy 366.655134 -246.832052)
			(xy 366.624603 -246.874074) (xy 366.587875 -246.910802) (xy 366.545854 -246.941333) (xy 366.499574 -246.964914)
			(xy 366.450175 -246.980965) (xy 366.398873 -246.98909) (xy 366.372902 -246.9896) (xy 366.347578 -246.989157)
			(xy 366.297522 -246.981433) (xy 366.24923 -246.966166) (xy 366.203831 -246.943712) (xy 366.162388 -246.914597)
			(xy 366.143794 -246.897398) (xy 366.133939 -246.888491) (xy 366.110728 -246.875595) (xy 366.084972 -246.869139)
			(xy 366.058422 -246.86956) (xy 366.032884 -246.876831) (xy 366.010094 -246.890457) (xy 366.000538 -246.899684)
			(xy 365.981748 -246.918251) (xy 365.93936 -246.94977) (xy 365.892501 -246.974151) (xy 365.842363 -246.990775)
			(xy 365.790221 -246.999219) (xy 365.76381 -246.99976) (xy 365.73723 -246.999206) (xy 365.684755 -246.990704)
			(xy 365.634315 -246.973919) (xy 365.587209 -246.949281) (xy 365.544651 -246.917426) (xy 365.525812 -246.898668)
			(xy 365.516041 -246.889143) (xy 365.492599 -246.875199) (xy 365.466298 -246.867969) (xy 365.439022 -246.867969)
			(xy 365.412721 -246.875199) (xy 365.389279 -246.889143) (xy 365.379508 -246.898668) (xy 365.360659 -246.917417)
			(xy 365.318107 -246.949282) (xy 365.271005 -246.973929) (xy 365.220566 -246.990722) (xy 365.16809 -246.999229)
			(xy 365.14151 -246.99976) (xy 365.115541 -246.999266) (xy 365.064241 -246.991142) (xy 365.014844 -246.975094)
			(xy 364.968566 -246.951515) (xy 364.926546 -246.920987) (xy 364.88982 -246.884261) (xy 364.85929 -246.842242)
			(xy 364.83571 -246.795965) (xy 364.81966 -246.746568) (xy 364.811535 -246.695269) (xy 364.702766 -246.695269)
			(xy 364.69625 -246.736408) (xy 364.680202 -246.785801) (xy 364.656624 -246.832075) (xy 364.626098 -246.874091)
			(xy 364.589375 -246.910814) (xy 364.547359 -246.94134) (xy 364.501085 -246.964918) (xy 364.451692 -246.980966)
			(xy 364.400397 -246.989091) (xy 364.348463 -246.989091) (xy 364.297168 -246.980966) (xy 364.247775 -246.964918)
			(xy 364.201501 -246.94134) (xy 364.159485 -246.910814) (xy 364.122762 -246.874091) (xy 364.092236 -246.832075)
			(xy 364.068658 -246.785801) (xy 364.05261 -246.736408) (xy 364.044485 -246.685113) (xy 363.418015 -246.685113)
			(xy 363.412573 -246.702894) (xy 363.391443 -246.747165) (xy 363.364005 -246.787829) (xy 363.347762 -246.806212)
			(xy 363.337963 -246.817706) (xy 363.324944 -246.84494) (xy 363.320472 -246.874794) (xy 363.32494 -246.904648)
			(xy 363.337957 -246.931884) (xy 363.347762 -246.943372) (xy 363.364007 -246.961754) (xy 363.391455 -247.002412)
			(xy 363.412585 -247.046684) (xy 363.426934 -247.093594) (xy 363.434185 -247.14211) (xy 363.43463 -247.166638)
			(xy 363.43463 -247.166892) (xy 363.434164 -247.192862) (xy 363.426039 -247.244163) (xy 363.409989 -247.293562)
			(xy 363.386408 -247.339841) (xy 363.355878 -247.381861) (xy 363.319149 -247.418588) (xy 363.277127 -247.449117)
			(xy 363.230847 -247.472695) (xy 363.181448 -247.488743) (xy 363.130146 -247.496865) (xy 363.104176 -247.497346)
			(xy 363.078373 -247.496812) (xy 363.027394 -247.4888) (xy 362.97828 -247.47296) (xy 362.932227 -247.449677)
			(xy 362.890353 -247.419517) (xy 362.853677 -247.383214) (xy 362.837984 -247.362726) (xy 362.829442 -247.351802)
			(xy 362.807646 -247.334674) (xy 362.782043 -247.324046) (xy 362.754524 -247.320705) (xy 362.727122 -247.324895)
			(xy 362.70186 -247.336308) (xy 362.680603 -247.354101) (xy 362.672376 -247.365266) (xy 362.656851 -247.387017)
			(xy 362.619914 -247.425631) (xy 362.577248 -247.457803) (xy 362.529964 -247.482696) (xy 362.479292 -247.499663)
			(xy 362.426552 -247.50826) (xy 362.399834 -247.508776) (xy 362.373865 -247.508252) (xy 362.322565 -247.500132)
			(xy 362.273167 -247.484086) (xy 362.226888 -247.460509) (xy 362.184867 -247.429983) (xy 362.148139 -247.393259)
			(xy 362.117608 -247.351241) (xy 362.094027 -247.304964) (xy 362.077976 -247.255568) (xy 362.069851 -247.204269)
			(xy 361.789979 -247.204269) (xy 361.789979 -247.204289) (xy 361.781854 -247.255584) (xy 361.765806 -247.304977)
			(xy 361.742228 -247.351251) (xy 361.711702 -247.393267) (xy 361.674979 -247.42999) (xy 361.632963 -247.460516)
			(xy 361.586689 -247.484094) (xy 361.537296 -247.500142) (xy 361.486001 -247.508267) (xy 361.434067 -247.508267)
			(xy 361.382772 -247.500142) (xy 361.333379 -247.484094) (xy 361.287105 -247.460516) (xy 361.245089 -247.42999)
			(xy 361.208366 -247.393267) (xy 361.17784 -247.351251) (xy 361.154262 -247.304977) (xy 361.138214 -247.255584)
			(xy 361.130089 -247.204289) (xy 360.849925 -247.204289) (xy 360.8418 -247.255584) (xy 360.825752 -247.304977)
			(xy 360.802174 -247.351251) (xy 360.771648 -247.393267) (xy 360.734925 -247.42999) (xy 360.692909 -247.460516)
			(xy 360.646635 -247.484094) (xy 360.597242 -247.500142) (xy 360.545947 -247.508267) (xy 360.494013 -247.508267)
			(xy 360.442718 -247.500142) (xy 360.393325 -247.484094) (xy 360.347051 -247.460516) (xy 360.305035 -247.42999)
			(xy 360.268312 -247.393267) (xy 360.237786 -247.351251) (xy 360.214208 -247.304977) (xy 360.19816 -247.255584)
			(xy 360.190035 -247.204289) (xy 359.910125 -247.204289) (xy 359.902 -247.255584) (xy 359.885952 -247.304977)
			(xy 359.862374 -247.351251) (xy 359.831848 -247.393267) (xy 359.795125 -247.42999) (xy 359.753109 -247.460516)
			(xy 359.706835 -247.484094) (xy 359.657442 -247.500142) (xy 359.606147 -247.508267) (xy 359.554213 -247.508267)
			(xy 359.502918 -247.500142) (xy 359.453525 -247.484094) (xy 359.407251 -247.460516) (xy 359.365235 -247.42999)
			(xy 359.328512 -247.393267) (xy 359.297986 -247.351251) (xy 359.274408 -247.304977) (xy 359.25836 -247.255584)
			(xy 359.250235 -247.204289) (xy 358.970579 -247.204289) (xy 358.962454 -247.255584) (xy 358.946406 -247.304977)
			(xy 358.922828 -247.351251) (xy 358.892302 -247.393267) (xy 358.855579 -247.42999) (xy 358.813563 -247.460516)
			(xy 358.767289 -247.484094) (xy 358.717896 -247.500142) (xy 358.666601 -247.508267) (xy 358.614667 -247.508267)
			(xy 358.563372 -247.500142) (xy 358.513979 -247.484094) (xy 358.467705 -247.460516) (xy 358.425689 -247.42999)
			(xy 358.388966 -247.393267) (xy 358.35844 -247.351251) (xy 358.334862 -247.304977) (xy 358.318814 -247.255584)
			(xy 358.310689 -247.204289) (xy 358.030525 -247.204289) (xy 358.0224 -247.255584) (xy 358.006352 -247.304977)
			(xy 357.982774 -247.351251) (xy 357.952248 -247.393267) (xy 357.915525 -247.42999) (xy 357.873509 -247.460516)
			(xy 357.827235 -247.484094) (xy 357.777842 -247.500142) (xy 357.726547 -247.508267) (xy 357.674613 -247.508267)
			(xy 357.623318 -247.500142) (xy 357.573925 -247.484094) (xy 357.527651 -247.460516) (xy 357.485635 -247.42999)
			(xy 357.448912 -247.393267) (xy 357.418386 -247.351251) (xy 357.394808 -247.304977) (xy 357.37876 -247.255584)
			(xy 357.370635 -247.204289) (xy 350.512379 -247.204289) (xy 350.504254 -247.255584) (xy 350.488206 -247.304977)
			(xy 350.464628 -247.351251) (xy 350.434102 -247.393267) (xy 350.397379 -247.42999) (xy 350.355363 -247.460516)
			(xy 350.309089 -247.484094) (xy 350.259696 -247.500142) (xy 350.208401 -247.508267) (xy 350.156467 -247.508267)
			(xy 350.105172 -247.500142) (xy 350.055779 -247.484094) (xy 350.009505 -247.460516) (xy 349.967489 -247.42999)
			(xy 349.930766 -247.393267) (xy 349.90024 -247.351251) (xy 349.876662 -247.304977) (xy 349.860614 -247.255584)
			(xy 349.852489 -247.204289) (xy 349.572579 -247.204289) (xy 349.564454 -247.255584) (xy 349.548406 -247.304977)
			(xy 349.524828 -247.351251) (xy 349.494302 -247.393267) (xy 349.457579 -247.42999) (xy 349.415563 -247.460516)
			(xy 349.369289 -247.484094) (xy 349.319896 -247.500142) (xy 349.268601 -247.508267) (xy 349.216667 -247.508267)
			(xy 349.165372 -247.500142) (xy 349.115979 -247.484094) (xy 349.069705 -247.460516) (xy 349.027689 -247.42999)
			(xy 348.990966 -247.393267) (xy 348.96044 -247.351251) (xy 348.936862 -247.304977) (xy 348.920814 -247.255584)
			(xy 348.912689 -247.204289) (xy 348.632779 -247.204289) (xy 348.624654 -247.255584) (xy 348.608606 -247.304977)
			(xy 348.585028 -247.351251) (xy 348.554502 -247.393267) (xy 348.517779 -247.42999) (xy 348.475763 -247.460516)
			(xy 348.429489 -247.484094) (xy 348.380096 -247.500142) (xy 348.328801 -247.508267) (xy 348.276867 -247.508267)
			(xy 348.225572 -247.500142) (xy 348.176179 -247.484094) (xy 348.129905 -247.460516) (xy 348.087889 -247.42999)
			(xy 348.051166 -247.393267) (xy 348.02064 -247.351251) (xy 347.997062 -247.304977) (xy 347.981014 -247.255584)
			(xy 347.972889 -247.204289) (xy 347.692979 -247.204289) (xy 347.684854 -247.255584) (xy 347.668806 -247.304977)
			(xy 347.645228 -247.351251) (xy 347.614702 -247.393267) (xy 347.577979 -247.42999) (xy 347.535963 -247.460516)
			(xy 347.489689 -247.484094) (xy 347.440296 -247.500142) (xy 347.389001 -247.508267) (xy 347.337067 -247.508267)
			(xy 347.285772 -247.500142) (xy 347.236379 -247.484094) (xy 347.190105 -247.460516) (xy 347.148089 -247.42999)
			(xy 347.111366 -247.393267) (xy 347.08084 -247.351251) (xy 347.057262 -247.304977) (xy 347.041214 -247.255584)
			(xy 347.033089 -247.204289) (xy 346.752925 -247.204289) (xy 346.7448 -247.255584) (xy 346.728752 -247.304977)
			(xy 346.705174 -247.351251) (xy 346.674648 -247.393267) (xy 346.637925 -247.42999) (xy 346.595909 -247.460516)
			(xy 346.549635 -247.484094) (xy 346.500242 -247.500142) (xy 346.448947 -247.508267) (xy 346.397013 -247.508267)
			(xy 346.345718 -247.500142) (xy 346.296325 -247.484094) (xy 346.250051 -247.460516) (xy 346.208035 -247.42999)
			(xy 346.171312 -247.393267) (xy 346.140786 -247.351251) (xy 346.117208 -247.304977) (xy 346.10116 -247.255584)
			(xy 346.093035 -247.204289) (xy 345.813379 -247.204289) (xy 345.805254 -247.255584) (xy 345.789206 -247.304977)
			(xy 345.765628 -247.351251) (xy 345.735102 -247.393267) (xy 345.698379 -247.42999) (xy 345.656363 -247.460516)
			(xy 345.610089 -247.484094) (xy 345.560696 -247.500142) (xy 345.509401 -247.508267) (xy 345.457467 -247.508267)
			(xy 345.406172 -247.500142) (xy 345.356779 -247.484094) (xy 345.310505 -247.460516) (xy 345.268489 -247.42999)
			(xy 345.231766 -247.393267) (xy 345.20124 -247.351251) (xy 345.177662 -247.304977) (xy 345.161614 -247.255584)
			(xy 345.153489 -247.204289) (xy 344.873325 -247.204289) (xy 344.8652 -247.255584) (xy 344.849152 -247.304977)
			(xy 344.825574 -247.351251) (xy 344.795048 -247.393267) (xy 344.758325 -247.42999) (xy 344.716309 -247.460516)
			(xy 344.670035 -247.484094) (xy 344.620642 -247.500142) (xy 344.569347 -247.508267) (xy 344.517413 -247.508267)
			(xy 344.466118 -247.500142) (xy 344.416725 -247.484094) (xy 344.370451 -247.460516) (xy 344.328435 -247.42999)
			(xy 344.291712 -247.393267) (xy 344.261186 -247.351251) (xy 344.237608 -247.304977) (xy 344.22156 -247.255584)
			(xy 344.213435 -247.204289) (xy 343.933779 -247.204289) (xy 343.925654 -247.255584) (xy 343.909606 -247.304977)
			(xy 343.886028 -247.351251) (xy 343.855502 -247.393267) (xy 343.818779 -247.42999) (xy 343.776763 -247.460516)
			(xy 343.730489 -247.484094) (xy 343.681096 -247.500142) (xy 343.629801 -247.508267) (xy 343.577867 -247.508267)
			(xy 343.526572 -247.500142) (xy 343.477179 -247.484094) (xy 343.430905 -247.460516) (xy 343.388889 -247.42999)
			(xy 343.352166 -247.393267) (xy 343.32164 -247.351251) (xy 343.298062 -247.304977) (xy 343.282014 -247.255584)
			(xy 343.273889 -247.204289) (xy 342.993666 -247.204289) (xy 342.99313 -247.21216) (xy 342.991694 -247.22328)
			(xy 342.991186 -247.226836) (xy 342.991186 -247.22836) (xy 342.986877 -247.25345) (xy 342.971568 -247.302)
			(xy 342.949009 -247.347634) (xy 342.919731 -247.389278) (xy 342.884424 -247.42595) (xy 342.86444 -247.44172)
			(xy 342.86063 -247.444514) (xy 342.85414 -247.451089) (xy 342.845939 -247.467627) (xy 342.844628 -247.476772)
			(xy 342.839548 -247.553988) (xy 342.839503 -247.564538) (xy 342.846978 -247.584239) (xy 342.854026 -247.592088)
			(xy 342.942164 -247.680226) (xy 342.945414 -247.683344) (xy 342.952826 -247.688459) (xy 342.956896 -247.690386)
			(xy 342.998044 -247.690386) (xy 343.003124 -247.688354) (xy 343.023827 -247.679846) (xy 343.066952 -247.667858)
			(xy 343.1113 -247.661801) (xy 343.13368 -247.66143) (xy 343.140284 -247.66143) (xy 343.1656 -247.662418)
			(xy 343.215506 -247.671139) (xy 343.263497 -247.687369) (xy 343.308452 -247.710729) (xy 343.349319 -247.740671)
			(xy 343.385141 -247.776495) (xy 343.415081 -247.817363) (xy 343.438438 -247.86232) (xy 343.454665 -247.910312)
			(xy 343.463384 -247.960218) (xy 343.464388 -247.985534) (xy 343.464388 -247.992138) (xy 343.463991 -248.015394)
			(xy 343.463607 -248.018105) (xy 343.743789 -248.018105) (xy 343.743789 -247.966171) (xy 343.751914 -247.914876)
			(xy 343.767962 -247.865483) (xy 343.79154 -247.819209) (xy 343.822066 -247.777193) (xy 343.858789 -247.74047)
			(xy 343.900805 -247.709944) (xy 343.947079 -247.686366) (xy 343.996472 -247.670318) (xy 344.047767 -247.662193)
			(xy 344.099701 -247.662193) (xy 344.150996 -247.670318) (xy 344.200389 -247.686366) (xy 344.246663 -247.709944)
			(xy 344.288679 -247.74047) (xy 344.325402 -247.777193) (xy 344.355928 -247.819209) (xy 344.379506 -247.865483)
			(xy 344.395554 -247.914876) (xy 344.403679 -247.966171) (xy 344.404188 -247.992138) (xy 344.403679 -248.018105)
			(xy 344.683335 -248.018105) (xy 344.683335 -247.966171) (xy 344.69146 -247.914876) (xy 344.707508 -247.865483)
			(xy 344.731086 -247.819209) (xy 344.761612 -247.777193) (xy 344.798335 -247.74047) (xy 344.840351 -247.709944)
			(xy 344.886625 -247.686366) (xy 344.936018 -247.670318) (xy 344.987313 -247.662193) (xy 345.039247 -247.662193)
			(xy 345.090542 -247.670318) (xy 345.139935 -247.686366) (xy 345.186209 -247.709944) (xy 345.228225 -247.74047)
			(xy 345.264948 -247.777193) (xy 345.295474 -247.819209) (xy 345.319052 -247.865483) (xy 345.3351 -247.914876)
			(xy 345.343225 -247.966171) (xy 345.343734 -247.992138) (xy 345.343225 -248.018105) (xy 345.623389 -248.018105)
			(xy 345.623389 -247.966171) (xy 345.631514 -247.914876) (xy 345.647562 -247.865483) (xy 345.67114 -247.819209)
			(xy 345.701666 -247.777193) (xy 345.738389 -247.74047) (xy 345.780405 -247.709944) (xy 345.826679 -247.686366)
			(xy 345.876072 -247.670318) (xy 345.927367 -247.662193) (xy 345.979301 -247.662193) (xy 346.030596 -247.670318)
			(xy 346.079989 -247.686366) (xy 346.126263 -247.709944) (xy 346.168279 -247.74047) (xy 346.205002 -247.777193)
			(xy 346.235528 -247.819209) (xy 346.259106 -247.865483) (xy 346.275154 -247.914876) (xy 346.283279 -247.966171)
			(xy 346.283788 -247.992138) (xy 346.283279 -248.018105) (xy 346.563189 -248.018105) (xy 346.563189 -247.966171)
			(xy 346.571314 -247.914876) (xy 346.587362 -247.865483) (xy 346.61094 -247.819209) (xy 346.641466 -247.777193)
			(xy 346.678189 -247.74047) (xy 346.720205 -247.709944) (xy 346.766479 -247.686366) (xy 346.815872 -247.670318)
			(xy 346.867167 -247.662193) (xy 346.919101 -247.662193) (xy 346.970396 -247.670318) (xy 347.019789 -247.686366)
			(xy 347.066063 -247.709944) (xy 347.108079 -247.74047) (xy 347.144802 -247.777193) (xy 347.175328 -247.819209)
			(xy 347.198906 -247.865483) (xy 347.214954 -247.914876) (xy 347.223079 -247.966171) (xy 347.223588 -247.992138)
			(xy 347.223079 -248.018105) (xy 347.502735 -248.018105) (xy 347.502735 -247.966171) (xy 347.51086 -247.914876)
			(xy 347.526908 -247.865483) (xy 347.550486 -247.819209) (xy 347.581012 -247.777193) (xy 347.617735 -247.74047)
			(xy 347.659751 -247.709944) (xy 347.706025 -247.686366) (xy 347.755418 -247.670318) (xy 347.806713 -247.662193)
			(xy 347.858647 -247.662193) (xy 347.909942 -247.670318) (xy 347.959335 -247.686366) (xy 348.005609 -247.709944)
			(xy 348.047625 -247.74047) (xy 348.084348 -247.777193) (xy 348.114874 -247.819209) (xy 348.138452 -247.865483)
			(xy 348.1545 -247.914876) (xy 348.162625 -247.966171) (xy 348.163134 -247.992138) (xy 348.162625 -248.018105)
			(xy 348.442535 -248.018105) (xy 348.442535 -247.966171) (xy 348.45066 -247.914876) (xy 348.466708 -247.865483)
			(xy 348.490286 -247.819209) (xy 348.520812 -247.777193) (xy 348.557535 -247.74047) (xy 348.599551 -247.709944)
			(xy 348.645825 -247.686366) (xy 348.695218 -247.670318) (xy 348.746513 -247.662193) (xy 348.798447 -247.662193)
			(xy 348.849742 -247.670318) (xy 348.899135 -247.686366) (xy 348.945409 -247.709944) (xy 348.987425 -247.74047)
			(xy 349.024148 -247.777193) (xy 349.054674 -247.819209) (xy 349.078252 -247.865483) (xy 349.0943 -247.914876)
			(xy 349.102425 -247.966171) (xy 349.102934 -247.992138) (xy 349.102425 -248.018105) (xy 349.382335 -248.018105)
			(xy 349.382335 -247.966171) (xy 349.39046 -247.914876) (xy 349.406508 -247.865483) (xy 349.430086 -247.819209)
			(xy 349.460612 -247.777193) (xy 349.497335 -247.74047) (xy 349.539351 -247.709944) (xy 349.585625 -247.686366)
			(xy 349.635018 -247.670318) (xy 349.686313 -247.662193) (xy 349.738247 -247.662193) (xy 349.789542 -247.670318)
			(xy 349.838935 -247.686366) (xy 349.885209 -247.709944) (xy 349.927225 -247.74047) (xy 349.963948 -247.777193)
			(xy 349.994474 -247.819209) (xy 350.018052 -247.865483) (xy 350.0341 -247.914876) (xy 350.042225 -247.966171)
			(xy 350.042734 -247.992138) (xy 350.042225 -248.018105) (xy 356.897941 -248.018105) (xy 356.897941 -247.966171)
			(xy 356.906066 -247.914876) (xy 356.922114 -247.865483) (xy 356.945692 -247.819209) (xy 356.976218 -247.777193)
			(xy 357.012941 -247.74047) (xy 357.054957 -247.709944) (xy 357.101231 -247.686366) (xy 357.150624 -247.670318)
			(xy 357.201919 -247.662193) (xy 357.253853 -247.662193) (xy 357.305148 -247.670318) (xy 357.354541 -247.686366)
			(xy 357.400815 -247.709944) (xy 357.442831 -247.74047) (xy 357.479554 -247.777193) (xy 357.51008 -247.819209)
			(xy 357.533658 -247.865483) (xy 357.549706 -247.914876) (xy 357.557831 -247.966171) (xy 357.55834 -247.992138)
			(xy 357.557831 -248.018105) (xy 357.840789 -248.018105) (xy 357.840789 -247.966171) (xy 357.848914 -247.914876)
			(xy 357.864962 -247.865483) (xy 357.88854 -247.819209) (xy 357.919066 -247.777193) (xy 357.955789 -247.74047)
			(xy 357.997805 -247.709944) (xy 358.044079 -247.686366) (xy 358.093472 -247.670318) (xy 358.144767 -247.662193)
			(xy 358.196701 -247.662193) (xy 358.247996 -247.670318) (xy 358.297389 -247.686366) (xy 358.343663 -247.709944)
			(xy 358.385679 -247.74047) (xy 358.422402 -247.777193) (xy 358.452928 -247.819209) (xy 358.476506 -247.865483)
			(xy 358.492554 -247.914876) (xy 358.500679 -247.966171) (xy 358.501188 -247.992138) (xy 358.500679 -248.018105)
			(xy 358.780589 -248.018105) (xy 358.780589 -247.966171) (xy 358.788714 -247.914876) (xy 358.804762 -247.865483)
			(xy 358.82834 -247.819209) (xy 358.858866 -247.777193) (xy 358.895589 -247.74047) (xy 358.937605 -247.709944)
			(xy 358.983879 -247.686366) (xy 359.033272 -247.670318) (xy 359.084567 -247.662193) (xy 359.136501 -247.662193)
			(xy 359.187796 -247.670318) (xy 359.237189 -247.686366) (xy 359.283463 -247.709944) (xy 359.325479 -247.74047)
			(xy 359.362202 -247.777193) (xy 359.392728 -247.819209) (xy 359.416306 -247.865483) (xy 359.432354 -247.914876)
			(xy 359.440479 -247.966171) (xy 359.440988 -247.992138) (xy 359.440479 -248.018105) (xy 359.720389 -248.018105)
			(xy 359.720389 -247.966171) (xy 359.728514 -247.914876) (xy 359.744562 -247.865483) (xy 359.76814 -247.819209)
			(xy 359.798666 -247.777193) (xy 359.835389 -247.74047) (xy 359.877405 -247.709944) (xy 359.923679 -247.686366)
			(xy 359.973072 -247.670318) (xy 360.024367 -247.662193) (xy 360.076301 -247.662193) (xy 360.127596 -247.670318)
			(xy 360.176989 -247.686366) (xy 360.223263 -247.709944) (xy 360.265279 -247.74047) (xy 360.302002 -247.777193)
			(xy 360.332528 -247.819209) (xy 360.356106 -247.865483) (xy 360.372154 -247.914876) (xy 360.380279 -247.966171)
			(xy 360.380788 -247.992138) (xy 360.380279 -248.018105) (xy 360.659935 -248.018105) (xy 360.659935 -247.966171)
			(xy 360.66806 -247.914876) (xy 360.684108 -247.865483) (xy 360.707686 -247.819209) (xy 360.738212 -247.777193)
			(xy 360.774935 -247.74047) (xy 360.816951 -247.709944) (xy 360.863225 -247.686366) (xy 360.912618 -247.670318)
			(xy 360.963913 -247.662193) (xy 361.015847 -247.662193) (xy 361.067142 -247.670318) (xy 361.116535 -247.686366)
			(xy 361.162809 -247.709944) (xy 361.204825 -247.74047) (xy 361.241548 -247.777193) (xy 361.272074 -247.819209)
			(xy 361.295652 -247.865483) (xy 361.3117 -247.914876) (xy 361.319825 -247.966171) (xy 361.320334 -247.992138)
			(xy 361.319825 -248.018105) (xy 361.599989 -248.018105) (xy 361.599989 -247.966171) (xy 361.608114 -247.914876)
			(xy 361.624162 -247.865483) (xy 361.64774 -247.819209) (xy 361.678266 -247.777193) (xy 361.714989 -247.74047)
			(xy 361.757005 -247.709944) (xy 361.803279 -247.686366) (xy 361.852672 -247.670318) (xy 361.903967 -247.662193)
			(xy 361.955901 -247.662193) (xy 362.007196 -247.670318) (xy 362.056589 -247.686366) (xy 362.102863 -247.709944)
			(xy 362.144879 -247.74047) (xy 362.181602 -247.777193) (xy 362.212128 -247.819209) (xy 362.235706 -247.865483)
			(xy 362.251754 -247.914876) (xy 362.259879 -247.966171) (xy 362.260388 -247.992138) (xy 362.259879 -248.018105)
			(xy 362.251754 -248.0694) (xy 362.235706 -248.118793) (xy 362.212128 -248.165067) (xy 362.181602 -248.207083)
			(xy 362.144879 -248.243806) (xy 362.102863 -248.274332) (xy 362.056589 -248.29791) (xy 362.007196 -248.313958)
			(xy 361.955901 -248.322083) (xy 361.903967 -248.322083) (xy 361.852672 -248.313958) (xy 361.803279 -248.29791)
			(xy 361.757005 -248.274332) (xy 361.714989 -248.243806) (xy 361.678266 -248.207083) (xy 361.64774 -248.165067)
			(xy 361.624162 -248.118793) (xy 361.608114 -248.0694) (xy 361.599989 -248.018105) (xy 361.319825 -248.018105)
			(xy 361.3117 -248.0694) (xy 361.295652 -248.118793) (xy 361.272074 -248.165067) (xy 361.241548 -248.207083)
			(xy 361.204825 -248.243806) (xy 361.162809 -248.274332) (xy 361.116535 -248.29791) (xy 361.067142 -248.313958)
			(xy 361.015847 -248.322083) (xy 360.963913 -248.322083) (xy 360.912618 -248.313958) (xy 360.863225 -248.29791)
			(xy 360.816951 -248.274332) (xy 360.774935 -248.243806) (xy 360.738212 -248.207083) (xy 360.707686 -248.165067)
			(xy 360.684108 -248.118793) (xy 360.66806 -248.0694) (xy 360.659935 -248.018105) (xy 360.380279 -248.018105)
			(xy 360.372154 -248.0694) (xy 360.356106 -248.118793) (xy 360.332528 -248.165067) (xy 360.302002 -248.207083)
			(xy 360.265279 -248.243806) (xy 360.223263 -248.274332) (xy 360.176989 -248.29791) (xy 360.127596 -248.313958)
			(xy 360.076301 -248.322083) (xy 360.024367 -248.322083) (xy 359.973072 -248.313958) (xy 359.923679 -248.29791)
			(xy 359.877405 -248.274332) (xy 359.835389 -248.243806) (xy 359.798666 -248.207083) (xy 359.76814 -248.165067)
			(xy 359.744562 -248.118793) (xy 359.728514 -248.0694) (xy 359.720389 -248.018105) (xy 359.440479 -248.018105)
			(xy 359.432354 -248.0694) (xy 359.416306 -248.118793) (xy 359.392728 -248.165067) (xy 359.362202 -248.207083)
			(xy 359.325479 -248.243806) (xy 359.283463 -248.274332) (xy 359.237189 -248.29791) (xy 359.187796 -248.313958)
			(xy 359.136501 -248.322083) (xy 359.084567 -248.322083) (xy 359.033272 -248.313958) (xy 358.983879 -248.29791)
			(xy 358.937605 -248.274332) (xy 358.895589 -248.243806) (xy 358.858866 -248.207083) (xy 358.82834 -248.165067)
			(xy 358.804762 -248.118793) (xy 358.788714 -248.0694) (xy 358.780589 -248.018105) (xy 358.500679 -248.018105)
			(xy 358.492554 -248.0694) (xy 358.476506 -248.118793) (xy 358.452928 -248.165067) (xy 358.422402 -248.207083)
			(xy 358.385679 -248.243806) (xy 358.343663 -248.274332) (xy 358.297389 -248.29791) (xy 358.247996 -248.313958)
			(xy 358.196701 -248.322083) (xy 358.144767 -248.322083) (xy 358.093472 -248.313958) (xy 358.044079 -248.29791)
			(xy 357.997805 -248.274332) (xy 357.955789 -248.243806) (xy 357.919066 -248.207083) (xy 357.88854 -248.165067)
			(xy 357.864962 -248.118793) (xy 357.848914 -248.0694) (xy 357.840789 -248.018105) (xy 357.557831 -248.018105)
			(xy 357.549706 -248.0694) (xy 357.533658 -248.118793) (xy 357.51008 -248.165067) (xy 357.479554 -248.207083)
			(xy 357.442831 -248.243806) (xy 357.400815 -248.274332) (xy 357.354541 -248.29791) (xy 357.305148 -248.313958)
			(xy 357.253853 -248.322083) (xy 357.201919 -248.322083) (xy 357.150624 -248.313958) (xy 357.101231 -248.29791)
			(xy 357.054957 -248.274332) (xy 357.012941 -248.243806) (xy 356.976218 -248.207083) (xy 356.945692 -248.165067)
			(xy 356.922114 -248.118793) (xy 356.906066 -248.0694) (xy 356.897941 -248.018105) (xy 350.042225 -248.018105)
			(xy 350.0341 -248.0694) (xy 350.018052 -248.118793) (xy 349.994474 -248.165067) (xy 349.963948 -248.207083)
			(xy 349.927225 -248.243806) (xy 349.885209 -248.274332) (xy 349.838935 -248.29791) (xy 349.789542 -248.313958)
			(xy 349.738247 -248.322083) (xy 349.686313 -248.322083) (xy 349.635018 -248.313958) (xy 349.585625 -248.29791)
			(xy 349.539351 -248.274332) (xy 349.497335 -248.243806) (xy 349.460612 -248.207083) (xy 349.430086 -248.165067)
			(xy 349.406508 -248.118793) (xy 349.39046 -248.0694) (xy 349.382335 -248.018105) (xy 349.102425 -248.018105)
			(xy 349.0943 -248.0694) (xy 349.078252 -248.118793) (xy 349.054674 -248.165067) (xy 349.024148 -248.207083)
			(xy 348.987425 -248.243806) (xy 348.945409 -248.274332) (xy 348.899135 -248.29791) (xy 348.849742 -248.313958)
			(xy 348.798447 -248.322083) (xy 348.746513 -248.322083) (xy 348.695218 -248.313958) (xy 348.645825 -248.29791)
			(xy 348.599551 -248.274332) (xy 348.557535 -248.243806) (xy 348.520812 -248.207083) (xy 348.490286 -248.165067)
			(xy 348.466708 -248.118793) (xy 348.45066 -248.0694) (xy 348.442535 -248.018105) (xy 348.162625 -248.018105)
			(xy 348.1545 -248.0694) (xy 348.138452 -248.118793) (xy 348.114874 -248.165067) (xy 348.084348 -248.207083)
			(xy 348.047625 -248.243806) (xy 348.005609 -248.274332) (xy 347.959335 -248.29791) (xy 347.909942 -248.313958)
			(xy 347.858647 -248.322083) (xy 347.806713 -248.322083) (xy 347.755418 -248.313958) (xy 347.706025 -248.29791)
			(xy 347.659751 -248.274332) (xy 347.617735 -248.243806) (xy 347.581012 -248.207083) (xy 347.550486 -248.165067)
			(xy 347.526908 -248.118793) (xy 347.51086 -248.0694) (xy 347.502735 -248.018105) (xy 347.223079 -248.018105)
			(xy 347.214954 -248.0694) (xy 347.198906 -248.118793) (xy 347.175328 -248.165067) (xy 347.144802 -248.207083)
			(xy 347.108079 -248.243806) (xy 347.066063 -248.274332) (xy 347.019789 -248.29791) (xy 346.970396 -248.313958)
			(xy 346.919101 -248.322083) (xy 346.867167 -248.322083) (xy 346.815872 -248.313958) (xy 346.766479 -248.29791)
			(xy 346.720205 -248.274332) (xy 346.678189 -248.243806) (xy 346.641466 -248.207083) (xy 346.61094 -248.165067)
			(xy 346.587362 -248.118793) (xy 346.571314 -248.0694) (xy 346.563189 -248.018105) (xy 346.283279 -248.018105)
			(xy 346.275154 -248.0694) (xy 346.259106 -248.118793) (xy 346.235528 -248.165067) (xy 346.205002 -248.207083)
			(xy 346.168279 -248.243806) (xy 346.126263 -248.274332) (xy 346.079989 -248.29791) (xy 346.030596 -248.313958)
			(xy 345.979301 -248.322083) (xy 345.927367 -248.322083) (xy 345.876072 -248.313958) (xy 345.826679 -248.29791)
			(xy 345.780405 -248.274332) (xy 345.738389 -248.243806) (xy 345.701666 -248.207083) (xy 345.67114 -248.165067)
			(xy 345.647562 -248.118793) (xy 345.631514 -248.0694) (xy 345.623389 -248.018105) (xy 345.343225 -248.018105)
			(xy 345.3351 -248.0694) (xy 345.319052 -248.118793) (xy 345.295474 -248.165067) (xy 345.264948 -248.207083)
			(xy 345.228225 -248.243806) (xy 345.186209 -248.274332) (xy 345.139935 -248.29791) (xy 345.090542 -248.313958)
			(xy 345.039247 -248.322083) (xy 344.987313 -248.322083) (xy 344.936018 -248.313958) (xy 344.886625 -248.29791)
			(xy 344.840351 -248.274332) (xy 344.798335 -248.243806) (xy 344.761612 -248.207083) (xy 344.731086 -248.165067)
			(xy 344.707508 -248.118793) (xy 344.69146 -248.0694) (xy 344.683335 -248.018105) (xy 344.403679 -248.018105)
			(xy 344.395554 -248.0694) (xy 344.379506 -248.118793) (xy 344.355928 -248.165067) (xy 344.325402 -248.207083)
			(xy 344.288679 -248.243806) (xy 344.246663 -248.274332) (xy 344.200389 -248.29791) (xy 344.150996 -248.313958)
			(xy 344.099701 -248.322083) (xy 344.047767 -248.322083) (xy 343.996472 -248.313958) (xy 343.947079 -248.29791)
			(xy 343.900805 -248.274332) (xy 343.858789 -248.243806) (xy 343.822066 -248.207083) (xy 343.79154 -248.165067)
			(xy 343.767962 -248.118793) (xy 343.751914 -248.0694) (xy 343.743789 -248.018105) (xy 343.463607 -248.018105)
			(xy 343.457474 -248.061446) (xy 343.444574 -248.106133) (xy 343.435432 -248.12752) (xy 343.435432 -248.127774)
			(xy 343.431683 -248.137181) (xy 343.431232 -248.157409) (xy 343.438745 -248.176195) (xy 343.445592 -248.183654)
			(xy 343.807796 -248.545858) (xy 343.810082 -248.547636) (xy 343.82916 -248.56341) (xy 343.86283 -248.599697)
			(xy 343.890714 -248.640599) (xy 343.912186 -248.685201) (xy 343.926768 -248.732506) (xy 343.934133 -248.781457)
			(xy 343.934542 -248.806208) (xy 343.934025 -248.832175) (xy 344.213689 -248.832175) (xy 344.213689 -248.780241)
			(xy 344.221814 -248.728946) (xy 344.237862 -248.679553) (xy 344.26144 -248.633279) (xy 344.291966 -248.591263)
			(xy 344.328689 -248.55454) (xy 344.370705 -248.524014) (xy 344.416979 -248.500436) (xy 344.466372 -248.484388)
			(xy 344.517667 -248.476263) (xy 344.569601 -248.476263) (xy 344.620896 -248.484388) (xy 344.670289 -248.500436)
			(xy 344.716563 -248.524014) (xy 344.758579 -248.55454) (xy 344.795302 -248.591263) (xy 344.825828 -248.633279)
			(xy 344.849406 -248.679553) (xy 344.865454 -248.728946) (xy 344.873579 -248.780241) (xy 344.874088 -248.806208)
			(xy 344.873579 -248.832175) (xy 345.153489 -248.832175) (xy 345.153489 -248.780241) (xy 345.161614 -248.728946)
			(xy 345.177662 -248.679553) (xy 345.20124 -248.633279) (xy 345.231766 -248.591263) (xy 345.268489 -248.55454)
			(xy 345.310505 -248.524014) (xy 345.356779 -248.500436) (xy 345.406172 -248.484388) (xy 345.457467 -248.476263)
			(xy 345.509401 -248.476263) (xy 345.560696 -248.484388) (xy 345.610089 -248.500436) (xy 345.656363 -248.524014)
			(xy 345.698379 -248.55454) (xy 345.735102 -248.591263) (xy 345.765628 -248.633279) (xy 345.789206 -248.679553)
			(xy 345.805254 -248.728946) (xy 345.813379 -248.780241) (xy 345.813888 -248.806208) (xy 345.813379 -248.832175)
			(xy 346.093289 -248.832175) (xy 346.093289 -248.780241) (xy 346.101414 -248.728946) (xy 346.117462 -248.679553)
			(xy 346.14104 -248.633279) (xy 346.171566 -248.591263) (xy 346.208289 -248.55454) (xy 346.250305 -248.524014)
			(xy 346.296579 -248.500436) (xy 346.345972 -248.484388) (xy 346.397267 -248.476263) (xy 346.449201 -248.476263)
			(xy 346.500496 -248.484388) (xy 346.549889 -248.500436) (xy 346.596163 -248.524014) (xy 346.638179 -248.55454)
			(xy 346.674902 -248.591263) (xy 346.705428 -248.633279) (xy 346.729006 -248.679553) (xy 346.745054 -248.728946)
			(xy 346.753179 -248.780241) (xy 346.753688 -248.806208) (xy 346.753179 -248.832175) (xy 347.033089 -248.832175)
			(xy 347.033089 -248.780241) (xy 347.041214 -248.728946) (xy 347.057262 -248.679553) (xy 347.08084 -248.633279)
			(xy 347.111366 -248.591263) (xy 347.148089 -248.55454) (xy 347.190105 -248.524014) (xy 347.236379 -248.500436)
			(xy 347.285772 -248.484388) (xy 347.337067 -248.476263) (xy 347.389001 -248.476263) (xy 347.440296 -248.484388)
			(xy 347.489689 -248.500436) (xy 347.535963 -248.524014) (xy 347.577979 -248.55454) (xy 347.614702 -248.591263)
			(xy 347.645228 -248.633279) (xy 347.668806 -248.679553) (xy 347.684854 -248.728946) (xy 347.692979 -248.780241)
			(xy 347.693488 -248.806208) (xy 347.692979 -248.832175) (xy 347.972889 -248.832175) (xy 347.972889 -248.780241)
			(xy 347.981014 -248.728946) (xy 347.997062 -248.679553) (xy 348.02064 -248.633279) (xy 348.051166 -248.591263)
			(xy 348.087889 -248.55454) (xy 348.129905 -248.524014) (xy 348.176179 -248.500436) (xy 348.225572 -248.484388)
			(xy 348.276867 -248.476263) (xy 348.328801 -248.476263) (xy 348.380096 -248.484388) (xy 348.429489 -248.500436)
			(xy 348.475763 -248.524014) (xy 348.517779 -248.55454) (xy 348.554502 -248.591263) (xy 348.585028 -248.633279)
			(xy 348.608606 -248.679553) (xy 348.624654 -248.728946) (xy 348.632779 -248.780241) (xy 348.633288 -248.806208)
			(xy 348.632779 -248.832175) (xy 348.912435 -248.832175) (xy 348.912435 -248.780241) (xy 348.92056 -248.728946)
			(xy 348.936608 -248.679553) (xy 348.960186 -248.633279) (xy 348.990712 -248.591263) (xy 349.027435 -248.55454)
			(xy 349.069451 -248.524014) (xy 349.115725 -248.500436) (xy 349.165118 -248.484388) (xy 349.216413 -248.476263)
			(xy 349.268347 -248.476263) (xy 349.319642 -248.484388) (xy 349.369035 -248.500436) (xy 349.415309 -248.524014)
			(xy 349.457325 -248.55454) (xy 349.494048 -248.591263) (xy 349.524574 -248.633279) (xy 349.548152 -248.679553)
			(xy 349.5642 -248.728946) (xy 349.572325 -248.780241) (xy 349.572834 -248.806208) (xy 349.572325 -248.83217)
			(xy 349.852437 -248.83217) (xy 349.852437 -248.78023) (xy 349.860563 -248.728928) (xy 349.876614 -248.67953)
			(xy 349.900196 -248.633251) (xy 349.930728 -248.591232) (xy 349.967458 -248.554506) (xy 350.00948 -248.523979)
			(xy 350.055762 -248.500401) (xy 350.105162 -248.484355) (xy 350.156464 -248.476234) (xy 350.182434 -248.475754)
			(xy 350.2122 -248.4764) (xy 350.270774 -248.487042) (xy 350.326498 -248.507994) (xy 350.35236 -248.522744)
			(xy 350.363988 -248.529221) (xy 350.389565 -248.536551) (xy 350.416168 -248.537007) (xy 350.441981 -248.530559)
			(xy 350.465244 -248.517647) (xy 350.48437 -248.499151) (xy 350.491552 -248.487946) (xy 350.504446 -248.467324)
			(xy 350.53532 -248.429747) (xy 350.571371 -248.397105) (xy 350.61182 -248.370104) (xy 350.655792 -248.349327)
			(xy 350.702336 -248.335224) (xy 350.750445 -248.3281) (xy 350.774762 -248.327672) (xy 350.800732 -248.328164)
			(xy 350.852032 -248.336284) (xy 350.90143 -248.35233) (xy 350.947709 -248.375908) (xy 350.98973 -248.406435)
			(xy 351.026457 -248.443161) (xy 351.056986 -248.48518) (xy 351.080565 -248.531459) (xy 351.096613 -248.580856)
			(xy 351.104735 -248.632156) (xy 351.105216 -248.658126) (xy 351.105216 -248.65838) (xy 351.104748 -248.682906)
			(xy 351.097488 -248.731418) (xy 351.083141 -248.778325) (xy 351.062019 -248.822597) (xy 351.034588 -248.863262)
			(xy 351.018348 -248.881646) (xy 351.008517 -248.893114) (xy 350.995503 -248.920358) (xy 350.991039 -248.950219)
			(xy 350.995515 -248.980078) (xy 351.007474 -249.00509) (xy 356.04323 -249.00509) (xy 356.04323 -249.004836)
			(xy 356.043722 -248.980311) (xy 356.050978 -248.931801) (xy 356.065321 -248.884895) (xy 356.086436 -248.840623)
			(xy 356.113861 -248.799956) (xy 356.130098 -248.78157) (xy 356.139909 -248.770088) (xy 356.152919 -248.742848)
			(xy 356.157384 -248.712993) (xy 356.152915 -248.683138) (xy 356.139901 -248.6559) (xy 356.130098 -248.64441)
			(xy 356.113838 -248.626041) (xy 356.086394 -248.585378) (xy 356.065267 -248.541104) (xy 356.050922 -248.494191)
			(xy 356.043674 -248.445673) (xy 356.04323 -248.421144) (xy 356.04323 -248.42089) (xy 356.043739 -248.394923)
			(xy 356.051864 -248.343628) (xy 356.067912 -248.294235) (xy 356.09149 -248.247961) (xy 356.122016 -248.205945)
			(xy 356.158739 -248.169222) (xy 356.200755 -248.138696) (xy 356.247029 -248.115118) (xy 356.296422 -248.09907)
			(xy 356.347717 -248.090945) (xy 356.399651 -248.090945) (xy 356.450946 -248.09907) (xy 356.500339 -248.115118)
			(xy 356.546613 -248.138696) (xy 356.588629 -248.169222) (xy 356.625352 -248.205945) (xy 356.655878 -248.247961)
			(xy 356.679456 -248.294235) (xy 356.695504 -248.343628) (xy 356.703629 -248.394923) (xy 356.704138 -248.42089)
			(xy 356.704138 -248.421144) (xy 356.703703 -248.445671) (xy 356.696434 -248.494184) (xy 356.682078 -248.541091)
			(xy 356.66095 -248.585362) (xy 356.633513 -248.626026) (xy 356.61727 -248.64441) (xy 356.607472 -248.655905)
			(xy 356.594452 -248.683139) (xy 356.589979 -248.712993) (xy 356.594447 -248.742847) (xy 356.607464 -248.770083)
			(xy 356.61727 -248.78157) (xy 356.633516 -248.799952) (xy 356.655269 -248.832175) (xy 357.370635 -248.832175)
			(xy 357.370635 -248.780241) (xy 357.37876 -248.728946) (xy 357.394808 -248.679553) (xy 357.418386 -248.633279)
			(xy 357.448912 -248.591263) (xy 357.485635 -248.55454) (xy 357.527651 -248.524014) (xy 357.573925 -248.500436)
			(xy 357.623318 -248.484388) (xy 357.674613 -248.476263) (xy 357.726547 -248.476263) (xy 357.777842 -248.484388)
			(xy 357.827235 -248.500436) (xy 357.873509 -248.524014) (xy 357.915525 -248.55454) (xy 357.952248 -248.591263)
			(xy 357.982774 -248.633279) (xy 358.006352 -248.679553) (xy 358.0224 -248.728946) (xy 358.030525 -248.780241)
			(xy 358.031034 -248.806208) (xy 358.030525 -248.832175) (xy 358.310689 -248.832175) (xy 358.310689 -248.780241)
			(xy 358.318814 -248.728946) (xy 358.334862 -248.679553) (xy 358.35844 -248.633279) (xy 358.388966 -248.591263)
			(xy 358.425689 -248.55454) (xy 358.467705 -248.524014) (xy 358.513979 -248.500436) (xy 358.563372 -248.484388)
			(xy 358.614667 -248.476263) (xy 358.666601 -248.476263) (xy 358.717896 -248.484388) (xy 358.767289 -248.500436)
			(xy 358.813563 -248.524014) (xy 358.855579 -248.55454) (xy 358.892302 -248.591263) (xy 358.922828 -248.633279)
			(xy 358.946406 -248.679553) (xy 358.962454 -248.728946) (xy 358.970579 -248.780241) (xy 358.971088 -248.806208)
			(xy 358.970579 -248.832175) (xy 359.250235 -248.832175) (xy 359.250235 -248.780241) (xy 359.25836 -248.728946)
			(xy 359.274408 -248.679553) (xy 359.297986 -248.633279) (xy 359.328512 -248.591263) (xy 359.365235 -248.55454)
			(xy 359.407251 -248.524014) (xy 359.453525 -248.500436) (xy 359.502918 -248.484388) (xy 359.554213 -248.476263)
			(xy 359.606147 -248.476263) (xy 359.657442 -248.484388) (xy 359.706835 -248.500436) (xy 359.753109 -248.524014)
			(xy 359.795125 -248.55454) (xy 359.831848 -248.591263) (xy 359.862374 -248.633279) (xy 359.885952 -248.679553)
			(xy 359.902 -248.728946) (xy 359.910125 -248.780241) (xy 359.910634 -248.806208) (xy 359.910125 -248.832175)
			(xy 360.190035 -248.832175) (xy 360.190035 -248.780241) (xy 360.19816 -248.728946) (xy 360.214208 -248.679553)
			(xy 360.237786 -248.633279) (xy 360.268312 -248.591263) (xy 360.305035 -248.55454) (xy 360.347051 -248.524014)
			(xy 360.393325 -248.500436) (xy 360.442718 -248.484388) (xy 360.494013 -248.476263) (xy 360.545947 -248.476263)
			(xy 360.597242 -248.484388) (xy 360.646635 -248.500436) (xy 360.692909 -248.524014) (xy 360.734925 -248.55454)
			(xy 360.771648 -248.591263) (xy 360.802174 -248.633279) (xy 360.825752 -248.679553) (xy 360.8418 -248.728946)
			(xy 360.849925 -248.780241) (xy 360.850434 -248.806208) (xy 360.849925 -248.832175) (xy 361.130089 -248.832175)
			(xy 361.130089 -248.780241) (xy 361.138214 -248.728946) (xy 361.154262 -248.679553) (xy 361.17784 -248.633279)
			(xy 361.208366 -248.591263) (xy 361.245089 -248.55454) (xy 361.287105 -248.524014) (xy 361.333379 -248.500436)
			(xy 361.382772 -248.484388) (xy 361.434067 -248.476263) (xy 361.486001 -248.476263) (xy 361.537296 -248.484388)
			(xy 361.586689 -248.500436) (xy 361.632963 -248.524014) (xy 361.674979 -248.55454) (xy 361.711702 -248.591263)
			(xy 361.742228 -248.633279) (xy 361.765806 -248.679553) (xy 361.781854 -248.728946) (xy 361.789979 -248.780241)
			(xy 361.790488 -248.806208) (xy 361.789979 -248.832175) (xy 362.069889 -248.832175) (xy 362.069889 -248.780241)
			(xy 362.078014 -248.728946) (xy 362.094062 -248.679553) (xy 362.11764 -248.633279) (xy 362.148166 -248.591263)
			(xy 362.184889 -248.55454) (xy 362.226905 -248.524014) (xy 362.273179 -248.500436) (xy 362.322572 -248.484388)
			(xy 362.373867 -248.476263) (xy 362.425801 -248.476263) (xy 362.477096 -248.484388) (xy 362.526489 -248.500436)
			(xy 362.572763 -248.524014) (xy 362.614779 -248.55454) (xy 362.651502 -248.591263) (xy 362.682028 -248.633279)
			(xy 362.705606 -248.679553) (xy 362.721654 -248.728946) (xy 362.729779 -248.780241) (xy 362.730288 -248.806208)
			(xy 362.729779 -248.832175) (xy 362.721654 -248.88347) (xy 362.705606 -248.932863) (xy 362.682028 -248.979137)
			(xy 362.651502 -249.021153) (xy 362.614779 -249.057876) (xy 362.572763 -249.088402) (xy 362.526489 -249.11198)
			(xy 362.477096 -249.128028) (xy 362.425801 -249.136153) (xy 362.373867 -249.136153) (xy 362.322572 -249.128028)
			(xy 362.273179 -249.11198) (xy 362.226905 -249.088402) (xy 362.184889 -249.057876) (xy 362.148166 -249.021153)
			(xy 362.11764 -248.979137) (xy 362.094062 -248.932863) (xy 362.078014 -248.88347) (xy 362.069889 -248.832175)
			(xy 361.789979 -248.832175) (xy 361.781854 -248.88347) (xy 361.765806 -248.932863) (xy 361.742228 -248.979137)
			(xy 361.711702 -249.021153) (xy 361.674979 -249.057876) (xy 361.632963 -249.088402) (xy 361.586689 -249.11198)
			(xy 361.537296 -249.128028) (xy 361.486001 -249.136153) (xy 361.434067 -249.136153) (xy 361.382772 -249.128028)
			(xy 361.333379 -249.11198) (xy 361.287105 -249.088402) (xy 361.245089 -249.057876) (xy 361.208366 -249.021153)
			(xy 361.17784 -248.979137) (xy 361.154262 -248.932863) (xy 361.138214 -248.88347) (xy 361.130089 -248.832175)
			(xy 360.849925 -248.832175) (xy 360.8418 -248.88347) (xy 360.825752 -248.932863) (xy 360.802174 -248.979137)
			(xy 360.771648 -249.021153) (xy 360.734925 -249.057876) (xy 360.692909 -249.088402) (xy 360.646635 -249.11198)
			(xy 360.597242 -249.128028) (xy 360.545947 -249.136153) (xy 360.494013 -249.136153) (xy 360.442718 -249.128028)
			(xy 360.393325 -249.11198) (xy 360.347051 -249.088402) (xy 360.305035 -249.057876) (xy 360.268312 -249.021153)
			(xy 360.237786 -248.979137) (xy 360.214208 -248.932863) (xy 360.19816 -248.88347) (xy 360.190035 -248.832175)
			(xy 359.910125 -248.832175) (xy 359.902 -248.88347) (xy 359.885952 -248.932863) (xy 359.862374 -248.979137)
			(xy 359.831848 -249.021153) (xy 359.795125 -249.057876) (xy 359.753109 -249.088402) (xy 359.706835 -249.11198)
			(xy 359.657442 -249.128028) (xy 359.606147 -249.136153) (xy 359.554213 -249.136153) (xy 359.502918 -249.128028)
			(xy 359.453525 -249.11198) (xy 359.407251 -249.088402) (xy 359.365235 -249.057876) (xy 359.328512 -249.021153)
			(xy 359.297986 -248.979137) (xy 359.274408 -248.932863) (xy 359.25836 -248.88347) (xy 359.250235 -248.832175)
			(xy 358.970579 -248.832175) (xy 358.962454 -248.88347) (xy 358.946406 -248.932863) (xy 358.922828 -248.979137)
			(xy 358.892302 -249.021153) (xy 358.855579 -249.057876) (xy 358.813563 -249.088402) (xy 358.767289 -249.11198)
			(xy 358.717896 -249.128028) (xy 358.666601 -249.136153) (xy 358.614667 -249.136153) (xy 358.563372 -249.128028)
			(xy 358.513979 -249.11198) (xy 358.467705 -249.088402) (xy 358.425689 -249.057876) (xy 358.388966 -249.021153)
			(xy 358.35844 -248.979137) (xy 358.334862 -248.932863) (xy 358.318814 -248.88347) (xy 358.310689 -248.832175)
			(xy 358.030525 -248.832175) (xy 358.0224 -248.88347) (xy 358.006352 -248.932863) (xy 357.982774 -248.979137)
			(xy 357.952248 -249.021153) (xy 357.915525 -249.057876) (xy 357.873509 -249.088402) (xy 357.827235 -249.11198)
			(xy 357.777842 -249.128028) (xy 357.726547 -249.136153) (xy 357.674613 -249.136153) (xy 357.623318 -249.128028)
			(xy 357.573925 -249.11198) (xy 357.527651 -249.088402) (xy 357.485635 -249.057876) (xy 357.448912 -249.021153)
			(xy 357.418386 -248.979137) (xy 357.394808 -248.932863) (xy 357.37876 -248.88347) (xy 357.370635 -248.832175)
			(xy 356.655269 -248.832175) (xy 356.660963 -248.84061) (xy 356.682093 -248.884882) (xy 356.696441 -248.931792)
			(xy 356.703693 -248.980308) (xy 356.704138 -249.004836) (xy 356.704138 -249.00509) (xy 356.7037 -249.028463)
			(xy 356.69712 -249.074743) (xy 356.684078 -249.119632) (xy 356.664833 -249.162233) (xy 356.639771 -249.201692)
			(xy 356.62489 -249.21972) (xy 356.61924 -249.226832) (xy 362.992162 -249.226832) (xy 362.992162 -249.226578)
			(xy 362.99261 -249.202051) (xy 362.999876 -249.153539) (xy 363.014228 -249.106632) (xy 363.035354 -249.06236)
			(xy 363.062788 -249.021696) (xy 363.07903 -249.003312) (xy 363.088806 -248.9918) (xy 363.101829 -248.964572)
			(xy 363.106306 -248.934724) (xy 363.101843 -248.904873) (xy 363.088833 -248.877639) (xy 363.07903 -248.866152)
			(xy 363.062795 -248.847761) (xy 363.035346 -248.807105) (xy 363.014214 -248.762836) (xy 362.999863 -248.715928)
			(xy 362.992609 -248.667413) (xy 362.992162 -248.642886) (xy 362.992162 -248.642632) (xy 362.992671 -248.616665)
			(xy 363.000796 -248.56537) (xy 363.016844 -248.515977) (xy 363.040422 -248.469703) (xy 363.070948 -248.427687)
			(xy 363.107671 -248.390964) (xy 363.149687 -248.360438) (xy 363.195961 -248.33686) (xy 363.245354 -248.320812)
			(xy 363.296649 -248.312687) (xy 363.348583 -248.312687) (xy 363.399878 -248.320812) (xy 363.449271 -248.33686)
			(xy 363.482643 -248.353864) (xy 368.562681 -248.353864) (xy 368.562681 -248.301936) (xy 368.570804 -248.250646)
			(xy 368.586851 -248.201259) (xy 368.610425 -248.15499) (xy 368.640947 -248.112978) (xy 368.677665 -248.076258)
			(xy 368.719675 -248.045734) (xy 368.765943 -248.022157) (xy 368.815329 -248.006108) (xy 368.866618 -247.997983)
			(xy 368.892582 -247.997472) (xy 368.893344 -247.997472) (xy 368.918447 -247.997965) (xy 368.968067 -248.005614)
			(xy 368.99215 -248.012712) (xy 369.006047 -248.016483) (xy 369.034814 -248.017158) (xy 369.062627 -248.009776)
			(xy 369.087273 -247.994926) (xy 369.106796 -247.973786) (xy 369.119642 -247.948038) (xy 369.122706 -247.933972)
			(xy 369.127662 -247.908846) (xy 369.144363 -247.860432) (xy 369.16833 -247.815173) (xy 369.19899 -247.774151)
			(xy 369.235608 -247.738347) (xy 369.277309 -247.708618) (xy 369.323096 -247.685675) (xy 369.371873 -247.670066)
			(xy 369.422473 -247.662166) (xy 369.44808 -247.661684) (xy 369.474053 -247.662089) (xy 369.525361 -247.670213)
			(xy 369.574766 -247.686263) (xy 369.621051 -247.709844) (xy 369.663078 -247.740376) (xy 369.699811 -247.777107)
			(xy 369.730345 -247.819132) (xy 369.753929 -247.865416) (xy 369.769982 -247.91482) (xy 369.778109 -247.966127)
			(xy 369.778109 -248.018073) (xy 369.778104 -248.018105) (xy 370.057935 -248.018105) (xy 370.057935 -247.966171)
			(xy 370.06606 -247.914876) (xy 370.082108 -247.865483) (xy 370.105686 -247.819209) (xy 370.136212 -247.777193)
			(xy 370.172935 -247.74047) (xy 370.214951 -247.709944) (xy 370.261225 -247.686366) (xy 370.310618 -247.670318)
			(xy 370.361913 -247.662193) (xy 370.413847 -247.662193) (xy 370.465142 -247.670318) (xy 370.514535 -247.686366)
			(xy 370.560809 -247.709944) (xy 370.602825 -247.74047) (xy 370.639548 -247.777193) (xy 370.670074 -247.819209)
			(xy 370.693652 -247.865483) (xy 370.7097 -247.914876) (xy 370.717825 -247.966171) (xy 370.718334 -247.992138)
			(xy 370.717825 -248.018105) (xy 370.997735 -248.018105) (xy 370.997735 -247.966171) (xy 371.00586 -247.914876)
			(xy 371.021908 -247.865483) (xy 371.045486 -247.819209) (xy 371.076012 -247.777193) (xy 371.112735 -247.74047)
			(xy 371.154751 -247.709944) (xy 371.201025 -247.686366) (xy 371.250418 -247.670318) (xy 371.301713 -247.662193)
			(xy 371.353647 -247.662193) (xy 371.404942 -247.670318) (xy 371.454335 -247.686366) (xy 371.500609 -247.709944)
			(xy 371.542625 -247.74047) (xy 371.579348 -247.777193) (xy 371.609874 -247.819209) (xy 371.633452 -247.865483)
			(xy 371.6495 -247.914876) (xy 371.657625 -247.966171) (xy 371.658134 -247.992138) (xy 371.657625 -248.018105)
			(xy 371.937535 -248.018105) (xy 371.937535 -247.966171) (xy 371.94566 -247.914876) (xy 371.961708 -247.865483)
			(xy 371.985286 -247.819209) (xy 372.015812 -247.777193) (xy 372.052535 -247.74047) (xy 372.094551 -247.709944)
			(xy 372.140825 -247.686366) (xy 372.190218 -247.670318) (xy 372.241513 -247.662193) (xy 372.293447 -247.662193)
			(xy 372.344742 -247.670318) (xy 372.394135 -247.686366) (xy 372.440409 -247.709944) (xy 372.482425 -247.74047)
			(xy 372.519148 -247.777193) (xy 372.549674 -247.819209) (xy 372.573252 -247.865483) (xy 372.5893 -247.914876)
			(xy 372.597425 -247.966171) (xy 372.597934 -247.992138) (xy 372.597425 -248.018105) (xy 372.877335 -248.018105)
			(xy 372.877335 -247.966171) (xy 372.88546 -247.914876) (xy 372.901508 -247.865483) (xy 372.925086 -247.819209)
			(xy 372.955612 -247.777193) (xy 372.992335 -247.74047) (xy 373.034351 -247.709944) (xy 373.080625 -247.686366)
			(xy 373.130018 -247.670318) (xy 373.181313 -247.662193) (xy 373.233247 -247.662193) (xy 373.284542 -247.670318)
			(xy 373.333935 -247.686366) (xy 373.380209 -247.709944) (xy 373.422225 -247.74047) (xy 373.458948 -247.777193)
			(xy 373.489474 -247.819209) (xy 373.513052 -247.865483) (xy 373.5291 -247.914876) (xy 373.537225 -247.966171)
			(xy 373.537734 -247.992138) (xy 373.537225 -248.018105) (xy 373.817389 -248.018105) (xy 373.817389 -247.966171)
			(xy 373.825514 -247.914876) (xy 373.841562 -247.865483) (xy 373.86514 -247.819209) (xy 373.895666 -247.777193)
			(xy 373.932389 -247.74047) (xy 373.974405 -247.709944) (xy 374.020679 -247.686366) (xy 374.070072 -247.670318)
			(xy 374.121367 -247.662193) (xy 374.173301 -247.662193) (xy 374.224596 -247.670318) (xy 374.273989 -247.686366)
			(xy 374.320263 -247.709944) (xy 374.362279 -247.74047) (xy 374.399002 -247.777193) (xy 374.429528 -247.819209)
			(xy 374.453106 -247.865483) (xy 374.469154 -247.914876) (xy 374.477279 -247.966171) (xy 374.477788 -247.992138)
			(xy 374.477279 -248.018105) (xy 374.756935 -248.018105) (xy 374.756935 -247.966171) (xy 374.76506 -247.914876)
			(xy 374.781108 -247.865483) (xy 374.804686 -247.819209) (xy 374.835212 -247.777193) (xy 374.871935 -247.74047)
			(xy 374.913951 -247.709944) (xy 374.960225 -247.686366) (xy 375.009618 -247.670318) (xy 375.060913 -247.662193)
			(xy 375.112847 -247.662193) (xy 375.164142 -247.670318) (xy 375.213535 -247.686366) (xy 375.259809 -247.709944)
			(xy 375.301825 -247.74047) (xy 375.338548 -247.777193) (xy 375.369074 -247.819209) (xy 375.392652 -247.865483)
			(xy 375.4087 -247.914876) (xy 375.416825 -247.966171) (xy 375.417334 -247.992138) (xy 375.416825 -248.018105)
			(xy 375.696735 -248.018105) (xy 375.696735 -247.966171) (xy 375.70486 -247.914876) (xy 375.720908 -247.865483)
			(xy 375.744486 -247.819209) (xy 375.775012 -247.777193) (xy 375.811735 -247.74047) (xy 375.853751 -247.709944)
			(xy 375.900025 -247.686366) (xy 375.949418 -247.670318) (xy 376.000713 -247.662193) (xy 376.052647 -247.662193)
			(xy 376.103942 -247.670318) (xy 376.153335 -247.686366) (xy 376.199609 -247.709944) (xy 376.241625 -247.74047)
			(xy 376.278348 -247.777193) (xy 376.308874 -247.819209) (xy 376.332452 -247.865483) (xy 376.3485 -247.914876)
			(xy 376.356625 -247.966171) (xy 376.357134 -247.992138) (xy 376.356625 -248.018105) (xy 376.636535 -248.018105)
			(xy 376.636535 -247.966171) (xy 376.64466 -247.914876) (xy 376.660708 -247.865483) (xy 376.684286 -247.819209)
			(xy 376.714812 -247.777193) (xy 376.751535 -247.74047) (xy 376.793551 -247.709944) (xy 376.839825 -247.686366)
			(xy 376.889218 -247.670318) (xy 376.940513 -247.662193) (xy 376.992447 -247.662193) (xy 377.043742 -247.670318)
			(xy 377.093135 -247.686366) (xy 377.139409 -247.709944) (xy 377.181425 -247.74047) (xy 377.218148 -247.777193)
			(xy 377.248674 -247.819209) (xy 377.272252 -247.865483) (xy 377.2883 -247.914876) (xy 377.296425 -247.966171)
			(xy 377.296934 -247.992138) (xy 377.296425 -248.018105) (xy 377.576335 -248.018105) (xy 377.576335 -247.966171)
			(xy 377.58446 -247.914876) (xy 377.600508 -247.865483) (xy 377.624086 -247.819209) (xy 377.654612 -247.777193)
			(xy 377.691335 -247.74047) (xy 377.733351 -247.709944) (xy 377.779625 -247.686366) (xy 377.829018 -247.670318)
			(xy 377.880313 -247.662193) (xy 377.932247 -247.662193) (xy 377.983542 -247.670318) (xy 378.032935 -247.686366)
			(xy 378.079209 -247.709944) (xy 378.121225 -247.74047) (xy 378.157948 -247.777193) (xy 378.188474 -247.819209)
			(xy 378.212052 -247.865483) (xy 378.2281 -247.914876) (xy 378.236225 -247.966171) (xy 378.236734 -247.992138)
			(xy 378.236225 -248.018105) (xy 378.516389 -248.018105) (xy 378.516389 -247.966171) (xy 378.524514 -247.914876)
			(xy 378.540562 -247.865483) (xy 378.56414 -247.819209) (xy 378.594666 -247.777193) (xy 378.631389 -247.74047)
			(xy 378.673405 -247.709944) (xy 378.719679 -247.686366) (xy 378.769072 -247.670318) (xy 378.820367 -247.662193)
			(xy 378.872301 -247.662193) (xy 378.923596 -247.670318) (xy 378.972989 -247.686366) (xy 379.019263 -247.709944)
			(xy 379.061279 -247.74047) (xy 379.098002 -247.777193) (xy 379.128528 -247.819209) (xy 379.152106 -247.865483)
			(xy 379.168154 -247.914876) (xy 379.176279 -247.966171) (xy 379.176788 -247.992138) (xy 379.176279 -248.018105)
			(xy 379.168154 -248.0694) (xy 379.152106 -248.118793) (xy 379.128528 -248.165067) (xy 379.098002 -248.207083)
			(xy 379.061279 -248.243806) (xy 379.019263 -248.274332) (xy 378.972989 -248.29791) (xy 378.923596 -248.313958)
			(xy 378.872301 -248.322083) (xy 378.820367 -248.322083) (xy 378.769072 -248.313958) (xy 378.719679 -248.29791)
			(xy 378.673405 -248.274332) (xy 378.631389 -248.243806) (xy 378.594666 -248.207083) (xy 378.56414 -248.165067)
			(xy 378.540562 -248.118793) (xy 378.524514 -248.0694) (xy 378.516389 -248.018105) (xy 378.236225 -248.018105)
			(xy 378.2281 -248.0694) (xy 378.212052 -248.118793) (xy 378.188474 -248.165067) (xy 378.157948 -248.207083)
			(xy 378.121225 -248.243806) (xy 378.079209 -248.274332) (xy 378.032935 -248.29791) (xy 377.983542 -248.313958)
			(xy 377.932247 -248.322083) (xy 377.880313 -248.322083) (xy 377.829018 -248.313958) (xy 377.779625 -248.29791)
			(xy 377.733351 -248.274332) (xy 377.691335 -248.243806) (xy 377.654612 -248.207083) (xy 377.624086 -248.165067)
			(xy 377.600508 -248.118793) (xy 377.58446 -248.0694) (xy 377.576335 -248.018105) (xy 377.296425 -248.018105)
			(xy 377.2883 -248.0694) (xy 377.272252 -248.118793) (xy 377.248674 -248.165067) (xy 377.218148 -248.207083)
			(xy 377.181425 -248.243806) (xy 377.139409 -248.274332) (xy 377.093135 -248.29791) (xy 377.043742 -248.313958)
			(xy 376.992447 -248.322083) (xy 376.940513 -248.322083) (xy 376.889218 -248.313958) (xy 376.839825 -248.29791)
			(xy 376.793551 -248.274332) (xy 376.751535 -248.243806) (xy 376.714812 -248.207083) (xy 376.684286 -248.165067)
			(xy 376.660708 -248.118793) (xy 376.64466 -248.0694) (xy 376.636535 -248.018105) (xy 376.356625 -248.018105)
			(xy 376.3485 -248.0694) (xy 376.332452 -248.118793) (xy 376.308874 -248.165067) (xy 376.278348 -248.207083)
			(xy 376.241625 -248.243806) (xy 376.199609 -248.274332) (xy 376.153335 -248.29791) (xy 376.103942 -248.313958)
			(xy 376.052647 -248.322083) (xy 376.000713 -248.322083) (xy 375.949418 -248.313958) (xy 375.900025 -248.29791)
			(xy 375.853751 -248.274332) (xy 375.811735 -248.243806) (xy 375.775012 -248.207083) (xy 375.744486 -248.165067)
			(xy 375.720908 -248.118793) (xy 375.70486 -248.0694) (xy 375.696735 -248.018105) (xy 375.416825 -248.018105)
			(xy 375.4087 -248.0694) (xy 375.392652 -248.118793) (xy 375.369074 -248.165067) (xy 375.338548 -248.207083)
			(xy 375.301825 -248.243806) (xy 375.259809 -248.274332) (xy 375.213535 -248.29791) (xy 375.164142 -248.313958)
			(xy 375.112847 -248.322083) (xy 375.060913 -248.322083) (xy 375.009618 -248.313958) (xy 374.960225 -248.29791)
			(xy 374.913951 -248.274332) (xy 374.871935 -248.243806) (xy 374.835212 -248.207083) (xy 374.804686 -248.165067)
			(xy 374.781108 -248.118793) (xy 374.76506 -248.0694) (xy 374.756935 -248.018105) (xy 374.477279 -248.018105)
			(xy 374.469154 -248.0694) (xy 374.453106 -248.118793) (xy 374.429528 -248.165067) (xy 374.399002 -248.207083)
			(xy 374.362279 -248.243806) (xy 374.320263 -248.274332) (xy 374.273989 -248.29791) (xy 374.224596 -248.313958)
			(xy 374.173301 -248.322083) (xy 374.121367 -248.322083) (xy 374.070072 -248.313958) (xy 374.020679 -248.29791)
			(xy 373.974405 -248.274332) (xy 373.932389 -248.243806) (xy 373.895666 -248.207083) (xy 373.86514 -248.165067)
			(xy 373.841562 -248.118793) (xy 373.825514 -248.0694) (xy 373.817389 -248.018105) (xy 373.537225 -248.018105)
			(xy 373.5291 -248.0694) (xy 373.513052 -248.118793) (xy 373.489474 -248.165067) (xy 373.458948 -248.207083)
			(xy 373.422225 -248.243806) (xy 373.380209 -248.274332) (xy 373.333935 -248.29791) (xy 373.284542 -248.313958)
			(xy 373.233247 -248.322083) (xy 373.181313 -248.322083) (xy 373.130018 -248.313958) (xy 373.080625 -248.29791)
			(xy 373.034351 -248.274332) (xy 372.992335 -248.243806) (xy 372.955612 -248.207083) (xy 372.925086 -248.165067)
			(xy 372.901508 -248.118793) (xy 372.88546 -248.0694) (xy 372.877335 -248.018105) (xy 372.597425 -248.018105)
			(xy 372.5893 -248.0694) (xy 372.573252 -248.118793) (xy 372.549674 -248.165067) (xy 372.519148 -248.207083)
			(xy 372.482425 -248.243806) (xy 372.440409 -248.274332) (xy 372.394135 -248.29791) (xy 372.344742 -248.313958)
			(xy 372.293447 -248.322083) (xy 372.241513 -248.322083) (xy 372.190218 -248.313958) (xy 372.140825 -248.29791)
			(xy 372.094551 -248.274332) (xy 372.052535 -248.243806) (xy 372.015812 -248.207083) (xy 371.985286 -248.165067)
			(xy 371.961708 -248.118793) (xy 371.94566 -248.0694) (xy 371.937535 -248.018105) (xy 371.657625 -248.018105)
			(xy 371.6495 -248.0694) (xy 371.633452 -248.118793) (xy 371.609874 -248.165067) (xy 371.579348 -248.207083)
			(xy 371.542625 -248.243806) (xy 371.500609 -248.274332) (xy 371.454335 -248.29791) (xy 371.404942 -248.313958)
			(xy 371.353647 -248.322083) (xy 371.301713 -248.322083) (xy 371.250418 -248.313958) (xy 371.201025 -248.29791)
			(xy 371.154751 -248.274332) (xy 371.112735 -248.243806) (xy 371.076012 -248.207083) (xy 371.045486 -248.165067)
			(xy 371.021908 -248.118793) (xy 371.00586 -248.0694) (xy 370.997735 -248.018105) (xy 370.717825 -248.018105)
			(xy 370.7097 -248.0694) (xy 370.693652 -248.118793) (xy 370.670074 -248.165067) (xy 370.639548 -248.207083)
			(xy 370.602825 -248.243806) (xy 370.560809 -248.274332) (xy 370.514535 -248.29791) (xy 370.465142 -248.313958)
			(xy 370.413847 -248.322083) (xy 370.361913 -248.322083) (xy 370.310618 -248.313958) (xy 370.261225 -248.29791)
			(xy 370.214951 -248.274332) (xy 370.172935 -248.243806) (xy 370.136212 -248.207083) (xy 370.105686 -248.165067)
			(xy 370.082108 -248.118793) (xy 370.06606 -248.0694) (xy 370.057935 -248.018105) (xy 369.778104 -248.018105)
			(xy 369.769982 -248.06938) (xy 369.753929 -248.118784) (xy 369.730345 -248.165068) (xy 369.699811 -248.207093)
			(xy 369.663078 -248.243824) (xy 369.621051 -248.274356) (xy 369.574766 -248.297937) (xy 369.525361 -248.313987)
			(xy 369.474053 -248.322111) (xy 369.44808 -248.322592) (xy 369.447318 -248.322592) (xy 369.422215 -248.322109)
			(xy 369.372595 -248.314453) (xy 369.348512 -248.307352) (xy 369.334636 -248.303488) (xy 369.305853 -248.30282)
			(xy 369.278027 -248.310215) (xy 369.253373 -248.325084) (xy 369.233851 -248.346246) (xy 369.221012 -248.372016)
			(xy 369.217956 -248.386092) (xy 369.212915 -248.4112) (xy 369.196223 -248.459609) (xy 369.172266 -248.504865)
			(xy 369.141618 -248.545886) (xy 369.105011 -248.581691) (xy 369.06332 -248.611423) (xy 369.017544 -248.63437)
			(xy 368.968777 -248.649985) (xy 368.918185 -248.657893) (xy 368.892582 -248.65838) (xy 368.866618 -248.657817)
			(xy 368.815329 -248.649692) (xy 368.765943 -248.633643) (xy 368.719675 -248.610066) (xy 368.677665 -248.579542)
			(xy 368.640947 -248.542822) (xy 368.610425 -248.50081) (xy 368.586851 -248.454541) (xy 368.570804 -248.405154)
			(xy 368.562681 -248.353864) (xy 363.482643 -248.353864) (xy 363.495545 -248.360438) (xy 363.537561 -248.390964)
			(xy 363.574284 -248.427687) (xy 363.60481 -248.469703) (xy 363.628388 -248.515977) (xy 363.644436 -248.56537)
			(xy 363.652561 -248.616665) (xy 363.65307 -248.642632) (xy 363.65307 -248.642886) (xy 363.652592 -248.667411)
			(xy 363.645332 -248.715922) (xy 363.630986 -248.762828) (xy 363.609868 -248.8071) (xy 363.58244 -248.847767)
			(xy 363.566202 -248.866152) (xy 363.556369 -248.877617) (xy 363.543362 -248.904863) (xy 363.5389 -248.934724)
			(xy 363.543375 -248.964582) (xy 363.556395 -248.991822) (xy 363.566202 -249.003312) (xy 363.582473 -249.021672)
			(xy 363.609915 -249.062337) (xy 363.63104 -249.106614) (xy 363.639063 -249.132858) (xy 368.598924 -249.132858)
			(xy 368.598926 -249.080918) (xy 368.607053 -249.029617) (xy 368.623106 -248.980219) (xy 368.646689 -248.93394)
			(xy 368.677222 -248.891921) (xy 368.713951 -248.855196) (xy 368.755974 -248.824668) (xy 368.802256 -248.801091)
			(xy 368.851656 -248.785044) (xy 368.902958 -248.776923) (xy 368.954898 -248.776927) (xy 369.006199 -248.785057)
			(xy 369.055596 -248.801112) (xy 369.101873 -248.824698) (xy 369.112162 -248.832175) (xy 369.588289 -248.832175)
			(xy 369.588289 -248.780241) (xy 369.596414 -248.728946) (xy 369.612462 -248.679553) (xy 369.63604 -248.633279)
			(xy 369.666566 -248.591263) (xy 369.703289 -248.55454) (xy 369.745305 -248.524014) (xy 369.791579 -248.500436)
			(xy 369.840972 -248.484388) (xy 369.892267 -248.476263) (xy 369.944201 -248.476263) (xy 369.995496 -248.484388)
			(xy 370.044889 -248.500436) (xy 370.091163 -248.524014) (xy 370.133179 -248.55454) (xy 370.169902 -248.591263)
			(xy 370.200428 -248.633279) (xy 370.224006 -248.679553) (xy 370.240054 -248.728946) (xy 370.248179 -248.780241)
			(xy 370.248688 -248.806208) (xy 370.248179 -248.832175) (xy 370.527835 -248.832175) (xy 370.527835 -248.780241)
			(xy 370.53596 -248.728946) (xy 370.552008 -248.679553) (xy 370.575586 -248.633279) (xy 370.606112 -248.591263)
			(xy 370.642835 -248.55454) (xy 370.684851 -248.524014) (xy 370.731125 -248.500436) (xy 370.780518 -248.484388)
			(xy 370.831813 -248.476263) (xy 370.883747 -248.476263) (xy 370.935042 -248.484388) (xy 370.984435 -248.500436)
			(xy 371.030709 -248.524014) (xy 371.072725 -248.55454) (xy 371.109448 -248.591263) (xy 371.139974 -248.633279)
			(xy 371.163552 -248.679553) (xy 371.1796 -248.728946) (xy 371.187725 -248.780241) (xy 371.188234 -248.806208)
			(xy 371.187725 -248.832175) (xy 371.467889 -248.832175) (xy 371.467889 -248.780241) (xy 371.476014 -248.728946)
			(xy 371.492062 -248.679553) (xy 371.51564 -248.633279) (xy 371.546166 -248.591263) (xy 371.582889 -248.55454)
			(xy 371.624905 -248.524014) (xy 371.671179 -248.500436) (xy 371.720572 -248.484388) (xy 371.771867 -248.476263)
			(xy 371.823801 -248.476263) (xy 371.875096 -248.484388) (xy 371.924489 -248.500436) (xy 371.970763 -248.524014)
			(xy 372.012779 -248.55454) (xy 372.049502 -248.591263) (xy 372.080028 -248.633279) (xy 372.103606 -248.679553)
			(xy 372.119654 -248.728946) (xy 372.127779 -248.780241) (xy 372.128288 -248.806208) (xy 372.127779 -248.832175)
			(xy 372.407689 -248.832175) (xy 372.407689 -248.780241) (xy 372.415814 -248.728946) (xy 372.431862 -248.679553)
			(xy 372.45544 -248.633279) (xy 372.485966 -248.591263) (xy 372.522689 -248.55454) (xy 372.564705 -248.524014)
			(xy 372.610979 -248.500436) (xy 372.660372 -248.484388) (xy 372.711667 -248.476263) (xy 372.763601 -248.476263)
			(xy 372.814896 -248.484388) (xy 372.864289 -248.500436) (xy 372.910563 -248.524014) (xy 372.952579 -248.55454)
			(xy 372.989302 -248.591263) (xy 373.019828 -248.633279) (xy 373.043406 -248.679553) (xy 373.059454 -248.728946)
			(xy 373.067579 -248.780241) (xy 373.068088 -248.806208) (xy 373.067579 -248.832175) (xy 373.347489 -248.832175)
			(xy 373.347489 -248.780241) (xy 373.355614 -248.728946) (xy 373.371662 -248.679553) (xy 373.39524 -248.633279)
			(xy 373.425766 -248.591263) (xy 373.462489 -248.55454) (xy 373.504505 -248.524014) (xy 373.550779 -248.500436)
			(xy 373.600172 -248.484388) (xy 373.651467 -248.476263) (xy 373.703401 -248.476263) (xy 373.754696 -248.484388)
			(xy 373.804089 -248.500436) (xy 373.850363 -248.524014) (xy 373.892379 -248.55454) (xy 373.929102 -248.591263)
			(xy 373.959628 -248.633279) (xy 373.983206 -248.679553) (xy 373.999254 -248.728946) (xy 374.007379 -248.780241)
			(xy 374.007888 -248.806208) (xy 374.007379 -248.832175) (xy 374.287289 -248.832175) (xy 374.287289 -248.780241)
			(xy 374.295414 -248.728946) (xy 374.311462 -248.679553) (xy 374.33504 -248.633279) (xy 374.365566 -248.591263)
			(xy 374.402289 -248.55454) (xy 374.444305 -248.524014) (xy 374.490579 -248.500436) (xy 374.539972 -248.484388)
			(xy 374.591267 -248.476263) (xy 374.643201 -248.476263) (xy 374.694496 -248.484388) (xy 374.743889 -248.500436)
			(xy 374.790163 -248.524014) (xy 374.832179 -248.55454) (xy 374.868902 -248.591263) (xy 374.899428 -248.633279)
			(xy 374.923006 -248.679553) (xy 374.939054 -248.728946) (xy 374.947179 -248.780241) (xy 374.947688 -248.806208)
			(xy 374.947179 -248.832175) (xy 375.227089 -248.832175) (xy 375.227089 -248.780241) (xy 375.235214 -248.728946)
			(xy 375.251262 -248.679553) (xy 375.27484 -248.633279) (xy 375.305366 -248.591263) (xy 375.342089 -248.55454)
			(xy 375.384105 -248.524014) (xy 375.430379 -248.500436) (xy 375.479772 -248.484388) (xy 375.531067 -248.476263)
			(xy 375.583001 -248.476263) (xy 375.634296 -248.484388) (xy 375.683689 -248.500436) (xy 375.729963 -248.524014)
			(xy 375.771979 -248.55454) (xy 375.808702 -248.591263) (xy 375.839228 -248.633279) (xy 375.862806 -248.679553)
			(xy 375.878854 -248.728946) (xy 375.886979 -248.780241) (xy 375.887488 -248.806208) (xy 375.886979 -248.832175)
			(xy 376.166889 -248.832175) (xy 376.166889 -248.780241) (xy 376.175014 -248.728946) (xy 376.191062 -248.679553)
			(xy 376.21464 -248.633279) (xy 376.245166 -248.591263) (xy 376.281889 -248.55454) (xy 376.323905 -248.524014)
			(xy 376.370179 -248.500436) (xy 376.419572 -248.484388) (xy 376.470867 -248.476263) (xy 376.522801 -248.476263)
			(xy 376.574096 -248.484388) (xy 376.623489 -248.500436) (xy 376.669763 -248.524014) (xy 376.711779 -248.55454)
			(xy 376.748502 -248.591263) (xy 376.779028 -248.633279) (xy 376.802606 -248.679553) (xy 376.818654 -248.728946)
			(xy 376.826779 -248.780241) (xy 376.827288 -248.806208) (xy 376.826779 -248.832175) (xy 377.106435 -248.832175)
			(xy 377.106435 -248.780241) (xy 377.11456 -248.728946) (xy 377.130608 -248.679553) (xy 377.154186 -248.633279)
			(xy 377.184712 -248.591263) (xy 377.221435 -248.55454) (xy 377.263451 -248.524014) (xy 377.309725 -248.500436)
			(xy 377.359118 -248.484388) (xy 377.410413 -248.476263) (xy 377.462347 -248.476263) (xy 377.513642 -248.484388)
			(xy 377.563035 -248.500436) (xy 377.609309 -248.524014) (xy 377.651325 -248.55454) (xy 377.688048 -248.591263)
			(xy 377.718574 -248.633279) (xy 377.742152 -248.679553) (xy 377.7582 -248.728946) (xy 377.766325 -248.780241)
			(xy 377.766834 -248.806208) (xy 377.766325 -248.832175) (xy 378.046489 -248.832175) (xy 378.046489 -248.780241)
			(xy 378.054614 -248.728946) (xy 378.070662 -248.679553) (xy 378.09424 -248.633279) (xy 378.124766 -248.591263)
			(xy 378.161489 -248.55454) (xy 378.203505 -248.524014) (xy 378.249779 -248.500436) (xy 378.299172 -248.484388)
			(xy 378.350467 -248.476263) (xy 378.402401 -248.476263) (xy 378.453696 -248.484388) (xy 378.503089 -248.500436)
			(xy 378.549363 -248.524014) (xy 378.591379 -248.55454) (xy 378.628102 -248.591263) (xy 378.658628 -248.633279)
			(xy 378.682206 -248.679553) (xy 378.698254 -248.728946) (xy 378.706379 -248.780241) (xy 378.706888 -248.806208)
			(xy 378.706379 -248.832175) (xy 378.986289 -248.832175) (xy 378.986289 -248.780241) (xy 378.994414 -248.728946)
			(xy 379.010462 -248.679553) (xy 379.03404 -248.633279) (xy 379.064566 -248.591263) (xy 379.101289 -248.55454)
			(xy 379.143305 -248.524014) (xy 379.189579 -248.500436) (xy 379.238972 -248.484388) (xy 379.290267 -248.476263)
			(xy 379.342201 -248.476263) (xy 379.393496 -248.484388) (xy 379.442889 -248.500436) (xy 379.489163 -248.524014)
			(xy 379.531179 -248.55454) (xy 379.567902 -248.591263) (xy 379.598428 -248.633279) (xy 379.622006 -248.679553)
			(xy 379.638054 -248.728946) (xy 379.646179 -248.780241) (xy 379.646688 -248.806208) (xy 379.646179 -248.832175)
			(xy 379.638054 -248.88347) (xy 379.622006 -248.932863) (xy 379.598428 -248.979137) (xy 379.567902 -249.021153)
			(xy 379.531179 -249.057876) (xy 379.489163 -249.088402) (xy 379.442889 -249.11198) (xy 379.393496 -249.128028)
			(xy 379.342201 -249.136153) (xy 379.290267 -249.136153) (xy 379.238972 -249.128028) (xy 379.189579 -249.11198)
			(xy 379.143305 -249.088402) (xy 379.101289 -249.057876) (xy 379.064566 -249.021153) (xy 379.03404 -248.979137)
			(xy 379.010462 -248.932863) (xy 378.994414 -248.88347) (xy 378.986289 -248.832175) (xy 378.706379 -248.832175)
			(xy 378.698254 -248.88347) (xy 378.682206 -248.932863) (xy 378.658628 -248.979137) (xy 378.628102 -249.021153)
			(xy 378.591379 -249.057876) (xy 378.549363 -249.088402) (xy 378.503089 -249.11198) (xy 378.453696 -249.128028)
			(xy 378.402401 -249.136153) (xy 378.350467 -249.136153) (xy 378.299172 -249.128028) (xy 378.249779 -249.11198)
			(xy 378.203505 -249.088402) (xy 378.161489 -249.057876) (xy 378.124766 -249.021153) (xy 378.09424 -248.979137)
			(xy 378.070662 -248.932863) (xy 378.054614 -248.88347) (xy 378.046489 -248.832175) (xy 377.766325 -248.832175)
			(xy 377.7582 -248.88347) (xy 377.742152 -248.932863) (xy 377.718574 -248.979137) (xy 377.688048 -249.021153)
			(xy 377.651325 -249.057876) (xy 377.609309 -249.088402) (xy 377.563035 -249.11198) (xy 377.513642 -249.128028)
			(xy 377.462347 -249.136153) (xy 377.410413 -249.136153) (xy 377.359118 -249.128028) (xy 377.309725 -249.11198)
			(xy 377.263451 -249.088402) (xy 377.221435 -249.057876) (xy 377.184712 -249.021153) (xy 377.154186 -248.979137)
			(xy 377.130608 -248.932863) (xy 377.11456 -248.88347) (xy 377.106435 -248.832175) (xy 376.826779 -248.832175)
			(xy 376.818654 -248.88347) (xy 376.802606 -248.932863) (xy 376.779028 -248.979137) (xy 376.748502 -249.021153)
			(xy 376.711779 -249.057876) (xy 376.669763 -249.088402) (xy 376.623489 -249.11198) (xy 376.574096 -249.128028)
			(xy 376.522801 -249.136153) (xy 376.470867 -249.136153) (xy 376.419572 -249.128028) (xy 376.370179 -249.11198)
			(xy 376.323905 -249.088402) (xy 376.281889 -249.057876) (xy 376.245166 -249.021153) (xy 376.21464 -248.979137)
			(xy 376.191062 -248.932863) (xy 376.175014 -248.88347) (xy 376.166889 -248.832175) (xy 375.886979 -248.832175)
			(xy 375.878854 -248.88347) (xy 375.862806 -248.932863) (xy 375.839228 -248.979137) (xy 375.808702 -249.021153)
			(xy 375.771979 -249.057876) (xy 375.729963 -249.088402) (xy 375.683689 -249.11198) (xy 375.634296 -249.128028)
			(xy 375.583001 -249.136153) (xy 375.531067 -249.136153) (xy 375.479772 -249.128028) (xy 375.430379 -249.11198)
			(xy 375.384105 -249.088402) (xy 375.342089 -249.057876) (xy 375.305366 -249.021153) (xy 375.27484 -248.979137)
			(xy 375.251262 -248.932863) (xy 375.235214 -248.88347) (xy 375.227089 -248.832175) (xy 374.947179 -248.832175)
			(xy 374.939054 -248.88347) (xy 374.923006 -248.932863) (xy 374.899428 -248.979137) (xy 374.868902 -249.021153)
			(xy 374.832179 -249.057876) (xy 374.790163 -249.088402) (xy 374.743889 -249.11198) (xy 374.694496 -249.128028)
			(xy 374.643201 -249.136153) (xy 374.591267 -249.136153) (xy 374.539972 -249.128028) (xy 374.490579 -249.11198)
			(xy 374.444305 -249.088402) (xy 374.402289 -249.057876) (xy 374.365566 -249.021153) (xy 374.33504 -248.979137)
			(xy 374.311462 -248.932863) (xy 374.295414 -248.88347) (xy 374.287289 -248.832175) (xy 374.007379 -248.832175)
			(xy 373.999254 -248.88347) (xy 373.983206 -248.932863) (xy 373.959628 -248.979137) (xy 373.929102 -249.021153)
			(xy 373.892379 -249.057876) (xy 373.850363 -249.088402) (xy 373.804089 -249.11198) (xy 373.754696 -249.128028)
			(xy 373.703401 -249.136153) (xy 373.651467 -249.136153) (xy 373.600172 -249.128028) (xy 373.550779 -249.11198)
			(xy 373.504505 -249.088402) (xy 373.462489 -249.057876) (xy 373.425766 -249.021153) (xy 373.39524 -248.979137)
			(xy 373.371662 -248.932863) (xy 373.355614 -248.88347) (xy 373.347489 -248.832175) (xy 373.067579 -248.832175)
			(xy 373.059454 -248.88347) (xy 373.043406 -248.932863) (xy 373.019828 -248.979137) (xy 372.989302 -249.021153)
			(xy 372.952579 -249.057876) (xy 372.910563 -249.088402) (xy 372.864289 -249.11198) (xy 372.814896 -249.128028)
			(xy 372.763601 -249.136153) (xy 372.711667 -249.136153) (xy 372.660372 -249.128028) (xy 372.610979 -249.11198)
			(xy 372.564705 -249.088402) (xy 372.522689 -249.057876) (xy 372.485966 -249.021153) (xy 372.45544 -248.979137)
			(xy 372.431862 -248.932863) (xy 372.415814 -248.88347) (xy 372.407689 -248.832175) (xy 372.127779 -248.832175)
			(xy 372.119654 -248.88347) (xy 372.103606 -248.932863) (xy 372.080028 -248.979137) (xy 372.049502 -249.021153)
			(xy 372.012779 -249.057876) (xy 371.970763 -249.088402) (xy 371.924489 -249.11198) (xy 371.875096 -249.128028)
			(xy 371.823801 -249.136153) (xy 371.771867 -249.136153) (xy 371.720572 -249.128028) (xy 371.671179 -249.11198)
			(xy 371.624905 -249.088402) (xy 371.582889 -249.057876) (xy 371.546166 -249.021153) (xy 371.51564 -248.979137)
			(xy 371.492062 -248.932863) (xy 371.476014 -248.88347) (xy 371.467889 -248.832175) (xy 371.187725 -248.832175)
			(xy 371.1796 -248.88347) (xy 371.163552 -248.932863) (xy 371.139974 -248.979137) (xy 371.109448 -249.021153)
			(xy 371.072725 -249.057876) (xy 371.030709 -249.088402) (xy 370.984435 -249.11198) (xy 370.935042 -249.128028)
			(xy 370.883747 -249.136153) (xy 370.831813 -249.136153) (xy 370.780518 -249.128028) (xy 370.731125 -249.11198)
			(xy 370.684851 -249.088402) (xy 370.642835 -249.057876) (xy 370.606112 -249.021153) (xy 370.575586 -248.979137)
			(xy 370.552008 -248.932863) (xy 370.53596 -248.88347) (xy 370.527835 -248.832175) (xy 370.248179 -248.832175)
			(xy 370.240054 -248.88347) (xy 370.224006 -248.932863) (xy 370.200428 -248.979137) (xy 370.169902 -249.021153)
			(xy 370.133179 -249.057876) (xy 370.091163 -249.088402) (xy 370.044889 -249.11198) (xy 369.995496 -249.128028)
			(xy 369.944201 -249.136153) (xy 369.892267 -249.136153) (xy 369.840972 -249.128028) (xy 369.791579 -249.11198)
			(xy 369.745305 -249.088402) (xy 369.703289 -249.057876) (xy 369.666566 -249.021153) (xy 369.63604 -248.979137)
			(xy 369.612462 -248.932863) (xy 369.596414 -248.88347) (xy 369.588289 -248.832175) (xy 369.112162 -248.832175)
			(xy 369.143891 -248.855232) (xy 369.180615 -248.891964) (xy 369.21114 -248.933988) (xy 369.234715 -248.980271)
			(xy 369.25076 -249.029671) (xy 369.258879 -249.080974) (xy 369.259358 -249.106944) (xy 369.259113 -249.124675)
			(xy 369.255298 -249.159931) (xy 369.251738 -249.177302) (xy 369.249013 -249.191697) (xy 369.251156 -249.22091)
			(xy 369.261494 -249.248316) (xy 369.279178 -249.271666) (xy 369.302758 -249.289044) (xy 369.330297 -249.299023)
			(xy 369.359535 -249.300785) (xy 369.373912 -249.297952) (xy 369.392076 -249.294039) (xy 369.428994 -249.289837)
			(xy 369.447572 -249.28957) (xy 369.44808 -249.28957) (xy 369.474049 -249.290034) (xy 369.525347 -249.298155)
			(xy 369.574744 -249.314202) (xy 369.621022 -249.337778) (xy 369.663042 -249.368304) (xy 369.699769 -249.405027)
			(xy 369.7303 -249.447043) (xy 369.753882 -249.493318) (xy 369.769935 -249.542713) (xy 369.778063 -249.59401)
			(xy 369.778066 -249.645947) (xy 369.778059 -249.645991) (xy 370.057935 -249.645991) (xy 370.057935 -249.594057)
			(xy 370.06606 -249.542762) (xy 370.082108 -249.493369) (xy 370.105686 -249.447095) (xy 370.136212 -249.405079)
			(xy 370.172935 -249.368356) (xy 370.214951 -249.33783) (xy 370.261225 -249.314252) (xy 370.310618 -249.298204)
			(xy 370.361913 -249.290079) (xy 370.413847 -249.290079) (xy 370.465142 -249.298204) (xy 370.514535 -249.314252)
			(xy 370.560809 -249.33783) (xy 370.602825 -249.368356) (xy 370.639548 -249.405079) (xy 370.670074 -249.447095)
			(xy 370.693652 -249.493369) (xy 370.7097 -249.542762) (xy 370.717825 -249.594057) (xy 370.718334 -249.620024)
			(xy 370.717825 -249.645991) (xy 370.997735 -249.645991) (xy 370.997735 -249.594057) (xy 371.00586 -249.542762)
			(xy 371.021908 -249.493369) (xy 371.045486 -249.447095) (xy 371.076012 -249.405079) (xy 371.112735 -249.368356)
			(xy 371.154751 -249.33783) (xy 371.201025 -249.314252) (xy 371.250418 -249.298204) (xy 371.301713 -249.290079)
			(xy 371.353647 -249.290079) (xy 371.404942 -249.298204) (xy 371.454335 -249.314252) (xy 371.500609 -249.33783)
			(xy 371.542625 -249.368356) (xy 371.579348 -249.405079) (xy 371.609874 -249.447095) (xy 371.633452 -249.493369)
			(xy 371.6495 -249.542762) (xy 371.657625 -249.594057) (xy 371.658134 -249.620024) (xy 371.657625 -249.645991)
			(xy 371.937535 -249.645991) (xy 371.937535 -249.594057) (xy 371.94566 -249.542762) (xy 371.961708 -249.493369)
			(xy 371.985286 -249.447095) (xy 372.015812 -249.405079) (xy 372.052535 -249.368356) (xy 372.094551 -249.33783)
			(xy 372.140825 -249.314252) (xy 372.190218 -249.298204) (xy 372.241513 -249.290079) (xy 372.293447 -249.290079)
			(xy 372.344742 -249.298204) (xy 372.394135 -249.314252) (xy 372.440409 -249.33783) (xy 372.482425 -249.368356)
			(xy 372.519148 -249.405079) (xy 372.549674 -249.447095) (xy 372.573252 -249.493369) (xy 372.5893 -249.542762)
			(xy 372.597425 -249.594057) (xy 372.597934 -249.620024) (xy 372.597425 -249.645991) (xy 372.877589 -249.645991)
			(xy 372.877589 -249.594057) (xy 372.885714 -249.542762) (xy 372.901762 -249.493369) (xy 372.92534 -249.447095)
			(xy 372.955866 -249.405079) (xy 372.992589 -249.368356) (xy 373.034605 -249.33783) (xy 373.080879 -249.314252)
			(xy 373.130272 -249.298204) (xy 373.181567 -249.290079) (xy 373.233501 -249.290079) (xy 373.284796 -249.298204)
			(xy 373.334189 -249.314252) (xy 373.380463 -249.33783) (xy 373.422479 -249.368356) (xy 373.459202 -249.405079)
			(xy 373.489728 -249.447095) (xy 373.513306 -249.493369) (xy 373.529354 -249.542762) (xy 373.537479 -249.594057)
			(xy 373.537988 -249.620024) (xy 373.537479 -249.645991) (xy 373.817135 -249.645991) (xy 373.817135 -249.594057)
			(xy 373.82526 -249.542762) (xy 373.841308 -249.493369) (xy 373.864886 -249.447095) (xy 373.895412 -249.405079)
			(xy 373.932135 -249.368356) (xy 373.974151 -249.33783) (xy 374.020425 -249.314252) (xy 374.069818 -249.298204)
			(xy 374.121113 -249.290079) (xy 374.173047 -249.290079) (xy 374.224342 -249.298204) (xy 374.273735 -249.314252)
			(xy 374.320009 -249.33783) (xy 374.362025 -249.368356) (xy 374.398748 -249.405079) (xy 374.429274 -249.447095)
			(xy 374.452852 -249.493369) (xy 374.4689 -249.542762) (xy 374.477025 -249.594057) (xy 374.477534 -249.620024)
			(xy 374.477025 -249.645991) (xy 374.756935 -249.645991) (xy 374.756935 -249.594057) (xy 374.76506 -249.542762)
			(xy 374.781108 -249.493369) (xy 374.804686 -249.447095) (xy 374.835212 -249.405079) (xy 374.871935 -249.368356)
			(xy 374.913951 -249.33783) (xy 374.960225 -249.314252) (xy 375.009618 -249.298204) (xy 375.060913 -249.290079)
			(xy 375.112847 -249.290079) (xy 375.164142 -249.298204) (xy 375.213535 -249.314252) (xy 375.259809 -249.33783)
			(xy 375.301825 -249.368356) (xy 375.338548 -249.405079) (xy 375.369074 -249.447095) (xy 375.392652 -249.493369)
			(xy 375.4087 -249.542762) (xy 375.416825 -249.594057) (xy 375.417334 -249.620024) (xy 375.416825 -249.645991)
			(xy 375.696735 -249.645991) (xy 375.696735 -249.594057) (xy 375.70486 -249.542762) (xy 375.720908 -249.493369)
			(xy 375.744486 -249.447095) (xy 375.775012 -249.405079) (xy 375.811735 -249.368356) (xy 375.853751 -249.33783)
			(xy 375.900025 -249.314252) (xy 375.949418 -249.298204) (xy 376.000713 -249.290079) (xy 376.052647 -249.290079)
			(xy 376.103942 -249.298204) (xy 376.153335 -249.314252) (xy 376.199609 -249.33783) (xy 376.241625 -249.368356)
			(xy 376.278348 -249.405079) (xy 376.308874 -249.447095) (xy 376.332452 -249.493369) (xy 376.3485 -249.542762)
			(xy 376.356625 -249.594057) (xy 376.357134 -249.620024) (xy 376.356625 -249.645991) (xy 376.636535 -249.645991)
			(xy 376.636535 -249.594057) (xy 376.64466 -249.542762) (xy 376.660708 -249.493369) (xy 376.684286 -249.447095)
			(xy 376.714812 -249.405079) (xy 376.751535 -249.368356) (xy 376.793551 -249.33783) (xy 376.839825 -249.314252)
			(xy 376.889218 -249.298204) (xy 376.940513 -249.290079) (xy 376.992447 -249.290079) (xy 377.043742 -249.298204)
			(xy 377.093135 -249.314252) (xy 377.139409 -249.33783) (xy 377.181425 -249.368356) (xy 377.218148 -249.405079)
			(xy 377.248674 -249.447095) (xy 377.272252 -249.493369) (xy 377.2883 -249.542762) (xy 377.296425 -249.594057)
			(xy 377.296934 -249.620024) (xy 377.296425 -249.645991) (xy 377.576335 -249.645991) (xy 377.576335 -249.594057)
			(xy 377.58446 -249.542762) (xy 377.600508 -249.493369) (xy 377.624086 -249.447095) (xy 377.654612 -249.405079)
			(xy 377.691335 -249.368356) (xy 377.733351 -249.33783) (xy 377.779625 -249.314252) (xy 377.829018 -249.298204)
			(xy 377.880313 -249.290079) (xy 377.932247 -249.290079) (xy 377.983542 -249.298204) (xy 378.032935 -249.314252)
			(xy 378.079209 -249.33783) (xy 378.121225 -249.368356) (xy 378.157948 -249.405079) (xy 378.188474 -249.447095)
			(xy 378.212052 -249.493369) (xy 378.2281 -249.542762) (xy 378.236225 -249.594057) (xy 378.236734 -249.620024)
			(xy 378.236225 -249.645991) (xy 378.516135 -249.645991) (xy 378.516135 -249.594057) (xy 378.52426 -249.542762)
			(xy 378.540308 -249.493369) (xy 378.563886 -249.447095) (xy 378.594412 -249.405079) (xy 378.631135 -249.368356)
			(xy 378.673151 -249.33783) (xy 378.719425 -249.314252) (xy 378.768818 -249.298204) (xy 378.820113 -249.290079)
			(xy 378.872047 -249.290079) (xy 378.923342 -249.298204) (xy 378.972735 -249.314252) (xy 379.019009 -249.33783)
			(xy 379.061025 -249.368356) (xy 379.097748 -249.405079) (xy 379.128274 -249.447095) (xy 379.151852 -249.493369)
			(xy 379.1679 -249.542762) (xy 379.176025 -249.594057) (xy 379.176534 -249.620024) (xy 379.176025 -249.645991)
			(xy 379.1679 -249.697286) (xy 379.151852 -249.746679) (xy 379.128274 -249.792953) (xy 379.097748 -249.834969)
			(xy 379.061025 -249.871692) (xy 379.019009 -249.902218) (xy 378.972735 -249.925796) (xy 378.923342 -249.941844)
			(xy 378.872047 -249.949969) (xy 378.820113 -249.949969) (xy 378.768818 -249.941844) (xy 378.719425 -249.925796)
			(xy 378.673151 -249.902218) (xy 378.631135 -249.871692) (xy 378.594412 -249.834969) (xy 378.563886 -249.792953)
			(xy 378.540308 -249.746679) (xy 378.52426 -249.697286) (xy 378.516135 -249.645991) (xy 378.236225 -249.645991)
			(xy 378.2281 -249.697286) (xy 378.212052 -249.746679) (xy 378.188474 -249.792953) (xy 378.157948 -249.834969)
			(xy 378.121225 -249.871692) (xy 378.079209 -249.902218) (xy 378.032935 -249.925796) (xy 377.983542 -249.941844)
			(xy 377.932247 -249.949969) (xy 377.880313 -249.949969) (xy 377.829018 -249.941844) (xy 377.779625 -249.925796)
			(xy 377.733351 -249.902218) (xy 377.691335 -249.871692) (xy 377.654612 -249.834969) (xy 377.624086 -249.792953)
			(xy 377.600508 -249.746679) (xy 377.58446 -249.697286) (xy 377.576335 -249.645991) (xy 377.296425 -249.645991)
			(xy 377.2883 -249.697286) (xy 377.272252 -249.746679) (xy 377.248674 -249.792953) (xy 377.218148 -249.834969)
			(xy 377.181425 -249.871692) (xy 377.139409 -249.902218) (xy 377.093135 -249.925796) (xy 377.043742 -249.941844)
			(xy 376.992447 -249.949969) (xy 376.940513 -249.949969) (xy 376.889218 -249.941844) (xy 376.839825 -249.925796)
			(xy 376.793551 -249.902218) (xy 376.751535 -249.871692) (xy 376.714812 -249.834969) (xy 376.684286 -249.792953)
			(xy 376.660708 -249.746679) (xy 376.64466 -249.697286) (xy 376.636535 -249.645991) (xy 376.356625 -249.645991)
			(xy 376.3485 -249.697286) (xy 376.332452 -249.746679) (xy 376.308874 -249.792953) (xy 376.278348 -249.834969)
			(xy 376.241625 -249.871692) (xy 376.199609 -249.902218) (xy 376.153335 -249.925796) (xy 376.103942 -249.941844)
			(xy 376.052647 -249.949969) (xy 376.000713 -249.949969) (xy 375.949418 -249.941844) (xy 375.900025 -249.925796)
			(xy 375.853751 -249.902218) (xy 375.811735 -249.871692) (xy 375.775012 -249.834969) (xy 375.744486 -249.792953)
			(xy 375.720908 -249.746679) (xy 375.70486 -249.697286) (xy 375.696735 -249.645991) (xy 375.416825 -249.645991)
			(xy 375.4087 -249.697286) (xy 375.392652 -249.746679) (xy 375.369074 -249.792953) (xy 375.338548 -249.834969)
			(xy 375.301825 -249.871692) (xy 375.259809 -249.902218) (xy 375.213535 -249.925796) (xy 375.164142 -249.941844)
			(xy 375.112847 -249.949969) (xy 375.060913 -249.949969) (xy 375.009618 -249.941844) (xy 374.960225 -249.925796)
			(xy 374.913951 -249.902218) (xy 374.871935 -249.871692) (xy 374.835212 -249.834969) (xy 374.804686 -249.792953)
			(xy 374.781108 -249.746679) (xy 374.76506 -249.697286) (xy 374.756935 -249.645991) (xy 374.477025 -249.645991)
			(xy 374.4689 -249.697286) (xy 374.452852 -249.746679) (xy 374.429274 -249.792953) (xy 374.398748 -249.834969)
			(xy 374.362025 -249.871692) (xy 374.320009 -249.902218) (xy 374.273735 -249.925796) (xy 374.224342 -249.941844)
			(xy 374.173047 -249.949969) (xy 374.121113 -249.949969) (xy 374.069818 -249.941844) (xy 374.020425 -249.925796)
			(xy 373.974151 -249.902218) (xy 373.932135 -249.871692) (xy 373.895412 -249.834969) (xy 373.864886 -249.792953)
			(xy 373.841308 -249.746679) (xy 373.82526 -249.697286) (xy 373.817135 -249.645991) (xy 373.537479 -249.645991)
			(xy 373.529354 -249.697286) (xy 373.513306 -249.746679) (xy 373.489728 -249.792953) (xy 373.459202 -249.834969)
			(xy 373.422479 -249.871692) (xy 373.380463 -249.902218) (xy 373.334189 -249.925796) (xy 373.284796 -249.941844)
			(xy 373.233501 -249.949969) (xy 373.181567 -249.949969) (xy 373.130272 -249.941844) (xy 373.080879 -249.925796)
			(xy 373.034605 -249.902218) (xy 372.992589 -249.871692) (xy 372.955866 -249.834969) (xy 372.92534 -249.792953)
			(xy 372.901762 -249.746679) (xy 372.885714 -249.697286) (xy 372.877589 -249.645991) (xy 372.597425 -249.645991)
			(xy 372.5893 -249.697286) (xy 372.573252 -249.746679) (xy 372.549674 -249.792953) (xy 372.519148 -249.834969)
			(xy 372.482425 -249.871692) (xy 372.440409 -249.902218) (xy 372.394135 -249.925796) (xy 372.344742 -249.941844)
			(xy 372.293447 -249.949969) (xy 372.241513 -249.949969) (xy 372.190218 -249.941844) (xy 372.140825 -249.925796)
			(xy 372.094551 -249.902218) (xy 372.052535 -249.871692) (xy 372.015812 -249.834969) (xy 371.985286 -249.792953)
			(xy 371.961708 -249.746679) (xy 371.94566 -249.697286) (xy 371.937535 -249.645991) (xy 371.657625 -249.645991)
			(xy 371.6495 -249.697286) (xy 371.633452 -249.746679) (xy 371.609874 -249.792953) (xy 371.579348 -249.834969)
			(xy 371.542625 -249.871692) (xy 371.500609 -249.902218) (xy 371.454335 -249.925796) (xy 371.404942 -249.941844)
			(xy 371.353647 -249.949969) (xy 371.301713 -249.949969) (xy 371.250418 -249.941844) (xy 371.201025 -249.925796)
			(xy 371.154751 -249.902218) (xy 371.112735 -249.871692) (xy 371.076012 -249.834969) (xy 371.045486 -249.792953)
			(xy 371.021908 -249.746679) (xy 371.00586 -249.697286) (xy 370.997735 -249.645991) (xy 370.717825 -249.645991)
			(xy 370.7097 -249.697286) (xy 370.693652 -249.746679) (xy 370.670074 -249.792953) (xy 370.639548 -249.834969)
			(xy 370.602825 -249.871692) (xy 370.560809 -249.902218) (xy 370.514535 -249.925796) (xy 370.465142 -249.941844)
			(xy 370.413847 -249.949969) (xy 370.361913 -249.949969) (xy 370.310618 -249.941844) (xy 370.261225 -249.925796)
			(xy 370.214951 -249.902218) (xy 370.172935 -249.871692) (xy 370.136212 -249.834969) (xy 370.105686 -249.792953)
			(xy 370.082108 -249.746679) (xy 370.06606 -249.697286) (xy 370.057935 -249.645991) (xy 369.778059 -249.645991)
			(xy 369.769945 -249.697246) (xy 369.753899 -249.746642) (xy 369.730323 -249.792921) (xy 369.699797 -249.834941)
			(xy 369.663074 -249.871669) (xy 369.621058 -249.902199) (xy 369.574783 -249.925782) (xy 369.525389 -249.941835)
			(xy 369.474091 -249.949963) (xy 369.422154 -249.949966) (xy 369.370855 -249.941845) (xy 369.321459 -249.925799)
			(xy 369.275181 -249.902223) (xy 369.23316 -249.871698) (xy 369.196432 -249.834975) (xy 369.165901 -249.792959)
			(xy 369.142319 -249.746684) (xy 369.126266 -249.69729) (xy 369.118137 -249.645993) (xy 369.117626 -249.620024)
			(xy 369.117866 -249.602293) (xy 369.121684 -249.567037) (xy 369.125246 -249.549666) (xy 369.127798 -249.535247)
			(xy 369.125672 -249.50606) (xy 369.115358 -249.478674) (xy 369.097703 -249.455335) (xy 369.074155 -249.43796)
			(xy 369.046648 -249.427973) (xy 369.017438 -249.426195) (xy 369.003072 -249.429016) (xy 368.984909 -249.432931)
			(xy 368.94799 -249.437132) (xy 368.929412 -249.437398) (xy 368.928904 -249.437398) (xy 368.902934 -249.436875)
			(xy 368.851632 -249.42875) (xy 368.802234 -249.4127) (xy 368.755954 -249.389119) (xy 368.713933 -249.358589)
			(xy 368.677206 -249.321861) (xy 368.646677 -249.279839) (xy 368.623097 -249.233559) (xy 368.607048 -249.18416)
			(xy 368.598924 -249.132858) (xy 363.639063 -249.132858) (xy 363.645383 -249.153529) (xy 363.652628 -249.202049)
			(xy 363.65307 -249.226578) (xy 363.65307 -249.226832) (xy 363.652561 -249.252799) (xy 363.644436 -249.304094)
			(xy 363.628388 -249.353487) (xy 363.60481 -249.399761) (xy 363.574284 -249.441777) (xy 363.537561 -249.4785)
			(xy 363.495545 -249.509026) (xy 363.449271 -249.532604) (xy 363.399878 -249.548652) (xy 363.348583 -249.556777)
			(xy 363.296649 -249.556777) (xy 363.245354 -249.548652) (xy 363.195961 -249.532604) (xy 363.149687 -249.509026)
			(xy 363.107671 -249.4785) (xy 363.070948 -249.441777) (xy 363.040422 -249.399761) (xy 363.016844 -249.353487)
			(xy 363.000796 -249.304094) (xy 362.992671 -249.252799) (xy 362.992162 -249.226832) (xy 356.61924 -249.226832)
			(xy 356.615439 -249.231617) (xy 356.603344 -249.259473) (xy 356.599968 -249.289653) (xy 356.605608 -249.319492)
			(xy 356.619767 -249.346357) (xy 356.641195 -249.367876) (xy 356.668001 -249.382149) (xy 356.682802 -249.385582)
			(xy 356.707517 -249.390851) (xy 356.755101 -249.407859) (xy 356.799541 -249.43191) (xy 356.819962 -249.446796)
			(xy 356.830969 -249.454663) (xy 356.856011 -249.464873) (xy 356.882857 -249.468133) (xy 356.909614 -249.464212)
			(xy 356.934397 -249.453386) (xy 356.955456 -249.43642) (xy 356.963726 -249.425714) (xy 356.979395 -249.405019)
			(xy 357.016105 -249.368322) (xy 357.058101 -249.337816) (xy 357.10435 -249.314252) (xy 357.153715 -249.29821)
			(xy 357.204981 -249.290083) (xy 357.230934 -249.28957) (xy 357.256901 -249.290034) (xy 357.308196 -249.298163)
			(xy 357.357588 -249.314216) (xy 357.40386 -249.337797) (xy 357.445874 -249.368326) (xy 357.482596 -249.405051)
			(xy 357.513121 -249.447069) (xy 357.536697 -249.493344) (xy 357.552745 -249.542737) (xy 357.560869 -249.594033)
			(xy 357.560869 -249.645967) (xy 357.560865 -249.645991) (xy 357.840789 -249.645991) (xy 357.840789 -249.594057)
			(xy 357.848914 -249.542762) (xy 357.864962 -249.493369) (xy 357.88854 -249.447095) (xy 357.919066 -249.405079)
			(xy 357.955789 -249.368356) (xy 357.997805 -249.33783) (xy 358.044079 -249.314252) (xy 358.093472 -249.298204)
			(xy 358.144767 -249.290079) (xy 358.196701 -249.290079) (xy 358.247996 -249.298204) (xy 358.297389 -249.314252)
			(xy 358.343663 -249.33783) (xy 358.385679 -249.368356) (xy 358.422402 -249.405079) (xy 358.452928 -249.447095)
			(xy 358.476506 -249.493369) (xy 358.492554 -249.542762) (xy 358.500679 -249.594057) (xy 358.501188 -249.620024)
			(xy 358.500679 -249.645991) (xy 358.780589 -249.645991) (xy 358.780589 -249.594057) (xy 358.788714 -249.542762)
			(xy 358.804762 -249.493369) (xy 358.82834 -249.447095) (xy 358.858866 -249.405079) (xy 358.895589 -249.368356)
			(xy 358.937605 -249.33783) (xy 358.983879 -249.314252) (xy 359.033272 -249.298204) (xy 359.084567 -249.290079)
			(xy 359.136501 -249.290079) (xy 359.187796 -249.298204) (xy 359.237189 -249.314252) (xy 359.283463 -249.33783)
			(xy 359.325479 -249.368356) (xy 359.362202 -249.405079) (xy 359.392728 -249.447095) (xy 359.416306 -249.493369)
			(xy 359.432354 -249.542762) (xy 359.440479 -249.594057) (xy 359.440988 -249.620024) (xy 359.440479 -249.645991)
			(xy 359.720389 -249.645991) (xy 359.720389 -249.594057) (xy 359.728514 -249.542762) (xy 359.744562 -249.493369)
			(xy 359.76814 -249.447095) (xy 359.798666 -249.405079) (xy 359.835389 -249.368356) (xy 359.877405 -249.33783)
			(xy 359.923679 -249.314252) (xy 359.973072 -249.298204) (xy 360.024367 -249.290079) (xy 360.076301 -249.290079)
			(xy 360.127596 -249.298204) (xy 360.176989 -249.314252) (xy 360.223263 -249.33783) (xy 360.265279 -249.368356)
			(xy 360.302002 -249.405079) (xy 360.332528 -249.447095) (xy 360.356106 -249.493369) (xy 360.372154 -249.542762)
			(xy 360.380279 -249.594057) (xy 360.380788 -249.620024) (xy 360.380279 -249.645991) (xy 360.659935 -249.645991)
			(xy 360.659935 -249.594057) (xy 360.66806 -249.542762) (xy 360.684108 -249.493369) (xy 360.707686 -249.447095)
			(xy 360.738212 -249.405079) (xy 360.774935 -249.368356) (xy 360.816951 -249.33783) (xy 360.863225 -249.314252)
			(xy 360.912618 -249.298204) (xy 360.963913 -249.290079) (xy 361.015847 -249.290079) (xy 361.067142 -249.298204)
			(xy 361.116535 -249.314252) (xy 361.162809 -249.33783) (xy 361.204825 -249.368356) (xy 361.241548 -249.405079)
			(xy 361.272074 -249.447095) (xy 361.295652 -249.493369) (xy 361.3117 -249.542762) (xy 361.319825 -249.594057)
			(xy 361.320334 -249.620024) (xy 361.319825 -249.645991) (xy 361.599989 -249.645991) (xy 361.599989 -249.594057)
			(xy 361.608114 -249.542762) (xy 361.624162 -249.493369) (xy 361.64774 -249.447095) (xy 361.678266 -249.405079)
			(xy 361.714989 -249.368356) (xy 361.757005 -249.33783) (xy 361.803279 -249.314252) (xy 361.852672 -249.298204)
			(xy 361.903967 -249.290079) (xy 361.955901 -249.290079) (xy 362.007196 -249.298204) (xy 362.056589 -249.314252)
			(xy 362.102863 -249.33783) (xy 362.144879 -249.368356) (xy 362.181602 -249.405079) (xy 362.212128 -249.447095)
			(xy 362.235706 -249.493369) (xy 362.251754 -249.542762) (xy 362.259879 -249.594057) (xy 362.260388 -249.620024)
			(xy 362.259879 -249.645991) (xy 362.251754 -249.697286) (xy 362.235706 -249.746679) (xy 362.212128 -249.792953)
			(xy 362.181602 -249.834969) (xy 362.144879 -249.871692) (xy 362.102863 -249.902218) (xy 362.056589 -249.925796)
			(xy 362.007196 -249.941844) (xy 361.955901 -249.949969) (xy 361.903967 -249.949969) (xy 361.852672 -249.941844)
			(xy 361.803279 -249.925796) (xy 361.757005 -249.902218) (xy 361.714989 -249.871692) (xy 361.678266 -249.834969)
			(xy 361.64774 -249.792953) (xy 361.624162 -249.746679) (xy 361.608114 -249.697286) (xy 361.599989 -249.645991)
			(xy 361.319825 -249.645991) (xy 361.3117 -249.697286) (xy 361.295652 -249.746679) (xy 361.272074 -249.792953)
			(xy 361.241548 -249.834969) (xy 361.204825 -249.871692) (xy 361.162809 -249.902218) (xy 361.116535 -249.925796)
			(xy 361.067142 -249.941844) (xy 361.015847 -249.949969) (xy 360.963913 -249.949969) (xy 360.912618 -249.941844)
			(xy 360.863225 -249.925796) (xy 360.816951 -249.902218) (xy 360.774935 -249.871692) (xy 360.738212 -249.834969)
			(xy 360.707686 -249.792953) (xy 360.684108 -249.746679) (xy 360.66806 -249.697286) (xy 360.659935 -249.645991)
			(xy 360.380279 -249.645991) (xy 360.372154 -249.697286) (xy 360.356106 -249.746679) (xy 360.332528 -249.792953)
			(xy 360.302002 -249.834969) (xy 360.265279 -249.871692) (xy 360.223263 -249.902218) (xy 360.176989 -249.925796)
			(xy 360.127596 -249.941844) (xy 360.076301 -249.949969) (xy 360.024367 -249.949969) (xy 359.973072 -249.941844)
			(xy 359.923679 -249.925796) (xy 359.877405 -249.902218) (xy 359.835389 -249.871692) (xy 359.798666 -249.834969)
			(xy 359.76814 -249.792953) (xy 359.744562 -249.746679) (xy 359.728514 -249.697286) (xy 359.720389 -249.645991)
			(xy 359.440479 -249.645991) (xy 359.432354 -249.697286) (xy 359.416306 -249.746679) (xy 359.392728 -249.792953)
			(xy 359.362202 -249.834969) (xy 359.325479 -249.871692) (xy 359.283463 -249.902218) (xy 359.237189 -249.925796)
			(xy 359.187796 -249.941844) (xy 359.136501 -249.949969) (xy 359.084567 -249.949969) (xy 359.033272 -249.941844)
			(xy 358.983879 -249.925796) (xy 358.937605 -249.902218) (xy 358.895589 -249.871692) (xy 358.858866 -249.834969)
			(xy 358.82834 -249.792953) (xy 358.804762 -249.746679) (xy 358.788714 -249.697286) (xy 358.780589 -249.645991)
			(xy 358.500679 -249.645991) (xy 358.492554 -249.697286) (xy 358.476506 -249.746679) (xy 358.452928 -249.792953)
			(xy 358.422402 -249.834969) (xy 358.385679 -249.871692) (xy 358.343663 -249.902218) (xy 358.297389 -249.925796)
			(xy 358.247996 -249.941844) (xy 358.196701 -249.949969) (xy 358.144767 -249.949969) (xy 358.093472 -249.941844)
			(xy 358.044079 -249.925796) (xy 357.997805 -249.902218) (xy 357.955789 -249.871692) (xy 357.919066 -249.834969)
			(xy 357.88854 -249.792953) (xy 357.864962 -249.746679) (xy 357.848914 -249.697286) (xy 357.840789 -249.645991)
			(xy 357.560865 -249.645991) (xy 357.552745 -249.697263) (xy 357.536697 -249.746656) (xy 357.513121 -249.792931)
			(xy 357.482596 -249.834949) (xy 357.445874 -249.871674) (xy 357.40386 -249.902203) (xy 357.357588 -249.925784)
			(xy 357.308196 -249.941837) (xy 357.256901 -249.949966) (xy 357.230934 -249.950478) (xy 357.204082 -249.949957)
			(xy 357.151084 -249.941276) (xy 357.100189 -249.924138) (xy 357.052735 -249.898994) (xy 357.031036 -249.883168)
			(xy 357.020026 -249.875308) (xy 356.994985 -249.865102) (xy 356.968141 -249.861844) (xy 356.941386 -249.865765)
			(xy 356.916605 -249.876586) (xy 356.895544 -249.893547) (xy 356.887272 -249.90425) (xy 356.881729 -249.911839)
			(xy 356.869911 -249.926452) (xy 356.86365 -249.93346) (xy 356.853805 -249.944918) (xy 356.840793 -249.972165)
			(xy 356.836331 -250.00203) (xy 356.84081 -250.031891) (xy 356.853839 -250.059132) (xy 356.86365 -250.07062)
			(xy 356.879916 -250.088985) (xy 356.907361 -250.129647) (xy 356.928487 -250.173923) (xy 356.942831 -250.220837)
			(xy 356.950076 -250.269357) (xy 356.950518 -250.293886) (xy 356.950518 -250.29414) (xy 356.950009 -250.320107)
			(xy 356.941884 -250.371402) (xy 356.925836 -250.420795) (xy 356.902258 -250.467069) (xy 356.871732 -250.509085)
			(xy 356.835009 -250.545808) (xy 356.792993 -250.576334) (xy 356.746719 -250.599912) (xy 356.697326 -250.61596)
			(xy 356.646031 -250.624085) (xy 356.594097 -250.624085) (xy 356.542802 -250.61596) (xy 356.493409 -250.599912)
			(xy 356.447135 -250.576334) (xy 356.405119 -250.545808) (xy 356.368396 -250.509085) (xy 356.33787 -250.467069)
			(xy 356.314292 -250.420795) (xy 356.298244 -250.371402) (xy 356.290119 -250.320107) (xy 356.28961 -250.29414)
			(xy 356.28961 -250.293886) (xy 356.290051 -250.269359) (xy 356.297316 -250.220846) (xy 356.31167 -250.173938)
			(xy 356.332797 -250.129667) (xy 356.360235 -250.089003) (xy 356.376478 -250.07062) (xy 356.386242 -250.0591)
			(xy 356.39926 -250.031874) (xy 356.403736 -250.00203) (xy 356.399277 -249.972183) (xy 356.386275 -249.944949)
			(xy 356.376478 -249.93346) (xy 356.360238 -249.915074) (xy 356.332792 -249.874415) (xy 356.311662 -249.830145)
			(xy 356.297312 -249.783236) (xy 356.290057 -249.734721) (xy 356.28961 -249.710194) (xy 356.28961 -249.70994)
			(xy 356.289996 -249.686565) (xy 356.296586 -249.640282) (xy 356.30964 -249.595392) (xy 356.328897 -249.552793)
			(xy 356.353971 -249.513336) (xy 356.368858 -249.49531) (xy 356.378301 -249.483404) (xy 356.390409 -249.455551)
			(xy 356.393794 -249.425369) (xy 356.388157 -249.395526) (xy 356.373996 -249.368659) (xy 356.352562 -249.347141)
			(xy 356.32575 -249.332875) (xy 356.310946 -249.329448) (xy 356.286139 -249.324236) (xy 356.238418 -249.307142)
			(xy 356.19387 -249.282957) (xy 356.153539 -249.252249) (xy 356.118375 -249.215739) (xy 356.089201 -249.174286)
			(xy 356.066704 -249.128861) (xy 356.051412 -249.080533) (xy 356.043683 -249.030435) (xy 356.04323 -249.00509)
			(xy 351.007474 -249.00509) (xy 351.008539 -249.007318) (xy 351.018348 -249.018806) (xy 351.034607 -249.037176)
			(xy 351.062053 -249.077838) (xy 351.083181 -249.122112) (xy 351.097526 -249.169025) (xy 351.104773 -249.217543)
			(xy 351.105216 -249.242072) (xy 351.105216 -249.242326) (xy 351.104707 -249.268293) (xy 351.096582 -249.319588)
			(xy 351.080534 -249.368981) (xy 351.056956 -249.415255) (xy 351.02643 -249.457271) (xy 350.989707 -249.493994)
			(xy 350.947691 -249.52452) (xy 350.901417 -249.548098) (xy 350.852024 -249.564146) (xy 350.800729 -249.572271)
			(xy 350.748795 -249.572271) (xy 350.6975 -249.564146) (xy 350.648107 -249.548098) (xy 350.601833 -249.52452)
			(xy 350.559817 -249.493994) (xy 350.523094 -249.457271) (xy 350.492568 -249.415255) (xy 350.46899 -249.368981)
			(xy 350.452942 -249.319588) (xy 350.444817 -249.268293) (xy 350.444308 -249.242326) (xy 350.445324 -249.215148)
			(xy 350.446047 -249.200356) (xy 350.439897 -249.171399) (xy 350.425709 -249.145417) (xy 350.404673 -249.124588)
			(xy 350.378553 -249.110658) (xy 350.349536 -249.104793) (xy 350.320056 -249.107486) (xy 350.306132 -249.112532)
			(xy 350.276449 -249.123766) (xy 350.214163 -249.135915) (xy 350.182434 -249.136662) (xy 350.156464 -249.136166)
			(xy 350.105162 -249.128045) (xy 350.055762 -249.111999) (xy 350.00948 -249.088421) (xy 349.967458 -249.057894)
			(xy 349.930728 -249.021168) (xy 349.900196 -248.979149) (xy 349.876614 -248.93287) (xy 349.860563 -248.883472)
			(xy 349.852437 -248.83217) (xy 349.572325 -248.83217) (xy 349.572325 -248.832175) (xy 349.5642 -248.88347)
			(xy 349.548152 -248.932863) (xy 349.524574 -248.979137) (xy 349.494048 -249.021153) (xy 349.457325 -249.057876)
			(xy 349.415309 -249.088402) (xy 349.369035 -249.11198) (xy 349.319642 -249.128028) (xy 349.268347 -249.136153)
			(xy 349.216413 -249.136153) (xy 349.165118 -249.128028) (xy 349.115725 -249.11198) (xy 349.069451 -249.088402)
			(xy 349.027435 -249.057876) (xy 348.990712 -249.021153) (xy 348.960186 -248.979137) (xy 348.936608 -248.932863)
			(xy 348.92056 -248.88347) (xy 348.912435 -248.832175) (xy 348.632779 -248.832175) (xy 348.624654 -248.88347)
			(xy 348.608606 -248.932863) (xy 348.585028 -248.979137) (xy 348.554502 -249.021153) (xy 348.517779 -249.057876)
			(xy 348.475763 -249.088402) (xy 348.429489 -249.11198) (xy 348.380096 -249.128028) (xy 348.328801 -249.136153)
			(xy 348.276867 -249.136153) (xy 348.225572 -249.128028) (xy 348.176179 -249.11198) (xy 348.129905 -249.088402)
			(xy 348.087889 -249.057876) (xy 348.051166 -249.021153) (xy 348.02064 -248.979137) (xy 347.997062 -248.932863)
			(xy 347.981014 -248.88347) (xy 347.972889 -248.832175) (xy 347.692979 -248.832175) (xy 347.684854 -248.88347)
			(xy 347.668806 -248.932863) (xy 347.645228 -248.979137) (xy 347.614702 -249.021153) (xy 347.577979 -249.057876)
			(xy 347.535963 -249.088402) (xy 347.489689 -249.11198) (xy 347.440296 -249.128028) (xy 347.389001 -249.136153)
			(xy 347.337067 -249.136153) (xy 347.285772 -249.128028) (xy 347.236379 -249.11198) (xy 347.190105 -249.088402)
			(xy 347.148089 -249.057876) (xy 347.111366 -249.021153) (xy 347.08084 -248.979137) (xy 347.057262 -248.932863)
			(xy 347.041214 -248.88347) (xy 347.033089 -248.832175) (xy 346.753179 -248.832175) (xy 346.745054 -248.88347)
			(xy 346.729006 -248.932863) (xy 346.705428 -248.979137) (xy 346.674902 -249.021153) (xy 346.638179 -249.057876)
			(xy 346.596163 -249.088402) (xy 346.549889 -249.11198) (xy 346.500496 -249.128028) (xy 346.449201 -249.136153)
			(xy 346.397267 -249.136153) (xy 346.345972 -249.128028) (xy 346.296579 -249.11198) (xy 346.250305 -249.088402)
			(xy 346.208289 -249.057876) (xy 346.171566 -249.021153) (xy 346.14104 -248.979137) (xy 346.117462 -248.932863)
			(xy 346.101414 -248.88347) (xy 346.093289 -248.832175) (xy 345.813379 -248.832175) (xy 345.805254 -248.88347)
			(xy 345.789206 -248.932863) (xy 345.765628 -248.979137) (xy 345.735102 -249.021153) (xy 345.698379 -249.057876)
			(xy 345.656363 -249.088402) (xy 345.610089 -249.11198) (xy 345.560696 -249.128028) (xy 345.509401 -249.136153)
			(xy 345.457467 -249.136153) (xy 345.406172 -249.128028) (xy 345.356779 -249.11198) (xy 345.310505 -249.088402)
			(xy 345.268489 -249.057876) (xy 345.231766 -249.021153) (xy 345.20124 -248.979137) (xy 345.177662 -248.932863)
			(xy 345.161614 -248.88347) (xy 345.153489 -248.832175) (xy 344.873579 -248.832175) (xy 344.865454 -248.88347)
			(xy 344.849406 -248.932863) (xy 344.825828 -248.979137) (xy 344.795302 -249.021153) (xy 344.758579 -249.057876)
			(xy 344.716563 -249.088402) (xy 344.670289 -249.11198) (xy 344.620896 -249.128028) (xy 344.569601 -249.136153)
			(xy 344.517667 -249.136153) (xy 344.466372 -249.128028) (xy 344.416979 -249.11198) (xy 344.370705 -249.088402)
			(xy 344.328689 -249.057876) (xy 344.291966 -249.021153) (xy 344.26144 -248.979137) (xy 344.237862 -248.932863)
			(xy 344.221814 -248.88347) (xy 344.213689 -248.832175) (xy 343.934025 -248.832175) (xy 343.934014 -248.832752)
			(xy 343.92553 -248.885159) (xy 343.908781 -248.935537) (xy 343.884197 -248.982591) (xy 343.852411 -249.025112)
			(xy 343.833704 -249.043952) (xy 343.83345 -249.044206) (xy 343.818464 -249.079766) (xy 343.818464 -249.218196)
			(xy 343.819226 -249.230277) (xy 343.830503 -249.251654) (xy 343.840054 -249.25909) (xy 343.90838 -249.305826)
			(xy 343.919048 -249.311414) (xy 343.954608 -249.311414) (xy 343.962736 -249.308366) (xy 343.989486 -249.299463)
			(xy 344.045039 -249.289886) (xy 344.073226 -249.289316) (xy 344.07348 -249.289316) (xy 344.099468 -249.289798)
			(xy 344.150806 -249.297926) (xy 344.200239 -249.313985) (xy 344.246552 -249.33758) (xy 344.288603 -249.36813)
			(xy 344.325357 -249.404882) (xy 344.35591 -249.446931) (xy 344.379507 -249.493242) (xy 344.39557 -249.542675)
			(xy 344.403701 -249.594012) (xy 344.403701 -249.645988) (xy 344.403701 -249.645991) (xy 344.683589 -249.645991)
			(xy 344.683589 -249.594057) (xy 344.691714 -249.542762) (xy 344.707762 -249.493369) (xy 344.73134 -249.447095)
			(xy 344.761866 -249.405079) (xy 344.798589 -249.368356) (xy 344.840605 -249.33783) (xy 344.886879 -249.314252)
			(xy 344.936272 -249.298204) (xy 344.987567 -249.290079) (xy 345.039501 -249.290079) (xy 345.090796 -249.298204)
			(xy 345.140189 -249.314252) (xy 345.186463 -249.33783) (xy 345.228479 -249.368356) (xy 345.265202 -249.405079)
			(xy 345.295728 -249.447095) (xy 345.319306 -249.493369) (xy 345.335354 -249.542762) (xy 345.343479 -249.594057)
			(xy 345.343988 -249.620024) (xy 345.343479 -249.645991) (xy 345.623135 -249.645991) (xy 345.623135 -249.594057)
			(xy 345.63126 -249.542762) (xy 345.647308 -249.493369) (xy 345.670886 -249.447095) (xy 345.701412 -249.405079)
			(xy 345.738135 -249.368356) (xy 345.780151 -249.33783) (xy 345.826425 -249.314252) (xy 345.875818 -249.298204)
			(xy 345.927113 -249.290079) (xy 345.979047 -249.290079) (xy 346.030342 -249.298204) (xy 346.079735 -249.314252)
			(xy 346.126009 -249.33783) (xy 346.168025 -249.368356) (xy 346.204748 -249.405079) (xy 346.235274 -249.447095)
			(xy 346.258852 -249.493369) (xy 346.2749 -249.542762) (xy 346.283025 -249.594057) (xy 346.283534 -249.620024)
			(xy 346.283025 -249.645991) (xy 346.562935 -249.645991) (xy 346.562935 -249.594057) (xy 346.57106 -249.542762)
			(xy 346.587108 -249.493369) (xy 346.610686 -249.447095) (xy 346.641212 -249.405079) (xy 346.677935 -249.368356)
			(xy 346.719951 -249.33783) (xy 346.766225 -249.314252) (xy 346.815618 -249.298204) (xy 346.866913 -249.290079)
			(xy 346.918847 -249.290079) (xy 346.970142 -249.298204) (xy 347.019535 -249.314252) (xy 347.065809 -249.33783)
			(xy 347.107825 -249.368356) (xy 347.144548 -249.405079) (xy 347.175074 -249.447095) (xy 347.198652 -249.493369)
			(xy 347.2147 -249.542762) (xy 347.222825 -249.594057) (xy 347.223334 -249.620024) (xy 347.222825 -249.645991)
			(xy 347.502735 -249.645991) (xy 347.502735 -249.594057) (xy 347.51086 -249.542762) (xy 347.526908 -249.493369)
			(xy 347.550486 -249.447095) (xy 347.581012 -249.405079) (xy 347.617735 -249.368356) (xy 347.659751 -249.33783)
			(xy 347.706025 -249.314252) (xy 347.755418 -249.298204) (xy 347.806713 -249.290079) (xy 347.858647 -249.290079)
			(xy 347.909942 -249.298204) (xy 347.959335 -249.314252) (xy 348.005609 -249.33783) (xy 348.047625 -249.368356)
			(xy 348.084348 -249.405079) (xy 348.114874 -249.447095) (xy 348.138452 -249.493369) (xy 348.1545 -249.542762)
			(xy 348.162625 -249.594057) (xy 348.163134 -249.620024) (xy 348.162625 -249.645991) (xy 348.442535 -249.645991)
			(xy 348.442535 -249.594057) (xy 348.45066 -249.542762) (xy 348.466708 -249.493369) (xy 348.490286 -249.447095)
			(xy 348.520812 -249.405079) (xy 348.557535 -249.368356) (xy 348.599551 -249.33783) (xy 348.645825 -249.314252)
			(xy 348.695218 -249.298204) (xy 348.746513 -249.290079) (xy 348.798447 -249.290079) (xy 348.849742 -249.298204)
			(xy 348.899135 -249.314252) (xy 348.945409 -249.33783) (xy 348.987425 -249.368356) (xy 349.024148 -249.405079)
			(xy 349.054674 -249.447095) (xy 349.078252 -249.493369) (xy 349.0943 -249.542762) (xy 349.102425 -249.594057)
			(xy 349.102934 -249.620024) (xy 349.102425 -249.645991) (xy 349.382335 -249.645991) (xy 349.382335 -249.594057)
			(xy 349.39046 -249.542762) (xy 349.406508 -249.493369) (xy 349.430086 -249.447095) (xy 349.460612 -249.405079)
			(xy 349.497335 -249.368356) (xy 349.539351 -249.33783) (xy 349.585625 -249.314252) (xy 349.635018 -249.298204)
			(xy 349.686313 -249.290079) (xy 349.738247 -249.290079) (xy 349.789542 -249.298204) (xy 349.838935 -249.314252)
			(xy 349.885209 -249.33783) (xy 349.927225 -249.368356) (xy 349.963948 -249.405079) (xy 349.994474 -249.447095)
			(xy 350.018052 -249.493369) (xy 350.0341 -249.542762) (xy 350.042225 -249.594057) (xy 350.042734 -249.620024)
			(xy 350.042225 -249.645991) (xy 350.0341 -249.697286) (xy 350.018052 -249.746679) (xy 349.994474 -249.792953)
			(xy 349.963948 -249.834969) (xy 349.927225 -249.871692) (xy 349.885209 -249.902218) (xy 349.838935 -249.925796)
			(xy 349.789542 -249.941844) (xy 349.738247 -249.949969) (xy 349.686313 -249.949969) (xy 349.635018 -249.941844)
			(xy 349.585625 -249.925796) (xy 349.539351 -249.902218) (xy 349.497335 -249.871692) (xy 349.460612 -249.834969)
			(xy 349.430086 -249.792953) (xy 349.406508 -249.746679) (xy 349.39046 -249.697286) (xy 349.382335 -249.645991)
			(xy 349.102425 -249.645991) (xy 349.0943 -249.697286) (xy 349.078252 -249.746679) (xy 349.054674 -249.792953)
			(xy 349.024148 -249.834969) (xy 348.987425 -249.871692) (xy 348.945409 -249.902218) (xy 348.899135 -249.925796)
			(xy 348.849742 -249.941844) (xy 348.798447 -249.949969) (xy 348.746513 -249.949969) (xy 348.695218 -249.941844)
			(xy 348.645825 -249.925796) (xy 348.599551 -249.902218) (xy 348.557535 -249.871692) (xy 348.520812 -249.834969)
			(xy 348.490286 -249.792953) (xy 348.466708 -249.746679) (xy 348.45066 -249.697286) (xy 348.442535 -249.645991)
			(xy 348.162625 -249.645991) (xy 348.1545 -249.697286) (xy 348.138452 -249.746679) (xy 348.114874 -249.792953)
			(xy 348.084348 -249.834969) (xy 348.047625 -249.871692) (xy 348.005609 -249.902218) (xy 347.959335 -249.925796)
			(xy 347.909942 -249.941844) (xy 347.858647 -249.949969) (xy 347.806713 -249.949969) (xy 347.755418 -249.941844)
			(xy 347.706025 -249.925796) (xy 347.659751 -249.902218) (xy 347.617735 -249.871692) (xy 347.581012 -249.834969)
			(xy 347.550486 -249.792953) (xy 347.526908 -249.746679) (xy 347.51086 -249.697286) (xy 347.502735 -249.645991)
			(xy 347.222825 -249.645991) (xy 347.2147 -249.697286) (xy 347.198652 -249.746679) (xy 347.175074 -249.792953)
			(xy 347.144548 -249.834969) (xy 347.107825 -249.871692) (xy 347.065809 -249.902218) (xy 347.019535 -249.925796)
			(xy 346.970142 -249.941844) (xy 346.918847 -249.949969) (xy 346.866913 -249.949969) (xy 346.815618 -249.941844)
			(xy 346.766225 -249.925796) (xy 346.719951 -249.902218) (xy 346.677935 -249.871692) (xy 346.641212 -249.834969)
			(xy 346.610686 -249.792953) (xy 346.587108 -249.746679) (xy 346.57106 -249.697286) (xy 346.562935 -249.645991)
			(xy 346.283025 -249.645991) (xy 346.2749 -249.697286) (xy 346.258852 -249.746679) (xy 346.235274 -249.792953)
			(xy 346.204748 -249.834969) (xy 346.168025 -249.871692) (xy 346.126009 -249.902218) (xy 346.079735 -249.925796)
			(xy 346.030342 -249.941844) (xy 345.979047 -249.949969) (xy 345.927113 -249.949969) (xy 345.875818 -249.941844)
			(xy 345.826425 -249.925796) (xy 345.780151 -249.902218) (xy 345.738135 -249.871692) (xy 345.701412 -249.834969)
			(xy 345.670886 -249.792953) (xy 345.647308 -249.746679) (xy 345.63126 -249.697286) (xy 345.623135 -249.645991)
			(xy 345.343479 -249.645991) (xy 345.335354 -249.697286) (xy 345.319306 -249.746679) (xy 345.295728 -249.792953)
			(xy 345.265202 -249.834969) (xy 345.228479 -249.871692) (xy 345.186463 -249.902218) (xy 345.140189 -249.925796)
			(xy 345.090796 -249.941844) (xy 345.039501 -249.949969) (xy 344.987567 -249.949969) (xy 344.936272 -249.941844)
			(xy 344.886879 -249.925796) (xy 344.840605 -249.902218) (xy 344.798589 -249.871692) (xy 344.761866 -249.834969)
			(xy 344.73134 -249.792953) (xy 344.707762 -249.746679) (xy 344.691714 -249.697286) (xy 344.683589 -249.645991)
			(xy 344.403701 -249.645991) (xy 344.39557 -249.697325) (xy 344.379507 -249.746758) (xy 344.35591 -249.793069)
			(xy 344.325357 -249.835118) (xy 344.288603 -249.87187) (xy 344.246552 -249.90242) (xy 344.200239 -249.926015)
			(xy 344.150806 -249.942074) (xy 344.099468 -249.950202) (xy 344.07348 -249.950732) (xy 344.073226 -249.950732)
			(xy 344.043006 -249.950065) (xy 343.983573 -249.93908) (xy 343.955116 -249.928888) (xy 343.952576 -249.927872)
			(xy 343.941336 -249.924772) (xy 343.918282 -249.928069) (xy 343.90838 -249.934222) (xy 343.840054 -249.980958)
			(xy 343.830537 -249.988419) (xy 343.81929 -250.009784) (xy 343.818464 -250.021852) (xy 343.818464 -251.135134)
			(xy 350.444308 -251.135134) (xy 350.444308 -251.13488) (xy 350.444746 -251.110353) (xy 350.452012 -251.061839)
			(xy 350.466366 -251.014932) (xy 350.487495 -250.970661) (xy 350.514932 -250.929997) (xy 350.531176 -250.911614)
			(xy 350.540946 -250.900099) (xy 350.553964 -250.872871) (xy 350.558438 -250.843025) (xy 350.553978 -250.813177)
			(xy 350.540974 -250.785943) (xy 350.531176 -250.774454) (xy 350.514933 -250.75607) (xy 350.487488 -250.715411)
			(xy 350.466358 -250.67114) (xy 350.452008 -250.624231) (xy 350.444755 -250.575715) (xy 350.444308 -250.551188)
			(xy 350.444308 -250.550934) (xy 350.444817 -250.524967) (xy 350.452942 -250.473672) (xy 350.46899 -250.424279)
			(xy 350.492568 -250.378005) (xy 350.523094 -250.335989) (xy 350.559817 -250.299266) (xy 350.601833 -250.26874)
			(xy 350.648107 -250.245162) (xy 350.6975 -250.229114) (xy 350.748795 -250.220989) (xy 350.800729 -250.220989)
			(xy 350.852024 -250.229114) (xy 350.901417 -250.245162) (xy 350.947691 -250.26874) (xy 350.989707 -250.299266)
			(xy 351.02643 -250.335989) (xy 351.051628 -250.370672) (xy 351.766315 -250.370672) (xy 351.766315 -250.318728)
			(xy 351.774441 -250.267425) (xy 351.790493 -250.218024) (xy 351.814076 -250.171743) (xy 351.844608 -250.129721)
			(xy 351.881339 -250.092993) (xy 351.923363 -250.062463) (xy 351.969646 -250.038884) (xy 352.019048 -250.022835)
			(xy 352.070352 -250.014713) (xy 352.096324 -250.014232) (xy 352.096578 -250.014232) (xy 352.121103 -250.014715)
			(xy 352.169614 -250.021973) (xy 352.21652 -250.036318) (xy 352.260792 -250.057436) (xy 352.301459 -250.084862)
			(xy 352.319844 -250.1011) (xy 352.331333 -250.110903) (xy 352.35857 -250.123917) (xy 352.388424 -250.128385)
			(xy 352.418278 -250.123917) (xy 352.445515 -250.110903) (xy 352.457004 -250.1011) (xy 352.475368 -250.084833)
			(xy 352.516032 -250.057391) (xy 352.560308 -250.036265) (xy 352.607222 -250.021921) (xy 352.655741 -250.014675)
			(xy 352.68027 -250.014232) (xy 352.680524 -250.014232) (xy 352.707168 -250.014736) (xy 352.759769 -250.023264)
			(xy 352.810319 -250.040126) (xy 352.857505 -250.064885) (xy 352.900104 -250.096899) (xy 352.937011 -250.135336)
			(xy 352.952558 -250.15698) (xy 352.961058 -250.168378) (xy 352.983003 -250.186431) (xy 353.009076 -250.197729)
			(xy 353.037255 -250.201396) (xy 353.065351 -250.197147) (xy 353.091186 -250.185312) (xy 353.112753 -250.166809)
			(xy 353.12096 -250.155202) (xy 353.136379 -250.132763) (xy 353.173377 -250.092823) (xy 353.216425 -250.059493)
			(xy 353.264357 -250.033677) (xy 353.315875 -250.016073) (xy 353.369583 -250.007159) (xy 353.396804 -250.006612)
			(xy 353.422558 -250.007091) (xy 353.473444 -250.015072) (xy 353.522474 -250.030855) (xy 353.56846 -250.054059)
			(xy 353.610287 -250.084119) (xy 353.62896 -250.101862) (xy 353.63865 -250.110855) (xy 353.661582 -250.123987)
			(xy 353.687121 -250.130782) (xy 353.713547 -250.130782) (xy 353.739086 -250.123987) (xy 353.762018 -250.110855)
			(xy 353.771708 -250.101862) (xy 353.790394 -250.084135) (xy 353.832224 -250.054086) (xy 353.878207 -250.030887)
			(xy 353.927232 -250.0151) (xy 353.978112 -250.007107) (xy 354.003864 -250.006612) (xy 354.031794 -250.007202)
			(xy 354.08686 -250.016595) (xy 354.139565 -250.035105) (xy 354.188412 -250.062204) (xy 354.232013 -250.097123)
			(xy 354.251006 -250.11761) (xy 354.260948 -250.128218) (xy 354.285583 -250.143647) (xy 354.313567 -250.151508)
			(xy 354.342632 -250.151163) (xy 354.370422 -250.14264) (xy 354.394683 -250.12663) (xy 354.404422 -250.115832)
			(xy 354.420199 -250.097849) (xy 354.456068 -250.066197) (xy 354.496125 -250.040045) (xy 354.539533 -250.01994)
			(xy 354.585385 -250.0063) (xy 354.632725 -249.999412) (xy 354.656644 -249.998992) (xy 354.684922 -249.999559)
			(xy 354.740654 -250.00917) (xy 354.793939 -250.028121) (xy 354.843223 -250.055861) (xy 354.88707 -250.091581)
			(xy 354.906072 -250.11253) (xy 354.915839 -250.122974) (xy 354.939848 -250.138482) (xy 354.967214 -250.146728)
			(xy 354.995794 -250.147066) (xy 355.023347 -250.13947) (xy 355.047716 -250.124535) (xy 355.05771 -250.114308)
			(xy 355.076632 -250.094372) (xy 355.119891 -250.060466) (xy 355.168162 -250.034183) (xy 355.220117 -250.016249)
			(xy 355.274323 -250.007157) (xy 355.301804 -250.006612) (xy 355.327768 -250.007189) (xy 355.379058 -250.015313)
			(xy 355.428445 -250.031361) (xy 355.474713 -250.054936) (xy 355.516724 -250.08546) (xy 355.553443 -250.122179)
			(xy 355.583966 -250.16419) (xy 355.607541 -250.210459) (xy 355.623587 -250.259846) (xy 355.631711 -250.311136)
			(xy 355.631711 -250.363064) (xy 355.623587 -250.414354) (xy 355.607541 -250.463741) (xy 355.583966 -250.51001)
			(xy 355.553443 -250.552021) (xy 355.516724 -250.58874) (xy 355.474713 -250.619264) (xy 355.428445 -250.642839)
			(xy 355.379058 -250.658887) (xy 355.327768 -250.667011) (xy 355.301804 -250.66752) (xy 355.273525 -250.666984)
			(xy 355.217792 -250.657365) (xy 355.164507 -250.638405) (xy 355.115223 -250.610659) (xy 355.071377 -250.574934)
			(xy 355.052376 -250.553982) (xy 355.042657 -250.543492) (xy 355.018631 -250.528) (xy 354.991255 -250.519768)
			(xy 354.962669 -250.51944) (xy 354.935111 -250.527041) (xy 354.910736 -250.541977) (xy 354.900738 -250.552204)
			(xy 354.881795 -250.57212) (xy 354.838542 -250.606028) (xy 354.790275 -250.632313) (xy 354.738325 -250.650253)
			(xy 354.684124 -250.659351) (xy 354.656644 -250.6599) (xy 354.628714 -250.659301) (xy 354.57365 -250.649909)
			(xy 354.520945 -250.631402) (xy 354.472097 -250.604305) (xy 354.428495 -250.569388) (xy 354.409502 -250.548902)
			(xy 354.399552 -250.538301) (xy 354.37492 -250.52287) (xy 354.346938 -250.515007) (xy 354.317873 -250.515351)
			(xy 354.290084 -250.523873) (xy 354.265824 -250.539882) (xy 354.256086 -250.55068) (xy 354.240308 -250.568661)
			(xy 354.204438 -250.600313) (xy 354.164382 -250.626465) (xy 354.120974 -250.64657) (xy 354.075122 -250.66021)
			(xy 354.027783 -250.667099) (xy 354.003864 -250.66752) (xy 353.97811 -250.667052) (xy 353.927223 -250.659067)
			(xy 353.878193 -250.64328) (xy 353.832208 -250.620075) (xy 353.790381 -250.590014) (xy 353.771708 -250.57227)
			(xy 353.762018 -250.563277) (xy 353.739086 -250.550145) (xy 353.713547 -250.54335) (xy 353.687121 -250.54335)
			(xy 353.661582 -250.550145) (xy 353.63865 -250.563277) (xy 353.62896 -250.57227) (xy 353.610293 -250.590018)
			(xy 353.568458 -250.620063) (xy 353.522469 -250.643258) (xy 353.47344 -250.65904) (xy 353.422557 -250.667028)
			(xy 353.396804 -250.66752) (xy 353.370162 -250.666973) (xy 353.317564 -250.658451) (xy 353.267016 -250.641596)
			(xy 353.21983 -250.616845) (xy 353.17723 -250.58484) (xy 353.14032 -250.546411) (xy 353.12477 -250.524772)
			(xy 353.116355 -250.513308) (xy 353.094388 -250.495262) (xy 353.068297 -250.483974) (xy 353.040104 -250.480318)
			(xy 353.011996 -250.484578) (xy 352.986153 -250.496424) (xy 352.964579 -250.514937) (xy 352.956368 -250.52655)
			(xy 352.940947 -250.548988) (xy 352.903948 -250.588925) (xy 352.8609 -250.622253) (xy 352.812968 -250.648069)
			(xy 352.761452 -250.665674) (xy 352.722792 -250.672092) (xy 362.773722 -250.672092) (xy 362.773722 -250.671838)
			(xy 362.774217 -250.647313) (xy 362.781472 -250.598803) (xy 362.795815 -250.551897) (xy 362.81693 -250.507625)
			(xy 362.844354 -250.466958) (xy 362.86059 -250.448572) (xy 362.8704 -250.437088) (xy 362.883411 -250.409849)
			(xy 362.887877 -250.379994) (xy 362.883407 -250.35014) (xy 362.870393 -250.322902) (xy 362.86059 -250.311412)
			(xy 362.844329 -250.293043) (xy 362.816886 -250.25238) (xy 362.795759 -250.208106) (xy 362.781414 -250.161193)
			(xy 362.774166 -250.112675) (xy 362.773722 -250.088146) (xy 362.773722 -250.087892) (xy 362.774231 -250.061925)
			(xy 362.782356 -250.01063) (xy 362.798404 -249.961237) (xy 362.821982 -249.914963) (xy 362.852508 -249.872947)
			(xy 362.889231 -249.836224) (xy 362.931247 -249.805698) (xy 362.977521 -249.78212) (xy 363.026914 -249.766072)
			(xy 363.078209 -249.757947) (xy 363.130143 -249.757947) (xy 363.181438 -249.766072) (xy 363.230831 -249.78212)
			(xy 363.277105 -249.805698) (xy 363.319121 -249.836224) (xy 363.355844 -249.872947) (xy 363.38637 -249.914963)
			(xy 363.409948 -249.961237) (xy 363.425996 -250.01063) (xy 363.434121 -250.061925) (xy 363.43463 -250.087892)
			(xy 363.43463 -250.088146) (xy 363.434198 -250.112673) (xy 363.426929 -250.161187) (xy 363.412573 -250.208094)
			(xy 363.391443 -250.252365) (xy 363.364005 -250.293029) (xy 363.347762 -250.311412) (xy 363.337963 -250.322906)
			(xy 363.324944 -250.35014) (xy 363.323013 -250.363033) (xy 364.044485 -250.363033) (xy 364.044485 -250.311099)
			(xy 364.05261 -250.259804) (xy 364.068658 -250.210411) (xy 364.092236 -250.164137) (xy 364.122762 -250.122121)
			(xy 364.159485 -250.085398) (xy 364.201501 -250.054872) (xy 364.247775 -250.031294) (xy 364.297168 -250.015246)
			(xy 364.348463 -250.007121) (xy 364.400397 -250.007121) (xy 364.451692 -250.015246) (xy 364.501085 -250.031294)
			(xy 364.547359 -250.054872) (xy 364.589375 -250.085398) (xy 364.626098 -250.122121) (xy 364.656624 -250.164137)
			(xy 364.680202 -250.210411) (xy 364.69625 -250.259804) (xy 364.704375 -250.311099) (xy 364.704884 -250.337066)
			(xy 364.704375 -250.363033) (xy 364.704369 -250.363072) (xy 364.811495 -250.363072) (xy 364.811495 -250.311128)
			(xy 364.819621 -250.259822) (xy 364.835673 -250.21042) (xy 364.859256 -250.164137) (xy 364.889789 -250.122113)
			(xy 364.92652 -250.085383) (xy 364.968545 -250.054851) (xy 365.014829 -250.031269) (xy 365.064232 -250.015219)
			(xy 365.115538 -250.007094) (xy 365.14151 -250.006612) (xy 365.168092 -250.007132) (xy 365.22057 -250.015638)
			(xy 365.271011 -250.032431) (xy 365.318116 -250.057077) (xy 365.360671 -250.088941) (xy 365.379508 -250.107704)
			(xy 365.389279 -250.117229) (xy 365.412721 -250.131173) (xy 365.439022 -250.138403) (xy 365.466298 -250.138403)
			(xy 365.492599 -250.131173) (xy 365.516041 -250.117229) (xy 365.525812 -250.107704) (xy 365.544647 -250.08894)
			(xy 365.587203 -250.057078) (xy 365.634309 -250.032435) (xy 365.684751 -250.015645) (xy 365.737229 -250.007142)
			(xy 365.76381 -250.006612) (xy 365.789672 -250.007101) (xy 365.840764 -250.015149) (xy 365.889978 -250.031063)
			(xy 365.936109 -250.054454) (xy 365.978031 -250.08475) (xy 365.996728 -250.102624) (xy 366.006443 -250.111669)
			(xy 366.029452 -250.124881) (xy 366.055089 -250.131718) (xy 366.081623 -250.131718) (xy 366.10726 -250.124881)
			(xy 366.130269 -250.111669) (xy 366.139984 -250.102624) (xy 366.158674 -250.084744) (xy 366.200604 -250.054462)
			(xy 366.246738 -250.03108) (xy 366.295951 -250.015167) (xy 366.347041 -250.007112) (xy 366.372902 -250.006612)
			(xy 366.397289 -250.007016) (xy 366.445534 -250.014173) (xy 366.492203 -250.028348) (xy 366.536279 -250.049231)
			(xy 366.576806 -250.076368) (xy 366.612902 -250.10917) (xy 366.62868 -250.12777) (xy 366.638601 -250.139005)
			(xy 366.663518 -250.155635) (xy 366.692187 -250.164323) (xy 366.722145 -250.164323) (xy 366.750814 -250.155635)
			(xy 366.775731 -250.139005) (xy 366.785652 -250.12777) (xy 366.801446 -250.109188) (xy 366.83755 -250.076406)
			(xy 366.878078 -250.049282) (xy 366.92215 -250.028404) (xy 366.96881 -250.014225) (xy 367.017047 -250.007053)
			(xy 367.04143 -250.006612) (xy 367.068726 -250.007207) (xy 367.122576 -250.016177) (xy 367.174216 -250.033883)
			(xy 367.222241 -250.059843) (xy 367.26534 -250.093349) (xy 367.284254 -250.113038) (xy 367.294087 -250.123018)
			(xy 367.317971 -250.137644) (xy 367.344927 -250.145243) (xy 367.372933 -250.145243) (xy 367.399889 -250.137644)
			(xy 367.423773 -250.123018) (xy 367.433606 -250.113038) (xy 367.452494 -250.093322) (xy 367.495601 -250.059815)
			(xy 367.543631 -250.033854) (xy 367.595277 -250.016146) (xy 367.649131 -250.007172) (xy 367.67643 -250.006612)
			(xy 367.702393 -250.007191) (xy 367.753679 -250.015319) (xy 367.803063 -250.031368) (xy 367.849328 -250.054945)
			(xy 367.891335 -250.085469) (xy 367.928051 -250.122188) (xy 367.958571 -250.164198) (xy 367.982143 -250.210465)
			(xy 367.998188 -250.25985) (xy 368.006311 -250.311137) (xy 368.006311 -250.363063) (xy 367.998188 -250.41435)
			(xy 367.982143 -250.463735) (xy 367.958571 -250.510002) (xy 367.928051 -250.552012) (xy 367.891335 -250.588731)
			(xy 367.849328 -250.619255) (xy 367.803063 -250.642832) (xy 367.753679 -250.658881) (xy 367.702393 -250.667009)
			(xy 367.67643 -250.66752) (xy 367.649132 -250.666973) (xy 367.595279 -250.657995) (xy 367.543637 -250.640279)
			(xy 367.495613 -250.614307) (xy 367.452517 -250.580789) (xy 367.433606 -250.561094) (xy 367.423773 -250.551114)
			(xy 367.399889 -250.536488) (xy 367.372933 -250.528889) (xy 367.344927 -250.528889) (xy 367.317971 -250.536488)
			(xy 367.294087 -250.551114) (xy 367.284254 -250.561094) (xy 367.265325 -250.580769) (xy 367.222231 -250.614283)
			(xy 367.174211 -250.640253) (xy 367.122574 -250.657971) (xy 367.068726 -250.666955) (xy 367.04143 -250.66752)
			(xy 367.017044 -250.667082) (xy 366.968801 -250.65993) (xy 366.922134 -250.645761) (xy 366.878057 -250.624885)
			(xy 366.83753 -250.597754) (xy 366.801432 -250.564959) (xy 366.785652 -250.546362) (xy 366.775731 -250.535127)
			(xy 366.750814 -250.518497) (xy 366.722145 -250.509809) (xy 366.692187 -250.509809) (xy 366.663518 -250.518497)
			(xy 366.638601 -250.535127) (xy 366.62868 -250.546362) (xy 366.612931 -250.564984) (xy 366.576816 -250.597761)
			(xy 366.536278 -250.62488) (xy 366.492198 -250.645751) (xy 366.445531 -250.659921) (xy 366.397288 -250.667084)
			(xy 366.372902 -250.66752) (xy 366.347041 -250.667014) (xy 366.29595 -250.658969) (xy 366.246737 -250.643058)
			(xy 366.200605 -250.619671) (xy 366.158682 -250.58938) (xy 366.139984 -250.571508) (xy 366.130269 -250.562463)
			(xy 366.10726 -250.549251) (xy 366.081623 -250.542414) (xy 366.055089 -250.542414) (xy 366.029452 -250.549251)
			(xy 366.006443 -250.562463) (xy 365.996728 -250.571508) (xy 365.978038 -250.589387) (xy 365.936107 -250.619668)
			(xy 365.889973 -250.64305) (xy 365.840761 -250.658963) (xy 365.789671 -250.667019) (xy 365.76381 -250.66752)
			(xy 365.73723 -250.666978) (xy 365.684753 -250.658475) (xy 365.634312 -250.641687) (xy 365.587207 -250.617047)
			(xy 365.54465 -250.585188) (xy 365.525812 -250.566428) (xy 365.516041 -250.556903) (xy 365.492599 -250.542959)
			(xy 365.466298 -250.535729) (xy 365.439022 -250.535729) (xy 365.412721 -250.542959) (xy 365.389279 -250.556903)
			(xy 365.379508 -250.566428) (xy 365.36067 -250.585188) (xy 365.318113 -250.617049) (xy 365.271008 -250.641693)
			(xy 365.220568 -250.658483) (xy 365.168091 -250.666989) (xy 365.14151 -250.66752) (xy 365.115538 -250.667106)
			(xy 365.064232 -250.658981) (xy 365.014829 -250.642931) (xy 364.968545 -250.619349) (xy 364.92652 -250.588817)
			(xy 364.889789 -250.552087) (xy 364.859256 -250.510063) (xy 364.835673 -250.46378) (xy 364.819621 -250.414378)
			(xy 364.811495 -250.363072) (xy 364.704369 -250.363072) (xy 364.69625 -250.414328) (xy 364.680202 -250.463721)
			(xy 364.656624 -250.509995) (xy 364.626098 -250.552011) (xy 364.589375 -250.588734) (xy 364.547359 -250.61926)
			(xy 364.501085 -250.642838) (xy 364.451692 -250.658886) (xy 364.400397 -250.667011) (xy 364.348463 -250.667011)
			(xy 364.297168 -250.658886) (xy 364.247775 -250.642838) (xy 364.201501 -250.61926) (xy 364.159485 -250.588734)
			(xy 364.122762 -250.552011) (xy 364.092236 -250.509995) (xy 364.068658 -250.463721) (xy 364.05261 -250.414328)
			(xy 364.044485 -250.363033) (xy 363.323013 -250.363033) (xy 363.320472 -250.379994) (xy 363.32494 -250.409848)
			(xy 363.337957 -250.437084) (xy 363.347762 -250.448572) (xy 363.364007 -250.466954) (xy 363.391455 -250.507612)
			(xy 363.412585 -250.551884) (xy 363.426934 -250.598794) (xy 363.434185 -250.64731) (xy 363.43463 -250.671838)
			(xy 363.43463 -250.672092) (xy 363.434121 -250.698059) (xy 363.425996 -250.749354) (xy 363.409948 -250.798747)
			(xy 363.38637 -250.845021) (xy 363.355844 -250.887037) (xy 363.319121 -250.92376) (xy 363.277105 -250.954286)
			(xy 363.230831 -250.977864) (xy 363.181438 -250.993912) (xy 363.130143 -251.002037) (xy 363.078209 -251.002037)
			(xy 363.026914 -250.993912) (xy 362.977521 -250.977864) (xy 362.931247 -250.954286) (xy 362.889231 -250.92376)
			(xy 362.852508 -250.887037) (xy 362.821982 -250.845021) (xy 362.798404 -250.798747) (xy 362.782356 -250.749354)
			(xy 362.774231 -250.698059) (xy 362.773722 -250.672092) (xy 352.722792 -250.672092) (xy 352.707745 -250.67459)
			(xy 352.680524 -250.67514) (xy 352.68027 -250.67514) (xy 352.655743 -250.674696) (xy 352.60723 -250.66743)
			(xy 352.560324 -250.653076) (xy 352.516052 -250.631949) (xy 352.475388 -250.604514) (xy 352.457004 -250.588272)
			(xy 352.445515 -250.578469) (xy 352.418278 -250.565455) (xy 352.388424 -250.560987) (xy 352.35857 -250.565455)
			(xy 352.331333 -250.578469) (xy 352.319844 -250.588272) (xy 352.301457 -250.604511) (xy 352.2608 -250.631959)
			(xy 352.21653 -250.65309) (xy 352.169621 -250.667441) (xy 352.121105 -250.674694) (xy 352.096578 -250.67514)
			(xy 352.096324 -250.67514) (xy 352.070352 -250.674687) (xy 352.019048 -250.666565) (xy 351.969646 -250.650516)
			(xy 351.923363 -250.626937) (xy 351.881339 -250.596407) (xy 351.844608 -250.559679) (xy 351.814076 -250.517657)
			(xy 351.790493 -250.471376) (xy 351.774441 -250.421975) (xy 351.766315 -250.370672) (xy 351.051628 -250.370672)
			(xy 351.056956 -250.378005) (xy 351.080534 -250.424279) (xy 351.096582 -250.473672) (xy 351.104707 -250.524967)
			(xy 351.105216 -250.550934) (xy 351.105216 -250.551188) (xy 351.104753 -250.575714) (xy 351.097492 -250.624226)
			(xy 351.083143 -250.671133) (xy 351.062021 -250.715405) (xy 351.034589 -250.75607) (xy 351.018348 -250.774454)
			(xy 351.008509 -250.785916) (xy 350.995496 -250.813163) (xy 350.991033 -250.843025) (xy 350.995511 -250.872886)
			(xy 351.008538 -250.900126) (xy 351.018348 -250.911614) (xy 351.034611 -250.929981) (xy 351.062056 -250.970643)
			(xy 351.083183 -251.014918) (xy 351.097528 -251.061832) (xy 351.104774 -251.110351) (xy 351.105216 -251.13488)
			(xy 351.105216 -251.135134) (xy 351.104707 -251.161101) (xy 351.096582 -251.212396) (xy 351.080534 -251.261789)
			(xy 351.056956 -251.308063) (xy 351.02643 -251.350079) (xy 350.989707 -251.386802) (xy 350.947691 -251.417328)
			(xy 350.901417 -251.440906) (xy 350.901282 -251.44095) (xy 368.58575 -251.44095) (xy 368.58575 -251.440696)
			(xy 368.586212 -251.41617) (xy 368.593475 -251.367658) (xy 368.607824 -251.320752) (xy 368.628947 -251.27648)
			(xy 368.656378 -251.235815) (xy 368.672618 -251.21743) (xy 368.682369 -251.205901) (xy 368.695383 -251.178677)
			(xy 368.699859 -251.148837) (xy 368.695404 -251.118993) (xy 368.682411 -251.09176) (xy 368.672618 -251.08027)
			(xy 368.656389 -251.061874) (xy 368.62894 -251.021219) (xy 368.607807 -250.976951) (xy 368.593455 -250.930045)
			(xy 368.586198 -250.881531) (xy 368.58575 -250.857004) (xy 368.58575 -250.85675) (xy 368.586259 -250.830783)
			(xy 368.594384 -250.779488) (xy 368.610432 -250.730095) (xy 368.63401 -250.683821) (xy 368.664536 -250.641805)
			(xy 368.701259 -250.605082) (xy 368.743275 -250.574556) (xy 368.789549 -250.550978) (xy 368.838942 -250.53493)
			(xy 368.890237 -250.526805) (xy 368.942171 -250.526805) (xy 368.993466 -250.53493) (xy 369.042859 -250.550978)
			(xy 369.089133 -250.574556) (xy 369.131149 -250.605082) (xy 369.167872 -250.641805) (xy 369.198398 -250.683821)
			(xy 369.221976 -250.730095) (xy 369.238024 -250.779488) (xy 369.246149 -250.830783) (xy 369.246658 -250.85675)
			(xy 369.246658 -250.857004) (xy 369.246194 -250.88153) (xy 369.238931 -250.930042) (xy 369.224582 -250.976948)
			(xy 369.20346 -251.02122) (xy 369.17603 -251.061885) (xy 369.15979 -251.08027) (xy 369.14994 -251.091722)
			(xy 369.136937 -251.118973) (xy 369.132479 -251.148837) (xy 369.136958 -251.178698) (xy 369.149982 -251.205939)
			(xy 369.15979 -251.21743) (xy 369.17602 -251.235825) (xy 369.203468 -251.27648) (xy 369.224601 -251.320748)
			(xy 369.238954 -251.367655) (xy 369.24621 -251.416169) (xy 369.246658 -251.440696) (xy 369.246658 -251.44095)
			(xy 369.246149 -251.466917) (xy 369.238024 -251.518212) (xy 369.221976 -251.567605) (xy 369.198398 -251.613879)
			(xy 369.167872 -251.655895) (xy 369.131149 -251.692618) (xy 369.089133 -251.723144) (xy 369.042859 -251.746722)
			(xy 368.993466 -251.76277) (xy 368.942171 -251.770895) (xy 368.890237 -251.770895) (xy 368.838942 -251.76277)
			(xy 368.789549 -251.746722) (xy 368.743275 -251.723144) (xy 368.701259 -251.692618) (xy 368.664536 -251.655895)
			(xy 368.63401 -251.613879) (xy 368.610432 -251.567605) (xy 368.594384 -251.518212) (xy 368.586259 -251.466917)
			(xy 368.58575 -251.44095) (xy 350.901282 -251.44095) (xy 350.852024 -251.456954) (xy 350.800729 -251.465079)
			(xy 350.748795 -251.465079) (xy 350.6975 -251.456954) (xy 350.648107 -251.440906) (xy 350.601833 -251.417328)
			(xy 350.559817 -251.386802) (xy 350.523094 -251.350079) (xy 350.492568 -251.308063) (xy 350.46899 -251.261789)
			(xy 350.452942 -251.212396) (xy 350.444817 -251.161101) (xy 350.444308 -251.135134) (xy 343.818464 -251.135134)
			(xy 343.818464 -251.431552) (xy 343.817933 -251.441392) (xy 343.810358 -251.459564) (xy 343.803732 -251.466858)
			(xy 342.138703 -253.131887) (xy 342.913463 -253.131887) (xy 342.913463 -253.079953) (xy 342.921588 -253.028658)
			(xy 342.937636 -252.979265) (xy 342.961214 -252.932991) (xy 342.99174 -252.890975) (xy 343.028463 -252.854252)
			(xy 343.070479 -252.823726) (xy 343.116753 -252.800148) (xy 343.166146 -252.7841) (xy 343.217441 -252.775975)
			(xy 343.269375 -252.775975) (xy 343.32067 -252.7841) (xy 343.366019 -252.798834) (xy 350.505268 -252.798834)
			(xy 350.505268 -252.79858) (xy 350.505716 -252.774053) (xy 350.512981 -252.725541) (xy 350.527334 -252.678634)
			(xy 350.54846 -252.634362) (xy 350.575894 -252.593698) (xy 350.592136 -252.575314) (xy 350.60191 -252.5638)
			(xy 350.614932 -252.536573) (xy 350.619409 -252.506725) (xy 350.614947 -252.476875) (xy 350.601938 -252.449641)
			(xy 350.592136 -252.438154) (xy 350.575903 -252.419762) (xy 350.548454 -252.379106) (xy 350.527321 -252.334838)
			(xy 350.51297 -252.28793) (xy 350.505715 -252.239415) (xy 350.505268 -252.214888) (xy 350.505268 -252.214634)
			(xy 350.505777 -252.188667) (xy 350.513902 -252.137372) (xy 350.52995 -252.087979) (xy 350.553528 -252.041705)
			(xy 350.584054 -251.999689) (xy 350.620777 -251.962966) (xy 350.662793 -251.93244) (xy 350.709067 -251.908862)
			(xy 350.75846 -251.892814) (xy 350.809755 -251.884689) (xy 350.861689 -251.884689) (xy 350.912984 -251.892814)
			(xy 350.962377 -251.908862) (xy 351.008651 -251.93244) (xy 351.050667 -251.962966) (xy 351.08739 -251.999689)
			(xy 351.117916 -252.041705) (xy 351.141494 -252.087979) (xy 351.157542 -252.137372) (xy 351.165667 -252.188667)
			(xy 351.166176 -252.214634) (xy 351.166176 -252.214888) (xy 351.165697 -252.239413) (xy 351.158438 -252.287924)
			(xy 351.144092 -252.33483) (xy 351.122973 -252.379102) (xy 351.095546 -252.419769) (xy 351.079308 -252.438154)
			(xy 351.069472 -252.449617) (xy 351.056465 -252.476864) (xy 351.052003 -252.506725) (xy 351.056479 -252.536584)
			(xy 351.069501 -252.563824) (xy 351.079308 -252.575314) (xy 351.095581 -252.593673) (xy 351.123022 -252.634338)
			(xy 351.134852 -252.659134) (xy 356.04323 -252.659134) (xy 356.04323 -252.65888) (xy 356.043688 -252.634354)
			(xy 356.050952 -252.585842) (xy 356.065303 -252.538936) (xy 356.086426 -252.494664) (xy 356.113858 -252.453999)
			(xy 356.130098 -252.435614) (xy 356.139866 -252.424098) (xy 356.152881 -252.39687) (xy 356.157355 -252.367025)
			(xy 356.152896 -252.337178) (xy 356.139895 -252.309944) (xy 356.130098 -252.298454) (xy 356.113858 -252.280067)
			(xy 356.086412 -252.239409) (xy 356.065281 -252.195139) (xy 356.050931 -252.148231) (xy 356.043677 -252.099715)
			(xy 356.04323 -252.075188) (xy 356.04323 -252.074934) (xy 356.043739 -252.048967) (xy 356.051864 -251.997672)
			(xy 356.067912 -251.948279) (xy 356.09149 -251.902005) (xy 356.122016 -251.859989) (xy 356.158739 -251.823266)
			(xy 356.200755 -251.79274) (xy 356.247029 -251.769162) (xy 356.296422 -251.753114) (xy 356.347717 -251.744989)
			(xy 356.399651 -251.744989) (xy 356.450946 -251.753114) (xy 356.500339 -251.769162) (xy 356.546613 -251.79274)
			(xy 356.588629 -251.823266) (xy 356.625352 -251.859989) (xy 356.655878 -251.902005) (xy 356.679456 -251.948279)
			(xy 356.695504 -251.997672) (xy 356.703629 -252.048967) (xy 356.704138 -252.074934) (xy 356.704138 -252.075188)
			(xy 356.703669 -252.099714) (xy 356.696409 -252.148226) (xy 356.682061 -252.195132) (xy 356.66094 -252.239404)
			(xy 356.63351 -252.280069) (xy 356.61727 -252.298454) (xy 356.60743 -252.309915) (xy 356.594414 -252.337162)
			(xy 356.589949 -252.367025) (xy 356.594428 -252.396887) (xy 356.607458 -252.424126) (xy 356.61727 -252.435614)
			(xy 356.633537 -252.453978) (xy 356.66098 -252.494641) (xy 356.682107 -252.538917) (xy 356.69645 -252.585831)
			(xy 356.703696 -252.634351) (xy 356.704138 -252.65888) (xy 356.704138 -252.659134) (xy 356.703724 -252.683048)
			(xy 356.69682 -252.730376) (xy 356.68316 -252.776213) (xy 356.669484 -252.805692) (xy 363.042962 -252.805692)
			(xy 363.042962 -252.805438) (xy 363.043446 -252.780913) (xy 363.050703 -252.732402) (xy 363.065047 -252.685495)
			(xy 363.086165 -252.641223) (xy 363.113592 -252.600557) (xy 363.12983 -252.582172) (xy 363.139645 -252.570691)
			(xy 363.152664 -252.543452) (xy 363.157133 -252.513594) (xy 363.15266 -252.483737) (xy 363.139638 -252.456499)
			(xy 363.12983 -252.445012) (xy 363.113576 -252.426637) (xy 363.08613 -252.385977) (xy 363.065002 -252.341704)
			(xy 363.050655 -252.294792) (xy 363.043406 -252.246274) (xy 363.042962 -252.221746) (xy 363.042962 -252.221492)
			(xy 363.043471 -252.195525) (xy 363.051596 -252.14423) (xy 363.067644 -252.094837) (xy 363.091222 -252.048563)
			(xy 363.121748 -252.006547) (xy 363.158471 -251.969824) (xy 363.200487 -251.939298) (xy 363.246761 -251.91572)
			(xy 363.296154 -251.899672) (xy 363.347449 -251.891547) (xy 363.399383 -251.891547) (xy 363.450678 -251.899672)
			(xy 363.500071 -251.91572) (xy 363.546345 -251.939298) (xy 363.588361 -251.969824) (xy 363.625084 -252.006547)
			(xy 363.65561 -252.048563) (xy 363.679188 -252.094837) (xy 363.695236 -252.14423) (xy 363.703361 -252.195525)
			(xy 363.70387 -252.221492) (xy 363.70387 -252.221746) (xy 363.703428 -252.246273) (xy 363.69616 -252.294785)
			(xy 363.681805 -252.341692) (xy 363.660678 -252.385963) (xy 363.633244 -252.426628) (xy 363.617002 -252.445012)
			(xy 363.607208 -252.456508) (xy 363.594197 -252.483743) (xy 363.589728 -252.513594) (xy 363.594193 -252.543446)
			(xy 363.607202 -252.570682) (xy 363.617002 -252.582172) (xy 363.633254 -252.600548) (xy 363.660699 -252.641209)
			(xy 363.681827 -252.685482) (xy 363.696174 -252.732393) (xy 363.703425 -252.78091) (xy 363.70387 -252.805438)
			(xy 363.70387 -252.805692) (xy 363.703361 -252.831659) (xy 363.695236 -252.882954) (xy 363.679188 -252.932347)
			(xy 363.65561 -252.978621) (xy 363.625084 -253.020637) (xy 363.588361 -253.05736) (xy 363.546345 -253.087886)
			(xy 363.500071 -253.111464) (xy 363.450678 -253.127512) (xy 363.399383 -253.135637) (xy 363.347449 -253.135637)
			(xy 363.296154 -253.127512) (xy 363.246761 -253.111464) (xy 363.200487 -253.087886) (xy 363.158471 -253.05736)
			(xy 363.121748 -253.020637) (xy 363.091222 -252.978621) (xy 363.067644 -252.932347) (xy 363.051596 -252.882954)
			(xy 363.043471 -252.831659) (xy 363.042962 -252.805692) (xy 356.669484 -252.805692) (xy 356.663032 -252.8196)
			(xy 356.636855 -252.85963) (xy 356.621334 -252.877828) (xy 356.612814 -252.888216) (xy 356.600948 -252.912306)
			(xy 356.59577 -252.938656) (xy 356.59764 -252.965444) (xy 356.606428 -252.99082) (xy 356.621527 -253.013027)
			(xy 356.641892 -253.030531) (xy 356.666116 -253.042121) (xy 356.679246 -253.04496) (xy 356.704298 -253.049984)
			(xy 356.752555 -253.066769) (xy 356.797654 -253.090781) (xy 356.838521 -253.121446) (xy 356.874183 -253.158035)
			(xy 356.899434 -253.19355) (xy 368.58575 -253.19355) (xy 368.58575 -253.193296) (xy 368.586212 -253.16877)
			(xy 368.593475 -253.120258) (xy 368.607824 -253.073352) (xy 368.628947 -253.02908) (xy 368.656378 -252.988415)
			(xy 368.672618 -252.97003) (xy 368.682369 -252.958501) (xy 368.695383 -252.931277) (xy 368.699859 -252.901437)
			(xy 368.695404 -252.871593) (xy 368.682411 -252.84436) (xy 368.672618 -252.83287) (xy 368.656389 -252.814474)
			(xy 368.62894 -252.773819) (xy 368.607807 -252.729551) (xy 368.593455 -252.682645) (xy 368.586198 -252.634131)
			(xy 368.58575 -252.609604) (xy 368.58575 -252.60935) (xy 368.586259 -252.583383) (xy 368.594384 -252.532088)
			(xy 368.610432 -252.482695) (xy 368.63401 -252.436421) (xy 368.664536 -252.394405) (xy 368.701259 -252.357682)
			(xy 368.743275 -252.327156) (xy 368.789549 -252.303578) (xy 368.838942 -252.28753) (xy 368.890237 -252.279405)
			(xy 368.942171 -252.279405) (xy 368.993466 -252.28753) (xy 369.042859 -252.303578) (xy 369.089133 -252.327156)
			(xy 369.131149 -252.357682) (xy 369.167872 -252.394405) (xy 369.198398 -252.436421) (xy 369.221976 -252.482695)
			(xy 369.238024 -252.532088) (xy 369.246149 -252.583383) (xy 369.246658 -252.60935) (xy 369.246658 -252.609604)
			(xy 369.246194 -252.63413) (xy 369.238931 -252.682642) (xy 369.224582 -252.729548) (xy 369.20346 -252.77382)
			(xy 369.17603 -252.814485) (xy 369.15979 -252.83287) (xy 369.14994 -252.844322) (xy 369.136937 -252.871573)
			(xy 369.132479 -252.901437) (xy 369.136958 -252.931298) (xy 369.149982 -252.958539) (xy 369.15979 -252.97003)
			(xy 369.17602 -252.988425) (xy 369.203468 -253.02908) (xy 369.224601 -253.073348) (xy 369.238954 -253.120255)
			(xy 369.24621 -253.168769) (xy 369.246658 -253.193296) (xy 369.246658 -253.19355) (xy 369.246149 -253.219517)
			(xy 369.238024 -253.270812) (xy 369.221976 -253.320205) (xy 369.198398 -253.366479) (xy 369.167872 -253.408495)
			(xy 369.131149 -253.445218) (xy 369.089133 -253.475744) (xy 369.042859 -253.499322) (xy 368.993466 -253.51537)
			(xy 368.942171 -253.523495) (xy 368.890237 -253.523495) (xy 368.838942 -253.51537) (xy 368.789549 -253.499322)
			(xy 368.743275 -253.475744) (xy 368.701259 -253.445218) (xy 368.664536 -253.408495) (xy 368.63401 -253.366479)
			(xy 368.610432 -253.320205) (xy 368.594384 -253.270812) (xy 368.586259 -253.219517) (xy 368.58575 -253.19355)
			(xy 356.899434 -253.19355) (xy 356.903789 -253.199676) (xy 356.926634 -253.245377) (xy 356.942175 -253.29405)
			(xy 356.95004 -253.344534) (xy 356.950518 -253.37008) (xy 356.950518 -253.370334) (xy 356.950082 -253.394861)
			(xy 356.942815 -253.443374) (xy 356.928459 -253.490282) (xy 356.907331 -253.534553) (xy 356.879893 -253.575217)
			(xy 356.86365 -253.5936) (xy 356.853864 -253.605103) (xy 356.840845 -253.632335) (xy 356.836371 -253.662185)
			(xy 356.840836 -253.692037) (xy 356.853847 -253.719272) (xy 356.86365 -253.73076) (xy 356.879888 -253.749149)
			(xy 356.907336 -253.789805) (xy 356.928468 -253.834074) (xy 356.942819 -253.880983) (xy 356.950072 -253.929499)
			(xy 356.950367 -253.945703) (xy 357.480617 -253.945703) (xy 357.480617 -253.893769) (xy 357.488742 -253.842474)
			(xy 357.50479 -253.793081) (xy 357.528368 -253.746807) (xy 357.558894 -253.704791) (xy 357.595617 -253.668068)
			(xy 357.637633 -253.637542) (xy 357.683907 -253.613964) (xy 357.7333 -253.597916) (xy 357.784595 -253.589791)
			(xy 357.836529 -253.589791) (xy 357.887824 -253.597916) (xy 357.937217 -253.613964) (xy 357.983491 -253.637542)
			(xy 358.025507 -253.668068) (xy 358.06223 -253.704791) (xy 358.092756 -253.746807) (xy 358.116334 -253.793081)
			(xy 358.132382 -253.842474) (xy 358.140507 -253.893769) (xy 358.141016 -253.919736) (xy 358.140507 -253.945703)
			(xy 358.420671 -253.945703) (xy 358.420671 -253.893769) (xy 358.428796 -253.842474) (xy 358.444844 -253.793081)
			(xy 358.468422 -253.746807) (xy 358.498948 -253.704791) (xy 358.535671 -253.668068) (xy 358.577687 -253.637542)
			(xy 358.623961 -253.613964) (xy 358.673354 -253.597916) (xy 358.724649 -253.589791) (xy 358.776583 -253.589791)
			(xy 358.827878 -253.597916) (xy 358.877271 -253.613964) (xy 358.923545 -253.637542) (xy 358.965561 -253.668068)
			(xy 359.002284 -253.704791) (xy 359.03281 -253.746807) (xy 359.056388 -253.793081) (xy 359.072436 -253.842474)
			(xy 359.080561 -253.893769) (xy 359.08107 -253.919736) (xy 359.080561 -253.945703) (xy 359.360217 -253.945703)
			(xy 359.360217 -253.893769) (xy 359.368342 -253.842474) (xy 359.38439 -253.793081) (xy 359.407968 -253.746807)
			(xy 359.438494 -253.704791) (xy 359.475217 -253.668068) (xy 359.517233 -253.637542) (xy 359.563507 -253.613964)
			(xy 359.6129 -253.597916) (xy 359.664195 -253.589791) (xy 359.716129 -253.589791) (xy 359.767424 -253.597916)
			(xy 359.816817 -253.613964) (xy 359.863091 -253.637542) (xy 359.905107 -253.668068) (xy 359.94183 -253.704791)
			(xy 359.972356 -253.746807) (xy 359.995934 -253.793081) (xy 360.011982 -253.842474) (xy 360.020107 -253.893769)
			(xy 360.020616 -253.919736) (xy 360.020107 -253.945703) (xy 360.300017 -253.945703) (xy 360.300017 -253.893769)
			(xy 360.308142 -253.842474) (xy 360.32419 -253.793081) (xy 360.347768 -253.746807) (xy 360.378294 -253.704791)
			(xy 360.415017 -253.668068) (xy 360.457033 -253.637542) (xy 360.503307 -253.613964) (xy 360.5527 -253.597916)
			(xy 360.603995 -253.589791) (xy 360.655929 -253.589791) (xy 360.707224 -253.597916) (xy 360.756617 -253.613964)
			(xy 360.802891 -253.637542) (xy 360.844907 -253.668068) (xy 360.88163 -253.704791) (xy 360.912156 -253.746807)
			(xy 360.935734 -253.793081) (xy 360.951782 -253.842474) (xy 360.959907 -253.893769) (xy 360.960416 -253.919736)
			(xy 360.959907 -253.945703) (xy 361.239817 -253.945703) (xy 361.239817 -253.893769) (xy 361.247942 -253.842474)
			(xy 361.26399 -253.793081) (xy 361.287568 -253.746807) (xy 361.318094 -253.704791) (xy 361.354817 -253.668068)
			(xy 361.396833 -253.637542) (xy 361.443107 -253.613964) (xy 361.4925 -253.597916) (xy 361.543795 -253.589791)
			(xy 361.595729 -253.589791) (xy 361.647024 -253.597916) (xy 361.696417 -253.613964) (xy 361.742691 -253.637542)
			(xy 361.784707 -253.668068) (xy 361.82143 -253.704791) (xy 361.851956 -253.746807) (xy 361.875534 -253.793081)
			(xy 361.891582 -253.842474) (xy 361.899707 -253.893769) (xy 361.900216 -253.919736) (xy 361.899708 -253.945662)
			(xy 362.179691 -253.945662) (xy 362.179691 -253.893738) (xy 362.187813 -253.842452) (xy 362.203858 -253.793068)
			(xy 362.22743 -253.746801) (xy 362.257948 -253.704792) (xy 362.294663 -253.668073) (xy 362.336669 -253.63755)
			(xy 362.382933 -253.613972) (xy 362.432315 -253.597922) (xy 362.4836 -253.589794) (xy 362.509562 -253.589282)
			(xy 362.531618 -253.589663) (xy 362.575335 -253.595551) (xy 362.617884 -253.607188) (xy 362.63834 -253.615444)
			(xy 362.652666 -253.620955) (xy 362.683184 -253.624078) (xy 362.713253 -253.617994) (xy 362.740157 -253.603252)
			(xy 362.761467 -253.581184) (xy 362.77526 -253.553781) (xy 362.778294 -253.538736) (xy 362.783035 -253.513354)
			(xy 362.799325 -253.464359) (xy 362.823042 -253.418496) (xy 362.853606 -253.376883) (xy 362.890274 -253.340533)
			(xy 362.932152 -253.310332) (xy 362.97822 -253.287016) (xy 363.027355 -253.271154) (xy 363.07836 -253.263131)
			(xy 363.104176 -253.262638) (xy 363.130144 -253.263151) (xy 363.181442 -253.271272) (xy 363.230837 -253.287318)
			(xy 363.277114 -253.310894) (xy 363.319133 -253.341419) (xy 363.35586 -253.378142) (xy 363.386389 -253.420158)
			(xy 363.409969 -253.466433) (xy 363.42602 -253.515827) (xy 363.434147 -253.567124) (xy 363.43463 -253.593092)
			(xy 363.43463 -253.593346) (xy 363.434198 -253.617873) (xy 363.426929 -253.666387) (xy 363.412573 -253.713294)
			(xy 363.391443 -253.757565) (xy 363.364005 -253.798229) (xy 363.347762 -253.816612) (xy 363.337963 -253.828106)
			(xy 363.324944 -253.85534) (xy 363.320472 -253.885194) (xy 363.32494 -253.915048) (xy 363.337957 -253.942284)
			(xy 363.347762 -253.953772) (xy 363.364007 -253.972154) (xy 363.391455 -254.012812) (xy 363.407311 -254.046033)
			(xy 364.044485 -254.046033) (xy 364.044485 -253.994099) (xy 364.05261 -253.942804) (xy 364.068658 -253.893411)
			(xy 364.092236 -253.847137) (xy 364.122762 -253.805121) (xy 364.159485 -253.768398) (xy 364.201501 -253.737872)
			(xy 364.247775 -253.714294) (xy 364.297168 -253.698246) (xy 364.348463 -253.690121) (xy 364.400397 -253.690121)
			(xy 364.451692 -253.698246) (xy 364.501085 -253.714294) (xy 364.547359 -253.737872) (xy 364.589375 -253.768398)
			(xy 364.626098 -253.805121) (xy 364.656624 -253.847137) (xy 364.680202 -253.893411) (xy 364.69625 -253.942804)
			(xy 364.704375 -253.994099) (xy 364.704884 -254.020066) (xy 364.704375 -254.046033) (xy 364.704369 -254.046072)
			(xy 364.811495 -254.046072) (xy 364.811495 -253.994128) (xy 364.819621 -253.942822) (xy 364.835673 -253.89342)
			(xy 364.859256 -253.847137) (xy 364.889789 -253.805113) (xy 364.92652 -253.768383) (xy 364.968545 -253.737851)
			(xy 365.014829 -253.714269) (xy 365.064232 -253.698219) (xy 365.115538 -253.690094) (xy 365.14151 -253.689612)
			(xy 365.167837 -253.690143) (xy 365.219824 -253.698499) (xy 365.269832 -253.714984) (xy 365.316597 -253.73918)
			(xy 365.35894 -253.770478) (xy 365.37773 -253.788926) (xy 365.387624 -253.798308) (xy 365.411187 -253.812004)
			(xy 365.437531 -253.818985) (xy 365.464784 -253.818755) (xy 365.491006 -253.811329) (xy 365.514333 -253.797235)
			(xy 365.524034 -253.787656) (xy 365.542915 -253.768561) (xy 365.58566 -253.736067) (xy 365.633097 -253.710913)
			(xy 365.683978 -253.693762) (xy 365.736963 -253.685064) (xy 365.76381 -253.684532) (xy 365.78967 -253.685043)
			(xy 365.840761 -253.69309) (xy 365.889974 -253.709) (xy 365.936105 -253.732385) (xy 365.978029 -253.762674)
			(xy 365.996728 -253.780544) (xy 366.006443 -253.789589) (xy 366.029452 -253.802801) (xy 366.055089 -253.809638)
			(xy 366.081623 -253.809638) (xy 366.10726 -253.802801) (xy 366.130269 -253.789589) (xy 366.139984 -253.780544)
			(xy 366.158678 -253.762668) (xy 366.200606 -253.732384) (xy 366.246739 -253.709001) (xy 366.295951 -253.693087)
			(xy 366.347041 -253.685032) (xy 366.372902 -253.684532) (xy 366.397484 -253.684957) (xy 366.446106 -253.692236)
			(xy 366.493115 -253.706634) (xy 366.537474 -253.727832) (xy 366.578205 -253.755365) (xy 366.614412 -253.788624)
			(xy 366.630204 -253.807468) (xy 366.640008 -253.818841) (xy 366.664842 -253.835702) (xy 366.693499 -253.844634)
			(xy 366.723515 -253.844869) (xy 366.752308 -253.836387) (xy 366.777403 -253.819918) (xy 366.78743 -253.808738)
			(xy 366.803198 -253.790431) (xy 366.839171 -253.758175) (xy 366.87946 -253.731505) (xy 366.923204 -253.710989)
			(xy 366.96947 -253.697065) (xy 367.017272 -253.69003) (xy 367.04143 -253.689612) (xy 367.068726 -253.690207)
			(xy 367.122576 -253.699177) (xy 367.174216 -253.716883) (xy 367.222241 -253.742843) (xy 367.26534 -253.776349)
			(xy 367.284254 -253.796038) (xy 367.294087 -253.806018) (xy 367.317971 -253.820644) (xy 367.344927 -253.828243)
			(xy 367.372933 -253.828243) (xy 367.399889 -253.820644) (xy 367.423773 -253.806018) (xy 367.433606 -253.796038)
			(xy 367.452494 -253.776322) (xy 367.495601 -253.742815) (xy 367.543631 -253.716854) (xy 367.595277 -253.699146)
			(xy 367.649131 -253.690172) (xy 367.67643 -253.689612) (xy 367.702393 -253.690191) (xy 367.753679 -253.698319)
			(xy 367.803063 -253.714368) (xy 367.849328 -253.737945) (xy 367.891335 -253.768469) (xy 367.928051 -253.805188)
			(xy 367.958571 -253.847198) (xy 367.982143 -253.893465) (xy 367.998188 -253.94285) (xy 367.99864 -253.945703)
			(xy 369.698271 -253.945703) (xy 369.698271 -253.893769) (xy 369.706396 -253.842474) (xy 369.722444 -253.793081)
			(xy 369.746022 -253.746807) (xy 369.776548 -253.704791) (xy 369.813271 -253.668068) (xy 369.855287 -253.637542)
			(xy 369.901561 -253.613964) (xy 369.950954 -253.597916) (xy 370.002249 -253.589791) (xy 370.054183 -253.589791)
			(xy 370.105478 -253.597916) (xy 370.154871 -253.613964) (xy 370.201145 -253.637542) (xy 370.243161 -253.668068)
			(xy 370.279884 -253.704791) (xy 370.31041 -253.746807) (xy 370.333988 -253.793081) (xy 370.350036 -253.842474)
			(xy 370.358161 -253.893769) (xy 370.35867 -253.919736) (xy 370.358161 -253.945703) (xy 370.637817 -253.945703)
			(xy 370.637817 -253.893769) (xy 370.645942 -253.842474) (xy 370.66199 -253.793081) (xy 370.685568 -253.746807)
			(xy 370.716094 -253.704791) (xy 370.752817 -253.668068) (xy 370.794833 -253.637542) (xy 370.841107 -253.613964)
			(xy 370.8905 -253.597916) (xy 370.941795 -253.589791) (xy 370.993729 -253.589791) (xy 371.045024 -253.597916)
			(xy 371.094417 -253.613964) (xy 371.140691 -253.637542) (xy 371.182707 -253.668068) (xy 371.21943 -253.704791)
			(xy 371.249956 -253.746807) (xy 371.273534 -253.793081) (xy 371.289582 -253.842474) (xy 371.297707 -253.893769)
			(xy 371.298216 -253.919736) (xy 371.297707 -253.945703) (xy 371.577871 -253.945703) (xy 371.577871 -253.893769)
			(xy 371.585996 -253.842474) (xy 371.602044 -253.793081) (xy 371.625622 -253.746807) (xy 371.656148 -253.704791)
			(xy 371.692871 -253.668068) (xy 371.734887 -253.637542) (xy 371.781161 -253.613964) (xy 371.830554 -253.597916)
			(xy 371.881849 -253.589791) (xy 371.933783 -253.589791) (xy 371.985078 -253.597916) (xy 372.034471 -253.613964)
			(xy 372.080745 -253.637542) (xy 372.122761 -253.668068) (xy 372.159484 -253.704791) (xy 372.19001 -253.746807)
			(xy 372.213588 -253.793081) (xy 372.229636 -253.842474) (xy 372.237761 -253.893769) (xy 372.23827 -253.919736)
			(xy 372.237761 -253.945703) (xy 372.517671 -253.945703) (xy 372.517671 -253.893769) (xy 372.525796 -253.842474)
			(xy 372.541844 -253.793081) (xy 372.565422 -253.746807) (xy 372.595948 -253.704791) (xy 372.632671 -253.668068)
			(xy 372.674687 -253.637542) (xy 372.720961 -253.613964) (xy 372.770354 -253.597916) (xy 372.821649 -253.589791)
			(xy 372.873583 -253.589791) (xy 372.924878 -253.597916) (xy 372.974271 -253.613964) (xy 373.020545 -253.637542)
			(xy 373.062561 -253.668068) (xy 373.099284 -253.704791) (xy 373.12981 -253.746807) (xy 373.153388 -253.793081)
			(xy 373.169436 -253.842474) (xy 373.177561 -253.893769) (xy 373.17807 -253.919736) (xy 373.177561 -253.945703)
			(xy 373.457471 -253.945703) (xy 373.457471 -253.893769) (xy 373.465596 -253.842474) (xy 373.481644 -253.793081)
			(xy 373.505222 -253.746807) (xy 373.535748 -253.704791) (xy 373.572471 -253.668068) (xy 373.614487 -253.637542)
			(xy 373.660761 -253.613964) (xy 373.710154 -253.597916) (xy 373.761449 -253.589791) (xy 373.813383 -253.589791)
			(xy 373.864678 -253.597916) (xy 373.914071 -253.613964) (xy 373.960345 -253.637542) (xy 374.002361 -253.668068)
			(xy 374.039084 -253.704791) (xy 374.06961 -253.746807) (xy 374.093188 -253.793081) (xy 374.109236 -253.842474)
			(xy 374.117361 -253.893769) (xy 374.11787 -253.919736) (xy 374.117361 -253.945703) (xy 374.397271 -253.945703)
			(xy 374.397271 -253.893769) (xy 374.405396 -253.842474) (xy 374.421444 -253.793081) (xy 374.445022 -253.746807)
			(xy 374.475548 -253.704791) (xy 374.512271 -253.668068) (xy 374.554287 -253.637542) (xy 374.600561 -253.613964)
			(xy 374.649954 -253.597916) (xy 374.701249 -253.589791) (xy 374.753183 -253.589791) (xy 374.804478 -253.597916)
			(xy 374.853871 -253.613964) (xy 374.900145 -253.637542) (xy 374.942161 -253.668068) (xy 374.978884 -253.704791)
			(xy 375.00941 -253.746807) (xy 375.032988 -253.793081) (xy 375.049036 -253.842474) (xy 375.057161 -253.893769)
			(xy 375.05767 -253.919736) (xy 375.057161 -253.945703) (xy 375.049036 -253.996998) (xy 375.032988 -254.046391)
			(xy 375.00941 -254.092665) (xy 374.978884 -254.134681) (xy 374.942161 -254.171404) (xy 374.900145 -254.20193)
			(xy 374.853871 -254.225508) (xy 374.804478 -254.241556) (xy 374.753183 -254.249681) (xy 374.701249 -254.249681)
			(xy 374.649954 -254.241556) (xy 374.600561 -254.225508) (xy 374.554287 -254.20193) (xy 374.512271 -254.171404)
			(xy 374.475548 -254.134681) (xy 374.445022 -254.092665) (xy 374.421444 -254.046391) (xy 374.405396 -253.996998)
			(xy 374.397271 -253.945703) (xy 374.117361 -253.945703) (xy 374.109236 -253.996998) (xy 374.093188 -254.046391)
			(xy 374.06961 -254.092665) (xy 374.039084 -254.134681) (xy 374.002361 -254.171404) (xy 373.960345 -254.20193)
			(xy 373.914071 -254.225508) (xy 373.864678 -254.241556) (xy 373.813383 -254.249681) (xy 373.761449 -254.249681)
			(xy 373.710154 -254.241556) (xy 373.660761 -254.225508) (xy 373.614487 -254.20193) (xy 373.572471 -254.171404)
			(xy 373.535748 -254.134681) (xy 373.505222 -254.092665) (xy 373.481644 -254.046391) (xy 373.465596 -253.996998)
			(xy 373.457471 -253.945703) (xy 373.177561 -253.945703) (xy 373.169436 -253.996998) (xy 373.153388 -254.046391)
			(xy 373.12981 -254.092665) (xy 373.099284 -254.134681) (xy 373.062561 -254.171404) (xy 373.020545 -254.20193)
			(xy 372.974271 -254.225508) (xy 372.924878 -254.241556) (xy 372.873583 -254.249681) (xy 372.821649 -254.249681)
			(xy 372.770354 -254.241556) (xy 372.720961 -254.225508) (xy 372.674687 -254.20193) (xy 372.632671 -254.171404)
			(xy 372.595948 -254.134681) (xy 372.565422 -254.092665) (xy 372.541844 -254.046391) (xy 372.525796 -253.996998)
			(xy 372.517671 -253.945703) (xy 372.237761 -253.945703) (xy 372.229636 -253.996998) (xy 372.213588 -254.046391)
			(xy 372.19001 -254.092665) (xy 372.159484 -254.134681) (xy 372.122761 -254.171404) (xy 372.080745 -254.20193)
			(xy 372.034471 -254.225508) (xy 371.985078 -254.241556) (xy 371.933783 -254.249681) (xy 371.881849 -254.249681)
			(xy 371.830554 -254.241556) (xy 371.781161 -254.225508) (xy 371.734887 -254.20193) (xy 371.692871 -254.171404)
			(xy 371.656148 -254.134681) (xy 371.625622 -254.092665) (xy 371.602044 -254.046391) (xy 371.585996 -253.996998)
			(xy 371.577871 -253.945703) (xy 371.297707 -253.945703) (xy 371.289582 -253.996998) (xy 371.273534 -254.046391)
			(xy 371.249956 -254.092665) (xy 371.21943 -254.134681) (xy 371.182707 -254.171404) (xy 371.140691 -254.20193)
			(xy 371.094417 -254.225508) (xy 371.045024 -254.241556) (xy 370.993729 -254.249681) (xy 370.941795 -254.249681)
			(xy 370.8905 -254.241556) (xy 370.841107 -254.225508) (xy 370.794833 -254.20193) (xy 370.752817 -254.171404)
			(xy 370.716094 -254.134681) (xy 370.685568 -254.092665) (xy 370.66199 -254.046391) (xy 370.645942 -253.996998)
			(xy 370.637817 -253.945703) (xy 370.358161 -253.945703) (xy 370.350036 -253.996998) (xy 370.333988 -254.046391)
			(xy 370.31041 -254.092665) (xy 370.279884 -254.134681) (xy 370.243161 -254.171404) (xy 370.201145 -254.20193)
			(xy 370.154871 -254.225508) (xy 370.105478 -254.241556) (xy 370.054183 -254.249681) (xy 370.002249 -254.249681)
			(xy 369.950954 -254.241556) (xy 369.901561 -254.225508) (xy 369.855287 -254.20193) (xy 369.813271 -254.171404)
			(xy 369.776548 -254.134681) (xy 369.746022 -254.092665) (xy 369.722444 -254.046391) (xy 369.706396 -253.996998)
			(xy 369.698271 -253.945703) (xy 367.99864 -253.945703) (xy 368.006311 -253.994137) (xy 368.006311 -254.046063)
			(xy 367.998188 -254.09735) (xy 367.982143 -254.146735) (xy 367.958571 -254.193002) (xy 367.928051 -254.235012)
			(xy 367.891335 -254.271731) (xy 367.849328 -254.302255) (xy 367.803063 -254.325832) (xy 367.753679 -254.341881)
			(xy 367.702393 -254.350009) (xy 367.67643 -254.35052) (xy 367.649132 -254.349973) (xy 367.595279 -254.340995)
			(xy 367.543637 -254.323279) (xy 367.495613 -254.297307) (xy 367.452517 -254.263789) (xy 367.433606 -254.244094)
			(xy 367.423773 -254.234114) (xy 367.399889 -254.219488) (xy 367.372933 -254.211889) (xy 367.344927 -254.211889)
			(xy 367.317971 -254.219488) (xy 367.294087 -254.234114) (xy 367.284254 -254.244094) (xy 367.265325 -254.263769)
			(xy 367.222231 -254.297283) (xy 367.174211 -254.323253) (xy 367.122574 -254.340971) (xy 367.068726 -254.349955)
			(xy 367.04143 -254.35052) (xy 367.01685 -254.350053) (xy 366.96823 -254.34278) (xy 366.921223 -254.328389)
			(xy 366.876865 -254.307199) (xy 366.836132 -254.279675) (xy 366.799922 -254.246424) (xy 366.784128 -254.227584)
			(xy 366.774288 -254.216247) (xy 366.749462 -254.199393) (xy 366.720816 -254.190462) (xy 366.690811 -254.190221)
			(xy 366.662025 -254.198691) (xy 366.636931 -254.215143) (xy 366.626902 -254.226314) (xy 366.611106 -254.244596)
			(xy 366.57514 -254.276855) (xy 366.534858 -254.30353) (xy 366.491119 -254.324051) (xy 366.444857 -254.33798)
			(xy 366.397059 -254.345019) (xy 366.372902 -254.34544) (xy 366.347042 -254.344929) (xy 366.295951 -254.336883)
			(xy 366.246738 -254.320974) (xy 366.200606 -254.297588) (xy 366.158683 -254.267299) (xy 366.139984 -254.249428)
			(xy 366.130269 -254.240383) (xy 366.10726 -254.227171) (xy 366.081623 -254.220334) (xy 366.055089 -254.220334)
			(xy 366.029452 -254.227171) (xy 366.006443 -254.240383) (xy 365.996728 -254.249428) (xy 365.978041 -254.267311)
			(xy 365.936109 -254.297591) (xy 365.889974 -254.320972) (xy 365.840761 -254.336884) (xy 365.789671 -254.344939)
			(xy 365.76381 -254.34544) (xy 365.737484 -254.344881) (xy 365.685499 -254.336529) (xy 365.635493 -254.32005)
			(xy 365.588727 -254.29586) (xy 365.546382 -254.26457) (xy 365.52759 -254.246126) (xy 365.517765 -254.236668)
			(xy 365.494181 -254.222983) (xy 365.46782 -254.216016) (xy 365.440554 -254.216262) (xy 365.414323 -254.223703)
			(xy 365.390989 -254.23781) (xy 365.381286 -254.247396) (xy 365.362452 -254.266539) (xy 365.319693 -254.299025)
			(xy 365.272244 -254.324169) (xy 365.221353 -254.341309) (xy 365.16836 -254.349994) (xy 365.14151 -254.35052)
			(xy 365.115538 -254.350106) (xy 365.064232 -254.341981) (xy 365.014829 -254.325931) (xy 364.968545 -254.302349)
			(xy 364.92652 -254.271817) (xy 364.889789 -254.235087) (xy 364.859256 -254.193063) (xy 364.835673 -254.14678)
			(xy 364.819621 -254.097378) (xy 364.811495 -254.046072) (xy 364.704369 -254.046072) (xy 364.69625 -254.097328)
			(xy 364.680202 -254.146721) (xy 364.656624 -254.192995) (xy 364.626098 -254.235011) (xy 364.589375 -254.271734)
			(xy 364.547359 -254.30226) (xy 364.501085 -254.325838) (xy 364.451692 -254.341886) (xy 364.400397 -254.350011)
			(xy 364.348463 -254.350011) (xy 364.297168 -254.341886) (xy 364.247775 -254.325838) (xy 364.201501 -254.30226)
			(xy 364.159485 -254.271734) (xy 364.122762 -254.235011) (xy 364.092236 -254.192995) (xy 364.068658 -254.146721)
			(xy 364.05261 -254.097328) (xy 364.044485 -254.046033) (xy 363.407311 -254.046033) (xy 363.412585 -254.057084)
			(xy 363.426934 -254.103994) (xy 363.434185 -254.15251) (xy 363.43463 -254.177038) (xy 363.43463 -254.177292)
			(xy 363.434164 -254.203262) (xy 363.426039 -254.254563) (xy 363.409989 -254.303962) (xy 363.386408 -254.350241)
			(xy 363.355878 -254.392261) (xy 363.319149 -254.428988) (xy 363.277127 -254.459517) (xy 363.230847 -254.483095)
			(xy 363.181448 -254.499143) (xy 363.130146 -254.507265) (xy 363.104176 -254.507746) (xy 363.078213 -254.507288)
			(xy 363.02693 -254.499136) (xy 362.977552 -254.483065) (xy 362.931293 -254.459473) (xy 362.889292 -254.428939)
			(xy 362.852581 -254.392215) (xy 362.822062 -254.350202) (xy 362.798487 -254.303935) (xy 362.789978 -254.2794)
			(xy 362.78511 -254.265835) (xy 362.768933 -254.241998) (xy 362.746733 -254.223637) (xy 362.720284 -254.212218)
			(xy 362.691696 -254.208654) (xy 362.663253 -254.213227) (xy 362.650024 -254.218948) (xy 362.628021 -254.228798)
			(xy 362.581863 -254.2427) (xy 362.534173 -254.249739) (xy 362.51007 -254.25019) (xy 362.509562 -254.25019)
			(xy 362.4836 -254.249606) (xy 362.432315 -254.241478) (xy 362.382933 -254.225428) (xy 362.336669 -254.20185)
			(xy 362.294663 -254.171327) (xy 362.257948 -254.134608) (xy 362.22743 -254.092599) (xy 362.203858 -254.046332)
			(xy 362.187813 -253.996948) (xy 362.179691 -253.945662) (xy 361.899708 -253.945662) (xy 361.899707 -253.945703)
			(xy 361.891582 -253.996998) (xy 361.875534 -254.046391) (xy 361.851956 -254.092665) (xy 361.82143 -254.134681)
			(xy 361.784707 -254.171404) (xy 361.742691 -254.20193) (xy 361.696417 -254.225508) (xy 361.647024 -254.241556)
			(xy 361.595729 -254.249681) (xy 361.543795 -254.249681) (xy 361.4925 -254.241556) (xy 361.443107 -254.225508)
			(xy 361.396833 -254.20193) (xy 361.354817 -254.171404) (xy 361.318094 -254.134681) (xy 361.287568 -254.092665)
			(xy 361.26399 -254.046391) (xy 361.247942 -253.996998) (xy 361.239817 -253.945703) (xy 360.959907 -253.945703)
			(xy 360.951782 -253.996998) (xy 360.935734 -254.046391) (xy 360.912156 -254.092665) (xy 360.88163 -254.134681)
			(xy 360.844907 -254.171404) (xy 360.802891 -254.20193) (xy 360.756617 -254.225508) (xy 360.707224 -254.241556)
			(xy 360.655929 -254.249681) (xy 360.603995 -254.249681) (xy 360.5527 -254.241556) (xy 360.503307 -254.225508)
			(xy 360.457033 -254.20193) (xy 360.415017 -254.171404) (xy 360.378294 -254.134681) (xy 360.347768 -254.092665)
			(xy 360.32419 -254.046391) (xy 360.308142 -253.996998) (xy 360.300017 -253.945703) (xy 360.020107 -253.945703)
			(xy 360.011982 -253.996998) (xy 359.995934 -254.046391) (xy 359.972356 -254.092665) (xy 359.94183 -254.134681)
			(xy 359.905107 -254.171404) (xy 359.863091 -254.20193) (xy 359.816817 -254.225508) (xy 359.767424 -254.241556)
			(xy 359.716129 -254.249681) (xy 359.664195 -254.249681) (xy 359.6129 -254.241556) (xy 359.563507 -254.225508)
			(xy 359.517233 -254.20193) (xy 359.475217 -254.171404) (xy 359.438494 -254.134681) (xy 359.407968 -254.092665)
			(xy 359.38439 -254.046391) (xy 359.368342 -253.996998) (xy 359.360217 -253.945703) (xy 359.080561 -253.945703)
			(xy 359.072436 -253.996998) (xy 359.056388 -254.046391) (xy 359.03281 -254.092665) (xy 359.002284 -254.134681)
			(xy 358.965561 -254.171404) (xy 358.923545 -254.20193) (xy 358.877271 -254.225508) (xy 358.827878 -254.241556)
			(xy 358.776583 -254.249681) (xy 358.724649 -254.249681) (xy 358.673354 -254.241556) (xy 358.623961 -254.225508)
			(xy 358.577687 -254.20193) (xy 358.535671 -254.171404) (xy 358.498948 -254.134681) (xy 358.468422 -254.092665)
			(xy 358.444844 -254.046391) (xy 358.428796 -253.996998) (xy 358.420671 -253.945703) (xy 358.140507 -253.945703)
			(xy 358.132382 -253.996998) (xy 358.116334 -254.046391) (xy 358.092756 -254.092665) (xy 358.06223 -254.134681)
			(xy 358.025507 -254.171404) (xy 357.983491 -254.20193) (xy 357.937217 -254.225508) (xy 357.887824 -254.241556)
			(xy 357.836529 -254.249681) (xy 357.784595 -254.249681) (xy 357.7333 -254.241556) (xy 357.683907 -254.225508)
			(xy 357.637633 -254.20193) (xy 357.595617 -254.171404) (xy 357.558894 -254.134681) (xy 357.528368 -254.092665)
			(xy 357.50479 -254.046391) (xy 357.488742 -253.996998) (xy 357.480617 -253.945703) (xy 356.950367 -253.945703)
			(xy 356.950518 -253.954026) (xy 356.950518 -253.95428) (xy 356.950009 -253.980247) (xy 356.941884 -254.031542)
			(xy 356.925836 -254.080935) (xy 356.902258 -254.127209) (xy 356.871732 -254.169225) (xy 356.835009 -254.205948)
			(xy 356.792993 -254.236474) (xy 356.746719 -254.260052) (xy 356.697326 -254.2761) (xy 356.646031 -254.284225)
			(xy 356.594097 -254.284225) (xy 356.542802 -254.2761) (xy 356.493409 -254.260052) (xy 356.447135 -254.236474)
			(xy 356.405119 -254.205948) (xy 356.368396 -254.169225) (xy 356.33787 -254.127209) (xy 356.314292 -254.080935)
			(xy 356.298244 -254.031542) (xy 356.290119 -253.980247) (xy 356.28961 -253.95428) (xy 356.28961 -253.954026)
			(xy 356.290075 -253.9295) (xy 356.297334 -253.880987) (xy 356.311682 -253.83408) (xy 356.332805 -253.789808)
			(xy 356.360237 -253.749144) (xy 356.376478 -253.73076) (xy 356.386301 -253.719286) (xy 356.399312 -253.692043)
			(xy 356.403776 -253.662185) (xy 356.399303 -253.632328) (xy 356.386284 -253.605089) (xy 356.376478 -253.5936)
			(xy 356.36021 -253.575238) (xy 356.332768 -253.534573) (xy 356.311643 -253.490297) (xy 356.297299 -253.443383)
			(xy 356.290053 -253.394863) (xy 356.28961 -253.370334) (xy 356.28961 -253.37008) (xy 356.29002 -253.346165)
			(xy 356.296924 -253.298837) (xy 356.310583 -253.253) (xy 356.330713 -253.209613) (xy 356.356892 -253.169584)
			(xy 356.372414 -253.151386) (xy 356.380944 -253.141003) (xy 356.392821 -253.116913) (xy 356.398005 -253.090558)
			(xy 356.396137 -253.063764) (xy 356.387347 -253.038384) (xy 356.372242 -253.016174) (xy 356.351868 -252.998672)
			(xy 356.327635 -252.987089) (xy 356.314502 -252.984254) (xy 356.289461 -252.979182) (xy 356.241205 -252.962404)
			(xy 356.196105 -252.9384) (xy 356.155237 -252.907741) (xy 356.119575 -252.871158) (xy 356.089967 -252.829523)
			(xy 356.067119 -252.783827) (xy 356.051577 -252.735159) (xy 356.043709 -252.684679) (xy 356.04323 -252.659134)
			(xy 351.134852 -252.659134) (xy 351.144147 -252.678616) (xy 351.158489 -252.72553) (xy 351.165734 -252.774051)
			(xy 351.166176 -252.79858) (xy 351.166176 -252.798834) (xy 351.165667 -252.824801) (xy 351.157542 -252.876096)
			(xy 351.141494 -252.925489) (xy 351.117916 -252.971763) (xy 351.08739 -253.013779) (xy 351.050667 -253.050502)
			(xy 351.008651 -253.081028) (xy 350.962377 -253.104606) (xy 350.912984 -253.120654) (xy 350.861689 -253.128779)
			(xy 350.809755 -253.128779) (xy 350.75846 -253.120654) (xy 350.709067 -253.104606) (xy 350.662793 -253.081028)
			(xy 350.620777 -253.050502) (xy 350.584054 -253.013779) (xy 350.553528 -252.971763) (xy 350.52995 -252.925489)
			(xy 350.513902 -252.876096) (xy 350.505777 -252.824801) (xy 350.505268 -252.798834) (xy 343.366019 -252.798834)
			(xy 343.370063 -252.800148) (xy 343.416337 -252.823726) (xy 343.458353 -252.854252) (xy 343.495076 -252.890975)
			(xy 343.525602 -252.932991) (xy 343.54918 -252.979265) (xy 343.565228 -253.028658) (xy 343.573353 -253.079953)
			(xy 343.573862 -253.10592) (xy 343.573353 -253.131887) (xy 343.565228 -253.183182) (xy 343.54918 -253.232575)
			(xy 343.525602 -253.278849) (xy 343.495076 -253.320865) (xy 343.458353 -253.357588) (xy 343.416337 -253.388114)
			(xy 343.370063 -253.411692) (xy 343.32067 -253.42774) (xy 343.269375 -253.435865) (xy 343.217441 -253.435865)
			(xy 343.166146 -253.42774) (xy 343.116753 -253.411692) (xy 343.070479 -253.388114) (xy 343.028463 -253.357588)
			(xy 342.99174 -253.320865) (xy 342.961214 -253.278849) (xy 342.937636 -253.232575) (xy 342.921588 -253.183182)
			(xy 342.913463 -253.131887) (xy 342.138703 -253.131887) (xy 341.877396 -253.393194) (xy 341.870679 -253.400431)
			(xy 341.863077 -253.418636) (xy 341.862664 -253.4285) (xy 341.862664 -253.547372) (xy 341.863248 -253.558222)
			(xy 341.8724 -253.577903) (xy 341.888923 -253.591979) (xy 341.89924 -253.595378) (xy 341.902796 -253.59614)
			(xy 341.927194 -253.601784) (xy 341.974056 -253.619435) (xy 342.017722 -253.643949) (xy 342.057193 -253.674766)
			(xy 342.091567 -253.71118) (xy 342.12006 -253.75236) (xy 342.142019 -253.797365) (xy 342.156943 -253.845165)
			(xy 342.164491 -253.894669) (xy 342.16449 -253.944746) (xy 342.164344 -253.945703) (xy 342.443817 -253.945703)
			(xy 342.443817 -253.893769) (xy 342.451942 -253.842474) (xy 342.46799 -253.793081) (xy 342.491568 -253.746807)
			(xy 342.522094 -253.704791) (xy 342.558817 -253.668068) (xy 342.600833 -253.637542) (xy 342.647107 -253.613964)
			(xy 342.6965 -253.597916) (xy 342.747795 -253.589791) (xy 342.799729 -253.589791) (xy 342.851024 -253.597916)
			(xy 342.900417 -253.613964) (xy 342.946691 -253.637542) (xy 342.988707 -253.668068) (xy 343.02543 -253.704791)
			(xy 343.055956 -253.746807) (xy 343.079534 -253.793081) (xy 343.095582 -253.842474) (xy 343.103707 -253.893769)
			(xy 343.104216 -253.919736) (xy 343.103707 -253.945703) (xy 343.383871 -253.945703) (xy 343.383871 -253.893769)
			(xy 343.391996 -253.842474) (xy 343.408044 -253.793081) (xy 343.431622 -253.746807) (xy 343.462148 -253.704791)
			(xy 343.498871 -253.668068) (xy 343.540887 -253.637542) (xy 343.587161 -253.613964) (xy 343.636554 -253.597916)
			(xy 343.687849 -253.589791) (xy 343.739783 -253.589791) (xy 343.791078 -253.597916) (xy 343.840471 -253.613964)
			(xy 343.886745 -253.637542) (xy 343.928761 -253.668068) (xy 343.965484 -253.704791) (xy 343.99601 -253.746807)
			(xy 344.019588 -253.793081) (xy 344.035636 -253.842474) (xy 344.043761 -253.893769) (xy 344.04427 -253.919736)
			(xy 344.043761 -253.945703) (xy 344.323671 -253.945703) (xy 344.323671 -253.893769) (xy 344.331796 -253.842474)
			(xy 344.347844 -253.793081) (xy 344.371422 -253.746807) (xy 344.401948 -253.704791) (xy 344.438671 -253.668068)
			(xy 344.480687 -253.637542) (xy 344.526961 -253.613964) (xy 344.576354 -253.597916) (xy 344.627649 -253.589791)
			(xy 344.679583 -253.589791) (xy 344.730878 -253.597916) (xy 344.780271 -253.613964) (xy 344.826545 -253.637542)
			(xy 344.868561 -253.668068) (xy 344.905284 -253.704791) (xy 344.93581 -253.746807) (xy 344.959388 -253.793081)
			(xy 344.975436 -253.842474) (xy 344.983561 -253.893769) (xy 344.98407 -253.919736) (xy 344.983561 -253.945703)
			(xy 345.263471 -253.945703) (xy 345.263471 -253.893769) (xy 345.271596 -253.842474) (xy 345.287644 -253.793081)
			(xy 345.311222 -253.746807) (xy 345.341748 -253.704791) (xy 345.378471 -253.668068) (xy 345.420487 -253.637542)
			(xy 345.466761 -253.613964) (xy 345.516154 -253.597916) (xy 345.567449 -253.589791) (xy 345.619383 -253.589791)
			(xy 345.670678 -253.597916) (xy 345.720071 -253.613964) (xy 345.766345 -253.637542) (xy 345.808361 -253.668068)
			(xy 345.845084 -253.704791) (xy 345.87561 -253.746807) (xy 345.899188 -253.793081) (xy 345.915236 -253.842474)
			(xy 345.923361 -253.893769) (xy 345.92387 -253.919736) (xy 345.923361 -253.945703) (xy 346.203271 -253.945703)
			(xy 346.203271 -253.893769) (xy 346.211396 -253.842474) (xy 346.227444 -253.793081) (xy 346.251022 -253.746807)
			(xy 346.281548 -253.704791) (xy 346.318271 -253.668068) (xy 346.360287 -253.637542) (xy 346.406561 -253.613964)
			(xy 346.455954 -253.597916) (xy 346.507249 -253.589791) (xy 346.559183 -253.589791) (xy 346.610478 -253.597916)
			(xy 346.659871 -253.613964) (xy 346.706145 -253.637542) (xy 346.748161 -253.668068) (xy 346.784884 -253.704791)
			(xy 346.81541 -253.746807) (xy 346.838988 -253.793081) (xy 346.855036 -253.842474) (xy 346.863161 -253.893769)
			(xy 346.86367 -253.919736) (xy 346.863161 -253.945703) (xy 347.143071 -253.945703) (xy 347.143071 -253.893769)
			(xy 347.151196 -253.842474) (xy 347.167244 -253.793081) (xy 347.190822 -253.746807) (xy 347.221348 -253.704791)
			(xy 347.258071 -253.668068) (xy 347.300087 -253.637542) (xy 347.346361 -253.613964) (xy 347.395754 -253.597916)
			(xy 347.447049 -253.589791) (xy 347.498983 -253.589791) (xy 347.550278 -253.597916) (xy 347.599671 -253.613964)
			(xy 347.645945 -253.637542) (xy 347.687961 -253.668068) (xy 347.724684 -253.704791) (xy 347.75521 -253.746807)
			(xy 347.778788 -253.793081) (xy 347.794836 -253.842474) (xy 347.802961 -253.893769) (xy 347.80347 -253.919736)
			(xy 347.802961 -253.945703) (xy 348.082871 -253.945703) (xy 348.082871 -253.893769) (xy 348.090996 -253.842474)
			(xy 348.107044 -253.793081) (xy 348.130622 -253.746807) (xy 348.161148 -253.704791) (xy 348.197871 -253.668068)
			(xy 348.239887 -253.637542) (xy 348.286161 -253.613964) (xy 348.335554 -253.597916) (xy 348.386849 -253.589791)
			(xy 348.438783 -253.589791) (xy 348.490078 -253.597916) (xy 348.539471 -253.613964) (xy 348.585745 -253.637542)
			(xy 348.627761 -253.668068) (xy 348.664484 -253.704791) (xy 348.69501 -253.746807) (xy 348.718588 -253.793081)
			(xy 348.734636 -253.842474) (xy 348.742761 -253.893769) (xy 348.74327 -253.919736) (xy 348.742761 -253.945703)
			(xy 349.022671 -253.945703) (xy 349.022671 -253.893769) (xy 349.030796 -253.842474) (xy 349.046844 -253.793081)
			(xy 349.070422 -253.746807) (xy 349.100948 -253.704791) (xy 349.137671 -253.668068) (xy 349.179687 -253.637542)
			(xy 349.225961 -253.613964) (xy 349.275354 -253.597916) (xy 349.326649 -253.589791) (xy 349.378583 -253.589791)
			(xy 349.429878 -253.597916) (xy 349.479271 -253.613964) (xy 349.525545 -253.637542) (xy 349.567561 -253.668068)
			(xy 349.604284 -253.704791) (xy 349.63481 -253.746807) (xy 349.658388 -253.793081) (xy 349.674436 -253.842474)
			(xy 349.682561 -253.893769) (xy 349.68307 -253.919736) (xy 349.682561 -253.945703) (xy 349.962471 -253.945703)
			(xy 349.962471 -253.893769) (xy 349.970596 -253.842474) (xy 349.986644 -253.793081) (xy 350.010222 -253.746807)
			(xy 350.040748 -253.704791) (xy 350.077471 -253.668068) (xy 350.119487 -253.637542) (xy 350.165761 -253.613964)
			(xy 350.215154 -253.597916) (xy 350.266449 -253.589791) (xy 350.318383 -253.589791) (xy 350.369678 -253.597916)
			(xy 350.419071 -253.613964) (xy 350.465345 -253.637542) (xy 350.507361 -253.668068) (xy 350.544084 -253.704791)
			(xy 350.57461 -253.746807) (xy 350.598188 -253.793081) (xy 350.614236 -253.842474) (xy 350.622361 -253.893769)
			(xy 350.62287 -253.919736) (xy 350.622361 -253.945703) (xy 350.614236 -253.996998) (xy 350.598292 -254.046072)
			(xy 351.771395 -254.046072) (xy 351.771395 -253.994128) (xy 351.779521 -253.942823) (xy 351.795573 -253.893421)
			(xy 351.819155 -253.847138) (xy 351.849687 -253.805115) (xy 351.886418 -253.768385) (xy 351.928442 -253.737853)
			(xy 351.974725 -253.714271) (xy 352.024127 -253.69822) (xy 352.075432 -253.690095) (xy 352.101404 -253.689612)
			(xy 352.101658 -253.689612) (xy 352.126186 -253.690026) (xy 352.174701 -253.697297) (xy 352.221608 -253.711658)
			(xy 352.265879 -253.732791) (xy 352.306542 -253.760234) (xy 352.324924 -253.77648) (xy 352.336413 -253.786283)
			(xy 352.36365 -253.799297) (xy 352.393504 -253.803765) (xy 352.423358 -253.799297) (xy 352.450595 -253.786283)
			(xy 352.462084 -253.77648) (xy 352.480453 -253.760219) (xy 352.521116 -253.732777) (xy 352.565391 -253.71165)
			(xy 352.612303 -253.697305) (xy 352.660822 -253.690056) (xy 352.68535 -253.689612) (xy 352.685604 -253.689612)
			(xy 352.712061 -253.69015) (xy 352.764302 -253.69857) (xy 352.814532 -253.715208) (xy 352.861468 -253.739641)
			(xy 352.903909 -253.771242) (xy 352.940771 -253.809205) (xy 352.956368 -253.830582) (xy 352.964808 -253.841825)
			(xy 352.986604 -253.859562) (xy 353.012411 -253.870681) (xy 353.040273 -253.874339) (xy 353.068076 -253.870259)
			(xy 353.093712 -253.85875) (xy 353.115237 -253.840685) (xy 353.1235 -253.829312) (xy 353.139032 -253.807419)
			(xy 353.17596 -253.768465) (xy 353.218701 -253.735996) (xy 353.266129 -253.710865) (xy 353.316998 -253.693735)
			(xy 353.369966 -253.685056) (xy 353.396804 -253.684532) (xy 353.422558 -253.685005) (xy 353.473445 -253.692987)
			(xy 353.522475 -253.708771) (xy 353.568461 -253.731976) (xy 353.610287 -253.762038) (xy 353.62896 -253.779782)
			(xy 353.63865 -253.788775) (xy 353.661582 -253.801907) (xy 353.687121 -253.808702) (xy 353.713547 -253.808702)
			(xy 353.739086 -253.801907) (xy 353.762018 -253.788775) (xy 353.771708 -253.779782) (xy 353.790381 -253.762041)
			(xy 353.832216 -253.731997) (xy 353.878203 -253.708802) (xy 353.92723 -253.693018) (xy 353.978111 -253.685027)
			(xy 354.003864 -253.684532) (xy 354.028126 -253.684946) (xy 354.076127 -253.692055) (xy 354.12257 -253.706111)
			(xy 354.166458 -253.726811) (xy 354.206844 -253.753709) (xy 354.24286 -253.786227) (xy 354.258626 -253.804674)
			(xy 354.268657 -253.815954) (xy 354.293798 -253.832628) (xy 354.322716 -253.841221) (xy 354.352883 -253.840982)
			(xy 354.381661 -253.831932) (xy 354.406534 -253.814862) (xy 354.41636 -253.803404) (xy 354.432151 -253.784425)
			(xy 354.468397 -253.750903) (xy 354.509226 -253.723144) (xy 354.553729 -253.701768) (xy 354.600916 -253.687248)
			(xy 354.649739 -253.679908) (xy 354.674424 -253.679452) (xy 354.701562 -253.679997) (xy 354.755106 -253.688875)
			(xy 354.806484 -253.706374) (xy 354.854316 -253.732024) (xy 354.897321 -253.765137) (xy 354.916232 -253.784608)
			(xy 354.925946 -253.794396) (xy 354.949457 -253.808792) (xy 354.97596 -253.816382) (xy 355.003527 -253.816615)
			(xy 355.030154 -253.809474) (xy 355.053905 -253.795478) (xy 355.063806 -253.785878) (xy 355.08263 -253.767084)
			(xy 355.125158 -253.735141) (xy 355.172257 -253.710432) (xy 355.22271 -253.693595) (xy 355.27521 -253.685066)
			(xy 355.301804 -253.684532) (xy 355.32777 -253.68507) (xy 355.379062 -253.693194) (xy 355.428452 -253.709242)
			(xy 355.474724 -253.732819) (xy 355.516737 -253.763344) (xy 355.553458 -253.800066) (xy 355.583983 -253.84208)
			(xy 355.607559 -253.888351) (xy 355.623607 -253.937742) (xy 355.631731 -253.989034) (xy 355.631731 -254.040966)
			(xy 355.623607 -254.092258) (xy 355.607559 -254.141649) (xy 355.583983 -254.18792) (xy 355.553458 -254.229934)
			(xy 355.516737 -254.266656) (xy 355.474724 -254.297181) (xy 355.428452 -254.320758) (xy 355.379062 -254.336806)
			(xy 355.32777 -254.34493) (xy 355.301804 -254.34544) (xy 355.274667 -254.34488) (xy 355.221123 -254.336005)
			(xy 355.169745 -254.31851) (xy 355.121913 -254.292864) (xy 355.078907 -254.259754) (xy 355.059996 -254.240284)
			(xy 355.050255 -254.230524) (xy 355.026752 -254.216128) (xy 355.000256 -254.208535) (xy 354.972695 -254.208297)
			(xy 354.946073 -254.215431) (xy 354.922323 -254.229418) (xy 354.912422 -254.239014) (xy 354.89363 -254.257841)
			(xy 354.851094 -254.28978) (xy 354.803986 -254.314484) (xy 354.753526 -254.331313) (xy 354.70102 -254.339832)
			(xy 354.674424 -254.34036) (xy 354.650164 -254.339887) (xy 354.602166 -254.332791) (xy 354.555723 -254.318747)
			(xy 354.511835 -254.298058) (xy 354.471448 -254.27117) (xy 354.435429 -254.23866) (xy 354.419662 -254.220218)
			(xy 354.409643 -254.208927) (xy 354.384498 -254.192254) (xy 354.355578 -254.183663) (xy 354.325409 -254.183904)
			(xy 354.296629 -254.192957) (xy 354.271754 -254.210029) (xy 354.261928 -254.221488) (xy 354.246141 -254.240472)
			(xy 354.209895 -254.273994) (xy 354.169065 -254.301751) (xy 354.124561 -254.323127) (xy 354.077373 -254.337646)
			(xy 354.02855 -254.344984) (xy 354.003864 -254.34544) (xy 353.97811 -254.344966) (xy 353.927224 -254.336982)
			(xy 353.878194 -254.321197) (xy 353.832209 -254.297993) (xy 353.790382 -254.267933) (xy 353.771708 -254.25019)
			(xy 353.762018 -254.241197) (xy 353.739086 -254.228065) (xy 353.713547 -254.22127) (xy 353.687121 -254.22127)
			(xy 353.661582 -254.228065) (xy 353.63865 -254.241197) (xy 353.62896 -254.25019) (xy 353.610296 -254.267941)
			(xy 353.56846 -254.297985) (xy 353.52247 -254.321179) (xy 353.473441 -254.33696) (xy 353.422557 -254.344948)
			(xy 353.396804 -254.34544) (xy 353.370346 -254.344916) (xy 353.318104 -254.336497) (xy 353.267872 -254.319857)
			(xy 353.220936 -254.295422) (xy 353.178495 -254.263816) (xy 353.141635 -254.225849) (xy 353.12604 -254.20447)
			(xy 353.117587 -254.19324) (xy 353.095792 -254.175512) (xy 353.069988 -254.164398) (xy 353.042132 -254.16074)
			(xy 353.014333 -254.164817) (xy 352.9887 -254.176318) (xy 352.967174 -254.194373) (xy 352.958908 -254.20574)
			(xy 352.943419 -254.227666) (xy 352.906484 -254.26662) (xy 352.863735 -254.299088) (xy 352.816298 -254.324214)
			(xy 352.765421 -254.341336) (xy 352.712445 -254.350003) (xy 352.685604 -254.35052) (xy 352.68535 -254.35052)
			(xy 352.660823 -254.350093) (xy 352.612309 -254.342823) (xy 352.565402 -254.328466) (xy 352.52113 -254.307335)
			(xy 352.480467 -254.279896) (xy 352.462084 -254.263652) (xy 352.450595 -254.253849) (xy 352.423358 -254.240835)
			(xy 352.393504 -254.236367) (xy 352.36365 -254.240835) (xy 352.336413 -254.253849) (xy 352.324924 -254.263652)
			(xy 352.306542 -254.279898) (xy 352.265884 -254.307345) (xy 352.221613 -254.328476) (xy 352.174703 -254.342824)
			(xy 352.126186 -254.350075) (xy 352.101658 -254.35052) (xy 352.101404 -254.35052) (xy 352.075432 -254.350105)
			(xy 352.024127 -254.34198) (xy 351.974725 -254.325929) (xy 351.928442 -254.302347) (xy 351.886418 -254.271815)
			(xy 351.849687 -254.235085) (xy 351.819155 -254.193062) (xy 351.795573 -254.146779) (xy 351.779521 -254.097377)
			(xy 351.771395 -254.046072) (xy 350.598292 -254.046072) (xy 350.598188 -254.046391) (xy 350.57461 -254.092665)
			(xy 350.544084 -254.134681) (xy 350.507361 -254.171404) (xy 350.465345 -254.20193) (xy 350.419071 -254.225508)
			(xy 350.369678 -254.241556) (xy 350.318383 -254.249681) (xy 350.266449 -254.249681) (xy 350.215154 -254.241556)
			(xy 350.165761 -254.225508) (xy 350.119487 -254.20193) (xy 350.077471 -254.171404) (xy 350.040748 -254.134681)
			(xy 350.010222 -254.092665) (xy 349.986644 -254.046391) (xy 349.970596 -253.996998) (xy 349.962471 -253.945703)
			(xy 349.682561 -253.945703) (xy 349.674436 -253.996998) (xy 349.658388 -254.046391) (xy 349.63481 -254.092665)
			(xy 349.604284 -254.134681) (xy 349.567561 -254.171404) (xy 349.525545 -254.20193) (xy 349.479271 -254.225508)
			(xy 349.429878 -254.241556) (xy 349.378583 -254.249681) (xy 349.326649 -254.249681) (xy 349.275354 -254.241556)
			(xy 349.225961 -254.225508) (xy 349.179687 -254.20193) (xy 349.137671 -254.171404) (xy 349.100948 -254.134681)
			(xy 349.070422 -254.092665) (xy 349.046844 -254.046391) (xy 349.030796 -253.996998) (xy 349.022671 -253.945703)
			(xy 348.742761 -253.945703) (xy 348.734636 -253.996998) (xy 348.718588 -254.046391) (xy 348.69501 -254.092665)
			(xy 348.664484 -254.134681) (xy 348.627761 -254.171404) (xy 348.585745 -254.20193) (xy 348.539471 -254.225508)
			(xy 348.490078 -254.241556) (xy 348.438783 -254.249681) (xy 348.386849 -254.249681) (xy 348.335554 -254.241556)
			(xy 348.286161 -254.225508) (xy 348.239887 -254.20193) (xy 348.197871 -254.171404) (xy 348.161148 -254.134681)
			(xy 348.130622 -254.092665) (xy 348.107044 -254.046391) (xy 348.090996 -253.996998) (xy 348.082871 -253.945703)
			(xy 347.802961 -253.945703) (xy 347.794836 -253.996998) (xy 347.778788 -254.046391) (xy 347.75521 -254.092665)
			(xy 347.724684 -254.134681) (xy 347.687961 -254.171404) (xy 347.645945 -254.20193) (xy 347.599671 -254.225508)
			(xy 347.550278 -254.241556) (xy 347.498983 -254.249681) (xy 347.447049 -254.249681) (xy 347.395754 -254.241556)
			(xy 347.346361 -254.225508) (xy 347.300087 -254.20193) (xy 347.258071 -254.171404) (xy 347.221348 -254.134681)
			(xy 347.190822 -254.092665) (xy 347.167244 -254.046391) (xy 347.151196 -253.996998) (xy 347.143071 -253.945703)
			(xy 346.863161 -253.945703) (xy 346.855036 -253.996998) (xy 346.838988 -254.046391) (xy 346.81541 -254.092665)
			(xy 346.784884 -254.134681) (xy 346.748161 -254.171404) (xy 346.706145 -254.20193) (xy 346.659871 -254.225508)
			(xy 346.610478 -254.241556) (xy 346.559183 -254.249681) (xy 346.507249 -254.249681) (xy 346.455954 -254.241556)
			(xy 346.406561 -254.225508) (xy 346.360287 -254.20193) (xy 346.318271 -254.171404) (xy 346.281548 -254.134681)
			(xy 346.251022 -254.092665) (xy 346.227444 -254.046391) (xy 346.211396 -253.996998) (xy 346.203271 -253.945703)
			(xy 345.923361 -253.945703) (xy 345.915236 -253.996998) (xy 345.899188 -254.046391) (xy 345.87561 -254.092665)
			(xy 345.845084 -254.134681) (xy 345.808361 -254.171404) (xy 345.766345 -254.20193) (xy 345.720071 -254.225508)
			(xy 345.670678 -254.241556) (xy 345.619383 -254.249681) (xy 345.567449 -254.249681) (xy 345.516154 -254.241556)
			(xy 345.466761 -254.225508) (xy 345.420487 -254.20193) (xy 345.378471 -254.171404) (xy 345.341748 -254.134681)
			(xy 345.311222 -254.092665) (xy 345.287644 -254.046391) (xy 345.271596 -253.996998) (xy 345.263471 -253.945703)
			(xy 344.983561 -253.945703) (xy 344.975436 -253.996998) (xy 344.959388 -254.046391) (xy 344.93581 -254.092665)
			(xy 344.905284 -254.134681) (xy 344.868561 -254.171404) (xy 344.826545 -254.20193) (xy 344.780271 -254.225508)
			(xy 344.730878 -254.241556) (xy 344.679583 -254.249681) (xy 344.627649 -254.249681) (xy 344.576354 -254.241556)
			(xy 344.526961 -254.225508) (xy 344.480687 -254.20193) (xy 344.438671 -254.171404) (xy 344.401948 -254.134681)
			(xy 344.371422 -254.092665) (xy 344.347844 -254.046391) (xy 344.331796 -253.996998) (xy 344.323671 -253.945703)
			(xy 344.043761 -253.945703) (xy 344.035636 -253.996998) (xy 344.019588 -254.046391) (xy 343.99601 -254.092665)
			(xy 343.965484 -254.134681) (xy 343.928761 -254.171404) (xy 343.886745 -254.20193) (xy 343.840471 -254.225508)
			(xy 343.791078 -254.241556) (xy 343.739783 -254.249681) (xy 343.687849 -254.249681) (xy 343.636554 -254.241556)
			(xy 343.587161 -254.225508) (xy 343.540887 -254.20193) (xy 343.498871 -254.171404) (xy 343.462148 -254.134681)
			(xy 343.431622 -254.092665) (xy 343.408044 -254.046391) (xy 343.391996 -253.996998) (xy 343.383871 -253.945703)
			(xy 343.103707 -253.945703) (xy 343.095582 -253.996998) (xy 343.079534 -254.046391) (xy 343.055956 -254.092665)
			(xy 343.02543 -254.134681) (xy 342.988707 -254.171404) (xy 342.946691 -254.20193) (xy 342.900417 -254.225508)
			(xy 342.851024 -254.241556) (xy 342.799729 -254.249681) (xy 342.747795 -254.249681) (xy 342.6965 -254.241556)
			(xy 342.647107 -254.225508) (xy 342.600833 -254.20193) (xy 342.558817 -254.171404) (xy 342.522094 -254.134681)
			(xy 342.491568 -254.092665) (xy 342.46799 -254.046391) (xy 342.451942 -253.996998) (xy 342.443817 -253.945703)
			(xy 342.164344 -253.945703) (xy 342.15694 -253.994249) (xy 342.142014 -254.042049) (xy 342.120052 -254.087053)
			(xy 342.091558 -254.128232) (xy 342.057182 -254.164644) (xy 342.017709 -254.195459) (xy 341.974042 -254.219971)
			(xy 341.92718 -254.23762) (xy 341.902796 -254.243332) (xy 341.89924 -254.244094) (xy 341.888926 -254.247515)
			(xy 341.872372 -254.261558) (xy 341.863232 -254.281247) (xy 341.862664 -254.2921) (xy 341.862664 -254.494792)
			(xy 341.867236 -254.504698) (xy 341.872824 -254.517144) (xy 341.87511 -254.522732) (xy 341.89162 -254.544068)
			(xy 341.896364 -254.547417) (xy 341.907017 -254.552029) (xy 341.912702 -254.553212) (xy 342.004904 -254.564388)
			(xy 342.015383 -254.564378) (xy 342.034929 -254.556887) (xy 342.04275 -254.54991) (xy 342.04783 -254.54483)
			(xy 342.049862 -254.542036) (xy 342.064998 -254.522735) (xy 342.100204 -254.488585) (xy 342.140232 -254.46024)
			(xy 342.184134 -254.438371) (xy 342.230872 -254.423495) (xy 342.279338 -254.415965) (xy 342.303862 -254.415544)
			(xy 342.328859 -254.416006) (xy 342.378238 -254.423821) (xy 342.425786 -254.439266) (xy 342.470333 -254.461959)
			(xy 342.510781 -254.491341) (xy 342.546134 -254.52669) (xy 342.575522 -254.567134) (xy 342.59822 -254.611678)
			(xy 342.61367 -254.659225) (xy 342.621491 -254.708603) (xy 342.621491 -254.758597) (xy 342.621345 -254.759519)
			(xy 342.913717 -254.759519) (xy 342.913717 -254.707585) (xy 342.921842 -254.65629) (xy 342.93789 -254.606897)
			(xy 342.961468 -254.560623) (xy 342.991994 -254.518607) (xy 343.028717 -254.481884) (xy 343.070733 -254.451358)
			(xy 343.117007 -254.42778) (xy 343.1664 -254.411732) (xy 343.217695 -254.403607) (xy 343.269629 -254.403607)
			(xy 343.320924 -254.411732) (xy 343.370317 -254.42778) (xy 343.416591 -254.451358) (xy 343.458607 -254.481884)
			(xy 343.49533 -254.518607) (xy 343.525856 -254.560623) (xy 343.549434 -254.606897) (xy 343.565482 -254.65629)
			(xy 343.573607 -254.707585) (xy 343.574116 -254.733552) (xy 343.573607 -254.759519) (xy 343.853517 -254.759519)
			(xy 343.853517 -254.707585) (xy 343.861642 -254.65629) (xy 343.87769 -254.606897) (xy 343.901268 -254.560623)
			(xy 343.931794 -254.518607) (xy 343.968517 -254.481884) (xy 344.010533 -254.451358) (xy 344.056807 -254.42778)
			(xy 344.1062 -254.411732) (xy 344.157495 -254.403607) (xy 344.209429 -254.403607) (xy 344.260724 -254.411732)
			(xy 344.310117 -254.42778) (xy 344.356391 -254.451358) (xy 344.398407 -254.481884) (xy 344.43513 -254.518607)
			(xy 344.465656 -254.560623) (xy 344.489234 -254.606897) (xy 344.505282 -254.65629) (xy 344.513407 -254.707585)
			(xy 344.513916 -254.733552) (xy 344.513407 -254.759519) (xy 344.793317 -254.759519) (xy 344.793317 -254.707585)
			(xy 344.801442 -254.65629) (xy 344.81749 -254.606897) (xy 344.841068 -254.560623) (xy 344.871594 -254.518607)
			(xy 344.908317 -254.481884) (xy 344.950333 -254.451358) (xy 344.996607 -254.42778) (xy 345.046 -254.411732)
			(xy 345.097295 -254.403607) (xy 345.149229 -254.403607) (xy 345.200524 -254.411732) (xy 345.249917 -254.42778)
			(xy 345.296191 -254.451358) (xy 345.338207 -254.481884) (xy 345.37493 -254.518607) (xy 345.405456 -254.560623)
			(xy 345.429034 -254.606897) (xy 345.445082 -254.65629) (xy 345.453207 -254.707585) (xy 345.453716 -254.733552)
			(xy 345.453207 -254.759519) (xy 345.733371 -254.759519) (xy 345.733371 -254.707585) (xy 345.741496 -254.65629)
			(xy 345.757544 -254.606897) (xy 345.781122 -254.560623) (xy 345.811648 -254.518607) (xy 345.848371 -254.481884)
			(xy 345.890387 -254.451358) (xy 345.936661 -254.42778) (xy 345.986054 -254.411732) (xy 346.037349 -254.403607)
			(xy 346.089283 -254.403607) (xy 346.140578 -254.411732) (xy 346.189971 -254.42778) (xy 346.236245 -254.451358)
			(xy 346.278261 -254.481884) (xy 346.314984 -254.518607) (xy 346.34551 -254.560623) (xy 346.369088 -254.606897)
			(xy 346.385136 -254.65629) (xy 346.393261 -254.707585) (xy 346.39377 -254.733552) (xy 346.393261 -254.759519)
			(xy 346.672917 -254.759519) (xy 346.672917 -254.707585) (xy 346.681042 -254.65629) (xy 346.69709 -254.606897)
			(xy 346.720668 -254.560623) (xy 346.751194 -254.518607) (xy 346.787917 -254.481884) (xy 346.829933 -254.451358)
			(xy 346.876207 -254.42778) (xy 346.9256 -254.411732) (xy 346.976895 -254.403607) (xy 347.028829 -254.403607)
			(xy 347.080124 -254.411732) (xy 347.129517 -254.42778) (xy 347.175791 -254.451358) (xy 347.217807 -254.481884)
			(xy 347.25453 -254.518607) (xy 347.285056 -254.560623) (xy 347.308634 -254.606897) (xy 347.324682 -254.65629)
			(xy 347.332807 -254.707585) (xy 347.333316 -254.733552) (xy 347.332807 -254.759519) (xy 347.612717 -254.759519)
			(xy 347.612717 -254.707585) (xy 347.620842 -254.65629) (xy 347.63689 -254.606897) (xy 347.660468 -254.560623)
			(xy 347.690994 -254.518607) (xy 347.727717 -254.481884) (xy 347.769733 -254.451358) (xy 347.816007 -254.42778)
			(xy 347.8654 -254.411732) (xy 347.916695 -254.403607) (xy 347.968629 -254.403607) (xy 348.019924 -254.411732)
			(xy 348.069317 -254.42778) (xy 348.115591 -254.451358) (xy 348.157607 -254.481884) (xy 348.19433 -254.518607)
			(xy 348.224856 -254.560623) (xy 348.248434 -254.606897) (xy 348.264482 -254.65629) (xy 348.272607 -254.707585)
			(xy 348.273116 -254.733552) (xy 348.272607 -254.759519) (xy 348.552517 -254.759519) (xy 348.552517 -254.707585)
			(xy 348.560642 -254.65629) (xy 348.57669 -254.606897) (xy 348.600268 -254.560623) (xy 348.630794 -254.518607)
			(xy 348.667517 -254.481884) (xy 348.709533 -254.451358) (xy 348.755807 -254.42778) (xy 348.8052 -254.411732)
			(xy 348.856495 -254.403607) (xy 348.908429 -254.403607) (xy 348.959724 -254.411732) (xy 349.009117 -254.42778)
			(xy 349.055391 -254.451358) (xy 349.097407 -254.481884) (xy 349.13413 -254.518607) (xy 349.164656 -254.560623)
			(xy 349.188234 -254.606897) (xy 349.204282 -254.65629) (xy 349.212407 -254.707585) (xy 349.212916 -254.733552)
			(xy 349.212407 -254.759519) (xy 349.492317 -254.759519) (xy 349.492317 -254.707585) (xy 349.500442 -254.65629)
			(xy 349.51649 -254.606897) (xy 349.540068 -254.560623) (xy 349.570594 -254.518607) (xy 349.607317 -254.481884)
			(xy 349.649333 -254.451358) (xy 349.695607 -254.42778) (xy 349.745 -254.411732) (xy 349.796295 -254.403607)
			(xy 349.848229 -254.403607) (xy 349.899524 -254.411732) (xy 349.948917 -254.42778) (xy 349.995191 -254.451358)
			(xy 350.037207 -254.481884) (xy 350.07393 -254.518607) (xy 350.104456 -254.560623) (xy 350.128034 -254.606897)
			(xy 350.144082 -254.65629) (xy 350.152207 -254.707585) (xy 350.152716 -254.733552) (xy 350.152207 -254.759519)
			(xy 357.010717 -254.759519) (xy 357.010717 -254.707585) (xy 357.018842 -254.65629) (xy 357.03489 -254.606897)
			(xy 357.058468 -254.560623) (xy 357.088994 -254.518607) (xy 357.125717 -254.481884) (xy 357.167733 -254.451358)
			(xy 357.214007 -254.42778) (xy 357.2634 -254.411732) (xy 357.314695 -254.403607) (xy 357.366629 -254.403607)
			(xy 357.417924 -254.411732) (xy 357.467317 -254.42778) (xy 357.513591 -254.451358) (xy 357.555607 -254.481884)
			(xy 357.59233 -254.518607) (xy 357.622856 -254.560623) (xy 357.646434 -254.606897) (xy 357.662482 -254.65629)
			(xy 357.670607 -254.707585) (xy 357.671116 -254.733552) (xy 357.670607 -254.759519) (xy 357.950517 -254.759519)
			(xy 357.950517 -254.707585) (xy 357.958642 -254.65629) (xy 357.97469 -254.606897) (xy 357.998268 -254.560623)
			(xy 358.028794 -254.518607) (xy 358.065517 -254.481884) (xy 358.107533 -254.451358) (xy 358.153807 -254.42778)
			(xy 358.2032 -254.411732) (xy 358.254495 -254.403607) (xy 358.306429 -254.403607) (xy 358.357724 -254.411732)
			(xy 358.407117 -254.42778) (xy 358.453391 -254.451358) (xy 358.495407 -254.481884) (xy 358.53213 -254.518607)
			(xy 358.562656 -254.560623) (xy 358.586234 -254.606897) (xy 358.602282 -254.65629) (xy 358.610407 -254.707585)
			(xy 358.610916 -254.733552) (xy 358.610407 -254.759519) (xy 358.890571 -254.759519) (xy 358.890571 -254.707585)
			(xy 358.898696 -254.65629) (xy 358.914744 -254.606897) (xy 358.938322 -254.560623) (xy 358.968848 -254.518607)
			(xy 359.005571 -254.481884) (xy 359.047587 -254.451358) (xy 359.093861 -254.42778) (xy 359.143254 -254.411732)
			(xy 359.194549 -254.403607) (xy 359.246483 -254.403607) (xy 359.297778 -254.411732) (xy 359.347171 -254.42778)
			(xy 359.393445 -254.451358) (xy 359.435461 -254.481884) (xy 359.472184 -254.518607) (xy 359.50271 -254.560623)
			(xy 359.526288 -254.606897) (xy 359.542336 -254.65629) (xy 359.550461 -254.707585) (xy 359.55097 -254.733552)
			(xy 359.550461 -254.759519) (xy 359.830371 -254.759519) (xy 359.830371 -254.707585) (xy 359.838496 -254.65629)
			(xy 359.854544 -254.606897) (xy 359.878122 -254.560623) (xy 359.908648 -254.518607) (xy 359.945371 -254.481884)
			(xy 359.987387 -254.451358) (xy 360.033661 -254.42778) (xy 360.083054 -254.411732) (xy 360.134349 -254.403607)
			(xy 360.186283 -254.403607) (xy 360.237578 -254.411732) (xy 360.286971 -254.42778) (xy 360.333245 -254.451358)
			(xy 360.375261 -254.481884) (xy 360.411984 -254.518607) (xy 360.44251 -254.560623) (xy 360.466088 -254.606897)
			(xy 360.482136 -254.65629) (xy 360.490261 -254.707585) (xy 360.49077 -254.733552) (xy 360.490261 -254.759519)
			(xy 360.769917 -254.759519) (xy 360.769917 -254.707585) (xy 360.778042 -254.65629) (xy 360.79409 -254.606897)
			(xy 360.817668 -254.560623) (xy 360.848194 -254.518607) (xy 360.884917 -254.481884) (xy 360.926933 -254.451358)
			(xy 360.973207 -254.42778) (xy 361.0226 -254.411732) (xy 361.073895 -254.403607) (xy 361.125829 -254.403607)
			(xy 361.177124 -254.411732) (xy 361.226517 -254.42778) (xy 361.272791 -254.451358) (xy 361.314807 -254.481884)
			(xy 361.35153 -254.518607) (xy 361.382056 -254.560623) (xy 361.405634 -254.606897) (xy 361.421682 -254.65629)
			(xy 361.429807 -254.707585) (xy 361.430316 -254.733552) (xy 361.429807 -254.759519) (xy 361.709971 -254.759519)
			(xy 361.709971 -254.707585) (xy 361.718096 -254.65629) (xy 361.734144 -254.606897) (xy 361.757722 -254.560623)
			(xy 361.788248 -254.518607) (xy 361.824971 -254.481884) (xy 361.866987 -254.451358) (xy 361.913261 -254.42778)
			(xy 361.962654 -254.411732) (xy 362.013949 -254.403607) (xy 362.065883 -254.403607) (xy 362.117178 -254.411732)
			(xy 362.166571 -254.42778) (xy 362.212845 -254.451358) (xy 362.254861 -254.481884) (xy 362.291584 -254.518607)
			(xy 362.32211 -254.560623) (xy 362.345688 -254.606897) (xy 362.361736 -254.65629) (xy 362.369861 -254.707585)
			(xy 362.37037 -254.733552) (xy 362.369861 -254.759519) (xy 362.361736 -254.810814) (xy 362.345688 -254.860207)
			(xy 362.32211 -254.906481) (xy 362.291584 -254.948497) (xy 362.254861 -254.98522) (xy 362.212845 -255.015746)
			(xy 362.166571 -255.039324) (xy 362.117178 -255.055372) (xy 362.065883 -255.063497) (xy 362.013949 -255.063497)
			(xy 361.962654 -255.055372) (xy 361.913261 -255.039324) (xy 361.866987 -255.015746) (xy 361.824971 -254.98522)
			(xy 361.788248 -254.948497) (xy 361.757722 -254.906481) (xy 361.734144 -254.860207) (xy 361.718096 -254.810814)
			(xy 361.709971 -254.759519) (xy 361.429807 -254.759519) (xy 361.421682 -254.810814) (xy 361.405634 -254.860207)
			(xy 361.382056 -254.906481) (xy 361.35153 -254.948497) (xy 361.314807 -254.98522) (xy 361.272791 -255.015746)
			(xy 361.226517 -255.039324) (xy 361.177124 -255.055372) (xy 361.125829 -255.063497) (xy 361.073895 -255.063497)
			(xy 361.0226 -255.055372) (xy 360.973207 -255.039324) (xy 360.926933 -255.015746) (xy 360.884917 -254.98522)
			(xy 360.848194 -254.948497) (xy 360.817668 -254.906481) (xy 360.79409 -254.860207) (xy 360.778042 -254.810814)
			(xy 360.769917 -254.759519) (xy 360.490261 -254.759519) (xy 360.482136 -254.810814) (xy 360.466088 -254.860207)
			(xy 360.44251 -254.906481) (xy 360.411984 -254.948497) (xy 360.375261 -254.98522) (xy 360.333245 -255.015746)
			(xy 360.286971 -255.039324) (xy 360.237578 -255.055372) (xy 360.186283 -255.063497) (xy 360.134349 -255.063497)
			(xy 360.083054 -255.055372) (xy 360.033661 -255.039324) (xy 359.987387 -255.015746) (xy 359.945371 -254.98522)
			(xy 359.908648 -254.948497) (xy 359.878122 -254.906481) (xy 359.854544 -254.860207) (xy 359.838496 -254.810814)
			(xy 359.830371 -254.759519) (xy 359.550461 -254.759519) (xy 359.542336 -254.810814) (xy 359.526288 -254.860207)
			(xy 359.50271 -254.906481) (xy 359.472184 -254.948497) (xy 359.435461 -254.98522) (xy 359.393445 -255.015746)
			(xy 359.347171 -255.039324) (xy 359.297778 -255.055372) (xy 359.246483 -255.063497) (xy 359.194549 -255.063497)
			(xy 359.143254 -255.055372) (xy 359.093861 -255.039324) (xy 359.047587 -255.015746) (xy 359.005571 -254.98522)
			(xy 358.968848 -254.948497) (xy 358.938322 -254.906481) (xy 358.914744 -254.860207) (xy 358.898696 -254.810814)
			(xy 358.890571 -254.759519) (xy 358.610407 -254.759519) (xy 358.602282 -254.810814) (xy 358.586234 -254.860207)
			(xy 358.562656 -254.906481) (xy 358.53213 -254.948497) (xy 358.495407 -254.98522) (xy 358.453391 -255.015746)
			(xy 358.407117 -255.039324) (xy 358.357724 -255.055372) (xy 358.306429 -255.063497) (xy 358.254495 -255.063497)
			(xy 358.2032 -255.055372) (xy 358.153807 -255.039324) (xy 358.107533 -255.015746) (xy 358.065517 -254.98522)
			(xy 358.028794 -254.948497) (xy 357.998268 -254.906481) (xy 357.97469 -254.860207) (xy 357.958642 -254.810814)
			(xy 357.950517 -254.759519) (xy 357.670607 -254.759519) (xy 357.662482 -254.810814) (xy 357.646434 -254.860207)
			(xy 357.622856 -254.906481) (xy 357.59233 -254.948497) (xy 357.555607 -254.98522) (xy 357.513591 -255.015746)
			(xy 357.467317 -255.039324) (xy 357.417924 -255.055372) (xy 357.366629 -255.063497) (xy 357.314695 -255.063497)
			(xy 357.2634 -255.055372) (xy 357.214007 -255.039324) (xy 357.167733 -255.015746) (xy 357.125717 -254.98522)
			(xy 357.088994 -254.948497) (xy 357.058468 -254.906481) (xy 357.03489 -254.860207) (xy 357.018842 -254.810814)
			(xy 357.010717 -254.759519) (xy 350.152207 -254.759519) (xy 350.144082 -254.810814) (xy 350.128034 -254.860207)
			(xy 350.104456 -254.906481) (xy 350.07393 -254.948497) (xy 350.037207 -254.98522) (xy 349.995191 -255.015746)
			(xy 349.948917 -255.039324) (xy 349.899524 -255.055372) (xy 349.848229 -255.063497) (xy 349.796295 -255.063497)
			(xy 349.745 -255.055372) (xy 349.695607 -255.039324) (xy 349.649333 -255.015746) (xy 349.607317 -254.98522)
			(xy 349.570594 -254.948497) (xy 349.540068 -254.906481) (xy 349.51649 -254.860207) (xy 349.500442 -254.810814)
			(xy 349.492317 -254.759519) (xy 349.212407 -254.759519) (xy 349.204282 -254.810814) (xy 349.188234 -254.860207)
			(xy 349.164656 -254.906481) (xy 349.13413 -254.948497) (xy 349.097407 -254.98522) (xy 349.055391 -255.015746)
			(xy 349.009117 -255.039324) (xy 348.959724 -255.055372) (xy 348.908429 -255.063497) (xy 348.856495 -255.063497)
			(xy 348.8052 -255.055372) (xy 348.755807 -255.039324) (xy 348.709533 -255.015746) (xy 348.667517 -254.98522)
			(xy 348.630794 -254.948497) (xy 348.600268 -254.906481) (xy 348.57669 -254.860207) (xy 348.560642 -254.810814)
			(xy 348.552517 -254.759519) (xy 348.272607 -254.759519) (xy 348.264482 -254.810814) (xy 348.248434 -254.860207)
			(xy 348.224856 -254.906481) (xy 348.19433 -254.948497) (xy 348.157607 -254.98522) (xy 348.115591 -255.015746)
			(xy 348.069317 -255.039324) (xy 348.019924 -255.055372) (xy 347.968629 -255.063497) (xy 347.916695 -255.063497)
			(xy 347.8654 -255.055372) (xy 347.816007 -255.039324) (xy 347.769733 -255.015746) (xy 347.727717 -254.98522)
			(xy 347.690994 -254.948497) (xy 347.660468 -254.906481) (xy 347.63689 -254.860207) (xy 347.620842 -254.810814)
			(xy 347.612717 -254.759519) (xy 347.332807 -254.759519) (xy 347.324682 -254.810814) (xy 347.308634 -254.860207)
			(xy 347.285056 -254.906481) (xy 347.25453 -254.948497) (xy 347.217807 -254.98522) (xy 347.175791 -255.015746)
			(xy 347.129517 -255.039324) (xy 347.080124 -255.055372) (xy 347.028829 -255.063497) (xy 346.976895 -255.063497)
			(xy 346.9256 -255.055372) (xy 346.876207 -255.039324) (xy 346.829933 -255.015746) (xy 346.787917 -254.98522)
			(xy 346.751194 -254.948497) (xy 346.720668 -254.906481) (xy 346.69709 -254.860207) (xy 346.681042 -254.810814)
			(xy 346.672917 -254.759519) (xy 346.393261 -254.759519) (xy 346.385136 -254.810814) (xy 346.369088 -254.860207)
			(xy 346.34551 -254.906481) (xy 346.314984 -254.948497) (xy 346.278261 -254.98522) (xy 346.236245 -255.015746)
			(xy 346.189971 -255.039324) (xy 346.140578 -255.055372) (xy 346.089283 -255.063497) (xy 346.037349 -255.063497)
			(xy 345.986054 -255.055372) (xy 345.936661 -255.039324) (xy 345.890387 -255.015746) (xy 345.848371 -254.98522)
			(xy 345.811648 -254.948497) (xy 345.781122 -254.906481) (xy 345.757544 -254.860207) (xy 345.741496 -254.810814)
			(xy 345.733371 -254.759519) (xy 345.453207 -254.759519) (xy 345.445082 -254.810814) (xy 345.429034 -254.860207)
			(xy 345.405456 -254.906481) (xy 345.37493 -254.948497) (xy 345.338207 -254.98522) (xy 345.296191 -255.015746)
			(xy 345.249917 -255.039324) (xy 345.200524 -255.055372) (xy 345.149229 -255.063497) (xy 345.097295 -255.063497)
			(xy 345.046 -255.055372) (xy 344.996607 -255.039324) (xy 344.950333 -255.015746) (xy 344.908317 -254.98522)
			(xy 344.871594 -254.948497) (xy 344.841068 -254.906481) (xy 344.81749 -254.860207) (xy 344.801442 -254.810814)
			(xy 344.793317 -254.759519) (xy 344.513407 -254.759519) (xy 344.505282 -254.810814) (xy 344.489234 -254.860207)
			(xy 344.465656 -254.906481) (xy 344.43513 -254.948497) (xy 344.398407 -254.98522) (xy 344.356391 -255.015746)
			(xy 344.310117 -255.039324) (xy 344.260724 -255.055372) (xy 344.209429 -255.063497) (xy 344.157495 -255.063497)
			(xy 344.1062 -255.055372) (xy 344.056807 -255.039324) (xy 344.010533 -255.015746) (xy 343.968517 -254.98522)
			(xy 343.931794 -254.948497) (xy 343.901268 -254.906481) (xy 343.87769 -254.860207) (xy 343.861642 -254.810814)
			(xy 343.853517 -254.759519) (xy 343.573607 -254.759519) (xy 343.565482 -254.810814) (xy 343.549434 -254.860207)
			(xy 343.525856 -254.906481) (xy 343.49533 -254.948497) (xy 343.458607 -254.98522) (xy 343.416591 -255.015746)
			(xy 343.370317 -255.039324) (xy 343.320924 -255.055372) (xy 343.269629 -255.063497) (xy 343.217695 -255.063497)
			(xy 343.1664 -255.055372) (xy 343.117007 -255.039324) (xy 343.070733 -255.015746) (xy 343.028717 -254.98522)
			(xy 342.991994 -254.948497) (xy 342.961468 -254.906481) (xy 342.93789 -254.860207) (xy 342.921842 -254.810814)
			(xy 342.913717 -254.759519) (xy 342.621345 -254.759519) (xy 342.61367 -254.807975) (xy 342.59822 -254.855522)
			(xy 342.575522 -254.900066) (xy 342.546134 -254.94051) (xy 342.510781 -254.975859) (xy 342.470333 -255.005241)
			(xy 342.425786 -255.027934) (xy 342.378238 -255.043379) (xy 342.328859 -255.051194) (xy 342.303862 -255.05156)
			(xy 342.279341 -255.051104) (xy 342.23088 -255.043575) (xy 342.184147 -255.028702) (xy 342.140249 -255.006835)
			(xy 342.100226 -254.978493) (xy 342.065023 -254.944347) (xy 342.049862 -254.925068) (xy 342.04783 -254.922274)
			(xy 342.04275 -254.917194) (xy 342.034944 -254.910199) (xy 342.015387 -254.902727) (xy 342.004904 -254.902716)
			(xy 341.912702 -254.913892) (xy 341.907022 -254.915087) (xy 341.896375 -254.919706) (xy 341.89162 -254.923036)
			(xy 341.87511 -254.944372) (xy 341.872824 -254.94996) (xy 341.867236 -254.962406) (xy 341.862664 -254.972312)
			(xy 341.862664 -255.175258) (xy 341.863245 -255.18611) (xy 341.872395 -255.205796) (xy 341.888918 -255.219877)
			(xy 341.89924 -255.223264) (xy 341.902796 -255.224026) (xy 341.927198 -255.229665) (xy 341.974069 -255.24731)
			(xy 342.017742 -255.271822) (xy 342.057219 -255.30264) (xy 342.091597 -255.33906) (xy 342.120089 -255.380247)
			(xy 342.142044 -255.42526) (xy 342.156959 -255.473069) (xy 342.164494 -255.522581) (xy 342.164924 -255.547622)
			(xy 342.164413 -255.573589) (xy 342.444071 -255.573589) (xy 342.444071 -255.521655) (xy 342.452196 -255.47036)
			(xy 342.468244 -255.420967) (xy 342.491822 -255.374693) (xy 342.522348 -255.332677) (xy 342.559071 -255.295954)
			(xy 342.601087 -255.265428) (xy 342.647361 -255.24185) (xy 342.696754 -255.225802) (xy 342.748049 -255.217677)
			(xy 342.799983 -255.217677) (xy 342.851278 -255.225802) (xy 342.900671 -255.24185) (xy 342.946945 -255.265428)
			(xy 342.988961 -255.295954) (xy 343.025684 -255.332677) (xy 343.05621 -255.374693) (xy 343.079788 -255.420967)
			(xy 343.095836 -255.47036) (xy 343.103961 -255.521655) (xy 343.10447 -255.547622) (xy 343.103961 -255.573589)
			(xy 343.383871 -255.573589) (xy 343.383871 -255.521655) (xy 343.391996 -255.47036) (xy 343.408044 -255.420967)
			(xy 343.431622 -255.374693) (xy 343.462148 -255.332677) (xy 343.498871 -255.295954) (xy 343.540887 -255.265428)
			(xy 343.587161 -255.24185) (xy 343.636554 -255.225802) (xy 343.687849 -255.217677) (xy 343.739783 -255.217677)
			(xy 343.791078 -255.225802) (xy 343.840471 -255.24185) (xy 343.886745 -255.265428) (xy 343.928761 -255.295954)
			(xy 343.965484 -255.332677) (xy 343.99601 -255.374693) (xy 344.019588 -255.420967) (xy 344.035636 -255.47036)
			(xy 344.043761 -255.521655) (xy 344.04427 -255.547622) (xy 344.043761 -255.573589) (xy 344.323671 -255.573589)
			(xy 344.323671 -255.521655) (xy 344.331796 -255.47036) (xy 344.347844 -255.420967) (xy 344.371422 -255.374693)
			(xy 344.401948 -255.332677) (xy 344.438671 -255.295954) (xy 344.480687 -255.265428) (xy 344.526961 -255.24185)
			(xy 344.576354 -255.225802) (xy 344.627649 -255.217677) (xy 344.679583 -255.217677) (xy 344.730878 -255.225802)
			(xy 344.780271 -255.24185) (xy 344.826545 -255.265428) (xy 344.868561 -255.295954) (xy 344.905284 -255.332677)
			(xy 344.93581 -255.374693) (xy 344.959388 -255.420967) (xy 344.975436 -255.47036) (xy 344.983561 -255.521655)
			(xy 344.98407 -255.547622) (xy 344.983561 -255.573589) (xy 345.263471 -255.573589) (xy 345.263471 -255.521655)
			(xy 345.271596 -255.47036) (xy 345.287644 -255.420967) (xy 345.311222 -255.374693) (xy 345.341748 -255.332677)
			(xy 345.378471 -255.295954) (xy 345.420487 -255.265428) (xy 345.466761 -255.24185) (xy 345.516154 -255.225802)
			(xy 345.567449 -255.217677) (xy 345.619383 -255.217677) (xy 345.670678 -255.225802) (xy 345.720071 -255.24185)
			(xy 345.766345 -255.265428) (xy 345.808361 -255.295954) (xy 345.845084 -255.332677) (xy 345.87561 -255.374693)
			(xy 345.899188 -255.420967) (xy 345.915236 -255.47036) (xy 345.923361 -255.521655) (xy 345.92387 -255.547622)
			(xy 345.923361 -255.573589) (xy 346.203017 -255.573589) (xy 346.203017 -255.521655) (xy 346.211142 -255.47036)
			(xy 346.22719 -255.420967) (xy 346.250768 -255.374693) (xy 346.281294 -255.332677) (xy 346.318017 -255.295954)
			(xy 346.360033 -255.265428) (xy 346.406307 -255.24185) (xy 346.4557 -255.225802) (xy 346.506995 -255.217677)
			(xy 346.558929 -255.217677) (xy 346.610224 -255.225802) (xy 346.659617 -255.24185) (xy 346.705891 -255.265428)
			(xy 346.747907 -255.295954) (xy 346.78463 -255.332677) (xy 346.815156 -255.374693) (xy 346.838734 -255.420967)
			(xy 346.854782 -255.47036) (xy 346.862907 -255.521655) (xy 346.863416 -255.547622) (xy 346.862907 -255.573589)
			(xy 347.143071 -255.573589) (xy 347.143071 -255.521655) (xy 347.151196 -255.47036) (xy 347.167244 -255.420967)
			(xy 347.190822 -255.374693) (xy 347.221348 -255.332677) (xy 347.258071 -255.295954) (xy 347.300087 -255.265428)
			(xy 347.346361 -255.24185) (xy 347.395754 -255.225802) (xy 347.447049 -255.217677) (xy 347.498983 -255.217677)
			(xy 347.550278 -255.225802) (xy 347.599671 -255.24185) (xy 347.645945 -255.265428) (xy 347.687961 -255.295954)
			(xy 347.724684 -255.332677) (xy 347.75521 -255.374693) (xy 347.778788 -255.420967) (xy 347.794836 -255.47036)
			(xy 347.802961 -255.521655) (xy 347.80347 -255.547622) (xy 347.802961 -255.573589) (xy 348.082871 -255.573589)
			(xy 348.082871 -255.521655) (xy 348.090996 -255.47036) (xy 348.107044 -255.420967) (xy 348.130622 -255.374693)
			(xy 348.161148 -255.332677) (xy 348.197871 -255.295954) (xy 348.239887 -255.265428) (xy 348.286161 -255.24185)
			(xy 348.335554 -255.225802) (xy 348.386849 -255.217677) (xy 348.438783 -255.217677) (xy 348.490078 -255.225802)
			(xy 348.539471 -255.24185) (xy 348.585745 -255.265428) (xy 348.627761 -255.295954) (xy 348.664484 -255.332677)
			(xy 348.69501 -255.374693) (xy 348.718588 -255.420967) (xy 348.734636 -255.47036) (xy 348.742761 -255.521655)
			(xy 348.74327 -255.547622) (xy 348.742761 -255.573589) (xy 349.022671 -255.573589) (xy 349.022671 -255.521655)
			(xy 349.030796 -255.47036) (xy 349.046844 -255.420967) (xy 349.070422 -255.374693) (xy 349.100948 -255.332677)
			(xy 349.137671 -255.295954) (xy 349.179687 -255.265428) (xy 349.225961 -255.24185) (xy 349.275354 -255.225802)
			(xy 349.326649 -255.217677) (xy 349.378583 -255.217677) (xy 349.429878 -255.225802) (xy 349.479271 -255.24185)
			(xy 349.525545 -255.265428) (xy 349.567561 -255.295954) (xy 349.604284 -255.332677) (xy 349.63481 -255.374693)
			(xy 349.658388 -255.420967) (xy 349.674436 -255.47036) (xy 349.682561 -255.521655) (xy 349.68307 -255.547622)
			(xy 349.682561 -255.573568) (xy 349.962451 -255.573568) (xy 349.962451 -255.521632) (xy 349.970576 -255.470334)
			(xy 349.986626 -255.42094) (xy 350.010205 -255.374664) (xy 350.040734 -255.332647) (xy 350.077459 -255.295923)
			(xy 350.119478 -255.265397) (xy 350.165755 -255.241819) (xy 350.21515 -255.225772) (xy 350.266448 -255.21765)
			(xy 350.292416 -255.217168) (xy 350.322434 -255.217823) (xy 350.381478 -255.228686) (xy 350.409764 -255.238758)
			(xy 350.42366 -255.243467) (xy 350.452903 -255.245652) (xy 350.481558 -255.239426) (xy 350.507259 -255.225304)
			(xy 350.527879 -255.204454) (xy 350.541715 -255.1786) (xy 350.545146 -255.164336) (xy 350.550761 -255.13987)
			(xy 350.568261 -255.092826) (xy 350.592674 -255.048969) (xy 350.623439 -255.009309) (xy 350.659847 -254.974758)
			(xy 350.701062 -254.94611) (xy 350.746136 -254.924024) (xy 350.79403 -254.909009) (xy 350.843645 -254.901409)
			(xy 350.868742 -254.900938) (xy 350.89471 -254.901416) (xy 350.946006 -254.909547) (xy 350.995398 -254.925601)
			(xy 351.041672 -254.949183) (xy 351.083687 -254.979713) (xy 351.120409 -255.016439) (xy 351.150935 -255.058457)
			(xy 351.174512 -255.104733) (xy 351.190561 -255.154127) (xy 351.198686 -255.205424) (xy 351.199196 -255.231392)
			(xy 351.198774 -255.256099) (xy 351.191407 -255.304962) (xy 351.176838 -255.352181) (xy 351.155391 -255.396699)
			(xy 351.127546 -255.437522) (xy 351.111058 -255.455928) (xy 351.10111 -255.467423) (xy 351.087909 -255.494791)
			(xy 351.08334 -255.524831) (xy 351.087809 -255.554886) (xy 351.100921 -255.582298) (xy 351.110804 -255.59385)
			(xy 351.127158 -255.612231) (xy 351.154754 -255.652962) (xy 351.176003 -255.697335) (xy 351.190434 -255.74437)
			(xy 351.197729 -255.793025) (xy 351.19818 -255.817624) (xy 351.197667 -255.843591) (xy 351.18954 -255.894884)
			(xy 351.17349 -255.944275) (xy 351.149911 -255.990547) (xy 351.119385 -256.032561) (xy 351.082663 -256.069284)
			(xy 351.040649 -256.09981) (xy 350.994376 -256.123389) (xy 350.944986 -256.139439) (xy 350.893693 -256.147567)
			(xy 350.867726 -256.148078) (xy 350.841571 -256.147558) (xy 350.789911 -256.139334) (xy 350.740193 -256.123071)
			(xy 350.69366 -256.099176) (xy 350.651473 -256.068246) (xy 350.614689 -256.031054) (xy 350.584225 -255.988529)
			(xy 350.560844 -255.941735) (xy 350.552512 -255.916938) (xy 350.547793 -255.903761) (xy 350.5324 -255.880402)
			(xy 350.511241 -255.862102) (xy 350.485907 -255.850235) (xy 350.458303 -255.845695) (xy 350.430503 -255.848821)
			(xy 350.417384 -255.853692) (xy 350.387581 -255.864998) (xy 350.325043 -255.877283) (xy 350.293178 -255.878076)
			(xy 350.292416 -255.878076) (xy 350.266448 -255.87755) (xy 350.21515 -255.869428) (xy 350.165755 -255.853381)
			(xy 350.119478 -255.829803) (xy 350.077459 -255.799277) (xy 350.040734 -255.762553) (xy 350.010205 -255.720536)
			(xy 349.986626 -255.67426) (xy 349.970576 -255.624866) (xy 349.962451 -255.573568) (xy 349.682561 -255.573568)
			(xy 349.682561 -255.573589) (xy 349.674436 -255.624884) (xy 349.658388 -255.674277) (xy 349.63481 -255.720551)
			(xy 349.604284 -255.762567) (xy 349.567561 -255.79929) (xy 349.525545 -255.829816) (xy 349.479271 -255.853394)
			(xy 349.429878 -255.869442) (xy 349.378583 -255.877567) (xy 349.326649 -255.877567) (xy 349.275354 -255.869442)
			(xy 349.225961 -255.853394) (xy 349.179687 -255.829816) (xy 349.137671 -255.79929) (xy 349.100948 -255.762567)
			(xy 349.070422 -255.720551) (xy 349.046844 -255.674277) (xy 349.030796 -255.624884) (xy 349.022671 -255.573589)
			(xy 348.742761 -255.573589) (xy 348.734636 -255.624884) (xy 348.718588 -255.674277) (xy 348.69501 -255.720551)
			(xy 348.664484 -255.762567) (xy 348.627761 -255.79929) (xy 348.585745 -255.829816) (xy 348.539471 -255.853394)
			(xy 348.490078 -255.869442) (xy 348.438783 -255.877567) (xy 348.386849 -255.877567) (xy 348.335554 -255.869442)
			(xy 348.286161 -255.853394) (xy 348.239887 -255.829816) (xy 348.197871 -255.79929) (xy 348.161148 -255.762567)
			(xy 348.130622 -255.720551) (xy 348.107044 -255.674277) (xy 348.090996 -255.624884) (xy 348.082871 -255.573589)
			(xy 347.802961 -255.573589) (xy 347.794836 -255.624884) (xy 347.778788 -255.674277) (xy 347.75521 -255.720551)
			(xy 347.724684 -255.762567) (xy 347.687961 -255.79929) (xy 347.645945 -255.829816) (xy 347.599671 -255.853394)
			(xy 347.550278 -255.869442) (xy 347.498983 -255.877567) (xy 347.447049 -255.877567) (xy 347.395754 -255.869442)
			(xy 347.346361 -255.853394) (xy 347.300087 -255.829816) (xy 347.258071 -255.79929) (xy 347.221348 -255.762567)
			(xy 347.190822 -255.720551) (xy 347.167244 -255.674277) (xy 347.151196 -255.624884) (xy 347.143071 -255.573589)
			(xy 346.862907 -255.573589) (xy 346.854782 -255.624884) (xy 346.838734 -255.674277) (xy 346.815156 -255.720551)
			(xy 346.78463 -255.762567) (xy 346.747907 -255.79929) (xy 346.705891 -255.829816) (xy 346.659617 -255.853394)
			(xy 346.610224 -255.869442) (xy 346.558929 -255.877567) (xy 346.506995 -255.877567) (xy 346.4557 -255.869442)
			(xy 346.406307 -255.853394) (xy 346.360033 -255.829816) (xy 346.318017 -255.79929) (xy 346.281294 -255.762567)
			(xy 346.250768 -255.720551) (xy 346.22719 -255.674277) (xy 346.211142 -255.624884) (xy 346.203017 -255.573589)
			(xy 345.923361 -255.573589) (xy 345.915236 -255.624884) (xy 345.899188 -255.674277) (xy 345.87561 -255.720551)
			(xy 345.845084 -255.762567) (xy 345.808361 -255.79929) (xy 345.766345 -255.829816) (xy 345.720071 -255.853394)
			(xy 345.670678 -255.869442) (xy 345.619383 -255.877567) (xy 345.567449 -255.877567) (xy 345.516154 -255.869442)
			(xy 345.466761 -255.853394) (xy 345.420487 -255.829816) (xy 345.378471 -255.79929) (xy 345.341748 -255.762567)
			(xy 345.311222 -255.720551) (xy 345.287644 -255.674277) (xy 345.271596 -255.624884) (xy 345.263471 -255.573589)
			(xy 344.983561 -255.573589) (xy 344.975436 -255.624884) (xy 344.959388 -255.674277) (xy 344.93581 -255.720551)
			(xy 344.905284 -255.762567) (xy 344.868561 -255.79929) (xy 344.826545 -255.829816) (xy 344.780271 -255.853394)
			(xy 344.730878 -255.869442) (xy 344.679583 -255.877567) (xy 344.627649 -255.877567) (xy 344.576354 -255.869442)
			(xy 344.526961 -255.853394) (xy 344.480687 -255.829816) (xy 344.438671 -255.79929) (xy 344.401948 -255.762567)
			(xy 344.371422 -255.720551) (xy 344.347844 -255.674277) (xy 344.331796 -255.624884) (xy 344.323671 -255.573589)
			(xy 344.043761 -255.573589) (xy 344.035636 -255.624884) (xy 344.019588 -255.674277) (xy 343.99601 -255.720551)
			(xy 343.965484 -255.762567) (xy 343.928761 -255.79929) (xy 343.886745 -255.829816) (xy 343.840471 -255.853394)
			(xy 343.791078 -255.869442) (xy 343.739783 -255.877567) (xy 343.687849 -255.877567) (xy 343.636554 -255.869442)
			(xy 343.587161 -255.853394) (xy 343.540887 -255.829816) (xy 343.498871 -255.79929) (xy 343.462148 -255.762567)
			(xy 343.431622 -255.720551) (xy 343.408044 -255.674277) (xy 343.391996 -255.624884) (xy 343.383871 -255.573589)
			(xy 343.103961 -255.573589) (xy 343.095836 -255.624884) (xy 343.079788 -255.674277) (xy 343.05621 -255.720551)
			(xy 343.025684 -255.762567) (xy 342.988961 -255.79929) (xy 342.946945 -255.829816) (xy 342.900671 -255.853394)
			(xy 342.851278 -255.869442) (xy 342.799983 -255.877567) (xy 342.748049 -255.877567) (xy 342.696754 -255.869442)
			(xy 342.647361 -255.853394) (xy 342.601087 -255.829816) (xy 342.559071 -255.79929) (xy 342.522348 -255.762567)
			(xy 342.491822 -255.720551) (xy 342.468244 -255.674277) (xy 342.452196 -255.624884) (xy 342.444071 -255.573589)
			(xy 342.164413 -255.573589) (xy 342.164413 -255.573609) (xy 342.15628 -255.624941) (xy 342.140217 -255.67437)
			(xy 342.11662 -255.720678) (xy 342.08607 -255.762724) (xy 342.049319 -255.799474) (xy 342.007272 -255.830023)
			(xy 341.960964 -255.853619) (xy 341.911535 -255.869681) (xy 341.860203 -255.877813) (xy 341.834216 -255.87833)
			(xy 341.833962 -255.87833) (xy 341.809505 -255.877892) (xy 341.761126 -255.870686) (xy 341.714338 -255.856423)
			(xy 341.670166 -255.835414) (xy 341.629577 -255.808119) (xy 341.611204 -255.79197) (xy 341.6046 -255.785874)
			(xy 341.570056 -255.771904) (xy 341.497666 -255.772666) (xy 341.48845 -255.773512) (xy 341.471521 -255.780948)
			(xy 341.464646 -255.787144) (xy 341.382604 -255.869186) (xy 341.376892 -255.875395) (xy 341.369631 -255.890613)
			(xy 341.367823 -255.907378) (xy 341.369396 -255.915668) (xy 341.382604 -255.96088) (xy 341.395304 -256.003298)
			(xy 341.398237 -256.011772) (xy 341.409068 -256.026046) (xy 341.424205 -256.035634) (xy 341.432896 -256.037842)
			(xy 341.432896 -256.038096) (xy 341.433404 -256.038096) (xy 341.457741 -256.043787) (xy 341.504474 -256.061507)
			(xy 341.548009 -256.086056) (xy 341.587356 -256.116875) (xy 341.621617 -256.153263) (xy 341.650014 -256.194392)
			(xy 341.6719 -256.239325) (xy 341.686777 -256.287039) (xy 341.694305 -256.336448) (xy 341.69477 -256.361438)
			(xy 341.694257 -256.387405) (xy 341.974171 -256.387405) (xy 341.974171 -256.335471) (xy 341.982296 -256.284176)
			(xy 341.998344 -256.234783) (xy 342.021922 -256.188509) (xy 342.052448 -256.146493) (xy 342.089171 -256.10977)
			(xy 342.131187 -256.079244) (xy 342.177461 -256.055666) (xy 342.226854 -256.039618) (xy 342.278149 -256.031493)
			(xy 342.330083 -256.031493) (xy 342.381378 -256.039618) (xy 342.430771 -256.055666) (xy 342.477045 -256.079244)
			(xy 342.519061 -256.10977) (xy 342.555784 -256.146493) (xy 342.58631 -256.188509) (xy 342.609888 -256.234783)
			(xy 342.625936 -256.284176) (xy 342.634061 -256.335471) (xy 342.63457 -256.361438) (xy 342.634061 -256.387405)
			(xy 342.913717 -256.387405) (xy 342.913717 -256.335471) (xy 342.921842 -256.284176) (xy 342.93789 -256.234783)
			(xy 342.961468 -256.188509) (xy 342.991994 -256.146493) (xy 343.028717 -256.10977) (xy 343.070733 -256.079244)
			(xy 343.117007 -256.055666) (xy 343.1664 -256.039618) (xy 343.217695 -256.031493) (xy 343.269629 -256.031493)
			(xy 343.320924 -256.039618) (xy 343.370317 -256.055666) (xy 343.416591 -256.079244) (xy 343.458607 -256.10977)
			(xy 343.49533 -256.146493) (xy 343.525856 -256.188509) (xy 343.549434 -256.234783) (xy 343.565482 -256.284176)
			(xy 343.573607 -256.335471) (xy 343.574116 -256.361438) (xy 343.573607 -256.387405) (xy 343.853517 -256.387405)
			(xy 343.853517 -256.335471) (xy 343.861642 -256.284176) (xy 343.87769 -256.234783) (xy 343.901268 -256.188509)
			(xy 343.931794 -256.146493) (xy 343.968517 -256.10977) (xy 344.010533 -256.079244) (xy 344.056807 -256.055666)
			(xy 344.1062 -256.039618) (xy 344.157495 -256.031493) (xy 344.209429 -256.031493) (xy 344.260724 -256.039618)
			(xy 344.310117 -256.055666) (xy 344.356391 -256.079244) (xy 344.398407 -256.10977) (xy 344.43513 -256.146493)
			(xy 344.465656 -256.188509) (xy 344.489234 -256.234783) (xy 344.505282 -256.284176) (xy 344.513407 -256.335471)
			(xy 344.513916 -256.361438) (xy 344.513407 -256.387405) (xy 344.793317 -256.387405) (xy 344.793317 -256.335471)
			(xy 344.801442 -256.284176) (xy 344.81749 -256.234783) (xy 344.841068 -256.188509) (xy 344.871594 -256.146493)
			(xy 344.908317 -256.10977) (xy 344.950333 -256.079244) (xy 344.996607 -256.055666) (xy 345.046 -256.039618)
			(xy 345.097295 -256.031493) (xy 345.149229 -256.031493) (xy 345.200524 -256.039618) (xy 345.249917 -256.055666)
			(xy 345.296191 -256.079244) (xy 345.338207 -256.10977) (xy 345.37493 -256.146493) (xy 345.405456 -256.188509)
			(xy 345.429034 -256.234783) (xy 345.445082 -256.284176) (xy 345.453207 -256.335471) (xy 345.453716 -256.361438)
			(xy 345.453207 -256.387405) (xy 345.733117 -256.387405) (xy 345.733117 -256.335471) (xy 345.741242 -256.284176)
			(xy 345.75729 -256.234783) (xy 345.780868 -256.188509) (xy 345.811394 -256.146493) (xy 345.848117 -256.10977)
			(xy 345.890133 -256.079244) (xy 345.936407 -256.055666) (xy 345.9858 -256.039618) (xy 346.037095 -256.031493)
			(xy 346.089029 -256.031493) (xy 346.140324 -256.039618) (xy 346.189717 -256.055666) (xy 346.235991 -256.079244)
			(xy 346.278007 -256.10977) (xy 346.31473 -256.146493) (xy 346.345256 -256.188509) (xy 346.368834 -256.234783)
			(xy 346.384882 -256.284176) (xy 346.393007 -256.335471) (xy 346.393516 -256.361438) (xy 346.393007 -256.387405)
			(xy 346.672917 -256.387405) (xy 346.672917 -256.335471) (xy 346.681042 -256.284176) (xy 346.69709 -256.234783)
			(xy 346.720668 -256.188509) (xy 346.751194 -256.146493) (xy 346.787917 -256.10977) (xy 346.829933 -256.079244)
			(xy 346.876207 -256.055666) (xy 346.9256 -256.039618) (xy 346.976895 -256.031493) (xy 347.028829 -256.031493)
			(xy 347.080124 -256.039618) (xy 347.129517 -256.055666) (xy 347.175791 -256.079244) (xy 347.217807 -256.10977)
			(xy 347.25453 -256.146493) (xy 347.285056 -256.188509) (xy 347.308634 -256.234783) (xy 347.324682 -256.284176)
			(xy 347.332807 -256.335471) (xy 347.333316 -256.361438) (xy 347.332807 -256.387405) (xy 347.612717 -256.387405)
			(xy 347.612717 -256.335471) (xy 347.620842 -256.284176) (xy 347.63689 -256.234783) (xy 347.660468 -256.188509)
			(xy 347.690994 -256.146493) (xy 347.727717 -256.10977) (xy 347.769733 -256.079244) (xy 347.816007 -256.055666)
			(xy 347.8654 -256.039618) (xy 347.916695 -256.031493) (xy 347.968629 -256.031493) (xy 348.019924 -256.039618)
			(xy 348.069317 -256.055666) (xy 348.115591 -256.079244) (xy 348.157607 -256.10977) (xy 348.19433 -256.146493)
			(xy 348.224856 -256.188509) (xy 348.248434 -256.234783) (xy 348.264482 -256.284176) (xy 348.272607 -256.335471)
			(xy 348.273116 -256.361438) (xy 348.272607 -256.387405) (xy 348.552771 -256.387405) (xy 348.552771 -256.335471)
			(xy 348.560896 -256.284176) (xy 348.576944 -256.234783) (xy 348.600522 -256.188509) (xy 348.631048 -256.146493)
			(xy 348.667771 -256.10977) (xy 348.709787 -256.079244) (xy 348.756061 -256.055666) (xy 348.805454 -256.039618)
			(xy 348.856749 -256.031493) (xy 348.908683 -256.031493) (xy 348.959978 -256.039618) (xy 349.009371 -256.055666)
			(xy 349.055645 -256.079244) (xy 349.097661 -256.10977) (xy 349.134384 -256.146493) (xy 349.16491 -256.188509)
			(xy 349.188488 -256.234783) (xy 349.204536 -256.284176) (xy 349.212661 -256.335471) (xy 349.21317 -256.361438)
			(xy 349.212661 -256.387405) (xy 349.492317 -256.387405) (xy 349.492317 -256.335471) (xy 349.500442 -256.284176)
			(xy 349.51649 -256.234783) (xy 349.540068 -256.188509) (xy 349.570594 -256.146493) (xy 349.607317 -256.10977)
			(xy 349.649333 -256.079244) (xy 349.695607 -256.055666) (xy 349.745 -256.039618) (xy 349.796295 -256.031493)
			(xy 349.848229 -256.031493) (xy 349.899524 -256.039618) (xy 349.948917 -256.055666) (xy 349.995191 -256.079244)
			(xy 350.037207 -256.10977) (xy 350.07393 -256.146493) (xy 350.104456 -256.188509) (xy 350.128034 -256.234783)
			(xy 350.144082 -256.284176) (xy 350.151371 -256.330196) (xy 356.04323 -256.330196) (xy 356.04323 -256.329942)
			(xy 356.043665 -256.305415) (xy 356.050935 -256.256902) (xy 356.065291 -256.209996) (xy 356.086419 -256.165724)
			(xy 356.113856 -256.12506) (xy 356.130098 -256.106676) (xy 356.139903 -256.095189) (xy 356.152914 -256.067951)
			(xy 356.15738 -256.038097) (xy 356.152912 -256.008244) (xy 356.1399 -255.981006) (xy 356.130098 -255.969516)
			(xy 356.11384 -255.951144) (xy 356.086397 -255.910483) (xy 356.065269 -255.866209) (xy 356.050923 -255.819296)
			(xy 356.043674 -255.770778) (xy 356.04323 -255.74625) (xy 356.04323 -255.745996) (xy 356.043739 -255.720029)
			(xy 356.051864 -255.668734) (xy 356.067912 -255.619341) (xy 356.09149 -255.573067) (xy 356.122016 -255.531051)
			(xy 356.158739 -255.494328) (xy 356.200755 -255.463802) (xy 356.247029 -255.440224) (xy 356.296422 -255.424176)
			(xy 356.347717 -255.416051) (xy 356.399651 -255.416051) (xy 356.450946 -255.424176) (xy 356.500339 -255.440224)
			(xy 356.546613 -255.463802) (xy 356.588629 -255.494328) (xy 356.625352 -255.531051) (xy 356.655878 -255.573067)
			(xy 356.656144 -255.573589) (xy 357.480617 -255.573589) (xy 357.480617 -255.521655) (xy 357.488742 -255.47036)
			(xy 357.50479 -255.420967) (xy 357.528368 -255.374693) (xy 357.558894 -255.332677) (xy 357.595617 -255.295954)
			(xy 357.637633 -255.265428) (xy 357.683907 -255.24185) (xy 357.7333 -255.225802) (xy 357.784595 -255.217677)
			(xy 357.836529 -255.217677) (xy 357.887824 -255.225802) (xy 357.937217 -255.24185) (xy 357.983491 -255.265428)
			(xy 358.025507 -255.295954) (xy 358.06223 -255.332677) (xy 358.092756 -255.374693) (xy 358.116334 -255.420967)
			(xy 358.132382 -255.47036) (xy 358.140507 -255.521655) (xy 358.141016 -255.547622) (xy 358.140507 -255.573589)
			(xy 358.420671 -255.573589) (xy 358.420671 -255.521655) (xy 358.428796 -255.47036) (xy 358.444844 -255.420967)
			(xy 358.468422 -255.374693) (xy 358.498948 -255.332677) (xy 358.535671 -255.295954) (xy 358.577687 -255.265428)
			(xy 358.623961 -255.24185) (xy 358.673354 -255.225802) (xy 358.724649 -255.217677) (xy 358.776583 -255.217677)
			(xy 358.827878 -255.225802) (xy 358.877271 -255.24185) (xy 358.923545 -255.265428) (xy 358.965561 -255.295954)
			(xy 359.002284 -255.332677) (xy 359.03281 -255.374693) (xy 359.056388 -255.420967) (xy 359.072436 -255.47036)
			(xy 359.080561 -255.521655) (xy 359.08107 -255.547622) (xy 359.080561 -255.573589) (xy 359.360217 -255.573589)
			(xy 359.360217 -255.521655) (xy 359.368342 -255.47036) (xy 359.38439 -255.420967) (xy 359.407968 -255.374693)
			(xy 359.438494 -255.332677) (xy 359.475217 -255.295954) (xy 359.517233 -255.265428) (xy 359.563507 -255.24185)
			(xy 359.6129 -255.225802) (xy 359.664195 -255.217677) (xy 359.716129 -255.217677) (xy 359.767424 -255.225802)
			(xy 359.816817 -255.24185) (xy 359.863091 -255.265428) (xy 359.905107 -255.295954) (xy 359.94183 -255.332677)
			(xy 359.972356 -255.374693) (xy 359.995934 -255.420967) (xy 360.011982 -255.47036) (xy 360.020107 -255.521655)
			(xy 360.020616 -255.547622) (xy 360.020107 -255.573589) (xy 360.300017 -255.573589) (xy 360.300017 -255.521655)
			(xy 360.308142 -255.47036) (xy 360.32419 -255.420967) (xy 360.347768 -255.374693) (xy 360.378294 -255.332677)
			(xy 360.415017 -255.295954) (xy 360.457033 -255.265428) (xy 360.503307 -255.24185) (xy 360.5527 -255.225802)
			(xy 360.603995 -255.217677) (xy 360.655929 -255.217677) (xy 360.707224 -255.225802) (xy 360.756617 -255.24185)
			(xy 360.802891 -255.265428) (xy 360.844907 -255.295954) (xy 360.88163 -255.332677) (xy 360.912156 -255.374693)
			(xy 360.935734 -255.420967) (xy 360.951782 -255.47036) (xy 360.959907 -255.521655) (xy 360.960416 -255.547622)
			(xy 360.959907 -255.573589) (xy 361.239817 -255.573589) (xy 361.239817 -255.521655) (xy 361.247942 -255.47036)
			(xy 361.26399 -255.420967) (xy 361.287568 -255.374693) (xy 361.318094 -255.332677) (xy 361.354817 -255.295954)
			(xy 361.396833 -255.265428) (xy 361.443107 -255.24185) (xy 361.4925 -255.225802) (xy 361.543795 -255.217677)
			(xy 361.595729 -255.217677) (xy 361.647024 -255.225802) (xy 361.696417 -255.24185) (xy 361.742691 -255.265428)
			(xy 361.784707 -255.295954) (xy 361.82143 -255.332677) (xy 361.851956 -255.374693) (xy 361.875534 -255.420967)
			(xy 361.891582 -255.47036) (xy 361.899707 -255.521655) (xy 361.900216 -255.547622) (xy 361.899707 -255.573589)
			(xy 362.179617 -255.573589) (xy 362.179617 -255.521655) (xy 362.187742 -255.47036) (xy 362.20379 -255.420967)
			(xy 362.227368 -255.374693) (xy 362.257894 -255.332677) (xy 362.294617 -255.295954) (xy 362.336633 -255.265428)
			(xy 362.382907 -255.24185) (xy 362.4323 -255.225802) (xy 362.483595 -255.217677) (xy 362.535529 -255.217677)
			(xy 362.586824 -255.225802) (xy 362.636217 -255.24185) (xy 362.682491 -255.265428) (xy 362.724507 -255.295954)
			(xy 362.76123 -255.332677) (xy 362.791756 -255.374693) (xy 362.815334 -255.420967) (xy 362.831382 -255.47036)
			(xy 362.839507 -255.521655) (xy 362.840016 -255.547622) (xy 362.839507 -255.573589) (xy 362.831382 -255.624884)
			(xy 362.815334 -255.674277) (xy 362.791756 -255.720551) (xy 362.76123 -255.762567) (xy 362.724507 -255.79929)
			(xy 362.682491 -255.829816) (xy 362.636217 -255.853394) (xy 362.586824 -255.869442) (xy 362.535529 -255.877567)
			(xy 362.483595 -255.877567) (xy 362.4323 -255.869442) (xy 362.382907 -255.853394) (xy 362.336633 -255.829816)
			(xy 362.294617 -255.79929) (xy 362.257894 -255.762567) (xy 362.227368 -255.720551) (xy 362.20379 -255.674277)
			(xy 362.187742 -255.624884) (xy 362.179617 -255.573589) (xy 361.899707 -255.573589) (xy 361.891582 -255.624884)
			(xy 361.875534 -255.674277) (xy 361.851956 -255.720551) (xy 361.82143 -255.762567) (xy 361.784707 -255.79929)
			(xy 361.742691 -255.829816) (xy 361.696417 -255.853394) (xy 361.647024 -255.869442) (xy 361.595729 -255.877567)
			(xy 361.543795 -255.877567) (xy 361.4925 -255.869442) (xy 361.443107 -255.853394) (xy 361.396833 -255.829816)
			(xy 361.354817 -255.79929) (xy 361.318094 -255.762567) (xy 361.287568 -255.720551) (xy 361.26399 -255.674277)
			(xy 361.247942 -255.624884) (xy 361.239817 -255.573589) (xy 360.959907 -255.573589) (xy 360.951782 -255.624884)
			(xy 360.935734 -255.674277) (xy 360.912156 -255.720551) (xy 360.88163 -255.762567) (xy 360.844907 -255.79929)
			(xy 360.802891 -255.829816) (xy 360.756617 -255.853394) (xy 360.707224 -255.869442) (xy 360.655929 -255.877567)
			(xy 360.603995 -255.877567) (xy 360.5527 -255.869442) (xy 360.503307 -255.853394) (xy 360.457033 -255.829816)
			(xy 360.415017 -255.79929) (xy 360.378294 -255.762567) (xy 360.347768 -255.720551) (xy 360.32419 -255.674277)
			(xy 360.308142 -255.624884) (xy 360.300017 -255.573589) (xy 360.020107 -255.573589) (xy 360.011982 -255.624884)
			(xy 359.995934 -255.674277) (xy 359.972356 -255.720551) (xy 359.94183 -255.762567) (xy 359.905107 -255.79929)
			(xy 359.863091 -255.829816) (xy 359.816817 -255.853394) (xy 359.767424 -255.869442) (xy 359.716129 -255.877567)
			(xy 359.664195 -255.877567) (xy 359.6129 -255.869442) (xy 359.563507 -255.853394) (xy 359.517233 -255.829816)
			(xy 359.475217 -255.79929) (xy 359.438494 -255.762567) (xy 359.407968 -255.720551) (xy 359.38439 -255.674277)
			(xy 359.368342 -255.624884) (xy 359.360217 -255.573589) (xy 359.080561 -255.573589) (xy 359.072436 -255.624884)
			(xy 359.056388 -255.674277) (xy 359.03281 -255.720551) (xy 359.002284 -255.762567) (xy 358.965561 -255.79929)
			(xy 358.923545 -255.829816) (xy 358.877271 -255.853394) (xy 358.827878 -255.869442) (xy 358.776583 -255.877567)
			(xy 358.724649 -255.877567) (xy 358.673354 -255.869442) (xy 358.623961 -255.853394) (xy 358.577687 -255.829816)
			(xy 358.535671 -255.79929) (xy 358.498948 -255.762567) (xy 358.468422 -255.720551) (xy 358.444844 -255.674277)
			(xy 358.428796 -255.624884) (xy 358.420671 -255.573589) (xy 358.140507 -255.573589) (xy 358.132382 -255.624884)
			(xy 358.116334 -255.674277) (xy 358.092756 -255.720551) (xy 358.06223 -255.762567) (xy 358.025507 -255.79929)
			(xy 357.983491 -255.829816) (xy 357.937217 -255.853394) (xy 357.887824 -255.869442) (xy 357.836529 -255.877567)
			(xy 357.784595 -255.877567) (xy 357.7333 -255.869442) (xy 357.683907 -255.853394) (xy 357.637633 -255.829816)
			(xy 357.595617 -255.79929) (xy 357.558894 -255.762567) (xy 357.528368 -255.720551) (xy 357.50479 -255.674277)
			(xy 357.488742 -255.624884) (xy 357.480617 -255.573589) (xy 356.656144 -255.573589) (xy 356.679456 -255.619341)
			(xy 356.695504 -255.668734) (xy 356.703629 -255.720029) (xy 356.704138 -255.745996) (xy 356.704138 -255.74625)
			(xy 356.703706 -255.770777) (xy 356.696437 -255.819291) (xy 356.68208 -255.866198) (xy 356.660951 -255.910469)
			(xy 356.633513 -255.951133) (xy 356.61727 -255.969516) (xy 356.607467 -255.981006) (xy 356.594446 -256.008242)
			(xy 356.589975 -256.038097) (xy 356.594445 -256.067952) (xy 356.607463 -256.095189) (xy 356.61727 -256.106676)
			(xy 356.633519 -256.125055) (xy 356.660965 -256.165715) (xy 356.682095 -256.209986) (xy 356.696443 -256.256897)
			(xy 356.703693 -256.305414) (xy 356.704138 -256.329942) (xy 356.704138 -256.330196) (xy 356.703629 -256.356163)
			(xy 356.69868 -256.387405) (xy 357.010717 -256.387405) (xy 357.010717 -256.335471) (xy 357.018842 -256.284176)
			(xy 357.03489 -256.234783) (xy 357.058468 -256.188509) (xy 357.088994 -256.146493) (xy 357.125717 -256.10977)
			(xy 357.167733 -256.079244) (xy 357.214007 -256.055666) (xy 357.2634 -256.039618) (xy 357.314695 -256.031493)
			(xy 357.366629 -256.031493) (xy 357.417924 -256.039618) (xy 357.467317 -256.055666) (xy 357.513591 -256.079244)
			(xy 357.555607 -256.10977) (xy 357.59233 -256.146493) (xy 357.622856 -256.188509) (xy 357.646434 -256.234783)
			(xy 357.662482 -256.284176) (xy 357.670607 -256.335471) (xy 357.671116 -256.361438) (xy 357.670607 -256.387405)
			(xy 357.950517 -256.387405) (xy 357.950517 -256.335471) (xy 357.958642 -256.284176) (xy 357.97469 -256.234783)
			(xy 357.998268 -256.188509) (xy 358.028794 -256.146493) (xy 358.065517 -256.10977) (xy 358.107533 -256.079244)
			(xy 358.153807 -256.055666) (xy 358.2032 -256.039618) (xy 358.254495 -256.031493) (xy 358.306429 -256.031493)
			(xy 358.357724 -256.039618) (xy 358.407117 -256.055666) (xy 358.453391 -256.079244) (xy 358.495407 -256.10977)
			(xy 358.53213 -256.146493) (xy 358.562656 -256.188509) (xy 358.586234 -256.234783) (xy 358.602282 -256.284176)
			(xy 358.610407 -256.335471) (xy 358.610916 -256.361438) (xy 358.610407 -256.387405) (xy 358.890571 -256.387405)
			(xy 358.890571 -256.335471) (xy 358.898696 -256.284176) (xy 358.914744 -256.234783) (xy 358.938322 -256.188509)
			(xy 358.968848 -256.146493) (xy 359.005571 -256.10977) (xy 359.047587 -256.079244) (xy 359.093861 -256.055666)
			(xy 359.143254 -256.039618) (xy 359.194549 -256.031493) (xy 359.246483 -256.031493) (xy 359.297778 -256.039618)
			(xy 359.347171 -256.055666) (xy 359.393445 -256.079244) (xy 359.435461 -256.10977) (xy 359.472184 -256.146493)
			(xy 359.50271 -256.188509) (xy 359.526288 -256.234783) (xy 359.542336 -256.284176) (xy 359.550461 -256.335471)
			(xy 359.55097 -256.361438) (xy 359.550461 -256.387405) (xy 359.830371 -256.387405) (xy 359.830371 -256.335471)
			(xy 359.838496 -256.284176) (xy 359.854544 -256.234783) (xy 359.878122 -256.188509) (xy 359.908648 -256.146493)
			(xy 359.945371 -256.10977) (xy 359.987387 -256.079244) (xy 360.033661 -256.055666) (xy 360.083054 -256.039618)
			(xy 360.134349 -256.031493) (xy 360.186283 -256.031493) (xy 360.237578 -256.039618) (xy 360.286971 -256.055666)
			(xy 360.333245 -256.079244) (xy 360.375261 -256.10977) (xy 360.411984 -256.146493) (xy 360.44251 -256.188509)
			(xy 360.466088 -256.234783) (xy 360.482136 -256.284176) (xy 360.490261 -256.335471) (xy 360.49077 -256.361438)
			(xy 360.490261 -256.387405) (xy 360.769917 -256.387405) (xy 360.769917 -256.335471) (xy 360.778042 -256.284176)
			(xy 360.79409 -256.234783) (xy 360.817668 -256.188509) (xy 360.848194 -256.146493) (xy 360.884917 -256.10977)
			(xy 360.926933 -256.079244) (xy 360.973207 -256.055666) (xy 361.0226 -256.039618) (xy 361.073895 -256.031493)
			(xy 361.125829 -256.031493) (xy 361.177124 -256.039618) (xy 361.226517 -256.055666) (xy 361.272791 -256.079244)
			(xy 361.314807 -256.10977) (xy 361.35153 -256.146493) (xy 361.382056 -256.188509) (xy 361.405634 -256.234783)
			(xy 361.421682 -256.284176) (xy 361.429807 -256.335471) (xy 361.430316 -256.361438) (xy 361.429807 -256.387405)
			(xy 361.709971 -256.387405) (xy 361.709971 -256.335471) (xy 361.718096 -256.284176) (xy 361.734144 -256.234783)
			(xy 361.757722 -256.188509) (xy 361.788248 -256.146493) (xy 361.824971 -256.10977) (xy 361.866987 -256.079244)
			(xy 361.913261 -256.055666) (xy 361.962654 -256.039618) (xy 362.013949 -256.031493) (xy 362.065883 -256.031493)
			(xy 362.117178 -256.039618) (xy 362.166571 -256.055666) (xy 362.212845 -256.079244) (xy 362.254861 -256.10977)
			(xy 362.291584 -256.146493) (xy 362.32211 -256.188509) (xy 362.345688 -256.234783) (xy 362.361736 -256.284176)
			(xy 362.369861 -256.335471) (xy 362.37037 -256.361438) (xy 362.369861 -256.387405) (xy 362.361736 -256.4387)
			(xy 362.345688 -256.488093) (xy 362.32211 -256.534367) (xy 362.291584 -256.576383) (xy 362.254861 -256.613106)
			(xy 362.212845 -256.643632) (xy 362.166571 -256.66721) (xy 362.117178 -256.683258) (xy 362.065883 -256.691383)
			(xy 362.013949 -256.691383) (xy 361.962654 -256.683258) (xy 361.913261 -256.66721) (xy 361.866987 -256.643632)
			(xy 361.824971 -256.613106) (xy 361.788248 -256.576383) (xy 361.757722 -256.534367) (xy 361.734144 -256.488093)
			(xy 361.718096 -256.4387) (xy 361.709971 -256.387405) (xy 361.429807 -256.387405) (xy 361.421682 -256.4387)
			(xy 361.405634 -256.488093) (xy 361.382056 -256.534367) (xy 361.35153 -256.576383) (xy 361.314807 -256.613106)
			(xy 361.272791 -256.643632) (xy 361.226517 -256.66721) (xy 361.177124 -256.683258) (xy 361.125829 -256.691383)
			(xy 361.073895 -256.691383) (xy 361.0226 -256.683258) (xy 360.973207 -256.66721) (xy 360.926933 -256.643632)
			(xy 360.884917 -256.613106) (xy 360.848194 -256.576383) (xy 360.817668 -256.534367) (xy 360.79409 -256.488093)
			(xy 360.778042 -256.4387) (xy 360.769917 -256.387405) (xy 360.490261 -256.387405) (xy 360.482136 -256.4387)
			(xy 360.466088 -256.488093) (xy 360.44251 -256.534367) (xy 360.411984 -256.576383) (xy 360.375261 -256.613106)
			(xy 360.333245 -256.643632) (xy 360.286971 -256.66721) (xy 360.237578 -256.683258) (xy 360.186283 -256.691383)
			(xy 360.134349 -256.691383) (xy 360.083054 -256.683258) (xy 360.033661 -256.66721) (xy 359.987387 -256.643632)
			(xy 359.945371 -256.613106) (xy 359.908648 -256.576383) (xy 359.878122 -256.534367) (xy 359.854544 -256.488093)
			(xy 359.838496 -256.4387) (xy 359.830371 -256.387405) (xy 359.550461 -256.387405) (xy 359.542336 -256.4387)
			(xy 359.526288 -256.488093) (xy 359.50271 -256.534367) (xy 359.472184 -256.576383) (xy 359.435461 -256.613106)
			(xy 359.393445 -256.643632) (xy 359.347171 -256.66721) (xy 359.297778 -256.683258) (xy 359.246483 -256.691383)
			(xy 359.194549 -256.691383) (xy 359.143254 -256.683258) (xy 359.093861 -256.66721) (xy 359.047587 -256.643632)
			(xy 359.005571 -256.613106) (xy 358.968848 -256.576383) (xy 358.938322 -256.534367) (xy 358.914744 -256.488093)
			(xy 358.898696 -256.4387) (xy 358.890571 -256.387405) (xy 358.610407 -256.387405) (xy 358.602282 -256.4387)
			(xy 358.586234 -256.488093) (xy 358.562656 -256.534367) (xy 358.53213 -256.576383) (xy 358.495407 -256.613106)
			(xy 358.453391 -256.643632) (xy 358.407117 -256.66721) (xy 358.357724 -256.683258) (xy 358.306429 -256.691383)
			(xy 358.254495 -256.691383) (xy 358.2032 -256.683258) (xy 358.153807 -256.66721) (xy 358.107533 -256.643632)
			(xy 358.065517 -256.613106) (xy 358.028794 -256.576383) (xy 357.998268 -256.534367) (xy 357.97469 -256.488093)
			(xy 357.958642 -256.4387) (xy 357.950517 -256.387405) (xy 357.670607 -256.387405) (xy 357.662482 -256.4387)
			(xy 357.646434 -256.488093) (xy 357.622856 -256.534367) (xy 357.59233 -256.576383) (xy 357.555607 -256.613106)
			(xy 357.513591 -256.643632) (xy 357.467317 -256.66721) (xy 357.417924 -256.683258) (xy 357.366629 -256.691383)
			(xy 357.314695 -256.691383) (xy 357.2634 -256.683258) (xy 357.214007 -256.66721) (xy 357.167733 -256.643632)
			(xy 357.125717 -256.613106) (xy 357.088994 -256.576383) (xy 357.058468 -256.534367) (xy 357.03489 -256.488093)
			(xy 357.018842 -256.4387) (xy 357.010717 -256.387405) (xy 356.69868 -256.387405) (xy 356.695504 -256.407458)
			(xy 356.679456 -256.456851) (xy 356.655878 -256.503125) (xy 356.625352 -256.545141) (xy 356.588629 -256.581864)
			(xy 356.546613 -256.61239) (xy 356.500339 -256.635968) (xy 356.450946 -256.652016) (xy 356.399651 -256.660141)
			(xy 356.347717 -256.660141) (xy 356.296422 -256.652016) (xy 356.247029 -256.635968) (xy 356.200755 -256.61239)
			(xy 356.158739 -256.581864) (xy 356.122016 -256.545141) (xy 356.09149 -256.503125) (xy 356.067912 -256.456851)
			(xy 356.051864 -256.407458) (xy 356.043739 -256.356163) (xy 356.04323 -256.330196) (xy 350.151371 -256.330196)
			(xy 350.152207 -256.335471) (xy 350.152716 -256.361438) (xy 350.152207 -256.387405) (xy 350.144082 -256.4387)
			(xy 350.128034 -256.488093) (xy 350.104456 -256.534367) (xy 350.07393 -256.576383) (xy 350.037207 -256.613106)
			(xy 349.995191 -256.643632) (xy 349.948917 -256.66721) (xy 349.899524 -256.683258) (xy 349.848229 -256.691383)
			(xy 349.796295 -256.691383) (xy 349.745 -256.683258) (xy 349.695607 -256.66721) (xy 349.649333 -256.643632)
			(xy 349.607317 -256.613106) (xy 349.570594 -256.576383) (xy 349.540068 -256.534367) (xy 349.51649 -256.488093)
			(xy 349.500442 -256.4387) (xy 349.492317 -256.387405) (xy 349.212661 -256.387405) (xy 349.204536 -256.4387)
			(xy 349.188488 -256.488093) (xy 349.16491 -256.534367) (xy 349.134384 -256.576383) (xy 349.097661 -256.613106)
			(xy 349.055645 -256.643632) (xy 349.009371 -256.66721) (xy 348.959978 -256.683258) (xy 348.908683 -256.691383)
			(xy 348.856749 -256.691383) (xy 348.805454 -256.683258) (xy 348.756061 -256.66721) (xy 348.709787 -256.643632)
			(xy 348.667771 -256.613106) (xy 348.631048 -256.576383) (xy 348.600522 -256.534367) (xy 348.576944 -256.488093)
			(xy 348.560896 -256.4387) (xy 348.552771 -256.387405) (xy 348.272607 -256.387405) (xy 348.264482 -256.4387)
			(xy 348.248434 -256.488093) (xy 348.224856 -256.534367) (xy 348.19433 -256.576383) (xy 348.157607 -256.613106)
			(xy 348.115591 -256.643632) (xy 348.069317 -256.66721) (xy 348.019924 -256.683258) (xy 347.968629 -256.691383)
			(xy 347.916695 -256.691383) (xy 347.8654 -256.683258) (xy 347.816007 -256.66721) (xy 347.769733 -256.643632)
			(xy 347.727717 -256.613106) (xy 347.690994 -256.576383) (xy 347.660468 -256.534367) (xy 347.63689 -256.488093)
			(xy 347.620842 -256.4387) (xy 347.612717 -256.387405) (xy 347.332807 -256.387405) (xy 347.324682 -256.4387)
			(xy 347.308634 -256.488093) (xy 347.285056 -256.534367) (xy 347.25453 -256.576383) (xy 347.217807 -256.613106)
			(xy 347.175791 -256.643632) (xy 347.129517 -256.66721) (xy 347.080124 -256.683258) (xy 347.028829 -256.691383)
			(xy 346.976895 -256.691383) (xy 346.9256 -256.683258) (xy 346.876207 -256.66721) (xy 346.829933 -256.643632)
			(xy 346.787917 -256.613106) (xy 346.751194 -256.576383) (xy 346.720668 -256.534367) (xy 346.69709 -256.488093)
			(xy 346.681042 -256.4387) (xy 346.672917 -256.387405) (xy 346.393007 -256.387405) (xy 346.384882 -256.4387)
			(xy 346.368834 -256.488093) (xy 346.345256 -256.534367) (xy 346.31473 -256.576383) (xy 346.278007 -256.613106)
			(xy 346.235991 -256.643632) (xy 346.189717 -256.66721) (xy 346.140324 -256.683258) (xy 346.089029 -256.691383)
			(xy 346.037095 -256.691383) (xy 345.9858 -256.683258) (xy 345.936407 -256.66721) (xy 345.890133 -256.643632)
			(xy 345.848117 -256.613106) (xy 345.811394 -256.576383) (xy 345.780868 -256.534367) (xy 345.75729 -256.488093)
			(xy 345.741242 -256.4387) (xy 345.733117 -256.387405) (xy 345.453207 -256.387405) (xy 345.445082 -256.4387)
			(xy 345.429034 -256.488093) (xy 345.405456 -256.534367) (xy 345.37493 -256.576383) (xy 345.338207 -256.613106)
			(xy 345.296191 -256.643632) (xy 345.249917 -256.66721) (xy 345.200524 -256.683258) (xy 345.149229 -256.691383)
			(xy 345.097295 -256.691383) (xy 345.046 -256.683258) (xy 344.996607 -256.66721) (xy 344.950333 -256.643632)
			(xy 344.908317 -256.613106) (xy 344.871594 -256.576383) (xy 344.841068 -256.534367) (xy 344.81749 -256.488093)
			(xy 344.801442 -256.4387) (xy 344.793317 -256.387405) (xy 344.513407 -256.387405) (xy 344.505282 -256.4387)
			(xy 344.489234 -256.488093) (xy 344.465656 -256.534367) (xy 344.43513 -256.576383) (xy 344.398407 -256.613106)
			(xy 344.356391 -256.643632) (xy 344.310117 -256.66721) (xy 344.260724 -256.683258) (xy 344.209429 -256.691383)
			(xy 344.157495 -256.691383) (xy 344.1062 -256.683258) (xy 344.056807 -256.66721) (xy 344.010533 -256.643632)
			(xy 343.968517 -256.613106) (xy 343.931794 -256.576383) (xy 343.901268 -256.534367) (xy 343.87769 -256.488093)
			(xy 343.861642 -256.4387) (xy 343.853517 -256.387405) (xy 343.573607 -256.387405) (xy 343.565482 -256.4387)
			(xy 343.549434 -256.488093) (xy 343.525856 -256.534367) (xy 343.49533 -256.576383) (xy 343.458607 -256.613106)
			(xy 343.416591 -256.643632) (xy 343.370317 -256.66721) (xy 343.320924 -256.683258) (xy 343.269629 -256.691383)
			(xy 343.217695 -256.691383) (xy 343.1664 -256.683258) (xy 343.117007 -256.66721) (xy 343.070733 -256.643632)
			(xy 343.028717 -256.613106) (xy 342.991994 -256.576383) (xy 342.961468 -256.534367) (xy 342.93789 -256.488093)
			(xy 342.921842 -256.4387) (xy 342.913717 -256.387405) (xy 342.634061 -256.387405) (xy 342.625936 -256.4387)
			(xy 342.609888 -256.488093) (xy 342.58631 -256.534367) (xy 342.555784 -256.576383) (xy 342.519061 -256.613106)
			(xy 342.477045 -256.643632) (xy 342.430771 -256.66721) (xy 342.381378 -256.683258) (xy 342.330083 -256.691383)
			(xy 342.278149 -256.691383) (xy 342.226854 -256.683258) (xy 342.177461 -256.66721) (xy 342.131187 -256.643632)
			(xy 342.089171 -256.613106) (xy 342.052448 -256.576383) (xy 342.021922 -256.534367) (xy 341.998344 -256.488093)
			(xy 341.982296 -256.4387) (xy 341.974171 -256.387405) (xy 341.694257 -256.387405) (xy 341.694257 -256.387422)
			(xy 341.686122 -256.43875) (xy 341.670057 -256.488173) (xy 341.646458 -256.534474) (xy 341.615907 -256.576514)
			(xy 341.579156 -256.613257) (xy 341.537109 -256.643798) (xy 341.490802 -256.667386) (xy 341.441376 -256.683439)
			(xy 341.390046 -256.691563) (xy 341.364062 -256.692146) (xy 341.339074 -256.691685) (xy 341.289667 -256.684158)
			(xy 341.241956 -256.669282) (xy 341.197027 -256.647394) (xy 341.155904 -256.618994) (xy 341.119523 -256.584728)
			(xy 341.088714 -256.545378) (xy 341.064177 -256.501839) (xy 341.046473 -256.455103) (xy 341.04072 -256.43078)
			(xy 341.04072 -256.430272) (xy 341.040466 -256.430272) (xy 341.038248 -256.421587) (xy 341.028652 -256.406461)
			(xy 341.014388 -256.395627) (xy 341.005922 -256.39268) (xy 340.963504 -256.37998) (xy 340.918292 -256.366772)
			(xy 340.910004 -256.365208) (xy 340.89325 -256.36705) (xy 340.878021 -256.374276) (xy 340.87181 -256.37998)
			(xy 340.678262 -256.573528) (xy 340.675468 -256.576576) (xy 340.67496 -256.577084) (xy 340.673944 -256.5781)
			(xy 340.673944 -256.578354) (xy 340.666263 -256.587041) (xy 340.649862 -256.603436) (xy 340.641178 -256.61112)
			(xy 340.640924 -256.61112) (xy 340.639908 -256.612136) (xy 340.6394 -256.612644) (xy 340.636352 -256.615438)
			(xy 340.266782 -256.985008) (xy 340.260266 -256.992203) (xy 340.252825 -257.010112) (xy 340.252304 -257.019806)
			(xy 340.256622 -257.04038) (xy 340.258654 -257.044952) (xy 340.267084 -257.065586) (xy 340.278956 -257.108548)
			(xy 340.28496 -257.152714) (xy 340.285324 -257.175) (xy 340.285324 -257.175254) (xy 340.284844 -257.201221)
			(xy 340.564217 -257.201221) (xy 340.564217 -257.149287) (xy 340.572342 -257.097992) (xy 340.58839 -257.048599)
			(xy 340.611968 -257.002325) (xy 340.642494 -256.960309) (xy 340.679217 -256.923586) (xy 340.721233 -256.89306)
			(xy 340.767507 -256.869482) (xy 340.8169 -256.853434) (xy 340.868195 -256.845309) (xy 340.920129 -256.845309)
			(xy 340.971424 -256.853434) (xy 341.020817 -256.869482) (xy 341.067091 -256.89306) (xy 341.109107 -256.923586)
			(xy 341.14583 -256.960309) (xy 341.176356 -257.002325) (xy 341.199934 -257.048599) (xy 341.215982 -257.097992)
			(xy 341.224107 -257.149287) (xy 341.224616 -257.175254) (xy 341.224107 -257.201221) (xy 341.504271 -257.201221)
			(xy 341.504271 -257.149287) (xy 341.512396 -257.097992) (xy 341.528444 -257.048599) (xy 341.552022 -257.002325)
			(xy 341.582548 -256.960309) (xy 341.619271 -256.923586) (xy 341.661287 -256.89306) (xy 341.707561 -256.869482)
			(xy 341.756954 -256.853434) (xy 341.808249 -256.845309) (xy 341.860183 -256.845309) (xy 341.911478 -256.853434)
			(xy 341.960871 -256.869482) (xy 342.007145 -256.89306) (xy 342.049161 -256.923586) (xy 342.085884 -256.960309)
			(xy 342.11641 -257.002325) (xy 342.139988 -257.048599) (xy 342.156036 -257.097992) (xy 342.164161 -257.149287)
			(xy 342.16467 -257.175254) (xy 342.164161 -257.201221) (xy 342.444071 -257.201221) (xy 342.444071 -257.149287)
			(xy 342.452196 -257.097992) (xy 342.468244 -257.048599) (xy 342.491822 -257.002325) (xy 342.522348 -256.960309)
			(xy 342.559071 -256.923586) (xy 342.601087 -256.89306) (xy 342.647361 -256.869482) (xy 342.696754 -256.853434)
			(xy 342.748049 -256.845309) (xy 342.799983 -256.845309) (xy 342.851278 -256.853434) (xy 342.900671 -256.869482)
			(xy 342.946945 -256.89306) (xy 342.988961 -256.923586) (xy 343.025684 -256.960309) (xy 343.05621 -257.002325)
			(xy 343.079788 -257.048599) (xy 343.095836 -257.097992) (xy 343.103961 -257.149287) (xy 343.10447 -257.175254)
			(xy 343.103961 -257.201221) (xy 343.383871 -257.201221) (xy 343.383871 -257.149287) (xy 343.391996 -257.097992)
			(xy 343.408044 -257.048599) (xy 343.431622 -257.002325) (xy 343.462148 -256.960309) (xy 343.498871 -256.923586)
			(xy 343.540887 -256.89306) (xy 343.587161 -256.869482) (xy 343.636554 -256.853434) (xy 343.687849 -256.845309)
			(xy 343.739783 -256.845309) (xy 343.791078 -256.853434) (xy 343.840471 -256.869482) (xy 343.886745 -256.89306)
			(xy 343.928761 -256.923586) (xy 343.965484 -256.960309) (xy 343.99601 -257.002325) (xy 344.019588 -257.048599)
			(xy 344.035636 -257.097992) (xy 344.043761 -257.149287) (xy 344.04427 -257.175254) (xy 344.043761 -257.201221)
			(xy 344.323671 -257.201221) (xy 344.323671 -257.149287) (xy 344.331796 -257.097992) (xy 344.347844 -257.048599)
			(xy 344.371422 -257.002325) (xy 344.401948 -256.960309) (xy 344.438671 -256.923586) (xy 344.480687 -256.89306)
			(xy 344.526961 -256.869482) (xy 344.576354 -256.853434) (xy 344.627649 -256.845309) (xy 344.679583 -256.845309)
			(xy 344.730878 -256.853434) (xy 344.780271 -256.869482) (xy 344.826545 -256.89306) (xy 344.868561 -256.923586)
			(xy 344.905284 -256.960309) (xy 344.93581 -257.002325) (xy 344.959388 -257.048599) (xy 344.975436 -257.097992)
			(xy 344.983561 -257.149287) (xy 344.98407 -257.175254) (xy 344.983561 -257.201221) (xy 345.263217 -257.201221)
			(xy 345.263217 -257.149287) (xy 345.271342 -257.097992) (xy 345.28739 -257.048599) (xy 345.310968 -257.002325)
			(xy 345.341494 -256.960309) (xy 345.378217 -256.923586) (xy 345.420233 -256.89306) (xy 345.466507 -256.869482)
			(xy 345.5159 -256.853434) (xy 345.567195 -256.845309) (xy 345.619129 -256.845309) (xy 345.670424 -256.853434)
			(xy 345.719817 -256.869482) (xy 345.766091 -256.89306) (xy 345.808107 -256.923586) (xy 345.84483 -256.960309)
			(xy 345.875356 -257.002325) (xy 345.898934 -257.048599) (xy 345.914982 -257.097992) (xy 345.923107 -257.149287)
			(xy 345.923616 -257.175254) (xy 345.923107 -257.201221) (xy 346.203271 -257.201221) (xy 346.203271 -257.149287)
			(xy 346.211396 -257.097992) (xy 346.227444 -257.048599) (xy 346.251022 -257.002325) (xy 346.281548 -256.960309)
			(xy 346.318271 -256.923586) (xy 346.360287 -256.89306) (xy 346.406561 -256.869482) (xy 346.455954 -256.853434)
			(xy 346.507249 -256.845309) (xy 346.559183 -256.845309) (xy 346.610478 -256.853434) (xy 346.659871 -256.869482)
			(xy 346.706145 -256.89306) (xy 346.748161 -256.923586) (xy 346.784884 -256.960309) (xy 346.81541 -257.002325)
			(xy 346.838988 -257.048599) (xy 346.855036 -257.097992) (xy 346.863161 -257.149287) (xy 346.86367 -257.175254)
			(xy 346.863161 -257.201221) (xy 347.142817 -257.201221) (xy 347.142817 -257.149287) (xy 347.150942 -257.097992)
			(xy 347.16699 -257.048599) (xy 347.190568 -257.002325) (xy 347.221094 -256.960309) (xy 347.257817 -256.923586)
			(xy 347.299833 -256.89306) (xy 347.346107 -256.869482) (xy 347.3955 -256.853434) (xy 347.446795 -256.845309)
			(xy 347.498729 -256.845309) (xy 347.550024 -256.853434) (xy 347.599417 -256.869482) (xy 347.645691 -256.89306)
			(xy 347.687707 -256.923586) (xy 347.72443 -256.960309) (xy 347.754956 -257.002325) (xy 347.778534 -257.048599)
			(xy 347.794582 -257.097992) (xy 347.802707 -257.149287) (xy 347.803216 -257.175254) (xy 347.802707 -257.201221)
			(xy 348.082871 -257.201221) (xy 348.082871 -257.149287) (xy 348.090996 -257.097992) (xy 348.107044 -257.048599)
			(xy 348.130622 -257.002325) (xy 348.161148 -256.960309) (xy 348.197871 -256.923586) (xy 348.239887 -256.89306)
			(xy 348.286161 -256.869482) (xy 348.335554 -256.853434) (xy 348.386849 -256.845309) (xy 348.438783 -256.845309)
			(xy 348.490078 -256.853434) (xy 348.539471 -256.869482) (xy 348.585745 -256.89306) (xy 348.627761 -256.923586)
			(xy 348.664484 -256.960309) (xy 348.69501 -257.002325) (xy 348.718588 -257.048599) (xy 348.734636 -257.097992)
			(xy 348.742761 -257.149287) (xy 348.74327 -257.175254) (xy 348.742761 -257.201221) (xy 349.022671 -257.201221)
			(xy 349.022671 -257.149287) (xy 349.030796 -257.097992) (xy 349.046844 -257.048599) (xy 349.070422 -257.002325)
			(xy 349.100948 -256.960309) (xy 349.137671 -256.923586) (xy 349.179687 -256.89306) (xy 349.225961 -256.869482)
			(xy 349.275354 -256.853434) (xy 349.326649 -256.845309) (xy 349.378583 -256.845309) (xy 349.429878 -256.853434)
			(xy 349.479271 -256.869482) (xy 349.525545 -256.89306) (xy 349.567561 -256.923586) (xy 349.604284 -256.960309)
			(xy 349.63481 -257.002325) (xy 349.658388 -257.048599) (xy 349.674436 -257.097992) (xy 349.682561 -257.149287)
			(xy 349.68307 -257.175254) (xy 349.682561 -257.201221) (xy 349.962471 -257.201221) (xy 349.962471 -257.149287)
			(xy 349.970596 -257.097992) (xy 349.986644 -257.048599) (xy 350.010222 -257.002325) (xy 350.040748 -256.960309)
			(xy 350.077471 -256.923586) (xy 350.119487 -256.89306) (xy 350.165761 -256.869482) (xy 350.215154 -256.853434)
			(xy 350.266449 -256.845309) (xy 350.318383 -256.845309) (xy 350.369678 -256.853434) (xy 350.419071 -256.869482)
			(xy 350.465345 -256.89306) (xy 350.507361 -256.923586) (xy 350.544084 -256.960309) (xy 350.57461 -257.002325)
			(xy 350.598188 -257.048599) (xy 350.614236 -257.097992) (xy 350.622361 -257.149287) (xy 350.62287 -257.175254)
			(xy 350.622361 -257.201221) (xy 350.614236 -257.252516) (xy 350.598188 -257.301909) (xy 350.57461 -257.348183)
			(xy 350.544084 -257.390199) (xy 350.507361 -257.426922) (xy 350.465345 -257.457448) (xy 350.419071 -257.481026)
			(xy 350.369678 -257.497074) (xy 350.318383 -257.505199) (xy 350.266449 -257.505199) (xy 350.215154 -257.497074)
			(xy 350.165761 -257.481026) (xy 350.119487 -257.457448) (xy 350.077471 -257.426922) (xy 350.040748 -257.390199)
			(xy 350.010222 -257.348183) (xy 349.986644 -257.301909) (xy 349.970596 -257.252516) (xy 349.962471 -257.201221)
			(xy 349.682561 -257.201221) (xy 349.674436 -257.252516) (xy 349.658388 -257.301909) (xy 349.63481 -257.348183)
			(xy 349.604284 -257.390199) (xy 349.567561 -257.426922) (xy 349.525545 -257.457448) (xy 349.479271 -257.481026)
			(xy 349.429878 -257.497074) (xy 349.378583 -257.505199) (xy 349.326649 -257.505199) (xy 349.275354 -257.497074)
			(xy 349.225961 -257.481026) (xy 349.179687 -257.457448) (xy 349.137671 -257.426922) (xy 349.100948 -257.390199)
			(xy 349.070422 -257.348183) (xy 349.046844 -257.301909) (xy 349.030796 -257.252516) (xy 349.022671 -257.201221)
			(xy 348.742761 -257.201221) (xy 348.734636 -257.252516) (xy 348.718588 -257.301909) (xy 348.69501 -257.348183)
			(xy 348.664484 -257.390199) (xy 348.627761 -257.426922) (xy 348.585745 -257.457448) (xy 348.539471 -257.481026)
			(xy 348.490078 -257.497074) (xy 348.438783 -257.505199) (xy 348.386849 -257.505199) (xy 348.335554 -257.497074)
			(xy 348.286161 -257.481026) (xy 348.239887 -257.457448) (xy 348.197871 -257.426922) (xy 348.161148 -257.390199)
			(xy 348.130622 -257.348183) (xy 348.107044 -257.301909) (xy 348.090996 -257.252516) (xy 348.082871 -257.201221)
			(xy 347.802707 -257.201221) (xy 347.794582 -257.252516) (xy 347.778534 -257.301909) (xy 347.754956 -257.348183)
			(xy 347.72443 -257.390199) (xy 347.687707 -257.426922) (xy 347.645691 -257.457448) (xy 347.599417 -257.481026)
			(xy 347.550024 -257.497074) (xy 347.498729 -257.505199) (xy 347.446795 -257.505199) (xy 347.3955 -257.497074)
			(xy 347.346107 -257.481026) (xy 347.299833 -257.457448) (xy 347.257817 -257.426922) (xy 347.221094 -257.390199)
			(xy 347.190568 -257.348183) (xy 347.16699 -257.301909) (xy 347.150942 -257.252516) (xy 347.142817 -257.201221)
			(xy 346.863161 -257.201221) (xy 346.855036 -257.252516) (xy 346.838988 -257.301909) (xy 346.81541 -257.348183)
			(xy 346.784884 -257.390199) (xy 346.748161 -257.426922) (xy 346.706145 -257.457448) (xy 346.659871 -257.481026)
			(xy 346.610478 -257.497074) (xy 346.559183 -257.505199) (xy 346.507249 -257.505199) (xy 346.455954 -257.497074)
			(xy 346.406561 -257.481026) (xy 346.360287 -257.457448) (xy 346.318271 -257.426922) (xy 346.281548 -257.390199)
			(xy 346.251022 -257.348183) (xy 346.227444 -257.301909) (xy 346.211396 -257.252516) (xy 346.203271 -257.201221)
			(xy 345.923107 -257.201221) (xy 345.914982 -257.252516) (xy 345.898934 -257.301909) (xy 345.875356 -257.348183)
			(xy 345.84483 -257.390199) (xy 345.808107 -257.426922) (xy 345.766091 -257.457448) (xy 345.719817 -257.481026)
			(xy 345.670424 -257.497074) (xy 345.619129 -257.505199) (xy 345.567195 -257.505199) (xy 345.5159 -257.497074)
			(xy 345.466507 -257.481026) (xy 345.420233 -257.457448) (xy 345.378217 -257.426922) (xy 345.341494 -257.390199)
			(xy 345.310968 -257.348183) (xy 345.28739 -257.301909) (xy 345.271342 -257.252516) (xy 345.263217 -257.201221)
			(xy 344.983561 -257.201221) (xy 344.975436 -257.252516) (xy 344.959388 -257.301909) (xy 344.93581 -257.348183)
			(xy 344.905284 -257.390199) (xy 344.868561 -257.426922) (xy 344.826545 -257.457448) (xy 344.780271 -257.481026)
			(xy 344.730878 -257.497074) (xy 344.679583 -257.505199) (xy 344.627649 -257.505199) (xy 344.576354 -257.497074)
			(xy 344.526961 -257.481026) (xy 344.480687 -257.457448) (xy 344.438671 -257.426922) (xy 344.401948 -257.390199)
			(xy 344.371422 -257.348183) (xy 344.347844 -257.301909) (xy 344.331796 -257.252516) (xy 344.323671 -257.201221)
			(xy 344.043761 -257.201221) (xy 344.035636 -257.252516) (xy 344.019588 -257.301909) (xy 343.99601 -257.348183)
			(xy 343.965484 -257.390199) (xy 343.928761 -257.426922) (xy 343.886745 -257.457448) (xy 343.840471 -257.481026)
			(xy 343.791078 -257.497074) (xy 343.739783 -257.505199) (xy 343.687849 -257.505199) (xy 343.636554 -257.497074)
			(xy 343.587161 -257.481026) (xy 343.540887 -257.457448) (xy 343.498871 -257.426922) (xy 343.462148 -257.390199)
			(xy 343.431622 -257.348183) (xy 343.408044 -257.301909) (xy 343.391996 -257.252516) (xy 343.383871 -257.201221)
			(xy 343.103961 -257.201221) (xy 343.095836 -257.252516) (xy 343.079788 -257.301909) (xy 343.05621 -257.348183)
			(xy 343.025684 -257.390199) (xy 342.988961 -257.426922) (xy 342.946945 -257.457448) (xy 342.900671 -257.481026)
			(xy 342.851278 -257.497074) (xy 342.799983 -257.505199) (xy 342.748049 -257.505199) (xy 342.696754 -257.497074)
			(xy 342.647361 -257.481026) (xy 342.601087 -257.457448) (xy 342.559071 -257.426922) (xy 342.522348 -257.390199)
			(xy 342.491822 -257.348183) (xy 342.468244 -257.301909) (xy 342.452196 -257.252516) (xy 342.444071 -257.201221)
			(xy 342.164161 -257.201221) (xy 342.156036 -257.252516) (xy 342.139988 -257.301909) (xy 342.11641 -257.348183)
			(xy 342.085884 -257.390199) (xy 342.049161 -257.426922) (xy 342.007145 -257.457448) (xy 341.960871 -257.481026)
			(xy 341.911478 -257.497074) (xy 341.860183 -257.505199) (xy 341.808249 -257.505199) (xy 341.756954 -257.497074)
			(xy 341.707561 -257.481026) (xy 341.661287 -257.457448) (xy 341.619271 -257.426922) (xy 341.582548 -257.390199)
			(xy 341.552022 -257.348183) (xy 341.528444 -257.301909) (xy 341.512396 -257.252516) (xy 341.504271 -257.201221)
			(xy 341.224107 -257.201221) (xy 341.215982 -257.252516) (xy 341.199934 -257.301909) (xy 341.176356 -257.348183)
			(xy 341.14583 -257.390199) (xy 341.109107 -257.426922) (xy 341.067091 -257.457448) (xy 341.020817 -257.481026)
			(xy 340.971424 -257.497074) (xy 340.920129 -257.505199) (xy 340.868195 -257.505199) (xy 340.8169 -257.497074)
			(xy 340.767507 -257.481026) (xy 340.721233 -257.457448) (xy 340.679217 -257.426922) (xy 340.642494 -257.390199)
			(xy 340.611968 -257.348183) (xy 340.58839 -257.301909) (xy 340.572342 -257.252516) (xy 340.564217 -257.201221)
			(xy 340.284844 -257.201221) (xy 340.284844 -257.201246) (xy 340.276719 -257.252591) (xy 340.260661 -257.302033)
			(xy 340.237066 -257.348354) (xy 340.206515 -257.390413) (xy 340.16976 -257.427174) (xy 340.127707 -257.457733)
			(xy 340.08139 -257.481337) (xy 340.031952 -257.497404) (xy 339.980608 -257.505539) (xy 339.954616 -257.505962)
			(xy 339.926268 -257.505379) (xy 339.870402 -257.495712) (xy 339.817004 -257.476658) (xy 339.767638 -257.448776)
			(xy 339.74532 -257.431286) (xy 339.738716 -257.425952) (xy 339.706204 -257.41376) (xy 339.696368 -257.4143)
			(xy 339.67821 -257.421889) (xy 339.670898 -257.428492) (xy 339.642196 -257.457194) (xy 339.635479 -257.464431)
			(xy 339.627877 -257.482636) (xy 339.627464 -257.4925) (xy 339.627464 -257.660902) (xy 339.651848 -257.703574)
			(xy 339.662516 -257.710432) (xy 339.683769 -257.724555) (xy 339.722056 -257.758287) (xy 339.754704 -257.797501)
			(xy 339.780939 -257.841267) (xy 339.800138 -257.888544) (xy 339.811843 -257.938209) (xy 339.815778 -257.989084)
			(xy 339.813773 -258.015037) (xy 340.094571 -258.015037) (xy 340.094571 -257.963103) (xy 340.102696 -257.911808)
			(xy 340.118744 -257.862415) (xy 340.142322 -257.816141) (xy 340.172848 -257.774125) (xy 340.209571 -257.737402)
			(xy 340.251587 -257.706876) (xy 340.297861 -257.683298) (xy 340.347254 -257.66725) (xy 340.398549 -257.659125)
			(xy 340.450483 -257.659125) (xy 340.501778 -257.66725) (xy 340.551171 -257.683298) (xy 340.597445 -257.706876)
			(xy 340.639461 -257.737402) (xy 340.676184 -257.774125) (xy 340.70671 -257.816141) (xy 340.730288 -257.862415)
			(xy 340.746336 -257.911808) (xy 340.754461 -257.963103) (xy 340.75497 -257.98907) (xy 340.754461 -258.015037)
			(xy 341.034117 -258.015037) (xy 341.034117 -257.963103) (xy 341.042242 -257.911808) (xy 341.05829 -257.862415)
			(xy 341.081868 -257.816141) (xy 341.112394 -257.774125) (xy 341.149117 -257.737402) (xy 341.191133 -257.706876)
			(xy 341.237407 -257.683298) (xy 341.2868 -257.66725) (xy 341.338095 -257.659125) (xy 341.390029 -257.659125)
			(xy 341.441324 -257.66725) (xy 341.490717 -257.683298) (xy 341.536991 -257.706876) (xy 341.579007 -257.737402)
			(xy 341.61573 -257.774125) (xy 341.646256 -257.816141) (xy 341.669834 -257.862415) (xy 341.685882 -257.911808)
			(xy 341.694007 -257.963103) (xy 341.694516 -257.98907) (xy 341.694007 -258.015037) (xy 341.973917 -258.015037)
			(xy 341.973917 -257.963103) (xy 341.982042 -257.911808) (xy 341.99809 -257.862415) (xy 342.021668 -257.816141)
			(xy 342.052194 -257.774125) (xy 342.088917 -257.737402) (xy 342.130933 -257.706876) (xy 342.177207 -257.683298)
			(xy 342.2266 -257.66725) (xy 342.277895 -257.659125) (xy 342.329829 -257.659125) (xy 342.381124 -257.66725)
			(xy 342.430517 -257.683298) (xy 342.476791 -257.706876) (xy 342.518807 -257.737402) (xy 342.55553 -257.774125)
			(xy 342.586056 -257.816141) (xy 342.609634 -257.862415) (xy 342.625682 -257.911808) (xy 342.633807 -257.963103)
			(xy 342.634316 -257.98907) (xy 342.633807 -258.015037) (xy 342.913717 -258.015037) (xy 342.913717 -257.963103)
			(xy 342.921842 -257.911808) (xy 342.93789 -257.862415) (xy 342.961468 -257.816141) (xy 342.991994 -257.774125)
			(xy 343.028717 -257.737402) (xy 343.070733 -257.706876) (xy 343.117007 -257.683298) (xy 343.1664 -257.66725)
			(xy 343.217695 -257.659125) (xy 343.269629 -257.659125) (xy 343.320924 -257.66725) (xy 343.370317 -257.683298)
			(xy 343.416591 -257.706876) (xy 343.458607 -257.737402) (xy 343.49533 -257.774125) (xy 343.525856 -257.816141)
			(xy 343.549434 -257.862415) (xy 343.565482 -257.911808) (xy 343.573607 -257.963103) (xy 343.574116 -257.98907)
			(xy 343.573607 -258.015037) (xy 343.853517 -258.015037) (xy 343.853517 -257.963103) (xy 343.861642 -257.911808)
			(xy 343.87769 -257.862415) (xy 343.901268 -257.816141) (xy 343.931794 -257.774125) (xy 343.968517 -257.737402)
			(xy 344.010533 -257.706876) (xy 344.056807 -257.683298) (xy 344.1062 -257.66725) (xy 344.157495 -257.659125)
			(xy 344.209429 -257.659125) (xy 344.260724 -257.66725) (xy 344.310117 -257.683298) (xy 344.356391 -257.706876)
			(xy 344.398407 -257.737402) (xy 344.43513 -257.774125) (xy 344.465656 -257.816141) (xy 344.489234 -257.862415)
			(xy 344.505282 -257.911808) (xy 344.513407 -257.963103) (xy 344.513916 -257.98907) (xy 344.513407 -258.015037)
			(xy 344.793571 -258.015037) (xy 344.793571 -257.963103) (xy 344.801696 -257.911808) (xy 344.817744 -257.862415)
			(xy 344.841322 -257.816141) (xy 344.871848 -257.774125) (xy 344.908571 -257.737402) (xy 344.950587 -257.706876)
			(xy 344.996861 -257.683298) (xy 345.046254 -257.66725) (xy 345.097549 -257.659125) (xy 345.149483 -257.659125)
			(xy 345.200778 -257.66725) (xy 345.250171 -257.683298) (xy 345.296445 -257.706876) (xy 345.338461 -257.737402)
			(xy 345.375184 -257.774125) (xy 345.40571 -257.816141) (xy 345.429288 -257.862415) (xy 345.445336 -257.911808)
			(xy 345.453461 -257.963103) (xy 345.45397 -257.98907) (xy 345.453461 -258.015037) (xy 345.733117 -258.015037)
			(xy 345.733117 -257.963103) (xy 345.741242 -257.911808) (xy 345.75729 -257.862415) (xy 345.780868 -257.816141)
			(xy 345.811394 -257.774125) (xy 345.848117 -257.737402) (xy 345.890133 -257.706876) (xy 345.936407 -257.683298)
			(xy 345.9858 -257.66725) (xy 346.037095 -257.659125) (xy 346.089029 -257.659125) (xy 346.140324 -257.66725)
			(xy 346.189717 -257.683298) (xy 346.235991 -257.706876) (xy 346.278007 -257.737402) (xy 346.31473 -257.774125)
			(xy 346.345256 -257.816141) (xy 346.368834 -257.862415) (xy 346.384882 -257.911808) (xy 346.393007 -257.963103)
			(xy 346.393516 -257.98907) (xy 346.393007 -258.015037) (xy 346.673171 -258.015037) (xy 346.673171 -257.963103)
			(xy 346.681296 -257.911808) (xy 346.697344 -257.862415) (xy 346.720922 -257.816141) (xy 346.751448 -257.774125)
			(xy 346.788171 -257.737402) (xy 346.830187 -257.706876) (xy 346.876461 -257.683298) (xy 346.925854 -257.66725)
			(xy 346.977149 -257.659125) (xy 347.029083 -257.659125) (xy 347.080378 -257.66725) (xy 347.129771 -257.683298)
			(xy 347.176045 -257.706876) (xy 347.218061 -257.737402) (xy 347.254784 -257.774125) (xy 347.28531 -257.816141)
			(xy 347.308888 -257.862415) (xy 347.324936 -257.911808) (xy 347.333061 -257.963103) (xy 347.33357 -257.98907)
			(xy 347.333061 -258.015037) (xy 347.612717 -258.015037) (xy 347.612717 -257.963103) (xy 347.620842 -257.911808)
			(xy 347.63689 -257.862415) (xy 347.660468 -257.816141) (xy 347.690994 -257.774125) (xy 347.727717 -257.737402)
			(xy 347.769733 -257.706876) (xy 347.816007 -257.683298) (xy 347.8654 -257.66725) (xy 347.916695 -257.659125)
			(xy 347.968629 -257.659125) (xy 348.019924 -257.66725) (xy 348.069317 -257.683298) (xy 348.115591 -257.706876)
			(xy 348.157607 -257.737402) (xy 348.19433 -257.774125) (xy 348.224856 -257.816141) (xy 348.248434 -257.862415)
			(xy 348.264482 -257.911808) (xy 348.272607 -257.963103) (xy 348.273116 -257.98907) (xy 348.272607 -258.015037)
			(xy 348.552517 -258.015037) (xy 348.552517 -257.963103) (xy 348.560642 -257.911808) (xy 348.57669 -257.862415)
			(xy 348.600268 -257.816141) (xy 348.630794 -257.774125) (xy 348.667517 -257.737402) (xy 348.709533 -257.706876)
			(xy 348.755807 -257.683298) (xy 348.8052 -257.66725) (xy 348.856495 -257.659125) (xy 348.908429 -257.659125)
			(xy 348.959724 -257.66725) (xy 349.009117 -257.683298) (xy 349.055391 -257.706876) (xy 349.097407 -257.737402)
			(xy 349.13413 -257.774125) (xy 349.164656 -257.816141) (xy 349.188234 -257.862415) (xy 349.204282 -257.911808)
			(xy 349.212407 -257.963103) (xy 349.212916 -257.98907) (xy 349.212407 -258.015037) (xy 349.492317 -258.015037)
			(xy 349.492317 -257.963103) (xy 349.500442 -257.911808) (xy 349.51649 -257.862415) (xy 349.540068 -257.816141)
			(xy 349.570594 -257.774125) (xy 349.607317 -257.737402) (xy 349.649333 -257.706876) (xy 349.695607 -257.683298)
			(xy 349.745 -257.66725) (xy 349.796295 -257.659125) (xy 349.848229 -257.659125) (xy 349.899524 -257.66725)
			(xy 349.948917 -257.683298) (xy 349.995191 -257.706876) (xy 350.011698 -257.718869) (xy 351.009435 -257.718869)
			(xy 351.009435 -257.666931) (xy 351.01756 -257.615632) (xy 351.03361 -257.566236) (xy 351.057189 -257.519959)
			(xy 351.087718 -257.477941) (xy 351.124444 -257.441215) (xy 351.166463 -257.410687) (xy 351.21274 -257.387108)
			(xy 351.262136 -257.371059) (xy 351.313435 -257.362935) (xy 351.339404 -257.362452) (xy 351.339658 -257.362452)
			(xy 351.364185 -257.362881) (xy 351.412699 -257.370152) (xy 351.459606 -257.384509) (xy 351.503877 -257.405639)
			(xy 351.544541 -257.433077) (xy 351.562924 -257.44932) (xy 351.574413 -257.459123) (xy 351.60165 -257.472137)
			(xy 351.631504 -257.476605) (xy 351.661358 -257.472137) (xy 351.688595 -257.459123) (xy 351.700084 -257.44932)
			(xy 351.718479 -257.43305) (xy 351.759186 -257.405583) (xy 351.803511 -257.384446) (xy 351.850478 -257.370106)
			(xy 351.89905 -257.362879) (xy 351.923604 -257.362452) (xy 351.948157 -257.362864) (xy 351.996725 -257.370112)
			(xy 352.043687 -257.384463) (xy 352.08801 -257.405601) (xy 352.128721 -257.433061) (xy 352.147124 -257.44932)
			(xy 352.158613 -257.459123) (xy 352.18585 -257.472137) (xy 352.215704 -257.476605) (xy 352.245558 -257.472137)
			(xy 352.272795 -257.459123) (xy 352.284284 -257.44932) (xy 352.302659 -257.433066) (xy 352.343319 -257.405621)
			(xy 352.387593 -257.384492) (xy 352.434504 -257.370146) (xy 352.483022 -257.362896) (xy 352.50755 -257.362452)
			(xy 352.507804 -257.362452) (xy 352.533771 -257.36295) (xy 352.585067 -257.371075) (xy 352.63446 -257.387124)
			(xy 352.680734 -257.410702) (xy 352.72275 -257.441229) (xy 352.759473 -257.477953) (xy 352.79 -257.519969)
			(xy 352.813578 -257.566244) (xy 352.829626 -257.615637) (xy 352.837751 -257.666933) (xy 352.837751 -257.718867)
			(xy 352.837751 -257.718869) (xy 353.066835 -257.718869) (xy 353.066835 -257.666931) (xy 353.07496 -257.615632)
			(xy 353.09101 -257.566236) (xy 353.114589 -257.519959) (xy 353.145118 -257.477941) (xy 353.181844 -257.441215)
			(xy 353.223863 -257.410687) (xy 353.27014 -257.387108) (xy 353.319536 -257.371059) (xy 353.370835 -257.362935)
			(xy 353.396804 -257.362452) (xy 353.422557 -257.362948) (xy 353.473442 -257.370928) (xy 353.522471 -257.386708)
			(xy 353.568457 -257.409907) (xy 353.610285 -257.439962) (xy 353.62896 -257.457702) (xy 353.63865 -257.466695)
			(xy 353.661582 -257.479827) (xy 353.687121 -257.486622) (xy 353.713547 -257.486622) (xy 353.739086 -257.479827)
			(xy 353.762018 -257.466695) (xy 353.771708 -257.457702) (xy 353.790385 -257.439965) (xy 353.832218 -257.409919)
			(xy 353.878204 -257.386723) (xy 353.92723 -257.370938) (xy 353.978112 -257.362947) (xy 354.003864 -257.362452)
			(xy 354.03026 -257.362964) (xy 354.082379 -257.371359) (xy 354.132498 -257.387941) (xy 354.17934 -257.412287)
			(xy 354.221711 -257.443777) (xy 354.258531 -257.481608) (xy 354.27412 -257.502914) (xy 354.282766 -257.514334)
			(xy 354.30505 -257.532303) (xy 354.331451 -257.543371) (xy 354.359887 -257.546668) (xy 354.388119 -257.541934)
			(xy 354.413924 -257.529541) (xy 354.435269 -257.510465) (xy 354.443284 -257.498596) (xy 354.458578 -257.475425)
			(xy 354.495672 -257.434119) (xy 354.539143 -257.399588) (xy 354.587771 -257.372803) (xy 354.640189 -257.354516)
			(xy 354.694926 -257.345241) (xy 354.722684 -257.344672) (xy 354.74678 -257.345072) (xy 354.794459 -257.352088)
			(xy 354.840612 -257.365959) (xy 354.88426 -257.386391) (xy 354.924474 -257.412949) (xy 354.960401 -257.44507)
			(xy 354.976176 -257.46329) (xy 354.986092 -257.474344) (xy 355.01088 -257.490675) (xy 355.039312 -257.499199)
			(xy 355.068996 -257.499199) (xy 355.097428 -257.490675) (xy 355.122216 -257.474344) (xy 355.132132 -257.46329)
			(xy 355.147904 -257.445068) (xy 355.183831 -257.41295) (xy 355.224046 -257.386396) (xy 355.267695 -257.365972)
			(xy 355.313849 -257.352111) (xy 355.361529 -257.345108) (xy 355.385624 -257.344672) (xy 355.411592 -257.345131)
			(xy 355.462888 -257.353259) (xy 355.512281 -257.369311) (xy 355.558556 -257.392892) (xy 355.600572 -257.423421)
			(xy 355.637295 -257.460147) (xy 355.667821 -257.502165) (xy 355.691398 -257.548441) (xy 355.707447 -257.597835)
			(xy 355.715571 -257.649132) (xy 355.715571 -257.670554) (xy 356.28961 -257.670554) (xy 356.28961 -257.6703)
			(xy 356.290059 -257.645773) (xy 356.297322 -257.59726) (xy 356.311674 -257.550353) (xy 356.3328 -257.506081)
			(xy 356.360235 -257.465417) (xy 356.376478 -257.447034) (xy 356.386327 -257.43558) (xy 356.399335 -257.40833)
			(xy 356.403795 -257.378466) (xy 356.399315 -257.348604) (xy 356.386288 -257.321363) (xy 356.376478 -257.309874)
			(xy 356.360245 -257.291482) (xy 356.332798 -257.250825) (xy 356.311666 -257.206556) (xy 356.297315 -257.159649)
			(xy 356.290058 -257.111135) (xy 356.28961 -257.086608) (xy 356.28961 -257.086354) (xy 356.290119 -257.060387)
			(xy 356.298244 -257.009092) (xy 356.314292 -256.959699) (xy 356.33787 -256.913425) (xy 356.368396 -256.871409)
			(xy 356.405119 -256.834686) (xy 356.447135 -256.80416) (xy 356.493409 -256.780582) (xy 356.542802 -256.764534)
			(xy 356.594097 -256.756409) (xy 356.646031 -256.756409) (xy 356.697326 -256.764534) (xy 356.746719 -256.780582)
			(xy 356.792993 -256.80416) (xy 356.835009 -256.834686) (xy 356.871732 -256.871409) (xy 356.902258 -256.913425)
			(xy 356.925836 -256.959699) (xy 356.941884 -257.009092) (xy 356.950009 -257.060387) (xy 356.950518 -257.086354)
			(xy 356.950518 -257.086608) (xy 356.950066 -257.111135) (xy 356.942803 -257.159647) (xy 356.930083 -257.201221)
			(xy 357.480617 -257.201221) (xy 357.480617 -257.149287) (xy 357.488742 -257.097992) (xy 357.50479 -257.048599)
			(xy 357.528368 -257.002325) (xy 357.558894 -256.960309) (xy 357.595617 -256.923586) (xy 357.637633 -256.89306)
			(xy 357.683907 -256.869482) (xy 357.7333 -256.853434) (xy 357.784595 -256.845309) (xy 357.836529 -256.845309)
			(xy 357.887824 -256.853434) (xy 357.937217 -256.869482) (xy 357.983491 -256.89306) (xy 358.025507 -256.923586)
			(xy 358.06223 -256.960309) (xy 358.092756 -257.002325) (xy 358.116334 -257.048599) (xy 358.132382 -257.097992)
			(xy 358.140507 -257.149287) (xy 358.141016 -257.175254) (xy 358.140507 -257.201221) (xy 358.420671 -257.201221)
			(xy 358.420671 -257.149287) (xy 358.428796 -257.097992) (xy 358.444844 -257.048599) (xy 358.468422 -257.002325)
			(xy 358.498948 -256.960309) (xy 358.535671 -256.923586) (xy 358.577687 -256.89306) (xy 358.623961 -256.869482)
			(xy 358.673354 -256.853434) (xy 358.724649 -256.845309) (xy 358.776583 -256.845309) (xy 358.827878 -256.853434)
			(xy 358.877271 -256.869482) (xy 358.923545 -256.89306) (xy 358.965561 -256.923586) (xy 359.002284 -256.960309)
			(xy 359.03281 -257.002325) (xy 359.056388 -257.048599) (xy 359.072436 -257.097992) (xy 359.080561 -257.149287)
			(xy 359.08107 -257.175254) (xy 359.080561 -257.201221) (xy 359.360217 -257.201221) (xy 359.360217 -257.149287)
			(xy 359.368342 -257.097992) (xy 359.38439 -257.048599) (xy 359.407968 -257.002325) (xy 359.438494 -256.960309)
			(xy 359.475217 -256.923586) (xy 359.517233 -256.89306) (xy 359.563507 -256.869482) (xy 359.6129 -256.853434)
			(xy 359.664195 -256.845309) (xy 359.716129 -256.845309) (xy 359.767424 -256.853434) (xy 359.816817 -256.869482)
			(xy 359.863091 -256.89306) (xy 359.905107 -256.923586) (xy 359.94183 -256.960309) (xy 359.972356 -257.002325)
			(xy 359.995934 -257.048599) (xy 360.011982 -257.097992) (xy 360.020107 -257.149287) (xy 360.020616 -257.175254)
			(xy 360.020107 -257.201221) (xy 360.300017 -257.201221) (xy 360.300017 -257.149287) (xy 360.308142 -257.097992)
			(xy 360.32419 -257.048599) (xy 360.347768 -257.002325) (xy 360.378294 -256.960309) (xy 360.415017 -256.923586)
			(xy 360.457033 -256.89306) (xy 360.503307 -256.869482) (xy 360.5527 -256.853434) (xy 360.603995 -256.845309)
			(xy 360.655929 -256.845309) (xy 360.707224 -256.853434) (xy 360.756617 -256.869482) (xy 360.802891 -256.89306)
			(xy 360.844907 -256.923586) (xy 360.88163 -256.960309) (xy 360.912156 -257.002325) (xy 360.935734 -257.048599)
			(xy 360.951782 -257.097992) (xy 360.959907 -257.149287) (xy 360.960416 -257.175254) (xy 360.959907 -257.201221)
			(xy 361.239817 -257.201221) (xy 361.239817 -257.149287) (xy 361.247942 -257.097992) (xy 361.26399 -257.048599)
			(xy 361.287568 -257.002325) (xy 361.318094 -256.960309) (xy 361.354817 -256.923586) (xy 361.396833 -256.89306)
			(xy 361.443107 -256.869482) (xy 361.4925 -256.853434) (xy 361.543795 -256.845309) (xy 361.595729 -256.845309)
			(xy 361.647024 -256.853434) (xy 361.696417 -256.869482) (xy 361.742691 -256.89306) (xy 361.784707 -256.923586)
			(xy 361.82143 -256.960309) (xy 361.851956 -257.002325) (xy 361.875534 -257.048599) (xy 361.891582 -257.097992)
			(xy 361.899707 -257.149287) (xy 361.900216 -257.175254) (xy 361.899707 -257.201221) (xy 361.899699 -257.201269)
			(xy 362.179609 -257.201269) (xy 362.179609 -257.149331) (xy 362.187734 -257.098033) (xy 362.203782 -257.048636)
			(xy 362.22736 -257.002359) (xy 362.257886 -256.960339) (xy 362.29461 -256.923611) (xy 362.336626 -256.89308)
			(xy 362.382901 -256.869497) (xy 362.432296 -256.853442) (xy 362.483593 -256.845312) (xy 362.509562 -256.8448)
			(xy 362.535936 -256.845319) (xy 362.588014 -256.853694) (xy 362.6381 -256.870237) (xy 362.684921 -256.894527)
			(xy 362.706412 -256.909824) (xy 362.719266 -256.918692) (xy 362.748776 -256.928864) (xy 362.779981 -256.929645)
			(xy 362.809962 -256.920959) (xy 362.835917 -256.903621) (xy 362.846112 -256.89179) (xy 362.861931 -256.872777)
			(xy 362.898239 -256.839196) (xy 362.939146 -256.8114) (xy 362.983737 -256.790009) (xy 363.031019 -256.775501)
			(xy 363.055408 -256.771394) (xy 363.068741 -256.768931) (xy 363.093541 -256.758) (xy 363.114595 -256.740934)
			(xy 363.130421 -256.718933) (xy 363.139906 -256.693544) (xy 363.142381 -256.666555) (xy 363.137673 -256.639865)
			(xy 363.126114 -256.615352) (xy 363.117638 -256.60477) (xy 363.102672 -256.586723) (xy 363.077479 -256.547184)
			(xy 363.058118 -256.504485) (xy 363.044974 -256.459481) (xy 363.038313 -256.413073) (xy 363.037882 -256.389632)
			(xy 363.037882 -256.389378) (xy 363.038325 -256.364851) (xy 363.045591 -256.316338) (xy 363.059945 -256.269431)
			(xy 363.081071 -256.22516) (xy 363.108507 -256.184496) (xy 363.12475 -256.166112) (xy 363.134524 -256.154599)
			(xy 363.147545 -256.127371) (xy 363.152021 -256.097524) (xy 363.147559 -256.067674) (xy 363.134551 -256.04044)
			(xy 363.12475 -256.028952) (xy 363.108518 -256.010559) (xy 363.081068 -255.969904) (xy 363.059935 -255.925635)
			(xy 363.045584 -255.878728) (xy 363.038329 -255.830213) (xy 363.037882 -255.805686) (xy 363.037882 -255.805432)
			(xy 363.038391 -255.779465) (xy 363.046516 -255.72817) (xy 363.062564 -255.678777) (xy 363.086142 -255.632503)
			(xy 363.116668 -255.590487) (xy 363.153391 -255.553764) (xy 363.195407 -255.523238) (xy 363.241681 -255.49966)
			(xy 363.291074 -255.483612) (xy 363.342369 -255.475487) (xy 363.394303 -255.475487) (xy 363.445598 -255.483612)
			(xy 363.494991 -255.49966) (xy 363.541265 -255.523238) (xy 363.551054 -255.53035) (xy 368.58575 -255.53035)
			(xy 368.58575 -255.530096) (xy 368.586212 -255.50557) (xy 368.593475 -255.457058) (xy 368.607824 -255.410152)
			(xy 368.628947 -255.36588) (xy 368.656378 -255.325215) (xy 368.672618 -255.30683) (xy 368.682369 -255.295301)
			(xy 368.695383 -255.268077) (xy 368.699859 -255.238237) (xy 368.695404 -255.208393) (xy 368.682411 -255.18116)
			(xy 368.672618 -255.16967) (xy 368.656389 -255.151274) (xy 368.62894 -255.110619) (xy 368.607807 -255.066351)
			(xy 368.593455 -255.019445) (xy 368.586198 -254.970931) (xy 368.58575 -254.946404) (xy 368.58575 -254.94615)
			(xy 368.586209 -254.920181) (xy 368.594341 -254.868884) (xy 368.610397 -254.81949) (xy 368.633981 -254.773216)
			(xy 368.664513 -254.731201) (xy 368.701242 -254.694478) (xy 368.743262 -254.663953) (xy 368.78954 -254.640376)
			(xy 368.838937 -254.624328) (xy 368.890235 -254.616205) (xy 368.916204 -254.615696) (xy 368.940134 -254.616117)
			(xy 368.987493 -254.623027) (xy 369.033362 -254.636687) (xy 369.076785 -254.656812) (xy 369.097052 -254.669544)
			(xy 369.110119 -254.677397) (xy 369.139424 -254.68575) (xy 369.169889 -254.685101) (xy 369.198811 -254.675506)
			(xy 369.223623 -254.657817) (xy 369.242123 -254.633604) (xy 369.247928 -254.619506) (xy 369.257023 -254.596023)
			(xy 369.28137 -254.551943) (xy 369.312125 -254.512068) (xy 369.348574 -254.477321) (xy 369.389873 -254.448508)
			(xy 369.435067 -254.426296) (xy 369.483108 -254.411199) (xy 369.532883 -254.403567) (xy 369.558062 -254.403098)
			(xy 369.584029 -254.403674) (xy 369.635326 -254.411793) (xy 369.68472 -254.427837) (xy 369.730996 -254.451411)
			(xy 369.773015 -254.481935) (xy 369.80974 -254.518656) (xy 369.840269 -254.560671) (xy 369.863848 -254.606945)
			(xy 369.879898 -254.656337) (xy 369.888023 -254.707633) (xy 369.888023 -254.759519) (xy 370.167917 -254.759519)
			(xy 370.167917 -254.707585) (xy 370.176042 -254.65629) (xy 370.19209 -254.606897) (xy 370.215668 -254.560623)
			(xy 370.246194 -254.518607) (xy 370.282917 -254.481884) (xy 370.324933 -254.451358) (xy 370.371207 -254.42778)
			(xy 370.4206 -254.411732) (xy 370.471895 -254.403607) (xy 370.523829 -254.403607) (xy 370.575124 -254.411732)
			(xy 370.624517 -254.42778) (xy 370.670791 -254.451358) (xy 370.712807 -254.481884) (xy 370.74953 -254.518607)
			(xy 370.780056 -254.560623) (xy 370.803634 -254.606897) (xy 370.819682 -254.65629) (xy 370.827807 -254.707585)
			(xy 370.828316 -254.733552) (xy 370.827807 -254.759519) (xy 371.107717 -254.759519) (xy 371.107717 -254.707585)
			(xy 371.115842 -254.65629) (xy 371.13189 -254.606897) (xy 371.155468 -254.560623) (xy 371.185994 -254.518607)
			(xy 371.222717 -254.481884) (xy 371.264733 -254.451358) (xy 371.311007 -254.42778) (xy 371.3604 -254.411732)
			(xy 371.411695 -254.403607) (xy 371.463629 -254.403607) (xy 371.514924 -254.411732) (xy 371.564317 -254.42778)
			(xy 371.610591 -254.451358) (xy 371.652607 -254.481884) (xy 371.68933 -254.518607) (xy 371.719856 -254.560623)
			(xy 371.743434 -254.606897) (xy 371.759482 -254.65629) (xy 371.767607 -254.707585) (xy 371.768116 -254.733552)
			(xy 371.767607 -254.759519) (xy 372.047771 -254.759519) (xy 372.047771 -254.707585) (xy 372.055896 -254.65629)
			(xy 372.071944 -254.606897) (xy 372.095522 -254.560623) (xy 372.126048 -254.518607) (xy 372.162771 -254.481884)
			(xy 372.204787 -254.451358) (xy 372.251061 -254.42778) (xy 372.300454 -254.411732) (xy 372.351749 -254.403607)
			(xy 372.403683 -254.403607) (xy 372.454978 -254.411732) (xy 372.504371 -254.42778) (xy 372.550645 -254.451358)
			(xy 372.592661 -254.481884) (xy 372.629384 -254.518607) (xy 372.65991 -254.560623) (xy 372.683488 -254.606897)
			(xy 372.699536 -254.65629) (xy 372.707661 -254.707585) (xy 372.70817 -254.733552) (xy 372.707661 -254.759519)
			(xy 372.987317 -254.759519) (xy 372.987317 -254.707585) (xy 372.995442 -254.65629) (xy 373.01149 -254.606897)
			(xy 373.035068 -254.560623) (xy 373.065594 -254.518607) (xy 373.102317 -254.481884) (xy 373.144333 -254.451358)
			(xy 373.190607 -254.42778) (xy 373.24 -254.411732) (xy 373.291295 -254.403607) (xy 373.343229 -254.403607)
			(xy 373.394524 -254.411732) (xy 373.443917 -254.42778) (xy 373.490191 -254.451358) (xy 373.532207 -254.481884)
			(xy 373.56893 -254.518607) (xy 373.599456 -254.560623) (xy 373.623034 -254.606897) (xy 373.639082 -254.65629)
			(xy 373.647207 -254.707585) (xy 373.647716 -254.733552) (xy 373.647207 -254.759519) (xy 373.927371 -254.759519)
			(xy 373.927371 -254.707585) (xy 373.935496 -254.65629) (xy 373.951544 -254.606897) (xy 373.975122 -254.560623)
			(xy 374.005648 -254.518607) (xy 374.042371 -254.481884) (xy 374.084387 -254.451358) (xy 374.130661 -254.42778)
			(xy 374.180054 -254.411732) (xy 374.231349 -254.403607) (xy 374.283283 -254.403607) (xy 374.334578 -254.411732)
			(xy 374.383971 -254.42778) (xy 374.430245 -254.451358) (xy 374.472261 -254.481884) (xy 374.508984 -254.518607)
			(xy 374.53951 -254.560623) (xy 374.563088 -254.606897) (xy 374.579136 -254.65629) (xy 374.587261 -254.707585)
			(xy 374.58777 -254.733552) (xy 374.587261 -254.759519) (xy 374.579136 -254.810814) (xy 374.563088 -254.860207)
			(xy 374.53951 -254.906481) (xy 374.508984 -254.948497) (xy 374.472261 -254.98522) (xy 374.430245 -255.015746)
			(xy 374.383971 -255.039324) (xy 374.334578 -255.055372) (xy 374.283283 -255.063497) (xy 374.231349 -255.063497)
			(xy 374.180054 -255.055372) (xy 374.130661 -255.039324) (xy 374.084387 -255.015746) (xy 374.042371 -254.98522)
			(xy 374.005648 -254.948497) (xy 373.975122 -254.906481) (xy 373.951544 -254.860207) (xy 373.935496 -254.810814)
			(xy 373.927371 -254.759519) (xy 373.647207 -254.759519) (xy 373.639082 -254.810814) (xy 373.623034 -254.860207)
			(xy 373.599456 -254.906481) (xy 373.56893 -254.948497) (xy 373.532207 -254.98522) (xy 373.490191 -255.015746)
			(xy 373.443917 -255.039324) (xy 373.394524 -255.055372) (xy 373.343229 -255.063497) (xy 373.291295 -255.063497)
			(xy 373.24 -255.055372) (xy 373.190607 -255.039324) (xy 373.144333 -255.015746) (xy 373.102317 -254.98522)
			(xy 373.065594 -254.948497) (xy 373.035068 -254.906481) (xy 373.01149 -254.860207) (xy 372.995442 -254.810814)
			(xy 372.987317 -254.759519) (xy 372.707661 -254.759519) (xy 372.699536 -254.810814) (xy 372.683488 -254.860207)
			(xy 372.65991 -254.906481) (xy 372.629384 -254.948497) (xy 372.592661 -254.98522) (xy 372.550645 -255.015746)
			(xy 372.504371 -255.039324) (xy 372.454978 -255.055372) (xy 372.403683 -255.063497) (xy 372.351749 -255.063497)
			(xy 372.300454 -255.055372) (xy 372.251061 -255.039324) (xy 372.204787 -255.015746) (xy 372.162771 -254.98522)
			(xy 372.126048 -254.948497) (xy 372.095522 -254.906481) (xy 372.071944 -254.860207) (xy 372.055896 -254.810814)
			(xy 372.047771 -254.759519) (xy 371.767607 -254.759519) (xy 371.759482 -254.810814) (xy 371.743434 -254.860207)
			(xy 371.719856 -254.906481) (xy 371.68933 -254.948497) (xy 371.652607 -254.98522) (xy 371.610591 -255.015746)
			(xy 371.564317 -255.039324) (xy 371.514924 -255.055372) (xy 371.463629 -255.063497) (xy 371.411695 -255.063497)
			(xy 371.3604 -255.055372) (xy 371.311007 -255.039324) (xy 371.264733 -255.015746) (xy 371.222717 -254.98522)
			(xy 371.185994 -254.948497) (xy 371.155468 -254.906481) (xy 371.13189 -254.860207) (xy 371.115842 -254.810814)
			(xy 371.107717 -254.759519) (xy 370.827807 -254.759519) (xy 370.819682 -254.810814) (xy 370.803634 -254.860207)
			(xy 370.780056 -254.906481) (xy 370.74953 -254.948497) (xy 370.712807 -254.98522) (xy 370.670791 -255.015746)
			(xy 370.624517 -255.039324) (xy 370.575124 -255.055372) (xy 370.523829 -255.063497) (xy 370.471895 -255.063497)
			(xy 370.4206 -255.055372) (xy 370.371207 -255.039324) (xy 370.324933 -255.015746) (xy 370.282917 -254.98522)
			(xy 370.246194 -254.948497) (xy 370.215668 -254.906481) (xy 370.19209 -254.860207) (xy 370.176042 -254.810814)
			(xy 370.167917 -254.759519) (xy 369.888023 -254.759519) (xy 369.888023 -254.759567) (xy 369.879898 -254.810863)
			(xy 369.863848 -254.860255) (xy 369.840269 -254.906529) (xy 369.80974 -254.948544) (xy 369.773015 -254.985265)
			(xy 369.730996 -255.015789) (xy 369.68472 -255.039363) (xy 369.635326 -255.055407) (xy 369.584029 -255.063526)
			(xy 369.558062 -255.064006) (xy 369.534133 -255.063553) (xy 369.486776 -255.056653) (xy 369.440906 -255.043002)
			(xy 369.397482 -255.022886) (xy 369.377214 -255.010158) (xy 369.364169 -255.002264) (xy 369.334856 -254.993916)
			(xy 369.304384 -254.994572) (xy 369.275458 -255.004175) (xy 369.250643 -255.021873) (xy 369.232143 -255.046094)
			(xy 369.226338 -255.060196) (xy 369.218629 -255.080266) (xy 369.198733 -255.118379) (xy 369.174055 -255.153585)
			(xy 369.15979 -255.16967) (xy 369.14994 -255.181122) (xy 369.136937 -255.208373) (xy 369.132479 -255.238237)
			(xy 369.136958 -255.268098) (xy 369.149982 -255.295339) (xy 369.15979 -255.30683) (xy 369.17602 -255.325225)
			(xy 369.203468 -255.36588) (xy 369.224601 -255.410148) (xy 369.238954 -255.457055) (xy 369.24621 -255.505569)
			(xy 369.246658 -255.530096) (xy 369.246658 -255.53035) (xy 369.246149 -255.556317) (xy 369.243413 -255.573589)
			(xy 370.638071 -255.573589) (xy 370.638071 -255.521655) (xy 370.646196 -255.47036) (xy 370.662244 -255.420967)
			(xy 370.685822 -255.374693) (xy 370.716348 -255.332677) (xy 370.753071 -255.295954) (xy 370.795087 -255.265428)
			(xy 370.841361 -255.24185) (xy 370.890754 -255.225802) (xy 370.942049 -255.217677) (xy 370.993983 -255.217677)
			(xy 371.045278 -255.225802) (xy 371.094671 -255.24185) (xy 371.140945 -255.265428) (xy 371.182961 -255.295954)
			(xy 371.219684 -255.332677) (xy 371.25021 -255.374693) (xy 371.273788 -255.420967) (xy 371.289836 -255.47036)
			(xy 371.297961 -255.521655) (xy 371.29847 -255.547622) (xy 371.297961 -255.573589) (xy 371.577871 -255.573589)
			(xy 371.577871 -255.521655) (xy 371.585996 -255.47036) (xy 371.602044 -255.420967) (xy 371.625622 -255.374693)
			(xy 371.656148 -255.332677) (xy 371.692871 -255.295954) (xy 371.734887 -255.265428) (xy 371.781161 -255.24185)
			(xy 371.830554 -255.225802) (xy 371.881849 -255.217677) (xy 371.933783 -255.217677) (xy 371.985078 -255.225802)
			(xy 372.034471 -255.24185) (xy 372.080745 -255.265428) (xy 372.122761 -255.295954) (xy 372.159484 -255.332677)
			(xy 372.19001 -255.374693) (xy 372.213588 -255.420967) (xy 372.229636 -255.47036) (xy 372.237761 -255.521655)
			(xy 372.23827 -255.547622) (xy 372.237761 -255.573589) (xy 372.517417 -255.573589) (xy 372.517417 -255.521655)
			(xy 372.525542 -255.47036) (xy 372.54159 -255.420967) (xy 372.565168 -255.374693) (xy 372.595694 -255.332677)
			(xy 372.632417 -255.295954) (xy 372.674433 -255.265428) (xy 372.720707 -255.24185) (xy 372.7701 -255.225802)
			(xy 372.821395 -255.217677) (xy 372.873329 -255.217677) (xy 372.924624 -255.225802) (xy 372.974017 -255.24185)
			(xy 373.020291 -255.265428) (xy 373.062307 -255.295954) (xy 373.09903 -255.332677) (xy 373.129556 -255.374693)
			(xy 373.153134 -255.420967) (xy 373.169182 -255.47036) (xy 373.177307 -255.521655) (xy 373.177816 -255.547622)
			(xy 373.177307 -255.573589) (xy 373.457471 -255.573589) (xy 373.457471 -255.521655) (xy 373.465596 -255.47036)
			(xy 373.481644 -255.420967) (xy 373.505222 -255.374693) (xy 373.535748 -255.332677) (xy 373.572471 -255.295954)
			(xy 373.614487 -255.265428) (xy 373.660761 -255.24185) (xy 373.710154 -255.225802) (xy 373.761449 -255.217677)
			(xy 373.813383 -255.217677) (xy 373.864678 -255.225802) (xy 373.914071 -255.24185) (xy 373.960345 -255.265428)
			(xy 374.002361 -255.295954) (xy 374.039084 -255.332677) (xy 374.06961 -255.374693) (xy 374.093188 -255.420967)
			(xy 374.109236 -255.47036) (xy 374.117361 -255.521655) (xy 374.11787 -255.547622) (xy 374.117361 -255.573589)
			(xy 374.109236 -255.624884) (xy 374.093188 -255.674277) (xy 374.06961 -255.720551) (xy 374.039084 -255.762567)
			(xy 374.002361 -255.79929) (xy 373.960345 -255.829816) (xy 373.914071 -255.853394) (xy 373.864678 -255.869442)
			(xy 373.813383 -255.877567) (xy 373.761449 -255.877567) (xy 373.710154 -255.869442) (xy 373.660761 -255.853394)
			(xy 373.614487 -255.829816) (xy 373.572471 -255.79929) (xy 373.535748 -255.762567) (xy 373.505222 -255.720551)
			(xy 373.481644 -255.674277) (xy 373.465596 -255.624884) (xy 373.457471 -255.573589) (xy 373.177307 -255.573589)
			(xy 373.169182 -255.624884) (xy 373.153134 -255.674277) (xy 373.129556 -255.720551) (xy 373.09903 -255.762567)
			(xy 373.062307 -255.79929) (xy 373.020291 -255.829816) (xy 372.974017 -255.853394) (xy 372.924624 -255.869442)
			(xy 372.873329 -255.877567) (xy 372.821395 -255.877567) (xy 372.7701 -255.869442) (xy 372.720707 -255.853394)
			(xy 372.674433 -255.829816) (xy 372.632417 -255.79929) (xy 372.595694 -255.762567) (xy 372.565168 -255.720551)
			(xy 372.54159 -255.674277) (xy 372.525542 -255.624884) (xy 372.517417 -255.573589) (xy 372.237761 -255.573589)
			(xy 372.229636 -255.624884) (xy 372.213588 -255.674277) (xy 372.19001 -255.720551) (xy 372.159484 -255.762567)
			(xy 372.122761 -255.79929) (xy 372.080745 -255.829816) (xy 372.034471 -255.853394) (xy 371.985078 -255.869442)
			(xy 371.933783 -255.877567) (xy 371.881849 -255.877567) (xy 371.830554 -255.869442) (xy 371.781161 -255.853394)
			(xy 371.734887 -255.829816) (xy 371.692871 -255.79929) (xy 371.656148 -255.762567) (xy 371.625622 -255.720551)
			(xy 371.602044 -255.674277) (xy 371.585996 -255.624884) (xy 371.577871 -255.573589) (xy 371.297961 -255.573589)
			(xy 371.289836 -255.624884) (xy 371.273788 -255.674277) (xy 371.25021 -255.720551) (xy 371.219684 -255.762567)
			(xy 371.182961 -255.79929) (xy 371.140945 -255.829816) (xy 371.094671 -255.853394) (xy 371.045278 -255.869442)
			(xy 370.993983 -255.877567) (xy 370.942049 -255.877567) (xy 370.890754 -255.869442) (xy 370.841361 -255.853394)
			(xy 370.795087 -255.829816) (xy 370.753071 -255.79929) (xy 370.716348 -255.762567) (xy 370.685822 -255.720551)
			(xy 370.662244 -255.674277) (xy 370.646196 -255.624884) (xy 370.638071 -255.573589) (xy 369.243413 -255.573589)
			(xy 369.238024 -255.607612) (xy 369.221976 -255.657005) (xy 369.198398 -255.703279) (xy 369.167872 -255.745295)
			(xy 369.131149 -255.782018) (xy 369.089133 -255.812544) (xy 369.042859 -255.836122) (xy 368.993466 -255.85217)
			(xy 368.942171 -255.860295) (xy 368.890237 -255.860295) (xy 368.838942 -255.85217) (xy 368.789549 -255.836122)
			(xy 368.743275 -255.812544) (xy 368.701259 -255.782018) (xy 368.664536 -255.745295) (xy 368.63401 -255.703279)
			(xy 368.610432 -255.657005) (xy 368.594384 -255.607612) (xy 368.586259 -255.556317) (xy 368.58575 -255.53035)
			(xy 363.551054 -255.53035) (xy 363.583281 -255.553764) (xy 363.620004 -255.590487) (xy 363.65053 -255.632503)
			(xy 363.674108 -255.678777) (xy 363.690156 -255.72817) (xy 363.698281 -255.779465) (xy 363.69879 -255.805432)
			(xy 363.69879 -255.805686) (xy 363.698332 -255.830212) (xy 363.691071 -255.878725) (xy 363.676721 -255.925632)
			(xy 363.655598 -255.969904) (xy 363.628164 -256.010568) (xy 363.611922 -256.028952) (xy 363.602088 -256.040417)
			(xy 363.589078 -256.067663) (xy 363.584615 -256.097524) (xy 363.589092 -256.127383) (xy 363.602114 -256.154623)
			(xy 363.611922 -256.166112) (xy 363.628196 -256.18447) (xy 363.655637 -256.225136) (xy 363.676761 -256.269413)
			(xy 363.691103 -256.316328) (xy 363.698348 -256.364849) (xy 363.69879 -256.389378) (xy 363.69879 -256.389632)
			(xy 363.698257 -256.415769) (xy 363.690051 -256.467394) (xy 363.673817 -256.517082) (xy 363.64996 -256.563593)
			(xy 363.619075 -256.605767) (xy 363.581935 -256.642551) (xy 363.539464 -256.673026) (xy 363.492724 -256.696432)
			(xy 363.442882 -256.712186) (xy 363.417104 -256.71653) (xy 363.403763 -256.718961) (xy 363.378957 -256.729893)
			(xy 363.357898 -256.746963) (xy 363.34207 -256.76897) (xy 363.332586 -256.794365) (xy 363.330113 -256.82136)
			(xy 363.334826 -256.848056) (xy 363.346394 -256.872572) (xy 363.354874 -256.883154) (xy 363.369837 -256.901203)
			(xy 363.395033 -256.940741) (xy 363.414397 -256.983439) (xy 363.42754 -257.028443) (xy 363.4342 -257.074851)
			(xy 363.43463 -257.098292) (xy 363.43463 -257.098546) (xy 363.434198 -257.123073) (xy 363.426929 -257.171587)
			(xy 363.412573 -257.218494) (xy 363.391443 -257.262765) (xy 363.377823 -257.28295) (xy 368.58575 -257.28295)
			(xy 368.586242 -257.256549) (xy 368.594651 -257.20442) (xy 368.611233 -257.154289) (xy 368.635565 -257.107427)
			(xy 368.667031 -257.065025) (xy 368.685572 -257.046222) (xy 368.694932 -257.036543) (xy 368.708606 -257.013357)
			(xy 368.715737 -256.987401) (xy 368.715828 -256.960484) (xy 368.708873 -256.93448) (xy 368.695356 -256.911202)
			(xy 368.68608 -256.901442) (xy 368.667893 -256.882697) (xy 368.637056 -256.840548) (xy 368.613229 -256.794075)
			(xy 368.597005 -256.744433) (xy 368.588787 -256.692859) (xy 368.58829 -256.666746) (xy 368.588771 -256.640776)
			(xy 368.596891 -256.589474) (xy 368.612937 -256.540074) (xy 368.636515 -256.493794) (xy 368.667043 -256.451772)
			(xy 368.703771 -256.415045) (xy 368.745792 -256.384516) (xy 368.792073 -256.360938) (xy 368.841472 -256.344891)
			(xy 368.892774 -256.336772) (xy 368.918744 -256.336292) (xy 368.918998 -256.336292) (xy 368.947392 -256.336885)
			(xy 369.003343 -256.34661) (xy 369.056813 -256.365741) (xy 369.081812 -256.379218) (xy 369.094159 -256.385714)
			(xy 369.121255 -256.392326) (xy 369.14913 -256.391364) (xy 369.175705 -256.382898) (xy 369.199001 -256.367561)
			(xy 369.21728 -256.346495) (xy 369.229181 -256.32127) (xy 369.231926 -256.30759) (xy 369.236641 -256.28217)
			(xy 369.252922 -256.233102) (xy 369.276643 -256.187167) (xy 369.307224 -256.145484) (xy 369.343921 -256.109068)
			(xy 369.385838 -256.078809) (xy 369.431954 -256.055443) (xy 369.481146 -256.039539) (xy 369.532213 -256.031486)
			(xy 369.558062 -256.030984) (xy 369.584036 -256.031388) (xy 369.635346 -256.039509) (xy 369.684753 -256.055558)
			(xy 369.731041 -256.079138) (xy 369.773071 -256.10967) (xy 369.809806 -256.146401) (xy 369.840342 -256.188426)
			(xy 369.863928 -256.234712) (xy 369.879982 -256.284117) (xy 369.888109 -256.335426) (xy 369.888109 -256.387374)
			(xy 369.888104 -256.387405) (xy 370.168171 -256.387405) (xy 370.168171 -256.335471) (xy 370.176296 -256.284176)
			(xy 370.192344 -256.234783) (xy 370.215922 -256.188509) (xy 370.246448 -256.146493) (xy 370.283171 -256.10977)
			(xy 370.325187 -256.079244) (xy 370.371461 -256.055666) (xy 370.420854 -256.039618) (xy 370.472149 -256.031493)
			(xy 370.524083 -256.031493) (xy 370.575378 -256.039618) (xy 370.624771 -256.055666) (xy 370.671045 -256.079244)
			(xy 370.713061 -256.10977) (xy 370.749784 -256.146493) (xy 370.78031 -256.188509) (xy 370.803888 -256.234783)
			(xy 370.819936 -256.284176) (xy 370.828061 -256.335471) (xy 370.82857 -256.361438) (xy 370.828061 -256.387405)
			(xy 371.107717 -256.387405) (xy 371.107717 -256.335471) (xy 371.115842 -256.284176) (xy 371.13189 -256.234783)
			(xy 371.155468 -256.188509) (xy 371.185994 -256.146493) (xy 371.222717 -256.10977) (xy 371.264733 -256.079244)
			(xy 371.311007 -256.055666) (xy 371.3604 -256.039618) (xy 371.411695 -256.031493) (xy 371.463629 -256.031493)
			(xy 371.514924 -256.039618) (xy 371.564317 -256.055666) (xy 371.610591 -256.079244) (xy 371.652607 -256.10977)
			(xy 371.68933 -256.146493) (xy 371.719856 -256.188509) (xy 371.743434 -256.234783) (xy 371.759482 -256.284176)
			(xy 371.767607 -256.335471) (xy 371.768116 -256.361438) (xy 371.767607 -256.387405) (xy 372.047517 -256.387405)
			(xy 372.047517 -256.335471) (xy 372.055642 -256.284176) (xy 372.07169 -256.234783) (xy 372.095268 -256.188509)
			(xy 372.125794 -256.146493) (xy 372.162517 -256.10977) (xy 372.204533 -256.079244) (xy 372.250807 -256.055666)
			(xy 372.3002 -256.039618) (xy 372.351495 -256.031493) (xy 372.403429 -256.031493) (xy 372.454724 -256.039618)
			(xy 372.504117 -256.055666) (xy 372.550391 -256.079244) (xy 372.592407 -256.10977) (xy 372.62913 -256.146493)
			(xy 372.659656 -256.188509) (xy 372.683234 -256.234783) (xy 372.699282 -256.284176) (xy 372.707407 -256.335471)
			(xy 372.707916 -256.361438) (xy 372.707407 -256.387405) (xy 372.987317 -256.387405) (xy 372.987317 -256.335471)
			(xy 372.995442 -256.284176) (xy 373.01149 -256.234783) (xy 373.035068 -256.188509) (xy 373.065594 -256.146493)
			(xy 373.102317 -256.10977) (xy 373.144333 -256.079244) (xy 373.190607 -256.055666) (xy 373.24 -256.039618)
			(xy 373.291295 -256.031493) (xy 373.343229 -256.031493) (xy 373.394524 -256.039618) (xy 373.443917 -256.055666)
			(xy 373.490191 -256.079244) (xy 373.532207 -256.10977) (xy 373.56893 -256.146493) (xy 373.599456 -256.188509)
			(xy 373.623034 -256.234783) (xy 373.639082 -256.284176) (xy 373.647207 -256.335471) (xy 373.647716 -256.361438)
			(xy 373.647207 -256.387405) (xy 373.927117 -256.387405) (xy 373.927117 -256.335471) (xy 373.935242 -256.284176)
			(xy 373.95129 -256.234783) (xy 373.974868 -256.188509) (xy 374.005394 -256.146493) (xy 374.042117 -256.10977)
			(xy 374.084133 -256.079244) (xy 374.130407 -256.055666) (xy 374.1798 -256.039618) (xy 374.231095 -256.031493)
			(xy 374.283029 -256.031493) (xy 374.334324 -256.039618) (xy 374.383717 -256.055666) (xy 374.429991 -256.079244)
			(xy 374.472007 -256.10977) (xy 374.50873 -256.146493) (xy 374.539256 -256.188509) (xy 374.562834 -256.234783)
			(xy 374.578882 -256.284176) (xy 374.587007 -256.335471) (xy 374.587516 -256.361438) (xy 374.587007 -256.387405)
			(xy 374.578882 -256.4387) (xy 374.562834 -256.488093) (xy 374.539256 -256.534367) (xy 374.50873 -256.576383)
			(xy 374.472007 -256.613106) (xy 374.429991 -256.643632) (xy 374.383717 -256.66721) (xy 374.334324 -256.683258)
			(xy 374.283029 -256.691383) (xy 374.231095 -256.691383) (xy 374.1798 -256.683258) (xy 374.130407 -256.66721)
			(xy 374.084133 -256.643632) (xy 374.042117 -256.613106) (xy 374.005394 -256.576383) (xy 373.974868 -256.534367)
			(xy 373.95129 -256.488093) (xy 373.935242 -256.4387) (xy 373.927117 -256.387405) (xy 373.647207 -256.387405)
			(xy 373.639082 -256.4387) (xy 373.623034 -256.488093) (xy 373.599456 -256.534367) (xy 373.56893 -256.576383)
			(xy 373.532207 -256.613106) (xy 373.490191 -256.643632) (xy 373.443917 -256.66721) (xy 373.394524 -256.683258)
			(xy 373.343229 -256.691383) (xy 373.291295 -256.691383) (xy 373.24 -256.683258) (xy 373.190607 -256.66721)
			(xy 373.144333 -256.643632) (xy 373.102317 -256.613106) (xy 373.065594 -256.576383) (xy 373.035068 -256.534367)
			(xy 373.01149 -256.488093) (xy 372.995442 -256.4387) (xy 372.987317 -256.387405) (xy 372.707407 -256.387405)
			(xy 372.699282 -256.4387) (xy 372.683234 -256.488093) (xy 372.659656 -256.534367) (xy 372.62913 -256.576383)
			(xy 372.592407 -256.613106) (xy 372.550391 -256.643632) (xy 372.504117 -256.66721) (xy 372.454724 -256.683258)
			(xy 372.403429 -256.691383) (xy 372.351495 -256.691383) (xy 372.3002 -256.683258) (xy 372.250807 -256.66721)
			(xy 372.204533 -256.643632) (xy 372.162517 -256.613106) (xy 372.125794 -256.576383) (xy 372.095268 -256.534367)
			(xy 372.07169 -256.488093) (xy 372.055642 -256.4387) (xy 372.047517 -256.387405) (xy 371.767607 -256.387405)
			(xy 371.759482 -256.4387) (xy 371.743434 -256.488093) (xy 371.719856 -256.534367) (xy 371.68933 -256.576383)
			(xy 371.652607 -256.613106) (xy 371.610591 -256.643632) (xy 371.564317 -256.66721) (xy 371.514924 -256.683258)
			(xy 371.463629 -256.691383) (xy 371.411695 -256.691383) (xy 371.3604 -256.683258) (xy 371.311007 -256.66721)
			(xy 371.264733 -256.643632) (xy 371.222717 -256.613106) (xy 371.185994 -256.576383) (xy 371.155468 -256.534367)
			(xy 371.13189 -256.488093) (xy 371.115842 -256.4387) (xy 371.107717 -256.387405) (xy 370.828061 -256.387405)
			(xy 370.819936 -256.4387) (xy 370.803888 -256.488093) (xy 370.78031 -256.534367) (xy 370.749784 -256.576383)
			(xy 370.713061 -256.613106) (xy 370.671045 -256.643632) (xy 370.624771 -256.66721) (xy 370.575378 -256.683258)
			(xy 370.524083 -256.691383) (xy 370.472149 -256.691383) (xy 370.420854 -256.683258) (xy 370.371461 -256.66721)
			(xy 370.325187 -256.643632) (xy 370.283171 -256.613106) (xy 370.246448 -256.576383) (xy 370.215922 -256.534367)
			(xy 370.192344 -256.488093) (xy 370.176296 -256.4387) (xy 370.168171 -256.387405) (xy 369.888104 -256.387405)
			(xy 369.879982 -256.438683) (xy 369.863928 -256.488088) (xy 369.840342 -256.534374) (xy 369.809806 -256.576399)
			(xy 369.773071 -256.61313) (xy 369.731041 -256.643662) (xy 369.684753 -256.667242) (xy 369.635346 -256.683291)
			(xy 369.584036 -256.691412) (xy 369.558062 -256.691892) (xy 369.557808 -256.691892) (xy 369.529414 -256.691298)
			(xy 369.473463 -256.681574) (xy 369.419993 -256.662443) (xy 369.394994 -256.648966) (xy 369.382669 -256.642418)
			(xy 369.355562 -256.635795) (xy 369.327674 -256.636756) (xy 369.301087 -256.645227) (xy 369.277785 -256.660578)
			(xy 369.259507 -256.681662) (xy 369.247616 -256.706906) (xy 369.24488 -256.720594) (xy 369.240102 -256.746402)
			(xy 369.223449 -256.796173) (xy 369.199151 -256.842694) (xy 369.167818 -256.884798) (xy 369.149376 -256.903474)
			(xy 369.140024 -256.913158) (xy 369.126356 -256.936344) (xy 369.119229 -256.962298) (xy 369.119137 -256.989212)
			(xy 369.126087 -257.015213) (xy 369.139596 -257.038492) (xy 369.148868 -257.048254) (xy 369.167043 -257.06701)
			(xy 369.197884 -257.109155) (xy 369.221714 -257.155625) (xy 369.236619 -257.201221) (xy 369.698271 -257.201221)
			(xy 369.698271 -257.149287) (xy 369.706396 -257.097992) (xy 369.722444 -257.048599) (xy 369.746022 -257.002325)
			(xy 369.776548 -256.960309) (xy 369.813271 -256.923586) (xy 369.855287 -256.89306) (xy 369.901561 -256.869482)
			(xy 369.950954 -256.853434) (xy 370.002249 -256.845309) (xy 370.054183 -256.845309) (xy 370.105478 -256.853434)
			(xy 370.154871 -256.869482) (xy 370.201145 -256.89306) (xy 370.243161 -256.923586) (xy 370.279884 -256.960309)
			(xy 370.31041 -257.002325) (xy 370.333988 -257.048599) (xy 370.350036 -257.097992) (xy 370.358161 -257.149287)
			(xy 370.35867 -257.175254) (xy 370.358161 -257.201221) (xy 370.638071 -257.201221) (xy 370.638071 -257.149287)
			(xy 370.646196 -257.097992) (xy 370.662244 -257.048599) (xy 370.685822 -257.002325) (xy 370.716348 -256.960309)
			(xy 370.753071 -256.923586) (xy 370.795087 -256.89306) (xy 370.841361 -256.869482) (xy 370.890754 -256.853434)
			(xy 370.942049 -256.845309) (xy 370.993983 -256.845309) (xy 371.045278 -256.853434) (xy 371.094671 -256.869482)
			(xy 371.140945 -256.89306) (xy 371.182961 -256.923586) (xy 371.219684 -256.960309) (xy 371.25021 -257.002325)
			(xy 371.273788 -257.048599) (xy 371.289836 -257.097992) (xy 371.297961 -257.149287) (xy 371.29847 -257.175254)
			(xy 371.297961 -257.201221) (xy 371.577871 -257.201221) (xy 371.577871 -257.149287) (xy 371.585996 -257.097992)
			(xy 371.602044 -257.048599) (xy 371.625622 -257.002325) (xy 371.656148 -256.960309) (xy 371.692871 -256.923586)
			(xy 371.734887 -256.89306) (xy 371.781161 -256.869482) (xy 371.830554 -256.853434) (xy 371.881849 -256.845309)
			(xy 371.933783 -256.845309) (xy 371.985078 -256.853434) (xy 372.034471 -256.869482) (xy 372.080745 -256.89306)
			(xy 372.122761 -256.923586) (xy 372.159484 -256.960309) (xy 372.19001 -257.002325) (xy 372.213588 -257.048599)
			(xy 372.229636 -257.097992) (xy 372.237761 -257.149287) (xy 372.23827 -257.175254) (xy 372.237761 -257.201221)
			(xy 372.517417 -257.201221) (xy 372.517417 -257.149287) (xy 372.525542 -257.097992) (xy 372.54159 -257.048599)
			(xy 372.565168 -257.002325) (xy 372.595694 -256.960309) (xy 372.632417 -256.923586) (xy 372.674433 -256.89306)
			(xy 372.720707 -256.869482) (xy 372.7701 -256.853434) (xy 372.821395 -256.845309) (xy 372.873329 -256.845309)
			(xy 372.924624 -256.853434) (xy 372.974017 -256.869482) (xy 373.020291 -256.89306) (xy 373.062307 -256.923586)
			(xy 373.09903 -256.960309) (xy 373.129556 -257.002325) (xy 373.153134 -257.048599) (xy 373.169182 -257.097992)
			(xy 373.177307 -257.149287) (xy 373.177816 -257.175254) (xy 373.177307 -257.201221) (xy 373.457217 -257.201221)
			(xy 373.457217 -257.149287) (xy 373.465342 -257.097992) (xy 373.48139 -257.048599) (xy 373.504968 -257.002325)
			(xy 373.535494 -256.960309) (xy 373.572217 -256.923586) (xy 373.614233 -256.89306) (xy 373.660507 -256.869482)
			(xy 373.7099 -256.853434) (xy 373.761195 -256.845309) (xy 373.813129 -256.845309) (xy 373.864424 -256.853434)
			(xy 373.913817 -256.869482) (xy 373.960091 -256.89306) (xy 374.002107 -256.923586) (xy 374.03883 -256.960309)
			(xy 374.069356 -257.002325) (xy 374.092934 -257.048599) (xy 374.108982 -257.097992) (xy 374.117107 -257.149287)
			(xy 374.117616 -257.175254) (xy 374.117107 -257.201221) (xy 374.397271 -257.201221) (xy 374.397271 -257.149287)
			(xy 374.405396 -257.097992) (xy 374.421444 -257.048599) (xy 374.445022 -257.002325) (xy 374.475548 -256.960309)
			(xy 374.512271 -256.923586) (xy 374.554287 -256.89306) (xy 374.600561 -256.869482) (xy 374.649954 -256.853434)
			(xy 374.701249 -256.845309) (xy 374.753183 -256.845309) (xy 374.804478 -256.853434) (xy 374.853871 -256.869482)
			(xy 374.900145 -256.89306) (xy 374.942161 -256.923586) (xy 374.978884 -256.960309) (xy 375.00941 -257.002325)
			(xy 375.032988 -257.048599) (xy 375.049036 -257.097992) (xy 375.057161 -257.149287) (xy 375.05767 -257.175254)
			(xy 375.057161 -257.201221) (xy 375.049036 -257.252516) (xy 375.032988 -257.301909) (xy 375.00941 -257.348183)
			(xy 374.978884 -257.390199) (xy 374.942161 -257.426922) (xy 374.900145 -257.457448) (xy 374.853871 -257.481026)
			(xy 374.804478 -257.497074) (xy 374.753183 -257.505199) (xy 374.701249 -257.505199) (xy 374.649954 -257.497074)
			(xy 374.600561 -257.481026) (xy 374.554287 -257.457448) (xy 374.512271 -257.426922) (xy 374.475548 -257.390199)
			(xy 374.445022 -257.348183) (xy 374.421444 -257.301909) (xy 374.405396 -257.252516) (xy 374.397271 -257.201221)
			(xy 374.117107 -257.201221) (xy 374.108982 -257.252516) (xy 374.092934 -257.301909) (xy 374.069356 -257.348183)
			(xy 374.03883 -257.390199) (xy 374.002107 -257.426922) (xy 373.960091 -257.457448) (xy 373.913817 -257.481026)
			(xy 373.864424 -257.497074) (xy 373.813129 -257.505199) (xy 373.761195 -257.505199) (xy 373.7099 -257.497074)
			(xy 373.660507 -257.481026) (xy 373.614233 -257.457448) (xy 373.572217 -257.426922) (xy 373.535494 -257.390199)
			(xy 373.504968 -257.348183) (xy 373.48139 -257.301909) (xy 373.465342 -257.252516) (xy 373.457217 -257.201221)
			(xy 373.177307 -257.201221) (xy 373.169182 -257.252516) (xy 373.153134 -257.301909) (xy 373.129556 -257.348183)
			(xy 373.09903 -257.390199) (xy 373.062307 -257.426922) (xy 373.020291 -257.457448) (xy 372.974017 -257.481026)
			(xy 372.924624 -257.497074) (xy 372.873329 -257.505199) (xy 372.821395 -257.505199) (xy 372.7701 -257.497074)
			(xy 372.720707 -257.481026) (xy 372.674433 -257.457448) (xy 372.632417 -257.426922) (xy 372.595694 -257.390199)
			(xy 372.565168 -257.348183) (xy 372.54159 -257.301909) (xy 372.525542 -257.252516) (xy 372.517417 -257.201221)
			(xy 372.237761 -257.201221) (xy 372.229636 -257.252516) (xy 372.213588 -257.301909) (xy 372.19001 -257.348183)
			(xy 372.159484 -257.390199) (xy 372.122761 -257.426922) (xy 372.080745 -257.457448) (xy 372.034471 -257.481026)
			(xy 371.985078 -257.497074) (xy 371.933783 -257.505199) (xy 371.881849 -257.505199) (xy 371.830554 -257.497074)
			(xy 371.781161 -257.481026) (xy 371.734887 -257.457448) (xy 371.692871 -257.426922) (xy 371.656148 -257.390199)
			(xy 371.625622 -257.348183) (xy 371.602044 -257.301909) (xy 371.585996 -257.252516) (xy 371.577871 -257.201221)
			(xy 371.297961 -257.201221) (xy 371.289836 -257.252516) (xy 371.273788 -257.301909) (xy 371.25021 -257.348183)
			(xy 371.219684 -257.390199) (xy 371.182961 -257.426922) (xy 371.140945 -257.457448) (xy 371.094671 -257.481026)
			(xy 371.045278 -257.497074) (xy 370.993983 -257.505199) (xy 370.942049 -257.505199) (xy 370.890754 -257.497074)
			(xy 370.841361 -257.481026) (xy 370.795087 -257.457448) (xy 370.753071 -257.426922) (xy 370.716348 -257.390199)
			(xy 370.685822 -257.348183) (xy 370.662244 -257.301909) (xy 370.646196 -257.252516) (xy 370.638071 -257.201221)
			(xy 370.358161 -257.201221) (xy 370.350036 -257.252516) (xy 370.333988 -257.301909) (xy 370.31041 -257.348183)
			(xy 370.279884 -257.390199) (xy 370.243161 -257.426922) (xy 370.201145 -257.457448) (xy 370.154871 -257.481026)
			(xy 370.105478 -257.497074) (xy 370.054183 -257.505199) (xy 370.002249 -257.505199) (xy 369.950954 -257.497074)
			(xy 369.901561 -257.481026) (xy 369.855287 -257.457448) (xy 369.813271 -257.426922) (xy 369.776548 -257.390199)
			(xy 369.746022 -257.348183) (xy 369.722444 -257.301909) (xy 369.706396 -257.252516) (xy 369.698271 -257.201221)
			(xy 369.236619 -257.201221) (xy 369.237941 -257.205265) (xy 369.24616 -257.256838) (xy 369.246658 -257.28295)
			(xy 369.246149 -257.308917) (xy 369.238024 -257.360212) (xy 369.221976 -257.409605) (xy 369.198398 -257.455879)
			(xy 369.167872 -257.497895) (xy 369.131149 -257.534618) (xy 369.089133 -257.565144) (xy 369.042859 -257.588722)
			(xy 368.993466 -257.60477) (xy 368.942171 -257.612895) (xy 368.890237 -257.612895) (xy 368.838942 -257.60477)
			(xy 368.789549 -257.588722) (xy 368.743275 -257.565144) (xy 368.701259 -257.534618) (xy 368.664536 -257.497895)
			(xy 368.63401 -257.455879) (xy 368.610432 -257.409605) (xy 368.594384 -257.360212) (xy 368.586259 -257.308917)
			(xy 368.58575 -257.28295) (xy 363.377823 -257.28295) (xy 363.364005 -257.303429) (xy 363.347762 -257.321812)
			(xy 363.337963 -257.333306) (xy 363.324944 -257.36054) (xy 363.320472 -257.390394) (xy 363.32494 -257.420248)
			(xy 363.337957 -257.447484) (xy 363.347762 -257.458972) (xy 363.364007 -257.477354) (xy 363.391455 -257.518012)
			(xy 363.412585 -257.562284) (xy 363.426934 -257.609194) (xy 363.434185 -257.65771) (xy 363.43463 -257.682238)
			(xy 363.43463 -257.682492) (xy 363.434121 -257.708459) (xy 363.432472 -257.71887) (xy 364.044435 -257.71887)
			(xy 364.044435 -257.66693) (xy 364.052561 -257.615629) (xy 364.068612 -257.56623) (xy 364.092194 -257.519952)
			(xy 364.122725 -257.477932) (xy 364.159455 -257.441206) (xy 364.201477 -257.410678) (xy 364.247758 -257.387101)
			(xy 364.297158 -257.371054) (xy 364.34846 -257.362933) (xy 364.37443 -257.362452) (xy 364.402127 -257.362968)
			(xy 364.456744 -257.372216) (xy 364.509052 -257.390449) (xy 364.557584 -257.417155) (xy 364.600979 -257.451585)
			(xy 364.638021 -257.492774) (xy 364.653322 -257.515868) (xy 364.661623 -257.528104) (xy 364.683945 -257.547482)
			(xy 364.710877 -257.559663) (xy 364.740169 -257.56363) (xy 364.769371 -257.559052) (xy 364.796043 -257.54631)
			(xy 364.817954 -257.52647) (xy 364.826042 -257.51409) (xy 364.83896 -257.493578) (xy 364.869871 -257.456238)
			(xy 364.905903 -257.423811) (xy 364.946284 -257.396993) (xy 364.990147 -257.376357) (xy 365.036553 -257.362346)
			(xy 365.084507 -257.355261) (xy 365.108744 -257.354832) (xy 365.132767 -257.355239) (xy 365.180305 -257.362202)
			(xy 365.226334 -257.375975) (xy 365.269883 -257.396268) (xy 365.310035 -257.422653) (xy 365.345944 -257.454573)
			(xy 365.361728 -257.472688) (xy 365.371519 -257.48354) (xy 365.395886 -257.499659) (xy 365.423814 -257.508238)
			(xy 365.453028 -257.508578) (xy 365.481148 -257.500652) (xy 365.505884 -257.485104) (xy 365.515906 -257.474466)
			(xy 365.534905 -257.453816) (xy 365.578564 -257.418572) (xy 365.62755 -257.391213) (xy 365.680454 -257.372525)
			(xy 365.735756 -257.363046) (xy 365.76381 -257.362452) (xy 365.789671 -257.362958) (xy 365.840762 -257.371005)
			(xy 365.889975 -257.386916) (xy 365.936106 -257.410303) (xy 365.978029 -257.440593) (xy 365.996728 -257.458464)
			(xy 366.006443 -257.467509) (xy 366.029452 -257.480721) (xy 366.055089 -257.487558) (xy 366.081623 -257.487558)
			(xy 366.10726 -257.480721) (xy 366.130269 -257.467509) (xy 366.139984 -257.458464) (xy 366.158664 -257.440574)
			(xy 366.200598 -257.410296) (xy 366.246735 -257.386916) (xy 366.295949 -257.371006) (xy 366.347041 -257.362952)
			(xy 366.372902 -257.362452) (xy 366.397256 -257.362876) (xy 366.445437 -257.370027) (xy 366.492046 -257.384172)
			(xy 366.536074 -257.405006) (xy 366.576567 -257.432077) (xy 366.612647 -257.464799) (xy 366.628426 -257.483356)
			(xy 366.638293 -257.49459) (xy 366.663098 -257.511261) (xy 366.691665 -257.520045) (xy 366.721551 -257.52019)
			(xy 366.750202 -257.511685) (xy 366.775168 -257.495256) (xy 366.785144 -257.484118) (xy 366.8009 -257.4658)
			(xy 366.836876 -257.433546) (xy 366.877167 -257.406878) (xy 366.920914 -257.386364) (xy 366.967182 -257.372442)
			(xy 367.014985 -257.365409) (xy 367.039144 -257.364992) (xy 367.063672 -257.365419) (xy 367.112185 -257.372688)
			(xy 367.159093 -257.387046) (xy 367.203364 -257.408176) (xy 367.244027 -257.435616) (xy 367.26241 -257.45186)
			(xy 367.27403 -257.461656) (xy 367.301477 -257.474662) (xy 367.331534 -257.479021) (xy 367.361544 -257.474348)
			(xy 367.388853 -257.461056) (xy 367.400332 -257.451098) (xy 367.418785 -257.434521) (xy 367.459728 -257.406521)
			(xy 367.504395 -257.384953) (xy 367.551783 -257.370301) (xy 367.600829 -257.362894) (xy 367.62563 -257.362452)
			(xy 367.651596 -257.362952) (xy 367.702888 -257.37108) (xy 367.752278 -257.387131) (xy 367.798549 -257.410711)
			(xy 367.840561 -257.441238) (xy 367.877281 -257.477962) (xy 367.907805 -257.519977) (xy 367.93138 -257.56625)
			(xy 367.947427 -257.615641) (xy 367.955551 -257.666934) (xy 367.955551 -257.718866) (xy 367.947427 -257.770159)
			(xy 367.93138 -257.81955) (xy 367.907805 -257.865823) (xy 367.877281 -257.907838) (xy 367.840561 -257.944562)
			(xy 367.798549 -257.975089) (xy 367.752278 -257.998669) (xy 367.702888 -258.01472) (xy 367.700888 -258.015037)
			(xy 369.228117 -258.015037) (xy 369.228117 -257.963103) (xy 369.236242 -257.911808) (xy 369.25229 -257.862415)
			(xy 369.275868 -257.816141) (xy 369.306394 -257.774125) (xy 369.343117 -257.737402) (xy 369.385133 -257.706876)
			(xy 369.431407 -257.683298) (xy 369.4808 -257.66725) (xy 369.532095 -257.659125) (xy 369.584029 -257.659125)
			(xy 369.635324 -257.66725) (xy 369.684717 -257.683298) (xy 369.730991 -257.706876) (xy 369.773007 -257.737402)
			(xy 369.80973 -257.774125) (xy 369.840256 -257.816141) (xy 369.863834 -257.862415) (xy 369.879882 -257.911808)
			(xy 369.888007 -257.963103) (xy 369.888516 -257.98907) (xy 369.888007 -258.015037) (xy 370.167917 -258.015037)
			(xy 370.167917 -257.963103) (xy 370.176042 -257.911808) (xy 370.19209 -257.862415) (xy 370.215668 -257.816141)
			(xy 370.246194 -257.774125) (xy 370.282917 -257.737402) (xy 370.324933 -257.706876) (xy 370.371207 -257.683298)
			(xy 370.4206 -257.66725) (xy 370.471895 -257.659125) (xy 370.523829 -257.659125) (xy 370.575124 -257.66725)
			(xy 370.624517 -257.683298) (xy 370.670791 -257.706876) (xy 370.712807 -257.737402) (xy 370.74953 -257.774125)
			(xy 370.780056 -257.816141) (xy 370.803634 -257.862415) (xy 370.819682 -257.911808) (xy 370.827807 -257.963103)
			(xy 370.828316 -257.98907) (xy 370.827807 -258.015037) (xy 371.107717 -258.015037) (xy 371.107717 -257.963103)
			(xy 371.115842 -257.911808) (xy 371.13189 -257.862415) (xy 371.155468 -257.816141) (xy 371.185994 -257.774125)
			(xy 371.222717 -257.737402) (xy 371.264733 -257.706876) (xy 371.311007 -257.683298) (xy 371.3604 -257.66725)
			(xy 371.411695 -257.659125) (xy 371.463629 -257.659125) (xy 371.514924 -257.66725) (xy 371.564317 -257.683298)
			(xy 371.610591 -257.706876) (xy 371.652607 -257.737402) (xy 371.68933 -257.774125) (xy 371.719856 -257.816141)
			(xy 371.743434 -257.862415) (xy 371.759482 -257.911808) (xy 371.767607 -257.963103) (xy 371.768116 -257.98907)
			(xy 371.767607 -258.015037) (xy 372.047517 -258.015037) (xy 372.047517 -257.963103) (xy 372.055642 -257.911808)
			(xy 372.07169 -257.862415) (xy 372.095268 -257.816141) (xy 372.125794 -257.774125) (xy 372.162517 -257.737402)
			(xy 372.204533 -257.706876) (xy 372.250807 -257.683298) (xy 372.3002 -257.66725) (xy 372.351495 -257.659125)
			(xy 372.403429 -257.659125) (xy 372.454724 -257.66725) (xy 372.504117 -257.683298) (xy 372.550391 -257.706876)
			(xy 372.592407 -257.737402) (xy 372.62913 -257.774125) (xy 372.659656 -257.816141) (xy 372.683234 -257.862415)
			(xy 372.699282 -257.911808) (xy 372.707407 -257.963103) (xy 372.707916 -257.98907) (xy 372.707407 -258.015037)
			(xy 372.987571 -258.015037) (xy 372.987571 -257.963103) (xy 372.995696 -257.911808) (xy 373.011744 -257.862415)
			(xy 373.035322 -257.816141) (xy 373.065848 -257.774125) (xy 373.102571 -257.737402) (xy 373.144587 -257.706876)
			(xy 373.190861 -257.683298) (xy 373.240254 -257.66725) (xy 373.291549 -257.659125) (xy 373.343483 -257.659125)
			(xy 373.394778 -257.66725) (xy 373.444171 -257.683298) (xy 373.490445 -257.706876) (xy 373.532461 -257.737402)
			(xy 373.569184 -257.774125) (xy 373.59971 -257.816141) (xy 373.623288 -257.862415) (xy 373.639336 -257.911808)
			(xy 373.647461 -257.963103) (xy 373.64797 -257.98907) (xy 373.647461 -258.015037) (xy 373.927117 -258.015037)
			(xy 373.927117 -257.963103) (xy 373.935242 -257.911808) (xy 373.95129 -257.862415) (xy 373.974868 -257.816141)
			(xy 374.005394 -257.774125) (xy 374.042117 -257.737402) (xy 374.084133 -257.706876) (xy 374.130407 -257.683298)
			(xy 374.1798 -257.66725) (xy 374.231095 -257.659125) (xy 374.283029 -257.659125) (xy 374.334324 -257.66725)
			(xy 374.383717 -257.683298) (xy 374.429991 -257.706876) (xy 374.472007 -257.737402) (xy 374.50873 -257.774125)
			(xy 374.539256 -257.816141) (xy 374.562834 -257.862415) (xy 374.578882 -257.911808) (xy 374.587007 -257.963103)
			(xy 374.587516 -257.98907) (xy 374.587007 -258.015037) (xy 374.867171 -258.015037) (xy 374.867171 -257.963103)
			(xy 374.875296 -257.911808) (xy 374.891344 -257.862415) (xy 374.914922 -257.816141) (xy 374.945448 -257.774125)
			(xy 374.982171 -257.737402) (xy 375.024187 -257.706876) (xy 375.070461 -257.683298) (xy 375.119854 -257.66725)
			(xy 375.171149 -257.659125) (xy 375.223083 -257.659125) (xy 375.274378 -257.66725) (xy 375.323771 -257.683298)
			(xy 375.370045 -257.706876) (xy 375.412061 -257.737402) (xy 375.448784 -257.774125) (xy 375.47931 -257.816141)
			(xy 375.502888 -257.862415) (xy 375.518936 -257.911808) (xy 375.527061 -257.963103) (xy 375.52757 -257.98907)
			(xy 375.527061 -258.015037) (xy 375.518936 -258.066332) (xy 375.502888 -258.115725) (xy 375.47931 -258.161999)
			(xy 375.448784 -258.204015) (xy 375.412061 -258.240738) (xy 375.370045 -258.271264) (xy 375.323771 -258.294842)
			(xy 375.274378 -258.31089) (xy 375.223083 -258.319015) (xy 375.171149 -258.319015) (xy 375.119854 -258.31089)
			(xy 375.070461 -258.294842) (xy 375.024187 -258.271264) (xy 374.982171 -258.240738) (xy 374.945448 -258.204015)
			(xy 374.914922 -258.161999) (xy 374.891344 -258.115725) (xy 374.875296 -258.066332) (xy 374.867171 -258.015037)
			(xy 374.587007 -258.015037) (xy 374.578882 -258.066332) (xy 374.562834 -258.115725) (xy 374.539256 -258.161999)
			(xy 374.50873 -258.204015) (xy 374.472007 -258.240738) (xy 374.429991 -258.271264) (xy 374.383717 -258.294842)
			(xy 374.334324 -258.31089) (xy 374.283029 -258.319015) (xy 374.231095 -258.319015) (xy 374.1798 -258.31089)
			(xy 374.130407 -258.294842) (xy 374.084133 -258.271264) (xy 374.042117 -258.240738) (xy 374.005394 -258.204015)
			(xy 373.974868 -258.161999) (xy 373.95129 -258.115725) (xy 373.935242 -258.066332) (xy 373.927117 -258.015037)
			(xy 373.647461 -258.015037) (xy 373.639336 -258.066332) (xy 373.623288 -258.115725) (xy 373.59971 -258.161999)
			(xy 373.569184 -258.204015) (xy 373.532461 -258.240738) (xy 373.490445 -258.271264) (xy 373.444171 -258.294842)
			(xy 373.394778 -258.31089) (xy 373.343483 -258.319015) (xy 373.291549 -258.319015) (xy 373.240254 -258.31089)
			(xy 373.190861 -258.294842) (xy 373.144587 -258.271264) (xy 373.102571 -258.240738) (xy 373.065848 -258.204015)
			(xy 373.035322 -258.161999) (xy 373.011744 -258.115725) (xy 372.995696 -258.066332) (xy 372.987571 -258.015037)
			(xy 372.707407 -258.015037) (xy 372.699282 -258.066332) (xy 372.683234 -258.115725) (xy 372.659656 -258.161999)
			(xy 372.62913 -258.204015) (xy 372.592407 -258.240738) (xy 372.550391 -258.271264) (xy 372.504117 -258.294842)
			(xy 372.454724 -258.31089) (xy 372.403429 -258.319015) (xy 372.351495 -258.319015) (xy 372.3002 -258.31089)
			(xy 372.250807 -258.294842) (xy 372.204533 -258.271264) (xy 372.162517 -258.240738) (xy 372.125794 -258.204015)
			(xy 372.095268 -258.161999) (xy 372.07169 -258.115725) (xy 372.055642 -258.066332) (xy 372.047517 -258.015037)
			(xy 371.767607 -258.015037) (xy 371.759482 -258.066332) (xy 371.743434 -258.115725) (xy 371.719856 -258.161999)
			(xy 371.68933 -258.204015) (xy 371.652607 -258.240738) (xy 371.610591 -258.271264) (xy 371.564317 -258.294842)
			(xy 371.514924 -258.31089) (xy 371.463629 -258.319015) (xy 371.411695 -258.319015) (xy 371.3604 -258.31089)
			(xy 371.311007 -258.294842) (xy 371.264733 -258.271264) (xy 371.222717 -258.240738) (xy 371.185994 -258.204015)
			(xy 371.155468 -258.161999) (xy 371.13189 -258.115725) (xy 371.115842 -258.066332) (xy 371.107717 -258.015037)
			(xy 370.827807 -258.015037) (xy 370.819682 -258.066332) (xy 370.803634 -258.115725) (xy 370.780056 -258.161999)
			(xy 370.74953 -258.204015) (xy 370.712807 -258.240738) (xy 370.670791 -258.271264) (xy 370.624517 -258.294842)
			(xy 370.575124 -258.31089) (xy 370.523829 -258.319015) (xy 370.471895 -258.319015) (xy 370.4206 -258.31089)
			(xy 370.371207 -258.294842) (xy 370.324933 -258.271264) (xy 370.282917 -258.240738) (xy 370.246194 -258.204015)
			(xy 370.215668 -258.161999) (xy 370.19209 -258.115725) (xy 370.176042 -258.066332) (xy 370.167917 -258.015037)
			(xy 369.888007 -258.015037) (xy 369.879882 -258.066332) (xy 369.863834 -258.115725) (xy 369.840256 -258.161999)
			(xy 369.80973 -258.204015) (xy 369.773007 -258.240738) (xy 369.730991 -258.271264) (xy 369.684717 -258.294842)
			(xy 369.635324 -258.31089) (xy 369.584029 -258.319015) (xy 369.532095 -258.319015) (xy 369.4808 -258.31089)
			(xy 369.431407 -258.294842) (xy 369.385133 -258.271264) (xy 369.343117 -258.240738) (xy 369.306394 -258.204015)
			(xy 369.275868 -258.161999) (xy 369.25229 -258.115725) (xy 369.236242 -258.066332) (xy 369.228117 -258.015037)
			(xy 367.700888 -258.015037) (xy 367.651596 -258.022848) (xy 367.62563 -258.02336) (xy 367.601105 -258.022875)
			(xy 367.552594 -258.015618) (xy 367.505688 -258.001273) (xy 367.461416 -257.980156) (xy 367.420749 -257.95273)
			(xy 367.402364 -257.936492) (xy 367.390762 -257.926675) (xy 367.363308 -257.913678) (xy 367.333247 -257.909325)
			(xy 367.303234 -257.914003) (xy 367.275923 -257.927296) (xy 367.264442 -257.937254) (xy 367.245993 -257.953835)
			(xy 367.20505 -257.981837) (xy 367.160382 -258.003405) (xy 367.112992 -258.018056) (xy 367.063945 -258.02546)
			(xy 367.039144 -258.0259) (xy 367.01479 -258.02546) (xy 366.966609 -258.018316) (xy 366.92 -258.004174)
			(xy 366.875971 -257.983343) (xy 366.835478 -257.956274) (xy 366.799398 -257.923552) (xy 366.78362 -257.904996)
			(xy 366.773702 -257.893812) (xy 366.748909 -257.877148) (xy 366.720357 -257.868363) (xy 366.690485 -257.86821)
			(xy 366.661843 -257.876699) (xy 366.63688 -257.893107) (xy 366.626902 -257.904234) (xy 366.61111 -257.92252)
			(xy 366.575143 -257.954778) (xy 366.53486 -257.981452) (xy 366.49112 -258.001972) (xy 366.444857 -258.0159)
			(xy 366.397059 -258.022939) (xy 366.372902 -258.02336) (xy 366.347042 -258.022843) (xy 366.295951 -258.014798)
			(xy 366.246739 -257.99889) (xy 366.200607 -257.975506) (xy 366.158683 -257.945218) (xy 366.139984 -257.927348)
			(xy 366.130269 -257.918303) (xy 366.10726 -257.905091) (xy 366.081623 -257.898254) (xy 366.055089 -257.898254)
			(xy 366.029452 -257.905091) (xy 366.006443 -257.918303) (xy 365.996728 -257.927348) (xy 365.978028 -257.945217)
			(xy 365.936101 -257.975502) (xy 365.88997 -257.998887) (xy 365.840759 -258.014802) (xy 365.78967 -258.022859)
			(xy 365.76381 -258.02336) (xy 365.739789 -258.022918) (xy 365.692252 -258.015963) (xy 365.646224 -258.002197)
			(xy 365.602674 -257.98191) (xy 365.562521 -257.955532) (xy 365.526611 -257.923616) (xy 365.510826 -257.905504)
			(xy 365.501081 -257.894607) (xy 365.476701 -257.87849) (xy 365.448761 -257.869917) (xy 365.419538 -257.869586)
			(xy 365.391411 -257.877523) (xy 365.366671 -257.893082) (xy 365.356648 -257.903726) (xy 365.33767 -257.924397)
			(xy 365.294006 -257.959638) (xy 365.245015 -257.986994) (xy 365.192106 -258.005677) (xy 365.1368 -258.01515)
			(xy 365.108744 -258.01574) (xy 365.081051 -258.015126) (xy 365.026441 -258.005892) (xy 364.974137 -257.987676)
			(xy 364.925606 -257.960989) (xy 364.882207 -257.926578) (xy 364.845159 -257.885409) (xy 364.829852 -257.862324)
			(xy 364.821454 -257.85016) (xy 364.799154 -257.830787) (xy 364.772243 -257.818604) (xy 364.742971 -257.814628)
			(xy 364.713786 -257.819193) (xy 364.687126 -257.831915) (xy 364.66522 -257.851733) (xy 364.657132 -257.864102)
			(xy 364.644229 -257.884624) (xy 364.613315 -257.921964) (xy 364.577281 -257.954391) (xy 364.536898 -257.981208)
			(xy 364.493033 -258.001843) (xy 364.446624 -258.015851) (xy 364.398668 -258.022933) (xy 364.37443 -258.02336)
			(xy 364.34846 -258.022867) (xy 364.297158 -258.014746) (xy 364.247758 -257.998699) (xy 364.201477 -257.975122)
			(xy 364.159455 -257.944594) (xy 364.122725 -257.907868) (xy 364.092194 -257.865848) (xy 364.068612 -257.81957)
			(xy 364.052561 -257.770171) (xy 364.044435 -257.71887) (xy 363.432472 -257.71887) (xy 363.425996 -257.759754)
			(xy 363.409948 -257.809147) (xy 363.38637 -257.855421) (xy 363.355844 -257.897437) (xy 363.319121 -257.93416)
			(xy 363.277105 -257.964686) (xy 363.230831 -257.988264) (xy 363.181438 -258.004312) (xy 363.130143 -258.012437)
			(xy 363.078209 -258.012437) (xy 363.026914 -258.004312) (xy 362.977521 -257.988264) (xy 362.931247 -257.964686)
			(xy 362.889231 -257.93416) (xy 362.852508 -257.897437) (xy 362.821982 -257.855421) (xy 362.798404 -257.809147)
			(xy 362.782356 -257.759754) (xy 362.774231 -257.708459) (xy 362.773722 -257.682492) (xy 362.774127 -257.658437)
			(xy 362.781093 -257.610836) (xy 362.794891 -257.564748) (xy 362.815229 -257.521149) (xy 362.841677 -257.480963)
			(xy 362.873675 -257.445038) (xy 362.891832 -257.429254) (xy 362.89998 -257.421672) (xy 362.909356 -257.401512)
			(xy 362.909353 -257.379278) (xy 362.899974 -257.35912) (xy 362.891832 -257.35153) (xy 362.872782 -257.334004)
			(xy 362.865944 -257.327796) (xy 362.849022 -257.320418) (xy 362.830584 -257.319503) (xy 362.813015 -257.325169)
			(xy 362.798586 -257.336683) (xy 362.793534 -257.344418) (xy 362.780674 -257.365171) (xy 362.749774 -257.40297)
			(xy 362.713652 -257.435813) (xy 362.673091 -257.462987) (xy 362.628976 -257.4839) (xy 362.582264 -257.498099)
			(xy 362.533973 -257.505273) (xy 362.509562 -257.505708) (xy 362.483593 -257.505288) (xy 362.432296 -257.497158)
			(xy 362.382901 -257.481103) (xy 362.336626 -257.45752) (xy 362.29461 -257.426989) (xy 362.257886 -257.390261)
			(xy 362.22736 -257.348241) (xy 362.203782 -257.301964) (xy 362.187734 -257.252567) (xy 362.179609 -257.201269)
			(xy 361.899699 -257.201269) (xy 361.891582 -257.252516) (xy 361.875534 -257.301909) (xy 361.851956 -257.348183)
			(xy 361.82143 -257.390199) (xy 361.784707 -257.426922) (xy 361.742691 -257.457448) (xy 361.696417 -257.481026)
			(xy 361.647024 -257.497074) (xy 361.595729 -257.505199) (xy 361.543795 -257.505199) (xy 361.4925 -257.497074)
			(xy 361.443107 -257.481026) (xy 361.396833 -257.457448) (xy 361.354817 -257.426922) (xy 361.318094 -257.390199)
			(xy 361.287568 -257.348183) (xy 361.26399 -257.301909) (xy 361.247942 -257.252516) (xy 361.239817 -257.201221)
			(xy 360.959907 -257.201221) (xy 360.951782 -257.252516) (xy 360.935734 -257.301909) (xy 360.912156 -257.348183)
			(xy 360.88163 -257.390199) (xy 360.844907 -257.426922) (xy 360.802891 -257.457448) (xy 360.756617 -257.481026)
			(xy 360.707224 -257.497074) (xy 360.655929 -257.505199) (xy 360.603995 -257.505199) (xy 360.5527 -257.497074)
			(xy 360.503307 -257.481026) (xy 360.457033 -257.457448) (xy 360.415017 -257.426922) (xy 360.378294 -257.390199)
			(xy 360.347768 -257.348183) (xy 360.32419 -257.301909) (xy 360.308142 -257.252516) (xy 360.300017 -257.201221)
			(xy 360.020107 -257.201221) (xy 360.011982 -257.252516) (xy 359.995934 -257.301909) (xy 359.972356 -257.348183)
			(xy 359.94183 -257.390199) (xy 359.905107 -257.426922) (xy 359.863091 -257.457448) (xy 359.816817 -257.481026)
			(xy 359.767424 -257.497074) (xy 359.716129 -257.505199) (xy 359.664195 -257.505199) (xy 359.6129 -257.497074)
			(xy 359.563507 -257.481026) (xy 359.517233 -257.457448) (xy 359.475217 -257.426922) (xy 359.438494 -257.390199)
			(xy 359.407968 -257.348183) (xy 359.38439 -257.301909) (xy 359.368342 -257.252516) (xy 359.360217 -257.201221)
			(xy 359.080561 -257.201221) (xy 359.072436 -257.252516) (xy 359.056388 -257.301909) (xy 359.03281 -257.348183)
			(xy 359.002284 -257.390199) (xy 358.965561 -257.426922) (xy 358.923545 -257.457448) (xy 358.877271 -257.481026)
			(xy 358.827878 -257.497074) (xy 358.776583 -257.505199) (xy 358.724649 -257.505199) (xy 358.673354 -257.497074)
			(xy 358.623961 -257.481026) (xy 358.577687 -257.457448) (xy 358.535671 -257.426922) (xy 358.498948 -257.390199)
			(xy 358.468422 -257.348183) (xy 358.444844 -257.301909) (xy 358.428796 -257.252516) (xy 358.420671 -257.201221)
			(xy 358.140507 -257.201221) (xy 358.132382 -257.252516) (xy 358.116334 -257.301909) (xy 358.092756 -257.348183)
			(xy 358.06223 -257.390199) (xy 358.025507 -257.426922) (xy 357.983491 -257.457448) (xy 357.937217 -257.481026)
			(xy 357.887824 -257.497074) (xy 357.836529 -257.505199) (xy 357.784595 -257.505199) (xy 357.7333 -257.497074)
			(xy 357.683907 -257.481026) (xy 357.637633 -257.457448) (xy 357.595617 -257.426922) (xy 357.558894 -257.390199)
			(xy 357.528368 -257.348183) (xy 357.50479 -257.301909) (xy 357.488742 -257.252516) (xy 357.480617 -257.201221)
			(xy 356.930083 -257.201221) (xy 356.928451 -257.206554) (xy 356.907326 -257.250826) (xy 356.879892 -257.29149)
			(xy 356.86365 -257.309874) (xy 356.853889 -257.321397) (xy 356.840867 -257.348622) (xy 356.836389 -257.378466)
			(xy 356.840847 -257.408313) (xy 356.853851 -257.435546) (xy 356.86365 -257.447034) (xy 356.879875 -257.465433)
			(xy 356.907326 -257.506086) (xy 356.92846 -257.550353) (xy 356.942814 -257.59726) (xy 356.95007 -257.645773)
			(xy 356.950518 -257.6703) (xy 356.950518 -257.670554) (xy 356.950009 -257.696521) (xy 356.941884 -257.747816)
			(xy 356.925836 -257.797209) (xy 356.902258 -257.843483) (xy 356.871732 -257.885499) (xy 356.835009 -257.922222)
			(xy 356.792993 -257.952748) (xy 356.746719 -257.976326) (xy 356.697326 -257.992374) (xy 356.646031 -258.000499)
			(xy 356.594097 -258.000499) (xy 356.542802 -257.992374) (xy 356.493409 -257.976326) (xy 356.447135 -257.952748)
			(xy 356.405119 -257.922222) (xy 356.368396 -257.885499) (xy 356.33787 -257.843483) (xy 356.314292 -257.797209)
			(xy 356.298244 -257.747816) (xy 356.290119 -257.696521) (xy 356.28961 -257.670554) (xy 355.715571 -257.670554)
			(xy 355.715571 -257.701068) (xy 355.707447 -257.752365) (xy 355.691398 -257.801759) (xy 355.667821 -257.848035)
			(xy 355.637295 -257.890053) (xy 355.600572 -257.926779) (xy 355.558556 -257.957308) (xy 355.512281 -257.980889)
			(xy 355.462888 -257.996941) (xy 355.411592 -258.005069) (xy 355.385624 -258.00558) (xy 355.361529 -258.005157)
			(xy 355.313852 -257.998143) (xy 355.2677 -257.984275) (xy 355.224053 -257.963848) (xy 355.183838 -257.937295)
			(xy 355.147908 -257.90518) (xy 355.132132 -257.886962) (xy 355.122216 -257.875908) (xy 355.097428 -257.859577)
			(xy 355.068996 -257.851053) (xy 355.039312 -257.851053) (xy 355.01088 -257.859577) (xy 354.986092 -257.875908)
			(xy 354.976176 -257.886962) (xy 354.960412 -257.90519) (xy 354.924482 -257.937306) (xy 354.884264 -257.963857)
			(xy 354.840614 -257.98428) (xy 354.794459 -257.99814) (xy 354.74678 -258.005143) (xy 354.722684 -258.00558)
			(xy 354.696288 -258.005093) (xy 354.644168 -257.99669) (xy 354.594049 -257.980103) (xy 354.547208 -257.955752)
			(xy 354.504837 -257.924259) (xy 354.468018 -257.886425) (xy 354.452428 -257.865118) (xy 354.44384 -257.853655)
			(xy 354.421538 -257.835697) (xy 354.395127 -257.82464) (xy 354.366683 -257.821352) (xy 354.338446 -257.826093)
			(xy 354.312636 -257.83849) (xy 354.291284 -257.857567) (xy 354.283264 -257.869436) (xy 354.267949 -257.892593)
			(xy 354.230859 -257.933897) (xy 354.187391 -257.968428) (xy 354.138768 -257.995215) (xy 354.086354 -258.013506)
			(xy 354.077326 -258.015037) (xy 357.010717 -258.015037) (xy 357.010717 -257.963103) (xy 357.018842 -257.911808)
			(xy 357.03489 -257.862415) (xy 357.058468 -257.816141) (xy 357.088994 -257.774125) (xy 357.125717 -257.737402)
			(xy 357.167733 -257.706876) (xy 357.214007 -257.683298) (xy 357.2634 -257.66725) (xy 357.314695 -257.659125)
			(xy 357.366629 -257.659125) (xy 357.417924 -257.66725) (xy 357.467317 -257.683298) (xy 357.513591 -257.706876)
			(xy 357.555607 -257.737402) (xy 357.59233 -257.774125) (xy 357.622856 -257.816141) (xy 357.646434 -257.862415)
			(xy 357.662482 -257.911808) (xy 357.670607 -257.963103) (xy 357.671116 -257.98907) (xy 357.670607 -258.015037)
			(xy 357.950517 -258.015037) (xy 357.950517 -257.963103) (xy 357.958642 -257.911808) (xy 357.97469 -257.862415)
			(xy 357.998268 -257.816141) (xy 358.028794 -257.774125) (xy 358.065517 -257.737402) (xy 358.107533 -257.706876)
			(xy 358.153807 -257.683298) (xy 358.2032 -257.66725) (xy 358.254495 -257.659125) (xy 358.306429 -257.659125)
			(xy 358.357724 -257.66725) (xy 358.407117 -257.683298) (xy 358.453391 -257.706876) (xy 358.495407 -257.737402)
			(xy 358.53213 -257.774125) (xy 358.562656 -257.816141) (xy 358.586234 -257.862415) (xy 358.602282 -257.911808)
			(xy 358.610407 -257.963103) (xy 358.610916 -257.98907) (xy 358.610407 -258.015037) (xy 358.890571 -258.015037)
			(xy 358.890571 -257.963103) (xy 358.898696 -257.911808) (xy 358.914744 -257.862415) (xy 358.938322 -257.816141)
			(xy 358.968848 -257.774125) (xy 359.005571 -257.737402) (xy 359.047587 -257.706876) (xy 359.093861 -257.683298)
			(xy 359.143254 -257.66725) (xy 359.194549 -257.659125) (xy 359.246483 -257.659125) (xy 359.297778 -257.66725)
			(xy 359.347171 -257.683298) (xy 359.393445 -257.706876) (xy 359.435461 -257.737402) (xy 359.472184 -257.774125)
			(xy 359.50271 -257.816141) (xy 359.526288 -257.862415) (xy 359.542336 -257.911808) (xy 359.550461 -257.963103)
			(xy 359.55097 -257.98907) (xy 359.550461 -258.015037) (xy 359.830371 -258.015037) (xy 359.830371 -257.963103)
			(xy 359.838496 -257.911808) (xy 359.854544 -257.862415) (xy 359.878122 -257.816141) (xy 359.908648 -257.774125)
			(xy 359.945371 -257.737402) (xy 359.987387 -257.706876) (xy 360.033661 -257.683298) (xy 360.083054 -257.66725)
			(xy 360.134349 -257.659125) (xy 360.186283 -257.659125) (xy 360.237578 -257.66725) (xy 360.286971 -257.683298)
			(xy 360.333245 -257.706876) (xy 360.375261 -257.737402) (xy 360.411984 -257.774125) (xy 360.44251 -257.816141)
			(xy 360.466088 -257.862415) (xy 360.482136 -257.911808) (xy 360.490261 -257.963103) (xy 360.49077 -257.98907)
			(xy 360.490261 -258.015037) (xy 360.769917 -258.015037) (xy 360.769917 -257.963103) (xy 360.778042 -257.911808)
			(xy 360.79409 -257.862415) (xy 360.817668 -257.816141) (xy 360.848194 -257.774125) (xy 360.884917 -257.737402)
			(xy 360.926933 -257.706876) (xy 360.973207 -257.683298) (xy 361.0226 -257.66725) (xy 361.073895 -257.659125)
			(xy 361.125829 -257.659125) (xy 361.177124 -257.66725) (xy 361.226517 -257.683298) (xy 361.272791 -257.706876)
			(xy 361.314807 -257.737402) (xy 361.35153 -257.774125) (xy 361.382056 -257.816141) (xy 361.405634 -257.862415)
			(xy 361.421682 -257.911808) (xy 361.429807 -257.963103) (xy 361.430316 -257.98907) (xy 361.429807 -258.015037)
			(xy 361.709971 -258.015037) (xy 361.709971 -257.963103) (xy 361.718096 -257.911808) (xy 361.734144 -257.862415)
			(xy 361.757722 -257.816141) (xy 361.788248 -257.774125) (xy 361.824971 -257.737402) (xy 361.866987 -257.706876)
			(xy 361.913261 -257.683298) (xy 361.962654 -257.66725) (xy 362.013949 -257.659125) (xy 362.065883 -257.659125)
			(xy 362.117178 -257.66725) (xy 362.166571 -257.683298) (xy 362.212845 -257.706876) (xy 362.254861 -257.737402)
			(xy 362.291584 -257.774125) (xy 362.32211 -257.816141) (xy 362.345688 -257.862415) (xy 362.361736 -257.911808)
			(xy 362.369861 -257.963103) (xy 362.37037 -257.98907) (xy 362.369861 -258.015037) (xy 362.361736 -258.066332)
			(xy 362.345688 -258.115725) (xy 362.32211 -258.161999) (xy 362.291584 -258.204015) (xy 362.254861 -258.240738)
			(xy 362.212845 -258.271264) (xy 362.166571 -258.294842) (xy 362.117178 -258.31089) (xy 362.065883 -258.319015)
			(xy 362.013949 -258.319015) (xy 361.962654 -258.31089) (xy 361.913261 -258.294842) (xy 361.866987 -258.271264)
			(xy 361.824971 -258.240738) (xy 361.788248 -258.204015) (xy 361.757722 -258.161999) (xy 361.734144 -258.115725)
			(xy 361.718096 -258.066332) (xy 361.709971 -258.015037) (xy 361.429807 -258.015037) (xy 361.421682 -258.066332)
			(xy 361.405634 -258.115725) (xy 361.382056 -258.161999) (xy 361.35153 -258.204015) (xy 361.314807 -258.240738)
			(xy 361.272791 -258.271264) (xy 361.226517 -258.294842) (xy 361.177124 -258.31089) (xy 361.125829 -258.319015)
			(xy 361.073895 -258.319015) (xy 361.0226 -258.31089) (xy 360.973207 -258.294842) (xy 360.926933 -258.271264)
			(xy 360.884917 -258.240738) (xy 360.848194 -258.204015) (xy 360.817668 -258.161999) (xy 360.79409 -258.115725)
			(xy 360.778042 -258.066332) (xy 360.769917 -258.015037) (xy 360.490261 -258.015037) (xy 360.482136 -258.066332)
			(xy 360.466088 -258.115725) (xy 360.44251 -258.161999) (xy 360.411984 -258.204015) (xy 360.375261 -258.240738)
			(xy 360.333245 -258.271264) (xy 360.286971 -258.294842) (xy 360.237578 -258.31089) (xy 360.186283 -258.319015)
			(xy 360.134349 -258.319015) (xy 360.083054 -258.31089) (xy 360.033661 -258.294842) (xy 359.987387 -258.271264)
			(xy 359.945371 -258.240738) (xy 359.908648 -258.204015) (xy 359.878122 -258.161999) (xy 359.854544 -258.115725)
			(xy 359.838496 -258.066332) (xy 359.830371 -258.015037) (xy 359.550461 -258.015037) (xy 359.542336 -258.066332)
			(xy 359.526288 -258.115725) (xy 359.50271 -258.161999) (xy 359.472184 -258.204015) (xy 359.435461 -258.240738)
			(xy 359.393445 -258.271264) (xy 359.347171 -258.294842) (xy 359.297778 -258.31089) (xy 359.246483 -258.319015)
			(xy 359.194549 -258.319015) (xy 359.143254 -258.31089) (xy 359.093861 -258.294842) (xy 359.047587 -258.271264)
			(xy 359.005571 -258.240738) (xy 358.968848 -258.204015) (xy 358.938322 -258.161999) (xy 358.914744 -258.115725)
			(xy 358.898696 -258.066332) (xy 358.890571 -258.015037) (xy 358.610407 -258.015037) (xy 358.602282 -258.066332)
			(xy 358.586234 -258.115725) (xy 358.562656 -258.161999) (xy 358.53213 -258.204015) (xy 358.495407 -258.240738)
			(xy 358.453391 -258.271264) (xy 358.407117 -258.294842) (xy 358.357724 -258.31089) (xy 358.306429 -258.319015)
			(xy 358.254495 -258.319015) (xy 358.2032 -258.31089) (xy 358.153807 -258.294842) (xy 358.107533 -258.271264)
			(xy 358.065517 -258.240738) (xy 358.028794 -258.204015) (xy 357.998268 -258.161999) (xy 357.97469 -258.115725)
			(xy 357.958642 -258.066332) (xy 357.950517 -258.015037) (xy 357.670607 -258.015037) (xy 357.662482 -258.066332)
			(xy 357.646434 -258.115725) (xy 357.622856 -258.161999) (xy 357.59233 -258.204015) (xy 357.555607 -258.240738)
			(xy 357.513591 -258.271264) (xy 357.467317 -258.294842) (xy 357.417924 -258.31089) (xy 357.366629 -258.319015)
			(xy 357.314695 -258.319015) (xy 357.2634 -258.31089) (xy 357.214007 -258.294842) (xy 357.167733 -258.271264)
			(xy 357.125717 -258.240738) (xy 357.088994 -258.204015) (xy 357.058468 -258.161999) (xy 357.03489 -258.115725)
			(xy 357.018842 -258.066332) (xy 357.010717 -258.015037) (xy 354.077326 -258.015037) (xy 354.031621 -258.022788)
			(xy 354.003864 -258.02336) (xy 353.978109 -258.022909) (xy 353.927221 -258.014922) (xy 353.87819 -257.999133)
			(xy 353.832205 -257.975923) (xy 353.79038 -257.945856) (xy 353.771708 -257.92811) (xy 353.762018 -257.919117)
			(xy 353.739086 -257.905985) (xy 353.713547 -257.89919) (xy 353.687121 -257.89919) (xy 353.661582 -257.905985)
			(xy 353.63865 -257.919117) (xy 353.62896 -257.92811) (xy 353.610299 -257.945865) (xy 353.568461 -257.975908)
			(xy 353.522471 -257.9991) (xy 353.473441 -258.014881) (xy 353.422557 -258.022868) (xy 353.396804 -258.02336)
			(xy 353.370835 -258.022865) (xy 353.319536 -258.014741) (xy 353.27014 -257.998692) (xy 353.223863 -257.975113)
			(xy 353.181844 -257.944585) (xy 353.145118 -257.907859) (xy 353.114589 -257.865841) (xy 353.09101 -257.819564)
			(xy 353.07496 -257.770168) (xy 353.066835 -257.718869) (xy 352.837751 -257.718869) (xy 352.829626 -257.770163)
			(xy 352.813578 -257.819556) (xy 352.79 -257.865831) (xy 352.759473 -257.907847) (xy 352.72275 -257.944571)
			(xy 352.680734 -257.975098) (xy 352.63446 -257.998676) (xy 352.585067 -258.014725) (xy 352.533771 -258.02285)
			(xy 352.507804 -258.02336) (xy 352.50755 -258.02336) (xy 352.483023 -258.022923) (xy 352.43451 -258.015654)
			(xy 352.387604 -258.001298) (xy 352.343332 -257.98017) (xy 352.302668 -257.952734) (xy 352.284284 -257.936492)
			(xy 352.272795 -257.926689) (xy 352.245558 -257.913675) (xy 352.215704 -257.909207) (xy 352.18585 -257.913675)
			(xy 352.158613 -257.926689) (xy 352.147124 -257.936492) (xy 352.128728 -257.95276) (xy 352.088021 -257.980227)
			(xy 352.043696 -258.001364) (xy 351.99673 -258.015704) (xy 351.948158 -258.022932) (xy 351.923604 -258.02336)
			(xy 351.899051 -258.02294) (xy 351.850484 -258.015693) (xy 351.803522 -258.001344) (xy 351.759198 -257.980208)
			(xy 351.718488 -257.95275) (xy 351.700084 -257.936492) (xy 351.688595 -257.926689) (xy 351.661358 -257.913675)
			(xy 351.631504 -257.909207) (xy 351.60165 -257.913675) (xy 351.574413 -257.926689) (xy 351.562924 -257.936492)
			(xy 351.544548 -257.952744) (xy 351.503887 -257.980189) (xy 351.459615 -258.001318) (xy 351.412703 -258.015665)
			(xy 351.364186 -258.022915) (xy 351.339658 -258.02336) (xy 351.339404 -258.02336) (xy 351.313435 -258.022865)
			(xy 351.262136 -258.014741) (xy 351.21274 -257.998692) (xy 351.166463 -257.975113) (xy 351.124444 -257.944585)
			(xy 351.087718 -257.907859) (xy 351.057189 -257.865841) (xy 351.03361 -257.819564) (xy 351.01756 -257.770168)
			(xy 351.009435 -257.718869) (xy 350.011698 -257.718869) (xy 350.037207 -257.737402) (xy 350.07393 -257.774125)
			(xy 350.104456 -257.816141) (xy 350.128034 -257.862415) (xy 350.144082 -257.911808) (xy 350.152207 -257.963103)
			(xy 350.152716 -257.98907) (xy 350.152207 -258.015037) (xy 350.144082 -258.066332) (xy 350.128034 -258.115725)
			(xy 350.104456 -258.161999) (xy 350.07393 -258.204015) (xy 350.037207 -258.240738) (xy 349.995191 -258.271264)
			(xy 349.948917 -258.294842) (xy 349.899524 -258.31089) (xy 349.848229 -258.319015) (xy 349.796295 -258.319015)
			(xy 349.745 -258.31089) (xy 349.695607 -258.294842) (xy 349.649333 -258.271264) (xy 349.607317 -258.240738)
			(xy 349.570594 -258.204015) (xy 349.540068 -258.161999) (xy 349.51649 -258.115725) (xy 349.500442 -258.066332)
			(xy 349.492317 -258.015037) (xy 349.212407 -258.015037) (xy 349.204282 -258.066332) (xy 349.188234 -258.115725)
			(xy 349.164656 -258.161999) (xy 349.13413 -258.204015) (xy 349.097407 -258.240738) (xy 349.055391 -258.271264)
			(xy 349.009117 -258.294842) (xy 348.959724 -258.31089) (xy 348.908429 -258.319015) (xy 348.856495 -258.319015)
			(xy 348.8052 -258.31089) (xy 348.755807 -258.294842) (xy 348.709533 -258.271264) (xy 348.667517 -258.240738)
			(xy 348.630794 -258.204015) (xy 348.600268 -258.161999) (xy 348.57669 -258.115725) (xy 348.560642 -258.066332)
			(xy 348.552517 -258.015037) (xy 348.272607 -258.015037) (xy 348.264482 -258.066332) (xy 348.248434 -258.115725)
			(xy 348.224856 -258.161999) (xy 348.19433 -258.204015) (xy 348.157607 -258.240738) (xy 348.115591 -258.271264)
			(xy 348.069317 -258.294842) (xy 348.019924 -258.31089) (xy 347.968629 -258.319015) (xy 347.916695 -258.319015)
			(xy 347.8654 -258.31089) (xy 347.816007 -258.294842) (xy 347.769733 -258.271264) (xy 347.727717 -258.240738)
			(xy 347.690994 -258.204015) (xy 347.660468 -258.161999) (xy 347.63689 -258.115725) (xy 347.620842 -258.066332)
			(xy 347.612717 -258.015037) (xy 347.333061 -258.015037) (xy 347.324936 -258.066332) (xy 347.308888 -258.115725)
			(xy 347.28531 -258.161999) (xy 347.254784 -258.204015) (xy 347.218061 -258.240738) (xy 347.176045 -258.271264)
			(xy 347.129771 -258.294842) (xy 347.080378 -258.31089) (xy 347.029083 -258.319015) (xy 346.977149 -258.319015)
			(xy 346.925854 -258.31089) (xy 346.876461 -258.294842) (xy 346.830187 -258.271264) (xy 346.788171 -258.240738)
			(xy 346.751448 -258.204015) (xy 346.720922 -258.161999) (xy 346.697344 -258.115725) (xy 346.681296 -258.066332)
			(xy 346.673171 -258.015037) (xy 346.393007 -258.015037) (xy 346.384882 -258.066332) (xy 346.368834 -258.115725)
			(xy 346.345256 -258.161999) (xy 346.31473 -258.204015) (xy 346.278007 -258.240738) (xy 346.235991 -258.271264)
			(xy 346.189717 -258.294842) (xy 346.140324 -258.31089) (xy 346.089029 -258.319015) (xy 346.037095 -258.319015)
			(xy 345.9858 -258.31089) (xy 345.936407 -258.294842) (xy 345.890133 -258.271264) (xy 345.848117 -258.240738)
			(xy 345.811394 -258.204015) (xy 345.780868 -258.161999) (xy 345.75729 -258.115725) (xy 345.741242 -258.066332)
			(xy 345.733117 -258.015037) (xy 345.453461 -258.015037) (xy 345.445336 -258.066332) (xy 345.429288 -258.115725)
			(xy 345.40571 -258.161999) (xy 345.375184 -258.204015) (xy 345.338461 -258.240738) (xy 345.296445 -258.271264)
			(xy 345.250171 -258.294842) (xy 345.200778 -258.31089) (xy 345.149483 -258.319015) (xy 345.097549 -258.319015)
			(xy 345.046254 -258.31089) (xy 344.996861 -258.294842) (xy 344.950587 -258.271264) (xy 344.908571 -258.240738)
			(xy 344.871848 -258.204015) (xy 344.841322 -258.161999) (xy 344.817744 -258.115725) (xy 344.801696 -258.066332)
			(xy 344.793571 -258.015037) (xy 344.513407 -258.015037) (xy 344.505282 -258.066332) (xy 344.489234 -258.115725)
			(xy 344.465656 -258.161999) (xy 344.43513 -258.204015) (xy 344.398407 -258.240738) (xy 344.356391 -258.271264)
			(xy 344.310117 -258.294842) (xy 344.260724 -258.31089) (xy 344.209429 -258.319015) (xy 344.157495 -258.319015)
			(xy 344.1062 -258.31089) (xy 344.056807 -258.294842) (xy 344.010533 -258.271264) (xy 343.968517 -258.240738)
			(xy 343.931794 -258.204015) (xy 343.901268 -258.161999) (xy 343.87769 -258.115725) (xy 343.861642 -258.066332)
			(xy 343.853517 -258.015037) (xy 343.573607 -258.015037) (xy 343.565482 -258.066332) (xy 343.549434 -258.115725)
			(xy 343.525856 -258.161999) (xy 343.49533 -258.204015) (xy 343.458607 -258.240738) (xy 343.416591 -258.271264)
			(xy 343.370317 -258.294842) (xy 343.320924 -258.31089) (xy 343.269629 -258.319015) (xy 343.217695 -258.319015)
			(xy 343.1664 -258.31089) (xy 343.117007 -258.294842) (xy 343.070733 -258.271264) (xy 343.028717 -258.240738)
			(xy 342.991994 -258.204015) (xy 342.961468 -258.161999) (xy 342.93789 -258.115725) (xy 342.921842 -258.066332)
			(xy 342.913717 -258.015037) (xy 342.633807 -258.015037) (xy 342.625682 -258.066332) (xy 342.609634 -258.115725)
			(xy 342.586056 -258.161999) (xy 342.55553 -258.204015) (xy 342.518807 -258.240738) (xy 342.476791 -258.271264)
			(xy 342.430517 -258.294842) (xy 342.381124 -258.31089) (xy 342.329829 -258.319015) (xy 342.277895 -258.319015)
			(xy 342.2266 -258.31089) (xy 342.177207 -258.294842) (xy 342.130933 -258.271264) (xy 342.088917 -258.240738)
			(xy 342.052194 -258.204015) (xy 342.021668 -258.161999) (xy 341.99809 -258.115725) (xy 341.982042 -258.066332)
			(xy 341.973917 -258.015037) (xy 341.694007 -258.015037) (xy 341.685882 -258.066332) (xy 341.669834 -258.115725)
			(xy 341.646256 -258.161999) (xy 341.61573 -258.204015) (xy 341.579007 -258.240738) (xy 341.536991 -258.271264)
			(xy 341.490717 -258.294842) (xy 341.441324 -258.31089) (xy 341.390029 -258.319015) (xy 341.338095 -258.319015)
			(xy 341.2868 -258.31089) (xy 341.237407 -258.294842) (xy 341.191133 -258.271264) (xy 341.149117 -258.240738)
			(xy 341.112394 -258.204015) (xy 341.081868 -258.161999) (xy 341.05829 -258.115725) (xy 341.042242 -258.066332)
			(xy 341.034117 -258.015037) (xy 340.754461 -258.015037) (xy 340.746336 -258.066332) (xy 340.730288 -258.115725)
			(xy 340.70671 -258.161999) (xy 340.676184 -258.204015) (xy 340.639461 -258.240738) (xy 340.597445 -258.271264)
			(xy 340.551171 -258.294842) (xy 340.501778 -258.31089) (xy 340.450483 -258.319015) (xy 340.398549 -258.319015)
			(xy 340.347254 -258.31089) (xy 340.297861 -258.294842) (xy 340.251587 -258.271264) (xy 340.209571 -258.240738)
			(xy 340.172848 -258.204015) (xy 340.142322 -258.161999) (xy 340.118744 -258.115725) (xy 340.102696 -258.066332)
			(xy 340.094571 -258.015037) (xy 339.813773 -258.015037) (xy 339.811848 -258.039959) (xy 339.800147 -258.089626)
			(xy 339.780954 -258.136905) (xy 339.754723 -258.180673) (xy 339.722078 -258.21989) (xy 339.683795 -258.253626)
			(xy 339.662516 -258.267708) (xy 339.651848 -258.274566) (xy 339.627464 -258.317238) (xy 339.627464 -258.436618)
			(xy 339.627783 -258.445002) (xy 339.633288 -258.460842) (xy 339.643683 -258.474) (xy 339.650578 -258.478782)
			(xy 339.718142 -258.516628) (xy 339.723391 -258.519116) (xy 339.734687 -258.521814) (xy 339.740494 -258.521962)
			(xy 339.76691 -258.521962) (xy 339.791294 -258.515358) (xy 339.795612 -258.513072) (xy 339.820105 -258.500302)
			(xy 339.872286 -258.482198) (xy 339.926746 -258.472999) (xy 339.954362 -258.472432) (xy 339.954616 -258.472432)
			(xy 339.980599 -258.472943) (xy 340.031925 -258.481075) (xy 340.081348 -258.497135) (xy 340.127649 -258.520729)
			(xy 340.16969 -258.551275) (xy 340.206435 -258.588022) (xy 340.236979 -258.630064) (xy 340.260571 -258.676367)
			(xy 340.276629 -258.72579) (xy 340.284758 -258.777117) (xy 340.284758 -258.829083) (xy 340.284754 -258.829107)
			(xy 340.564471 -258.829107) (xy 340.564471 -258.777173) (xy 340.572596 -258.725878) (xy 340.588644 -258.676485)
			(xy 340.612222 -258.630211) (xy 340.642748 -258.588195) (xy 340.679471 -258.551472) (xy 340.721487 -258.520946)
			(xy 340.767761 -258.497368) (xy 340.817154 -258.48132) (xy 340.868449 -258.473195) (xy 340.920383 -258.473195)
			(xy 340.971678 -258.48132) (xy 341.021071 -258.497368) (xy 341.067345 -258.520946) (xy 341.109361 -258.551472)
			(xy 341.146084 -258.588195) (xy 341.17661 -258.630211) (xy 341.200188 -258.676485) (xy 341.216236 -258.725878)
			(xy 341.224361 -258.777173) (xy 341.22487 -258.80314) (xy 341.224361 -258.829107) (xy 341.504271 -258.829107)
			(xy 341.504271 -258.777173) (xy 341.512396 -258.725878) (xy 341.528444 -258.676485) (xy 341.552022 -258.630211)
			(xy 341.582548 -258.588195) (xy 341.619271 -258.551472) (xy 341.661287 -258.520946) (xy 341.707561 -258.497368)
			(xy 341.756954 -258.48132) (xy 341.808249 -258.473195) (xy 341.860183 -258.473195) (xy 341.911478 -258.48132)
			(xy 341.960871 -258.497368) (xy 342.007145 -258.520946) (xy 342.049161 -258.551472) (xy 342.085884 -258.588195)
			(xy 342.11641 -258.630211) (xy 342.139988 -258.676485) (xy 342.156036 -258.725878) (xy 342.164161 -258.777173)
			(xy 342.16467 -258.80314) (xy 342.164161 -258.829107) (xy 342.443817 -258.829107) (xy 342.443817 -258.777173)
			(xy 342.451942 -258.725878) (xy 342.46799 -258.676485) (xy 342.491568 -258.630211) (xy 342.522094 -258.588195)
			(xy 342.558817 -258.551472) (xy 342.600833 -258.520946) (xy 342.647107 -258.497368) (xy 342.6965 -258.48132)
			(xy 342.747795 -258.473195) (xy 342.799729 -258.473195) (xy 342.851024 -258.48132) (xy 342.900417 -258.497368)
			(xy 342.946691 -258.520946) (xy 342.988707 -258.551472) (xy 343.02543 -258.588195) (xy 343.055956 -258.630211)
			(xy 343.079534 -258.676485) (xy 343.095582 -258.725878) (xy 343.103707 -258.777173) (xy 343.104216 -258.80314)
			(xy 343.103707 -258.829107) (xy 343.383871 -258.829107) (xy 343.383871 -258.777173) (xy 343.391996 -258.725878)
			(xy 343.408044 -258.676485) (xy 343.431622 -258.630211) (xy 343.462148 -258.588195) (xy 343.498871 -258.551472)
			(xy 343.540887 -258.520946) (xy 343.587161 -258.497368) (xy 343.636554 -258.48132) (xy 343.687849 -258.473195)
			(xy 343.739783 -258.473195) (xy 343.791078 -258.48132) (xy 343.840471 -258.497368) (xy 343.886745 -258.520946)
			(xy 343.928761 -258.551472) (xy 343.965484 -258.588195) (xy 343.99601 -258.630211) (xy 344.019588 -258.676485)
			(xy 344.035636 -258.725878) (xy 344.043761 -258.777173) (xy 344.04427 -258.80314) (xy 344.043761 -258.829107)
			(xy 344.323671 -258.829107) (xy 344.323671 -258.777173) (xy 344.331796 -258.725878) (xy 344.347844 -258.676485)
			(xy 344.371422 -258.630211) (xy 344.401948 -258.588195) (xy 344.438671 -258.551472) (xy 344.480687 -258.520946)
			(xy 344.526961 -258.497368) (xy 344.576354 -258.48132) (xy 344.627649 -258.473195) (xy 344.679583 -258.473195)
			(xy 344.730878 -258.48132) (xy 344.780271 -258.497368) (xy 344.826545 -258.520946) (xy 344.868561 -258.551472)
			(xy 344.905284 -258.588195) (xy 344.93581 -258.630211) (xy 344.959388 -258.676485) (xy 344.975436 -258.725878)
			(xy 344.983561 -258.777173) (xy 344.98407 -258.80314) (xy 344.983561 -258.829107) (xy 345.263471 -258.829107)
			(xy 345.263471 -258.777173) (xy 345.271596 -258.725878) (xy 345.287644 -258.676485) (xy 345.311222 -258.630211)
			(xy 345.341748 -258.588195) (xy 345.378471 -258.551472) (xy 345.420487 -258.520946) (xy 345.466761 -258.497368)
			(xy 345.516154 -258.48132) (xy 345.567449 -258.473195) (xy 345.619383 -258.473195) (xy 345.670678 -258.48132)
			(xy 345.720071 -258.497368) (xy 345.766345 -258.520946) (xy 345.808361 -258.551472) (xy 345.845084 -258.588195)
			(xy 345.87561 -258.630211) (xy 345.899188 -258.676485) (xy 345.915236 -258.725878) (xy 345.923361 -258.777173)
			(xy 345.92387 -258.80314) (xy 345.923361 -258.829107) (xy 346.203271 -258.829107) (xy 346.203271 -258.777173)
			(xy 346.211396 -258.725878) (xy 346.227444 -258.676485) (xy 346.251022 -258.630211) (xy 346.281548 -258.588195)
			(xy 346.318271 -258.551472) (xy 346.360287 -258.520946) (xy 346.406561 -258.497368) (xy 346.455954 -258.48132)
			(xy 346.507249 -258.473195) (xy 346.559183 -258.473195) (xy 346.610478 -258.48132) (xy 346.659871 -258.497368)
			(xy 346.706145 -258.520946) (xy 346.748161 -258.551472) (xy 346.784884 -258.588195) (xy 346.81541 -258.630211)
			(xy 346.838988 -258.676485) (xy 346.855036 -258.725878) (xy 346.863161 -258.777173) (xy 346.86367 -258.80314)
			(xy 346.863161 -258.829107) (xy 347.143071 -258.829107) (xy 347.143071 -258.777173) (xy 347.151196 -258.725878)
			(xy 347.167244 -258.676485) (xy 347.190822 -258.630211) (xy 347.221348 -258.588195) (xy 347.258071 -258.551472)
			(xy 347.300087 -258.520946) (xy 347.346361 -258.497368) (xy 347.395754 -258.48132) (xy 347.447049 -258.473195)
			(xy 347.498983 -258.473195) (xy 347.550278 -258.48132) (xy 347.599671 -258.497368) (xy 347.645945 -258.520946)
			(xy 347.687961 -258.551472) (xy 347.724684 -258.588195) (xy 347.75521 -258.630211) (xy 347.778788 -258.676485)
			(xy 347.794836 -258.725878) (xy 347.802961 -258.777173) (xy 347.80347 -258.80314) (xy 347.802961 -258.829107)
			(xy 348.082871 -258.829107) (xy 348.082871 -258.777173) (xy 348.090996 -258.725878) (xy 348.107044 -258.676485)
			(xy 348.130622 -258.630211) (xy 348.161148 -258.588195) (xy 348.197871 -258.551472) (xy 348.239887 -258.520946)
			(xy 348.286161 -258.497368) (xy 348.335554 -258.48132) (xy 348.386849 -258.473195) (xy 348.438783 -258.473195)
			(xy 348.490078 -258.48132) (xy 348.539471 -258.497368) (xy 348.585745 -258.520946) (xy 348.627761 -258.551472)
			(xy 348.664484 -258.588195) (xy 348.69501 -258.630211) (xy 348.718588 -258.676485) (xy 348.734636 -258.725878)
			(xy 348.742761 -258.777173) (xy 348.74327 -258.80314) (xy 348.742761 -258.829107) (xy 349.022417 -258.829107)
			(xy 349.022417 -258.777173) (xy 349.030542 -258.725878) (xy 349.04659 -258.676485) (xy 349.070168 -258.630211)
			(xy 349.100694 -258.588195) (xy 349.137417 -258.551472) (xy 349.179433 -258.520946) (xy 349.225707 -258.497368)
			(xy 349.2751 -258.48132) (xy 349.326395 -258.473195) (xy 349.378329 -258.473195) (xy 349.429624 -258.48132)
			(xy 349.479017 -258.497368) (xy 349.525291 -258.520946) (xy 349.567307 -258.551472) (xy 349.60403 -258.588195)
			(xy 349.634556 -258.630211) (xy 349.658134 -258.676485) (xy 349.674182 -258.725878) (xy 349.682307 -258.777173)
			(xy 349.682816 -258.80314) (xy 349.682307 -258.829107) (xy 349.961963 -258.829107) (xy 349.961963 -258.777173)
			(xy 349.970088 -258.725878) (xy 349.986136 -258.676485) (xy 350.009714 -258.630211) (xy 350.04024 -258.588195)
			(xy 350.076963 -258.551472) (xy 350.118979 -258.520946) (xy 350.165253 -258.497368) (xy 350.214646 -258.48132)
			(xy 350.265941 -258.473195) (xy 350.317875 -258.473195) (xy 350.36917 -258.48132) (xy 350.418563 -258.497368)
			(xy 350.464837 -258.520946) (xy 350.506853 -258.551472) (xy 350.543576 -258.588195) (xy 350.574102 -258.630211)
			(xy 350.59768 -258.676485) (xy 350.613728 -258.725878) (xy 350.621853 -258.777173) (xy 350.622362 -258.80314)
			(xy 350.621853 -258.829107) (xy 350.613728 -258.880402) (xy 350.59768 -258.929795) (xy 350.574102 -258.976069)
			(xy 350.543576 -259.018085) (xy 350.506853 -259.054808) (xy 350.464837 -259.085334) (xy 350.418563 -259.108912)
			(xy 350.36917 -259.12496) (xy 350.317875 -259.133085) (xy 350.265941 -259.133085) (xy 350.214646 -259.12496)
			(xy 350.165253 -259.108912) (xy 350.118979 -259.085334) (xy 350.076963 -259.054808) (xy 350.04024 -259.018085)
			(xy 350.009714 -258.976069) (xy 349.986136 -258.929795) (xy 349.970088 -258.880402) (xy 349.961963 -258.829107)
			(xy 349.682307 -258.829107) (xy 349.674182 -258.880402) (xy 349.658134 -258.929795) (xy 349.634556 -258.976069)
			(xy 349.60403 -259.018085) (xy 349.567307 -259.054808) (xy 349.525291 -259.085334) (xy 349.479017 -259.108912)
			(xy 349.429624 -259.12496) (xy 349.378329 -259.133085) (xy 349.326395 -259.133085) (xy 349.2751 -259.12496)
			(xy 349.225707 -259.108912) (xy 349.179433 -259.085334) (xy 349.137417 -259.054808) (xy 349.100694 -259.018085)
			(xy 349.070168 -258.976069) (xy 349.04659 -258.929795) (xy 349.030542 -258.880402) (xy 349.022417 -258.829107)
			(xy 348.742761 -258.829107) (xy 348.734636 -258.880402) (xy 348.718588 -258.929795) (xy 348.69501 -258.976069)
			(xy 348.664484 -259.018085) (xy 348.627761 -259.054808) (xy 348.585745 -259.085334) (xy 348.539471 -259.108912)
			(xy 348.490078 -259.12496) (xy 348.438783 -259.133085) (xy 348.386849 -259.133085) (xy 348.335554 -259.12496)
			(xy 348.286161 -259.108912) (xy 348.239887 -259.085334) (xy 348.197871 -259.054808) (xy 348.161148 -259.018085)
			(xy 348.130622 -258.976069) (xy 348.107044 -258.929795) (xy 348.090996 -258.880402) (xy 348.082871 -258.829107)
			(xy 347.802961 -258.829107) (xy 347.794836 -258.880402) (xy 347.778788 -258.929795) (xy 347.75521 -258.976069)
			(xy 347.724684 -259.018085) (xy 347.687961 -259.054808) (xy 347.645945 -259.085334) (xy 347.599671 -259.108912)
			(xy 347.550278 -259.12496) (xy 347.498983 -259.133085) (xy 347.447049 -259.133085) (xy 347.395754 -259.12496)
			(xy 347.346361 -259.108912) (xy 347.300087 -259.085334) (xy 347.258071 -259.054808) (xy 347.221348 -259.018085)
			(xy 347.190822 -258.976069) (xy 347.167244 -258.929795) (xy 347.151196 -258.880402) (xy 347.143071 -258.829107)
			(xy 346.863161 -258.829107) (xy 346.855036 -258.880402) (xy 346.838988 -258.929795) (xy 346.81541 -258.976069)
			(xy 346.784884 -259.018085) (xy 346.748161 -259.054808) (xy 346.706145 -259.085334) (xy 346.659871 -259.108912)
			(xy 346.610478 -259.12496) (xy 346.559183 -259.133085) (xy 346.507249 -259.133085) (xy 346.455954 -259.12496)
			(xy 346.406561 -259.108912) (xy 346.360287 -259.085334) (xy 346.318271 -259.054808) (xy 346.281548 -259.018085)
			(xy 346.251022 -258.976069) (xy 346.227444 -258.929795) (xy 346.211396 -258.880402) (xy 346.203271 -258.829107)
			(xy 345.923361 -258.829107) (xy 345.915236 -258.880402) (xy 345.899188 -258.929795) (xy 345.87561 -258.976069)
			(xy 345.845084 -259.018085) (xy 345.808361 -259.054808) (xy 345.766345 -259.085334) (xy 345.720071 -259.108912)
			(xy 345.670678 -259.12496) (xy 345.619383 -259.133085) (xy 345.567449 -259.133085) (xy 345.516154 -259.12496)
			(xy 345.466761 -259.108912) (xy 345.420487 -259.085334) (xy 345.378471 -259.054808) (xy 345.341748 -259.018085)
			(xy 345.311222 -258.976069) (xy 345.287644 -258.929795) (xy 345.271596 -258.880402) (xy 345.263471 -258.829107)
			(xy 344.983561 -258.829107) (xy 344.975436 -258.880402) (xy 344.959388 -258.929795) (xy 344.93581 -258.976069)
			(xy 344.905284 -259.018085) (xy 344.868561 -259.054808) (xy 344.826545 -259.085334) (xy 344.780271 -259.108912)
			(xy 344.730878 -259.12496) (xy 344.679583 -259.133085) (xy 344.627649 -259.133085) (xy 344.576354 -259.12496)
			(xy 344.526961 -259.108912) (xy 344.480687 -259.085334) (xy 344.438671 -259.054808) (xy 344.401948 -259.018085)
			(xy 344.371422 -258.976069) (xy 344.347844 -258.929795) (xy 344.331796 -258.880402) (xy 344.323671 -258.829107)
			(xy 344.043761 -258.829107) (xy 344.035636 -258.880402) (xy 344.019588 -258.929795) (xy 343.99601 -258.976069)
			(xy 343.965484 -259.018085) (xy 343.928761 -259.054808) (xy 343.886745 -259.085334) (xy 343.840471 -259.108912)
			(xy 343.791078 -259.12496) (xy 343.739783 -259.133085) (xy 343.687849 -259.133085) (xy 343.636554 -259.12496)
			(xy 343.587161 -259.108912) (xy 343.540887 -259.085334) (xy 343.498871 -259.054808) (xy 343.462148 -259.018085)
			(xy 343.431622 -258.976069) (xy 343.408044 -258.929795) (xy 343.391996 -258.880402) (xy 343.383871 -258.829107)
			(xy 343.103707 -258.829107) (xy 343.095582 -258.880402) (xy 343.079534 -258.929795) (xy 343.055956 -258.976069)
			(xy 343.02543 -259.018085) (xy 342.988707 -259.054808) (xy 342.946691 -259.085334) (xy 342.900417 -259.108912)
			(xy 342.851024 -259.12496) (xy 342.799729 -259.133085) (xy 342.747795 -259.133085) (xy 342.6965 -259.12496)
			(xy 342.647107 -259.108912) (xy 342.600833 -259.085334) (xy 342.558817 -259.054808) (xy 342.522094 -259.018085)
			(xy 342.491568 -258.976069) (xy 342.46799 -258.929795) (xy 342.451942 -258.880402) (xy 342.443817 -258.829107)
			(xy 342.164161 -258.829107) (xy 342.156036 -258.880402) (xy 342.139988 -258.929795) (xy 342.11641 -258.976069)
			(xy 342.085884 -259.018085) (xy 342.049161 -259.054808) (xy 342.007145 -259.085334) (xy 341.960871 -259.108912)
			(xy 341.911478 -259.12496) (xy 341.860183 -259.133085) (xy 341.808249 -259.133085) (xy 341.756954 -259.12496)
			(xy 341.707561 -259.108912) (xy 341.661287 -259.085334) (xy 341.619271 -259.054808) (xy 341.582548 -259.018085)
			(xy 341.552022 -258.976069) (xy 341.528444 -258.929795) (xy 341.512396 -258.880402) (xy 341.504271 -258.829107)
			(xy 341.224361 -258.829107) (xy 341.216236 -258.880402) (xy 341.200188 -258.929795) (xy 341.17661 -258.976069)
			(xy 341.146084 -259.018085) (xy 341.109361 -259.054808) (xy 341.067345 -259.085334) (xy 341.021071 -259.108912)
			(xy 340.971678 -259.12496) (xy 340.920383 -259.133085) (xy 340.868449 -259.133085) (xy 340.817154 -259.12496)
			(xy 340.767761 -259.108912) (xy 340.721487 -259.085334) (xy 340.679471 -259.054808) (xy 340.642748 -259.018085)
			(xy 340.612222 -258.976069) (xy 340.588644 -258.929795) (xy 340.572596 -258.880402) (xy 340.564471 -258.829107)
			(xy 340.284754 -258.829107) (xy 340.276629 -258.88041) (xy 340.260571 -258.929833) (xy 340.236979 -258.976136)
			(xy 340.206435 -259.018178) (xy 340.16969 -259.054925) (xy 340.127649 -259.085471) (xy 340.081348 -259.109065)
			(xy 340.031925 -259.125125) (xy 339.980599 -259.133257) (xy 339.954616 -259.133848) (xy 339.931701 -259.133457)
			(xy 339.886312 -259.127122) (xy 339.842234 -259.114573) (xy 339.800315 -259.096048) (xy 339.780626 -259.084318)
			(xy 339.780372 -259.084318) (xy 339.772614 -259.079924) (xy 339.755157 -259.076356) (xy 339.737544 -259.079053)
			(xy 339.729572 -259.083048) (xy 339.691218 -259.104638) (xy 339.65134 -259.12699) (xy 339.644245 -259.131748)
			(xy 339.633514 -259.145026) (xy 339.627833 -259.161125) (xy 339.627464 -259.169662) (xy 339.627464 -259.288788)
			(xy 339.651848 -259.331206) (xy 339.662516 -259.338064) (xy 339.683798 -259.352194) (xy 339.722139 -259.385948)
			(xy 339.754836 -259.425195) (xy 339.78111 -259.469002) (xy 339.800338 -259.516328) (xy 339.812062 -259.566046)
			(xy 339.816004 -259.616976) (xy 339.814 -259.642923) (xy 340.094317 -259.642923) (xy 340.094317 -259.590989)
			(xy 340.102442 -259.539694) (xy 340.11849 -259.490301) (xy 340.142068 -259.444027) (xy 340.172594 -259.402011)
			(xy 340.209317 -259.365288) (xy 340.251333 -259.334762) (xy 340.297607 -259.311184) (xy 340.347 -259.295136)
			(xy 340.398295 -259.287011) (xy 340.450229 -259.287011) (xy 340.501524 -259.295136) (xy 340.550917 -259.311184)
			(xy 340.597191 -259.334762) (xy 340.639207 -259.365288) (xy 340.67593 -259.402011) (xy 340.706456 -259.444027)
			(xy 340.730034 -259.490301) (xy 340.746082 -259.539694) (xy 340.754207 -259.590989) (xy 340.754716 -259.616956)
			(xy 340.754207 -259.642923) (xy 341.034117 -259.642923) (xy 341.034117 -259.590989) (xy 341.042242 -259.539694)
			(xy 341.05829 -259.490301) (xy 341.081868 -259.444027) (xy 341.112394 -259.402011) (xy 341.149117 -259.365288)
			(xy 341.191133 -259.334762) (xy 341.237407 -259.311184) (xy 341.2868 -259.295136) (xy 341.338095 -259.287011)
			(xy 341.390029 -259.287011) (xy 341.441324 -259.295136) (xy 341.490717 -259.311184) (xy 341.536991 -259.334762)
			(xy 341.579007 -259.365288) (xy 341.61573 -259.402011) (xy 341.646256 -259.444027) (xy 341.669834 -259.490301)
			(xy 341.685882 -259.539694) (xy 341.694007 -259.590989) (xy 341.694516 -259.616956) (xy 341.694007 -259.642923)
			(xy 341.973917 -259.642923) (xy 341.973917 -259.590989) (xy 341.982042 -259.539694) (xy 341.99809 -259.490301)
			(xy 342.021668 -259.444027) (xy 342.052194 -259.402011) (xy 342.088917 -259.365288) (xy 342.130933 -259.334762)
			(xy 342.177207 -259.311184) (xy 342.2266 -259.295136) (xy 342.277895 -259.287011) (xy 342.329829 -259.287011)
			(xy 342.381124 -259.295136) (xy 342.430517 -259.311184) (xy 342.476791 -259.334762) (xy 342.518807 -259.365288)
			(xy 342.55553 -259.402011) (xy 342.586056 -259.444027) (xy 342.609634 -259.490301) (xy 342.625682 -259.539694)
			(xy 342.633807 -259.590989) (xy 342.634316 -259.616956) (xy 342.633807 -259.642923) (xy 342.913717 -259.642923)
			(xy 342.913717 -259.590989) (xy 342.921842 -259.539694) (xy 342.93789 -259.490301) (xy 342.961468 -259.444027)
			(xy 342.991994 -259.402011) (xy 343.028717 -259.365288) (xy 343.070733 -259.334762) (xy 343.117007 -259.311184)
			(xy 343.1664 -259.295136) (xy 343.217695 -259.287011) (xy 343.269629 -259.287011) (xy 343.320924 -259.295136)
			(xy 343.370317 -259.311184) (xy 343.416591 -259.334762) (xy 343.458607 -259.365288) (xy 343.49533 -259.402011)
			(xy 343.525856 -259.444027) (xy 343.549434 -259.490301) (xy 343.565482 -259.539694) (xy 343.573607 -259.590989)
			(xy 343.574116 -259.616956) (xy 343.573607 -259.642923) (xy 343.853517 -259.642923) (xy 343.853517 -259.590989)
			(xy 343.861642 -259.539694) (xy 343.87769 -259.490301) (xy 343.901268 -259.444027) (xy 343.931794 -259.402011)
			(xy 343.968517 -259.365288) (xy 344.010533 -259.334762) (xy 344.056807 -259.311184) (xy 344.1062 -259.295136)
			(xy 344.157495 -259.287011) (xy 344.209429 -259.287011) (xy 344.260724 -259.295136) (xy 344.310117 -259.311184)
			(xy 344.356391 -259.334762) (xy 344.398407 -259.365288) (xy 344.43513 -259.402011) (xy 344.465656 -259.444027)
			(xy 344.489234 -259.490301) (xy 344.505282 -259.539694) (xy 344.513407 -259.590989) (xy 344.513916 -259.616956)
			(xy 344.513407 -259.642923) (xy 344.793317 -259.642923) (xy 344.793317 -259.590989) (xy 344.801442 -259.539694)
			(xy 344.81749 -259.490301) (xy 344.841068 -259.444027) (xy 344.871594 -259.402011) (xy 344.908317 -259.365288)
			(xy 344.950333 -259.334762) (xy 344.996607 -259.311184) (xy 345.046 -259.295136) (xy 345.097295 -259.287011)
			(xy 345.149229 -259.287011) (xy 345.200524 -259.295136) (xy 345.249917 -259.311184) (xy 345.296191 -259.334762)
			(xy 345.338207 -259.365288) (xy 345.37493 -259.402011) (xy 345.405456 -259.444027) (xy 345.429034 -259.490301)
			(xy 345.445082 -259.539694) (xy 345.453207 -259.590989) (xy 345.453716 -259.616956) (xy 345.453207 -259.642923)
			(xy 345.733371 -259.642923) (xy 345.733371 -259.590989) (xy 345.741496 -259.539694) (xy 345.757544 -259.490301)
			(xy 345.781122 -259.444027) (xy 345.811648 -259.402011) (xy 345.848371 -259.365288) (xy 345.890387 -259.334762)
			(xy 345.936661 -259.311184) (xy 345.986054 -259.295136) (xy 346.037349 -259.287011) (xy 346.089283 -259.287011)
			(xy 346.140578 -259.295136) (xy 346.189971 -259.311184) (xy 346.236245 -259.334762) (xy 346.278261 -259.365288)
			(xy 346.314984 -259.402011) (xy 346.34551 -259.444027) (xy 346.369088 -259.490301) (xy 346.385136 -259.539694)
			(xy 346.393261 -259.590989) (xy 346.39377 -259.616956) (xy 346.393261 -259.642923) (xy 346.672917 -259.642923)
			(xy 346.672917 -259.590989) (xy 346.681042 -259.539694) (xy 346.69709 -259.490301) (xy 346.720668 -259.444027)
			(xy 346.751194 -259.402011) (xy 346.787917 -259.365288) (xy 346.829933 -259.334762) (xy 346.876207 -259.311184)
			(xy 346.9256 -259.295136) (xy 346.976895 -259.287011) (xy 347.028829 -259.287011) (xy 347.080124 -259.295136)
			(xy 347.129517 -259.311184) (xy 347.175791 -259.334762) (xy 347.217807 -259.365288) (xy 347.25453 -259.402011)
			(xy 347.285056 -259.444027) (xy 347.308634 -259.490301) (xy 347.324682 -259.539694) (xy 347.332807 -259.590989)
			(xy 347.333316 -259.616956) (xy 347.332807 -259.642923) (xy 347.612717 -259.642923) (xy 347.612717 -259.590989)
			(xy 347.620842 -259.539694) (xy 347.63689 -259.490301) (xy 347.660468 -259.444027) (xy 347.690994 -259.402011)
			(xy 347.727717 -259.365288) (xy 347.769733 -259.334762) (xy 347.816007 -259.311184) (xy 347.8654 -259.295136)
			(xy 347.916695 -259.287011) (xy 347.968629 -259.287011) (xy 348.019924 -259.295136) (xy 348.069317 -259.311184)
			(xy 348.115591 -259.334762) (xy 348.157607 -259.365288) (xy 348.19433 -259.402011) (xy 348.224856 -259.444027)
			(xy 348.248434 -259.490301) (xy 348.264482 -259.539694) (xy 348.272607 -259.590989) (xy 348.273116 -259.616956)
			(xy 348.272607 -259.642923) (xy 348.552517 -259.642923) (xy 348.552517 -259.590989) (xy 348.560642 -259.539694)
			(xy 348.57669 -259.490301) (xy 348.600268 -259.444027) (xy 348.630794 -259.402011) (xy 348.667517 -259.365288)
			(xy 348.709533 -259.334762) (xy 348.755807 -259.311184) (xy 348.8052 -259.295136) (xy 348.856495 -259.287011)
			(xy 348.908429 -259.287011) (xy 348.959724 -259.295136) (xy 349.009117 -259.311184) (xy 349.055391 -259.334762)
			(xy 349.097407 -259.365288) (xy 349.13413 -259.402011) (xy 349.164656 -259.444027) (xy 349.188234 -259.490301)
			(xy 349.204282 -259.539694) (xy 349.212407 -259.590989) (xy 349.212916 -259.616956) (xy 349.212407 -259.642923)
			(xy 349.492317 -259.642923) (xy 349.492317 -259.590989) (xy 349.500442 -259.539694) (xy 349.51649 -259.490301)
			(xy 349.540068 -259.444027) (xy 349.570594 -259.402011) (xy 349.607317 -259.365288) (xy 349.649333 -259.334762)
			(xy 349.695607 -259.311184) (xy 349.745 -259.295136) (xy 349.796295 -259.287011) (xy 349.848229 -259.287011)
			(xy 349.899524 -259.295136) (xy 349.948917 -259.311184) (xy 349.995191 -259.334762) (xy 350.037207 -259.365288)
			(xy 350.07393 -259.402011) (xy 350.104456 -259.444027) (xy 350.128034 -259.490301) (xy 350.144082 -259.539694)
			(xy 350.152207 -259.590989) (xy 350.152716 -259.616956) (xy 350.152207 -259.642923) (xy 350.144082 -259.694218)
			(xy 350.134917 -259.722425) (xy 350.476567 -259.722425) (xy 350.476567 -259.670491) (xy 350.484692 -259.619196)
			(xy 350.50074 -259.569803) (xy 350.524318 -259.523529) (xy 350.554844 -259.481513) (xy 350.591567 -259.44479)
			(xy 350.633583 -259.414264) (xy 350.679857 -259.390686) (xy 350.72925 -259.374638) (xy 350.780545 -259.366513)
			(xy 350.832479 -259.366513) (xy 350.883774 -259.374638) (xy 350.933167 -259.390686) (xy 350.979441 -259.414264)
			(xy 351.021457 -259.44479) (xy 351.05818 -259.481513) (xy 351.088706 -259.523529) (xy 351.112284 -259.569803)
			(xy 351.11506 -259.578348) (xy 356.04323 -259.578348) (xy 356.04323 -259.578094) (xy 356.043696 -259.553568)
			(xy 356.050958 -259.505057) (xy 356.065308 -259.45815) (xy 356.086429 -259.413879) (xy 356.113859 -259.373213)
			(xy 356.130098 -259.354828) (xy 356.139853 -259.343301) (xy 356.152869 -259.316077) (xy 356.157345 -259.286236)
			(xy 356.15289 -259.256391) (xy 356.139893 -259.229158) (xy 356.130098 -259.217668) (xy 356.113865 -259.199276)
			(xy 356.086418 -259.158619) (xy 356.065286 -259.114351) (xy 356.050934 -259.067443) (xy 356.043678 -259.018929)
			(xy 356.04323 -258.994402) (xy 356.04323 -258.994148) (xy 356.043739 -258.968181) (xy 356.051864 -258.916886)
			(xy 356.067912 -258.867493) (xy 356.09149 -258.821219) (xy 356.122016 -258.779203) (xy 356.158739 -258.74248)
			(xy 356.200755 -258.711954) (xy 356.247029 -258.688376) (xy 356.296422 -258.672328) (xy 356.347717 -258.664203)
			(xy 356.399651 -258.664203) (xy 356.450946 -258.672328) (xy 356.500339 -258.688376) (xy 356.546613 -258.711954)
			(xy 356.588629 -258.74248) (xy 356.625352 -258.779203) (xy 356.655878 -258.821219) (xy 356.659897 -258.829107)
			(xy 357.480617 -258.829107) (xy 357.480617 -258.777173) (xy 357.488742 -258.725878) (xy 357.50479 -258.676485)
			(xy 357.528368 -258.630211) (xy 357.558894 -258.588195) (xy 357.595617 -258.551472) (xy 357.637633 -258.520946)
			(xy 357.683907 -258.497368) (xy 357.7333 -258.48132) (xy 357.784595 -258.473195) (xy 357.836529 -258.473195)
			(xy 357.887824 -258.48132) (xy 357.937217 -258.497368) (xy 357.983491 -258.520946) (xy 358.025507 -258.551472)
			(xy 358.06223 -258.588195) (xy 358.092756 -258.630211) (xy 358.116334 -258.676485) (xy 358.132382 -258.725878)
			(xy 358.140507 -258.777173) (xy 358.141016 -258.80314) (xy 358.140507 -258.829107) (xy 358.420671 -258.829107)
			(xy 358.420671 -258.777173) (xy 358.428796 -258.725878) (xy 358.444844 -258.676485) (xy 358.468422 -258.630211)
			(xy 358.498948 -258.588195) (xy 358.535671 -258.551472) (xy 358.577687 -258.520946) (xy 358.623961 -258.497368)
			(xy 358.673354 -258.48132) (xy 358.724649 -258.473195) (xy 358.776583 -258.473195) (xy 358.827878 -258.48132)
			(xy 358.877271 -258.497368) (xy 358.923545 -258.520946) (xy 358.965561 -258.551472) (xy 359.002284 -258.588195)
			(xy 359.03281 -258.630211) (xy 359.056388 -258.676485) (xy 359.072436 -258.725878) (xy 359.080561 -258.777173)
			(xy 359.08107 -258.80314) (xy 359.080561 -258.829107) (xy 359.360217 -258.829107) (xy 359.360217 -258.777173)
			(xy 359.368342 -258.725878) (xy 359.38439 -258.676485) (xy 359.407968 -258.630211) (xy 359.438494 -258.588195)
			(xy 359.475217 -258.551472) (xy 359.517233 -258.520946) (xy 359.563507 -258.497368) (xy 359.6129 -258.48132)
			(xy 359.664195 -258.473195) (xy 359.716129 -258.473195) (xy 359.767424 -258.48132) (xy 359.816817 -258.497368)
			(xy 359.863091 -258.520946) (xy 359.905107 -258.551472) (xy 359.94183 -258.588195) (xy 359.972356 -258.630211)
			(xy 359.995934 -258.676485) (xy 360.011982 -258.725878) (xy 360.020107 -258.777173) (xy 360.020616 -258.80314)
			(xy 360.020107 -258.829107) (xy 360.300017 -258.829107) (xy 360.300017 -258.777173) (xy 360.308142 -258.725878)
			(xy 360.32419 -258.676485) (xy 360.347768 -258.630211) (xy 360.378294 -258.588195) (xy 360.415017 -258.551472)
			(xy 360.457033 -258.520946) (xy 360.503307 -258.497368) (xy 360.5527 -258.48132) (xy 360.603995 -258.473195)
			(xy 360.655929 -258.473195) (xy 360.707224 -258.48132) (xy 360.756617 -258.497368) (xy 360.802891 -258.520946)
			(xy 360.844907 -258.551472) (xy 360.88163 -258.588195) (xy 360.912156 -258.630211) (xy 360.935734 -258.676485)
			(xy 360.951782 -258.725878) (xy 360.959907 -258.777173) (xy 360.960416 -258.80314) (xy 360.959907 -258.829107)
			(xy 361.239817 -258.829107) (xy 361.239817 -258.777173) (xy 361.247942 -258.725878) (xy 361.26399 -258.676485)
			(xy 361.287568 -258.630211) (xy 361.318094 -258.588195) (xy 361.354817 -258.551472) (xy 361.396833 -258.520946)
			(xy 361.443107 -258.497368) (xy 361.4925 -258.48132) (xy 361.543795 -258.473195) (xy 361.595729 -258.473195)
			(xy 361.647024 -258.48132) (xy 361.696417 -258.497368) (xy 361.742691 -258.520946) (xy 361.784707 -258.551472)
			(xy 361.82143 -258.588195) (xy 361.851956 -258.630211) (xy 361.875534 -258.676485) (xy 361.891582 -258.725878)
			(xy 361.899707 -258.777173) (xy 361.900216 -258.80314) (xy 361.899707 -258.829107) (xy 362.179617 -258.829107)
			(xy 362.179617 -258.777173) (xy 362.187742 -258.725878) (xy 362.20379 -258.676485) (xy 362.227368 -258.630211)
			(xy 362.257894 -258.588195) (xy 362.294617 -258.551472) (xy 362.336633 -258.520946) (xy 362.382907 -258.497368)
			(xy 362.4323 -258.48132) (xy 362.483595 -258.473195) (xy 362.535529 -258.473195) (xy 362.561552 -258.477317)
			(xy 368.586259 -258.477317) (xy 368.586259 -258.425383) (xy 368.594384 -258.374088) (xy 368.610432 -258.324695)
			(xy 368.63401 -258.278421) (xy 368.664536 -258.236405) (xy 368.701259 -258.199682) (xy 368.743275 -258.169156)
			(xy 368.789549 -258.145578) (xy 368.838942 -258.12953) (xy 368.890237 -258.121405) (xy 368.942171 -258.121405)
			(xy 368.993466 -258.12953) (xy 369.042859 -258.145578) (xy 369.089133 -258.169156) (xy 369.131149 -258.199682)
			(xy 369.167872 -258.236405) (xy 369.198398 -258.278421) (xy 369.221976 -258.324695) (xy 369.238024 -258.374088)
			(xy 369.246149 -258.425383) (xy 369.246658 -258.45135) (xy 369.246149 -258.477317) (xy 369.238024 -258.528612)
			(xy 369.221976 -258.578005) (xy 369.198398 -258.624279) (xy 369.167872 -258.666295) (xy 369.131149 -258.703018)
			(xy 369.089133 -258.733544) (xy 369.042859 -258.757122) (xy 368.993466 -258.77317) (xy 368.942171 -258.781295)
			(xy 368.890237 -258.781295) (xy 368.838942 -258.77317) (xy 368.789549 -258.757122) (xy 368.743275 -258.733544)
			(xy 368.701259 -258.703018) (xy 368.664536 -258.666295) (xy 368.63401 -258.624279) (xy 368.610432 -258.578005)
			(xy 368.594384 -258.528612) (xy 368.586259 -258.477317) (xy 362.561552 -258.477317) (xy 362.586824 -258.48132)
			(xy 362.636217 -258.497368) (xy 362.682491 -258.520946) (xy 362.724507 -258.551472) (xy 362.76123 -258.588195)
			(xy 362.791756 -258.630211) (xy 362.815334 -258.676485) (xy 362.831382 -258.725878) (xy 362.839507 -258.777173)
			(xy 362.840016 -258.80314) (xy 362.839507 -258.829107) (xy 362.831382 -258.880402) (xy 362.815334 -258.929795)
			(xy 362.791756 -258.976069) (xy 362.76123 -259.018085) (xy 362.724507 -259.054808) (xy 362.682491 -259.085334)
			(xy 362.636217 -259.108912) (xy 362.586824 -259.12496) (xy 362.535529 -259.133085) (xy 362.483595 -259.133085)
			(xy 362.4323 -259.12496) (xy 362.382907 -259.108912) (xy 362.336633 -259.085334) (xy 362.294617 -259.054808)
			(xy 362.257894 -259.018085) (xy 362.227368 -258.976069) (xy 362.20379 -258.929795) (xy 362.187742 -258.880402)
			(xy 362.179617 -258.829107) (xy 361.899707 -258.829107) (xy 361.891582 -258.880402) (xy 361.875534 -258.929795)
			(xy 361.851956 -258.976069) (xy 361.82143 -259.018085) (xy 361.784707 -259.054808) (xy 361.742691 -259.085334)
			(xy 361.696417 -259.108912) (xy 361.647024 -259.12496) (xy 361.595729 -259.133085) (xy 361.543795 -259.133085)
			(xy 361.4925 -259.12496) (xy 361.443107 -259.108912) (xy 361.396833 -259.085334) (xy 361.354817 -259.054808)
			(xy 361.318094 -259.018085) (xy 361.287568 -258.976069) (xy 361.26399 -258.929795) (xy 361.247942 -258.880402)
			(xy 361.239817 -258.829107) (xy 360.959907 -258.829107) (xy 360.951782 -258.880402) (xy 360.935734 -258.929795)
			(xy 360.912156 -258.976069) (xy 360.88163 -259.018085) (xy 360.844907 -259.054808) (xy 360.802891 -259.085334)
			(xy 360.756617 -259.108912) (xy 360.707224 -259.12496) (xy 360.655929 -259.133085) (xy 360.603995 -259.133085)
			(xy 360.5527 -259.12496) (xy 360.503307 -259.108912) (xy 360.457033 -259.085334) (xy 360.415017 -259.054808)
			(xy 360.378294 -259.018085) (xy 360.347768 -258.976069) (xy 360.32419 -258.929795) (xy 360.308142 -258.880402)
			(xy 360.300017 -258.829107) (xy 360.020107 -258.829107) (xy 360.011982 -258.880402) (xy 359.995934 -258.929795)
			(xy 359.972356 -258.976069) (xy 359.94183 -259.018085) (xy 359.905107 -259.054808) (xy 359.863091 -259.085334)
			(xy 359.816817 -259.108912) (xy 359.767424 -259.12496) (xy 359.716129 -259.133085) (xy 359.664195 -259.133085)
			(xy 359.6129 -259.12496) (xy 359.563507 -259.108912) (xy 359.517233 -259.085334) (xy 359.475217 -259.054808)
			(xy 359.438494 -259.018085) (xy 359.407968 -258.976069) (xy 359.38439 -258.929795) (xy 359.368342 -258.880402)
			(xy 359.360217 -258.829107) (xy 359.080561 -258.829107) (xy 359.072436 -258.880402) (xy 359.056388 -258.929795)
			(xy 359.03281 -258.976069) (xy 359.002284 -259.018085) (xy 358.965561 -259.054808) (xy 358.923545 -259.085334)
			(xy 358.877271 -259.108912) (xy 358.827878 -259.12496) (xy 358.776583 -259.133085) (xy 358.724649 -259.133085)
			(xy 358.673354 -259.12496) (xy 358.623961 -259.108912) (xy 358.577687 -259.085334) (xy 358.535671 -259.054808)
			(xy 358.498948 -259.018085) (xy 358.468422 -258.976069) (xy 358.444844 -258.929795) (xy 358.428796 -258.880402)
			(xy 358.420671 -258.829107) (xy 358.140507 -258.829107) (xy 358.132382 -258.880402) (xy 358.116334 -258.929795)
			(xy 358.092756 -258.976069) (xy 358.06223 -259.018085) (xy 358.025507 -259.054808) (xy 357.983491 -259.085334)
			(xy 357.937217 -259.108912) (xy 357.887824 -259.12496) (xy 357.836529 -259.133085) (xy 357.784595 -259.133085)
			(xy 357.7333 -259.12496) (xy 357.683907 -259.108912) (xy 357.637633 -259.085334) (xy 357.595617 -259.054808)
			(xy 357.558894 -259.018085) (xy 357.528368 -258.976069) (xy 357.50479 -258.929795) (xy 357.488742 -258.880402)
			(xy 357.480617 -258.829107) (xy 356.659897 -258.829107) (xy 356.679456 -258.867493) (xy 356.695504 -258.916886)
			(xy 356.703629 -258.968181) (xy 356.704138 -258.994148) (xy 356.704138 -258.994402) (xy 356.703678 -259.018928)
			(xy 356.696415 -259.06744) (xy 356.682065 -259.114347) (xy 356.660942 -259.158619) (xy 356.633511 -259.199284)
			(xy 356.61727 -259.217668) (xy 356.607416 -259.229119) (xy 356.594402 -259.256369) (xy 356.58994 -259.286236)
			(xy 356.594422 -259.316099) (xy 356.607456 -259.34334) (xy 356.61727 -259.354828) (xy 356.633496 -259.373227)
			(xy 356.660945 -259.41388) (xy 356.682079 -259.458148) (xy 356.696433 -259.505054) (xy 356.70369 -259.553567)
			(xy 356.704138 -259.578094) (xy 356.704138 -259.578348) (xy 356.703629 -259.604315) (xy 356.697514 -259.642923)
			(xy 357.010717 -259.642923) (xy 357.010717 -259.590989) (xy 357.018842 -259.539694) (xy 357.03489 -259.490301)
			(xy 357.058468 -259.444027) (xy 357.088994 -259.402011) (xy 357.125717 -259.365288) (xy 357.167733 -259.334762)
			(xy 357.214007 -259.311184) (xy 357.2634 -259.295136) (xy 357.314695 -259.287011) (xy 357.366629 -259.287011)
			(xy 357.417924 -259.295136) (xy 357.467317 -259.311184) (xy 357.513591 -259.334762) (xy 357.555607 -259.365288)
			(xy 357.59233 -259.402011) (xy 357.622856 -259.444027) (xy 357.646434 -259.490301) (xy 357.662482 -259.539694)
			(xy 357.670607 -259.590989) (xy 357.671116 -259.616956) (xy 357.670607 -259.642923) (xy 357.950517 -259.642923)
			(xy 357.950517 -259.590989) (xy 357.958642 -259.539694) (xy 357.97469 -259.490301) (xy 357.998268 -259.444027)
			(xy 358.028794 -259.402011) (xy 358.065517 -259.365288) (xy 358.107533 -259.334762) (xy 358.153807 -259.311184)
			(xy 358.2032 -259.295136) (xy 358.254495 -259.287011) (xy 358.306429 -259.287011) (xy 358.357724 -259.295136)
			(xy 358.407117 -259.311184) (xy 358.453391 -259.334762) (xy 358.495407 -259.365288) (xy 358.53213 -259.402011)
			(xy 358.562656 -259.444027) (xy 358.586234 -259.490301) (xy 358.602282 -259.539694) (xy 358.610407 -259.590989)
			(xy 358.610916 -259.616956) (xy 358.610407 -259.642923) (xy 358.890571 -259.642923) (xy 358.890571 -259.590989)
			(xy 358.898696 -259.539694) (xy 358.914744 -259.490301) (xy 358.938322 -259.444027) (xy 358.968848 -259.402011)
			(xy 359.005571 -259.365288) (xy 359.047587 -259.334762) (xy 359.093861 -259.311184) (xy 359.143254 -259.295136)
			(xy 359.194549 -259.287011) (xy 359.246483 -259.287011) (xy 359.297778 -259.295136) (xy 359.347171 -259.311184)
			(xy 359.393445 -259.334762) (xy 359.435461 -259.365288) (xy 359.472184 -259.402011) (xy 359.50271 -259.444027)
			(xy 359.526288 -259.490301) (xy 359.542336 -259.539694) (xy 359.550461 -259.590989) (xy 359.55097 -259.616956)
			(xy 359.550461 -259.642923) (xy 359.830371 -259.642923) (xy 359.830371 -259.590989) (xy 359.838496 -259.539694)
			(xy 359.854544 -259.490301) (xy 359.878122 -259.444027) (xy 359.908648 -259.402011) (xy 359.945371 -259.365288)
			(xy 359.987387 -259.334762) (xy 360.033661 -259.311184) (xy 360.083054 -259.295136) (xy 360.134349 -259.287011)
			(xy 360.186283 -259.287011) (xy 360.237578 -259.295136) (xy 360.286971 -259.311184) (xy 360.333245 -259.334762)
			(xy 360.375261 -259.365288) (xy 360.411984 -259.402011) (xy 360.44251 -259.444027) (xy 360.466088 -259.490301)
			(xy 360.482136 -259.539694) (xy 360.490261 -259.590989) (xy 360.49077 -259.616956) (xy 360.490261 -259.642923)
			(xy 360.769917 -259.642923) (xy 360.769917 -259.590989) (xy 360.778042 -259.539694) (xy 360.79409 -259.490301)
			(xy 360.817668 -259.444027) (xy 360.848194 -259.402011) (xy 360.884917 -259.365288) (xy 360.926933 -259.334762)
			(xy 360.973207 -259.311184) (xy 361.0226 -259.295136) (xy 361.073895 -259.287011) (xy 361.125829 -259.287011)
			(xy 361.177124 -259.295136) (xy 361.226517 -259.311184) (xy 361.272791 -259.334762) (xy 361.314807 -259.365288)
			(xy 361.35153 -259.402011) (xy 361.382056 -259.444027) (xy 361.405634 -259.490301) (xy 361.421682 -259.539694)
			(xy 361.429807 -259.590989) (xy 361.430316 -259.616956) (xy 361.429807 -259.642923) (xy 361.709971 -259.642923)
			(xy 361.709971 -259.590989) (xy 361.718096 -259.539694) (xy 361.734144 -259.490301) (xy 361.757722 -259.444027)
			(xy 361.788248 -259.402011) (xy 361.824971 -259.365288) (xy 361.866987 -259.334762) (xy 361.913261 -259.311184)
			(xy 361.962654 -259.295136) (xy 362.013949 -259.287011) (xy 362.065883 -259.287011) (xy 362.117178 -259.295136)
			(xy 362.166571 -259.311184) (xy 362.212845 -259.334762) (xy 362.254861 -259.365288) (xy 362.291584 -259.402011)
			(xy 362.32211 -259.444027) (xy 362.345688 -259.490301) (xy 362.361736 -259.539694) (xy 362.369861 -259.590989)
			(xy 362.37037 -259.616956) (xy 362.370017 -259.63499) (xy 363.035596 -259.63499) (xy 363.035596 -259.634736)
			(xy 363.03607 -259.61021) (xy 363.043328 -259.561698) (xy 363.057674 -259.514792) (xy 363.078794 -259.47052)
			(xy 363.106224 -259.429854) (xy 363.122464 -259.41147) (xy 363.132278 -259.399989) (xy 363.145292 -259.372749)
			(xy 363.149759 -259.342893) (xy 363.145288 -259.313037) (xy 363.13227 -259.285799) (xy 363.122464 -259.27431)
			(xy 363.106214 -259.255931) (xy 363.078767 -259.215273) (xy 363.057637 -259.171001) (xy 363.043289 -259.12409)
			(xy 363.03604 -259.075572) (xy 363.035596 -259.051044) (xy 363.035596 -259.05079) (xy 363.036105 -259.024823)
			(xy 363.04423 -258.973528) (xy 363.060278 -258.924135) (xy 363.083856 -258.877861) (xy 363.114382 -258.835845)
			(xy 363.151105 -258.799122) (xy 363.193121 -258.768596) (xy 363.239395 -258.745018) (xy 363.288788 -258.72897)
			(xy 363.340083 -258.720845) (xy 363.392017 -258.720845) (xy 363.443312 -258.72897) (xy 363.492705 -258.745018)
			(xy 363.538979 -258.768596) (xy 363.580995 -258.799122) (xy 363.61098 -258.829107) (xy 369.698017 -258.829107)
			(xy 369.698017 -258.777173) (xy 369.706142 -258.725878) (xy 369.72219 -258.676485) (xy 369.745768 -258.630211)
			(xy 369.776294 -258.588195) (xy 369.813017 -258.551472) (xy 369.855033 -258.520946) (xy 369.901307 -258.497368)
			(xy 369.9507 -258.48132) (xy 370.001995 -258.473195) (xy 370.053929 -258.473195) (xy 370.105224 -258.48132)
			(xy 370.154617 -258.497368) (xy 370.200891 -258.520946) (xy 370.242907 -258.551472) (xy 370.27963 -258.588195)
			(xy 370.310156 -258.630211) (xy 370.333734 -258.676485) (xy 370.349782 -258.725878) (xy 370.357907 -258.777173)
			(xy 370.358416 -258.80314) (xy 370.357907 -258.829107) (xy 370.637817 -258.829107) (xy 370.637817 -258.777173)
			(xy 370.645942 -258.725878) (xy 370.66199 -258.676485) (xy 370.685568 -258.630211) (xy 370.716094 -258.588195)
			(xy 370.752817 -258.551472) (xy 370.794833 -258.520946) (xy 370.841107 -258.497368) (xy 370.8905 -258.48132)
			(xy 370.941795 -258.473195) (xy 370.993729 -258.473195) (xy 371.045024 -258.48132) (xy 371.094417 -258.497368)
			(xy 371.140691 -258.520946) (xy 371.182707 -258.551472) (xy 371.21943 -258.588195) (xy 371.249956 -258.630211)
			(xy 371.273534 -258.676485) (xy 371.289582 -258.725878) (xy 371.297707 -258.777173) (xy 371.298216 -258.80314)
			(xy 371.297707 -258.829107) (xy 371.577871 -258.829107) (xy 371.577871 -258.777173) (xy 371.585996 -258.725878)
			(xy 371.602044 -258.676485) (xy 371.625622 -258.630211) (xy 371.656148 -258.588195) (xy 371.692871 -258.551472)
			(xy 371.734887 -258.520946) (xy 371.781161 -258.497368) (xy 371.830554 -258.48132) (xy 371.881849 -258.473195)
			(xy 371.933783 -258.473195) (xy 371.985078 -258.48132) (xy 372.034471 -258.497368) (xy 372.080745 -258.520946)
			(xy 372.122761 -258.551472) (xy 372.159484 -258.588195) (xy 372.19001 -258.630211) (xy 372.213588 -258.676485)
			(xy 372.229636 -258.725878) (xy 372.237761 -258.777173) (xy 372.23827 -258.80314) (xy 372.237761 -258.829107)
			(xy 372.517671 -258.829107) (xy 372.517671 -258.777173) (xy 372.525796 -258.725878) (xy 372.541844 -258.676485)
			(xy 372.565422 -258.630211) (xy 372.595948 -258.588195) (xy 372.632671 -258.551472) (xy 372.674687 -258.520946)
			(xy 372.720961 -258.497368) (xy 372.770354 -258.48132) (xy 372.821649 -258.473195) (xy 372.873583 -258.473195)
			(xy 372.924878 -258.48132) (xy 372.974271 -258.497368) (xy 373.020545 -258.520946) (xy 373.062561 -258.551472)
			(xy 373.099284 -258.588195) (xy 373.12981 -258.630211) (xy 373.153388 -258.676485) (xy 373.169436 -258.725878)
			(xy 373.177561 -258.777173) (xy 373.17807 -258.80314) (xy 373.177561 -258.829107) (xy 373.457471 -258.829107)
			(xy 373.457471 -258.777173) (xy 373.465596 -258.725878) (xy 373.481644 -258.676485) (xy 373.505222 -258.630211)
			(xy 373.535748 -258.588195) (xy 373.572471 -258.551472) (xy 373.614487 -258.520946) (xy 373.660761 -258.497368)
			(xy 373.710154 -258.48132) (xy 373.761449 -258.473195) (xy 373.813383 -258.473195) (xy 373.864678 -258.48132)
			(xy 373.914071 -258.497368) (xy 373.960345 -258.520946) (xy 374.002361 -258.551472) (xy 374.039084 -258.588195)
			(xy 374.06961 -258.630211) (xy 374.093188 -258.676485) (xy 374.109236 -258.725878) (xy 374.117361 -258.777173)
			(xy 374.11787 -258.80314) (xy 374.117361 -258.829107) (xy 374.397271 -258.829107) (xy 374.397271 -258.777173)
			(xy 374.405396 -258.725878) (xy 374.421444 -258.676485) (xy 374.445022 -258.630211) (xy 374.475548 -258.588195)
			(xy 374.512271 -258.551472) (xy 374.554287 -258.520946) (xy 374.600561 -258.497368) (xy 374.649954 -258.48132)
			(xy 374.701249 -258.473195) (xy 374.753183 -258.473195) (xy 374.804478 -258.48132) (xy 374.853871 -258.497368)
			(xy 374.900145 -258.520946) (xy 374.942161 -258.551472) (xy 374.978884 -258.588195) (xy 375.00941 -258.630211)
			(xy 375.032988 -258.676485) (xy 375.049036 -258.725878) (xy 375.057161 -258.777173) (xy 375.05767 -258.80314)
			(xy 375.057161 -258.829107) (xy 375.337071 -258.829107) (xy 375.337071 -258.777173) (xy 375.345196 -258.725878)
			(xy 375.361244 -258.676485) (xy 375.384822 -258.630211) (xy 375.415348 -258.588195) (xy 375.452071 -258.551472)
			(xy 375.494087 -258.520946) (xy 375.540361 -258.497368) (xy 375.589754 -258.48132) (xy 375.641049 -258.473195)
			(xy 375.692983 -258.473195) (xy 375.744278 -258.48132) (xy 375.793671 -258.497368) (xy 375.839945 -258.520946)
			(xy 375.881961 -258.551472) (xy 375.918684 -258.588195) (xy 375.94921 -258.630211) (xy 375.972788 -258.676485)
			(xy 375.988836 -258.725878) (xy 375.996961 -258.777173) (xy 375.99747 -258.80314) (xy 375.996961 -258.829107)
			(xy 376.276871 -258.829107) (xy 376.276871 -258.777173) (xy 376.284996 -258.725878) (xy 376.301044 -258.676485)
			(xy 376.324622 -258.630211) (xy 376.355148 -258.588195) (xy 376.391871 -258.551472) (xy 376.433887 -258.520946)
			(xy 376.480161 -258.497368) (xy 376.529554 -258.48132) (xy 376.580849 -258.473195) (xy 376.632783 -258.473195)
			(xy 376.684078 -258.48132) (xy 376.733471 -258.497368) (xy 376.779745 -258.520946) (xy 376.821761 -258.551472)
			(xy 376.858484 -258.588195) (xy 376.88901 -258.630211) (xy 376.912588 -258.676485) (xy 376.928636 -258.725878)
			(xy 376.936761 -258.777173) (xy 376.93727 -258.80314) (xy 376.936761 -258.829107) (xy 376.928636 -258.880402)
			(xy 376.912588 -258.929795) (xy 376.88901 -258.976069) (xy 376.858484 -259.018085) (xy 376.821761 -259.054808)
			(xy 376.779745 -259.085334) (xy 376.733471 -259.108912) (xy 376.684078 -259.12496) (xy 376.632783 -259.133085)
			(xy 376.580849 -259.133085) (xy 376.529554 -259.12496) (xy 376.480161 -259.108912) (xy 376.433887 -259.085334)
			(xy 376.391871 -259.054808) (xy 376.355148 -259.018085) (xy 376.324622 -258.976069) (xy 376.301044 -258.929795)
			(xy 376.284996 -258.880402) (xy 376.276871 -258.829107) (xy 375.996961 -258.829107) (xy 375.988836 -258.880402)
			(xy 375.972788 -258.929795) (xy 375.94921 -258.976069) (xy 375.918684 -259.018085) (xy 375.881961 -259.054808)
			(xy 375.839945 -259.085334) (xy 375.793671 -259.108912) (xy 375.744278 -259.12496) (xy 375.692983 -259.133085)
			(xy 375.641049 -259.133085) (xy 375.589754 -259.12496) (xy 375.540361 -259.108912) (xy 375.494087 -259.085334)
			(xy 375.452071 -259.054808) (xy 375.415348 -259.018085) (xy 375.384822 -258.976069) (xy 375.361244 -258.929795)
			(xy 375.345196 -258.880402) (xy 375.337071 -258.829107) (xy 375.057161 -258.829107) (xy 375.049036 -258.880402)
			(xy 375.032988 -258.929795) (xy 375.00941 -258.976069) (xy 374.978884 -259.018085) (xy 374.942161 -259.054808)
			(xy 374.900145 -259.085334) (xy 374.853871 -259.108912) (xy 374.804478 -259.12496) (xy 374.753183 -259.133085)
			(xy 374.701249 -259.133085) (xy 374.649954 -259.12496) (xy 374.600561 -259.108912) (xy 374.554287 -259.085334)
			(xy 374.512271 -259.054808) (xy 374.475548 -259.018085) (xy 374.445022 -258.976069) (xy 374.421444 -258.929795)
			(xy 374.405396 -258.880402) (xy 374.397271 -258.829107) (xy 374.117361 -258.829107) (xy 374.109236 -258.880402)
			(xy 374.093188 -258.929795) (xy 374.06961 -258.976069) (xy 374.039084 -259.018085) (xy 374.002361 -259.054808)
			(xy 373.960345 -259.085334) (xy 373.914071 -259.108912) (xy 373.864678 -259.12496) (xy 373.813383 -259.133085)
			(xy 373.761449 -259.133085) (xy 373.710154 -259.12496) (xy 373.660761 -259.108912) (xy 373.614487 -259.085334)
			(xy 373.572471 -259.054808) (xy 373.535748 -259.018085) (xy 373.505222 -258.976069) (xy 373.481644 -258.929795)
			(xy 373.465596 -258.880402) (xy 373.457471 -258.829107) (xy 373.177561 -258.829107) (xy 373.169436 -258.880402)
			(xy 373.153388 -258.929795) (xy 373.12981 -258.976069) (xy 373.099284 -259.018085) (xy 373.062561 -259.054808)
			(xy 373.020545 -259.085334) (xy 372.974271 -259.108912) (xy 372.924878 -259.12496) (xy 372.873583 -259.133085)
			(xy 372.821649 -259.133085) (xy 372.770354 -259.12496) (xy 372.720961 -259.108912) (xy 372.674687 -259.085334)
			(xy 372.632671 -259.054808) (xy 372.595948 -259.018085) (xy 372.565422 -258.976069) (xy 372.541844 -258.929795)
			(xy 372.525796 -258.880402) (xy 372.517671 -258.829107) (xy 372.237761 -258.829107) (xy 372.229636 -258.880402)
			(xy 372.213588 -258.929795) (xy 372.19001 -258.976069) (xy 372.159484 -259.018085) (xy 372.122761 -259.054808)
			(xy 372.080745 -259.085334) (xy 372.034471 -259.108912) (xy 371.985078 -259.12496) (xy 371.933783 -259.133085)
			(xy 371.881849 -259.133085) (xy 371.830554 -259.12496) (xy 371.781161 -259.108912) (xy 371.734887 -259.085334)
			(xy 371.692871 -259.054808) (xy 371.656148 -259.018085) (xy 371.625622 -258.976069) (xy 371.602044 -258.929795)
			(xy 371.585996 -258.880402) (xy 371.577871 -258.829107) (xy 371.297707 -258.829107) (xy 371.289582 -258.880402)
			(xy 371.273534 -258.929795) (xy 371.249956 -258.976069) (xy 371.21943 -259.018085) (xy 371.182707 -259.054808)
			(xy 371.140691 -259.085334) (xy 371.094417 -259.108912) (xy 371.045024 -259.12496) (xy 370.993729 -259.133085)
			(xy 370.941795 -259.133085) (xy 370.8905 -259.12496) (xy 370.841107 -259.108912) (xy 370.794833 -259.085334)
			(xy 370.752817 -259.054808) (xy 370.716094 -259.018085) (xy 370.685568 -258.976069) (xy 370.66199 -258.929795)
			(xy 370.645942 -258.880402) (xy 370.637817 -258.829107) (xy 370.357907 -258.829107) (xy 370.349782 -258.880402)
			(xy 370.333734 -258.929795) (xy 370.310156 -258.976069) (xy 370.27963 -259.018085) (xy 370.242907 -259.054808)
			(xy 370.200891 -259.085334) (xy 370.154617 -259.108912) (xy 370.105224 -259.12496) (xy 370.053929 -259.133085)
			(xy 370.001995 -259.133085) (xy 369.9507 -259.12496) (xy 369.901307 -259.108912) (xy 369.855033 -259.085334)
			(xy 369.813017 -259.054808) (xy 369.776294 -259.018085) (xy 369.745768 -258.976069) (xy 369.72219 -258.929795)
			(xy 369.706142 -258.880402) (xy 369.698017 -258.829107) (xy 363.61098 -258.829107) (xy 363.617718 -258.835845)
			(xy 363.648244 -258.877861) (xy 363.671822 -258.924135) (xy 363.68787 -258.973528) (xy 363.695995 -259.024823)
			(xy 363.696504 -259.05079) (xy 363.696504 -259.051044) (xy 363.696078 -259.075572) (xy 363.688808 -259.124085)
			(xy 363.674451 -259.170993) (xy 363.65332 -259.215264) (xy 363.62588 -259.255927) (xy 363.609636 -259.27431)
			(xy 363.599841 -259.285806) (xy 363.586825 -259.313041) (xy 363.582354 -259.342893) (xy 363.586821 -259.372745)
			(xy 363.599833 -259.399981) (xy 363.609636 -259.41147) (xy 363.625876 -259.429857) (xy 363.653325 -259.470513)
			(xy 363.674457 -259.514783) (xy 363.688807 -259.561692) (xy 363.696059 -259.610208) (xy 363.696504 -259.634736)
			(xy 363.696504 -259.63499) (xy 363.695995 -259.660957) (xy 363.68787 -259.712252) (xy 363.671822 -259.761645)
			(xy 363.648244 -259.807919) (xy 363.617718 -259.849935) (xy 363.580995 -259.886658) (xy 363.538979 -259.917184)
			(xy 363.492705 -259.940762) (xy 363.443312 -259.95681) (xy 363.392017 -259.964935) (xy 363.340083 -259.964935)
			(xy 363.288788 -259.95681) (xy 363.239395 -259.940762) (xy 363.193121 -259.917184) (xy 363.151105 -259.886658)
			(xy 363.114382 -259.849935) (xy 363.083856 -259.807919) (xy 363.060278 -259.761645) (xy 363.04423 -259.712252)
			(xy 363.036105 -259.660957) (xy 363.035596 -259.63499) (xy 362.370017 -259.63499) (xy 362.369861 -259.642923)
			(xy 362.361736 -259.694218) (xy 362.345688 -259.743611) (xy 362.32211 -259.789885) (xy 362.291584 -259.831901)
			(xy 362.254861 -259.868624) (xy 362.212845 -259.89915) (xy 362.166571 -259.922728) (xy 362.117178 -259.938776)
			(xy 362.065883 -259.946901) (xy 362.013949 -259.946901) (xy 361.962654 -259.938776) (xy 361.913261 -259.922728)
			(xy 361.866987 -259.89915) (xy 361.824971 -259.868624) (xy 361.788248 -259.831901) (xy 361.757722 -259.789885)
			(xy 361.734144 -259.743611) (xy 361.718096 -259.694218) (xy 361.709971 -259.642923) (xy 361.429807 -259.642923)
			(xy 361.421682 -259.694218) (xy 361.405634 -259.743611) (xy 361.382056 -259.789885) (xy 361.35153 -259.831901)
			(xy 361.314807 -259.868624) (xy 361.272791 -259.89915) (xy 361.226517 -259.922728) (xy 361.177124 -259.938776)
			(xy 361.125829 -259.946901) (xy 361.073895 -259.946901) (xy 361.0226 -259.938776) (xy 360.973207 -259.922728)
			(xy 360.926933 -259.89915) (xy 360.884917 -259.868624) (xy 360.848194 -259.831901) (xy 360.817668 -259.789885)
			(xy 360.79409 -259.743611) (xy 360.778042 -259.694218) (xy 360.769917 -259.642923) (xy 360.490261 -259.642923)
			(xy 360.482136 -259.694218) (xy 360.466088 -259.743611) (xy 360.44251 -259.789885) (xy 360.411984 -259.831901)
			(xy 360.375261 -259.868624) (xy 360.333245 -259.89915) (xy 360.286971 -259.922728) (xy 360.237578 -259.938776)
			(xy 360.186283 -259.946901) (xy 360.134349 -259.946901) (xy 360.083054 -259.938776) (xy 360.033661 -259.922728)
			(xy 359.987387 -259.89915) (xy 359.945371 -259.868624) (xy 359.908648 -259.831901) (xy 359.878122 -259.789885)
			(xy 359.854544 -259.743611) (xy 359.838496 -259.694218) (xy 359.830371 -259.642923) (xy 359.550461 -259.642923)
			(xy 359.542336 -259.694218) (xy 359.526288 -259.743611) (xy 359.50271 -259.789885) (xy 359.472184 -259.831901)
			(xy 359.435461 -259.868624) (xy 359.393445 -259.89915) (xy 359.347171 -259.922728) (xy 359.297778 -259.938776)
			(xy 359.246483 -259.946901) (xy 359.194549 -259.946901) (xy 359.143254 -259.938776) (xy 359.093861 -259.922728)
			(xy 359.047587 -259.89915) (xy 359.005571 -259.868624) (xy 358.968848 -259.831901) (xy 358.938322 -259.789885)
			(xy 358.914744 -259.743611) (xy 358.898696 -259.694218) (xy 358.890571 -259.642923) (xy 358.610407 -259.642923)
			(xy 358.602282 -259.694218) (xy 358.586234 -259.743611) (xy 358.562656 -259.789885) (xy 358.53213 -259.831901)
			(xy 358.495407 -259.868624) (xy 358.453391 -259.89915) (xy 358.407117 -259.922728) (xy 358.357724 -259.938776)
			(xy 358.306429 -259.946901) (xy 358.254495 -259.946901) (xy 358.2032 -259.938776) (xy 358.153807 -259.922728)
			(xy 358.107533 -259.89915) (xy 358.065517 -259.868624) (xy 358.028794 -259.831901) (xy 357.998268 -259.789885)
			(xy 357.97469 -259.743611) (xy 357.958642 -259.694218) (xy 357.950517 -259.642923) (xy 357.670607 -259.642923)
			(xy 357.662482 -259.694218) (xy 357.646434 -259.743611) (xy 357.622856 -259.789885) (xy 357.59233 -259.831901)
			(xy 357.555607 -259.868624) (xy 357.513591 -259.89915) (xy 357.467317 -259.922728) (xy 357.417924 -259.938776)
			(xy 357.366629 -259.946901) (xy 357.314695 -259.946901) (xy 357.2634 -259.938776) (xy 357.214007 -259.922728)
			(xy 357.167733 -259.89915) (xy 357.125717 -259.868624) (xy 357.088994 -259.831901) (xy 357.058468 -259.789885)
			(xy 357.03489 -259.743611) (xy 357.018842 -259.694218) (xy 357.010717 -259.642923) (xy 356.697514 -259.642923)
			(xy 356.695504 -259.65561) (xy 356.679456 -259.705003) (xy 356.655878 -259.751277) (xy 356.625352 -259.793293)
			(xy 356.588629 -259.830016) (xy 356.546613 -259.860542) (xy 356.500339 -259.88412) (xy 356.450946 -259.900168)
			(xy 356.399651 -259.908293) (xy 356.347717 -259.908293) (xy 356.296422 -259.900168) (xy 356.247029 -259.88412)
			(xy 356.200755 -259.860542) (xy 356.158739 -259.830016) (xy 356.122016 -259.793293) (xy 356.09149 -259.751277)
			(xy 356.067912 -259.705003) (xy 356.051864 -259.65561) (xy 356.043739 -259.604315) (xy 356.04323 -259.578348)
			(xy 351.11506 -259.578348) (xy 351.128332 -259.619196) (xy 351.136457 -259.670491) (xy 351.136966 -259.696458)
			(xy 351.136457 -259.722425) (xy 351.128332 -259.77372) (xy 351.112284 -259.823113) (xy 351.088706 -259.869387)
			(xy 351.05818 -259.911403) (xy 351.021457 -259.948126) (xy 350.979441 -259.978652) (xy 350.933167 -260.00223)
			(xy 350.883774 -260.018278) (xy 350.832479 -260.026403) (xy 350.780545 -260.026403) (xy 350.72925 -260.018278)
			(xy 350.679857 -260.00223) (xy 350.633583 -259.978652) (xy 350.591567 -259.948126) (xy 350.554844 -259.911403)
			(xy 350.524318 -259.869387) (xy 350.50074 -259.823113) (xy 350.484692 -259.77372) (xy 350.476567 -259.722425)
			(xy 350.134917 -259.722425) (xy 350.128034 -259.743611) (xy 350.104456 -259.789885) (xy 350.07393 -259.831901)
			(xy 350.037207 -259.868624) (xy 349.995191 -259.89915) (xy 349.948917 -259.922728) (xy 349.899524 -259.938776)
			(xy 349.848229 -259.946901) (xy 349.796295 -259.946901) (xy 349.745 -259.938776) (xy 349.695607 -259.922728)
			(xy 349.649333 -259.89915) (xy 349.607317 -259.868624) (xy 349.570594 -259.831901) (xy 349.540068 -259.789885)
			(xy 349.51649 -259.743611) (xy 349.500442 -259.694218) (xy 349.492317 -259.642923) (xy 349.212407 -259.642923)
			(xy 349.204282 -259.694218) (xy 349.188234 -259.743611) (xy 349.164656 -259.789885) (xy 349.13413 -259.831901)
			(xy 349.097407 -259.868624) (xy 349.055391 -259.89915) (xy 349.009117 -259.922728) (xy 348.959724 -259.938776)
			(xy 348.908429 -259.946901) (xy 348.856495 -259.946901) (xy 348.8052 -259.938776) (xy 348.755807 -259.922728)
			(xy 348.709533 -259.89915) (xy 348.667517 -259.868624) (xy 348.630794 -259.831901) (xy 348.600268 -259.789885)
			(xy 348.57669 -259.743611) (xy 348.560642 -259.694218) (xy 348.552517 -259.642923) (xy 348.272607 -259.642923)
			(xy 348.264482 -259.694218) (xy 348.248434 -259.743611) (xy 348.224856 -259.789885) (xy 348.19433 -259.831901)
			(xy 348.157607 -259.868624) (xy 348.115591 -259.89915) (xy 348.069317 -259.922728) (xy 348.019924 -259.938776)
			(xy 347.968629 -259.946901) (xy 347.916695 -259.946901) (xy 347.8654 -259.938776) (xy 347.816007 -259.922728)
			(xy 347.769733 -259.89915) (xy 347.727717 -259.868624) (xy 347.690994 -259.831901) (xy 347.660468 -259.789885)
			(xy 347.63689 -259.743611) (xy 347.620842 -259.694218) (xy 347.612717 -259.642923) (xy 347.332807 -259.642923)
			(xy 347.324682 -259.694218) (xy 347.308634 -259.743611) (xy 347.285056 -259.789885) (xy 347.25453 -259.831901)
			(xy 347.217807 -259.868624) (xy 347.175791 -259.89915) (xy 347.129517 -259.922728) (xy 347.080124 -259.938776)
			(xy 347.028829 -259.946901) (xy 346.976895 -259.946901) (xy 346.9256 -259.938776) (xy 346.876207 -259.922728)
			(xy 346.829933 -259.89915) (xy 346.787917 -259.868624) (xy 346.751194 -259.831901) (xy 346.720668 -259.789885)
			(xy 346.69709 -259.743611) (xy 346.681042 -259.694218) (xy 346.672917 -259.642923) (xy 346.393261 -259.642923)
			(xy 346.385136 -259.694218) (xy 346.369088 -259.743611) (xy 346.34551 -259.789885) (xy 346.314984 -259.831901)
			(xy 346.278261 -259.868624) (xy 346.236245 -259.89915) (xy 346.189971 -259.922728) (xy 346.140578 -259.938776)
			(xy 346.089283 -259.946901) (xy 346.037349 -259.946901) (xy 345.986054 -259.938776) (xy 345.936661 -259.922728)
			(xy 345.890387 -259.89915) (xy 345.848371 -259.868624) (xy 345.811648 -259.831901) (xy 345.781122 -259.789885)
			(xy 345.757544 -259.743611) (xy 345.741496 -259.694218) (xy 345.733371 -259.642923) (xy 345.453207 -259.642923)
			(xy 345.445082 -259.694218) (xy 345.429034 -259.743611) (xy 345.405456 -259.789885) (xy 345.37493 -259.831901)
			(xy 345.338207 -259.868624) (xy 345.296191 -259.89915) (xy 345.249917 -259.922728) (xy 345.200524 -259.938776)
			(xy 345.149229 -259.946901) (xy 345.097295 -259.946901) (xy 345.046 -259.938776) (xy 344.996607 -259.922728)
			(xy 344.950333 -259.89915) (xy 344.908317 -259.868624) (xy 344.871594 -259.831901) (xy 344.841068 -259.789885)
			(xy 344.81749 -259.743611) (xy 344.801442 -259.694218) (xy 344.793317 -259.642923) (xy 344.513407 -259.642923)
			(xy 344.505282 -259.694218) (xy 344.489234 -259.743611) (xy 344.465656 -259.789885) (xy 344.43513 -259.831901)
			(xy 344.398407 -259.868624) (xy 344.356391 -259.89915) (xy 344.310117 -259.922728) (xy 344.260724 -259.938776)
			(xy 344.209429 -259.946901) (xy 344.157495 -259.946901) (xy 344.1062 -259.938776) (xy 344.056807 -259.922728)
			(xy 344.010533 -259.89915) (xy 343.968517 -259.868624) (xy 343.931794 -259.831901) (xy 343.901268 -259.789885)
			(xy 343.87769 -259.743611) (xy 343.861642 -259.694218) (xy 343.853517 -259.642923) (xy 343.573607 -259.642923)
			(xy 343.565482 -259.694218) (xy 343.549434 -259.743611) (xy 343.525856 -259.789885) (xy 343.49533 -259.831901)
			(xy 343.458607 -259.868624) (xy 343.416591 -259.89915) (xy 343.370317 -259.922728) (xy 343.320924 -259.938776)
			(xy 343.269629 -259.946901) (xy 343.217695 -259.946901) (xy 343.1664 -259.938776) (xy 343.117007 -259.922728)
			(xy 343.070733 -259.89915) (xy 343.028717 -259.868624) (xy 342.991994 -259.831901) (xy 342.961468 -259.789885)
			(xy 342.93789 -259.743611) (xy 342.921842 -259.694218) (xy 342.913717 -259.642923) (xy 342.633807 -259.642923)
			(xy 342.625682 -259.694218) (xy 342.609634 -259.743611) (xy 342.586056 -259.789885) (xy 342.55553 -259.831901)
			(xy 342.518807 -259.868624) (xy 342.476791 -259.89915) (xy 342.430517 -259.922728) (xy 342.381124 -259.938776)
			(xy 342.329829 -259.946901) (xy 342.277895 -259.946901) (xy 342.2266 -259.938776) (xy 342.177207 -259.922728)
			(xy 342.130933 -259.89915) (xy 342.088917 -259.868624) (xy 342.052194 -259.831901) (xy 342.021668 -259.789885)
			(xy 341.99809 -259.743611) (xy 341.982042 -259.694218) (xy 341.973917 -259.642923) (xy 341.694007 -259.642923)
			(xy 341.685882 -259.694218) (xy 341.669834 -259.743611) (xy 341.646256 -259.789885) (xy 341.61573 -259.831901)
			(xy 341.579007 -259.868624) (xy 341.536991 -259.89915) (xy 341.490717 -259.922728) (xy 341.441324 -259.938776)
			(xy 341.390029 -259.946901) (xy 341.338095 -259.946901) (xy 341.2868 -259.938776) (xy 341.237407 -259.922728)
			(xy 341.191133 -259.89915) (xy 341.149117 -259.868624) (xy 341.112394 -259.831901) (xy 341.081868 -259.789885)
			(xy 341.05829 -259.743611) (xy 341.042242 -259.694218) (xy 341.034117 -259.642923) (xy 340.754207 -259.642923)
			(xy 340.746082 -259.694218) (xy 340.730034 -259.743611) (xy 340.706456 -259.789885) (xy 340.67593 -259.831901)
			(xy 340.639207 -259.868624) (xy 340.597191 -259.89915) (xy 340.550917 -259.922728) (xy 340.501524 -259.938776)
			(xy 340.450229 -259.946901) (xy 340.398295 -259.946901) (xy 340.347 -259.938776) (xy 340.297607 -259.922728)
			(xy 340.251333 -259.89915) (xy 340.209317 -259.868624) (xy 340.172594 -259.831901) (xy 340.142068 -259.789885)
			(xy 340.11849 -259.743611) (xy 340.102442 -259.694218) (xy 340.094317 -259.642923) (xy 339.814 -259.642923)
			(xy 339.81207 -259.667907) (xy 339.800353 -259.717627) (xy 339.781132 -259.764955) (xy 339.754863 -259.808766)
			(xy 339.722172 -259.848018) (xy 339.683836 -259.881778) (xy 339.662516 -259.895848) (xy 339.651848 -259.902706)
			(xy 339.627464 -259.945124) (xy 339.627464 -260.063996) (xy 339.62778 -260.072382) (xy 339.63328 -260.088227)
			(xy 339.643673 -260.101391) (xy 339.650578 -260.10616) (xy 339.718142 -260.144006) (xy 339.723391 -260.146495)
			(xy 339.734687 -260.149195) (xy 339.740494 -260.14934) (xy 339.767418 -260.14934) (xy 339.772591 -260.149186)
			(xy 339.782707 -260.147011) (xy 339.787484 -260.145022) (xy 339.791548 -260.142736) (xy 339.816481 -260.129339)
			(xy 339.86979 -260.110329) (xy 339.925556 -260.100662) (xy 339.953854 -260.100064) (xy 339.954362 -260.100064)
			(xy 339.980355 -260.100544) (xy 340.031703 -260.108672) (xy 340.081147 -260.124732) (xy 340.127469 -260.14833)
			(xy 340.169529 -260.178884) (xy 340.206292 -260.215642) (xy 340.236851 -260.257698) (xy 340.260454 -260.304018)
			(xy 340.27652 -260.35346) (xy 340.284653 -260.404807) (xy 340.284653 -260.456739) (xy 340.564471 -260.456739)
			(xy 340.564471 -260.404805) (xy 340.572596 -260.35351) (xy 340.588644 -260.304117) (xy 340.612222 -260.257843)
			(xy 340.642748 -260.215827) (xy 340.679471 -260.179104) (xy 340.721487 -260.148578) (xy 340.767761 -260.125)
			(xy 340.817154 -260.108952) (xy 340.868449 -260.100827) (xy 340.920383 -260.100827) (xy 340.971678 -260.108952)
			(xy 341.021071 -260.125) (xy 341.067345 -260.148578) (xy 341.109361 -260.179104) (xy 341.146084 -260.215827)
			(xy 341.17661 -260.257843) (xy 341.200188 -260.304117) (xy 341.216236 -260.35351) (xy 341.224361 -260.404805)
			(xy 341.22487 -260.430772) (xy 341.224361 -260.456739) (xy 341.504271 -260.456739) (xy 341.504271 -260.404805)
			(xy 341.512396 -260.35351) (xy 341.528444 -260.304117) (xy 341.552022 -260.257843) (xy 341.582548 -260.215827)
			(xy 341.619271 -260.179104) (xy 341.661287 -260.148578) (xy 341.707561 -260.125) (xy 341.756954 -260.108952)
			(xy 341.808249 -260.100827) (xy 341.860183 -260.100827) (xy 341.911478 -260.108952) (xy 341.960871 -260.125)
			(xy 342.007145 -260.148578) (xy 342.049161 -260.179104) (xy 342.085884 -260.215827) (xy 342.11641 -260.257843)
			(xy 342.139988 -260.304117) (xy 342.156036 -260.35351) (xy 342.164161 -260.404805) (xy 342.16467 -260.430772)
			(xy 342.164161 -260.456739) (xy 342.443563 -260.456739) (xy 342.443563 -260.404805) (xy 342.451688 -260.35351)
			(xy 342.467736 -260.304117) (xy 342.491314 -260.257843) (xy 342.52184 -260.215827) (xy 342.558563 -260.179104)
			(xy 342.600579 -260.148578) (xy 342.646853 -260.125) (xy 342.696246 -260.108952) (xy 342.747541 -260.100827)
			(xy 342.799475 -260.100827) (xy 342.85077 -260.108952) (xy 342.900163 -260.125) (xy 342.946437 -260.148578)
			(xy 342.988453 -260.179104) (xy 343.025176 -260.215827) (xy 343.055702 -260.257843) (xy 343.07928 -260.304117)
			(xy 343.095328 -260.35351) (xy 343.103453 -260.404805) (xy 343.103962 -260.430772) (xy 343.103453 -260.456739)
			(xy 343.383871 -260.456739) (xy 343.383871 -260.404805) (xy 343.391996 -260.35351) (xy 343.408044 -260.304117)
			(xy 343.431622 -260.257843) (xy 343.462148 -260.215827) (xy 343.498871 -260.179104) (xy 343.540887 -260.148578)
			(xy 343.587161 -260.125) (xy 343.636554 -260.108952) (xy 343.687849 -260.100827) (xy 343.739783 -260.100827)
			(xy 343.791078 -260.108952) (xy 343.840471 -260.125) (xy 343.886745 -260.148578) (xy 343.928761 -260.179104)
			(xy 343.965484 -260.215827) (xy 343.99601 -260.257843) (xy 344.019588 -260.304117) (xy 344.035636 -260.35351)
			(xy 344.043761 -260.404805) (xy 344.04427 -260.430772) (xy 344.043761 -260.456739) (xy 344.323163 -260.456739)
			(xy 344.323163 -260.404805) (xy 344.331288 -260.35351) (xy 344.347336 -260.304117) (xy 344.370914 -260.257843)
			(xy 344.40144 -260.215827) (xy 344.438163 -260.179104) (xy 344.480179 -260.148578) (xy 344.526453 -260.125)
			(xy 344.575846 -260.108952) (xy 344.627141 -260.100827) (xy 344.679075 -260.100827) (xy 344.73037 -260.108952)
			(xy 344.779763 -260.125) (xy 344.826037 -260.148578) (xy 344.868053 -260.179104) (xy 344.904776 -260.215827)
			(xy 344.935302 -260.257843) (xy 344.95888 -260.304117) (xy 344.974928 -260.35351) (xy 344.983053 -260.404805)
			(xy 344.983562 -260.430772) (xy 344.983053 -260.456739) (xy 345.263471 -260.456739) (xy 345.263471 -260.404805)
			(xy 345.271596 -260.35351) (xy 345.287644 -260.304117) (xy 345.311222 -260.257843) (xy 345.341748 -260.215827)
			(xy 345.378471 -260.179104) (xy 345.420487 -260.148578) (xy 345.466761 -260.125) (xy 345.516154 -260.108952)
			(xy 345.567449 -260.100827) (xy 345.619383 -260.100827) (xy 345.670678 -260.108952) (xy 345.720071 -260.125)
			(xy 345.766345 -260.148578) (xy 345.808361 -260.179104) (xy 345.845084 -260.215827) (xy 345.87561 -260.257843)
			(xy 345.899188 -260.304117) (xy 345.915236 -260.35351) (xy 345.923361 -260.404805) (xy 345.92387 -260.430772)
			(xy 345.923361 -260.456739) (xy 346.203017 -260.456739) (xy 346.203017 -260.404805) (xy 346.211142 -260.35351)
			(xy 346.22719 -260.304117) (xy 346.250768 -260.257843) (xy 346.281294 -260.215827) (xy 346.318017 -260.179104)
			(xy 346.360033 -260.148578) (xy 346.406307 -260.125) (xy 346.4557 -260.108952) (xy 346.506995 -260.100827)
			(xy 346.558929 -260.100827) (xy 346.610224 -260.108952) (xy 346.659617 -260.125) (xy 346.705891 -260.148578)
			(xy 346.747907 -260.179104) (xy 346.78463 -260.215827) (xy 346.815156 -260.257843) (xy 346.838734 -260.304117)
			(xy 346.854782 -260.35351) (xy 346.862907 -260.404805) (xy 346.863416 -260.430772) (xy 346.862907 -260.456739)
			(xy 347.143071 -260.456739) (xy 347.143071 -260.404805) (xy 347.151196 -260.35351) (xy 347.167244 -260.304117)
			(xy 347.190822 -260.257843) (xy 347.221348 -260.215827) (xy 347.258071 -260.179104) (xy 347.300087 -260.148578)
			(xy 347.346361 -260.125) (xy 347.395754 -260.108952) (xy 347.447049 -260.100827) (xy 347.498983 -260.100827)
			(xy 347.550278 -260.108952) (xy 347.599671 -260.125) (xy 347.645945 -260.148578) (xy 347.687961 -260.179104)
			(xy 347.724684 -260.215827) (xy 347.75521 -260.257843) (xy 347.778788 -260.304117) (xy 347.794836 -260.35351)
			(xy 347.802961 -260.404805) (xy 347.80347 -260.430772) (xy 347.802961 -260.456739) (xy 348.082871 -260.456739)
			(xy 348.082871 -260.404805) (xy 348.090996 -260.35351) (xy 348.107044 -260.304117) (xy 348.130622 -260.257843)
			(xy 348.161148 -260.215827) (xy 348.197871 -260.179104) (xy 348.239887 -260.148578) (xy 348.286161 -260.125)
			(xy 348.335554 -260.108952) (xy 348.386849 -260.100827) (xy 348.438783 -260.100827) (xy 348.490078 -260.108952)
			(xy 348.539471 -260.125) (xy 348.585745 -260.148578) (xy 348.627761 -260.179104) (xy 348.664484 -260.215827)
			(xy 348.69501 -260.257843) (xy 348.718588 -260.304117) (xy 348.734636 -260.35351) (xy 348.742761 -260.404805)
			(xy 348.74327 -260.430772) (xy 348.742761 -260.456739) (xy 349.022671 -260.456739) (xy 349.022671 -260.404805)
			(xy 349.030796 -260.35351) (xy 349.046844 -260.304117) (xy 349.070422 -260.257843) (xy 349.100948 -260.215827)
			(xy 349.137671 -260.179104) (xy 349.179687 -260.148578) (xy 349.225961 -260.125) (xy 349.275354 -260.108952)
			(xy 349.326649 -260.100827) (xy 349.378583 -260.100827) (xy 349.429878 -260.108952) (xy 349.479271 -260.125)
			(xy 349.525545 -260.148578) (xy 349.567561 -260.179104) (xy 349.604284 -260.215827) (xy 349.63481 -260.257843)
			(xy 349.658388 -260.304117) (xy 349.674436 -260.35351) (xy 349.682561 -260.404805) (xy 349.68307 -260.430772)
			(xy 349.682561 -260.456739) (xy 349.682556 -260.456772) (xy 349.962401 -260.456772) (xy 349.962401 -260.404828)
			(xy 349.970527 -260.353523) (xy 349.986579 -260.304121) (xy 350.010162 -260.257838) (xy 350.040695 -260.215815)
			(xy 350.077427 -260.179085) (xy 350.119452 -260.148554) (xy 350.165735 -260.124973) (xy 350.215138 -260.108923)
			(xy 350.266444 -260.1008) (xy 350.292416 -260.100318) (xy 350.319503 -260.100867) (xy 350.37295 -260.109705)
			(xy 350.42424 -260.127142) (xy 350.472 -260.15271) (xy 350.51495 -260.185726) (xy 350.551941 -260.225304)
			(xy 350.581981 -260.270385) (xy 350.604267 -260.319763) (xy 350.6182 -260.372113) (xy 350.621346 -260.399022)
			(xy 350.623184 -260.413163) (xy 350.63358 -260.4397) (xy 350.650914 -260.462323) (xy 350.673831 -260.479266)
			(xy 350.700543 -260.489205) (xy 350.728962 -260.491364) (xy 350.743012 -260.488938) (xy 350.759467 -260.485761)
			(xy 350.792803 -260.482322) (xy 350.80956 -260.48208) (xy 350.835534 -260.482492) (xy 350.886843 -260.490613)
			(xy 350.93625 -260.506661) (xy 350.982538 -260.530241) (xy 351.024567 -260.560772) (xy 351.061302 -260.597502)
			(xy 351.091838 -260.639528) (xy 351.115424 -260.685813) (xy 351.131478 -260.735218) (xy 351.139605 -260.786526)
			(xy 351.139605 -260.838474) (xy 351.131478 -260.889782) (xy 351.115424 -260.939187) (xy 351.091838 -260.985472)
			(xy 351.061302 -261.027498) (xy 351.024567 -261.064228) (xy 350.982538 -261.094759) (xy 350.93625 -261.118339)
			(xy 350.886843 -261.134387) (xy 350.835534 -261.142508) (xy 350.80956 -261.142988) (xy 350.782473 -261.142455)
			(xy 350.729025 -261.133614) (xy 350.677735 -261.116174) (xy 350.629975 -261.090603) (xy 350.587026 -261.057585)
			(xy 350.550035 -261.018006) (xy 350.519996 -260.972923) (xy 350.49771 -260.923545) (xy 350.483776 -260.871193)
			(xy 350.48063 -260.844284) (xy 350.478815 -260.830139) (xy 350.468417 -260.803598) (xy 350.45108 -260.780972)
			(xy 350.428157 -260.764028) (xy 350.40144 -260.754092) (xy 350.373016 -260.751938) (xy 350.358964 -260.754368)
			(xy 350.34251 -260.757548) (xy 350.309173 -260.760986) (xy 350.292416 -260.761226) (xy 350.266444 -260.7608)
			(xy 350.215138 -260.752677) (xy 350.165735 -260.736627) (xy 350.119452 -260.713046) (xy 350.077427 -260.682515)
			(xy 350.040695 -260.645785) (xy 350.010162 -260.603762) (xy 349.986579 -260.557479) (xy 349.970527 -260.508077)
			(xy 349.962401 -260.456772) (xy 349.682556 -260.456772) (xy 349.674436 -260.508034) (xy 349.658388 -260.557427)
			(xy 349.63481 -260.603701) (xy 349.604284 -260.645717) (xy 349.567561 -260.68244) (xy 349.525545 -260.712966)
			(xy 349.479271 -260.736544) (xy 349.429878 -260.752592) (xy 349.378583 -260.760717) (xy 349.326649 -260.760717)
			(xy 349.275354 -260.752592) (xy 349.225961 -260.736544) (xy 349.179687 -260.712966) (xy 349.137671 -260.68244)
			(xy 349.100948 -260.645717) (xy 349.070422 -260.603701) (xy 349.046844 -260.557427) (xy 349.030796 -260.508034)
			(xy 349.022671 -260.456739) (xy 348.742761 -260.456739) (xy 348.734636 -260.508034) (xy 348.718588 -260.557427)
			(xy 348.69501 -260.603701) (xy 348.664484 -260.645717) (xy 348.627761 -260.68244) (xy 348.585745 -260.712966)
			(xy 348.539471 -260.736544) (xy 348.490078 -260.752592) (xy 348.438783 -260.760717) (xy 348.386849 -260.760717)
			(xy 348.335554 -260.752592) (xy 348.286161 -260.736544) (xy 348.239887 -260.712966) (xy 348.197871 -260.68244)
			(xy 348.161148 -260.645717) (xy 348.130622 -260.603701) (xy 348.107044 -260.557427) (xy 348.090996 -260.508034)
			(xy 348.082871 -260.456739) (xy 347.802961 -260.456739) (xy 347.794836 -260.508034) (xy 347.778788 -260.557427)
			(xy 347.75521 -260.603701) (xy 347.724684 -260.645717) (xy 347.687961 -260.68244) (xy 347.645945 -260.712966)
			(xy 347.599671 -260.736544) (xy 347.550278 -260.752592) (xy 347.498983 -260.760717) (xy 347.447049 -260.760717)
			(xy 347.395754 -260.752592) (xy 347.346361 -260.736544) (xy 347.300087 -260.712966) (xy 347.258071 -260.68244)
			(xy 347.221348 -260.645717) (xy 347.190822 -260.603701) (xy 347.167244 -260.557427) (xy 347.151196 -260.508034)
			(xy 347.143071 -260.456739) (xy 346.862907 -260.456739) (xy 346.854782 -260.508034) (xy 346.838734 -260.557427)
			(xy 346.815156 -260.603701) (xy 346.78463 -260.645717) (xy 346.747907 -260.68244) (xy 346.705891 -260.712966)
			(xy 346.659617 -260.736544) (xy 346.610224 -260.752592) (xy 346.558929 -260.760717) (xy 346.506995 -260.760717)
			(xy 346.4557 -260.752592) (xy 346.406307 -260.736544) (xy 346.360033 -260.712966) (xy 346.318017 -260.68244)
			(xy 346.281294 -260.645717) (xy 346.250768 -260.603701) (xy 346.22719 -260.557427) (xy 346.211142 -260.508034)
			(xy 346.203017 -260.456739) (xy 345.923361 -260.456739) (xy 345.915236 -260.508034) (xy 345.899188 -260.557427)
			(xy 345.87561 -260.603701) (xy 345.845084 -260.645717) (xy 345.808361 -260.68244) (xy 345.766345 -260.712966)
			(xy 345.720071 -260.736544) (xy 345.670678 -260.752592) (xy 345.619383 -260.760717) (xy 345.567449 -260.760717)
			(xy 345.516154 -260.752592) (xy 345.466761 -260.736544) (xy 345.420487 -260.712966) (xy 345.378471 -260.68244)
			(xy 345.341748 -260.645717) (xy 345.311222 -260.603701) (xy 345.287644 -260.557427) (xy 345.271596 -260.508034)
			(xy 345.263471 -260.456739) (xy 344.983053 -260.456739) (xy 344.974928 -260.508034) (xy 344.95888 -260.557427)
			(xy 344.935302 -260.603701) (xy 344.904776 -260.645717) (xy 344.868053 -260.68244) (xy 344.826037 -260.712966)
			(xy 344.779763 -260.736544) (xy 344.73037 -260.752592) (xy 344.679075 -260.760717) (xy 344.627141 -260.760717)
			(xy 344.575846 -260.752592) (xy 344.526453 -260.736544) (xy 344.480179 -260.712966) (xy 344.438163 -260.68244)
			(xy 344.40144 -260.645717) (xy 344.370914 -260.603701) (xy 344.347336 -260.557427) (xy 344.331288 -260.508034)
			(xy 344.323163 -260.456739) (xy 344.043761 -260.456739) (xy 344.035636 -260.508034) (xy 344.019588 -260.557427)
			(xy 343.99601 -260.603701) (xy 343.965484 -260.645717) (xy 343.928761 -260.68244) (xy 343.886745 -260.712966)
			(xy 343.840471 -260.736544) (xy 343.791078 -260.752592) (xy 343.739783 -260.760717) (xy 343.687849 -260.760717)
			(xy 343.636554 -260.752592) (xy 343.587161 -260.736544) (xy 343.540887 -260.712966) (xy 343.498871 -260.68244)
			(xy 343.462148 -260.645717) (xy 343.431622 -260.603701) (xy 343.408044 -260.557427) (xy 343.391996 -260.508034)
			(xy 343.383871 -260.456739) (xy 343.103453 -260.456739) (xy 343.095328 -260.508034) (xy 343.07928 -260.557427)
			(xy 343.055702 -260.603701) (xy 343.025176 -260.645717) (xy 342.988453 -260.68244) (xy 342.946437 -260.712966)
			(xy 342.900163 -260.736544) (xy 342.85077 -260.752592) (xy 342.799475 -260.760717) (xy 342.747541 -260.760717)
			(xy 342.696246 -260.752592) (xy 342.646853 -260.736544) (xy 342.600579 -260.712966) (xy 342.558563 -260.68244)
			(xy 342.52184 -260.645717) (xy 342.491314 -260.603701) (xy 342.467736 -260.557427) (xy 342.451688 -260.508034)
			(xy 342.443563 -260.456739) (xy 342.164161 -260.456739) (xy 342.156036 -260.508034) (xy 342.139988 -260.557427)
			(xy 342.11641 -260.603701) (xy 342.085884 -260.645717) (xy 342.049161 -260.68244) (xy 342.007145 -260.712966)
			(xy 341.960871 -260.736544) (xy 341.911478 -260.752592) (xy 341.860183 -260.760717) (xy 341.808249 -260.760717)
			(xy 341.756954 -260.752592) (xy 341.707561 -260.736544) (xy 341.661287 -260.712966) (xy 341.619271 -260.68244)
			(xy 341.582548 -260.645717) (xy 341.552022 -260.603701) (xy 341.528444 -260.557427) (xy 341.512396 -260.508034)
			(xy 341.504271 -260.456739) (xy 341.224361 -260.456739) (xy 341.216236 -260.508034) (xy 341.200188 -260.557427)
			(xy 341.17661 -260.603701) (xy 341.146084 -260.645717) (xy 341.109361 -260.68244) (xy 341.067345 -260.712966)
			(xy 341.021071 -260.736544) (xy 340.971678 -260.752592) (xy 340.920383 -260.760717) (xy 340.868449 -260.760717)
			(xy 340.817154 -260.752592) (xy 340.767761 -260.736544) (xy 340.721487 -260.712966) (xy 340.679471 -260.68244)
			(xy 340.642748 -260.645717) (xy 340.612222 -260.603701) (xy 340.588644 -260.557427) (xy 340.572596 -260.508034)
			(xy 340.564471 -260.456739) (xy 340.284653 -260.456739) (xy 340.284653 -260.456793) (xy 340.27652 -260.50814)
			(xy 340.260454 -260.557582) (xy 340.236851 -260.603902) (xy 340.206292 -260.645958) (xy 340.169529 -260.682716)
			(xy 340.127469 -260.71327) (xy 340.081147 -260.736868) (xy 340.031703 -260.752928) (xy 339.980355 -260.761056)
			(xy 339.954362 -260.76148) (xy 339.954108 -260.76148) (xy 339.942896 -260.76139) (xy 339.920524 -260.759866)
			(xy 339.909404 -260.758432) (xy 339.905848 -260.757924) (xy 339.904324 -260.757924) (xy 339.87308 -260.752422)
			(xy 339.813351 -260.731069) (xy 339.785706 -260.715506) (xy 339.780118 -260.712204) (xy 339.75421 -260.704838)
			(xy 339.748194 -260.704961) (xy 339.736499 -260.707779) (xy 339.731096 -260.710426) (xy 339.709506 -260.722364)
			(xy 339.653118 -260.75386) (xy 339.645528 -260.758497) (xy 339.633962 -260.771993) (xy 339.627787 -260.788661)
			(xy 339.627464 -260.797548) (xy 339.627464 -260.916674) (xy 339.651848 -260.959346) (xy 339.662516 -260.966204)
			(xy 339.683763 -260.980327) (xy 339.722039 -261.014057) (xy 339.754677 -261.053268) (xy 339.780902 -261.097028)
			(xy 339.800092 -261.144299) (xy 339.811789 -261.193957) (xy 339.815717 -261.244823) (xy 339.813707 -261.270809)
			(xy 340.094317 -261.270809) (xy 340.094317 -261.218875) (xy 340.102442 -261.16758) (xy 340.11849 -261.118187)
			(xy 340.142068 -261.071913) (xy 340.172594 -261.029897) (xy 340.209317 -260.993174) (xy 340.251333 -260.962648)
			(xy 340.297607 -260.93907) (xy 340.347 -260.923022) (xy 340.398295 -260.914897) (xy 340.450229 -260.914897)
			(xy 340.501524 -260.923022) (xy 340.550917 -260.93907) (xy 340.597191 -260.962648) (xy 340.639207 -260.993174)
			(xy 340.67593 -261.029897) (xy 340.706456 -261.071913) (xy 340.730034 -261.118187) (xy 340.746082 -261.16758)
			(xy 340.754207 -261.218875) (xy 340.754716 -261.244842) (xy 340.754207 -261.270809) (xy 341.034117 -261.270809)
			(xy 341.034117 -261.218875) (xy 341.042242 -261.16758) (xy 341.05829 -261.118187) (xy 341.081868 -261.071913)
			(xy 341.112394 -261.029897) (xy 341.149117 -260.993174) (xy 341.191133 -260.962648) (xy 341.237407 -260.93907)
			(xy 341.2868 -260.923022) (xy 341.338095 -260.914897) (xy 341.390029 -260.914897) (xy 341.441324 -260.923022)
			(xy 341.490717 -260.93907) (xy 341.536991 -260.962648) (xy 341.579007 -260.993174) (xy 341.61573 -261.029897)
			(xy 341.646256 -261.071913) (xy 341.669834 -261.118187) (xy 341.685882 -261.16758) (xy 341.694007 -261.218875)
			(xy 341.694516 -261.244842) (xy 341.694007 -261.270809) (xy 341.973917 -261.270809) (xy 341.973917 -261.218875)
			(xy 341.982042 -261.16758) (xy 341.99809 -261.118187) (xy 342.021668 -261.071913) (xy 342.052194 -261.029897)
			(xy 342.088917 -260.993174) (xy 342.130933 -260.962648) (xy 342.177207 -260.93907) (xy 342.2266 -260.923022)
			(xy 342.277895 -260.914897) (xy 342.329829 -260.914897) (xy 342.381124 -260.923022) (xy 342.430517 -260.93907)
			(xy 342.476791 -260.962648) (xy 342.518807 -260.993174) (xy 342.55553 -261.029897) (xy 342.586056 -261.071913)
			(xy 342.609634 -261.118187) (xy 342.625682 -261.16758) (xy 342.633807 -261.218875) (xy 342.634316 -261.244842)
			(xy 342.633807 -261.270809) (xy 342.913717 -261.270809) (xy 342.913717 -261.218875) (xy 342.921842 -261.16758)
			(xy 342.93789 -261.118187) (xy 342.961468 -261.071913) (xy 342.991994 -261.029897) (xy 343.028717 -260.993174)
			(xy 343.070733 -260.962648) (xy 343.117007 -260.93907) (xy 343.1664 -260.923022) (xy 343.217695 -260.914897)
			(xy 343.269629 -260.914897) (xy 343.320924 -260.923022) (xy 343.370317 -260.93907) (xy 343.416591 -260.962648)
			(xy 343.458607 -260.993174) (xy 343.49533 -261.029897) (xy 343.525856 -261.071913) (xy 343.549434 -261.118187)
			(xy 343.565482 -261.16758) (xy 343.573607 -261.218875) (xy 343.574116 -261.244842) (xy 343.573607 -261.270809)
			(xy 343.853517 -261.270809) (xy 343.853517 -261.218875) (xy 343.861642 -261.16758) (xy 343.87769 -261.118187)
			(xy 343.901268 -261.071913) (xy 343.931794 -261.029897) (xy 343.968517 -260.993174) (xy 344.010533 -260.962648)
			(xy 344.056807 -260.93907) (xy 344.1062 -260.923022) (xy 344.157495 -260.914897) (xy 344.209429 -260.914897)
			(xy 344.260724 -260.923022) (xy 344.310117 -260.93907) (xy 344.356391 -260.962648) (xy 344.398407 -260.993174)
			(xy 344.43513 -261.029897) (xy 344.465656 -261.071913) (xy 344.489234 -261.118187) (xy 344.505282 -261.16758)
			(xy 344.513407 -261.218875) (xy 344.513916 -261.244842) (xy 344.513407 -261.270809) (xy 344.793317 -261.270809)
			(xy 344.793317 -261.218875) (xy 344.801442 -261.16758) (xy 344.81749 -261.118187) (xy 344.841068 -261.071913)
			(xy 344.871594 -261.029897) (xy 344.908317 -260.993174) (xy 344.950333 -260.962648) (xy 344.996607 -260.93907)
			(xy 345.046 -260.923022) (xy 345.097295 -260.914897) (xy 345.149229 -260.914897) (xy 345.200524 -260.923022)
			(xy 345.249917 -260.93907) (xy 345.296191 -260.962648) (xy 345.338207 -260.993174) (xy 345.37493 -261.029897)
			(xy 345.405456 -261.071913) (xy 345.429034 -261.118187) (xy 345.445082 -261.16758) (xy 345.453207 -261.218875)
			(xy 345.453716 -261.244842) (xy 345.453207 -261.270809) (xy 345.733117 -261.270809) (xy 345.733117 -261.218875)
			(xy 345.741242 -261.16758) (xy 345.75729 -261.118187) (xy 345.780868 -261.071913) (xy 345.811394 -261.029897)
			(xy 345.848117 -260.993174) (xy 345.890133 -260.962648) (xy 345.936407 -260.93907) (xy 345.9858 -260.923022)
			(xy 346.037095 -260.914897) (xy 346.089029 -260.914897) (xy 346.140324 -260.923022) (xy 346.189717 -260.93907)
			(xy 346.235991 -260.962648) (xy 346.278007 -260.993174) (xy 346.31473 -261.029897) (xy 346.345256 -261.071913)
			(xy 346.368834 -261.118187) (xy 346.384882 -261.16758) (xy 346.393007 -261.218875) (xy 346.393516 -261.244842)
			(xy 346.393007 -261.270809) (xy 346.672917 -261.270809) (xy 346.672917 -261.218875) (xy 346.681042 -261.16758)
			(xy 346.69709 -261.118187) (xy 346.720668 -261.071913) (xy 346.751194 -261.029897) (xy 346.787917 -260.993174)
			(xy 346.829933 -260.962648) (xy 346.876207 -260.93907) (xy 346.9256 -260.923022) (xy 346.976895 -260.914897)
			(xy 347.028829 -260.914897) (xy 347.080124 -260.923022) (xy 347.129517 -260.93907) (xy 347.175791 -260.962648)
			(xy 347.217807 -260.993174) (xy 347.25453 -261.029897) (xy 347.285056 -261.071913) (xy 347.308634 -261.118187)
			(xy 347.324682 -261.16758) (xy 347.332807 -261.218875) (xy 347.333316 -261.244842) (xy 347.332807 -261.270809)
			(xy 347.612717 -261.270809) (xy 347.612717 -261.218875) (xy 347.620842 -261.16758) (xy 347.63689 -261.118187)
			(xy 347.660468 -261.071913) (xy 347.690994 -261.029897) (xy 347.727717 -260.993174) (xy 347.769733 -260.962648)
			(xy 347.816007 -260.93907) (xy 347.8654 -260.923022) (xy 347.916695 -260.914897) (xy 347.968629 -260.914897)
			(xy 348.019924 -260.923022) (xy 348.069317 -260.93907) (xy 348.115591 -260.962648) (xy 348.157607 -260.993174)
			(xy 348.19433 -261.029897) (xy 348.224856 -261.071913) (xy 348.248434 -261.118187) (xy 348.264482 -261.16758)
			(xy 348.272607 -261.218875) (xy 348.273116 -261.244842) (xy 348.272607 -261.270809) (xy 348.552517 -261.270809)
			(xy 348.552517 -261.218875) (xy 348.560642 -261.16758) (xy 348.57669 -261.118187) (xy 348.600268 -261.071913)
			(xy 348.630794 -261.029897) (xy 348.667517 -260.993174) (xy 348.709533 -260.962648) (xy 348.755807 -260.93907)
			(xy 348.8052 -260.923022) (xy 348.856495 -260.914897) (xy 348.908429 -260.914897) (xy 348.959724 -260.923022)
			(xy 349.009117 -260.93907) (xy 349.055391 -260.962648) (xy 349.097407 -260.993174) (xy 349.13413 -261.029897)
			(xy 349.164656 -261.071913) (xy 349.188234 -261.118187) (xy 349.204282 -261.16758) (xy 349.212407 -261.218875)
			(xy 349.212916 -261.244842) (xy 349.212407 -261.270809) (xy 349.492317 -261.270809) (xy 349.492317 -261.218875)
			(xy 349.500442 -261.16758) (xy 349.51649 -261.118187) (xy 349.540068 -261.071913) (xy 349.570594 -261.029897)
			(xy 349.607317 -260.993174) (xy 349.649333 -260.962648) (xy 349.695607 -260.93907) (xy 349.745 -260.923022)
			(xy 349.796295 -260.914897) (xy 349.848229 -260.914897) (xy 349.899524 -260.923022) (xy 349.948917 -260.93907)
			(xy 349.995191 -260.962648) (xy 350.037207 -260.993174) (xy 350.07393 -261.029897) (xy 350.104456 -261.071913)
			(xy 350.128034 -261.118187) (xy 350.144082 -261.16758) (xy 350.152207 -261.218875) (xy 350.152716 -261.244842)
			(xy 350.152207 -261.270809) (xy 350.144082 -261.322104) (xy 350.128034 -261.371497) (xy 350.104456 -261.417771)
			(xy 350.07393 -261.459787) (xy 350.037207 -261.49651) (xy 349.995191 -261.527036) (xy 349.948917 -261.550614)
			(xy 349.899524 -261.566662) (xy 349.848229 -261.574787) (xy 349.796295 -261.574787) (xy 349.745 -261.566662)
			(xy 349.695607 -261.550614) (xy 349.649333 -261.527036) (xy 349.607317 -261.49651) (xy 349.570594 -261.459787)
			(xy 349.540068 -261.417771) (xy 349.51649 -261.371497) (xy 349.500442 -261.322104) (xy 349.492317 -261.270809)
			(xy 349.212407 -261.270809) (xy 349.204282 -261.322104) (xy 349.188234 -261.371497) (xy 349.164656 -261.417771)
			(xy 349.13413 -261.459787) (xy 349.097407 -261.49651) (xy 349.055391 -261.527036) (xy 349.009117 -261.550614)
			(xy 348.959724 -261.566662) (xy 348.908429 -261.574787) (xy 348.856495 -261.574787) (xy 348.8052 -261.566662)
			(xy 348.755807 -261.550614) (xy 348.709533 -261.527036) (xy 348.667517 -261.49651) (xy 348.630794 -261.459787)
			(xy 348.600268 -261.417771) (xy 348.57669 -261.371497) (xy 348.560642 -261.322104) (xy 348.552517 -261.270809)
			(xy 348.272607 -261.270809) (xy 348.264482 -261.322104) (xy 348.248434 -261.371497) (xy 348.224856 -261.417771)
			(xy 348.19433 -261.459787) (xy 348.157607 -261.49651) (xy 348.115591 -261.527036) (xy 348.069317 -261.550614)
			(xy 348.019924 -261.566662) (xy 347.968629 -261.574787) (xy 347.916695 -261.574787) (xy 347.8654 -261.566662)
			(xy 347.816007 -261.550614) (xy 347.769733 -261.527036) (xy 347.727717 -261.49651) (xy 347.690994 -261.459787)
			(xy 347.660468 -261.417771) (xy 347.63689 -261.371497) (xy 347.620842 -261.322104) (xy 347.612717 -261.270809)
			(xy 347.332807 -261.270809) (xy 347.324682 -261.322104) (xy 347.308634 -261.371497) (xy 347.285056 -261.417771)
			(xy 347.25453 -261.459787) (xy 347.217807 -261.49651) (xy 347.175791 -261.527036) (xy 347.129517 -261.550614)
			(xy 347.080124 -261.566662) (xy 347.028829 -261.574787) (xy 346.976895 -261.574787) (xy 346.9256 -261.566662)
			(xy 346.876207 -261.550614) (xy 346.829933 -261.527036) (xy 346.787917 -261.49651) (xy 346.751194 -261.459787)
			(xy 346.720668 -261.417771) (xy 346.69709 -261.371497) (xy 346.681042 -261.322104) (xy 346.672917 -261.270809)
			(xy 346.393007 -261.270809) (xy 346.384882 -261.322104) (xy 346.368834 -261.371497) (xy 346.345256 -261.417771)
			(xy 346.31473 -261.459787) (xy 346.278007 -261.49651) (xy 346.235991 -261.527036) (xy 346.189717 -261.550614)
			(xy 346.140324 -261.566662) (xy 346.089029 -261.574787) (xy 346.037095 -261.574787) (xy 345.9858 -261.566662)
			(xy 345.936407 -261.550614) (xy 345.890133 -261.527036) (xy 345.848117 -261.49651) (xy 345.811394 -261.459787)
			(xy 345.780868 -261.417771) (xy 345.75729 -261.371497) (xy 345.741242 -261.322104) (xy 345.733117 -261.270809)
			(xy 345.453207 -261.270809) (xy 345.445082 -261.322104) (xy 345.429034 -261.371497) (xy 345.405456 -261.417771)
			(xy 345.37493 -261.459787) (xy 345.338207 -261.49651) (xy 345.296191 -261.527036) (xy 345.249917 -261.550614)
			(xy 345.200524 -261.566662) (xy 345.149229 -261.574787) (xy 345.097295 -261.574787) (xy 345.046 -261.566662)
			(xy 344.996607 -261.550614) (xy 344.950333 -261.527036) (xy 344.908317 -261.49651) (xy 344.871594 -261.459787)
			(xy 344.841068 -261.417771) (xy 344.81749 -261.371497) (xy 344.801442 -261.322104) (xy 344.793317 -261.270809)
			(xy 344.513407 -261.270809) (xy 344.505282 -261.322104) (xy 344.489234 -261.371497) (xy 344.465656 -261.417771)
			(xy 344.43513 -261.459787) (xy 344.398407 -261.49651) (xy 344.356391 -261.527036) (xy 344.310117 -261.550614)
			(xy 344.260724 -261.566662) (xy 344.209429 -261.574787) (xy 344.157495 -261.574787) (xy 344.1062 -261.566662)
			(xy 344.056807 -261.550614) (xy 344.010533 -261.527036) (xy 343.968517 -261.49651) (xy 343.931794 -261.459787)
			(xy 343.901268 -261.417771) (xy 343.87769 -261.371497) (xy 343.861642 -261.322104) (xy 343.853517 -261.270809)
			(xy 343.573607 -261.270809) (xy 343.565482 -261.322104) (xy 343.549434 -261.371497) (xy 343.525856 -261.417771)
			(xy 343.49533 -261.459787) (xy 343.458607 -261.49651) (xy 343.416591 -261.527036) (xy 343.370317 -261.550614)
			(xy 343.320924 -261.566662) (xy 343.269629 -261.574787) (xy 343.217695 -261.574787) (xy 343.1664 -261.566662)
			(xy 343.117007 -261.550614) (xy 343.070733 -261.527036) (xy 343.028717 -261.49651) (xy 342.991994 -261.459787)
			(xy 342.961468 -261.417771) (xy 342.93789 -261.371497) (xy 342.921842 -261.322104) (xy 342.913717 -261.270809)
			(xy 342.633807 -261.270809) (xy 342.625682 -261.322104) (xy 342.609634 -261.371497) (xy 342.586056 -261.417771)
			(xy 342.55553 -261.459787) (xy 342.518807 -261.49651) (xy 342.476791 -261.527036) (xy 342.430517 -261.550614)
			(xy 342.381124 -261.566662) (xy 342.329829 -261.574787) (xy 342.277895 -261.574787) (xy 342.2266 -261.566662)
			(xy 342.177207 -261.550614) (xy 342.130933 -261.527036) (xy 342.088917 -261.49651) (xy 342.052194 -261.459787)
			(xy 342.021668 -261.417771) (xy 341.99809 -261.371497) (xy 341.982042 -261.322104) (xy 341.973917 -261.270809)
			(xy 341.694007 -261.270809) (xy 341.685882 -261.322104) (xy 341.669834 -261.371497) (xy 341.646256 -261.417771)
			(xy 341.61573 -261.459787) (xy 341.579007 -261.49651) (xy 341.536991 -261.527036) (xy 341.490717 -261.550614)
			(xy 341.441324 -261.566662) (xy 341.390029 -261.574787) (xy 341.338095 -261.574787) (xy 341.2868 -261.566662)
			(xy 341.237407 -261.550614) (xy 341.191133 -261.527036) (xy 341.149117 -261.49651) (xy 341.112394 -261.459787)
			(xy 341.081868 -261.417771) (xy 341.05829 -261.371497) (xy 341.042242 -261.322104) (xy 341.034117 -261.270809)
			(xy 340.754207 -261.270809) (xy 340.746082 -261.322104) (xy 340.730034 -261.371497) (xy 340.706456 -261.417771)
			(xy 340.67593 -261.459787) (xy 340.639207 -261.49651) (xy 340.597191 -261.527036) (xy 340.550917 -261.550614)
			(xy 340.501524 -261.566662) (xy 340.450229 -261.574787) (xy 340.398295 -261.574787) (xy 340.347 -261.566662)
			(xy 340.297607 -261.550614) (xy 340.251333 -261.527036) (xy 340.209317 -261.49651) (xy 340.172594 -261.459787)
			(xy 340.142068 -261.417771) (xy 340.11849 -261.371497) (xy 340.102442 -261.322104) (xy 340.094317 -261.270809)
			(xy 339.813707 -261.270809) (xy 339.811782 -261.295688) (xy 339.800078 -261.345344) (xy 339.780882 -261.392612)
			(xy 339.754651 -261.436369) (xy 339.722008 -261.475576) (xy 339.683727 -261.5093) (xy 339.662516 -261.52348)
			(xy 339.651848 -261.530338) (xy 339.627464 -261.57301) (xy 339.627464 -261.692136) (xy 339.627786 -261.700519)
			(xy 339.633295 -261.716354) (xy 339.643691 -261.729508) (xy 339.650578 -261.7343) (xy 339.718142 -261.772146)
			(xy 339.723391 -261.774634) (xy 339.734687 -261.777331) (xy 339.740494 -261.77748) (xy 339.76691 -261.77748)
			(xy 339.791294 -261.770876) (xy 339.795612 -261.76859) (xy 339.820106 -261.755823) (xy 339.872287 -261.737724)
			(xy 339.926747 -261.728527) (xy 339.954362 -261.72795) (xy 339.954616 -261.72795) (xy 339.980606 -261.728461)
			(xy 340.031945 -261.736594) (xy 340.081379 -261.752659) (xy 340.127693 -261.776259) (xy 340.169744 -261.806813)
			(xy 340.206498 -261.843568) (xy 340.23705 -261.885621) (xy 340.260647 -261.931935) (xy 340.276709 -261.981371)
			(xy 340.28484 -262.03271) (xy 340.28484 -262.084625) (xy 340.564471 -262.084625) (xy 340.564471 -262.032691)
			(xy 340.572596 -261.981396) (xy 340.588644 -261.932003) (xy 340.612222 -261.885729) (xy 340.642748 -261.843713)
			(xy 340.679471 -261.80699) (xy 340.721487 -261.776464) (xy 340.767761 -261.752886) (xy 340.817154 -261.736838)
			(xy 340.868449 -261.728713) (xy 340.920383 -261.728713) (xy 340.971678 -261.736838) (xy 341.021071 -261.752886)
			(xy 341.067345 -261.776464) (xy 341.109361 -261.80699) (xy 341.146084 -261.843713) (xy 341.17661 -261.885729)
			(xy 341.200188 -261.932003) (xy 341.216236 -261.981396) (xy 341.224361 -262.032691) (xy 341.22487 -262.058658)
			(xy 341.224361 -262.084625) (xy 341.504271 -262.084625) (xy 341.504271 -262.032691) (xy 341.512396 -261.981396)
			(xy 341.528444 -261.932003) (xy 341.552022 -261.885729) (xy 341.582548 -261.843713) (xy 341.619271 -261.80699)
			(xy 341.661287 -261.776464) (xy 341.707561 -261.752886) (xy 341.756954 -261.736838) (xy 341.808249 -261.728713)
			(xy 341.860183 -261.728713) (xy 341.911478 -261.736838) (xy 341.960871 -261.752886) (xy 342.007145 -261.776464)
			(xy 342.049161 -261.80699) (xy 342.085884 -261.843713) (xy 342.11641 -261.885729) (xy 342.139988 -261.932003)
			(xy 342.156036 -261.981396) (xy 342.164161 -262.032691) (xy 342.16467 -262.058658) (xy 342.164161 -262.084625)
			(xy 342.444071 -262.084625) (xy 342.444071 -262.032691) (xy 342.452196 -261.981396) (xy 342.468244 -261.932003)
			(xy 342.491822 -261.885729) (xy 342.522348 -261.843713) (xy 342.559071 -261.80699) (xy 342.601087 -261.776464)
			(xy 342.647361 -261.752886) (xy 342.696754 -261.736838) (xy 342.748049 -261.728713) (xy 342.799983 -261.728713)
			(xy 342.851278 -261.736838) (xy 342.900671 -261.752886) (xy 342.946945 -261.776464) (xy 342.988961 -261.80699)
			(xy 343.025684 -261.843713) (xy 343.05621 -261.885729) (xy 343.079788 -261.932003) (xy 343.095836 -261.981396)
			(xy 343.103961 -262.032691) (xy 343.10447 -262.058658) (xy 343.103961 -262.084625) (xy 343.383871 -262.084625)
			(xy 343.383871 -262.032691) (xy 343.391996 -261.981396) (xy 343.408044 -261.932003) (xy 343.431622 -261.885729)
			(xy 343.462148 -261.843713) (xy 343.498871 -261.80699) (xy 343.540887 -261.776464) (xy 343.587161 -261.752886)
			(xy 343.636554 -261.736838) (xy 343.687849 -261.728713) (xy 343.739783 -261.728713) (xy 343.791078 -261.736838)
			(xy 343.840471 -261.752886) (xy 343.886745 -261.776464) (xy 343.928761 -261.80699) (xy 343.965484 -261.843713)
			(xy 343.99601 -261.885729) (xy 344.019588 -261.932003) (xy 344.035636 -261.981396) (xy 344.043761 -262.032691)
			(xy 344.04427 -262.058658) (xy 344.043761 -262.084625) (xy 344.323671 -262.084625) (xy 344.323671 -262.032691)
			(xy 344.331796 -261.981396) (xy 344.347844 -261.932003) (xy 344.371422 -261.885729) (xy 344.401948 -261.843713)
			(xy 344.438671 -261.80699) (xy 344.480687 -261.776464) (xy 344.526961 -261.752886) (xy 344.576354 -261.736838)
			(xy 344.627649 -261.728713) (xy 344.679583 -261.728713) (xy 344.730878 -261.736838) (xy 344.780271 -261.752886)
			(xy 344.826545 -261.776464) (xy 344.868561 -261.80699) (xy 344.905284 -261.843713) (xy 344.93581 -261.885729)
			(xy 344.959388 -261.932003) (xy 344.975436 -261.981396) (xy 344.983561 -262.032691) (xy 344.98407 -262.058658)
			(xy 344.983561 -262.084625) (xy 345.263217 -262.084625) (xy 345.263217 -262.032691) (xy 345.271342 -261.981396)
			(xy 345.28739 -261.932003) (xy 345.310968 -261.885729) (xy 345.341494 -261.843713) (xy 345.378217 -261.80699)
			(xy 345.420233 -261.776464) (xy 345.466507 -261.752886) (xy 345.5159 -261.736838) (xy 345.567195 -261.728713)
			(xy 345.619129 -261.728713) (xy 345.670424 -261.736838) (xy 345.719817 -261.752886) (xy 345.766091 -261.776464)
			(xy 345.808107 -261.80699) (xy 345.84483 -261.843713) (xy 345.875356 -261.885729) (xy 345.898934 -261.932003)
			(xy 345.914982 -261.981396) (xy 345.923107 -262.032691) (xy 345.923616 -262.058658) (xy 345.923107 -262.084625)
			(xy 346.203271 -262.084625) (xy 346.203271 -262.032691) (xy 346.211396 -261.981396) (xy 346.227444 -261.932003)
			(xy 346.251022 -261.885729) (xy 346.281548 -261.843713) (xy 346.318271 -261.80699) (xy 346.360287 -261.776464)
			(xy 346.406561 -261.752886) (xy 346.455954 -261.736838) (xy 346.507249 -261.728713) (xy 346.559183 -261.728713)
			(xy 346.610478 -261.736838) (xy 346.659871 -261.752886) (xy 346.706145 -261.776464) (xy 346.748161 -261.80699)
			(xy 346.784884 -261.843713) (xy 346.81541 -261.885729) (xy 346.838988 -261.932003) (xy 346.855036 -261.981396)
			(xy 346.863161 -262.032691) (xy 346.86367 -262.058658) (xy 346.863161 -262.084625) (xy 347.143071 -262.084625)
			(xy 347.143071 -262.032691) (xy 347.151196 -261.981396) (xy 347.167244 -261.932003) (xy 347.190822 -261.885729)
			(xy 347.221348 -261.843713) (xy 347.258071 -261.80699) (xy 347.300087 -261.776464) (xy 347.346361 -261.752886)
			(xy 347.395754 -261.736838) (xy 347.447049 -261.728713) (xy 347.498983 -261.728713) (xy 347.550278 -261.736838)
			(xy 347.599671 -261.752886) (xy 347.645945 -261.776464) (xy 347.687961 -261.80699) (xy 347.724684 -261.843713)
			(xy 347.75521 -261.885729) (xy 347.778788 -261.932003) (xy 347.794836 -261.981396) (xy 347.802961 -262.032691)
			(xy 347.80347 -262.058658) (xy 347.802961 -262.084625) (xy 348.082871 -262.084625) (xy 348.082871 -262.032691)
			(xy 348.090996 -261.981396) (xy 348.107044 -261.932003) (xy 348.130622 -261.885729) (xy 348.161148 -261.843713)
			(xy 348.197871 -261.80699) (xy 348.239887 -261.776464) (xy 348.286161 -261.752886) (xy 348.335554 -261.736838)
			(xy 348.386849 -261.728713) (xy 348.438783 -261.728713) (xy 348.490078 -261.736838) (xy 348.539471 -261.752886)
			(xy 348.585745 -261.776464) (xy 348.627761 -261.80699) (xy 348.664484 -261.843713) (xy 348.69501 -261.885729)
			(xy 348.718588 -261.932003) (xy 348.734636 -261.981396) (xy 348.742761 -262.032691) (xy 348.74327 -262.058658)
			(xy 348.742761 -262.084625) (xy 349.022671 -262.084625) (xy 349.022671 -262.032691) (xy 349.030796 -261.981396)
			(xy 349.046844 -261.932003) (xy 349.070422 -261.885729) (xy 349.100948 -261.843713) (xy 349.137671 -261.80699)
			(xy 349.179687 -261.776464) (xy 349.225961 -261.752886) (xy 349.275354 -261.736838) (xy 349.326649 -261.728713)
			(xy 349.378583 -261.728713) (xy 349.429878 -261.736838) (xy 349.479271 -261.752886) (xy 349.525545 -261.776464)
			(xy 349.567561 -261.80699) (xy 349.604284 -261.843713) (xy 349.63481 -261.885729) (xy 349.658388 -261.932003)
			(xy 349.674436 -261.981396) (xy 349.682561 -262.032691) (xy 349.68307 -262.058658) (xy 349.682561 -262.084625)
			(xy 349.962471 -262.084625) (xy 349.962471 -262.032691) (xy 349.970596 -261.981396) (xy 349.986644 -261.932003)
			(xy 350.010222 -261.885729) (xy 350.040748 -261.843713) (xy 350.077471 -261.80699) (xy 350.119487 -261.776464)
			(xy 350.165761 -261.752886) (xy 350.215154 -261.736838) (xy 350.266449 -261.728713) (xy 350.318383 -261.728713)
			(xy 350.369678 -261.736838) (xy 350.419071 -261.752886) (xy 350.465345 -261.776464) (xy 350.507361 -261.80699)
			(xy 350.544084 -261.843713) (xy 350.57461 -261.885729) (xy 350.598188 -261.932003) (xy 350.614236 -261.981396)
			(xy 350.622361 -262.032691) (xy 350.62287 -262.058658) (xy 350.622361 -262.084625) (xy 350.614236 -262.13592)
			(xy 350.598188 -262.185313) (xy 350.57461 -262.231587) (xy 350.544084 -262.273603) (xy 350.507361 -262.310326)
			(xy 350.465345 -262.340852) (xy 350.419071 -262.36443) (xy 350.369678 -262.380478) (xy 350.318383 -262.388603)
			(xy 350.266449 -262.388603) (xy 350.215154 -262.380478) (xy 350.165761 -262.36443) (xy 350.119487 -262.340852)
			(xy 350.077471 -262.310326) (xy 350.040748 -262.273603) (xy 350.010222 -262.231587) (xy 349.986644 -262.185313)
			(xy 349.970596 -262.13592) (xy 349.962471 -262.084625) (xy 349.682561 -262.084625) (xy 349.674436 -262.13592)
			(xy 349.658388 -262.185313) (xy 349.63481 -262.231587) (xy 349.604284 -262.273603) (xy 349.567561 -262.310326)
			(xy 349.525545 -262.340852) (xy 349.479271 -262.36443) (xy 349.429878 -262.380478) (xy 349.378583 -262.388603)
			(xy 349.326649 -262.388603) (xy 349.275354 -262.380478) (xy 349.225961 -262.36443) (xy 349.179687 -262.340852)
			(xy 349.137671 -262.310326) (xy 349.100948 -262.273603) (xy 349.070422 -262.231587) (xy 349.046844 -262.185313)
			(xy 349.030796 -262.13592) (xy 349.022671 -262.084625) (xy 348.742761 -262.084625) (xy 348.734636 -262.13592)
			(xy 348.718588 -262.185313) (xy 348.69501 -262.231587) (xy 348.664484 -262.273603) (xy 348.627761 -262.310326)
			(xy 348.585745 -262.340852) (xy 348.539471 -262.36443) (xy 348.490078 -262.380478) (xy 348.438783 -262.388603)
			(xy 348.386849 -262.388603) (xy 348.335554 -262.380478) (xy 348.286161 -262.36443) (xy 348.239887 -262.340852)
			(xy 348.197871 -262.310326) (xy 348.161148 -262.273603) (xy 348.130622 -262.231587) (xy 348.107044 -262.185313)
			(xy 348.090996 -262.13592) (xy 348.082871 -262.084625) (xy 347.802961 -262.084625) (xy 347.794836 -262.13592)
			(xy 347.778788 -262.185313) (xy 347.75521 -262.231587) (xy 347.724684 -262.273603) (xy 347.687961 -262.310326)
			(xy 347.645945 -262.340852) (xy 347.599671 -262.36443) (xy 347.550278 -262.380478) (xy 347.498983 -262.388603)
			(xy 347.447049 -262.388603) (xy 347.395754 -262.380478) (xy 347.346361 -262.36443) (xy 347.300087 -262.340852)
			(xy 347.258071 -262.310326) (xy 347.221348 -262.273603) (xy 347.190822 -262.231587) (xy 347.167244 -262.185313)
			(xy 347.151196 -262.13592) (xy 347.143071 -262.084625) (xy 346.863161 -262.084625) (xy 346.855036 -262.13592)
			(xy 346.838988 -262.185313) (xy 346.81541 -262.231587) (xy 346.784884 -262.273603) (xy 346.748161 -262.310326)
			(xy 346.706145 -262.340852) (xy 346.659871 -262.36443) (xy 346.610478 -262.380478) (xy 346.559183 -262.388603)
			(xy 346.507249 -262.388603) (xy 346.455954 -262.380478) (xy 346.406561 -262.36443) (xy 346.360287 -262.340852)
			(xy 346.318271 -262.310326) (xy 346.281548 -262.273603) (xy 346.251022 -262.231587) (xy 346.227444 -262.185313)
			(xy 346.211396 -262.13592) (xy 346.203271 -262.084625) (xy 345.923107 -262.084625) (xy 345.914982 -262.13592)
			(xy 345.898934 -262.185313) (xy 345.875356 -262.231587) (xy 345.84483 -262.273603) (xy 345.808107 -262.310326)
			(xy 345.766091 -262.340852) (xy 345.719817 -262.36443) (xy 345.670424 -262.380478) (xy 345.619129 -262.388603)
			(xy 345.567195 -262.388603) (xy 345.5159 -262.380478) (xy 345.466507 -262.36443) (xy 345.420233 -262.340852)
			(xy 345.378217 -262.310326) (xy 345.341494 -262.273603) (xy 345.310968 -262.231587) (xy 345.28739 -262.185313)
			(xy 345.271342 -262.13592) (xy 345.263217 -262.084625) (xy 344.983561 -262.084625) (xy 344.975436 -262.13592)
			(xy 344.959388 -262.185313) (xy 344.93581 -262.231587) (xy 344.905284 -262.273603) (xy 344.868561 -262.310326)
			(xy 344.826545 -262.340852) (xy 344.780271 -262.36443) (xy 344.730878 -262.380478) (xy 344.679583 -262.388603)
			(xy 344.627649 -262.388603) (xy 344.576354 -262.380478) (xy 344.526961 -262.36443) (xy 344.480687 -262.340852)
			(xy 344.438671 -262.310326) (xy 344.401948 -262.273603) (xy 344.371422 -262.231587) (xy 344.347844 -262.185313)
			(xy 344.331796 -262.13592) (xy 344.323671 -262.084625) (xy 344.043761 -262.084625) (xy 344.035636 -262.13592)
			(xy 344.019588 -262.185313) (xy 343.99601 -262.231587) (xy 343.965484 -262.273603) (xy 343.928761 -262.310326)
			(xy 343.886745 -262.340852) (xy 343.840471 -262.36443) (xy 343.791078 -262.380478) (xy 343.739783 -262.388603)
			(xy 343.687849 -262.388603) (xy 343.636554 -262.380478) (xy 343.587161 -262.36443) (xy 343.540887 -262.340852)
			(xy 343.498871 -262.310326) (xy 343.462148 -262.273603) (xy 343.431622 -262.231587) (xy 343.408044 -262.185313)
			(xy 343.391996 -262.13592) (xy 343.383871 -262.084625) (xy 343.103961 -262.084625) (xy 343.095836 -262.13592)
			(xy 343.079788 -262.185313) (xy 343.05621 -262.231587) (xy 343.025684 -262.273603) (xy 342.988961 -262.310326)
			(xy 342.946945 -262.340852) (xy 342.900671 -262.36443) (xy 342.851278 -262.380478) (xy 342.799983 -262.388603)
			(xy 342.748049 -262.388603) (xy 342.696754 -262.380478) (xy 342.647361 -262.36443) (xy 342.601087 -262.340852)
			(xy 342.559071 -262.310326) (xy 342.522348 -262.273603) (xy 342.491822 -262.231587) (xy 342.468244 -262.185313)
			(xy 342.452196 -262.13592) (xy 342.444071 -262.084625) (xy 342.164161 -262.084625) (xy 342.156036 -262.13592)
			(xy 342.139988 -262.185313) (xy 342.11641 -262.231587) (xy 342.085884 -262.273603) (xy 342.049161 -262.310326)
			(xy 342.007145 -262.340852) (xy 341.960871 -262.36443) (xy 341.911478 -262.380478) (xy 341.860183 -262.388603)
			(xy 341.808249 -262.388603) (xy 341.756954 -262.380478) (xy 341.707561 -262.36443) (xy 341.661287 -262.340852)
			(xy 341.619271 -262.310326) (xy 341.582548 -262.273603) (xy 341.552022 -262.231587) (xy 341.528444 -262.185313)
			(xy 341.512396 -262.13592) (xy 341.504271 -262.084625) (xy 341.224361 -262.084625) (xy 341.216236 -262.13592)
			(xy 341.200188 -262.185313) (xy 341.17661 -262.231587) (xy 341.146084 -262.273603) (xy 341.109361 -262.310326)
			(xy 341.067345 -262.340852) (xy 341.021071 -262.36443) (xy 340.971678 -262.380478) (xy 340.920383 -262.388603)
			(xy 340.868449 -262.388603) (xy 340.817154 -262.380478) (xy 340.767761 -262.36443) (xy 340.721487 -262.340852)
			(xy 340.679471 -262.310326) (xy 340.642748 -262.273603) (xy 340.612222 -262.231587) (xy 340.588644 -262.185313)
			(xy 340.572596 -262.13592) (xy 340.564471 -262.084625) (xy 340.28484 -262.084625) (xy 340.28484 -262.08469)
			(xy 340.276709 -262.136029) (xy 340.260647 -262.185465) (xy 340.23705 -262.231779) (xy 340.206498 -262.273832)
			(xy 340.169744 -262.310587) (xy 340.127693 -262.341141) (xy 340.081379 -262.364741) (xy 340.031945 -262.380806)
			(xy 339.980606 -262.388939) (xy 339.954616 -262.389366) (xy 339.931701 -262.388975) (xy 339.886311 -262.382641)
			(xy 339.842233 -262.370091) (xy 339.800314 -262.351568) (xy 339.780626 -262.339836) (xy 339.780372 -262.339836)
			(xy 339.772614 -262.33544) (xy 339.755157 -262.331871) (xy 339.737543 -262.33457) (xy 339.729572 -262.338566)
			(xy 339.691218 -262.360156) (xy 339.65134 -262.382508) (xy 339.644247 -262.387267) (xy 339.63352 -262.400546)
			(xy 339.627845 -262.416644) (xy 339.627464 -262.42518) (xy 339.627464 -262.544306) (xy 339.651848 -262.586978)
			(xy 339.662516 -262.593836) (xy 339.683769 -262.607959) (xy 339.722055 -262.641691) (xy 339.754703 -262.680905)
			(xy 339.780937 -262.72467) (xy 339.800135 -262.771947) (xy 339.81184 -262.821612) (xy 339.815774 -262.872486)
			(xy 339.813769 -262.898441) (xy 340.094317 -262.898441) (xy 340.094317 -262.846507) (xy 340.102442 -262.795212)
			(xy 340.11849 -262.745819) (xy 340.142068 -262.699545) (xy 340.172594 -262.657529) (xy 340.209317 -262.620806)
			(xy 340.251333 -262.59028) (xy 340.297607 -262.566702) (xy 340.347 -262.550654) (xy 340.398295 -262.542529)
			(xy 340.450229 -262.542529) (xy 340.501524 -262.550654) (xy 340.550917 -262.566702) (xy 340.597191 -262.59028)
			(xy 340.639207 -262.620806) (xy 340.67593 -262.657529) (xy 340.706456 -262.699545) (xy 340.730034 -262.745819)
			(xy 340.746082 -262.795212) (xy 340.754207 -262.846507) (xy 340.754716 -262.872474) (xy 340.754207 -262.898441)
			(xy 341.034117 -262.898441) (xy 341.034117 -262.846507) (xy 341.042242 -262.795212) (xy 341.05829 -262.745819)
			(xy 341.081868 -262.699545) (xy 341.112394 -262.657529) (xy 341.149117 -262.620806) (xy 341.191133 -262.59028)
			(xy 341.237407 -262.566702) (xy 341.2868 -262.550654) (xy 341.338095 -262.542529) (xy 341.390029 -262.542529)
			(xy 341.441324 -262.550654) (xy 341.490717 -262.566702) (xy 341.536991 -262.59028) (xy 341.579007 -262.620806)
			(xy 341.61573 -262.657529) (xy 341.646256 -262.699545) (xy 341.669834 -262.745819) (xy 341.685882 -262.795212)
			(xy 341.694007 -262.846507) (xy 341.694516 -262.872474) (xy 341.694007 -262.898441) (xy 341.973917 -262.898441)
			(xy 341.973917 -262.846507) (xy 341.982042 -262.795212) (xy 341.99809 -262.745819) (xy 342.021668 -262.699545)
			(xy 342.052194 -262.657529) (xy 342.088917 -262.620806) (xy 342.130933 -262.59028) (xy 342.177207 -262.566702)
			(xy 342.2266 -262.550654) (xy 342.277895 -262.542529) (xy 342.329829 -262.542529) (xy 342.381124 -262.550654)
			(xy 342.430517 -262.566702) (xy 342.476791 -262.59028) (xy 342.518807 -262.620806) (xy 342.55553 -262.657529)
			(xy 342.586056 -262.699545) (xy 342.609634 -262.745819) (xy 342.625682 -262.795212) (xy 342.633807 -262.846507)
			(xy 342.634316 -262.872474) (xy 342.633807 -262.898441) (xy 342.913717 -262.898441) (xy 342.913717 -262.846507)
			(xy 342.921842 -262.795212) (xy 342.93789 -262.745819) (xy 342.961468 -262.699545) (xy 342.991994 -262.657529)
			(xy 343.028717 -262.620806) (xy 343.070733 -262.59028) (xy 343.117007 -262.566702) (xy 343.1664 -262.550654)
			(xy 343.217695 -262.542529) (xy 343.269629 -262.542529) (xy 343.320924 -262.550654) (xy 343.370317 -262.566702)
			(xy 343.416591 -262.59028) (xy 343.458607 -262.620806) (xy 343.49533 -262.657529) (xy 343.525856 -262.699545)
			(xy 343.549434 -262.745819) (xy 343.565482 -262.795212) (xy 343.573607 -262.846507) (xy 343.574116 -262.872474)
			(xy 343.573607 -262.898441) (xy 343.853517 -262.898441) (xy 343.853517 -262.846507) (xy 343.861642 -262.795212)
			(xy 343.87769 -262.745819) (xy 343.901268 -262.699545) (xy 343.931794 -262.657529) (xy 343.968517 -262.620806)
			(xy 344.010533 -262.59028) (xy 344.056807 -262.566702) (xy 344.1062 -262.550654) (xy 344.157495 -262.542529)
			(xy 344.209429 -262.542529) (xy 344.260724 -262.550654) (xy 344.310117 -262.566702) (xy 344.356391 -262.59028)
			(xy 344.398407 -262.620806) (xy 344.43513 -262.657529) (xy 344.465656 -262.699545) (xy 344.489234 -262.745819)
			(xy 344.505282 -262.795212) (xy 344.513407 -262.846507) (xy 344.513916 -262.872474) (xy 344.513407 -262.898441)
			(xy 344.793571 -262.898441) (xy 344.793571 -262.846507) (xy 344.801696 -262.795212) (xy 344.817744 -262.745819)
			(xy 344.841322 -262.699545) (xy 344.871848 -262.657529) (xy 344.908571 -262.620806) (xy 344.950587 -262.59028)
			(xy 344.996861 -262.566702) (xy 345.046254 -262.550654) (xy 345.097549 -262.542529) (xy 345.149483 -262.542529)
			(xy 345.200778 -262.550654) (xy 345.250171 -262.566702) (xy 345.296445 -262.59028) (xy 345.338461 -262.620806)
			(xy 345.375184 -262.657529) (xy 345.40571 -262.699545) (xy 345.429288 -262.745819) (xy 345.445336 -262.795212)
			(xy 345.453461 -262.846507) (xy 345.45397 -262.872474) (xy 345.453461 -262.898441) (xy 345.733117 -262.898441)
			(xy 345.733117 -262.846507) (xy 345.741242 -262.795212) (xy 345.75729 -262.745819) (xy 345.780868 -262.699545)
			(xy 345.811394 -262.657529) (xy 345.848117 -262.620806) (xy 345.890133 -262.59028) (xy 345.936407 -262.566702)
			(xy 345.9858 -262.550654) (xy 346.037095 -262.542529) (xy 346.089029 -262.542529) (xy 346.140324 -262.550654)
			(xy 346.189717 -262.566702) (xy 346.235991 -262.59028) (xy 346.278007 -262.620806) (xy 346.31473 -262.657529)
			(xy 346.345256 -262.699545) (xy 346.368834 -262.745819) (xy 346.384882 -262.795212) (xy 346.393007 -262.846507)
			(xy 346.393516 -262.872474) (xy 346.393007 -262.898441) (xy 346.672917 -262.898441) (xy 346.672917 -262.846507)
			(xy 346.681042 -262.795212) (xy 346.69709 -262.745819) (xy 346.720668 -262.699545) (xy 346.751194 -262.657529)
			(xy 346.787917 -262.620806) (xy 346.829933 -262.59028) (xy 346.876207 -262.566702) (xy 346.9256 -262.550654)
			(xy 346.976895 -262.542529) (xy 347.028829 -262.542529) (xy 347.080124 -262.550654) (xy 347.129517 -262.566702)
			(xy 347.175791 -262.59028) (xy 347.217807 -262.620806) (xy 347.25453 -262.657529) (xy 347.285056 -262.699545)
			(xy 347.308634 -262.745819) (xy 347.324682 -262.795212) (xy 347.332807 -262.846507) (xy 347.333316 -262.872474)
			(xy 347.332807 -262.898441) (xy 347.612717 -262.898441) (xy 347.612717 -262.846507) (xy 347.620842 -262.795212)
			(xy 347.63689 -262.745819) (xy 347.660468 -262.699545) (xy 347.690994 -262.657529) (xy 347.727717 -262.620806)
			(xy 347.769733 -262.59028) (xy 347.816007 -262.566702) (xy 347.8654 -262.550654) (xy 347.916695 -262.542529)
			(xy 347.968629 -262.542529) (xy 348.019924 -262.550654) (xy 348.069317 -262.566702) (xy 348.115591 -262.59028)
			(xy 348.157607 -262.620806) (xy 348.19433 -262.657529) (xy 348.224856 -262.699545) (xy 348.248434 -262.745819)
			(xy 348.264482 -262.795212) (xy 348.272607 -262.846507) (xy 348.273116 -262.872474) (xy 348.272607 -262.898441)
			(xy 348.552517 -262.898441) (xy 348.552517 -262.846507) (xy 348.560642 -262.795212) (xy 348.57669 -262.745819)
			(xy 348.600268 -262.699545) (xy 348.630794 -262.657529) (xy 348.667517 -262.620806) (xy 348.709533 -262.59028)
			(xy 348.755807 -262.566702) (xy 348.8052 -262.550654) (xy 348.856495 -262.542529) (xy 348.908429 -262.542529)
			(xy 348.959724 -262.550654) (xy 349.009117 -262.566702) (xy 349.055391 -262.59028) (xy 349.097407 -262.620806)
			(xy 349.13413 -262.657529) (xy 349.164656 -262.699545) (xy 349.167221 -262.70458) (xy 351.32391 -262.70458)
			(xy 351.32391 -262.704326) (xy 351.324375 -262.6798) (xy 351.331634 -262.631287) (xy 351.345982 -262.58438)
			(xy 351.367105 -262.540108) (xy 351.394537 -262.499444) (xy 351.410778 -262.48106) (xy 351.420601 -262.469586)
			(xy 351.433612 -262.442343) (xy 351.438076 -262.412485) (xy 351.433603 -262.382628) (xy 351.420584 -262.355389)
			(xy 351.410778 -262.3439) (xy 351.39451 -262.325538) (xy 351.367068 -262.284873) (xy 351.345943 -262.240597)
			(xy 351.331599 -262.193683) (xy 351.324353 -262.145163) (xy 351.32391 -262.120634) (xy 351.32391 -262.12038)
			(xy 351.324419 -262.094413) (xy 351.332544 -262.043118) (xy 351.348592 -261.993725) (xy 351.37217 -261.947451)
			(xy 351.402696 -261.905435) (xy 351.439419 -261.868712) (xy 351.481435 -261.838186) (xy 351.527709 -261.814608)
			(xy 351.577102 -261.79856) (xy 351.628397 -261.790435) (xy 351.680331 -261.790435) (xy 351.731626 -261.79856)
			(xy 351.781019 -261.814608) (xy 351.827293 -261.838186) (xy 351.869309 -261.868712) (xy 351.906032 -261.905435)
			(xy 351.936558 -261.947451) (xy 351.960136 -261.993725) (xy 351.976184 -262.043118) (xy 351.984309 -262.094413)
			(xy 351.984818 -262.12038) (xy 351.984818 -262.120634) (xy 351.984382 -262.145161) (xy 351.977115 -262.193674)
			(xy 351.962759 -262.240582) (xy 351.941631 -262.284853) (xy 351.914193 -262.325517) (xy 351.89795 -262.3439)
			(xy 351.888164 -262.355403) (xy 351.875145 -262.382635) (xy 351.870671 -262.412485) (xy 351.875136 -262.442337)
			(xy 351.888147 -262.469572) (xy 351.89795 -262.48106) (xy 351.914188 -262.499449) (xy 351.941636 -262.540105)
			(xy 351.962768 -262.584374) (xy 351.977119 -262.631283) (xy 351.984372 -262.679799) (xy 351.984818 -262.704326)
			(xy 351.984818 -262.70458) (xy 351.984309 -262.730547) (xy 351.976184 -262.781842) (xy 351.960136 -262.831235)
			(xy 351.936558 -262.877509) (xy 351.906032 -262.919525) (xy 351.869309 -262.956248) (xy 351.827293 -262.986774)
			(xy 351.781019 -263.010352) (xy 351.731626 -263.0264) (xy 351.680331 -263.034525) (xy 351.628397 -263.034525)
			(xy 351.577102 -263.0264) (xy 351.527709 -263.010352) (xy 351.481435 -262.986774) (xy 351.439419 -262.956248)
			(xy 351.402696 -262.919525) (xy 351.37217 -262.877509) (xy 351.348592 -262.831235) (xy 351.332544 -262.781842)
			(xy 351.324419 -262.730547) (xy 351.32391 -262.70458) (xy 349.167221 -262.70458) (xy 349.188234 -262.745819)
			(xy 349.204282 -262.795212) (xy 349.212407 -262.846507) (xy 349.212916 -262.872474) (xy 349.212407 -262.898441)
			(xy 349.204282 -262.949736) (xy 349.188234 -262.999129) (xy 349.164656 -263.045403) (xy 349.13413 -263.087419)
			(xy 349.097407 -263.124142) (xy 349.055391 -263.154668) (xy 349.009117 -263.178246) (xy 348.959724 -263.194294)
			(xy 348.908429 -263.202419) (xy 348.856495 -263.202419) (xy 348.8052 -263.194294) (xy 348.755807 -263.178246)
			(xy 348.709533 -263.154668) (xy 348.667517 -263.124142) (xy 348.630794 -263.087419) (xy 348.600268 -263.045403)
			(xy 348.57669 -262.999129) (xy 348.560642 -262.949736) (xy 348.552517 -262.898441) (xy 348.272607 -262.898441)
			(xy 348.264482 -262.949736) (xy 348.248434 -262.999129) (xy 348.224856 -263.045403) (xy 348.19433 -263.087419)
			(xy 348.157607 -263.124142) (xy 348.115591 -263.154668) (xy 348.069317 -263.178246) (xy 348.019924 -263.194294)
			(xy 347.968629 -263.202419) (xy 347.916695 -263.202419) (xy 347.8654 -263.194294) (xy 347.816007 -263.178246)
			(xy 347.769733 -263.154668) (xy 347.727717 -263.124142) (xy 347.690994 -263.087419) (xy 347.660468 -263.045403)
			(xy 347.63689 -262.999129) (xy 347.620842 -262.949736) (xy 347.612717 -262.898441) (xy 347.332807 -262.898441)
			(xy 347.324682 -262.949736) (xy 347.308634 -262.999129) (xy 347.285056 -263.045403) (xy 347.25453 -263.087419)
			(xy 347.217807 -263.124142) (xy 347.175791 -263.154668) (xy 347.129517 -263.178246) (xy 347.080124 -263.194294)
			(xy 347.028829 -263.202419) (xy 346.976895 -263.202419) (xy 346.9256 -263.194294) (xy 346.876207 -263.178246)
			(xy 346.829933 -263.154668) (xy 346.787917 -263.124142) (xy 346.751194 -263.087419) (xy 346.720668 -263.045403)
			(xy 346.69709 -262.999129) (xy 346.681042 -262.949736) (xy 346.672917 -262.898441) (xy 346.393007 -262.898441)
			(xy 346.384882 -262.949736) (xy 346.368834 -262.999129) (xy 346.345256 -263.045403) (xy 346.31473 -263.087419)
			(xy 346.278007 -263.124142) (xy 346.235991 -263.154668) (xy 346.189717 -263.178246) (xy 346.140324 -263.194294)
			(xy 346.089029 -263.202419) (xy 346.037095 -263.202419) (xy 345.9858 -263.194294) (xy 345.936407 -263.178246)
			(xy 345.890133 -263.154668) (xy 345.848117 -263.124142) (xy 345.811394 -263.087419) (xy 345.780868 -263.045403)
			(xy 345.75729 -262.999129) (xy 345.741242 -262.949736) (xy 345.733117 -262.898441) (xy 345.453461 -262.898441)
			(xy 345.445336 -262.949736) (xy 345.429288 -262.999129) (xy 345.40571 -263.045403) (xy 345.375184 -263.087419)
			(xy 345.338461 -263.124142) (xy 345.296445 -263.154668) (xy 345.250171 -263.178246) (xy 345.200778 -263.194294)
			(xy 345.149483 -263.202419) (xy 345.097549 -263.202419) (xy 345.046254 -263.194294) (xy 344.996861 -263.178246)
			(xy 344.950587 -263.154668) (xy 344.908571 -263.124142) (xy 344.871848 -263.087419) (xy 344.841322 -263.045403)
			(xy 344.817744 -262.999129) (xy 344.801696 -262.949736) (xy 344.793571 -262.898441) (xy 344.513407 -262.898441)
			(xy 344.505282 -262.949736) (xy 344.489234 -262.999129) (xy 344.465656 -263.045403) (xy 344.43513 -263.087419)
			(xy 344.398407 -263.124142) (xy 344.356391 -263.154668) (xy 344.310117 -263.178246) (xy 344.260724 -263.194294)
			(xy 344.209429 -263.202419) (xy 344.157495 -263.202419) (xy 344.1062 -263.194294) (xy 344.056807 -263.178246)
			(xy 344.010533 -263.154668) (xy 343.968517 -263.124142) (xy 343.931794 -263.087419) (xy 343.901268 -263.045403)
			(xy 343.87769 -262.999129) (xy 343.861642 -262.949736) (xy 343.853517 -262.898441) (xy 343.573607 -262.898441)
			(xy 343.565482 -262.949736) (xy 343.549434 -262.999129) (xy 343.525856 -263.045403) (xy 343.49533 -263.087419)
			(xy 343.458607 -263.124142) (xy 343.416591 -263.154668) (xy 343.370317 -263.178246) (xy 343.320924 -263.194294)
			(xy 343.269629 -263.202419) (xy 343.217695 -263.202419) (xy 343.1664 -263.194294) (xy 343.117007 -263.178246)
			(xy 343.070733 -263.154668) (xy 343.028717 -263.124142) (xy 342.991994 -263.087419) (xy 342.961468 -263.045403)
			(xy 342.93789 -262.999129) (xy 342.921842 -262.949736) (xy 342.913717 -262.898441) (xy 342.633807 -262.898441)
			(xy 342.625682 -262.949736) (xy 342.609634 -262.999129) (xy 342.586056 -263.045403) (xy 342.55553 -263.087419)
			(xy 342.518807 -263.124142) (xy 342.476791 -263.154668) (xy 342.430517 -263.178246) (xy 342.381124 -263.194294)
			(xy 342.329829 -263.202419) (xy 342.277895 -263.202419) (xy 342.2266 -263.194294) (xy 342.177207 -263.178246)
			(xy 342.130933 -263.154668) (xy 342.088917 -263.124142) (xy 342.052194 -263.087419) (xy 342.021668 -263.045403)
			(xy 341.99809 -262.999129) (xy 341.982042 -262.949736) (xy 341.973917 -262.898441) (xy 341.694007 -262.898441)
			(xy 341.685882 -262.949736) (xy 341.669834 -262.999129) (xy 341.646256 -263.045403) (xy 341.61573 -263.087419)
			(xy 341.579007 -263.124142) (xy 341.536991 -263.154668) (xy 341.490717 -263.178246) (xy 341.441324 -263.194294)
			(xy 341.390029 -263.202419) (xy 341.338095 -263.202419) (xy 341.2868 -263.194294) (xy 341.237407 -263.178246)
			(xy 341.191133 -263.154668) (xy 341.149117 -263.124142) (xy 341.112394 -263.087419) (xy 341.081868 -263.045403)
			(xy 341.05829 -262.999129) (xy 341.042242 -262.949736) (xy 341.034117 -262.898441) (xy 340.754207 -262.898441)
			(xy 340.746082 -262.949736) (xy 340.730034 -262.999129) (xy 340.706456 -263.045403) (xy 340.67593 -263.087419)
			(xy 340.639207 -263.124142) (xy 340.597191 -263.154668) (xy 340.550917 -263.178246) (xy 340.501524 -263.194294)
			(xy 340.450229 -263.202419) (xy 340.398295 -263.202419) (xy 340.347 -263.194294) (xy 340.297607 -263.178246)
			(xy 340.251333 -263.154668) (xy 340.209317 -263.124142) (xy 340.172594 -263.087419) (xy 340.142068 -263.045403)
			(xy 340.11849 -262.999129) (xy 340.102442 -262.949736) (xy 340.094317 -262.898441) (xy 339.813769 -262.898441)
			(xy 339.811844 -262.92336) (xy 339.800144 -262.973027) (xy 339.78095 -263.020305) (xy 339.754719 -263.064072)
			(xy 339.722074 -263.103289) (xy 339.683791 -263.137024) (xy 339.662516 -263.151112) (xy 339.651848 -263.15797)
			(xy 339.627464 -263.200642) (xy 339.627464 -263.320022) (xy 339.627784 -263.328406) (xy 339.633289 -263.344245)
			(xy 339.643685 -263.357402) (xy 339.650578 -263.362186) (xy 339.718142 -263.400032) (xy 339.723391 -263.40252)
			(xy 339.734687 -263.405218) (xy 339.740494 -263.405366) (xy 339.76691 -263.405366) (xy 339.791294 -263.398762)
			(xy 339.795612 -263.396476) (xy 339.820105 -263.383706) (xy 339.872285 -263.365602) (xy 339.926746 -263.356402)
			(xy 339.954362 -263.355836) (xy 339.954616 -263.355836) (xy 339.980599 -263.356347) (xy 340.031925 -263.364479)
			(xy 340.081346 -263.380539) (xy 340.127647 -263.404132) (xy 340.169688 -263.434678) (xy 340.206432 -263.471425)
			(xy 340.236976 -263.513466) (xy 340.260567 -263.559769) (xy 340.276625 -263.609191) (xy 340.284754 -263.660517)
			(xy 340.284754 -263.712483) (xy 340.28475 -263.712511) (xy 340.564471 -263.712511) (xy 340.564471 -263.660577)
			(xy 340.572596 -263.609282) (xy 340.588644 -263.559889) (xy 340.612222 -263.513615) (xy 340.642748 -263.471599)
			(xy 340.679471 -263.434876) (xy 340.721487 -263.40435) (xy 340.767761 -263.380772) (xy 340.817154 -263.364724)
			(xy 340.868449 -263.356599) (xy 340.920383 -263.356599) (xy 340.971678 -263.364724) (xy 341.021071 -263.380772)
			(xy 341.067345 -263.40435) (xy 341.109361 -263.434876) (xy 341.146084 -263.471599) (xy 341.17661 -263.513615)
			(xy 341.200188 -263.559889) (xy 341.216236 -263.609282) (xy 341.224361 -263.660577) (xy 341.22487 -263.686544)
			(xy 341.224361 -263.712511) (xy 341.504271 -263.712511) (xy 341.504271 -263.660577) (xy 341.512396 -263.609282)
			(xy 341.528444 -263.559889) (xy 341.552022 -263.513615) (xy 341.582548 -263.471599) (xy 341.619271 -263.434876)
			(xy 341.661287 -263.40435) (xy 341.707561 -263.380772) (xy 341.756954 -263.364724) (xy 341.808249 -263.356599)
			(xy 341.860183 -263.356599) (xy 341.911478 -263.364724) (xy 341.960871 -263.380772) (xy 342.007145 -263.40435)
			(xy 342.049161 -263.434876) (xy 342.085884 -263.471599) (xy 342.11641 -263.513615) (xy 342.139988 -263.559889)
			(xy 342.156036 -263.609282) (xy 342.164161 -263.660577) (xy 342.16467 -263.686544) (xy 342.164161 -263.712511)
			(xy 342.443817 -263.712511) (xy 342.443817 -263.660577) (xy 342.451942 -263.609282) (xy 342.46799 -263.559889)
			(xy 342.491568 -263.513615) (xy 342.522094 -263.471599) (xy 342.558817 -263.434876) (xy 342.600833 -263.40435)
			(xy 342.647107 -263.380772) (xy 342.6965 -263.364724) (xy 342.747795 -263.356599) (xy 342.799729 -263.356599)
			(xy 342.851024 -263.364724) (xy 342.900417 -263.380772) (xy 342.946691 -263.40435) (xy 342.988707 -263.434876)
			(xy 343.02543 -263.471599) (xy 343.055956 -263.513615) (xy 343.079534 -263.559889) (xy 343.095582 -263.609282)
			(xy 343.103707 -263.660577) (xy 343.104216 -263.686544) (xy 343.103707 -263.712511) (xy 343.383871 -263.712511)
			(xy 343.383871 -263.660577) (xy 343.391996 -263.609282) (xy 343.408044 -263.559889) (xy 343.431622 -263.513615)
			(xy 343.462148 -263.471599) (xy 343.498871 -263.434876) (xy 343.540887 -263.40435) (xy 343.587161 -263.380772)
			(xy 343.636554 -263.364724) (xy 343.687849 -263.356599) (xy 343.739783 -263.356599) (xy 343.791078 -263.364724)
			(xy 343.840471 -263.380772) (xy 343.886745 -263.40435) (xy 343.928761 -263.434876) (xy 343.965484 -263.471599)
			(xy 343.99601 -263.513615) (xy 344.019588 -263.559889) (xy 344.035636 -263.609282) (xy 344.043761 -263.660577)
			(xy 344.04427 -263.686544) (xy 344.043761 -263.712511) (xy 344.323671 -263.712511) (xy 344.323671 -263.660577)
			(xy 344.331796 -263.609282) (xy 344.347844 -263.559889) (xy 344.371422 -263.513615) (xy 344.401948 -263.471599)
			(xy 344.438671 -263.434876) (xy 344.480687 -263.40435) (xy 344.526961 -263.380772) (xy 344.576354 -263.364724)
			(xy 344.627649 -263.356599) (xy 344.679583 -263.356599) (xy 344.730878 -263.364724) (xy 344.780271 -263.380772)
			(xy 344.826545 -263.40435) (xy 344.868561 -263.434876) (xy 344.905284 -263.471599) (xy 344.93581 -263.513615)
			(xy 344.959388 -263.559889) (xy 344.975436 -263.609282) (xy 344.983561 -263.660577) (xy 344.98407 -263.686544)
			(xy 344.983561 -263.712511) (xy 345.263471 -263.712511) (xy 345.263471 -263.660577) (xy 345.271596 -263.609282)
			(xy 345.287644 -263.559889) (xy 345.311222 -263.513615) (xy 345.341748 -263.471599) (xy 345.378471 -263.434876)
			(xy 345.420487 -263.40435) (xy 345.466761 -263.380772) (xy 345.516154 -263.364724) (xy 345.567449 -263.356599)
			(xy 345.619383 -263.356599) (xy 345.670678 -263.364724) (xy 345.720071 -263.380772) (xy 345.766345 -263.40435)
			(xy 345.808361 -263.434876) (xy 345.845084 -263.471599) (xy 345.87561 -263.513615) (xy 345.899188 -263.559889)
			(xy 345.915236 -263.609282) (xy 345.923361 -263.660577) (xy 345.92387 -263.686544) (xy 345.923361 -263.712511)
			(xy 346.203271 -263.712511) (xy 346.203271 -263.660577) (xy 346.211396 -263.609282) (xy 346.227444 -263.559889)
			(xy 346.251022 -263.513615) (xy 346.281548 -263.471599) (xy 346.318271 -263.434876) (xy 346.360287 -263.40435)
			(xy 346.406561 -263.380772) (xy 346.455954 -263.364724) (xy 346.507249 -263.356599) (xy 346.559183 -263.356599)
			(xy 346.610478 -263.364724) (xy 346.659871 -263.380772) (xy 346.706145 -263.40435) (xy 346.748161 -263.434876)
			(xy 346.784884 -263.471599) (xy 346.81541 -263.513615) (xy 346.838988 -263.559889) (xy 346.855036 -263.609282)
			(xy 346.863161 -263.660577) (xy 346.86367 -263.686544) (xy 346.863161 -263.712511) (xy 347.143071 -263.712511)
			(xy 347.143071 -263.660577) (xy 347.151196 -263.609282) (xy 347.167244 -263.559889) (xy 347.190822 -263.513615)
			(xy 347.221348 -263.471599) (xy 347.258071 -263.434876) (xy 347.300087 -263.40435) (xy 347.346361 -263.380772)
			(xy 347.395754 -263.364724) (xy 347.447049 -263.356599) (xy 347.498983 -263.356599) (xy 347.550278 -263.364724)
			(xy 347.599671 -263.380772) (xy 347.645945 -263.40435) (xy 347.687961 -263.434876) (xy 347.724684 -263.471599)
			(xy 347.75521 -263.513615) (xy 347.778788 -263.559889) (xy 347.794836 -263.609282) (xy 347.802961 -263.660577)
			(xy 347.80347 -263.686544) (xy 347.802961 -263.712511) (xy 348.082871 -263.712511) (xy 348.082871 -263.660577)
			(xy 348.090996 -263.609282) (xy 348.107044 -263.559889) (xy 348.130622 -263.513615) (xy 348.161148 -263.471599)
			(xy 348.197871 -263.434876) (xy 348.239887 -263.40435) (xy 348.286161 -263.380772) (xy 348.335554 -263.364724)
			(xy 348.386849 -263.356599) (xy 348.438783 -263.356599) (xy 348.490078 -263.364724) (xy 348.539471 -263.380772)
			(xy 348.585745 -263.40435) (xy 348.627761 -263.434876) (xy 348.664484 -263.471599) (xy 348.69501 -263.513615)
			(xy 348.718588 -263.559889) (xy 348.734636 -263.609282) (xy 348.742761 -263.660577) (xy 348.74327 -263.686544)
			(xy 348.742761 -263.712511) (xy 349.022417 -263.712511) (xy 349.022417 -263.660577) (xy 349.030542 -263.609282)
			(xy 349.04659 -263.559889) (xy 349.070168 -263.513615) (xy 349.100694 -263.471599) (xy 349.137417 -263.434876)
			(xy 349.179433 -263.40435) (xy 349.225707 -263.380772) (xy 349.2751 -263.364724) (xy 349.326395 -263.356599)
			(xy 349.378329 -263.356599) (xy 349.429624 -263.364724) (xy 349.479017 -263.380772) (xy 349.525291 -263.40435)
			(xy 349.567307 -263.434876) (xy 349.60403 -263.471599) (xy 349.634556 -263.513615) (xy 349.658134 -263.559889)
			(xy 349.674182 -263.609282) (xy 349.682307 -263.660577) (xy 349.682816 -263.686544) (xy 349.682307 -263.712511)
			(xy 349.962471 -263.712511) (xy 349.962471 -263.660577) (xy 349.970596 -263.609282) (xy 349.986644 -263.559889)
			(xy 350.010222 -263.513615) (xy 350.040748 -263.471599) (xy 350.077471 -263.434876) (xy 350.119487 -263.40435)
			(xy 350.165761 -263.380772) (xy 350.215154 -263.364724) (xy 350.266449 -263.356599) (xy 350.318383 -263.356599)
			(xy 350.369678 -263.364724) (xy 350.419071 -263.380772) (xy 350.465345 -263.40435) (xy 350.507361 -263.434876)
			(xy 350.544084 -263.471599) (xy 350.57461 -263.513615) (xy 350.598188 -263.559889) (xy 350.614236 -263.609282)
			(xy 350.622361 -263.660577) (xy 350.62287 -263.686544) (xy 350.622361 -263.712511) (xy 350.614236 -263.763806)
			(xy 350.598188 -263.813199) (xy 350.57461 -263.859473) (xy 350.544084 -263.901489) (xy 350.507361 -263.938212)
			(xy 350.465345 -263.968738) (xy 350.419071 -263.992316) (xy 350.369678 -264.008364) (xy 350.318383 -264.016489)
			(xy 350.266449 -264.016489) (xy 350.215154 -264.008364) (xy 350.165761 -263.992316) (xy 350.119487 -263.968738)
			(xy 350.077471 -263.938212) (xy 350.040748 -263.901489) (xy 350.010222 -263.859473) (xy 349.986644 -263.813199)
			(xy 349.970596 -263.763806) (xy 349.962471 -263.712511) (xy 349.682307 -263.712511) (xy 349.674182 -263.763806)
			(xy 349.658134 -263.813199) (xy 349.634556 -263.859473) (xy 349.60403 -263.901489) (xy 349.567307 -263.938212)
			(xy 349.525291 -263.968738) (xy 349.479017 -263.992316) (xy 349.429624 -264.008364) (xy 349.378329 -264.016489)
			(xy 349.326395 -264.016489) (xy 349.2751 -264.008364) (xy 349.225707 -263.992316) (xy 349.179433 -263.968738)
			(xy 349.137417 -263.938212) (xy 349.100694 -263.901489) (xy 349.070168 -263.859473) (xy 349.04659 -263.813199)
			(xy 349.030542 -263.763806) (xy 349.022417 -263.712511) (xy 348.742761 -263.712511) (xy 348.734636 -263.763806)
			(xy 348.718588 -263.813199) (xy 348.69501 -263.859473) (xy 348.664484 -263.901489) (xy 348.627761 -263.938212)
			(xy 348.585745 -263.968738) (xy 348.539471 -263.992316) (xy 348.490078 -264.008364) (xy 348.438783 -264.016489)
			(xy 348.386849 -264.016489) (xy 348.335554 -264.008364) (xy 348.286161 -263.992316) (xy 348.239887 -263.968738)
			(xy 348.197871 -263.938212) (xy 348.161148 -263.901489) (xy 348.130622 -263.859473) (xy 348.107044 -263.813199)
			(xy 348.090996 -263.763806) (xy 348.082871 -263.712511) (xy 347.802961 -263.712511) (xy 347.794836 -263.763806)
			(xy 347.778788 -263.813199) (xy 347.75521 -263.859473) (xy 347.724684 -263.901489) (xy 347.687961 -263.938212)
			(xy 347.645945 -263.968738) (xy 347.599671 -263.992316) (xy 347.550278 -264.008364) (xy 347.498983 -264.016489)
			(xy 347.447049 -264.016489) (xy 347.395754 -264.008364) (xy 347.346361 -263.992316) (xy 347.300087 -263.968738)
			(xy 347.258071 -263.938212) (xy 347.221348 -263.901489) (xy 347.190822 -263.859473) (xy 347.167244 -263.813199)
			(xy 347.151196 -263.763806) (xy 347.143071 -263.712511) (xy 346.863161 -263.712511) (xy 346.855036 -263.763806)
			(xy 346.838988 -263.813199) (xy 346.81541 -263.859473) (xy 346.784884 -263.901489) (xy 346.748161 -263.938212)
			(xy 346.706145 -263.968738) (xy 346.659871 -263.992316) (xy 346.610478 -264.008364) (xy 346.559183 -264.016489)
			(xy 346.507249 -264.016489) (xy 346.455954 -264.008364) (xy 346.406561 -263.992316) (xy 346.360287 -263.968738)
			(xy 346.318271 -263.938212) (xy 346.281548 -263.901489) (xy 346.251022 -263.859473) (xy 346.227444 -263.813199)
			(xy 346.211396 -263.763806) (xy 346.203271 -263.712511) (xy 345.923361 -263.712511) (xy 345.915236 -263.763806)
			(xy 345.899188 -263.813199) (xy 345.87561 -263.859473) (xy 345.845084 -263.901489) (xy 345.808361 -263.938212)
			(xy 345.766345 -263.968738) (xy 345.720071 -263.992316) (xy 345.670678 -264.008364) (xy 345.619383 -264.016489)
			(xy 345.567449 -264.016489) (xy 345.516154 -264.008364) (xy 345.466761 -263.992316) (xy 345.420487 -263.968738)
			(xy 345.378471 -263.938212) (xy 345.341748 -263.901489) (xy 345.311222 -263.859473) (xy 345.287644 -263.813199)
			(xy 345.271596 -263.763806) (xy 345.263471 -263.712511) (xy 344.983561 -263.712511) (xy 344.975436 -263.763806)
			(xy 344.959388 -263.813199) (xy 344.93581 -263.859473) (xy 344.905284 -263.901489) (xy 344.868561 -263.938212)
			(xy 344.826545 -263.968738) (xy 344.780271 -263.992316) (xy 344.730878 -264.008364) (xy 344.679583 -264.016489)
			(xy 344.627649 -264.016489) (xy 344.576354 -264.008364) (xy 344.526961 -263.992316) (xy 344.480687 -263.968738)
			(xy 344.438671 -263.938212) (xy 344.401948 -263.901489) (xy 344.371422 -263.859473) (xy 344.347844 -263.813199)
			(xy 344.331796 -263.763806) (xy 344.323671 -263.712511) (xy 344.043761 -263.712511) (xy 344.035636 -263.763806)
			(xy 344.019588 -263.813199) (xy 343.99601 -263.859473) (xy 343.965484 -263.901489) (xy 343.928761 -263.938212)
			(xy 343.886745 -263.968738) (xy 343.840471 -263.992316) (xy 343.791078 -264.008364) (xy 343.739783 -264.016489)
			(xy 343.687849 -264.016489) (xy 343.636554 -264.008364) (xy 343.587161 -263.992316) (xy 343.540887 -263.968738)
			(xy 343.498871 -263.938212) (xy 343.462148 -263.901489) (xy 343.431622 -263.859473) (xy 343.408044 -263.813199)
			(xy 343.391996 -263.763806) (xy 343.383871 -263.712511) (xy 343.103707 -263.712511) (xy 343.095582 -263.763806)
			(xy 343.079534 -263.813199) (xy 343.055956 -263.859473) (xy 343.02543 -263.901489) (xy 342.988707 -263.938212)
			(xy 342.946691 -263.968738) (xy 342.900417 -263.992316) (xy 342.851024 -264.008364) (xy 342.799729 -264.016489)
			(xy 342.747795 -264.016489) (xy 342.6965 -264.008364) (xy 342.647107 -263.992316) (xy 342.600833 -263.968738)
			(xy 342.558817 -263.938212) (xy 342.522094 -263.901489) (xy 342.491568 -263.859473) (xy 342.46799 -263.813199)
			(xy 342.451942 -263.763806) (xy 342.443817 -263.712511) (xy 342.164161 -263.712511) (xy 342.156036 -263.763806)
			(xy 342.139988 -263.813199) (xy 342.11641 -263.859473) (xy 342.085884 -263.901489) (xy 342.049161 -263.938212)
			(xy 342.007145 -263.968738) (xy 341.960871 -263.992316) (xy 341.911478 -264.008364) (xy 341.860183 -264.016489)
			(xy 341.808249 -264.016489) (xy 341.756954 -264.008364) (xy 341.707561 -263.992316) (xy 341.661287 -263.968738)
			(xy 341.619271 -263.938212) (xy 341.582548 -263.901489) (xy 341.552022 -263.859473) (xy 341.528444 -263.813199)
			(xy 341.512396 -263.763806) (xy 341.504271 -263.712511) (xy 341.224361 -263.712511) (xy 341.216236 -263.763806)
			(xy 341.200188 -263.813199) (xy 341.17661 -263.859473) (xy 341.146084 -263.901489) (xy 341.109361 -263.938212)
			(xy 341.067345 -263.968738) (xy 341.021071 -263.992316) (xy 340.971678 -264.008364) (xy 340.920383 -264.016489)
			(xy 340.868449 -264.016489) (xy 340.817154 -264.008364) (xy 340.767761 -263.992316) (xy 340.721487 -263.968738)
			(xy 340.679471 -263.938212) (xy 340.642748 -263.901489) (xy 340.612222 -263.859473) (xy 340.588644 -263.813199)
			(xy 340.572596 -263.763806) (xy 340.564471 -263.712511) (xy 340.28475 -263.712511) (xy 340.276625 -263.763809)
			(xy 340.260567 -263.813231) (xy 340.236976 -263.859534) (xy 340.206432 -263.901575) (xy 340.169688 -263.938322)
			(xy 340.127647 -263.968868) (xy 340.081346 -263.992461) (xy 340.031925 -264.008521) (xy 339.980599 -264.016653)
			(xy 339.954616 -264.017252) (xy 339.931701 -264.016861) (xy 339.886311 -264.010527) (xy 339.842234 -263.997977)
			(xy 339.800314 -263.979453) (xy 339.780626 -263.967722) (xy 339.780372 -263.967722) (xy 339.772614 -263.963327)
			(xy 339.755157 -263.959759) (xy 339.737544 -263.962457) (xy 339.729572 -263.966452) (xy 339.691218 -263.988042)
			(xy 339.65134 -264.010394) (xy 339.644245 -264.015152) (xy 339.633515 -264.028431) (xy 339.627835 -264.04453)
			(xy 339.627464 -264.053066) (xy 339.627464 -264.172192) (xy 339.651848 -264.21461) (xy 339.662516 -264.221468)
			(xy 339.683798 -264.235598) (xy 339.722138 -264.269352) (xy 339.754834 -264.308599) (xy 339.781108 -264.352406)
			(xy 339.800336 -264.399731) (xy 339.812059 -264.449449) (xy 339.816001 -264.500378) (xy 339.813996 -264.526327)
			(xy 340.094317 -264.526327) (xy 340.094317 -264.474393) (xy 340.102442 -264.423098) (xy 340.11849 -264.373705)
			(xy 340.142068 -264.327431) (xy 340.172594 -264.285415) (xy 340.209317 -264.248692) (xy 340.251333 -264.218166)
			(xy 340.297607 -264.194588) (xy 340.347 -264.17854) (xy 340.398295 -264.170415) (xy 340.450229 -264.170415)
			(xy 340.501524 -264.17854) (xy 340.550917 -264.194588) (xy 340.597191 -264.218166) (xy 340.639207 -264.248692)
			(xy 340.67593 -264.285415) (xy 340.706456 -264.327431) (xy 340.730034 -264.373705) (xy 340.746082 -264.423098)
			(xy 340.754207 -264.474393) (xy 340.754716 -264.50036) (xy 340.754207 -264.526327) (xy 341.034117 -264.526327)
			(xy 341.034117 -264.474393) (xy 341.042242 -264.423098) (xy 341.05829 -264.373705) (xy 341.081868 -264.327431)
			(xy 341.112394 -264.285415) (xy 341.149117 -264.248692) (xy 341.191133 -264.218166) (xy 341.237407 -264.194588)
			(xy 341.2868 -264.17854) (xy 341.338095 -264.170415) (xy 341.390029 -264.170415) (xy 341.441324 -264.17854)
			(xy 341.490717 -264.194588) (xy 341.536991 -264.218166) (xy 341.579007 -264.248692) (xy 341.61573 -264.285415)
			(xy 341.646256 -264.327431) (xy 341.669834 -264.373705) (xy 341.685882 -264.423098) (xy 341.694007 -264.474393)
			(xy 341.694516 -264.50036) (xy 341.694007 -264.526327) (xy 341.973917 -264.526327) (xy 341.973917 -264.474393)
			(xy 341.982042 -264.423098) (xy 341.99809 -264.373705) (xy 342.021668 -264.327431) (xy 342.052194 -264.285415)
			(xy 342.088917 -264.248692) (xy 342.130933 -264.218166) (xy 342.177207 -264.194588) (xy 342.2266 -264.17854)
			(xy 342.277895 -264.170415) (xy 342.329829 -264.170415) (xy 342.381124 -264.17854) (xy 342.430517 -264.194588)
			(xy 342.476791 -264.218166) (xy 342.518807 -264.248692) (xy 342.55553 -264.285415) (xy 342.586056 -264.327431)
			(xy 342.609634 -264.373705) (xy 342.625682 -264.423098) (xy 342.633807 -264.474393) (xy 342.634316 -264.50036)
			(xy 342.633807 -264.526327) (xy 342.913717 -264.526327) (xy 342.913717 -264.474393) (xy 342.921842 -264.423098)
			(xy 342.93789 -264.373705) (xy 342.961468 -264.327431) (xy 342.991994 -264.285415) (xy 343.028717 -264.248692)
			(xy 343.070733 -264.218166) (xy 343.117007 -264.194588) (xy 343.1664 -264.17854) (xy 343.217695 -264.170415)
			(xy 343.269629 -264.170415) (xy 343.320924 -264.17854) (xy 343.370317 -264.194588) (xy 343.416591 -264.218166)
			(xy 343.458607 -264.248692) (xy 343.49533 -264.285415) (xy 343.525856 -264.327431) (xy 343.549434 -264.373705)
			(xy 343.565482 -264.423098) (xy 343.573607 -264.474393) (xy 343.574116 -264.50036) (xy 343.573607 -264.526327)
			(xy 343.853517 -264.526327) (xy 343.853517 -264.474393) (xy 343.861642 -264.423098) (xy 343.87769 -264.373705)
			(xy 343.901268 -264.327431) (xy 343.931794 -264.285415) (xy 343.968517 -264.248692) (xy 344.010533 -264.218166)
			(xy 344.056807 -264.194588) (xy 344.1062 -264.17854) (xy 344.157495 -264.170415) (xy 344.209429 -264.170415)
			(xy 344.260724 -264.17854) (xy 344.310117 -264.194588) (xy 344.356391 -264.218166) (xy 344.398407 -264.248692)
			(xy 344.43513 -264.285415) (xy 344.465656 -264.327431) (xy 344.489234 -264.373705) (xy 344.505282 -264.423098)
			(xy 344.513407 -264.474393) (xy 344.513916 -264.50036) (xy 344.513407 -264.526327) (xy 344.793317 -264.526327)
			(xy 344.793317 -264.474393) (xy 344.801442 -264.423098) (xy 344.81749 -264.373705) (xy 344.841068 -264.327431)
			(xy 344.871594 -264.285415) (xy 344.908317 -264.248692) (xy 344.950333 -264.218166) (xy 344.996607 -264.194588)
			(xy 345.046 -264.17854) (xy 345.097295 -264.170415) (xy 345.149229 -264.170415) (xy 345.200524 -264.17854)
			(xy 345.249917 -264.194588) (xy 345.296191 -264.218166) (xy 345.338207 -264.248692) (xy 345.37493 -264.285415)
			(xy 345.405456 -264.327431) (xy 345.429034 -264.373705) (xy 345.445082 -264.423098) (xy 345.453207 -264.474393)
			(xy 345.453716 -264.50036) (xy 345.453207 -264.526327) (xy 345.733371 -264.526327) (xy 345.733371 -264.474393)
			(xy 345.741496 -264.423098) (xy 345.757544 -264.373705) (xy 345.781122 -264.327431) (xy 345.811648 -264.285415)
			(xy 345.848371 -264.248692) (xy 345.890387 -264.218166) (xy 345.936661 -264.194588) (xy 345.986054 -264.17854)
			(xy 346.037349 -264.170415) (xy 346.089283 -264.170415) (xy 346.140578 -264.17854) (xy 346.189971 -264.194588)
			(xy 346.236245 -264.218166) (xy 346.278261 -264.248692) (xy 346.314984 -264.285415) (xy 346.34551 -264.327431)
			(xy 346.369088 -264.373705) (xy 346.385136 -264.423098) (xy 346.393261 -264.474393) (xy 346.39377 -264.50036)
			(xy 346.393261 -264.526327) (xy 346.672917 -264.526327) (xy 346.672917 -264.474393) (xy 346.681042 -264.423098)
			(xy 346.69709 -264.373705) (xy 346.720668 -264.327431) (xy 346.751194 -264.285415) (xy 346.787917 -264.248692)
			(xy 346.829933 -264.218166) (xy 346.876207 -264.194588) (xy 346.9256 -264.17854) (xy 346.976895 -264.170415)
			(xy 347.028829 -264.170415) (xy 347.080124 -264.17854) (xy 347.129517 -264.194588) (xy 347.175791 -264.218166)
			(xy 347.217807 -264.248692) (xy 347.25453 -264.285415) (xy 347.285056 -264.327431) (xy 347.308634 -264.373705)
			(xy 347.324682 -264.423098) (xy 347.332807 -264.474393) (xy 347.333316 -264.50036) (xy 347.332807 -264.526327)
			(xy 347.612717 -264.526327) (xy 347.612717 -264.474393) (xy 347.620842 -264.423098) (xy 347.63689 -264.373705)
			(xy 347.660468 -264.327431) (xy 347.690994 -264.285415) (xy 347.727717 -264.248692) (xy 347.769733 -264.218166)
			(xy 347.816007 -264.194588) (xy 347.8654 -264.17854) (xy 347.916695 -264.170415) (xy 347.968629 -264.170415)
			(xy 348.019924 -264.17854) (xy 348.069317 -264.194588) (xy 348.115591 -264.218166) (xy 348.157607 -264.248692)
			(xy 348.19433 -264.285415) (xy 348.224856 -264.327431) (xy 348.248434 -264.373705) (xy 348.264482 -264.423098)
			(xy 348.272607 -264.474393) (xy 348.273116 -264.50036) (xy 348.272607 -264.526327) (xy 348.552517 -264.526327)
			(xy 348.552517 -264.474393) (xy 348.560642 -264.423098) (xy 348.57669 -264.373705) (xy 348.600268 -264.327431)
			(xy 348.630794 -264.285415) (xy 348.667517 -264.248692) (xy 348.709533 -264.218166) (xy 348.755807 -264.194588)
			(xy 348.8052 -264.17854) (xy 348.856495 -264.170415) (xy 348.908429 -264.170415) (xy 348.959724 -264.17854)
			(xy 349.009117 -264.194588) (xy 349.055391 -264.218166) (xy 349.097407 -264.248692) (xy 349.13413 -264.285415)
			(xy 349.164656 -264.327431) (xy 349.188234 -264.373705) (xy 349.204282 -264.423098) (xy 349.212407 -264.474393)
			(xy 349.212916 -264.50036) (xy 349.212407 -264.526327) (xy 349.492317 -264.526327) (xy 349.492317 -264.474393)
			(xy 349.500442 -264.423098) (xy 349.51649 -264.373705) (xy 349.540068 -264.327431) (xy 349.570594 -264.285415)
			(xy 349.607317 -264.248692) (xy 349.649333 -264.218166) (xy 349.695607 -264.194588) (xy 349.745 -264.17854)
			(xy 349.796295 -264.170415) (xy 349.848229 -264.170415) (xy 349.899524 -264.17854) (xy 349.948917 -264.194588)
			(xy 349.995191 -264.218166) (xy 350.037207 -264.248692) (xy 350.07393 -264.285415) (xy 350.104456 -264.327431)
			(xy 350.128034 -264.373705) (xy 350.144082 -264.423098) (xy 350.152207 -264.474393) (xy 350.152716 -264.50036)
			(xy 350.152207 -264.526327) (xy 350.432117 -264.526327) (xy 350.432117 -264.474393) (xy 350.440242 -264.423098)
			(xy 350.45629 -264.373705) (xy 350.479868 -264.327431) (xy 350.510394 -264.285415) (xy 350.547117 -264.248692)
			(xy 350.589133 -264.218166) (xy 350.635407 -264.194588) (xy 350.6848 -264.17854) (xy 350.736095 -264.170415)
			(xy 350.788029 -264.170415) (xy 350.839324 -264.17854) (xy 350.888717 -264.194588) (xy 350.934991 -264.218166)
			(xy 350.977007 -264.248692) (xy 351.01373 -264.285415) (xy 351.044256 -264.327431) (xy 351.067834 -264.373705)
			(xy 351.083882 -264.423098) (xy 351.092007 -264.474393) (xy 351.092516 -264.50036) (xy 351.092007 -264.526327)
			(xy 351.092001 -264.526368) (xy 351.371915 -264.526368) (xy 351.371915 -264.474432) (xy 351.380039 -264.423134)
			(xy 351.396088 -264.373739) (xy 351.419665 -264.327462) (xy 351.450191 -264.285442) (xy 351.486914 -264.248715)
			(xy 351.528929 -264.218185) (xy 351.575203 -264.194602) (xy 351.624597 -264.178548) (xy 351.675894 -264.170418)
			(xy 351.701862 -264.169906) (xy 351.702116 -264.169906) (xy 351.728819 -264.170445) (xy 351.781527 -264.179062)
			(xy 351.83217 -264.196024) (xy 351.85604 -264.208006) (xy 351.867216 -264.213848) (xy 351.930716 -264.213848)
			(xy 351.930716 -264.159746) (xy 352.17862 -263.911588) (xy 355.295454 -263.911588) (xy 355.365812 -263.84123)
			(xy 355.375587 -263.830687) (xy 355.38945 -263.80552) (xy 355.395741 -263.777484) (xy 355.393961 -263.748806)
			(xy 355.384251 -263.721764) (xy 355.367381 -263.698504) (xy 355.344692 -263.680875) (xy 355.331522 -263.675114)
			(xy 355.308842 -263.665579) (xy 355.266374 -263.640743) (xy 355.228057 -263.609884) (xy 355.194738 -263.573686)
			(xy 355.167155 -263.532948) (xy 355.145917 -263.488571) (xy 355.131492 -263.441535) (xy 355.124201 -263.392881)
			(xy 355.12375 -263.368282) (xy 355.12375 -263.368028) (xy 355.124232 -263.343503) (xy 355.131489 -263.294992)
			(xy 355.145834 -263.248085) (xy 355.166952 -263.203813) (xy 355.19438 -263.163147) (xy 355.210618 -263.144762)
			(xy 355.220436 -263.133285) (xy 355.233442 -263.106043) (xy 355.237905 -263.076187) (xy 355.233434 -263.046332)
			(xy 355.220421 -263.019093) (xy 355.210618 -263.007602) (xy 355.194341 -262.989213) (xy 355.166875 -262.948505)
			(xy 355.14574 -262.904178) (xy 355.131401 -262.85721) (xy 355.124176 -262.808636) (xy 355.12375 -262.784082)
			(xy 355.124215 -262.759531) (xy 355.13145 -262.710965) (xy 355.145788 -262.664004) (xy 355.166915 -262.61968)
			(xy 355.194364 -262.578967) (xy 355.210618 -262.560562) (xy 355.220436 -262.549085) (xy 355.233442 -262.521843)
			(xy 355.237905 -262.491987) (xy 355.233434 -262.462132) (xy 355.220421 -262.434893) (xy 355.210618 -262.423402)
			(xy 355.194357 -262.405033) (xy 355.166913 -262.364371) (xy 355.145786 -262.320096) (xy 355.131441 -262.273183)
			(xy 355.124193 -262.224665) (xy 355.12375 -262.200136) (xy 355.12375 -262.199882) (xy 355.124259 -262.173915)
			(xy 355.132384 -262.12262) (xy 355.148432 -262.073227) (xy 355.17201 -262.026953) (xy 355.202536 -261.984937)
			(xy 355.239259 -261.948214) (xy 355.281275 -261.917688) (xy 355.327549 -261.89411) (xy 355.376942 -261.878062)
			(xy 355.428237 -261.869937) (xy 355.480171 -261.869937) (xy 355.531466 -261.878062) (xy 355.580859 -261.89411)
			(xy 355.627133 -261.917688) (xy 355.669149 -261.948214) (xy 355.705872 -261.984937) (xy 355.736398 -262.026953)
			(xy 355.759976 -262.073227) (xy 355.776024 -262.12262) (xy 355.784149 -262.173915) (xy 355.784658 -262.199882)
			(xy 355.784658 -262.200136) (xy 355.784213 -262.224663) (xy 355.776946 -262.273175) (xy 355.762592 -262.320082)
			(xy 355.741466 -262.364353) (xy 355.714032 -262.405018) (xy 355.69779 -262.423402) (xy 355.688007 -262.434906)
			(xy 355.674996 -262.462139) (xy 355.670526 -262.491987) (xy 355.674988 -262.521836) (xy 355.687992 -262.549072)
			(xy 355.69779 -262.560562) (xy 355.714051 -262.578964) (xy 355.741519 -262.619669) (xy 355.762657 -262.663993)
			(xy 355.777 -262.710958) (xy 355.784229 -262.759529) (xy 355.784658 -262.784082) (xy 355.78423 -262.808634)
			(xy 355.776985 -262.857202) (xy 355.762638 -262.904163) (xy 355.741504 -262.948487) (xy 355.714047 -262.989198)
			(xy 355.69779 -263.007602) (xy 355.688007 -263.019106) (xy 355.674996 -263.046339) (xy 355.670526 -263.076187)
			(xy 355.674988 -263.106036) (xy 355.687992 -263.133272) (xy 355.69779 -263.144762) (xy 355.717516 -263.167298)
			(xy 355.749341 -263.218028) (xy 355.761036 -263.2456) (xy 355.766755 -263.258775) (xy 355.78444 -263.281398)
			(xy 355.807716 -263.298214) (xy 355.834748 -263.3079) (xy 355.863407 -263.309693) (xy 355.891435 -263.30345)
			(xy 355.916624 -263.289665) (xy 355.927152 -263.27989) (xy 356.411276 -262.795766) (xy 356.378002 -262.759952)
			(xy 356.36152 -262.7415) (xy 356.333631 -262.700637) (xy 356.312137 -262.656076) (xy 356.297517 -262.608812)
			(xy 356.290098 -262.559898) (xy 356.28961 -262.535162) (xy 356.28961 -262.534908) (xy 356.290064 -262.510381)
			(xy 356.297326 -262.461869) (xy 356.311677 -262.414961) (xy 356.332801 -262.37069) (xy 356.360236 -262.330025)
			(xy 356.376478 -262.311642) (xy 356.386319 -262.300182) (xy 356.399328 -262.272934) (xy 356.403789 -262.243072)
			(xy 356.399311 -262.213212) (xy 356.386287 -262.185971) (xy 356.376478 -262.174482) (xy 356.360185 -262.156107)
			(xy 356.332723 -262.115394) (xy 356.311591 -262.071063) (xy 356.297256 -262.024093) (xy 356.290035 -261.975517)
			(xy 356.28961 -261.950962) (xy 356.290047 -261.92641) (xy 356.297287 -261.877842) (xy 356.311631 -261.83088)
			(xy 356.332763 -261.786556) (xy 356.36022 -261.745845) (xy 356.376478 -261.727442) (xy 356.386319 -261.715982)
			(xy 356.399328 -261.688734) (xy 356.403789 -261.658872) (xy 356.399311 -261.629012) (xy 356.386287 -261.601771)
			(xy 356.376478 -261.590282) (xy 356.360185 -261.571907) (xy 356.332723 -261.531194) (xy 356.311591 -261.486863)
			(xy 356.297256 -261.439893) (xy 356.290035 -261.391317) (xy 356.28961 -261.366762) (xy 356.290047 -261.34221)
			(xy 356.297287 -261.293642) (xy 356.311631 -261.24668) (xy 356.332763 -261.202356) (xy 356.36022 -261.161645)
			(xy 356.376478 -261.143242) (xy 356.386319 -261.131782) (xy 356.399328 -261.104534) (xy 356.403789 -261.074672)
			(xy 356.399311 -261.044812) (xy 356.386287 -261.017571) (xy 356.376478 -261.006082) (xy 356.360201 -260.987727)
			(xy 356.332761 -260.94706) (xy 356.311637 -260.902782) (xy 356.297296 -260.855866) (xy 356.290052 -260.807345)
			(xy 356.28961 -260.782816) (xy 356.28961 -260.782562) (xy 356.290119 -260.756595) (xy 356.298244 -260.7053)
			(xy 356.314292 -260.655907) (xy 356.33787 -260.609633) (xy 356.368396 -260.567617) (xy 356.405119 -260.530894)
			(xy 356.447135 -260.500368) (xy 356.493409 -260.47679) (xy 356.542802 -260.460742) (xy 356.594097 -260.452617)
			(xy 356.646031 -260.452617) (xy 356.672054 -260.456739) (xy 357.480617 -260.456739) (xy 357.480617 -260.404805)
			(xy 357.488742 -260.35351) (xy 357.50479 -260.304117) (xy 357.528368 -260.257843) (xy 357.558894 -260.215827)
			(xy 357.595617 -260.179104) (xy 357.637633 -260.148578) (xy 357.683907 -260.125) (xy 357.7333 -260.108952)
			(xy 357.784595 -260.100827) (xy 357.836529 -260.100827) (xy 357.887824 -260.108952) (xy 357.937217 -260.125)
			(xy 357.983491 -260.148578) (xy 358.025507 -260.179104) (xy 358.06223 -260.215827) (xy 358.092756 -260.257843)
			(xy 358.116334 -260.304117) (xy 358.132382 -260.35351) (xy 358.140507 -260.404805) (xy 358.141016 -260.430772)
			(xy 358.140507 -260.456739) (xy 358.420671 -260.456739) (xy 358.420671 -260.404805) (xy 358.428796 -260.35351)
			(xy 358.444844 -260.304117) (xy 358.468422 -260.257843) (xy 358.498948 -260.215827) (xy 358.535671 -260.179104)
			(xy 358.577687 -260.148578) (xy 358.623961 -260.125) (xy 358.673354 -260.108952) (xy 358.724649 -260.100827)
			(xy 358.776583 -260.100827) (xy 358.827878 -260.108952) (xy 358.877271 -260.125) (xy 358.923545 -260.148578)
			(xy 358.965561 -260.179104) (xy 359.002284 -260.215827) (xy 359.03281 -260.257843) (xy 359.056388 -260.304117)
			(xy 359.072436 -260.35351) (xy 359.080561 -260.404805) (xy 359.08107 -260.430772) (xy 359.080561 -260.456739)
			(xy 359.360217 -260.456739) (xy 359.360217 -260.404805) (xy 359.368342 -260.35351) (xy 359.38439 -260.304117)
			(xy 359.407968 -260.257843) (xy 359.438494 -260.215827) (xy 359.475217 -260.179104) (xy 359.517233 -260.148578)
			(xy 359.563507 -260.125) (xy 359.6129 -260.108952) (xy 359.664195 -260.100827) (xy 359.716129 -260.100827)
			(xy 359.767424 -260.108952) (xy 359.816817 -260.125) (xy 359.863091 -260.148578) (xy 359.905107 -260.179104)
			(xy 359.94183 -260.215827) (xy 359.972356 -260.257843) (xy 359.995934 -260.304117) (xy 360.011982 -260.35351)
			(xy 360.020107 -260.404805) (xy 360.020616 -260.430772) (xy 360.020107 -260.456739) (xy 360.300017 -260.456739)
			(xy 360.300017 -260.404805) (xy 360.308142 -260.35351) (xy 360.32419 -260.304117) (xy 360.347768 -260.257843)
			(xy 360.378294 -260.215827) (xy 360.415017 -260.179104) (xy 360.457033 -260.148578) (xy 360.503307 -260.125)
			(xy 360.5527 -260.108952) (xy 360.603995 -260.100827) (xy 360.655929 -260.100827) (xy 360.707224 -260.108952)
			(xy 360.756617 -260.125) (xy 360.802891 -260.148578) (xy 360.844907 -260.179104) (xy 360.88163 -260.215827)
			(xy 360.912156 -260.257843) (xy 360.935734 -260.304117) (xy 360.951782 -260.35351) (xy 360.959907 -260.404805)
			(xy 360.960416 -260.430772) (xy 360.959907 -260.456739) (xy 361.239817 -260.456739) (xy 361.239817 -260.404805)
			(xy 361.247942 -260.35351) (xy 361.26399 -260.304117) (xy 361.287568 -260.257843) (xy 361.318094 -260.215827)
			(xy 361.354817 -260.179104) (xy 361.396833 -260.148578) (xy 361.443107 -260.125) (xy 361.4925 -260.108952)
			(xy 361.543795 -260.100827) (xy 361.595729 -260.100827) (xy 361.647024 -260.108952) (xy 361.696417 -260.125)
			(xy 361.742691 -260.148578) (xy 361.784707 -260.179104) (xy 361.82143 -260.215827) (xy 361.851956 -260.257843)
			(xy 361.875534 -260.304117) (xy 361.891582 -260.35351) (xy 361.899707 -260.404805) (xy 361.900216 -260.430772)
			(xy 361.899707 -260.456739) (xy 362.179617 -260.456739) (xy 362.179617 -260.404805) (xy 362.187742 -260.35351)
			(xy 362.20379 -260.304117) (xy 362.227368 -260.257843) (xy 362.257894 -260.215827) (xy 362.294617 -260.179104)
			(xy 362.336633 -260.148578) (xy 362.382907 -260.125) (xy 362.4323 -260.108952) (xy 362.483595 -260.100827)
			(xy 362.535529 -260.100827) (xy 362.586824 -260.108952) (xy 362.636217 -260.125) (xy 362.682491 -260.148578)
			(xy 362.724507 -260.179104) (xy 362.76123 -260.215827) (xy 362.791756 -260.257843) (xy 362.815334 -260.304117)
			(xy 362.831382 -260.35351) (xy 362.839507 -260.404805) (xy 362.840016 -260.430772) (xy 362.839507 -260.456739)
			(xy 362.831382 -260.508034) (xy 362.815334 -260.557427) (xy 362.791756 -260.603701) (xy 362.76123 -260.645717)
			(xy 362.724507 -260.68244) (xy 362.682491 -260.712966) (xy 362.636217 -260.736544) (xy 362.586824 -260.752592)
			(xy 362.535529 -260.760717) (xy 362.483595 -260.760717) (xy 362.4323 -260.752592) (xy 362.382907 -260.736544)
			(xy 362.336633 -260.712966) (xy 362.294617 -260.68244) (xy 362.257894 -260.645717) (xy 362.227368 -260.603701)
			(xy 362.20379 -260.557427) (xy 362.187742 -260.508034) (xy 362.179617 -260.456739) (xy 361.899707 -260.456739)
			(xy 361.891582 -260.508034) (xy 361.875534 -260.557427) (xy 361.851956 -260.603701) (xy 361.82143 -260.645717)
			(xy 361.784707 -260.68244) (xy 361.742691 -260.712966) (xy 361.696417 -260.736544) (xy 361.647024 -260.752592)
			(xy 361.595729 -260.760717) (xy 361.543795 -260.760717) (xy 361.4925 -260.752592) (xy 361.443107 -260.736544)
			(xy 361.396833 -260.712966) (xy 361.354817 -260.68244) (xy 361.318094 -260.645717) (xy 361.287568 -260.603701)
			(xy 361.26399 -260.557427) (xy 361.247942 -260.508034) (xy 361.239817 -260.456739) (xy 360.959907 -260.456739)
			(xy 360.951782 -260.508034) (xy 360.935734 -260.557427) (xy 360.912156 -260.603701) (xy 360.88163 -260.645717)
			(xy 360.844907 -260.68244) (xy 360.802891 -260.712966) (xy 360.756617 -260.736544) (xy 360.707224 -260.752592)
			(xy 360.655929 -260.760717) (xy 360.603995 -260.760717) (xy 360.5527 -260.752592) (xy 360.503307 -260.736544)
			(xy 360.457033 -260.712966) (xy 360.415017 -260.68244) (xy 360.378294 -260.645717) (xy 360.347768 -260.603701)
			(xy 360.32419 -260.557427) (xy 360.308142 -260.508034) (xy 360.300017 -260.456739) (xy 360.020107 -260.456739)
			(xy 360.011982 -260.508034) (xy 359.995934 -260.557427) (xy 359.972356 -260.603701) (xy 359.94183 -260.645717)
			(xy 359.905107 -260.68244) (xy 359.863091 -260.712966) (xy 359.816817 -260.736544) (xy 359.767424 -260.752592)
			(xy 359.716129 -260.760717) (xy 359.664195 -260.760717) (xy 359.6129 -260.752592) (xy 359.563507 -260.736544)
			(xy 359.517233 -260.712966) (xy 359.475217 -260.68244) (xy 359.438494 -260.645717) (xy 359.407968 -260.603701)
			(xy 359.38439 -260.557427) (xy 359.368342 -260.508034) (xy 359.360217 -260.456739) (xy 359.080561 -260.456739)
			(xy 359.072436 -260.508034) (xy 359.056388 -260.557427) (xy 359.03281 -260.603701) (xy 359.002284 -260.645717)
			(xy 358.965561 -260.68244) (xy 358.923545 -260.712966) (xy 358.877271 -260.736544) (xy 358.827878 -260.752592)
			(xy 358.776583 -260.760717) (xy 358.724649 -260.760717) (xy 358.673354 -260.752592) (xy 358.623961 -260.736544)
			(xy 358.577687 -260.712966) (xy 358.535671 -260.68244) (xy 358.498948 -260.645717) (xy 358.468422 -260.603701)
			(xy 358.444844 -260.557427) (xy 358.428796 -260.508034) (xy 358.420671 -260.456739) (xy 358.140507 -260.456739)
			(xy 358.132382 -260.508034) (xy 358.116334 -260.557427) (xy 358.092756 -260.603701) (xy 358.06223 -260.645717)
			(xy 358.025507 -260.68244) (xy 357.983491 -260.712966) (xy 357.937217 -260.736544) (xy 357.887824 -260.752592)
			(xy 357.836529 -260.760717) (xy 357.784595 -260.760717) (xy 357.7333 -260.752592) (xy 357.683907 -260.736544)
			(xy 357.637633 -260.712966) (xy 357.595617 -260.68244) (xy 357.558894 -260.645717) (xy 357.528368 -260.603701)
			(xy 357.50479 -260.557427) (xy 357.488742 -260.508034) (xy 357.480617 -260.456739) (xy 356.672054 -260.456739)
			(xy 356.697326 -260.460742) (xy 356.746719 -260.47679) (xy 356.792993 -260.500368) (xy 356.835009 -260.530894)
			(xy 356.871732 -260.567617) (xy 356.902258 -260.609633) (xy 356.925836 -260.655907) (xy 356.941884 -260.7053)
			(xy 356.950009 -260.756595) (xy 356.950518 -260.782562) (xy 356.950518 -260.782816) (xy 356.950071 -260.807343)
			(xy 356.942806 -260.855856) (xy 356.928453 -260.902763) (xy 356.907328 -260.947034) (xy 356.879892 -260.987698)
			(xy 356.86365 -261.006082) (xy 356.853881 -261.017599) (xy 356.84086 -261.044826) (xy 356.836383 -261.074672)
			(xy 356.840844 -261.10452) (xy 356.85385 -261.131754) (xy 356.86365 -261.143242) (xy 356.86619 -261.14629)
			(xy 356.876307 -261.156907) (xy 356.901279 -261.172266) (xy 356.929583 -261.179906) (xy 356.958892 -261.179199)
			(xy 356.986796 -261.170204) (xy 357.010999 -261.153661) (xy 357.029513 -261.130928) (xy 357.035608 -261.117588)
			(xy 357.04535 -261.095327) (xy 357.070431 -261.05371) (xy 357.101336 -261.016214) (xy 357.137397 -260.983646)
			(xy 357.177839 -260.95671) (xy 357.221788 -260.935985) (xy 357.268298 -260.921918) (xy 357.316367 -260.914813)
			(xy 357.340662 -260.914388) (xy 357.366637 -260.914784) (xy 357.417947 -260.922905) (xy 357.467355 -260.938954)
			(xy 357.513643 -260.962535) (xy 357.555673 -260.993067) (xy 357.592409 -261.029798) (xy 357.622945 -261.071824)
			(xy 357.646531 -261.11811) (xy 357.662586 -261.167516) (xy 357.670713 -261.218826) (xy 357.670713 -261.270774)
			(xy 357.662586 -261.322084) (xy 357.646531 -261.37149) (xy 357.622946 -261.417776) (xy 357.592409 -261.459802)
			(xy 357.555673 -261.496533) (xy 357.513643 -261.527065) (xy 357.467355 -261.550646) (xy 357.417947 -261.566695)
			(xy 357.366637 -261.574816) (xy 357.340662 -261.575296) (xy 357.312879 -261.574683) (xy 357.258096 -261.565386)
			(xy 357.205639 -261.547059) (xy 357.156985 -261.52022) (xy 357.113503 -261.485624) (xy 357.094536 -261.465314)
			(xy 357.084392 -261.454725) (xy 357.059427 -261.439365) (xy 357.031129 -261.431721) (xy 357.001825 -261.432423)
			(xy 356.973926 -261.441413) (xy 356.949725 -261.457952) (xy 356.931213 -261.480679) (xy 356.925118 -261.494016)
			(xy 356.913505 -261.520287) (xy 356.882598 -261.568695) (xy 356.86365 -261.590282) (xy 356.853881 -261.601799)
			(xy 356.84086 -261.629026) (xy 356.836383 -261.658872) (xy 356.840844 -261.68872) (xy 356.85385 -261.715954)
			(xy 356.86365 -261.727442) (xy 356.879879 -261.745838) (xy 356.907329 -261.786492) (xy 356.928463 -261.83076)
			(xy 356.942815 -261.877667) (xy 356.950071 -261.926181) (xy 356.950518 -261.950708) (xy 356.950518 -261.950962)
			(xy 356.950066 -261.975015) (xy 356.943108 -262.022614) (xy 356.929318 -262.0687) (xy 356.908989 -262.112298)
			(xy 356.88255 -262.152486) (xy 356.85056 -262.188414) (xy 356.832408 -262.2042) (xy 356.824314 -262.21183)
			(xy 356.814945 -262.23197) (xy 356.814934 -262.254182) (xy 356.824284 -262.274331) (xy 356.832408 -262.281924)
			(xy 356.844854 -262.2931) (xy 356.880668 -262.326374) (xy 357.57104 -261.636256) (xy 357.960168 -261.636256)
			(xy 357.974849 -261.635709) (xy 358.002994 -261.62734) (xy 358.027597 -261.611312) (xy 358.046626 -261.58895)
			(xy 358.058509 -261.562099) (xy 358.062267 -261.532978) (xy 358.057587 -261.50399) (xy 358.044857 -261.47753)
			(xy 358.035352 -261.46633) (xy 358.019359 -261.448038) (xy 357.99238 -261.40763) (xy 357.971622 -261.363701)
			(xy 357.957537 -261.3172) (xy 357.950429 -261.269136) (xy 357.950008 -261.244842) (xy 357.950517 -261.218875)
			(xy 357.958642 -261.16758) (xy 357.97469 -261.118187) (xy 357.998268 -261.071913) (xy 358.028794 -261.029897)
			(xy 358.065517 -260.993174) (xy 358.107533 -260.962648) (xy 358.153807 -260.93907) (xy 358.2032 -260.923022)
			(xy 358.254495 -260.914897) (xy 358.306429 -260.914897) (xy 358.357724 -260.923022) (xy 358.407117 -260.93907)
			(xy 358.453391 -260.962648) (xy 358.495407 -260.993174) (xy 358.53213 -261.029897) (xy 358.562656 -261.071913)
			(xy 358.586234 -261.118187) (xy 358.602282 -261.16758) (xy 358.610407 -261.218875) (xy 358.610916 -261.244842)
			(xy 358.610426 -261.269129) (xy 358.603278 -261.317174) (xy 358.589188 -261.36366) (xy 358.568456 -261.407588)
			(xy 358.541528 -261.448015) (xy 358.525572 -261.46633) (xy 358.516091 -261.477534) (xy 358.503421 -261.503997)
			(xy 358.49878 -261.532968) (xy 358.502551 -261.562065) (xy 358.514424 -261.588895) (xy 358.533421 -261.611254)
			(xy 358.557982 -261.627304) (xy 358.586088 -261.635724) (xy 358.600756 -261.636256) (xy 358.900222 -261.636256)
			(xy 358.914903 -261.635742) (xy 358.943045 -261.627361) (xy 358.967643 -261.611325) (xy 358.986667 -261.588959)
			(xy 358.998549 -261.562107) (xy 359.002307 -261.532985) (xy 358.997631 -261.503997) (xy 358.984907 -261.477533)
			(xy 358.975406 -261.46633) (xy 358.959406 -261.448045) (xy 358.932428 -261.407634) (xy 358.911673 -261.363703)
			(xy 358.89759 -261.317201) (xy 358.890483 -261.269136) (xy 358.890062 -261.244842) (xy 358.890571 -261.218875)
			(xy 358.898696 -261.16758) (xy 358.914744 -261.118187) (xy 358.938322 -261.071913) (xy 358.968848 -261.029897)
			(xy 359.005571 -260.993174) (xy 359.047587 -260.962648) (xy 359.093861 -260.93907) (xy 359.143254 -260.923022)
			(xy 359.194549 -260.914897) (xy 359.246483 -260.914897) (xy 359.297778 -260.923022) (xy 359.347171 -260.93907)
			(xy 359.393445 -260.962648) (xy 359.435461 -260.993174) (xy 359.472184 -261.029897) (xy 359.50271 -261.071913)
			(xy 359.526288 -261.118187) (xy 359.542336 -261.16758) (xy 359.550461 -261.218875) (xy 359.55097 -261.244842)
			(xy 359.550552 -261.268956) (xy 359.543536 -261.316672) (xy 359.529659 -261.362861) (xy 359.509216 -261.406543)
			(xy 359.482641 -261.44679) (xy 359.466896 -261.46506) (xy 359.457437 -261.476236) (xy 359.444912 -261.502692)
			(xy 359.440408 -261.531614) (xy 359.444296 -261.560626) (xy 359.456256 -261.587343) (xy 359.475305 -261.609568)
			(xy 359.499876 -261.625475) (xy 359.527952 -261.633756) (xy 359.542588 -261.634224) (xy 359.838244 -261.634224)
			(xy 359.852854 -261.633654) (xy 359.880868 -261.625339) (xy 359.90538 -261.609431) (xy 359.924384 -261.587232)
			(xy 359.936323 -261.560561) (xy 359.94022 -261.5316) (xy 359.935757 -261.502721) (xy 359.923297 -261.476288)
			(xy 359.913936 -261.46506) (xy 359.898214 -261.446772) (xy 359.871639 -261.40653) (xy 359.851196 -261.362852)
			(xy 359.837319 -261.316667) (xy 359.830303 -261.268955) (xy 359.829862 -261.244842) (xy 359.830371 -261.218875)
			(xy 359.838496 -261.16758) (xy 359.854544 -261.118187) (xy 359.878122 -261.071913) (xy 359.908648 -261.029897)
			(xy 359.945371 -260.993174) (xy 359.987387 -260.962648) (xy 360.033661 -260.93907) (xy 360.083054 -260.923022)
			(xy 360.134349 -260.914897) (xy 360.186283 -260.914897) (xy 360.237578 -260.923022) (xy 360.286971 -260.93907)
			(xy 360.333245 -260.962648) (xy 360.375261 -260.993174) (xy 360.411984 -261.029897) (xy 360.44251 -261.071913)
			(xy 360.466088 -261.118187) (xy 360.482136 -261.16758) (xy 360.490261 -261.218875) (xy 360.49077 -261.244842)
			(xy 360.490352 -261.268956) (xy 360.483336 -261.316672) (xy 360.469459 -261.362861) (xy 360.449016 -261.406543)
			(xy 360.422441 -261.44679) (xy 360.406696 -261.46506) (xy 360.397237 -261.476236) (xy 360.384712 -261.502692)
			(xy 360.380208 -261.531614) (xy 360.384096 -261.560626) (xy 360.396056 -261.587343) (xy 360.415105 -261.609568)
			(xy 360.439676 -261.625475) (xy 360.467752 -261.633756) (xy 360.482388 -261.634224) (xy 360.77779 -261.634224)
			(xy 360.7924 -261.633621) (xy 360.820417 -261.625318) (xy 360.844934 -261.609417) (xy 360.863942 -261.587223)
			(xy 360.875883 -261.560553) (xy 360.87978 -261.531592) (xy 360.875312 -261.502714) (xy 360.862847 -261.476285)
			(xy 360.853482 -261.46506) (xy 360.837752 -261.446779) (xy 360.81118 -261.406534) (xy 360.790739 -261.362854)
			(xy 360.776864 -261.316668) (xy 360.769849 -261.268955) (xy 360.769408 -261.244842) (xy 360.769917 -261.218875)
			(xy 360.778042 -261.16758) (xy 360.79409 -261.118187) (xy 360.817668 -261.071913) (xy 360.848194 -261.029897)
			(xy 360.884917 -260.993174) (xy 360.926933 -260.962648) (xy 360.973207 -260.93907) (xy 361.0226 -260.923022)
			(xy 361.073895 -260.914897) (xy 361.125829 -260.914897) (xy 361.177124 -260.923022) (xy 361.226517 -260.93907)
			(xy 361.272791 -260.962648) (xy 361.314807 -260.993174) (xy 361.35153 -261.029897) (xy 361.382056 -261.071913)
			(xy 361.405634 -261.118187) (xy 361.421682 -261.16758) (xy 361.429807 -261.218875) (xy 361.430316 -261.244842)
			(xy 361.429912 -261.268957) (xy 361.422894 -261.316674) (xy 361.409015 -261.362864) (xy 361.388568 -261.406546)
			(xy 361.361989 -261.446791) (xy 361.346242 -261.46506) (xy 361.33682 -261.476261) (xy 361.324306 -261.50271)
			(xy 361.319808 -261.531622) (xy 361.323695 -261.560623) (xy 361.335648 -261.58733) (xy 361.354685 -261.609551)
			(xy 361.379243 -261.625459) (xy 361.407304 -261.633749) (xy 361.421934 -261.634224) (xy 361.717844 -261.634224)
			(xy 361.732454 -261.633654) (xy 361.760468 -261.625339) (xy 361.78498 -261.609431) (xy 361.803984 -261.587232)
			(xy 361.815923 -261.560561) (xy 361.81982 -261.5316) (xy 361.815357 -261.502721) (xy 361.802897 -261.476288)
			(xy 361.793536 -261.46506) (xy 361.777814 -261.446772) (xy 361.751239 -261.40653) (xy 361.730796 -261.362852)
			(xy 361.716919 -261.316667) (xy 361.709903 -261.268955) (xy 361.709462 -261.244842) (xy 361.709971 -261.218875)
			(xy 361.718096 -261.16758) (xy 361.734144 -261.118187) (xy 361.757722 -261.071913) (xy 361.788248 -261.029897)
			(xy 361.824971 -260.993174) (xy 361.866987 -260.962648) (xy 361.913261 -260.93907) (xy 361.962654 -260.923022)
			(xy 362.013949 -260.914897) (xy 362.065883 -260.914897) (xy 362.117178 -260.923022) (xy 362.166571 -260.93907)
			(xy 362.212845 -260.962648) (xy 362.254861 -260.993174) (xy 362.291584 -261.029897) (xy 362.32211 -261.071913)
			(xy 362.345688 -261.118187) (xy 362.361736 -261.16758) (xy 362.369861 -261.218875) (xy 362.37037 -261.244842)
			(xy 362.369952 -261.268956) (xy 362.362936 -261.316672) (xy 362.349059 -261.362861) (xy 362.328616 -261.406543)
			(xy 362.302041 -261.44679) (xy 362.286296 -261.46506) (xy 362.276837 -261.476236) (xy 362.264312 -261.502692)
			(xy 362.259808 -261.531614) (xy 362.263696 -261.560626) (xy 362.275656 -261.587343) (xy 362.294705 -261.609568)
			(xy 362.319276 -261.625475) (xy 362.347352 -261.633756) (xy 362.361988 -261.634224) (xy 366.816386 -261.634224)
			(xy 367.203228 -261.247382) (xy 367.206784 -261.235952) (xy 367.21525 -261.211336) (xy 367.238855 -261.164942)
			(xy 367.26944 -261.122821) (xy 367.30625 -261.086016) (xy 367.348374 -261.055435) (xy 367.394771 -261.031835)
			(xy 367.419382 -261.023354) (xy 367.430812 -261.019798) (xy 368.395504 -260.05536) (xy 368.533172 -260.05536)
			(xy 368.548198 -260.054863) (xy 368.576953 -260.046127) (xy 368.601923 -260.029403) (xy 368.620946 -260.006138)
			(xy 368.632378 -259.978344) (xy 368.635228 -259.948427) (xy 368.629251 -259.918975) (xy 368.62258 -259.9055)
			(xy 368.610224 -259.881332) (xy 368.592691 -259.829966) (xy 368.583781 -259.776427) (xy 368.58321 -259.74929)
			(xy 368.583746 -259.723324) (xy 368.591871 -259.672032) (xy 368.607918 -259.622643) (xy 368.631494 -259.576371)
			(xy 368.662018 -259.534357) (xy 368.698737 -259.497635) (xy 368.740749 -259.467108) (xy 368.787019 -259.443528)
			(xy 368.836407 -259.427477) (xy 368.887698 -259.419348) (xy 368.913664 -259.418836) (xy 368.914172 -259.418836)
			(xy 368.941516 -259.419355) (xy 368.99545 -259.428404) (xy 369.047159 -259.446211) (xy 369.095229 -259.472289)
			(xy 369.117118 -259.488686) (xy 369.128968 -259.497343) (xy 369.156268 -259.508082) (xy 369.185495 -259.510614)
			(xy 369.214235 -259.504729) (xy 369.240114 -259.490914) (xy 369.260996 -259.47031) (xy 369.268502 -259.457698)
			(xy 369.281094 -259.435841) (xy 369.311837 -259.395854) (xy 369.3483 -259.361003) (xy 369.389634 -259.332096)
			(xy 369.434881 -259.309806) (xy 369.48299 -259.294651) (xy 369.532842 -259.286981) (xy 369.558062 -259.286502)
			(xy 369.58403 -259.28707) (xy 369.635327 -259.295189) (xy 369.684722 -259.311233) (xy 369.730999 -259.334808)
			(xy 369.773017 -259.365332) (xy 369.809743 -259.402054) (xy 369.840272 -259.444069) (xy 369.863852 -259.490343)
			(xy 369.879902 -259.539736) (xy 369.888027 -259.591032) (xy 369.888027 -259.642923) (xy 370.167917 -259.642923)
			(xy 370.167917 -259.590989) (xy 370.176042 -259.539694) (xy 370.19209 -259.490301) (xy 370.215668 -259.444027)
			(xy 370.246194 -259.402011) (xy 370.282917 -259.365288) (xy 370.324933 -259.334762) (xy 370.371207 -259.311184)
			(xy 370.4206 -259.295136) (xy 370.471895 -259.287011) (xy 370.523829 -259.287011) (xy 370.575124 -259.295136)
			(xy 370.624517 -259.311184) (xy 370.670791 -259.334762) (xy 370.712807 -259.365288) (xy 370.74953 -259.402011)
			(xy 370.780056 -259.444027) (xy 370.803634 -259.490301) (xy 370.819682 -259.539694) (xy 370.827807 -259.590989)
			(xy 370.828316 -259.616956) (xy 370.827807 -259.642923) (xy 371.107717 -259.642923) (xy 371.107717 -259.590989)
			(xy 371.115842 -259.539694) (xy 371.13189 -259.490301) (xy 371.155468 -259.444027) (xy 371.185994 -259.402011)
			(xy 371.222717 -259.365288) (xy 371.264733 -259.334762) (xy 371.311007 -259.311184) (xy 371.3604 -259.295136)
			(xy 371.411695 -259.287011) (xy 371.463629 -259.287011) (xy 371.514924 -259.295136) (xy 371.564317 -259.311184)
			(xy 371.610591 -259.334762) (xy 371.652607 -259.365288) (xy 371.68933 -259.402011) (xy 371.719856 -259.444027)
			(xy 371.743434 -259.490301) (xy 371.759482 -259.539694) (xy 371.767607 -259.590989) (xy 371.768116 -259.616956)
			(xy 371.767607 -259.642923) (xy 372.047517 -259.642923) (xy 372.047517 -259.590989) (xy 372.055642 -259.539694)
			(xy 372.07169 -259.490301) (xy 372.095268 -259.444027) (xy 372.125794 -259.402011) (xy 372.162517 -259.365288)
			(xy 372.204533 -259.334762) (xy 372.250807 -259.311184) (xy 372.3002 -259.295136) (xy 372.351495 -259.287011)
			(xy 372.403429 -259.287011) (xy 372.454724 -259.295136) (xy 372.504117 -259.311184) (xy 372.550391 -259.334762)
			(xy 372.592407 -259.365288) (xy 372.62913 -259.402011) (xy 372.659656 -259.444027) (xy 372.683234 -259.490301)
			(xy 372.699282 -259.539694) (xy 372.707407 -259.590989) (xy 372.707916 -259.616956) (xy 372.707407 -259.642923)
			(xy 372.987317 -259.642923) (xy 372.987317 -259.590989) (xy 372.995442 -259.539694) (xy 373.01149 -259.490301)
			(xy 373.035068 -259.444027) (xy 373.065594 -259.402011) (xy 373.102317 -259.365288) (xy 373.144333 -259.334762)
			(xy 373.190607 -259.311184) (xy 373.24 -259.295136) (xy 373.291295 -259.287011) (xy 373.343229 -259.287011)
			(xy 373.394524 -259.295136) (xy 373.443917 -259.311184) (xy 373.490191 -259.334762) (xy 373.532207 -259.365288)
			(xy 373.56893 -259.402011) (xy 373.599456 -259.444027) (xy 373.623034 -259.490301) (xy 373.639082 -259.539694)
			(xy 373.647207 -259.590989) (xy 373.647716 -259.616956) (xy 373.647207 -259.642923) (xy 373.927117 -259.642923)
			(xy 373.927117 -259.590989) (xy 373.935242 -259.539694) (xy 373.95129 -259.490301) (xy 373.974868 -259.444027)
			(xy 374.005394 -259.402011) (xy 374.042117 -259.365288) (xy 374.084133 -259.334762) (xy 374.130407 -259.311184)
			(xy 374.1798 -259.295136) (xy 374.231095 -259.287011) (xy 374.283029 -259.287011) (xy 374.334324 -259.295136)
			(xy 374.383717 -259.311184) (xy 374.429991 -259.334762) (xy 374.472007 -259.365288) (xy 374.50873 -259.402011)
			(xy 374.539256 -259.444027) (xy 374.562834 -259.490301) (xy 374.578882 -259.539694) (xy 374.587007 -259.590989)
			(xy 374.587516 -259.616956) (xy 374.587007 -259.642923) (xy 374.866917 -259.642923) (xy 374.866917 -259.590989)
			(xy 374.875042 -259.539694) (xy 374.89109 -259.490301) (xy 374.914668 -259.444027) (xy 374.945194 -259.402011)
			(xy 374.981917 -259.365288) (xy 375.023933 -259.334762) (xy 375.070207 -259.311184) (xy 375.1196 -259.295136)
			(xy 375.170895 -259.287011) (xy 375.222829 -259.287011) (xy 375.274124 -259.295136) (xy 375.323517 -259.311184)
			(xy 375.369791 -259.334762) (xy 375.411807 -259.365288) (xy 375.44853 -259.402011) (xy 375.479056 -259.444027)
			(xy 375.502634 -259.490301) (xy 375.518682 -259.539694) (xy 375.526807 -259.590989) (xy 375.527316 -259.616956)
			(xy 375.526807 -259.642923) (xy 375.806717 -259.642923) (xy 375.806717 -259.590989) (xy 375.814842 -259.539694)
			(xy 375.83089 -259.490301) (xy 375.854468 -259.444027) (xy 375.884994 -259.402011) (xy 375.921717 -259.365288)
			(xy 375.963733 -259.334762) (xy 376.010007 -259.311184) (xy 376.0594 -259.295136) (xy 376.110695 -259.287011)
			(xy 376.162629 -259.287011) (xy 376.213924 -259.295136) (xy 376.263317 -259.311184) (xy 376.309591 -259.334762)
			(xy 376.351607 -259.365288) (xy 376.38833 -259.402011) (xy 376.418856 -259.444027) (xy 376.442434 -259.490301)
			(xy 376.458482 -259.539694) (xy 376.466607 -259.590989) (xy 376.467116 -259.616956) (xy 376.466607 -259.642923)
			(xy 376.746517 -259.642923) (xy 376.746517 -259.590989) (xy 376.754642 -259.539694) (xy 376.77069 -259.490301)
			(xy 376.794268 -259.444027) (xy 376.824794 -259.402011) (xy 376.861517 -259.365288) (xy 376.903533 -259.334762)
			(xy 376.949807 -259.311184) (xy 376.9992 -259.295136) (xy 377.050495 -259.287011) (xy 377.102429 -259.287011)
			(xy 377.153724 -259.295136) (xy 377.203117 -259.311184) (xy 377.249391 -259.334762) (xy 377.291407 -259.365288)
			(xy 377.32813 -259.402011) (xy 377.358656 -259.444027) (xy 377.382234 -259.490301) (xy 377.398282 -259.539694)
			(xy 377.406407 -259.590989) (xy 377.406916 -259.616956) (xy 377.406407 -259.642923) (xy 377.398282 -259.694218)
			(xy 377.382234 -259.743611) (xy 377.358656 -259.789885) (xy 377.32813 -259.831901) (xy 377.291407 -259.868624)
			(xy 377.249391 -259.89915) (xy 377.203117 -259.922728) (xy 377.153724 -259.938776) (xy 377.102429 -259.946901)
			(xy 377.050495 -259.946901) (xy 376.9992 -259.938776) (xy 376.949807 -259.922728) (xy 376.903533 -259.89915)
			(xy 376.861517 -259.868624) (xy 376.824794 -259.831901) (xy 376.794268 -259.789885) (xy 376.77069 -259.743611)
			(xy 376.754642 -259.694218) (xy 376.746517 -259.642923) (xy 376.466607 -259.642923) (xy 376.458482 -259.694218)
			(xy 376.442434 -259.743611) (xy 376.418856 -259.789885) (xy 376.38833 -259.831901) (xy 376.351607 -259.868624)
			(xy 376.309591 -259.89915) (xy 376.263317 -259.922728) (xy 376.213924 -259.938776) (xy 376.162629 -259.946901)
			(xy 376.110695 -259.946901) (xy 376.0594 -259.938776) (xy 376.010007 -259.922728) (xy 375.963733 -259.89915)
			(xy 375.921717 -259.868624) (xy 375.884994 -259.831901) (xy 375.854468 -259.789885) (xy 375.83089 -259.743611)
			(xy 375.814842 -259.694218) (xy 375.806717 -259.642923) (xy 375.526807 -259.642923) (xy 375.518682 -259.694218)
			(xy 375.502634 -259.743611) (xy 375.479056 -259.789885) (xy 375.44853 -259.831901) (xy 375.411807 -259.868624)
			(xy 375.369791 -259.89915) (xy 375.323517 -259.922728) (xy 375.274124 -259.938776) (xy 375.222829 -259.946901)
			(xy 375.170895 -259.946901) (xy 375.1196 -259.938776) (xy 375.070207 -259.922728) (xy 375.023933 -259.89915)
			(xy 374.981917 -259.868624) (xy 374.945194 -259.831901) (xy 374.914668 -259.789885) (xy 374.89109 -259.743611)
			(xy 374.875042 -259.694218) (xy 374.866917 -259.642923) (xy 374.587007 -259.642923) (xy 374.578882 -259.694218)
			(xy 374.562834 -259.743611) (xy 374.539256 -259.789885) (xy 374.50873 -259.831901) (xy 374.472007 -259.868624)
			(xy 374.429991 -259.89915) (xy 374.383717 -259.922728) (xy 374.334324 -259.938776) (xy 374.283029 -259.946901)
			(xy 374.231095 -259.946901) (xy 374.1798 -259.938776) (xy 374.130407 -259.922728) (xy 374.084133 -259.89915)
			(xy 374.042117 -259.868624) (xy 374.005394 -259.831901) (xy 373.974868 -259.789885) (xy 373.95129 -259.743611)
			(xy 373.935242 -259.694218) (xy 373.927117 -259.642923) (xy 373.647207 -259.642923) (xy 373.639082 -259.694218)
			(xy 373.623034 -259.743611) (xy 373.599456 -259.789885) (xy 373.56893 -259.831901) (xy 373.532207 -259.868624)
			(xy 373.490191 -259.89915) (xy 373.443917 -259.922728) (xy 373.394524 -259.938776) (xy 373.343229 -259.946901)
			(xy 373.291295 -259.946901) (xy 373.24 -259.938776) (xy 373.190607 -259.922728) (xy 373.144333 -259.89915)
			(xy 373.102317 -259.868624) (xy 373.065594 -259.831901) (xy 373.035068 -259.789885) (xy 373.01149 -259.743611)
			(xy 372.995442 -259.694218) (xy 372.987317 -259.642923) (xy 372.707407 -259.642923) (xy 372.699282 -259.694218)
			(xy 372.683234 -259.743611) (xy 372.659656 -259.789885) (xy 372.62913 -259.831901) (xy 372.592407 -259.868624)
			(xy 372.550391 -259.89915) (xy 372.504117 -259.922728) (xy 372.454724 -259.938776) (xy 372.403429 -259.946901)
			(xy 372.351495 -259.946901) (xy 372.3002 -259.938776) (xy 372.250807 -259.922728) (xy 372.204533 -259.89915)
			(xy 372.162517 -259.868624) (xy 372.125794 -259.831901) (xy 372.095268 -259.789885) (xy 372.07169 -259.743611)
			(xy 372.055642 -259.694218) (xy 372.047517 -259.642923) (xy 371.767607 -259.642923) (xy 371.759482 -259.694218)
			(xy 371.743434 -259.743611) (xy 371.719856 -259.789885) (xy 371.68933 -259.831901) (xy 371.652607 -259.868624)
			(xy 371.610591 -259.89915) (xy 371.564317 -259.922728) (xy 371.514924 -259.938776) (xy 371.463629 -259.946901)
			(xy 371.411695 -259.946901) (xy 371.3604 -259.938776) (xy 371.311007 -259.922728) (xy 371.264733 -259.89915)
			(xy 371.222717 -259.868624) (xy 371.185994 -259.831901) (xy 371.155468 -259.789885) (xy 371.13189 -259.743611)
			(xy 371.115842 -259.694218) (xy 371.107717 -259.642923) (xy 370.827807 -259.642923) (xy 370.819682 -259.694218)
			(xy 370.803634 -259.743611) (xy 370.780056 -259.789885) (xy 370.74953 -259.831901) (xy 370.712807 -259.868624)
			(xy 370.670791 -259.89915) (xy 370.624517 -259.922728) (xy 370.575124 -259.938776) (xy 370.523829 -259.946901)
			(xy 370.471895 -259.946901) (xy 370.4206 -259.938776) (xy 370.371207 -259.922728) (xy 370.324933 -259.89915)
			(xy 370.282917 -259.868624) (xy 370.246194 -259.831901) (xy 370.215668 -259.789885) (xy 370.19209 -259.743611)
			(xy 370.176042 -259.694218) (xy 370.167917 -259.642923) (xy 369.888027 -259.642923) (xy 369.888027 -259.642968)
			(xy 369.879902 -259.694264) (xy 369.863852 -259.743657) (xy 369.840272 -259.789931) (xy 369.809743 -259.831946)
			(xy 369.773017 -259.868668) (xy 369.730998 -259.899192) (xy 369.684722 -259.922767) (xy 369.635327 -259.938811)
			(xy 369.58403 -259.94693) (xy 369.558062 -259.94741) (xy 369.530348 -259.946857) (xy 369.475696 -259.93761)
			(xy 369.423357 -259.919366) (xy 369.374799 -259.892636) (xy 369.331388 -259.858172) (xy 369.312444 -259.837936)
			(xy 369.304943 -259.830421) (xy 369.285552 -259.821817) (xy 369.264339 -259.821756) (xy 369.244899 -259.830248)
			(xy 369.23053 -259.845853) (xy 369.226592 -259.855716) (xy 369.222041 -259.868542) (xy 369.211103 -259.893465)
			(xy 369.204748 -259.9055) (xy 369.198174 -259.919012) (xy 369.192207 -259.948441) (xy 369.195056 -259.978332)
			(xy 369.206475 -260.006103) (xy 369.225476 -260.029353) (xy 369.250417 -260.046073) (xy 369.279143 -260.054817)
			(xy 369.294156 -260.05536) (xy 370.930678 -260.05536) (xy 370.975382 -260.09981) (xy 370.994178 -260.101334)
			(xy 371.019998 -260.103905) (xy 371.070441 -260.116047) (xy 371.118368 -260.135921) (xy 371.1626 -260.163041)
			(xy 371.202051 -260.19674) (xy 371.235751 -260.23619) (xy 371.262873 -260.280421) (xy 371.282749 -260.328347)
			(xy 371.294893 -260.37879) (xy 371.297454 -260.40461) (xy 371.298978 -260.423406) (xy 371.404642 -260.52907)
			(xy 371.414615 -260.538441) (xy 371.438367 -260.552009) (xy 371.464871 -260.558773) (xy 371.49222 -260.558246)
			(xy 371.518445 -260.550466) (xy 371.541657 -260.535994) (xy 371.560185 -260.515871) (xy 371.572697 -260.491546)
			(xy 371.57829 -260.46477) (xy 371.57787 -260.451092) (xy 371.577362 -260.430772) (xy 371.577885 -260.404808)
			(xy 371.586013 -260.353519) (xy 371.602063 -260.304133) (xy 371.625642 -260.257866) (xy 371.656167 -260.215857)
			(xy 371.692889 -260.179141) (xy 371.734902 -260.14862) (xy 371.781172 -260.125048) (xy 371.830559 -260.109003)
			(xy 371.881849 -260.100882) (xy 371.933778 -260.100884) (xy 371.985067 -260.109009) (xy 372.034453 -260.125058)
			(xy 372.080721 -260.148634) (xy 372.122732 -260.179158) (xy 372.15945 -260.215878) (xy 372.189972 -260.257889)
			(xy 372.213547 -260.304158) (xy 372.229593 -260.353545) (xy 372.237717 -260.404834) (xy 372.237717 -260.456739)
			(xy 372.517671 -260.456739) (xy 372.517671 -260.404805) (xy 372.525796 -260.35351) (xy 372.541844 -260.304117)
			(xy 372.565422 -260.257843) (xy 372.595948 -260.215827) (xy 372.632671 -260.179104) (xy 372.674687 -260.148578)
			(xy 372.720961 -260.125) (xy 372.770354 -260.108952) (xy 372.821649 -260.100827) (xy 372.873583 -260.100827)
			(xy 372.924878 -260.108952) (xy 372.974271 -260.125) (xy 373.020545 -260.148578) (xy 373.062561 -260.179104)
			(xy 373.099284 -260.215827) (xy 373.12981 -260.257843) (xy 373.153388 -260.304117) (xy 373.169436 -260.35351)
			(xy 373.177561 -260.404805) (xy 373.17807 -260.430772) (xy 373.177561 -260.456739) (xy 373.457471 -260.456739)
			(xy 373.457471 -260.404805) (xy 373.465596 -260.35351) (xy 373.481644 -260.304117) (xy 373.505222 -260.257843)
			(xy 373.535748 -260.215827) (xy 373.572471 -260.179104) (xy 373.614487 -260.148578) (xy 373.660761 -260.125)
			(xy 373.710154 -260.108952) (xy 373.761449 -260.100827) (xy 373.813383 -260.100827) (xy 373.864678 -260.108952)
			(xy 373.914071 -260.125) (xy 373.960345 -260.148578) (xy 374.002361 -260.179104) (xy 374.039084 -260.215827)
			(xy 374.06961 -260.257843) (xy 374.093188 -260.304117) (xy 374.109236 -260.35351) (xy 374.117361 -260.404805)
			(xy 374.11787 -260.430772) (xy 374.117361 -260.456739) (xy 374.397017 -260.456739) (xy 374.397017 -260.404805)
			(xy 374.405142 -260.35351) (xy 374.42119 -260.304117) (xy 374.444768 -260.257843) (xy 374.475294 -260.215827)
			(xy 374.512017 -260.179104) (xy 374.554033 -260.148578) (xy 374.600307 -260.125) (xy 374.6497 -260.108952)
			(xy 374.700995 -260.100827) (xy 374.752929 -260.100827) (xy 374.804224 -260.108952) (xy 374.853617 -260.125)
			(xy 374.899891 -260.148578) (xy 374.941907 -260.179104) (xy 374.97863 -260.215827) (xy 375.009156 -260.257843)
			(xy 375.032734 -260.304117) (xy 375.048782 -260.35351) (xy 375.056907 -260.404805) (xy 375.057416 -260.430772)
			(xy 375.056907 -260.456739) (xy 375.337071 -260.456739) (xy 375.337071 -260.404805) (xy 375.345196 -260.35351)
			(xy 375.361244 -260.304117) (xy 375.384822 -260.257843) (xy 375.415348 -260.215827) (xy 375.452071 -260.179104)
			(xy 375.494087 -260.148578) (xy 375.540361 -260.125) (xy 375.589754 -260.108952) (xy 375.641049 -260.100827)
			(xy 375.692983 -260.100827) (xy 375.744278 -260.108952) (xy 375.793671 -260.125) (xy 375.839945 -260.148578)
			(xy 375.881961 -260.179104) (xy 375.918684 -260.215827) (xy 375.94921 -260.257843) (xy 375.972788 -260.304117)
			(xy 375.988836 -260.35351) (xy 375.996961 -260.404805) (xy 375.99747 -260.430772) (xy 375.996961 -260.456739)
			(xy 376.276871 -260.456739) (xy 376.276871 -260.404805) (xy 376.284996 -260.35351) (xy 376.301044 -260.304117)
			(xy 376.324622 -260.257843) (xy 376.355148 -260.215827) (xy 376.391871 -260.179104) (xy 376.433887 -260.148578)
			(xy 376.480161 -260.125) (xy 376.529554 -260.108952) (xy 376.580849 -260.100827) (xy 376.632783 -260.100827)
			(xy 376.684078 -260.108952) (xy 376.733471 -260.125) (xy 376.779745 -260.148578) (xy 376.821761 -260.179104)
			(xy 376.858484 -260.215827) (xy 376.88901 -260.257843) (xy 376.912588 -260.304117) (xy 376.928636 -260.35351)
			(xy 376.936761 -260.404805) (xy 376.93727 -260.430772) (xy 376.936761 -260.456739) (xy 377.216671 -260.456739)
			(xy 377.216671 -260.404805) (xy 377.224796 -260.35351) (xy 377.240844 -260.304117) (xy 377.264422 -260.257843)
			(xy 377.294948 -260.215827) (xy 377.331671 -260.179104) (xy 377.373687 -260.148578) (xy 377.419961 -260.125)
			(xy 377.469354 -260.108952) (xy 377.520649 -260.100827) (xy 377.572583 -260.100827) (xy 377.623878 -260.108952)
			(xy 377.673271 -260.125) (xy 377.719545 -260.148578) (xy 377.761561 -260.179104) (xy 377.798284 -260.215827)
			(xy 377.82881 -260.257843) (xy 377.852388 -260.304117) (xy 377.868436 -260.35351) (xy 377.876561 -260.404805)
			(xy 377.87707 -260.430772) (xy 377.876561 -260.456739) (xy 377.868436 -260.508034) (xy 377.852388 -260.557427)
			(xy 377.82881 -260.603701) (xy 377.798284 -260.645717) (xy 377.761561 -260.68244) (xy 377.719545 -260.712966)
			(xy 377.673271 -260.736544) (xy 377.623878 -260.752592) (xy 377.572583 -260.760717) (xy 377.520649 -260.760717)
			(xy 377.469354 -260.752592) (xy 377.419961 -260.736544) (xy 377.373687 -260.712966) (xy 377.331671 -260.68244)
			(xy 377.294948 -260.645717) (xy 377.264422 -260.603701) (xy 377.240844 -260.557427) (xy 377.224796 -260.508034)
			(xy 377.216671 -260.456739) (xy 376.936761 -260.456739) (xy 376.928636 -260.508034) (xy 376.912588 -260.557427)
			(xy 376.88901 -260.603701) (xy 376.858484 -260.645717) (xy 376.821761 -260.68244) (xy 376.779745 -260.712966)
			(xy 376.733471 -260.736544) (xy 376.684078 -260.752592) (xy 376.632783 -260.760717) (xy 376.580849 -260.760717)
			(xy 376.529554 -260.752592) (xy 376.480161 -260.736544) (xy 376.433887 -260.712966) (xy 376.391871 -260.68244)
			(xy 376.355148 -260.645717) (xy 376.324622 -260.603701) (xy 376.301044 -260.557427) (xy 376.284996 -260.508034)
			(xy 376.276871 -260.456739) (xy 375.996961 -260.456739) (xy 375.988836 -260.508034) (xy 375.972788 -260.557427)
			(xy 375.94921 -260.603701) (xy 375.918684 -260.645717) (xy 375.881961 -260.68244) (xy 375.839945 -260.712966)
			(xy 375.793671 -260.736544) (xy 375.744278 -260.752592) (xy 375.692983 -260.760717) (xy 375.641049 -260.760717)
			(xy 375.589754 -260.752592) (xy 375.540361 -260.736544) (xy 375.494087 -260.712966) (xy 375.452071 -260.68244)
			(xy 375.415348 -260.645717) (xy 375.384822 -260.603701) (xy 375.361244 -260.557427) (xy 375.345196 -260.508034)
			(xy 375.337071 -260.456739) (xy 375.056907 -260.456739) (xy 375.048782 -260.508034) (xy 375.032734 -260.557427)
			(xy 375.009156 -260.603701) (xy 374.97863 -260.645717) (xy 374.941907 -260.68244) (xy 374.899891 -260.712966)
			(xy 374.853617 -260.736544) (xy 374.804224 -260.752592) (xy 374.752929 -260.760717) (xy 374.700995 -260.760717)
			(xy 374.6497 -260.752592) (xy 374.600307 -260.736544) (xy 374.554033 -260.712966) (xy 374.512017 -260.68244)
			(xy 374.475294 -260.645717) (xy 374.444768 -260.603701) (xy 374.42119 -260.557427) (xy 374.405142 -260.508034)
			(xy 374.397017 -260.456739) (xy 374.117361 -260.456739) (xy 374.109236 -260.508034) (xy 374.093188 -260.557427)
			(xy 374.06961 -260.603701) (xy 374.039084 -260.645717) (xy 374.002361 -260.68244) (xy 373.960345 -260.712966)
			(xy 373.914071 -260.736544) (xy 373.864678 -260.752592) (xy 373.813383 -260.760717) (xy 373.761449 -260.760717)
			(xy 373.710154 -260.752592) (xy 373.660761 -260.736544) (xy 373.614487 -260.712966) (xy 373.572471 -260.68244)
			(xy 373.535748 -260.645717) (xy 373.505222 -260.603701) (xy 373.481644 -260.557427) (xy 373.465596 -260.508034)
			(xy 373.457471 -260.456739) (xy 373.177561 -260.456739) (xy 373.169436 -260.508034) (xy 373.153388 -260.557427)
			(xy 373.12981 -260.603701) (xy 373.099284 -260.645717) (xy 373.062561 -260.68244) (xy 373.020545 -260.712966)
			(xy 372.974271 -260.736544) (xy 372.924878 -260.752592) (xy 372.873583 -260.760717) (xy 372.821649 -260.760717)
			(xy 372.770354 -260.752592) (xy 372.720961 -260.736544) (xy 372.674687 -260.712966) (xy 372.632671 -260.68244)
			(xy 372.595948 -260.645717) (xy 372.565422 -260.603701) (xy 372.541844 -260.557427) (xy 372.525796 -260.508034)
			(xy 372.517671 -260.456739) (xy 372.237717 -260.456739) (xy 372.237717 -260.456763) (xy 372.229594 -260.508052)
			(xy 372.213548 -260.557439) (xy 372.189974 -260.603709) (xy 372.159452 -260.64572) (xy 372.122734 -260.68244)
			(xy 372.080723 -260.712964) (xy 372.034456 -260.736541) (xy 371.985069 -260.75259) (xy 371.93378 -260.760716)
			(xy 371.907816 -260.761226) (xy 371.907562 -260.761226) (xy 371.882904 -260.76076) (xy 371.834137 -260.753406)
			(xy 371.787003 -260.738897) (xy 371.742543 -260.717553) (xy 371.721888 -260.704076) (xy 371.657626 -260.782054)
			(xy 371.720872 -260.845554) (xy 371.720872 -261.074408) (xy 371.727222 -261.085584) (xy 371.740118 -261.110122)
			(xy 371.75835 -261.162468) (xy 371.767592 -261.217122) (xy 371.767586 -261.270809) (xy 372.047517 -261.270809)
			(xy 372.047517 -261.218875) (xy 372.055642 -261.16758) (xy 372.07169 -261.118187) (xy 372.095268 -261.071913)
			(xy 372.125794 -261.029897) (xy 372.162517 -260.993174) (xy 372.204533 -260.962648) (xy 372.250807 -260.93907)
			(xy 372.3002 -260.923022) (xy 372.351495 -260.914897) (xy 372.403429 -260.914897) (xy 372.454724 -260.923022)
			(xy 372.504117 -260.93907) (xy 372.550391 -260.962648) (xy 372.592407 -260.993174) (xy 372.62913 -261.029897)
			(xy 372.659656 -261.071913) (xy 372.683234 -261.118187) (xy 372.699282 -261.16758) (xy 372.707407 -261.218875)
			(xy 372.707916 -261.244842) (xy 372.707407 -261.270809) (xy 372.987317 -261.270809) (xy 372.987317 -261.218875)
			(xy 372.995442 -261.16758) (xy 373.01149 -261.118187) (xy 373.035068 -261.071913) (xy 373.065594 -261.029897)
			(xy 373.102317 -260.993174) (xy 373.144333 -260.962648) (xy 373.190607 -260.93907) (xy 373.24 -260.923022)
			(xy 373.291295 -260.914897) (xy 373.343229 -260.914897) (xy 373.394524 -260.923022) (xy 373.443917 -260.93907)
			(xy 373.490191 -260.962648) (xy 373.532207 -260.993174) (xy 373.56893 -261.029897) (xy 373.599456 -261.071913)
			(xy 373.623034 -261.118187) (xy 373.639082 -261.16758) (xy 373.647207 -261.218875) (xy 373.647716 -261.244842)
			(xy 373.647207 -261.270809) (xy 373.927117 -261.270809) (xy 373.927117 -261.218875) (xy 373.935242 -261.16758)
			(xy 373.95129 -261.118187) (xy 373.974868 -261.071913) (xy 374.005394 -261.029897) (xy 374.042117 -260.993174)
			(xy 374.084133 -260.962648) (xy 374.130407 -260.93907) (xy 374.1798 -260.923022) (xy 374.231095 -260.914897)
			(xy 374.283029 -260.914897) (xy 374.334324 -260.923022) (xy 374.383717 -260.93907) (xy 374.429991 -260.962648)
			(xy 374.472007 -260.993174) (xy 374.50873 -261.029897) (xy 374.539256 -261.071913) (xy 374.562834 -261.118187)
			(xy 374.578882 -261.16758) (xy 374.587007 -261.218875) (xy 374.587516 -261.244842) (xy 374.587007 -261.270809)
			(xy 374.866917 -261.270809) (xy 374.866917 -261.218875) (xy 374.875042 -261.16758) (xy 374.89109 -261.118187)
			(xy 374.914668 -261.071913) (xy 374.945194 -261.029897) (xy 374.981917 -260.993174) (xy 375.023933 -260.962648)
			(xy 375.070207 -260.93907) (xy 375.1196 -260.923022) (xy 375.170895 -260.914897) (xy 375.222829 -260.914897)
			(xy 375.274124 -260.923022) (xy 375.323517 -260.93907) (xy 375.369791 -260.962648) (xy 375.411807 -260.993174)
			(xy 375.44853 -261.029897) (xy 375.479056 -261.071913) (xy 375.502634 -261.118187) (xy 375.518682 -261.16758)
			(xy 375.526807 -261.218875) (xy 375.527316 -261.244842) (xy 375.526807 -261.270809) (xy 375.806717 -261.270809)
			(xy 375.806717 -261.218875) (xy 375.814842 -261.16758) (xy 375.83089 -261.118187) (xy 375.854468 -261.071913)
			(xy 375.884994 -261.029897) (xy 375.921717 -260.993174) (xy 375.963733 -260.962648) (xy 376.010007 -260.93907)
			(xy 376.0594 -260.923022) (xy 376.110695 -260.914897) (xy 376.162629 -260.914897) (xy 376.213924 -260.923022)
			(xy 376.263317 -260.93907) (xy 376.309591 -260.962648) (xy 376.351607 -260.993174) (xy 376.38833 -261.029897)
			(xy 376.418856 -261.071913) (xy 376.442434 -261.118187) (xy 376.458482 -261.16758) (xy 376.466607 -261.218875)
			(xy 376.467116 -261.244842) (xy 376.466607 -261.270809) (xy 376.746517 -261.270809) (xy 376.746517 -261.218875)
			(xy 376.754642 -261.16758) (xy 376.77069 -261.118187) (xy 376.794268 -261.071913) (xy 376.824794 -261.029897)
			(xy 376.861517 -260.993174) (xy 376.903533 -260.962648) (xy 376.949807 -260.93907) (xy 376.9992 -260.923022)
			(xy 377.050495 -260.914897) (xy 377.102429 -260.914897) (xy 377.153724 -260.923022) (xy 377.203117 -260.93907)
			(xy 377.249391 -260.962648) (xy 377.291407 -260.993174) (xy 377.32813 -261.029897) (xy 377.358656 -261.071913)
			(xy 377.382234 -261.118187) (xy 377.398282 -261.16758) (xy 377.406407 -261.218875) (xy 377.406916 -261.244842)
			(xy 377.406407 -261.270809) (xy 377.686317 -261.270809) (xy 377.686317 -261.218875) (xy 377.694442 -261.16758)
			(xy 377.71049 -261.118187) (xy 377.734068 -261.071913) (xy 377.764594 -261.029897) (xy 377.801317 -260.993174)
			(xy 377.843333 -260.962648) (xy 377.889607 -260.93907) (xy 377.939 -260.923022) (xy 377.990295 -260.914897)
			(xy 378.042229 -260.914897) (xy 378.093524 -260.923022) (xy 378.142917 -260.93907) (xy 378.189191 -260.962648)
			(xy 378.231207 -260.993174) (xy 378.26793 -261.029897) (xy 378.298456 -261.071913) (xy 378.322034 -261.118187)
			(xy 378.338082 -261.16758) (xy 378.346207 -261.218875) (xy 378.346716 -261.244842) (xy 378.346207 -261.270809)
			(xy 378.626117 -261.270809) (xy 378.626117 -261.218875) (xy 378.634242 -261.16758) (xy 378.65029 -261.118187)
			(xy 378.673868 -261.071913) (xy 378.704394 -261.029897) (xy 378.741117 -260.993174) (xy 378.783133 -260.962648)
			(xy 378.829407 -260.93907) (xy 378.8788 -260.923022) (xy 378.930095 -260.914897) (xy 378.982029 -260.914897)
			(xy 379.033324 -260.923022) (xy 379.082717 -260.93907) (xy 379.128991 -260.962648) (xy 379.171007 -260.993174)
			(xy 379.20773 -261.029897) (xy 379.238256 -261.071913) (xy 379.261834 -261.118187) (xy 379.277882 -261.16758)
			(xy 379.286007 -261.218875) (xy 379.286516 -261.244842) (xy 379.286007 -261.270809) (xy 379.277882 -261.322104)
			(xy 379.261834 -261.371497) (xy 379.238256 -261.417771) (xy 379.20773 -261.459787) (xy 379.171007 -261.49651)
			(xy 379.128991 -261.527036) (xy 379.082717 -261.550614) (xy 379.033324 -261.566662) (xy 378.982029 -261.574787)
			(xy 378.930095 -261.574787) (xy 378.8788 -261.566662) (xy 378.829407 -261.550614) (xy 378.783133 -261.527036)
			(xy 378.741117 -261.49651) (xy 378.704394 -261.459787) (xy 378.673868 -261.417771) (xy 378.65029 -261.371497)
			(xy 378.634242 -261.322104) (xy 378.626117 -261.270809) (xy 378.346207 -261.270809) (xy 378.338082 -261.322104)
			(xy 378.322034 -261.371497) (xy 378.298456 -261.417771) (xy 378.26793 -261.459787) (xy 378.231207 -261.49651)
			(xy 378.189191 -261.527036) (xy 378.142917 -261.550614) (xy 378.093524 -261.566662) (xy 378.042229 -261.574787)
			(xy 377.990295 -261.574787) (xy 377.939 -261.566662) (xy 377.889607 -261.550614) (xy 377.843333 -261.527036)
			(xy 377.801317 -261.49651) (xy 377.764594 -261.459787) (xy 377.734068 -261.417771) (xy 377.71049 -261.371497)
			(xy 377.694442 -261.322104) (xy 377.686317 -261.270809) (xy 377.406407 -261.270809) (xy 377.398282 -261.322104)
			(xy 377.382234 -261.371497) (xy 377.358656 -261.417771) (xy 377.32813 -261.459787) (xy 377.291407 -261.49651)
			(xy 377.249391 -261.527036) (xy 377.203117 -261.550614) (xy 377.153724 -261.566662) (xy 377.102429 -261.574787)
			(xy 377.050495 -261.574787) (xy 376.9992 -261.566662) (xy 376.949807 -261.550614) (xy 376.903533 -261.527036)
			(xy 376.861517 -261.49651) (xy 376.824794 -261.459787) (xy 376.794268 -261.417771) (xy 376.77069 -261.371497)
			(xy 376.754642 -261.322104) (xy 376.746517 -261.270809) (xy 376.466607 -261.270809) (xy 376.458482 -261.322104)
			(xy 376.442434 -261.371497) (xy 376.418856 -261.417771) (xy 376.38833 -261.459787) (xy 376.351607 -261.49651)
			(xy 376.309591 -261.527036) (xy 376.263317 -261.550614) (xy 376.213924 -261.566662) (xy 376.162629 -261.574787)
			(xy 376.110695 -261.574787) (xy 376.0594 -261.566662) (xy 376.010007 -261.550614) (xy 375.963733 -261.527036)
			(xy 375.921717 -261.49651) (xy 375.884994 -261.459787) (xy 375.854468 -261.417771) (xy 375.83089 -261.371497)
			(xy 375.814842 -261.322104) (xy 375.806717 -261.270809) (xy 375.526807 -261.270809) (xy 375.518682 -261.322104)
			(xy 375.502634 -261.371497) (xy 375.479056 -261.417771) (xy 375.44853 -261.459787) (xy 375.411807 -261.49651)
			(xy 375.369791 -261.527036) (xy 375.323517 -261.550614) (xy 375.274124 -261.566662) (xy 375.222829 -261.574787)
			(xy 375.170895 -261.574787) (xy 375.1196 -261.566662) (xy 375.070207 -261.550614) (xy 375.023933 -261.527036)
			(xy 374.981917 -261.49651) (xy 374.945194 -261.459787) (xy 374.914668 -261.417771) (xy 374.89109 -261.371497)
			(xy 374.875042 -261.322104) (xy 374.866917 -261.270809) (xy 374.587007 -261.270809) (xy 374.578882 -261.322104)
			(xy 374.562834 -261.371497) (xy 374.539256 -261.417771) (xy 374.50873 -261.459787) (xy 374.472007 -261.49651)
			(xy 374.429991 -261.527036) (xy 374.383717 -261.550614) (xy 374.334324 -261.566662) (xy 374.283029 -261.574787)
			(xy 374.231095 -261.574787) (xy 374.1798 -261.566662) (xy 374.130407 -261.550614) (xy 374.084133 -261.527036)
			(xy 374.042117 -261.49651) (xy 374.005394 -261.459787) (xy 373.974868 -261.417771) (xy 373.95129 -261.371497)
			(xy 373.935242 -261.322104) (xy 373.927117 -261.270809) (xy 373.647207 -261.270809) (xy 373.639082 -261.322104)
			(xy 373.623034 -261.371497) (xy 373.599456 -261.417771) (xy 373.56893 -261.459787) (xy 373.532207 -261.49651)
			(xy 373.490191 -261.527036) (xy 373.443917 -261.550614) (xy 373.394524 -261.566662) (xy 373.343229 -261.574787)
			(xy 373.291295 -261.574787) (xy 373.24 -261.566662) (xy 373.190607 -261.550614) (xy 373.144333 -261.527036)
			(xy 373.102317 -261.49651) (xy 373.065594 -261.459787) (xy 373.035068 -261.417771) (xy 373.01149 -261.371497)
			(xy 372.995442 -261.322104) (xy 372.987317 -261.270809) (xy 372.707407 -261.270809) (xy 372.699282 -261.322104)
			(xy 372.683234 -261.371497) (xy 372.659656 -261.417771) (xy 372.62913 -261.459787) (xy 372.592407 -261.49651)
			(xy 372.550391 -261.527036) (xy 372.504117 -261.550614) (xy 372.454724 -261.566662) (xy 372.403429 -261.574787)
			(xy 372.351495 -261.574787) (xy 372.3002 -261.566662) (xy 372.250807 -261.550614) (xy 372.204533 -261.527036)
			(xy 372.162517 -261.49651) (xy 372.125794 -261.459787) (xy 372.095268 -261.417771) (xy 372.07169 -261.371497)
			(xy 372.055642 -261.322104) (xy 372.047517 -261.270809) (xy 371.767586 -261.270809) (xy 371.767586 -261.272552)
			(xy 371.758331 -261.327204) (xy 371.740088 -261.379546) (xy 371.727222 -261.4041) (xy 371.720872 -261.415276)
			(xy 371.720872 -261.63524) (xy 371.721437 -261.650247) (xy 371.730169 -261.678964) (xy 371.746869 -261.703904)
			(xy 371.770096 -261.722916) (xy 371.797844 -261.734358) (xy 371.82772 -261.737244) (xy 371.842538 -261.734808)
			(xy 371.858684 -261.731744) (xy 371.891383 -261.728434) (xy 371.907816 -261.728204) (xy 371.933779 -261.728798)
			(xy 371.985066 -261.736924) (xy 372.03445 -261.752972) (xy 372.080716 -261.776547) (xy 372.122724 -261.80707)
			(xy 372.159441 -261.843788) (xy 372.189961 -261.885798) (xy 372.213535 -261.932065) (xy 372.22958 -261.98145)
			(xy 372.237703 -262.032737) (xy 372.237703 -262.084625) (xy 372.517671 -262.084625) (xy 372.517671 -262.032691)
			(xy 372.525796 -261.981396) (xy 372.541844 -261.932003) (xy 372.565422 -261.885729) (xy 372.595948 -261.843713)
			(xy 372.632671 -261.80699) (xy 372.674687 -261.776464) (xy 372.720961 -261.752886) (xy 372.770354 -261.736838)
			(xy 372.821649 -261.728713) (xy 372.873583 -261.728713) (xy 372.924878 -261.736838) (xy 372.974271 -261.752886)
			(xy 373.020545 -261.776464) (xy 373.062561 -261.80699) (xy 373.099284 -261.843713) (xy 373.12981 -261.885729)
			(xy 373.153388 -261.932003) (xy 373.169436 -261.981396) (xy 373.177561 -262.032691) (xy 373.17807 -262.058658)
			(xy 373.177561 -262.084625) (xy 373.457217 -262.084625) (xy 373.457217 -262.032691) (xy 373.465342 -261.981396)
			(xy 373.48139 -261.932003) (xy 373.504968 -261.885729) (xy 373.535494 -261.843713) (xy 373.572217 -261.80699)
			(xy 373.614233 -261.776464) (xy 373.660507 -261.752886) (xy 373.7099 -261.736838) (xy 373.761195 -261.728713)
			(xy 373.813129 -261.728713) (xy 373.864424 -261.736838) (xy 373.913817 -261.752886) (xy 373.960091 -261.776464)
			(xy 374.002107 -261.80699) (xy 374.03883 -261.843713) (xy 374.069356 -261.885729) (xy 374.092934 -261.932003)
			(xy 374.108982 -261.981396) (xy 374.117107 -262.032691) (xy 374.117616 -262.058658) (xy 374.117107 -262.084625)
			(xy 374.397271 -262.084625) (xy 374.397271 -262.032691) (xy 374.405396 -261.981396) (xy 374.421444 -261.932003)
			(xy 374.445022 -261.885729) (xy 374.475548 -261.843713) (xy 374.512271 -261.80699) (xy 374.554287 -261.776464)
			(xy 374.600561 -261.752886) (xy 374.649954 -261.736838) (xy 374.701249 -261.728713) (xy 374.753183 -261.728713)
			(xy 374.804478 -261.736838) (xy 374.853871 -261.752886) (xy 374.900145 -261.776464) (xy 374.942161 -261.80699)
			(xy 374.978884 -261.843713) (xy 375.00941 -261.885729) (xy 375.032988 -261.932003) (xy 375.049036 -261.981396)
			(xy 375.057161 -262.032691) (xy 375.05767 -262.058658) (xy 375.057161 -262.084625) (xy 375.337071 -262.084625)
			(xy 375.337071 -262.032691) (xy 375.345196 -261.981396) (xy 375.361244 -261.932003) (xy 375.384822 -261.885729)
			(xy 375.415348 -261.843713) (xy 375.452071 -261.80699) (xy 375.494087 -261.776464) (xy 375.540361 -261.752886)
			(xy 375.589754 -261.736838) (xy 375.641049 -261.728713) (xy 375.692983 -261.728713) (xy 375.744278 -261.736838)
			(xy 375.793671 -261.752886) (xy 375.839945 -261.776464) (xy 375.881961 -261.80699) (xy 375.918684 -261.843713)
			(xy 375.94921 -261.885729) (xy 375.972788 -261.932003) (xy 375.988836 -261.981396) (xy 375.996961 -262.032691)
			(xy 375.99747 -262.058658) (xy 375.996961 -262.084625) (xy 376.276871 -262.084625) (xy 376.276871 -262.032691)
			(xy 376.284996 -261.981396) (xy 376.301044 -261.932003) (xy 376.324622 -261.885729) (xy 376.355148 -261.843713)
			(xy 376.391871 -261.80699) (xy 376.433887 -261.776464) (xy 376.480161 -261.752886) (xy 376.529554 -261.736838)
			(xy 376.580849 -261.728713) (xy 376.632783 -261.728713) (xy 376.684078 -261.736838) (xy 376.733471 -261.752886)
			(xy 376.779745 -261.776464) (xy 376.821761 -261.80699) (xy 376.858484 -261.843713) (xy 376.88901 -261.885729)
			(xy 376.912588 -261.932003) (xy 376.928636 -261.981396) (xy 376.936761 -262.032691) (xy 376.93727 -262.058658)
			(xy 376.936761 -262.084625) (xy 377.216671 -262.084625) (xy 377.216671 -262.032691) (xy 377.224796 -261.981396)
			(xy 377.240844 -261.932003) (xy 377.264422 -261.885729) (xy 377.294948 -261.843713) (xy 377.331671 -261.80699)
			(xy 377.373687 -261.776464) (xy 377.419961 -261.752886) (xy 377.469354 -261.736838) (xy 377.520649 -261.728713)
			(xy 377.572583 -261.728713) (xy 377.623878 -261.736838) (xy 377.673271 -261.752886) (xy 377.719545 -261.776464)
			(xy 377.761561 -261.80699) (xy 377.798284 -261.843713) (xy 377.82881 -261.885729) (xy 377.852388 -261.932003)
			(xy 377.868436 -261.981396) (xy 377.876561 -262.032691) (xy 377.87707 -262.058658) (xy 377.876561 -262.084625)
			(xy 378.156471 -262.084625) (xy 378.156471 -262.032691) (xy 378.164596 -261.981396) (xy 378.180644 -261.932003)
			(xy 378.204222 -261.885729) (xy 378.234748 -261.843713) (xy 378.271471 -261.80699) (xy 378.313487 -261.776464)
			(xy 378.359761 -261.752886) (xy 378.409154 -261.736838) (xy 378.460449 -261.728713) (xy 378.512383 -261.728713)
			(xy 378.563678 -261.736838) (xy 378.613071 -261.752886) (xy 378.659345 -261.776464) (xy 378.701361 -261.80699)
			(xy 378.738084 -261.843713) (xy 378.76861 -261.885729) (xy 378.792188 -261.932003) (xy 378.808236 -261.981396)
			(xy 378.816361 -262.032691) (xy 378.81687 -262.058658) (xy 378.816361 -262.084625) (xy 378.808236 -262.13592)
			(xy 378.792188 -262.185313) (xy 378.76861 -262.231587) (xy 378.738084 -262.273603) (xy 378.701361 -262.310326)
			(xy 378.659345 -262.340852) (xy 378.613071 -262.36443) (xy 378.563678 -262.380478) (xy 378.512383 -262.388603)
			(xy 378.460449 -262.388603) (xy 378.409154 -262.380478) (xy 378.359761 -262.36443) (xy 378.313487 -262.340852)
			(xy 378.271471 -262.310326) (xy 378.234748 -262.273603) (xy 378.204222 -262.231587) (xy 378.180644 -262.185313)
			(xy 378.164596 -262.13592) (xy 378.156471 -262.084625) (xy 377.876561 -262.084625) (xy 377.868436 -262.13592)
			(xy 377.852388 -262.185313) (xy 377.82881 -262.231587) (xy 377.798284 -262.273603) (xy 377.761561 -262.310326)
			(xy 377.719545 -262.340852) (xy 377.673271 -262.36443) (xy 377.623878 -262.380478) (xy 377.572583 -262.388603)
			(xy 377.520649 -262.388603) (xy 377.469354 -262.380478) (xy 377.419961 -262.36443) (xy 377.373687 -262.340852)
			(xy 377.331671 -262.310326) (xy 377.294948 -262.273603) (xy 377.264422 -262.231587) (xy 377.240844 -262.185313)
			(xy 377.224796 -262.13592) (xy 377.216671 -262.084625) (xy 376.936761 -262.084625) (xy 376.928636 -262.13592)
			(xy 376.912588 -262.185313) (xy 376.88901 -262.231587) (xy 376.858484 -262.273603) (xy 376.821761 -262.310326)
			(xy 376.779745 -262.340852) (xy 376.733471 -262.36443) (xy 376.684078 -262.380478) (xy 376.632783 -262.388603)
			(xy 376.580849 -262.388603) (xy 376.529554 -262.380478) (xy 376.480161 -262.36443) (xy 376.433887 -262.340852)
			(xy 376.391871 -262.310326) (xy 376.355148 -262.273603) (xy 376.324622 -262.231587) (xy 376.301044 -262.185313)
			(xy 376.284996 -262.13592) (xy 376.276871 -262.084625) (xy 375.996961 -262.084625) (xy 375.988836 -262.13592)
			(xy 375.972788 -262.185313) (xy 375.94921 -262.231587) (xy 375.918684 -262.273603) (xy 375.881961 -262.310326)
			(xy 375.839945 -262.340852) (xy 375.793671 -262.36443) (xy 375.744278 -262.380478) (xy 375.692983 -262.388603)
			(xy 375.641049 -262.388603) (xy 375.589754 -262.380478) (xy 375.540361 -262.36443) (xy 375.494087 -262.340852)
			(xy 375.452071 -262.310326) (xy 375.415348 -262.273603) (xy 375.384822 -262.231587) (xy 375.361244 -262.185313)
			(xy 375.345196 -262.13592) (xy 375.337071 -262.084625) (xy 375.057161 -262.084625) (xy 375.049036 -262.13592)
			(xy 375.032988 -262.185313) (xy 375.00941 -262.231587) (xy 374.978884 -262.273603) (xy 374.942161 -262.310326)
			(xy 374.900145 -262.340852) (xy 374.853871 -262.36443) (xy 374.804478 -262.380478) (xy 374.753183 -262.388603)
			(xy 374.701249 -262.388603) (xy 374.649954 -262.380478) (xy 374.600561 -262.36443) (xy 374.554287 -262.340852)
			(xy 374.512271 -262.310326) (xy 374.475548 -262.273603) (xy 374.445022 -262.231587) (xy 374.421444 -262.185313)
			(xy 374.405396 -262.13592) (xy 374.397271 -262.084625) (xy 374.117107 -262.084625) (xy 374.108982 -262.13592)
			(xy 374.092934 -262.185313) (xy 374.069356 -262.231587) (xy 374.03883 -262.273603) (xy 374.002107 -262.310326)
			(xy 373.960091 -262.340852) (xy 373.913817 -262.36443) (xy 373.864424 -262.380478) (xy 373.813129 -262.388603)
			(xy 373.761195 -262.388603) (xy 373.7099 -262.380478) (xy 373.660507 -262.36443) (xy 373.614233 -262.340852)
			(xy 373.572217 -262.310326) (xy 373.535494 -262.273603) (xy 373.504968 -262.231587) (xy 373.48139 -262.185313)
			(xy 373.465342 -262.13592) (xy 373.457217 -262.084625) (xy 373.177561 -262.084625) (xy 373.169436 -262.13592)
			(xy 373.153388 -262.185313) (xy 373.12981 -262.231587) (xy 373.099284 -262.273603) (xy 373.062561 -262.310326)
			(xy 373.020545 -262.340852) (xy 372.974271 -262.36443) (xy 372.924878 -262.380478) (xy 372.873583 -262.388603)
			(xy 372.821649 -262.388603) (xy 372.770354 -262.380478) (xy 372.720961 -262.36443) (xy 372.674687 -262.340852)
			(xy 372.632671 -262.310326) (xy 372.595948 -262.273603) (xy 372.565422 -262.231587) (xy 372.541844 -262.185313)
			(xy 372.525796 -262.13592) (xy 372.517671 -262.084625) (xy 372.237703 -262.084625) (xy 372.237703 -262.084663)
			(xy 372.22958 -262.13595) (xy 372.213535 -262.185335) (xy 372.189961 -262.231602) (xy 372.159441 -262.273612)
			(xy 372.122724 -262.31033) (xy 372.080716 -262.340853) (xy 372.03445 -262.364428) (xy 371.985066 -262.380476)
			(xy 371.933779 -262.388602) (xy 371.907816 -262.389112) (xy 371.891383 -262.388892) (xy 371.858683 -262.385582)
			(xy 371.842538 -262.382508) (xy 371.827708 -262.380137) (xy 371.797832 -262.382998) (xy 371.77008 -262.394423)
			(xy 371.746848 -262.413423) (xy 371.730144 -262.438357) (xy 371.721411 -262.46707) (xy 371.720872 -262.482076)
			(xy 371.720872 -262.70204) (xy 371.727222 -262.713216) (xy 371.740063 -262.73778) (xy 371.758303 -262.790118)
			(xy 371.767554 -262.844765) (xy 371.767558 -262.898441) (xy 372.047517 -262.898441) (xy 372.047517 -262.846507)
			(xy 372.055642 -262.795212) (xy 372.07169 -262.745819) (xy 372.095268 -262.699545) (xy 372.125794 -262.657529)
			(xy 372.162517 -262.620806) (xy 372.204533 -262.59028) (xy 372.250807 -262.566702) (xy 372.3002 -262.550654)
			(xy 372.351495 -262.542529) (xy 372.403429 -262.542529) (xy 372.454724 -262.550654) (xy 372.504117 -262.566702)
			(xy 372.550391 -262.59028) (xy 372.592407 -262.620806) (xy 372.62913 -262.657529) (xy 372.659656 -262.699545)
			(xy 372.683234 -262.745819) (xy 372.699282 -262.795212) (xy 372.707407 -262.846507) (xy 372.707916 -262.872474)
			(xy 372.707407 -262.898441) (xy 372.987571 -262.898441) (xy 372.987571 -262.846507) (xy 372.995696 -262.795212)
			(xy 373.011744 -262.745819) (xy 373.035322 -262.699545) (xy 373.065848 -262.657529) (xy 373.102571 -262.620806)
			(xy 373.144587 -262.59028) (xy 373.190861 -262.566702) (xy 373.240254 -262.550654) (xy 373.291549 -262.542529)
			(xy 373.343483 -262.542529) (xy 373.394778 -262.550654) (xy 373.444171 -262.566702) (xy 373.490445 -262.59028)
			(xy 373.532461 -262.620806) (xy 373.569184 -262.657529) (xy 373.59971 -262.699545) (xy 373.623288 -262.745819)
			(xy 373.639336 -262.795212) (xy 373.647461 -262.846507) (xy 373.64797 -262.872474) (xy 373.647461 -262.898441)
			(xy 373.927117 -262.898441) (xy 373.927117 -262.846507) (xy 373.935242 -262.795212) (xy 373.95129 -262.745819)
			(xy 373.974868 -262.699545) (xy 374.005394 -262.657529) (xy 374.042117 -262.620806) (xy 374.084133 -262.59028)
			(xy 374.130407 -262.566702) (xy 374.1798 -262.550654) (xy 374.231095 -262.542529) (xy 374.283029 -262.542529)
			(xy 374.334324 -262.550654) (xy 374.383717 -262.566702) (xy 374.429991 -262.59028) (xy 374.472007 -262.620806)
			(xy 374.50873 -262.657529) (xy 374.539256 -262.699545) (xy 374.562834 -262.745819) (xy 374.578882 -262.795212)
			(xy 374.587007 -262.846507) (xy 374.587516 -262.872474) (xy 374.587007 -262.898441) (xy 374.866917 -262.898441)
			(xy 374.866917 -262.846507) (xy 374.875042 -262.795212) (xy 374.89109 -262.745819) (xy 374.914668 -262.699545)
			(xy 374.945194 -262.657529) (xy 374.981917 -262.620806) (xy 375.023933 -262.59028) (xy 375.070207 -262.566702)
			(xy 375.1196 -262.550654) (xy 375.170895 -262.542529) (xy 375.222829 -262.542529) (xy 375.274124 -262.550654)
			(xy 375.323517 -262.566702) (xy 375.369791 -262.59028) (xy 375.411807 -262.620806) (xy 375.44853 -262.657529)
			(xy 375.479056 -262.699545) (xy 375.502634 -262.745819) (xy 375.518682 -262.795212) (xy 375.526807 -262.846507)
			(xy 375.527316 -262.872474) (xy 375.526807 -262.898441) (xy 375.806717 -262.898441) (xy 375.806717 -262.846507)
			(xy 375.814842 -262.795212) (xy 375.83089 -262.745819) (xy 375.854468 -262.699545) (xy 375.884994 -262.657529)
			(xy 375.921717 -262.620806) (xy 375.963733 -262.59028) (xy 376.010007 -262.566702) (xy 376.0594 -262.550654)
			(xy 376.110695 -262.542529) (xy 376.162629 -262.542529) (xy 376.213924 -262.550654) (xy 376.263317 -262.566702)
			(xy 376.309591 -262.59028) (xy 376.351607 -262.620806) (xy 376.38833 -262.657529) (xy 376.418856 -262.699545)
			(xy 376.442434 -262.745819) (xy 376.458482 -262.795212) (xy 376.466607 -262.846507) (xy 376.467116 -262.872474)
			(xy 376.466607 -262.898441) (xy 376.746517 -262.898441) (xy 376.746517 -262.846507) (xy 376.754642 -262.795212)
			(xy 376.77069 -262.745819) (xy 376.794268 -262.699545) (xy 376.824794 -262.657529) (xy 376.861517 -262.620806)
			(xy 376.903533 -262.59028) (xy 376.949807 -262.566702) (xy 376.9992 -262.550654) (xy 377.050495 -262.542529)
			(xy 377.102429 -262.542529) (xy 377.153724 -262.550654) (xy 377.203117 -262.566702) (xy 377.249391 -262.59028)
			(xy 377.291407 -262.620806) (xy 377.32813 -262.657529) (xy 377.358656 -262.699545) (xy 377.382234 -262.745819)
			(xy 377.398282 -262.795212) (xy 377.406407 -262.846507) (xy 377.406916 -262.872474) (xy 377.406407 -262.898441)
			(xy 377.686317 -262.898441) (xy 377.686317 -262.846507) (xy 377.694442 -262.795212) (xy 377.71049 -262.745819)
			(xy 377.734068 -262.699545) (xy 377.764594 -262.657529) (xy 377.801317 -262.620806) (xy 377.843333 -262.59028)
			(xy 377.889607 -262.566702) (xy 377.939 -262.550654) (xy 377.990295 -262.542529) (xy 378.042229 -262.542529)
			(xy 378.093524 -262.550654) (xy 378.142917 -262.566702) (xy 378.189191 -262.59028) (xy 378.231207 -262.620806)
			(xy 378.26793 -262.657529) (xy 378.298456 -262.699545) (xy 378.322034 -262.745819) (xy 378.338082 -262.795212)
			(xy 378.346207 -262.846507) (xy 378.346716 -262.872474) (xy 378.346207 -262.898441) (xy 378.626117 -262.898441)
			(xy 378.626117 -262.846507) (xy 378.634242 -262.795212) (xy 378.65029 -262.745819) (xy 378.673868 -262.699545)
			(xy 378.704394 -262.657529) (xy 378.741117 -262.620806) (xy 378.783133 -262.59028) (xy 378.829407 -262.566702)
			(xy 378.8788 -262.550654) (xy 378.930095 -262.542529) (xy 378.982029 -262.542529) (xy 379.033324 -262.550654)
			(xy 379.082717 -262.566702) (xy 379.128991 -262.59028) (xy 379.171007 -262.620806) (xy 379.20773 -262.657529)
			(xy 379.238256 -262.699545) (xy 379.261834 -262.745819) (xy 379.277882 -262.795212) (xy 379.286007 -262.846507)
			(xy 379.286516 -262.872474) (xy 379.286007 -262.898441) (xy 379.277882 -262.949736) (xy 379.261834 -262.999129)
			(xy 379.238256 -263.045403) (xy 379.20773 -263.087419) (xy 379.171007 -263.124142) (xy 379.128991 -263.154668)
			(xy 379.082717 -263.178246) (xy 379.033324 -263.194294) (xy 378.982029 -263.202419) (xy 378.930095 -263.202419)
			(xy 378.8788 -263.194294) (xy 378.829407 -263.178246) (xy 378.783133 -263.154668) (xy 378.741117 -263.124142)
			(xy 378.704394 -263.087419) (xy 378.673868 -263.045403) (xy 378.65029 -262.999129) (xy 378.634242 -262.949736)
			(xy 378.626117 -262.898441) (xy 378.346207 -262.898441) (xy 378.338082 -262.949736) (xy 378.322034 -262.999129)
			(xy 378.298456 -263.045403) (xy 378.26793 -263.087419) (xy 378.231207 -263.124142) (xy 378.189191 -263.154668)
			(xy 378.142917 -263.178246) (xy 378.093524 -263.194294) (xy 378.042229 -263.202419) (xy 377.990295 -263.202419)
			(xy 377.939 -263.194294) (xy 377.889607 -263.178246) (xy 377.843333 -263.154668) (xy 377.801317 -263.124142)
			(xy 377.764594 -263.087419) (xy 377.734068 -263.045403) (xy 377.71049 -262.999129) (xy 377.694442 -262.949736)
			(xy 377.686317 -262.898441) (xy 377.406407 -262.898441) (xy 377.398282 -262.949736) (xy 377.382234 -262.999129)
			(xy 377.358656 -263.045403) (xy 377.32813 -263.087419) (xy 377.291407 -263.124142) (xy 377.249391 -263.154668)
			(xy 377.203117 -263.178246) (xy 377.153724 -263.194294) (xy 377.102429 -263.202419) (xy 377.050495 -263.202419)
			(xy 376.9992 -263.194294) (xy 376.949807 -263.178246) (xy 376.903533 -263.154668) (xy 376.861517 -263.124142)
			(xy 376.824794 -263.087419) (xy 376.794268 -263.045403) (xy 376.77069 -262.999129) (xy 376.754642 -262.949736)
			(xy 376.746517 -262.898441) (xy 376.466607 -262.898441) (xy 376.458482 -262.949736) (xy 376.442434 -262.999129)
			(xy 376.418856 -263.045403) (xy 376.38833 -263.087419) (xy 376.351607 -263.124142) (xy 376.309591 -263.154668)
			(xy 376.263317 -263.178246) (xy 376.213924 -263.194294) (xy 376.162629 -263.202419) (xy 376.110695 -263.202419)
			(xy 376.0594 -263.194294) (xy 376.010007 -263.178246) (xy 375.963733 -263.154668) (xy 375.921717 -263.124142)
			(xy 375.884994 -263.087419) (xy 375.854468 -263.045403) (xy 375.83089 -262.999129) (xy 375.814842 -262.949736)
			(xy 375.806717 -262.898441) (xy 375.526807 -262.898441) (xy 375.518682 -262.949736) (xy 375.502634 -262.999129)
			(xy 375.479056 -263.045403) (xy 375.44853 -263.087419) (xy 375.411807 -263.124142) (xy 375.369791 -263.154668)
			(xy 375.323517 -263.178246) (xy 375.274124 -263.194294) (xy 375.222829 -263.202419) (xy 375.170895 -263.202419)
			(xy 375.1196 -263.194294) (xy 375.070207 -263.178246) (xy 375.023933 -263.154668) (xy 374.981917 -263.124142)
			(xy 374.945194 -263.087419) (xy 374.914668 -263.045403) (xy 374.89109 -262.999129) (xy 374.875042 -262.949736)
			(xy 374.866917 -262.898441) (xy 374.587007 -262.898441) (xy 374.578882 -262.949736) (xy 374.562834 -262.999129)
			(xy 374.539256 -263.045403) (xy 374.50873 -263.087419) (xy 374.472007 -263.124142) (xy 374.429991 -263.154668)
			(xy 374.383717 -263.178246) (xy 374.334324 -263.194294) (xy 374.283029 -263.202419) (xy 374.231095 -263.202419)
			(xy 374.1798 -263.194294) (xy 374.130407 -263.178246) (xy 374.084133 -263.154668) (xy 374.042117 -263.124142)
			(xy 374.005394 -263.087419) (xy 373.974868 -263.045403) (xy 373.95129 -262.999129) (xy 373.935242 -262.949736)
			(xy 373.927117 -262.898441) (xy 373.647461 -262.898441) (xy 373.639336 -262.949736) (xy 373.623288 -262.999129)
			(xy 373.59971 -263.045403) (xy 373.569184 -263.087419) (xy 373.532461 -263.124142) (xy 373.490445 -263.154668)
			(xy 373.444171 -263.178246) (xy 373.394778 -263.194294) (xy 373.343483 -263.202419) (xy 373.291549 -263.202419)
			(xy 373.240254 -263.194294) (xy 373.190861 -263.178246) (xy 373.144587 -263.154668) (xy 373.102571 -263.124142)
			(xy 373.065848 -263.087419) (xy 373.035322 -263.045403) (xy 373.011744 -262.999129) (xy 372.995696 -262.949736)
			(xy 372.987571 -262.898441) (xy 372.707407 -262.898441) (xy 372.699282 -262.949736) (xy 372.683234 -262.999129)
			(xy 372.659656 -263.045403) (xy 372.62913 -263.087419) (xy 372.592407 -263.124142) (xy 372.550391 -263.154668)
			(xy 372.504117 -263.178246) (xy 372.454724 -263.194294) (xy 372.403429 -263.202419) (xy 372.351495 -263.202419)
			(xy 372.3002 -263.194294) (xy 372.250807 -263.178246) (xy 372.204533 -263.154668) (xy 372.162517 -263.124142)
			(xy 372.125794 -263.087419) (xy 372.095268 -263.045403) (xy 372.07169 -262.999129) (xy 372.055642 -262.949736)
			(xy 372.047517 -262.898441) (xy 371.767558 -262.898441) (xy 371.767558 -262.90019) (xy 371.758314 -262.954838)
			(xy 371.740082 -263.007178) (xy 371.727222 -263.031732) (xy 371.720872 -263.042908) (xy 371.720872 -263.263126)
			(xy 371.721449 -263.278133) (xy 371.730178 -263.306849) (xy 371.746875 -263.331789) (xy 371.770099 -263.350801)
			(xy 371.797846 -263.362244) (xy 371.827721 -263.36513) (xy 371.842538 -263.362694) (xy 371.858684 -263.35963)
			(xy 371.891383 -263.35632) (xy 371.907816 -263.35609) (xy 371.933786 -263.356513) (xy 371.985086 -263.36464)
			(xy 372.034483 -263.380692) (xy 372.080761 -263.404274) (xy 372.12278 -263.434805) (xy 372.159506 -263.471532)
			(xy 372.190035 -263.513553) (xy 372.213614 -263.559832) (xy 372.229664 -263.60923) (xy 372.237789 -263.66053)
			(xy 372.237789 -263.71247) (xy 372.237783 -263.712511) (xy 372.517671 -263.712511) (xy 372.517671 -263.660577)
			(xy 372.525796 -263.609282) (xy 372.541844 -263.559889) (xy 372.565422 -263.513615) (xy 372.595948 -263.471599)
			(xy 372.632671 -263.434876) (xy 372.674687 -263.40435) (xy 372.720961 -263.380772) (xy 372.770354 -263.364724)
			(xy 372.821649 -263.356599) (xy 372.873583 -263.356599) (xy 372.924878 -263.364724) (xy 372.974271 -263.380772)
			(xy 373.020545 -263.40435) (xy 373.062561 -263.434876) (xy 373.099284 -263.471599) (xy 373.12981 -263.513615)
			(xy 373.153388 -263.559889) (xy 373.169436 -263.609282) (xy 373.177561 -263.660577) (xy 373.17807 -263.686544)
			(xy 373.177561 -263.712511) (xy 373.457471 -263.712511) (xy 373.457471 -263.660577) (xy 373.465596 -263.609282)
			(xy 373.481644 -263.559889) (xy 373.505222 -263.513615) (xy 373.535748 -263.471599) (xy 373.572471 -263.434876)
			(xy 373.614487 -263.40435) (xy 373.660761 -263.380772) (xy 373.710154 -263.364724) (xy 373.761449 -263.356599)
			(xy 373.813383 -263.356599) (xy 373.864678 -263.364724) (xy 373.914071 -263.380772) (xy 373.960345 -263.40435)
			(xy 374.002361 -263.434876) (xy 374.039084 -263.471599) (xy 374.06961 -263.513615) (xy 374.093188 -263.559889)
			(xy 374.109236 -263.609282) (xy 374.117361 -263.660577) (xy 374.11787 -263.686544) (xy 374.117361 -263.712511)
			(xy 374.397271 -263.712511) (xy 374.397271 -263.660577) (xy 374.405396 -263.609282) (xy 374.421444 -263.559889)
			(xy 374.445022 -263.513615) (xy 374.475548 -263.471599) (xy 374.512271 -263.434876) (xy 374.554287 -263.40435)
			(xy 374.600561 -263.380772) (xy 374.649954 -263.364724) (xy 374.701249 -263.356599) (xy 374.753183 -263.356599)
			(xy 374.804478 -263.364724) (xy 374.853871 -263.380772) (xy 374.900145 -263.40435) (xy 374.942161 -263.434876)
			(xy 374.978884 -263.471599) (xy 375.00941 -263.513615) (xy 375.032988 -263.559889) (xy 375.049036 -263.609282)
			(xy 375.057161 -263.660577) (xy 375.05767 -263.686544) (xy 375.057161 -263.712511) (xy 375.337071 -263.712511)
			(xy 375.337071 -263.660577) (xy 375.345196 -263.609282) (xy 375.361244 -263.559889) (xy 375.384822 -263.513615)
			(xy 375.415348 -263.471599) (xy 375.452071 -263.434876) (xy 375.494087 -263.40435) (xy 375.540361 -263.380772)
			(xy 375.589754 -263.364724) (xy 375.641049 -263.356599) (xy 375.692983 -263.356599) (xy 375.744278 -263.364724)
			(xy 375.793671 -263.380772) (xy 375.839945 -263.40435) (xy 375.881961 -263.434876) (xy 375.918684 -263.471599)
			(xy 375.94921 -263.513615) (xy 375.972788 -263.559889) (xy 375.988836 -263.609282) (xy 375.996961 -263.660577)
			(xy 375.99747 -263.686544) (xy 375.996961 -263.712511) (xy 376.276871 -263.712511) (xy 376.276871 -263.660577)
			(xy 376.284996 -263.609282) (xy 376.301044 -263.559889) (xy 376.324622 -263.513615) (xy 376.355148 -263.471599)
			(xy 376.391871 -263.434876) (xy 376.433887 -263.40435) (xy 376.480161 -263.380772) (xy 376.529554 -263.364724)
			(xy 376.580849 -263.356599) (xy 376.632783 -263.356599) (xy 376.684078 -263.364724) (xy 376.733471 -263.380772)
			(xy 376.779745 -263.40435) (xy 376.821761 -263.434876) (xy 376.858484 -263.471599) (xy 376.88901 -263.513615)
			(xy 376.912588 -263.559889) (xy 376.928636 -263.609282) (xy 376.936761 -263.660577) (xy 376.93727 -263.686544)
			(xy 376.936761 -263.712511) (xy 377.216417 -263.712511) (xy 377.216417 -263.660577) (xy 377.224542 -263.609282)
			(xy 377.24059 -263.559889) (xy 377.264168 -263.513615) (xy 377.294694 -263.471599) (xy 377.331417 -263.434876)
			(xy 377.373433 -263.40435) (xy 377.419707 -263.380772) (xy 377.4691 -263.364724) (xy 377.520395 -263.356599)
			(xy 377.572329 -263.356599) (xy 377.623624 -263.364724) (xy 377.673017 -263.380772) (xy 377.719291 -263.40435)
			(xy 377.761307 -263.434876) (xy 377.79803 -263.471599) (xy 377.828556 -263.513615) (xy 377.852134 -263.559889)
			(xy 377.868182 -263.609282) (xy 377.876307 -263.660577) (xy 377.876816 -263.686544) (xy 377.876307 -263.712511)
			(xy 378.156471 -263.712511) (xy 378.156471 -263.660577) (xy 378.164596 -263.609282) (xy 378.180644 -263.559889)
			(xy 378.204222 -263.513615) (xy 378.234748 -263.471599) (xy 378.271471 -263.434876) (xy 378.313487 -263.40435)
			(xy 378.359761 -263.380772) (xy 378.409154 -263.364724) (xy 378.460449 -263.356599) (xy 378.512383 -263.356599)
			(xy 378.563678 -263.364724) (xy 378.613071 -263.380772) (xy 378.659345 -263.40435) (xy 378.701361 -263.434876)
			(xy 378.738084 -263.471599) (xy 378.76861 -263.513615) (xy 378.792188 -263.559889) (xy 378.808236 -263.609282)
			(xy 378.816361 -263.660577) (xy 378.81687 -263.686544) (xy 378.816361 -263.712511) (xy 378.808236 -263.763806)
			(xy 378.792188 -263.813199) (xy 378.76861 -263.859473) (xy 378.738084 -263.901489) (xy 378.701361 -263.938212)
			(xy 378.659345 -263.968738) (xy 378.613071 -263.992316) (xy 378.563678 -264.008364) (xy 378.512383 -264.016489)
			(xy 378.460449 -264.016489) (xy 378.409154 -264.008364) (xy 378.359761 -263.992316) (xy 378.313487 -263.968738)
			(xy 378.271471 -263.938212) (xy 378.234748 -263.901489) (xy 378.204222 -263.859473) (xy 378.180644 -263.813199)
			(xy 378.164596 -263.763806) (xy 378.156471 -263.712511) (xy 377.876307 -263.712511) (xy 377.868182 -263.763806)
			(xy 377.852134 -263.813199) (xy 377.828556 -263.859473) (xy 377.79803 -263.901489) (xy 377.761307 -263.938212)
			(xy 377.719291 -263.968738) (xy 377.673017 -263.992316) (xy 377.623624 -264.008364) (xy 377.572329 -264.016489)
			(xy 377.520395 -264.016489) (xy 377.4691 -264.008364) (xy 377.419707 -263.992316) (xy 377.373433 -263.968738)
			(xy 377.331417 -263.938212) (xy 377.294694 -263.901489) (xy 377.264168 -263.859473) (xy 377.24059 -263.813199)
			(xy 377.224542 -263.763806) (xy 377.216417 -263.712511) (xy 376.936761 -263.712511) (xy 376.928636 -263.763806)
			(xy 376.912588 -263.813199) (xy 376.88901 -263.859473) (xy 376.858484 -263.901489) (xy 376.821761 -263.938212)
			(xy 376.779745 -263.968738) (xy 376.733471 -263.992316) (xy 376.684078 -264.008364) (xy 376.632783 -264.016489)
			(xy 376.580849 -264.016489) (xy 376.529554 -264.008364) (xy 376.480161 -263.992316) (xy 376.433887 -263.968738)
			(xy 376.391871 -263.938212) (xy 376.355148 -263.901489) (xy 376.324622 -263.859473) (xy 376.301044 -263.813199)
			(xy 376.284996 -263.763806) (xy 376.276871 -263.712511) (xy 375.996961 -263.712511) (xy 375.988836 -263.763806)
			(xy 375.972788 -263.813199) (xy 375.94921 -263.859473) (xy 375.918684 -263.901489) (xy 375.881961 -263.938212)
			(xy 375.839945 -263.968738) (xy 375.793671 -263.992316) (xy 375.744278 -264.008364) (xy 375.692983 -264.016489)
			(xy 375.641049 -264.016489) (xy 375.589754 -264.008364) (xy 375.540361 -263.992316) (xy 375.494087 -263.968738)
			(xy 375.452071 -263.938212) (xy 375.415348 -263.901489) (xy 375.384822 -263.859473) (xy 375.361244 -263.813199)
			(xy 375.345196 -263.763806) (xy 375.337071 -263.712511) (xy 375.057161 -263.712511) (xy 375.049036 -263.763806)
			(xy 375.032988 -263.813199) (xy 375.00941 -263.859473) (xy 374.978884 -263.901489) (xy 374.942161 -263.938212)
			(xy 374.900145 -263.968738) (xy 374.853871 -263.992316) (xy 374.804478 -264.008364) (xy 374.753183 -264.016489)
			(xy 374.701249 -264.016489) (xy 374.649954 -264.008364) (xy 374.600561 -263.992316) (xy 374.554287 -263.968738)
			(xy 374.512271 -263.938212) (xy 374.475548 -263.901489) (xy 374.445022 -263.859473) (xy 374.421444 -263.813199)
			(xy 374.405396 -263.763806) (xy 374.397271 -263.712511) (xy 374.117361 -263.712511) (xy 374.109236 -263.763806)
			(xy 374.093188 -263.813199) (xy 374.06961 -263.859473) (xy 374.039084 -263.901489) (xy 374.002361 -263.938212)
			(xy 373.960345 -263.968738) (xy 373.914071 -263.992316) (xy 373.864678 -264.008364) (xy 373.813383 -264.016489)
			(xy 373.761449 -264.016489) (xy 373.710154 -264.008364) (xy 373.660761 -263.992316) (xy 373.614487 -263.968738)
			(xy 373.572471 -263.938212) (xy 373.535748 -263.901489) (xy 373.505222 -263.859473) (xy 373.481644 -263.813199)
			(xy 373.465596 -263.763806) (xy 373.457471 -263.712511) (xy 373.177561 -263.712511) (xy 373.169436 -263.763806)
			(xy 373.153388 -263.813199) (xy 373.12981 -263.859473) (xy 373.099284 -263.901489) (xy 373.062561 -263.938212)
			(xy 373.020545 -263.968738) (xy 372.974271 -263.992316) (xy 372.924878 -264.008364) (xy 372.873583 -264.016489)
			(xy 372.821649 -264.016489) (xy 372.770354 -264.008364) (xy 372.720961 -263.992316) (xy 372.674687 -263.968738)
			(xy 372.632671 -263.938212) (xy 372.595948 -263.901489) (xy 372.565422 -263.859473) (xy 372.541844 -263.813199)
			(xy 372.525796 -263.763806) (xy 372.517671 -263.712511) (xy 372.237783 -263.712511) (xy 372.229664 -263.76377)
			(xy 372.213614 -263.813168) (xy 372.190034 -263.859447) (xy 372.159506 -263.901468) (xy 372.12278 -263.938195)
			(xy 372.080761 -263.968726) (xy 372.034483 -263.992308) (xy 371.985086 -264.00836) (xy 371.933786 -264.016487)
			(xy 371.907816 -264.016998) (xy 371.891383 -264.016779) (xy 371.858683 -264.013468) (xy 371.842538 -264.010394)
			(xy 371.827716 -264.007937) (xy 371.797824 -264.0108) (xy 371.770057 -264.022236) (xy 371.746819 -264.041255)
			(xy 371.730118 -264.066211) (xy 371.721399 -264.094947) (xy 371.720872 -264.109962) (xy 371.720872 -264.329926)
			(xy 371.727222 -264.341102) (xy 371.740052 -264.365672) (xy 371.758293 -264.418008) (xy 371.767546 -264.472653)
			(xy 371.767552 -264.526327) (xy 372.047517 -264.526327) (xy 372.047517 -264.474393) (xy 372.055642 -264.423098)
			(xy 372.07169 -264.373705) (xy 372.095268 -264.327431) (xy 372.125794 -264.285415) (xy 372.162517 -264.248692)
			(xy 372.204533 -264.218166) (xy 372.250807 -264.194588) (xy 372.3002 -264.17854) (xy 372.351495 -264.170415)
			(xy 372.403429 -264.170415) (xy 372.454724 -264.17854) (xy 372.504117 -264.194588) (xy 372.550391 -264.218166)
			(xy 372.592407 -264.248692) (xy 372.62913 -264.285415) (xy 372.659656 -264.327431) (xy 372.683234 -264.373705)
			(xy 372.699282 -264.423098) (xy 372.707407 -264.474393) (xy 372.707916 -264.50036) (xy 372.707407 -264.526327)
			(xy 372.987317 -264.526327) (xy 372.987317 -264.474393) (xy 372.995442 -264.423098) (xy 373.01149 -264.373705)
			(xy 373.035068 -264.327431) (xy 373.065594 -264.285415) (xy 373.102317 -264.248692) (xy 373.144333 -264.218166)
			(xy 373.190607 -264.194588) (xy 373.24 -264.17854) (xy 373.291295 -264.170415) (xy 373.343229 -264.170415)
			(xy 373.394524 -264.17854) (xy 373.443917 -264.194588) (xy 373.490191 -264.218166) (xy 373.532207 -264.248692)
			(xy 373.56893 -264.285415) (xy 373.599456 -264.327431) (xy 373.623034 -264.373705) (xy 373.639082 -264.423098)
			(xy 373.647207 -264.474393) (xy 373.647716 -264.50036) (xy 373.647207 -264.526327) (xy 373.927371 -264.526327)
			(xy 373.927371 -264.474393) (xy 373.935496 -264.423098) (xy 373.951544 -264.373705) (xy 373.975122 -264.327431)
			(xy 374.005648 -264.285415) (xy 374.042371 -264.248692) (xy 374.084387 -264.218166) (xy 374.130661 -264.194588)
			(xy 374.180054 -264.17854) (xy 374.231349 -264.170415) (xy 374.283283 -264.170415) (xy 374.334578 -264.17854)
			(xy 374.383971 -264.194588) (xy 374.430245 -264.218166) (xy 374.472261 -264.248692) (xy 374.508984 -264.285415)
			(xy 374.53951 -264.327431) (xy 374.563088 -264.373705) (xy 374.579136 -264.423098) (xy 374.587261 -264.474393)
			(xy 374.58777 -264.50036) (xy 374.587261 -264.526327) (xy 374.866917 -264.526327) (xy 374.866917 -264.474393)
			(xy 374.875042 -264.423098) (xy 374.89109 -264.373705) (xy 374.914668 -264.327431) (xy 374.945194 -264.285415)
			(xy 374.981917 -264.248692) (xy 375.023933 -264.218166) (xy 375.070207 -264.194588) (xy 375.1196 -264.17854)
			(xy 375.170895 -264.170415) (xy 375.222829 -264.170415) (xy 375.274124 -264.17854) (xy 375.323517 -264.194588)
			(xy 375.369791 -264.218166) (xy 375.411807 -264.248692) (xy 375.44853 -264.285415) (xy 375.479056 -264.327431)
			(xy 375.502634 -264.373705) (xy 375.518682 -264.423098) (xy 375.526807 -264.474393) (xy 375.527316 -264.50036)
			(xy 375.526807 -264.526327) (xy 375.806717 -264.526327) (xy 375.806717 -264.474393) (xy 375.814842 -264.423098)
			(xy 375.83089 -264.373705) (xy 375.854468 -264.327431) (xy 375.884994 -264.285415) (xy 375.921717 -264.248692)
			(xy 375.963733 -264.218166) (xy 376.010007 -264.194588) (xy 376.0594 -264.17854) (xy 376.110695 -264.170415)
			(xy 376.162629 -264.170415) (xy 376.213924 -264.17854) (xy 376.263317 -264.194588) (xy 376.309591 -264.218166)
			(xy 376.351607 -264.248692) (xy 376.38833 -264.285415) (xy 376.418856 -264.327431) (xy 376.442434 -264.373705)
			(xy 376.458482 -264.423098) (xy 376.466607 -264.474393) (xy 376.467116 -264.50036) (xy 376.466607 -264.526327)
			(xy 376.746517 -264.526327) (xy 376.746517 -264.474393) (xy 376.754642 -264.423098) (xy 376.77069 -264.373705)
			(xy 376.794268 -264.327431) (xy 376.824794 -264.285415) (xy 376.861517 -264.248692) (xy 376.903533 -264.218166)
			(xy 376.949807 -264.194588) (xy 376.9992 -264.17854) (xy 377.050495 -264.170415) (xy 377.102429 -264.170415)
			(xy 377.153724 -264.17854) (xy 377.203117 -264.194588) (xy 377.249391 -264.218166) (xy 377.291407 -264.248692)
			(xy 377.32813 -264.285415) (xy 377.358656 -264.327431) (xy 377.382234 -264.373705) (xy 377.398282 -264.423098)
			(xy 377.406407 -264.474393) (xy 377.406916 -264.50036) (xy 377.406407 -264.526327) (xy 377.686317 -264.526327)
			(xy 377.686317 -264.474393) (xy 377.694442 -264.423098) (xy 377.71049 -264.373705) (xy 377.734068 -264.327431)
			(xy 377.764594 -264.285415) (xy 377.801317 -264.248692) (xy 377.843333 -264.218166) (xy 377.889607 -264.194588)
			(xy 377.939 -264.17854) (xy 377.990295 -264.170415) (xy 378.042229 -264.170415) (xy 378.093524 -264.17854)
			(xy 378.142917 -264.194588) (xy 378.189191 -264.218166) (xy 378.231207 -264.248692) (xy 378.26793 -264.285415)
			(xy 378.298456 -264.327431) (xy 378.322034 -264.373705) (xy 378.338082 -264.423098) (xy 378.346207 -264.474393)
			(xy 378.346716 -264.50036) (xy 378.346207 -264.526327) (xy 378.626117 -264.526327) (xy 378.626117 -264.474393)
			(xy 378.634242 -264.423098) (xy 378.65029 -264.373705) (xy 378.673868 -264.327431) (xy 378.704394 -264.285415)
			(xy 378.741117 -264.248692) (xy 378.783133 -264.218166) (xy 378.829407 -264.194588) (xy 378.8788 -264.17854)
			(xy 378.930095 -264.170415) (xy 378.982029 -264.170415) (xy 379.033324 -264.17854) (xy 379.082717 -264.194588)
			(xy 379.128991 -264.218166) (xy 379.171007 -264.248692) (xy 379.20773 -264.285415) (xy 379.238256 -264.327431)
			(xy 379.261834 -264.373705) (xy 379.277882 -264.423098) (xy 379.286007 -264.474393) (xy 379.286516 -264.50036)
			(xy 379.286007 -264.526327) (xy 379.277882 -264.577622) (xy 379.261834 -264.627015) (xy 379.238256 -264.673289)
			(xy 379.20773 -264.715305) (xy 379.171007 -264.752028) (xy 379.128991 -264.782554) (xy 379.082717 -264.806132)
			(xy 379.033324 -264.82218) (xy 378.982029 -264.830305) (xy 378.930095 -264.830305) (xy 378.8788 -264.82218)
			(xy 378.829407 -264.806132) (xy 378.783133 -264.782554) (xy 378.741117 -264.752028) (xy 378.704394 -264.715305)
			(xy 378.673868 -264.673289) (xy 378.65029 -264.627015) (xy 378.634242 -264.577622) (xy 378.626117 -264.526327)
			(xy 378.346207 -264.526327) (xy 378.338082 -264.577622) (xy 378.322034 -264.627015) (xy 378.298456 -264.673289)
			(xy 378.26793 -264.715305) (xy 378.231207 -264.752028) (xy 378.189191 -264.782554) (xy 378.142917 -264.806132)
			(xy 378.093524 -264.82218) (xy 378.042229 -264.830305) (xy 377.990295 -264.830305) (xy 377.939 -264.82218)
			(xy 377.889607 -264.806132) (xy 377.843333 -264.782554) (xy 377.801317 -264.752028) (xy 377.764594 -264.715305)
			(xy 377.734068 -264.673289) (xy 377.71049 -264.627015) (xy 377.694442 -264.577622) (xy 377.686317 -264.526327)
			(xy 377.406407 -264.526327) (xy 377.398282 -264.577622) (xy 377.382234 -264.627015) (xy 377.358656 -264.673289)
			(xy 377.32813 -264.715305) (xy 377.291407 -264.752028) (xy 377.249391 -264.782554) (xy 377.203117 -264.806132)
			(xy 377.153724 -264.82218) (xy 377.102429 -264.830305) (xy 377.050495 -264.830305) (xy 376.9992 -264.82218)
			(xy 376.949807 -264.806132) (xy 376.903533 -264.782554) (xy 376.861517 -264.752028) (xy 376.824794 -264.715305)
			(xy 376.794268 -264.673289) (xy 376.77069 -264.627015) (xy 376.754642 -264.577622) (xy 376.746517 -264.526327)
			(xy 376.466607 -264.526327) (xy 376.458482 -264.577622) (xy 376.442434 -264.627015) (xy 376.418856 -264.673289)
			(xy 376.38833 -264.715305) (xy 376.351607 -264.752028) (xy 376.309591 -264.782554) (xy 376.263317 -264.806132)
			(xy 376.213924 -264.82218) (xy 376.162629 -264.830305) (xy 376.110695 -264.830305) (xy 376.0594 -264.82218)
			(xy 376.010007 -264.806132) (xy 375.963733 -264.782554) (xy 375.921717 -264.752028) (xy 375.884994 -264.715305)
			(xy 375.854468 -264.673289) (xy 375.83089 -264.627015) (xy 375.814842 -264.577622) (xy 375.806717 -264.526327)
			(xy 375.526807 -264.526327) (xy 375.518682 -264.577622) (xy 375.502634 -264.627015) (xy 375.479056 -264.673289)
			(xy 375.44853 -264.715305) (xy 375.411807 -264.752028) (xy 375.369791 -264.782554) (xy 375.323517 -264.806132)
			(xy 375.274124 -264.82218) (xy 375.222829 -264.830305) (xy 375.170895 -264.830305) (xy 375.1196 -264.82218)
			(xy 375.070207 -264.806132) (xy 375.023933 -264.782554) (xy 374.981917 -264.752028) (xy 374.945194 -264.715305)
			(xy 374.914668 -264.673289) (xy 374.89109 -264.627015) (xy 374.875042 -264.577622) (xy 374.866917 -264.526327)
			(xy 374.587261 -264.526327) (xy 374.579136 -264.577622) (xy 374.563088 -264.627015) (xy 374.53951 -264.673289)
			(xy 374.508984 -264.715305) (xy 374.472261 -264.752028) (xy 374.430245 -264.782554) (xy 374.383971 -264.806132)
			(xy 374.334578 -264.82218) (xy 374.283283 -264.830305) (xy 374.231349 -264.830305) (xy 374.180054 -264.82218)
			(xy 374.130661 -264.806132) (xy 374.084387 -264.782554) (xy 374.042371 -264.752028) (xy 374.005648 -264.715305)
			(xy 373.975122 -264.673289) (xy 373.951544 -264.627015) (xy 373.935496 -264.577622) (xy 373.927371 -264.526327)
			(xy 373.647207 -264.526327) (xy 373.639082 -264.577622) (xy 373.623034 -264.627015) (xy 373.599456 -264.673289)
			(xy 373.56893 -264.715305) (xy 373.532207 -264.752028) (xy 373.490191 -264.782554) (xy 373.443917 -264.806132)
			(xy 373.394524 -264.82218) (xy 373.343229 -264.830305) (xy 373.291295 -264.830305) (xy 373.24 -264.82218)
			(xy 373.190607 -264.806132) (xy 373.144333 -264.782554) (xy 373.102317 -264.752028) (xy 373.065594 -264.715305)
			(xy 373.035068 -264.673289) (xy 373.01149 -264.627015) (xy 372.995442 -264.577622) (xy 372.987317 -264.526327)
			(xy 372.707407 -264.526327) (xy 372.699282 -264.577622) (xy 372.683234 -264.627015) (xy 372.659656 -264.673289)
			(xy 372.62913 -264.715305) (xy 372.592407 -264.752028) (xy 372.550391 -264.782554) (xy 372.504117 -264.806132)
			(xy 372.454724 -264.82218) (xy 372.403429 -264.830305) (xy 372.351495 -264.830305) (xy 372.3002 -264.82218)
			(xy 372.250807 -264.806132) (xy 372.204533 -264.782554) (xy 372.162517 -264.752028) (xy 372.125794 -264.715305)
			(xy 372.095268 -264.673289) (xy 372.07169 -264.627015) (xy 372.055642 -264.577622) (xy 372.047517 -264.526327)
			(xy 371.767552 -264.526327) (xy 371.767552 -264.528077) (xy 371.758311 -264.582724) (xy 371.740081 -264.635064)
			(xy 371.727222 -264.659618) (xy 371.720872 -264.670794) (xy 371.720872 -264.890758) (xy 371.721421 -264.905766)
			(xy 371.730159 -264.934483) (xy 371.746862 -264.959423) (xy 371.770091 -264.978434) (xy 371.797841 -264.989876)
			(xy 371.827719 -264.992762) (xy 371.842538 -264.990326) (xy 371.858684 -264.987262) (xy 371.891383 -264.983952)
			(xy 371.907816 -264.983722) (xy 371.933781 -264.98428) (xy 371.98507 -264.992406) (xy 372.034457 -265.008455)
			(xy 372.080725 -265.032032) (xy 372.122736 -265.062556) (xy 372.159454 -265.099276) (xy 372.189977 -265.141289)
			(xy 372.213551 -265.187558) (xy 372.229598 -265.236946) (xy 372.237721 -265.288235) (xy 372.237721 -265.340143)
			(xy 372.517671 -265.340143) (xy 372.517671 -265.288209) (xy 372.525796 -265.236914) (xy 372.541844 -265.187521)
			(xy 372.565422 -265.141247) (xy 372.595948 -265.099231) (xy 372.632671 -265.062508) (xy 372.674687 -265.031982)
			(xy 372.720961 -265.008404) (xy 372.770354 -264.992356) (xy 372.821649 -264.984231) (xy 372.873583 -264.984231)
			(xy 372.924878 -264.992356) (xy 372.974271 -265.008404) (xy 373.020545 -265.031982) (xy 373.062561 -265.062508)
			(xy 373.099284 -265.099231) (xy 373.12981 -265.141247) (xy 373.153388 -265.187521) (xy 373.169436 -265.236914)
			(xy 373.177561 -265.288209) (xy 373.17807 -265.314176) (xy 373.177561 -265.340143) (xy 373.457471 -265.340143)
			(xy 373.457471 -265.288209) (xy 373.465596 -265.236914) (xy 373.481644 -265.187521) (xy 373.505222 -265.141247)
			(xy 373.535748 -265.099231) (xy 373.572471 -265.062508) (xy 373.614487 -265.031982) (xy 373.660761 -265.008404)
			(xy 373.710154 -264.992356) (xy 373.761449 -264.984231) (xy 373.813383 -264.984231) (xy 373.864678 -264.992356)
			(xy 373.914071 -265.008404) (xy 373.960345 -265.031982) (xy 374.002361 -265.062508) (xy 374.039084 -265.099231)
			(xy 374.06961 -265.141247) (xy 374.093188 -265.187521) (xy 374.109236 -265.236914) (xy 374.117361 -265.288209)
			(xy 374.11787 -265.314176) (xy 374.117361 -265.340143) (xy 374.397017 -265.340143) (xy 374.397017 -265.288209)
			(xy 374.405142 -265.236914) (xy 374.42119 -265.187521) (xy 374.444768 -265.141247) (xy 374.475294 -265.099231)
			(xy 374.512017 -265.062508) (xy 374.554033 -265.031982) (xy 374.600307 -265.008404) (xy 374.6497 -264.992356)
			(xy 374.700995 -264.984231) (xy 374.752929 -264.984231) (xy 374.804224 -264.992356) (xy 374.853617 -265.008404)
			(xy 374.899891 -265.031982) (xy 374.941907 -265.062508) (xy 374.97863 -265.099231) (xy 375.009156 -265.141247)
			(xy 375.032734 -265.187521) (xy 375.048782 -265.236914) (xy 375.056907 -265.288209) (xy 375.057416 -265.314176)
			(xy 375.056907 -265.340143) (xy 375.337071 -265.340143) (xy 375.337071 -265.288209) (xy 375.345196 -265.236914)
			(xy 375.361244 -265.187521) (xy 375.384822 -265.141247) (xy 375.415348 -265.099231) (xy 375.452071 -265.062508)
			(xy 375.494087 -265.031982) (xy 375.540361 -265.008404) (xy 375.589754 -264.992356) (xy 375.641049 -264.984231)
			(xy 375.692983 -264.984231) (xy 375.744278 -264.992356) (xy 375.793671 -265.008404) (xy 375.839945 -265.031982)
			(xy 375.881961 -265.062508) (xy 375.918684 -265.099231) (xy 375.94921 -265.141247) (xy 375.972788 -265.187521)
			(xy 375.988836 -265.236914) (xy 375.996961 -265.288209) (xy 375.99747 -265.314176) (xy 375.996961 -265.340143)
			(xy 376.276871 -265.340143) (xy 376.276871 -265.288209) (xy 376.284996 -265.236914) (xy 376.301044 -265.187521)
			(xy 376.324622 -265.141247) (xy 376.355148 -265.099231) (xy 376.391871 -265.062508) (xy 376.433887 -265.031982)
			(xy 376.480161 -265.008404) (xy 376.529554 -264.992356) (xy 376.580849 -264.984231) (xy 376.632783 -264.984231)
			(xy 376.684078 -264.992356) (xy 376.733471 -265.008404) (xy 376.779745 -265.031982) (xy 376.821761 -265.062508)
			(xy 376.858484 -265.099231) (xy 376.88901 -265.141247) (xy 376.912588 -265.187521) (xy 376.928636 -265.236914)
			(xy 376.936761 -265.288209) (xy 376.93727 -265.314176) (xy 376.936761 -265.340143) (xy 377.216671 -265.340143)
			(xy 377.216671 -265.288209) (xy 377.224796 -265.236914) (xy 377.240844 -265.187521) (xy 377.264422 -265.141247)
			(xy 377.294948 -265.099231) (xy 377.331671 -265.062508) (xy 377.373687 -265.031982) (xy 377.419961 -265.008404)
			(xy 377.469354 -264.992356) (xy 377.520649 -264.984231) (xy 377.572583 -264.984231) (xy 377.623878 -264.992356)
			(xy 377.673271 -265.008404) (xy 377.719545 -265.031982) (xy 377.761561 -265.062508) (xy 377.798284 -265.099231)
			(xy 377.82881 -265.141247) (xy 377.852388 -265.187521) (xy 377.868436 -265.236914) (xy 377.876561 -265.288209)
			(xy 377.87707 -265.314176) (xy 377.876561 -265.340143) (xy 378.156471 -265.340143) (xy 378.156471 -265.288209)
			(xy 378.164596 -265.236914) (xy 378.180644 -265.187521) (xy 378.204222 -265.141247) (xy 378.234748 -265.099231)
			(xy 378.271471 -265.062508) (xy 378.313487 -265.031982) (xy 378.359761 -265.008404) (xy 378.409154 -264.992356)
			(xy 378.460449 -264.984231) (xy 378.512383 -264.984231) (xy 378.563678 -264.992356) (xy 378.613071 -265.008404)
			(xy 378.659345 -265.031982) (xy 378.701361 -265.062508) (xy 378.738084 -265.099231) (xy 378.76861 -265.141247)
			(xy 378.792188 -265.187521) (xy 378.808236 -265.236914) (xy 378.816361 -265.288209) (xy 378.81687 -265.314176)
			(xy 378.816361 -265.340143) (xy 378.808236 -265.391438) (xy 378.792188 -265.440831) (xy 378.76861 -265.487105)
			(xy 378.738084 -265.529121) (xy 378.701361 -265.565844) (xy 378.659345 -265.59637) (xy 378.613071 -265.619948)
			(xy 378.563678 -265.635996) (xy 378.512383 -265.644121) (xy 378.460449 -265.644121) (xy 378.409154 -265.635996)
			(xy 378.359761 -265.619948) (xy 378.313487 -265.59637) (xy 378.271471 -265.565844) (xy 378.234748 -265.529121)
			(xy 378.204222 -265.487105) (xy 378.180644 -265.440831) (xy 378.164596 -265.391438) (xy 378.156471 -265.340143)
			(xy 377.876561 -265.340143) (xy 377.868436 -265.391438) (xy 377.852388 -265.440831) (xy 377.82881 -265.487105)
			(xy 377.798284 -265.529121) (xy 377.761561 -265.565844) (xy 377.719545 -265.59637) (xy 377.673271 -265.619948)
			(xy 377.623878 -265.635996) (xy 377.572583 -265.644121) (xy 377.520649 -265.644121) (xy 377.469354 -265.635996)
			(xy 377.419961 -265.619948) (xy 377.373687 -265.59637) (xy 377.331671 -265.565844) (xy 377.294948 -265.529121)
			(xy 377.264422 -265.487105) (xy 377.240844 -265.440831) (xy 377.224796 -265.391438) (xy 377.216671 -265.340143)
			(xy 376.936761 -265.340143) (xy 376.928636 -265.391438) (xy 376.912588 -265.440831) (xy 376.88901 -265.487105)
			(xy 376.858484 -265.529121) (xy 376.821761 -265.565844) (xy 376.779745 -265.59637) (xy 376.733471 -265.619948)
			(xy 376.684078 -265.635996) (xy 376.632783 -265.644121) (xy 376.580849 -265.644121) (xy 376.529554 -265.635996)
			(xy 376.480161 -265.619948) (xy 376.433887 -265.59637) (xy 376.391871 -265.565844) (xy 376.355148 -265.529121)
			(xy 376.324622 -265.487105) (xy 376.301044 -265.440831) (xy 376.284996 -265.391438) (xy 376.276871 -265.340143)
			(xy 375.996961 -265.340143) (xy 375.988836 -265.391438) (xy 375.972788 -265.440831) (xy 375.94921 -265.487105)
			(xy 375.918684 -265.529121) (xy 375.881961 -265.565844) (xy 375.839945 -265.59637) (xy 375.793671 -265.619948)
			(xy 375.744278 -265.635996) (xy 375.692983 -265.644121) (xy 375.641049 -265.644121) (xy 375.589754 -265.635996)
			(xy 375.540361 -265.619948) (xy 375.494087 -265.59637) (xy 375.452071 -265.565844) (xy 375.415348 -265.529121)
			(xy 375.384822 -265.487105) (xy 375.361244 -265.440831) (xy 375.345196 -265.391438) (xy 375.337071 -265.340143)
			(xy 375.056907 -265.340143) (xy 375.048782 -265.391438) (xy 375.032734 -265.440831) (xy 375.009156 -265.487105)
			(xy 374.97863 -265.529121) (xy 374.941907 -265.565844) (xy 374.899891 -265.59637) (xy 374.853617 -265.619948)
			(xy 374.804224 -265.635996) (xy 374.752929 -265.644121) (xy 374.700995 -265.644121) (xy 374.6497 -265.635996)
			(xy 374.600307 -265.619948) (xy 374.554033 -265.59637) (xy 374.512017 -265.565844) (xy 374.475294 -265.529121)
			(xy 374.444768 -265.487105) (xy 374.42119 -265.440831) (xy 374.405142 -265.391438) (xy 374.397017 -265.340143)
			(xy 374.117361 -265.340143) (xy 374.109236 -265.391438) (xy 374.093188 -265.440831) (xy 374.06961 -265.487105)
			(xy 374.039084 -265.529121) (xy 374.002361 -265.565844) (xy 373.960345 -265.59637) (xy 373.914071 -265.619948)
			(xy 373.864678 -265.635996) (xy 373.813383 -265.644121) (xy 373.761449 -265.644121) (xy 373.710154 -265.635996)
			(xy 373.660761 -265.619948) (xy 373.614487 -265.59637) (xy 373.572471 -265.565844) (xy 373.535748 -265.529121)
			(xy 373.505222 -265.487105) (xy 373.481644 -265.440831) (xy 373.465596 -265.391438) (xy 373.457471 -265.340143)
			(xy 373.177561 -265.340143) (xy 373.169436 -265.391438) (xy 373.153388 -265.440831) (xy 373.12981 -265.487105)
			(xy 373.099284 -265.529121) (xy 373.062561 -265.565844) (xy 373.020545 -265.59637) (xy 372.974271 -265.619948)
			(xy 372.924878 -265.635996) (xy 372.873583 -265.644121) (xy 372.821649 -265.644121) (xy 372.770354 -265.635996)
			(xy 372.720961 -265.619948) (xy 372.674687 -265.59637) (xy 372.632671 -265.565844) (xy 372.595948 -265.529121)
			(xy 372.565422 -265.487105) (xy 372.541844 -265.440831) (xy 372.525796 -265.391438) (xy 372.517671 -265.340143)
			(xy 372.237721 -265.340143) (xy 372.237721 -265.340165) (xy 372.229598 -265.391454) (xy 372.213551 -265.440842)
			(xy 372.189977 -265.487111) (xy 372.159454 -265.529124) (xy 372.122736 -265.565844) (xy 372.080725 -265.596368)
			(xy 372.034457 -265.619945) (xy 371.98507 -265.635994) (xy 371.933781 -265.64412) (xy 371.907816 -265.64463)
			(xy 371.891382 -265.644418) (xy 371.858682 -265.641107) (xy 371.842538 -265.638026) (xy 371.82771 -265.635637)
			(xy 371.797831 -265.638499) (xy 371.770075 -265.649925) (xy 371.746842 -265.668929) (xy 371.730138 -265.693868)
			(xy 371.721408 -265.722586) (xy 371.720872 -265.737594) (xy 371.720872 -265.957812) (xy 371.727222 -265.968988)
			(xy 371.740121 -265.993524) (xy 371.758352 -266.045871) (xy 371.767594 -266.100525) (xy 371.767587 -266.154213)
			(xy 372.047517 -266.154213) (xy 372.047517 -266.102279) (xy 372.055642 -266.050984) (xy 372.07169 -266.001591)
			(xy 372.095268 -265.955317) (xy 372.125794 -265.913301) (xy 372.162517 -265.876578) (xy 372.204533 -265.846052)
			(xy 372.250807 -265.822474) (xy 372.3002 -265.806426) (xy 372.351495 -265.798301) (xy 372.403429 -265.798301)
			(xy 372.454724 -265.806426) (xy 372.504117 -265.822474) (xy 372.550391 -265.846052) (xy 372.592407 -265.876578)
			(xy 372.62913 -265.913301) (xy 372.659656 -265.955317) (xy 372.683234 -266.001591) (xy 372.699282 -266.050984)
			(xy 372.707407 -266.102279) (xy 372.707916 -266.128246) (xy 372.707407 -266.154213) (xy 372.987317 -266.154213)
			(xy 372.987317 -266.102279) (xy 372.995442 -266.050984) (xy 373.01149 -266.001591) (xy 373.035068 -265.955317)
			(xy 373.065594 -265.913301) (xy 373.102317 -265.876578) (xy 373.144333 -265.846052) (xy 373.190607 -265.822474)
			(xy 373.24 -265.806426) (xy 373.291295 -265.798301) (xy 373.343229 -265.798301) (xy 373.394524 -265.806426)
			(xy 373.443917 -265.822474) (xy 373.490191 -265.846052) (xy 373.532207 -265.876578) (xy 373.56893 -265.913301)
			(xy 373.599456 -265.955317) (xy 373.623034 -266.001591) (xy 373.639082 -266.050984) (xy 373.647207 -266.102279)
			(xy 373.647716 -266.128246) (xy 373.647207 -266.154213) (xy 373.927117 -266.154213) (xy 373.927117 -266.102279)
			(xy 373.935242 -266.050984) (xy 373.95129 -266.001591) (xy 373.974868 -265.955317) (xy 374.005394 -265.913301)
			(xy 374.042117 -265.876578) (xy 374.084133 -265.846052) (xy 374.130407 -265.822474) (xy 374.1798 -265.806426)
			(xy 374.231095 -265.798301) (xy 374.283029 -265.798301) (xy 374.334324 -265.806426) (xy 374.383717 -265.822474)
			(xy 374.429991 -265.846052) (xy 374.472007 -265.876578) (xy 374.50873 -265.913301) (xy 374.539256 -265.955317)
			(xy 374.562834 -266.001591) (xy 374.578882 -266.050984) (xy 374.587007 -266.102279) (xy 374.587516 -266.128246)
			(xy 374.587007 -266.154213) (xy 374.866917 -266.154213) (xy 374.866917 -266.102279) (xy 374.875042 -266.050984)
			(xy 374.89109 -266.001591) (xy 374.914668 -265.955317) (xy 374.945194 -265.913301) (xy 374.981917 -265.876578)
			(xy 375.023933 -265.846052) (xy 375.070207 -265.822474) (xy 375.1196 -265.806426) (xy 375.170895 -265.798301)
			(xy 375.222829 -265.798301) (xy 375.274124 -265.806426) (xy 375.323517 -265.822474) (xy 375.369791 -265.846052)
			(xy 375.411807 -265.876578) (xy 375.44853 -265.913301) (xy 375.479056 -265.955317) (xy 375.502634 -266.001591)
			(xy 375.518682 -266.050984) (xy 375.526807 -266.102279) (xy 375.527316 -266.128246) (xy 375.526807 -266.154213)
			(xy 375.806717 -266.154213) (xy 375.806717 -266.102279) (xy 375.814842 -266.050984) (xy 375.83089 -266.001591)
			(xy 375.854468 -265.955317) (xy 375.884994 -265.913301) (xy 375.921717 -265.876578) (xy 375.963733 -265.846052)
			(xy 376.010007 -265.822474) (xy 376.0594 -265.806426) (xy 376.110695 -265.798301) (xy 376.162629 -265.798301)
			(xy 376.213924 -265.806426) (xy 376.263317 -265.822474) (xy 376.309591 -265.846052) (xy 376.351607 -265.876578)
			(xy 376.38833 -265.913301) (xy 376.418856 -265.955317) (xy 376.442434 -266.001591) (xy 376.458482 -266.050984)
			(xy 376.466607 -266.102279) (xy 376.467116 -266.128246) (xy 376.466607 -266.154213) (xy 376.746517 -266.154213)
			(xy 376.746517 -266.102279) (xy 376.754642 -266.050984) (xy 376.77069 -266.001591) (xy 376.794268 -265.955317)
			(xy 376.824794 -265.913301) (xy 376.861517 -265.876578) (xy 376.903533 -265.846052) (xy 376.949807 -265.822474)
			(xy 376.9992 -265.806426) (xy 377.050495 -265.798301) (xy 377.102429 -265.798301) (xy 377.153724 -265.806426)
			(xy 377.203117 -265.822474) (xy 377.249391 -265.846052) (xy 377.291407 -265.876578) (xy 377.32813 -265.913301)
			(xy 377.358656 -265.955317) (xy 377.382234 -266.001591) (xy 377.398282 -266.050984) (xy 377.406407 -266.102279)
			(xy 377.406916 -266.128246) (xy 377.406407 -266.154213) (xy 377.686317 -266.154213) (xy 377.686317 -266.102279)
			(xy 377.694442 -266.050984) (xy 377.71049 -266.001591) (xy 377.734068 -265.955317) (xy 377.764594 -265.913301)
			(xy 377.801317 -265.876578) (xy 377.843333 -265.846052) (xy 377.889607 -265.822474) (xy 377.939 -265.806426)
			(xy 377.990295 -265.798301) (xy 378.042229 -265.798301) (xy 378.093524 -265.806426) (xy 378.142917 -265.822474)
			(xy 378.189191 -265.846052) (xy 378.231207 -265.876578) (xy 378.26793 -265.913301) (xy 378.298456 -265.955317)
			(xy 378.322034 -266.001591) (xy 378.338082 -266.050984) (xy 378.346207 -266.102279) (xy 378.346716 -266.128246)
			(xy 378.346207 -266.154213) (xy 378.626117 -266.154213) (xy 378.626117 -266.102279) (xy 378.634242 -266.050984)
			(xy 378.65029 -266.001591) (xy 378.673868 -265.955317) (xy 378.704394 -265.913301) (xy 378.741117 -265.876578)
			(xy 378.783133 -265.846052) (xy 378.829407 -265.822474) (xy 378.8788 -265.806426) (xy 378.930095 -265.798301)
			(xy 378.982029 -265.798301) (xy 379.033324 -265.806426) (xy 379.082717 -265.822474) (xy 379.128991 -265.846052)
			(xy 379.171007 -265.876578) (xy 379.20773 -265.913301) (xy 379.238256 -265.955317) (xy 379.261834 -266.001591)
			(xy 379.277882 -266.050984) (xy 379.286007 -266.102279) (xy 379.286516 -266.128246) (xy 379.286007 -266.154213)
			(xy 379.277882 -266.205508) (xy 379.261834 -266.254901) (xy 379.238256 -266.301175) (xy 379.20773 -266.343191)
			(xy 379.171007 -266.379914) (xy 379.128991 -266.41044) (xy 379.082717 -266.434018) (xy 379.033324 -266.450066)
			(xy 378.982029 -266.458191) (xy 378.930095 -266.458191) (xy 378.8788 -266.450066) (xy 378.829407 -266.434018)
			(xy 378.783133 -266.41044) (xy 378.741117 -266.379914) (xy 378.704394 -266.343191) (xy 378.673868 -266.301175)
			(xy 378.65029 -266.254901) (xy 378.634242 -266.205508) (xy 378.626117 -266.154213) (xy 378.346207 -266.154213)
			(xy 378.338082 -266.205508) (xy 378.322034 -266.254901) (xy 378.298456 -266.301175) (xy 378.26793 -266.343191)
			(xy 378.231207 -266.379914) (xy 378.189191 -266.41044) (xy 378.142917 -266.434018) (xy 378.093524 -266.450066)
			(xy 378.042229 -266.458191) (xy 377.990295 -266.458191) (xy 377.939 -266.450066) (xy 377.889607 -266.434018)
			(xy 377.843333 -266.41044) (xy 377.801317 -266.379914) (xy 377.764594 -266.343191) (xy 377.734068 -266.301175)
			(xy 377.71049 -266.254901) (xy 377.694442 -266.205508) (xy 377.686317 -266.154213) (xy 377.406407 -266.154213)
			(xy 377.398282 -266.205508) (xy 377.382234 -266.254901) (xy 377.358656 -266.301175) (xy 377.32813 -266.343191)
			(xy 377.291407 -266.379914) (xy 377.249391 -266.41044) (xy 377.203117 -266.434018) (xy 377.153724 -266.450066)
			(xy 377.102429 -266.458191) (xy 377.050495 -266.458191) (xy 376.9992 -266.450066) (xy 376.949807 -266.434018)
			(xy 376.903533 -266.41044) (xy 376.861517 -266.379914) (xy 376.824794 -266.343191) (xy 376.794268 -266.301175)
			(xy 376.77069 -266.254901) (xy 376.754642 -266.205508) (xy 376.746517 -266.154213) (xy 376.466607 -266.154213)
			(xy 376.458482 -266.205508) (xy 376.442434 -266.254901) (xy 376.418856 -266.301175) (xy 376.38833 -266.343191)
			(xy 376.351607 -266.379914) (xy 376.309591 -266.41044) (xy 376.263317 -266.434018) (xy 376.213924 -266.450066)
			(xy 376.162629 -266.458191) (xy 376.110695 -266.458191) (xy 376.0594 -266.450066) (xy 376.010007 -266.434018)
			(xy 375.963733 -266.41044) (xy 375.921717 -266.379914) (xy 375.884994 -266.343191) (xy 375.854468 -266.301175)
			(xy 375.83089 -266.254901) (xy 375.814842 -266.205508) (xy 375.806717 -266.154213) (xy 375.526807 -266.154213)
			(xy 375.518682 -266.205508) (xy 375.502634 -266.254901) (xy 375.479056 -266.301175) (xy 375.44853 -266.343191)
			(xy 375.411807 -266.379914) (xy 375.369791 -266.41044) (xy 375.323517 -266.434018) (xy 375.274124 -266.450066)
			(xy 375.222829 -266.458191) (xy 375.170895 -266.458191) (xy 375.1196 -266.450066) (xy 375.070207 -266.434018)
			(xy 375.023933 -266.41044) (xy 374.981917 -266.379914) (xy 374.945194 -266.343191) (xy 374.914668 -266.301175)
			(xy 374.89109 -266.254901) (xy 374.875042 -266.205508) (xy 374.866917 -266.154213) (xy 374.587007 -266.154213)
			(xy 374.578882 -266.205508) (xy 374.562834 -266.254901) (xy 374.539256 -266.301175) (xy 374.50873 -266.343191)
			(xy 374.472007 -266.379914) (xy 374.429991 -266.41044) (xy 374.383717 -266.434018) (xy 374.334324 -266.450066)
			(xy 374.283029 -266.458191) (xy 374.231095 -266.458191) (xy 374.1798 -266.450066) (xy 374.130407 -266.434018)
			(xy 374.084133 -266.41044) (xy 374.042117 -266.379914) (xy 374.005394 -266.343191) (xy 373.974868 -266.301175)
			(xy 373.95129 -266.254901) (xy 373.935242 -266.205508) (xy 373.927117 -266.154213) (xy 373.647207 -266.154213)
			(xy 373.639082 -266.205508) (xy 373.623034 -266.254901) (xy 373.599456 -266.301175) (xy 373.56893 -266.343191)
			(xy 373.532207 -266.379914) (xy 373.490191 -266.41044) (xy 373.443917 -266.434018) (xy 373.394524 -266.450066)
			(xy 373.343229 -266.458191) (xy 373.291295 -266.458191) (xy 373.24 -266.450066) (xy 373.190607 -266.434018)
			(xy 373.144333 -266.41044) (xy 373.102317 -266.379914) (xy 373.065594 -266.343191) (xy 373.035068 -266.301175)
			(xy 373.01149 -266.254901) (xy 372.995442 -266.205508) (xy 372.987317 -266.154213) (xy 372.707407 -266.154213)
			(xy 372.699282 -266.205508) (xy 372.683234 -266.254901) (xy 372.659656 -266.301175) (xy 372.62913 -266.343191)
			(xy 372.592407 -266.379914) (xy 372.550391 -266.41044) (xy 372.504117 -266.434018) (xy 372.454724 -266.450066)
			(xy 372.403429 -266.458191) (xy 372.351495 -266.458191) (xy 372.3002 -266.450066) (xy 372.250807 -266.434018)
			(xy 372.204533 -266.41044) (xy 372.162517 -266.379914) (xy 372.125794 -266.343191) (xy 372.095268 -266.301175)
			(xy 372.07169 -266.254901) (xy 372.055642 -266.205508) (xy 372.047517 -266.154213) (xy 371.767587 -266.154213)
			(xy 371.767587 -266.155955) (xy 371.758332 -266.210608) (xy 371.740088 -266.26295) (xy 371.727222 -266.287504)
			(xy 371.720872 -266.29868) (xy 371.720872 -266.51839) (xy 371.721395 -266.533399) (xy 371.73014 -266.562117)
			(xy 371.74685 -266.587056) (xy 371.770083 -266.606065) (xy 371.797837 -266.617507) (xy 371.827718 -266.620393)
			(xy 371.842538 -266.617958) (xy 371.858684 -266.614894) (xy 371.891383 -266.611584) (xy 371.907816 -266.611354)
			(xy 371.933783 -266.611848) (xy 371.985077 -266.619975) (xy 372.034469 -266.636025) (xy 372.080742 -266.659605)
			(xy 372.122756 -266.690132) (xy 372.159479 -266.726856) (xy 372.190004 -266.768872) (xy 372.213581 -266.815146)
			(xy 372.229629 -266.864538) (xy 372.237753 -266.915833) (xy 372.237753 -266.967767) (xy 372.237752 -266.967775)
			(xy 372.517671 -266.967775) (xy 372.517671 -266.915841) (xy 372.525796 -266.864546) (xy 372.541844 -266.815153)
			(xy 372.565422 -266.768879) (xy 372.595948 -266.726863) (xy 372.632671 -266.69014) (xy 372.674687 -266.659614)
			(xy 372.720961 -266.636036) (xy 372.770354 -266.619988) (xy 372.821649 -266.611863) (xy 372.873583 -266.611863)
			(xy 372.924878 -266.619988) (xy 372.974271 -266.636036) (xy 373.020545 -266.659614) (xy 373.062561 -266.69014)
			(xy 373.099284 -266.726863) (xy 373.12981 -266.768879) (xy 373.153388 -266.815153) (xy 373.169436 -266.864546)
			(xy 373.177561 -266.915841) (xy 373.17807 -266.941808) (xy 373.177561 -266.967775) (xy 373.457217 -266.967775)
			(xy 373.457217 -266.915841) (xy 373.465342 -266.864546) (xy 373.48139 -266.815153) (xy 373.504968 -266.768879)
			(xy 373.535494 -266.726863) (xy 373.572217 -266.69014) (xy 373.614233 -266.659614) (xy 373.660507 -266.636036)
			(xy 373.7099 -266.619988) (xy 373.761195 -266.611863) (xy 373.813129 -266.611863) (xy 373.864424 -266.619988)
			(xy 373.913817 -266.636036) (xy 373.960091 -266.659614) (xy 374.002107 -266.69014) (xy 374.03883 -266.726863)
			(xy 374.069356 -266.768879) (xy 374.092934 -266.815153) (xy 374.108982 -266.864546) (xy 374.117107 -266.915841)
			(xy 374.117616 -266.941808) (xy 374.117107 -266.967775) (xy 374.397271 -266.967775) (xy 374.397271 -266.915841)
			(xy 374.405396 -266.864546) (xy 374.421444 -266.815153) (xy 374.445022 -266.768879) (xy 374.475548 -266.726863)
			(xy 374.512271 -266.69014) (xy 374.554287 -266.659614) (xy 374.600561 -266.636036) (xy 374.649954 -266.619988)
			(xy 374.701249 -266.611863) (xy 374.753183 -266.611863) (xy 374.804478 -266.619988) (xy 374.853871 -266.636036)
			(xy 374.900145 -266.659614) (xy 374.942161 -266.69014) (xy 374.978884 -266.726863) (xy 375.00941 -266.768879)
			(xy 375.032988 -266.815153) (xy 375.049036 -266.864546) (xy 375.057161 -266.915841) (xy 375.05767 -266.941808)
			(xy 375.057161 -266.967775) (xy 375.337071 -266.967775) (xy 375.337071 -266.915841) (xy 375.345196 -266.864546)
			(xy 375.361244 -266.815153) (xy 375.384822 -266.768879) (xy 375.415348 -266.726863) (xy 375.452071 -266.69014)
			(xy 375.494087 -266.659614) (xy 375.540361 -266.636036) (xy 375.589754 -266.619988) (xy 375.641049 -266.611863)
			(xy 375.692983 -266.611863) (xy 375.744278 -266.619988) (xy 375.793671 -266.636036) (xy 375.839945 -266.659614)
			(xy 375.881961 -266.69014) (xy 375.918684 -266.726863) (xy 375.94921 -266.768879) (xy 375.972788 -266.815153)
			(xy 375.988836 -266.864546) (xy 375.996961 -266.915841) (xy 375.99747 -266.941808) (xy 375.996961 -266.967775)
			(xy 376.276871 -266.967775) (xy 376.276871 -266.915841) (xy 376.284996 -266.864546) (xy 376.301044 -266.815153)
			(xy 376.324622 -266.768879) (xy 376.355148 -266.726863) (xy 376.391871 -266.69014) (xy 376.433887 -266.659614)
			(xy 376.480161 -266.636036) (xy 376.529554 -266.619988) (xy 376.580849 -266.611863) (xy 376.632783 -266.611863)
			(xy 376.684078 -266.619988) (xy 376.733471 -266.636036) (xy 376.779745 -266.659614) (xy 376.821761 -266.69014)
			(xy 376.858484 -266.726863) (xy 376.88901 -266.768879) (xy 376.912588 -266.815153) (xy 376.928636 -266.864546)
			(xy 376.936761 -266.915841) (xy 376.93727 -266.941808) (xy 376.936761 -266.967775) (xy 377.216671 -266.967775)
			(xy 377.216671 -266.915841) (xy 377.224796 -266.864546) (xy 377.240844 -266.815153) (xy 377.264422 -266.768879)
			(xy 377.294948 -266.726863) (xy 377.331671 -266.69014) (xy 377.373687 -266.659614) (xy 377.419961 -266.636036)
			(xy 377.469354 -266.619988) (xy 377.520649 -266.611863) (xy 377.572583 -266.611863) (xy 377.623878 -266.619988)
			(xy 377.673271 -266.636036) (xy 377.719545 -266.659614) (xy 377.761561 -266.69014) (xy 377.798284 -266.726863)
			(xy 377.82881 -266.768879) (xy 377.852388 -266.815153) (xy 377.868436 -266.864546) (xy 377.876561 -266.915841)
			(xy 377.87707 -266.941808) (xy 377.876561 -266.967775) (xy 378.156471 -266.967775) (xy 378.156471 -266.915841)
			(xy 378.164596 -266.864546) (xy 378.180644 -266.815153) (xy 378.204222 -266.768879) (xy 378.234748 -266.726863)
			(xy 378.271471 -266.69014) (xy 378.313487 -266.659614) (xy 378.359761 -266.636036) (xy 378.409154 -266.619988)
			(xy 378.460449 -266.611863) (xy 378.512383 -266.611863) (xy 378.563678 -266.619988) (xy 378.613071 -266.636036)
			(xy 378.659345 -266.659614) (xy 378.701361 -266.69014) (xy 378.738084 -266.726863) (xy 378.76861 -266.768879)
			(xy 378.792188 -266.815153) (xy 378.808236 -266.864546) (xy 378.816361 -266.915841) (xy 378.81687 -266.941808)
			(xy 378.816361 -266.967775) (xy 378.808236 -267.01907) (xy 378.792188 -267.068463) (xy 378.76861 -267.114737)
			(xy 378.738084 -267.156753) (xy 378.701361 -267.193476) (xy 378.659345 -267.224002) (xy 378.613071 -267.24758)
			(xy 378.563678 -267.263628) (xy 378.512383 -267.271753) (xy 378.460449 -267.271753) (xy 378.409154 -267.263628)
			(xy 378.359761 -267.24758) (xy 378.313487 -267.224002) (xy 378.271471 -267.193476) (xy 378.234748 -267.156753)
			(xy 378.204222 -267.114737) (xy 378.180644 -267.068463) (xy 378.164596 -267.01907) (xy 378.156471 -266.967775)
			(xy 377.876561 -266.967775) (xy 377.868436 -267.01907) (xy 377.852388 -267.068463) (xy 377.82881 -267.114737)
			(xy 377.798284 -267.156753) (xy 377.761561 -267.193476) (xy 377.719545 -267.224002) (xy 377.673271 -267.24758)
			(xy 377.623878 -267.263628) (xy 377.572583 -267.271753) (xy 377.520649 -267.271753) (xy 377.469354 -267.263628)
			(xy 377.419961 -267.24758) (xy 377.373687 -267.224002) (xy 377.331671 -267.193476) (xy 377.294948 -267.156753)
			(xy 377.264422 -267.114737) (xy 377.240844 -267.068463) (xy 377.224796 -267.01907) (xy 377.216671 -266.967775)
			(xy 376.936761 -266.967775) (xy 376.928636 -267.01907) (xy 376.912588 -267.068463) (xy 376.88901 -267.114737)
			(xy 376.858484 -267.156753) (xy 376.821761 -267.193476) (xy 376.779745 -267.224002) (xy 376.733471 -267.24758)
			(xy 376.684078 -267.263628) (xy 376.632783 -267.271753) (xy 376.580849 -267.271753) (xy 376.529554 -267.263628)
			(xy 376.480161 -267.24758) (xy 376.433887 -267.224002) (xy 376.391871 -267.193476) (xy 376.355148 -267.156753)
			(xy 376.324622 -267.114737) (xy 376.301044 -267.068463) (xy 376.284996 -267.01907) (xy 376.276871 -266.967775)
			(xy 375.996961 -266.967775) (xy 375.988836 -267.01907) (xy 375.972788 -267.068463) (xy 375.94921 -267.114737)
			(xy 375.918684 -267.156753) (xy 375.881961 -267.193476) (xy 375.839945 -267.224002) (xy 375.793671 -267.24758)
			(xy 375.744278 -267.263628) (xy 375.692983 -267.271753) (xy 375.641049 -267.271753) (xy 375.589754 -267.263628)
			(xy 375.540361 -267.24758) (xy 375.494087 -267.224002) (xy 375.452071 -267.193476) (xy 375.415348 -267.156753)
			(xy 375.384822 -267.114737) (xy 375.361244 -267.068463) (xy 375.345196 -267.01907) (xy 375.337071 -266.967775)
			(xy 375.057161 -266.967775) (xy 375.049036 -267.01907) (xy 375.032988 -267.068463) (xy 375.00941 -267.114737)
			(xy 374.978884 -267.156753) (xy 374.942161 -267.193476) (xy 374.900145 -267.224002) (xy 374.853871 -267.24758)
			(xy 374.804478 -267.263628) (xy 374.753183 -267.271753) (xy 374.701249 -267.271753) (xy 374.649954 -267.263628)
			(xy 374.600561 -267.24758) (xy 374.554287 -267.224002) (xy 374.512271 -267.193476) (xy 374.475548 -267.156753)
			(xy 374.445022 -267.114737) (xy 374.421444 -267.068463) (xy 374.405396 -267.01907) (xy 374.397271 -266.967775)
			(xy 374.117107 -266.967775) (xy 374.108982 -267.01907) (xy 374.092934 -267.068463) (xy 374.069356 -267.114737)
			(xy 374.03883 -267.156753) (xy 374.002107 -267.193476) (xy 373.960091 -267.224002) (xy 373.913817 -267.24758)
			(xy 373.864424 -267.263628) (xy 373.813129 -267.271753) (xy 373.761195 -267.271753) (xy 373.7099 -267.263628)
			(xy 373.660507 -267.24758) (xy 373.614233 -267.224002) (xy 373.572217 -267.193476) (xy 373.535494 -267.156753)
			(xy 373.504968 -267.114737) (xy 373.48139 -267.068463) (xy 373.465342 -267.01907) (xy 373.457217 -266.967775)
			(xy 373.177561 -266.967775) (xy 373.169436 -267.01907) (xy 373.153388 -267.068463) (xy 373.12981 -267.114737)
			(xy 373.099284 -267.156753) (xy 373.062561 -267.193476) (xy 373.020545 -267.224002) (xy 372.974271 -267.24758)
			(xy 372.924878 -267.263628) (xy 372.873583 -267.271753) (xy 372.821649 -267.271753) (xy 372.770354 -267.263628)
			(xy 372.720961 -267.24758) (xy 372.674687 -267.224002) (xy 372.632671 -267.193476) (xy 372.595948 -267.156753)
			(xy 372.565422 -267.114737) (xy 372.541844 -267.068463) (xy 372.525796 -267.01907) (xy 372.517671 -266.967775)
			(xy 372.237752 -266.967775) (xy 372.229629 -267.019062) (xy 372.213581 -267.068454) (xy 372.190004 -267.114728)
			(xy 372.159479 -267.156744) (xy 372.122756 -267.193468) (xy 372.080742 -267.223995) (xy 372.034469 -267.247575)
			(xy 371.985077 -267.263625) (xy 371.933783 -267.271752) (xy 371.907816 -267.272262) (xy 371.891382 -267.27205)
			(xy 371.858682 -267.268739) (xy 371.842538 -267.265658) (xy 371.827713 -267.263237) (xy 371.797827 -267.2661)
			(xy 371.770067 -267.27753) (xy 371.746831 -267.296541) (xy 371.730129 -267.321488) (xy 371.721404 -267.350215)
			(xy 371.720872 -267.365226) (xy 371.720872 -267.585444) (xy 371.727222 -267.59662) (xy 371.740067 -267.621183)
			(xy 371.758306 -267.673521) (xy 371.767556 -267.728168) (xy 371.76756 -267.781845) (xy 372.047517 -267.781845)
			(xy 372.047517 -267.729911) (xy 372.055642 -267.678616) (xy 372.07169 -267.629223) (xy 372.095268 -267.582949)
			(xy 372.125794 -267.540933) (xy 372.162517 -267.50421) (xy 372.204533 -267.473684) (xy 372.250807 -267.450106)
			(xy 372.3002 -267.434058) (xy 372.351495 -267.425933) (xy 372.403429 -267.425933) (xy 372.454724 -267.434058)
			(xy 372.504117 -267.450106) (xy 372.550391 -267.473684) (xy 372.592407 -267.50421) (xy 372.62913 -267.540933)
			(xy 372.659656 -267.582949) (xy 372.683234 -267.629223) (xy 372.699282 -267.678616) (xy 372.707407 -267.729911)
			(xy 372.707916 -267.755878) (xy 372.707407 -267.781845) (xy 372.987317 -267.781845) (xy 372.987317 -267.729911)
			(xy 372.995442 -267.678616) (xy 373.01149 -267.629223) (xy 373.035068 -267.582949) (xy 373.065594 -267.540933)
			(xy 373.102317 -267.50421) (xy 373.144333 -267.473684) (xy 373.190607 -267.450106) (xy 373.24 -267.434058)
			(xy 373.291295 -267.425933) (xy 373.343229 -267.425933) (xy 373.394524 -267.434058) (xy 373.443917 -267.450106)
			(xy 373.490191 -267.473684) (xy 373.532207 -267.50421) (xy 373.56893 -267.540933) (xy 373.599456 -267.582949)
			(xy 373.623034 -267.629223) (xy 373.639082 -267.678616) (xy 373.647207 -267.729911) (xy 373.647716 -267.755878)
			(xy 373.647207 -267.781845) (xy 373.927117 -267.781845) (xy 373.927117 -267.729911) (xy 373.935242 -267.678616)
			(xy 373.95129 -267.629223) (xy 373.974868 -267.582949) (xy 374.005394 -267.540933) (xy 374.042117 -267.50421)
			(xy 374.084133 -267.473684) (xy 374.130407 -267.450106) (xy 374.1798 -267.434058) (xy 374.231095 -267.425933)
			(xy 374.283029 -267.425933) (xy 374.334324 -267.434058) (xy 374.383717 -267.450106) (xy 374.429991 -267.473684)
			(xy 374.472007 -267.50421) (xy 374.50873 -267.540933) (xy 374.539256 -267.582949) (xy 374.562834 -267.629223)
			(xy 374.578882 -267.678616) (xy 374.587007 -267.729911) (xy 374.587516 -267.755878) (xy 374.587007 -267.781845)
			(xy 374.866917 -267.781845) (xy 374.866917 -267.729911) (xy 374.875042 -267.678616) (xy 374.89109 -267.629223)
			(xy 374.914668 -267.582949) (xy 374.945194 -267.540933) (xy 374.981917 -267.50421) (xy 375.023933 -267.473684)
			(xy 375.070207 -267.450106) (xy 375.1196 -267.434058) (xy 375.170895 -267.425933) (xy 375.222829 -267.425933)
			(xy 375.274124 -267.434058) (xy 375.323517 -267.450106) (xy 375.369791 -267.473684) (xy 375.411807 -267.50421)
			(xy 375.44853 -267.540933) (xy 375.479056 -267.582949) (xy 375.502634 -267.629223) (xy 375.518682 -267.678616)
			(xy 375.526807 -267.729911) (xy 375.527316 -267.755878) (xy 375.526807 -267.781845) (xy 375.806717 -267.781845)
			(xy 375.806717 -267.729911) (xy 375.814842 -267.678616) (xy 375.83089 -267.629223) (xy 375.854468 -267.582949)
			(xy 375.884994 -267.540933) (xy 375.921717 -267.50421) (xy 375.963733 -267.473684) (xy 376.010007 -267.450106)
			(xy 376.0594 -267.434058) (xy 376.110695 -267.425933) (xy 376.162629 -267.425933) (xy 376.213924 -267.434058)
			(xy 376.263317 -267.450106) (xy 376.309591 -267.473684) (xy 376.351607 -267.50421) (xy 376.38833 -267.540933)
			(xy 376.418856 -267.582949) (xy 376.442434 -267.629223) (xy 376.458482 -267.678616) (xy 376.466607 -267.729911)
			(xy 376.467116 -267.755878) (xy 376.466607 -267.781845) (xy 376.746517 -267.781845) (xy 376.746517 -267.729911)
			(xy 376.754642 -267.678616) (xy 376.77069 -267.629223) (xy 376.794268 -267.582949) (xy 376.824794 -267.540933)
			(xy 376.861517 -267.50421) (xy 376.903533 -267.473684) (xy 376.949807 -267.450106) (xy 376.9992 -267.434058)
			(xy 377.050495 -267.425933) (xy 377.102429 -267.425933) (xy 377.153724 -267.434058) (xy 377.203117 -267.450106)
			(xy 377.249391 -267.473684) (xy 377.291407 -267.50421) (xy 377.32813 -267.540933) (xy 377.358656 -267.582949)
			(xy 377.382234 -267.629223) (xy 377.398282 -267.678616) (xy 377.406407 -267.729911) (xy 377.406916 -267.755878)
			(xy 377.406407 -267.781845) (xy 377.686317 -267.781845) (xy 377.686317 -267.729911) (xy 377.694442 -267.678616)
			(xy 377.71049 -267.629223) (xy 377.734068 -267.582949) (xy 377.764594 -267.540933) (xy 377.801317 -267.50421)
			(xy 377.843333 -267.473684) (xy 377.889607 -267.450106) (xy 377.939 -267.434058) (xy 377.990295 -267.425933)
			(xy 378.042229 -267.425933) (xy 378.093524 -267.434058) (xy 378.142917 -267.450106) (xy 378.189191 -267.473684)
			(xy 378.231207 -267.50421) (xy 378.26793 -267.540933) (xy 378.298456 -267.582949) (xy 378.322034 -267.629223)
			(xy 378.338082 -267.678616) (xy 378.346207 -267.729911) (xy 378.346716 -267.755878) (xy 378.346207 -267.781845)
			(xy 378.626117 -267.781845) (xy 378.626117 -267.729911) (xy 378.634242 -267.678616) (xy 378.65029 -267.629223)
			(xy 378.673868 -267.582949) (xy 378.704394 -267.540933) (xy 378.741117 -267.50421) (xy 378.783133 -267.473684)
			(xy 378.829407 -267.450106) (xy 378.8788 -267.434058) (xy 378.930095 -267.425933) (xy 378.982029 -267.425933)
			(xy 379.033324 -267.434058) (xy 379.082717 -267.450106) (xy 379.128991 -267.473684) (xy 379.171007 -267.50421)
			(xy 379.20773 -267.540933) (xy 379.238256 -267.582949) (xy 379.261834 -267.629223) (xy 379.277882 -267.678616)
			(xy 379.286007 -267.729911) (xy 379.286516 -267.755878) (xy 379.286007 -267.781845) (xy 379.277882 -267.83314)
			(xy 379.261834 -267.882533) (xy 379.238256 -267.928807) (xy 379.20773 -267.970823) (xy 379.171007 -268.007546)
			(xy 379.128991 -268.038072) (xy 379.082717 -268.06165) (xy 379.033324 -268.077698) (xy 378.982029 -268.085823)
			(xy 378.930095 -268.085823) (xy 378.8788 -268.077698) (xy 378.829407 -268.06165) (xy 378.783133 -268.038072)
			(xy 378.741117 -268.007546) (xy 378.704394 -267.970823) (xy 378.673868 -267.928807) (xy 378.65029 -267.882533)
			(xy 378.634242 -267.83314) (xy 378.626117 -267.781845) (xy 378.346207 -267.781845) (xy 378.338082 -267.83314)
			(xy 378.322034 -267.882533) (xy 378.298456 -267.928807) (xy 378.26793 -267.970823) (xy 378.231207 -268.007546)
			(xy 378.189191 -268.038072) (xy 378.142917 -268.06165) (xy 378.093524 -268.077698) (xy 378.042229 -268.085823)
			(xy 377.990295 -268.085823) (xy 377.939 -268.077698) (xy 377.889607 -268.06165) (xy 377.843333 -268.038072)
			(xy 377.801317 -268.007546) (xy 377.764594 -267.970823) (xy 377.734068 -267.928807) (xy 377.71049 -267.882533)
			(xy 377.694442 -267.83314) (xy 377.686317 -267.781845) (xy 377.406407 -267.781845) (xy 377.398282 -267.83314)
			(xy 377.382234 -267.882533) (xy 377.358656 -267.928807) (xy 377.32813 -267.970823) (xy 377.291407 -268.007546)
			(xy 377.249391 -268.038072) (xy 377.203117 -268.06165) (xy 377.153724 -268.077698) (xy 377.102429 -268.085823)
			(xy 377.050495 -268.085823) (xy 376.9992 -268.077698) (xy 376.949807 -268.06165) (xy 376.903533 -268.038072)
			(xy 376.861517 -268.007546) (xy 376.824794 -267.970823) (xy 376.794268 -267.928807) (xy 376.77069 -267.882533)
			(xy 376.754642 -267.83314) (xy 376.746517 -267.781845) (xy 376.466607 -267.781845) (xy 376.458482 -267.83314)
			(xy 376.442434 -267.882533) (xy 376.418856 -267.928807) (xy 376.38833 -267.970823) (xy 376.351607 -268.007546)
			(xy 376.309591 -268.038072) (xy 376.263317 -268.06165) (xy 376.213924 -268.077698) (xy 376.162629 -268.085823)
			(xy 376.110695 -268.085823) (xy 376.0594 -268.077698) (xy 376.010007 -268.06165) (xy 375.963733 -268.038072)
			(xy 375.921717 -268.007546) (xy 375.884994 -267.970823) (xy 375.854468 -267.928807) (xy 375.83089 -267.882533)
			(xy 375.814842 -267.83314) (xy 375.806717 -267.781845) (xy 375.526807 -267.781845) (xy 375.518682 -267.83314)
			(xy 375.502634 -267.882533) (xy 375.479056 -267.928807) (xy 375.44853 -267.970823) (xy 375.411807 -268.007546)
			(xy 375.369791 -268.038072) (xy 375.323517 -268.06165) (xy 375.274124 -268.077698) (xy 375.222829 -268.085823)
			(xy 375.170895 -268.085823) (xy 375.1196 -268.077698) (xy 375.070207 -268.06165) (xy 375.023933 -268.038072)
			(xy 374.981917 -268.007546) (xy 374.945194 -267.970823) (xy 374.914668 -267.928807) (xy 374.89109 -267.882533)
			(xy 374.875042 -267.83314) (xy 374.866917 -267.781845) (xy 374.587007 -267.781845) (xy 374.578882 -267.83314)
			(xy 374.562834 -267.882533) (xy 374.539256 -267.928807) (xy 374.50873 -267.970823) (xy 374.472007 -268.007546)
			(xy 374.429991 -268.038072) (xy 374.383717 -268.06165) (xy 374.334324 -268.077698) (xy 374.283029 -268.085823)
			(xy 374.231095 -268.085823) (xy 374.1798 -268.077698) (xy 374.130407 -268.06165) (xy 374.084133 -268.038072)
			(xy 374.042117 -268.007546) (xy 374.005394 -267.970823) (xy 373.974868 -267.928807) (xy 373.95129 -267.882533)
			(xy 373.935242 -267.83314) (xy 373.927117 -267.781845) (xy 373.647207 -267.781845) (xy 373.639082 -267.83314)
			(xy 373.623034 -267.882533) (xy 373.599456 -267.928807) (xy 373.56893 -267.970823) (xy 373.532207 -268.007546)
			(xy 373.490191 -268.038072) (xy 373.443917 -268.06165) (xy 373.394524 -268.077698) (xy 373.343229 -268.085823)
			(xy 373.291295 -268.085823) (xy 373.24 -268.077698) (xy 373.190607 -268.06165) (xy 373.144333 -268.038072)
			(xy 373.102317 -268.007546) (xy 373.065594 -267.970823) (xy 373.035068 -267.928807) (xy 373.01149 -267.882533)
			(xy 372.995442 -267.83314) (xy 372.987317 -267.781845) (xy 372.707407 -267.781845) (xy 372.699282 -267.83314)
			(xy 372.683234 -267.882533) (xy 372.659656 -267.928807) (xy 372.62913 -267.970823) (xy 372.592407 -268.007546)
			(xy 372.550391 -268.038072) (xy 372.504117 -268.06165) (xy 372.454724 -268.077698) (xy 372.403429 -268.085823)
			(xy 372.351495 -268.085823) (xy 372.3002 -268.077698) (xy 372.250807 -268.06165) (xy 372.204533 -268.038072)
			(xy 372.162517 -268.007546) (xy 372.125794 -267.970823) (xy 372.095268 -267.928807) (xy 372.07169 -267.882533)
			(xy 372.055642 -267.83314) (xy 372.047517 -267.781845) (xy 371.76756 -267.781845) (xy 371.76756 -267.783593)
			(xy 371.758315 -267.838242) (xy 371.740082 -267.890582) (xy 371.727222 -267.915136) (xy 371.720872 -267.926312)
			(xy 371.720872 -268.146276) (xy 371.721406 -268.161285) (xy 371.730148 -268.190002) (xy 371.746855 -268.214941)
			(xy 371.770087 -268.233951) (xy 371.797839 -268.245393) (xy 371.827718 -268.24828) (xy 371.842538 -268.245844)
			(xy 371.858684 -268.24278) (xy 371.891383 -268.23947) (xy 371.907816 -268.23924) (xy 371.933782 -268.239762)
			(xy 371.985074 -268.247889) (xy 372.034464 -268.263938) (xy 372.080734 -268.287517) (xy 372.122747 -268.318043)
			(xy 372.159468 -268.354765) (xy 372.189992 -268.396779) (xy 372.213568 -268.443051) (xy 372.229615 -268.492441)
			(xy 372.237739 -268.543734) (xy 372.237739 -268.595661) (xy 372.517671 -268.595661) (xy 372.517671 -268.543727)
			(xy 372.525796 -268.492432) (xy 372.541844 -268.443039) (xy 372.565422 -268.396765) (xy 372.595948 -268.354749)
			(xy 372.632671 -268.318026) (xy 372.674687 -268.2875) (xy 372.720961 -268.263922) (xy 372.770354 -268.247874)
			(xy 372.821649 -268.239749) (xy 372.873583 -268.239749) (xy 372.924878 -268.247874) (xy 372.974271 -268.263922)
			(xy 373.020545 -268.2875) (xy 373.062561 -268.318026) (xy 373.099284 -268.354749) (xy 373.12981 -268.396765)
			(xy 373.153388 -268.443039) (xy 373.169436 -268.492432) (xy 373.177561 -268.543727) (xy 373.17807 -268.569694)
			(xy 373.177561 -268.595661) (xy 373.457471 -268.595661) (xy 373.457471 -268.543727) (xy 373.465596 -268.492432)
			(xy 373.481644 -268.443039) (xy 373.505222 -268.396765) (xy 373.535748 -268.354749) (xy 373.572471 -268.318026)
			(xy 373.614487 -268.2875) (xy 373.660761 -268.263922) (xy 373.710154 -268.247874) (xy 373.761449 -268.239749)
			(xy 373.813383 -268.239749) (xy 373.864678 -268.247874) (xy 373.914071 -268.263922) (xy 373.960345 -268.2875)
			(xy 374.002361 -268.318026) (xy 374.039084 -268.354749) (xy 374.06961 -268.396765) (xy 374.093188 -268.443039)
			(xy 374.109236 -268.492432) (xy 374.117361 -268.543727) (xy 374.11787 -268.569694) (xy 374.117361 -268.595661)
			(xy 374.397271 -268.595661) (xy 374.397271 -268.543727) (xy 374.405396 -268.492432) (xy 374.421444 -268.443039)
			(xy 374.445022 -268.396765) (xy 374.475548 -268.354749) (xy 374.512271 -268.318026) (xy 374.554287 -268.2875)
			(xy 374.600561 -268.263922) (xy 374.649954 -268.247874) (xy 374.701249 -268.239749) (xy 374.753183 -268.239749)
			(xy 374.804478 -268.247874) (xy 374.853871 -268.263922) (xy 374.900145 -268.2875) (xy 374.942161 -268.318026)
			(xy 374.978884 -268.354749) (xy 375.00941 -268.396765) (xy 375.032988 -268.443039) (xy 375.049036 -268.492432)
			(xy 375.057161 -268.543727) (xy 375.05767 -268.569694) (xy 375.057161 -268.595661) (xy 375.337071 -268.595661)
			(xy 375.337071 -268.543727) (xy 375.345196 -268.492432) (xy 375.361244 -268.443039) (xy 375.384822 -268.396765)
			(xy 375.415348 -268.354749) (xy 375.452071 -268.318026) (xy 375.494087 -268.2875) (xy 375.540361 -268.263922)
			(xy 375.589754 -268.247874) (xy 375.641049 -268.239749) (xy 375.692983 -268.239749) (xy 375.744278 -268.247874)
			(xy 375.793671 -268.263922) (xy 375.839945 -268.2875) (xy 375.881961 -268.318026) (xy 375.918684 -268.354749)
			(xy 375.94921 -268.396765) (xy 375.972788 -268.443039) (xy 375.988836 -268.492432) (xy 375.996961 -268.543727)
			(xy 375.99747 -268.569694) (xy 375.996961 -268.595661) (xy 376.276871 -268.595661) (xy 376.276871 -268.543727)
			(xy 376.284996 -268.492432) (xy 376.301044 -268.443039) (xy 376.324622 -268.396765) (xy 376.355148 -268.354749)
			(xy 376.391871 -268.318026) (xy 376.433887 -268.2875) (xy 376.480161 -268.263922) (xy 376.529554 -268.247874)
			(xy 376.580849 -268.239749) (xy 376.632783 -268.239749) (xy 376.684078 -268.247874) (xy 376.733471 -268.263922)
			(xy 376.779745 -268.2875) (xy 376.821761 -268.318026) (xy 376.858484 -268.354749) (xy 376.88901 -268.396765)
			(xy 376.912588 -268.443039) (xy 376.928636 -268.492432) (xy 376.936761 -268.543727) (xy 376.93727 -268.569694)
			(xy 376.936761 -268.595661) (xy 377.216671 -268.595661) (xy 377.216671 -268.543727) (xy 377.224796 -268.492432)
			(xy 377.240844 -268.443039) (xy 377.264422 -268.396765) (xy 377.294948 -268.354749) (xy 377.331671 -268.318026)
			(xy 377.373687 -268.2875) (xy 377.419961 -268.263922) (xy 377.469354 -268.247874) (xy 377.520649 -268.239749)
			(xy 377.572583 -268.239749) (xy 377.623878 -268.247874) (xy 377.673271 -268.263922) (xy 377.719545 -268.2875)
			(xy 377.761561 -268.318026) (xy 377.798284 -268.354749) (xy 377.82881 -268.396765) (xy 377.852388 -268.443039)
			(xy 377.868436 -268.492432) (xy 377.876561 -268.543727) (xy 377.87707 -268.569694) (xy 377.876561 -268.595661)
			(xy 378.156471 -268.595661) (xy 378.156471 -268.543727) (xy 378.164596 -268.492432) (xy 378.180644 -268.443039)
			(xy 378.204222 -268.396765) (xy 378.234748 -268.354749) (xy 378.271471 -268.318026) (xy 378.313487 -268.2875)
			(xy 378.359761 -268.263922) (xy 378.409154 -268.247874) (xy 378.460449 -268.239749) (xy 378.512383 -268.239749)
			(xy 378.563678 -268.247874) (xy 378.613071 -268.263922) (xy 378.659345 -268.2875) (xy 378.701361 -268.318026)
			(xy 378.738084 -268.354749) (xy 378.76861 -268.396765) (xy 378.792188 -268.443039) (xy 378.808236 -268.492432)
			(xy 378.816361 -268.543727) (xy 378.81687 -268.569694) (xy 378.816361 -268.595661) (xy 378.808236 -268.646956)
			(xy 378.792188 -268.696349) (xy 378.76861 -268.742623) (xy 378.738084 -268.784639) (xy 378.701361 -268.821362)
			(xy 378.659345 -268.851888) (xy 378.613071 -268.875466) (xy 378.563678 -268.891514) (xy 378.512383 -268.899639)
			(xy 378.460449 -268.899639) (xy 378.409154 -268.891514) (xy 378.359761 -268.875466) (xy 378.313487 -268.851888)
			(xy 378.271471 -268.821362) (xy 378.234748 -268.784639) (xy 378.204222 -268.742623) (xy 378.180644 -268.696349)
			(xy 378.164596 -268.646956) (xy 378.156471 -268.595661) (xy 377.876561 -268.595661) (xy 377.868436 -268.646956)
			(xy 377.852388 -268.696349) (xy 377.82881 -268.742623) (xy 377.798284 -268.784639) (xy 377.761561 -268.821362)
			(xy 377.719545 -268.851888) (xy 377.673271 -268.875466) (xy 377.623878 -268.891514) (xy 377.572583 -268.899639)
			(xy 377.520649 -268.899639) (xy 377.469354 -268.891514) (xy 377.419961 -268.875466) (xy 377.373687 -268.851888)
			(xy 377.331671 -268.821362) (xy 377.294948 -268.784639) (xy 377.264422 -268.742623) (xy 377.240844 -268.696349)
			(xy 377.224796 -268.646956) (xy 377.216671 -268.595661) (xy 376.936761 -268.595661) (xy 376.928636 -268.646956)
			(xy 376.912588 -268.696349) (xy 376.88901 -268.742623) (xy 376.858484 -268.784639) (xy 376.821761 -268.821362)
			(xy 376.779745 -268.851888) (xy 376.733471 -268.875466) (xy 376.684078 -268.891514) (xy 376.632783 -268.899639)
			(xy 376.580849 -268.899639) (xy 376.529554 -268.891514) (xy 376.480161 -268.875466) (xy 376.433887 -268.851888)
			(xy 376.391871 -268.821362) (xy 376.355148 -268.784639) (xy 376.324622 -268.742623) (xy 376.301044 -268.696349)
			(xy 376.284996 -268.646956) (xy 376.276871 -268.595661) (xy 375.996961 -268.595661) (xy 375.988836 -268.646956)
			(xy 375.972788 -268.696349) (xy 375.94921 -268.742623) (xy 375.918684 -268.784639) (xy 375.881961 -268.821362)
			(xy 375.839945 -268.851888) (xy 375.793671 -268.875466) (xy 375.744278 -268.891514) (xy 375.692983 -268.899639)
			(xy 375.641049 -268.899639) (xy 375.589754 -268.891514) (xy 375.540361 -268.875466) (xy 375.494087 -268.851888)
			(xy 375.452071 -268.821362) (xy 375.415348 -268.784639) (xy 375.384822 -268.742623) (xy 375.361244 -268.696349)
			(xy 375.345196 -268.646956) (xy 375.337071 -268.595661) (xy 375.057161 -268.595661) (xy 375.049036 -268.646956)
			(xy 375.032988 -268.696349) (xy 375.00941 -268.742623) (xy 374.978884 -268.784639) (xy 374.942161 -268.821362)
			(xy 374.900145 -268.851888) (xy 374.853871 -268.875466) (xy 374.804478 -268.891514) (xy 374.753183 -268.899639)
			(xy 374.701249 -268.899639) (xy 374.649954 -268.891514) (xy 374.600561 -268.875466) (xy 374.554287 -268.851888)
			(xy 374.512271 -268.821362) (xy 374.475548 -268.784639) (xy 374.445022 -268.742623) (xy 374.421444 -268.696349)
			(xy 374.405396 -268.646956) (xy 374.397271 -268.595661) (xy 374.117361 -268.595661) (xy 374.109236 -268.646956)
			(xy 374.093188 -268.696349) (xy 374.06961 -268.742623) (xy 374.039084 -268.784639) (xy 374.002361 -268.821362)
			(xy 373.960345 -268.851888) (xy 373.914071 -268.875466) (xy 373.864678 -268.891514) (xy 373.813383 -268.899639)
			(xy 373.761449 -268.899639) (xy 373.710154 -268.891514) (xy 373.660761 -268.875466) (xy 373.614487 -268.851888)
			(xy 373.572471 -268.821362) (xy 373.535748 -268.784639) (xy 373.505222 -268.742623) (xy 373.481644 -268.696349)
			(xy 373.465596 -268.646956) (xy 373.457471 -268.595661) (xy 373.177561 -268.595661) (xy 373.169436 -268.646956)
			(xy 373.153388 -268.696349) (xy 373.12981 -268.742623) (xy 373.099284 -268.784639) (xy 373.062561 -268.821362)
			(xy 373.020545 -268.851888) (xy 372.974271 -268.875466) (xy 372.924878 -268.891514) (xy 372.873583 -268.899639)
			(xy 372.821649 -268.899639) (xy 372.770354 -268.891514) (xy 372.720961 -268.875466) (xy 372.674687 -268.851888)
			(xy 372.632671 -268.821362) (xy 372.595948 -268.784639) (xy 372.565422 -268.742623) (xy 372.541844 -268.696349)
			(xy 372.525796 -268.646956) (xy 372.517671 -268.595661) (xy 372.237739 -268.595661) (xy 372.237739 -268.595666)
			(xy 372.229615 -268.646959) (xy 372.213568 -268.696349) (xy 372.189992 -268.742621) (xy 372.159468 -268.784635)
			(xy 372.122747 -268.821357) (xy 372.080734 -268.851883) (xy 372.034464 -268.875462) (xy 371.985074 -268.891511)
			(xy 371.933782 -268.899638) (xy 371.907816 -268.900148) (xy 371.891382 -268.899936) (xy 371.858682 -268.896625)
			(xy 371.842538 -268.893544) (xy 371.827711 -268.891137) (xy 371.797829 -268.893999) (xy 371.77007 -268.905428)
			(xy 371.746836 -268.924436) (xy 371.730133 -268.94938) (xy 371.721406 -268.978102) (xy 371.720872 -268.993112)
			(xy 371.720872 -269.213076) (xy 371.727222 -269.224252) (xy 371.740092 -269.248802) (xy 371.758328 -269.301144)
			(xy 371.767574 -269.355795) (xy 371.767573 -269.409477) (xy 372.047517 -269.409477) (xy 372.047517 -269.357543)
			(xy 372.055642 -269.306248) (xy 372.07169 -269.256855) (xy 372.095268 -269.210581) (xy 372.125794 -269.168565)
			(xy 372.162517 -269.131842) (xy 372.204533 -269.101316) (xy 372.250807 -269.077738) (xy 372.3002 -269.06169)
			(xy 372.351495 -269.053565) (xy 372.403429 -269.053565) (xy 372.454724 -269.06169) (xy 372.504117 -269.077738)
			(xy 372.550391 -269.101316) (xy 372.592407 -269.131842) (xy 372.62913 -269.168565) (xy 372.659656 -269.210581)
			(xy 372.683234 -269.256855) (xy 372.699282 -269.306248) (xy 372.707407 -269.357543) (xy 372.707916 -269.38351)
			(xy 372.707407 -269.409477) (xy 372.987317 -269.409477) (xy 372.987317 -269.357543) (xy 372.995442 -269.306248)
			(xy 373.01149 -269.256855) (xy 373.035068 -269.210581) (xy 373.065594 -269.168565) (xy 373.102317 -269.131842)
			(xy 373.144333 -269.101316) (xy 373.190607 -269.077738) (xy 373.24 -269.06169) (xy 373.291295 -269.053565)
			(xy 373.343229 -269.053565) (xy 373.394524 -269.06169) (xy 373.443917 -269.077738) (xy 373.490191 -269.101316)
			(xy 373.532207 -269.131842) (xy 373.56893 -269.168565) (xy 373.599456 -269.210581) (xy 373.623034 -269.256855)
			(xy 373.639082 -269.306248) (xy 373.647207 -269.357543) (xy 373.647716 -269.38351) (xy 373.647207 -269.409477)
			(xy 373.927117 -269.409477) (xy 373.927117 -269.357543) (xy 373.935242 -269.306248) (xy 373.95129 -269.256855)
			(xy 373.974868 -269.210581) (xy 374.005394 -269.168565) (xy 374.042117 -269.131842) (xy 374.084133 -269.101316)
			(xy 374.130407 -269.077738) (xy 374.1798 -269.06169) (xy 374.231095 -269.053565) (xy 374.283029 -269.053565)
			(xy 374.334324 -269.06169) (xy 374.383717 -269.077738) (xy 374.429991 -269.101316) (xy 374.472007 -269.131842)
			(xy 374.50873 -269.168565) (xy 374.539256 -269.210581) (xy 374.562834 -269.256855) (xy 374.578882 -269.306248)
			(xy 374.587007 -269.357543) (xy 374.587516 -269.38351) (xy 374.587007 -269.409477) (xy 374.866917 -269.409477)
			(xy 374.866917 -269.357543) (xy 374.875042 -269.306248) (xy 374.89109 -269.256855) (xy 374.914668 -269.210581)
			(xy 374.945194 -269.168565) (xy 374.981917 -269.131842) (xy 375.023933 -269.101316) (xy 375.070207 -269.077738)
			(xy 375.1196 -269.06169) (xy 375.170895 -269.053565) (xy 375.222829 -269.053565) (xy 375.274124 -269.06169)
			(xy 375.323517 -269.077738) (xy 375.369791 -269.101316) (xy 375.411807 -269.131842) (xy 375.44853 -269.168565)
			(xy 375.479056 -269.210581) (xy 375.502634 -269.256855) (xy 375.518682 -269.306248) (xy 375.526807 -269.357543)
			(xy 375.527316 -269.38351) (xy 375.526807 -269.409477) (xy 375.806717 -269.409477) (xy 375.806717 -269.357543)
			(xy 375.814842 -269.306248) (xy 375.83089 -269.256855) (xy 375.854468 -269.210581) (xy 375.884994 -269.168565)
			(xy 375.921717 -269.131842) (xy 375.963733 -269.101316) (xy 376.010007 -269.077738) (xy 376.0594 -269.06169)
			(xy 376.110695 -269.053565) (xy 376.162629 -269.053565) (xy 376.213924 -269.06169) (xy 376.263317 -269.077738)
			(xy 376.309591 -269.101316) (xy 376.351607 -269.131842) (xy 376.38833 -269.168565) (xy 376.418856 -269.210581)
			(xy 376.442434 -269.256855) (xy 376.458482 -269.306248) (xy 376.466607 -269.357543) (xy 376.467116 -269.38351)
			(xy 376.466607 -269.409477) (xy 376.746517 -269.409477) (xy 376.746517 -269.357543) (xy 376.754642 -269.306248)
			(xy 376.77069 -269.256855) (xy 376.794268 -269.210581) (xy 376.824794 -269.168565) (xy 376.861517 -269.131842)
			(xy 376.903533 -269.101316) (xy 376.949807 -269.077738) (xy 376.9992 -269.06169) (xy 377.050495 -269.053565)
			(xy 377.102429 -269.053565) (xy 377.153724 -269.06169) (xy 377.203117 -269.077738) (xy 377.249391 -269.101316)
			(xy 377.291407 -269.131842) (xy 377.32813 -269.168565) (xy 377.358656 -269.210581) (xy 377.382234 -269.256855)
			(xy 377.398282 -269.306248) (xy 377.406407 -269.357543) (xy 377.406916 -269.38351) (xy 377.406407 -269.409477)
			(xy 377.686317 -269.409477) (xy 377.686317 -269.357543) (xy 377.694442 -269.306248) (xy 377.71049 -269.256855)
			(xy 377.734068 -269.210581) (xy 377.764594 -269.168565) (xy 377.801317 -269.131842) (xy 377.843333 -269.101316)
			(xy 377.889607 -269.077738) (xy 377.939 -269.06169) (xy 377.990295 -269.053565) (xy 378.042229 -269.053565)
			(xy 378.093524 -269.06169) (xy 378.142917 -269.077738) (xy 378.189191 -269.101316) (xy 378.231207 -269.131842)
			(xy 378.26793 -269.168565) (xy 378.298456 -269.210581) (xy 378.322034 -269.256855) (xy 378.338082 -269.306248)
			(xy 378.346207 -269.357543) (xy 378.346716 -269.38351) (xy 378.346207 -269.409477) (xy 378.626117 -269.409477)
			(xy 378.626117 -269.357543) (xy 378.634242 -269.306248) (xy 378.65029 -269.256855) (xy 378.673868 -269.210581)
			(xy 378.704394 -269.168565) (xy 378.741117 -269.131842) (xy 378.783133 -269.101316) (xy 378.829407 -269.077738)
			(xy 378.8788 -269.06169) (xy 378.930095 -269.053565) (xy 378.982029 -269.053565) (xy 379.033324 -269.06169)
			(xy 379.082717 -269.077738) (xy 379.128991 -269.101316) (xy 379.171007 -269.131842) (xy 379.20773 -269.168565)
			(xy 379.238256 -269.210581) (xy 379.261834 -269.256855) (xy 379.277882 -269.306248) (xy 379.286007 -269.357543)
			(xy 379.286516 -269.38351) (xy 379.286007 -269.409477) (xy 379.277882 -269.460772) (xy 379.261834 -269.510165)
			(xy 379.238256 -269.556439) (xy 379.20773 -269.598455) (xy 379.171007 -269.635178) (xy 379.128991 -269.665704)
			(xy 379.082717 -269.689282) (xy 379.033324 -269.70533) (xy 378.982029 -269.713455) (xy 378.930095 -269.713455)
			(xy 378.8788 -269.70533) (xy 378.829407 -269.689282) (xy 378.783133 -269.665704) (xy 378.741117 -269.635178)
			(xy 378.704394 -269.598455) (xy 378.673868 -269.556439) (xy 378.65029 -269.510165) (xy 378.634242 -269.460772)
			(xy 378.626117 -269.409477) (xy 378.346207 -269.409477) (xy 378.338082 -269.460772) (xy 378.322034 -269.510165)
			(xy 378.298456 -269.556439) (xy 378.26793 -269.598455) (xy 378.231207 -269.635178) (xy 378.189191 -269.665704)
			(xy 378.142917 -269.689282) (xy 378.093524 -269.70533) (xy 378.042229 -269.713455) (xy 377.990295 -269.713455)
			(xy 377.939 -269.70533) (xy 377.889607 -269.689282) (xy 377.843333 -269.665704) (xy 377.801317 -269.635178)
			(xy 377.764594 -269.598455) (xy 377.734068 -269.556439) (xy 377.71049 -269.510165) (xy 377.694442 -269.460772)
			(xy 377.686317 -269.409477) (xy 377.406407 -269.409477) (xy 377.398282 -269.460772) (xy 377.382234 -269.510165)
			(xy 377.358656 -269.556439) (xy 377.32813 -269.598455) (xy 377.291407 -269.635178) (xy 377.249391 -269.665704)
			(xy 377.203117 -269.689282) (xy 377.153724 -269.70533) (xy 377.102429 -269.713455) (xy 377.050495 -269.713455)
			(xy 376.9992 -269.70533) (xy 376.949807 -269.689282) (xy 376.903533 -269.665704) (xy 376.861517 -269.635178)
			(xy 376.824794 -269.598455) (xy 376.794268 -269.556439) (xy 376.77069 -269.510165) (xy 376.754642 -269.460772)
			(xy 376.746517 -269.409477) (xy 376.466607 -269.409477) (xy 376.458482 -269.460772) (xy 376.442434 -269.510165)
			(xy 376.418856 -269.556439) (xy 376.38833 -269.598455) (xy 376.351607 -269.635178) (xy 376.309591 -269.665704)
			(xy 376.263317 -269.689282) (xy 376.213924 -269.70533) (xy 376.162629 -269.713455) (xy 376.110695 -269.713455)
			(xy 376.0594 -269.70533) (xy 376.010007 -269.689282) (xy 375.963733 -269.665704) (xy 375.921717 -269.635178)
			(xy 375.884994 -269.598455) (xy 375.854468 -269.556439) (xy 375.83089 -269.510165) (xy 375.814842 -269.460772)
			(xy 375.806717 -269.409477) (xy 375.526807 -269.409477) (xy 375.518682 -269.460772) (xy 375.502634 -269.510165)
			(xy 375.479056 -269.556439) (xy 375.44853 -269.598455) (xy 375.411807 -269.635178) (xy 375.369791 -269.665704)
			(xy 375.323517 -269.689282) (xy 375.274124 -269.70533) (xy 375.222829 -269.713455) (xy 375.170895 -269.713455)
			(xy 375.1196 -269.70533) (xy 375.070207 -269.689282) (xy 375.023933 -269.665704) (xy 374.981917 -269.635178)
			(xy 374.945194 -269.598455) (xy 374.914668 -269.556439) (xy 374.89109 -269.510165) (xy 374.875042 -269.460772)
			(xy 374.866917 -269.409477) (xy 374.587007 -269.409477) (xy 374.578882 -269.460772) (xy 374.562834 -269.510165)
			(xy 374.539256 -269.556439) (xy 374.50873 -269.598455) (xy 374.472007 -269.635178) (xy 374.429991 -269.665704)
			(xy 374.383717 -269.689282) (xy 374.334324 -269.70533) (xy 374.283029 -269.713455) (xy 374.231095 -269.713455)
			(xy 374.1798 -269.70533) (xy 374.130407 -269.689282) (xy 374.084133 -269.665704) (xy 374.042117 -269.635178)
			(xy 374.005394 -269.598455) (xy 373.974868 -269.556439) (xy 373.95129 -269.510165) (xy 373.935242 -269.460772)
			(xy 373.927117 -269.409477) (xy 373.647207 -269.409477) (xy 373.639082 -269.460772) (xy 373.623034 -269.510165)
			(xy 373.599456 -269.556439) (xy 373.56893 -269.598455) (xy 373.532207 -269.635178) (xy 373.490191 -269.665704)
			(xy 373.443917 -269.689282) (xy 373.394524 -269.70533) (xy 373.343229 -269.713455) (xy 373.291295 -269.713455)
			(xy 373.24 -269.70533) (xy 373.190607 -269.689282) (xy 373.144333 -269.665704) (xy 373.102317 -269.635178)
			(xy 373.065594 -269.598455) (xy 373.035068 -269.556439) (xy 373.01149 -269.510165) (xy 372.995442 -269.460772)
			(xy 372.987317 -269.409477) (xy 372.707407 -269.409477) (xy 372.699282 -269.460772) (xy 372.683234 -269.510165)
			(xy 372.659656 -269.556439) (xy 372.62913 -269.598455) (xy 372.592407 -269.635178) (xy 372.550391 -269.665704)
			(xy 372.504117 -269.689282) (xy 372.454724 -269.70533) (xy 372.403429 -269.713455) (xy 372.351495 -269.713455)
			(xy 372.3002 -269.70533) (xy 372.250807 -269.689282) (xy 372.204533 -269.665704) (xy 372.162517 -269.635178)
			(xy 372.125794 -269.598455) (xy 372.095268 -269.556439) (xy 372.07169 -269.510165) (xy 372.055642 -269.460772)
			(xy 372.047517 -269.409477) (xy 371.767573 -269.409477) (xy 371.767573 -269.411222) (xy 371.758323 -269.465873)
			(xy 371.740085 -269.518214) (xy 371.727222 -269.542768) (xy 371.720872 -269.553944) (xy 371.720872 -269.774162)
			(xy 371.721418 -269.78917) (xy 371.730156 -269.817887) (xy 371.746861 -269.842827) (xy 371.77009 -269.861838)
			(xy 371.797841 -269.87328) (xy 371.827719 -269.876166) (xy 371.842538 -269.87373) (xy 371.858684 -269.870666)
			(xy 371.891383 -269.867356) (xy 371.907816 -269.867126) (xy 371.933781 -269.867676) (xy 371.985071 -269.875802)
			(xy 372.034458 -269.891851) (xy 372.080727 -269.915428) (xy 372.122738 -269.945953) (xy 372.159457 -269.982674)
			(xy 372.18998 -270.024686) (xy 372.213555 -270.070957) (xy 372.229602 -270.120345) (xy 372.237725 -270.171635)
			(xy 372.237725 -270.223547) (xy 372.517671 -270.223547) (xy 372.517671 -270.171613) (xy 372.525796 -270.120318)
			(xy 372.541844 -270.070925) (xy 372.565422 -270.024651) (xy 372.595948 -269.982635) (xy 372.632671 -269.945912)
			(xy 372.674687 -269.915386) (xy 372.720961 -269.891808) (xy 372.770354 -269.87576) (xy 372.821649 -269.867635)
			(xy 372.873583 -269.867635) (xy 372.924878 -269.87576) (xy 372.974271 -269.891808) (xy 373.020545 -269.915386)
			(xy 373.062561 -269.945912) (xy 373.099284 -269.982635) (xy 373.12981 -270.024651) (xy 373.153388 -270.070925)
			(xy 373.169436 -270.120318) (xy 373.177561 -270.171613) (xy 373.17807 -270.19758) (xy 373.177561 -270.223547)
			(xy 373.457471 -270.223547) (xy 373.457471 -270.171613) (xy 373.465596 -270.120318) (xy 373.481644 -270.070925)
			(xy 373.505222 -270.024651) (xy 373.535748 -269.982635) (xy 373.572471 -269.945912) (xy 373.614487 -269.915386)
			(xy 373.660761 -269.891808) (xy 373.710154 -269.87576) (xy 373.761449 -269.867635) (xy 373.813383 -269.867635)
			(xy 373.864678 -269.87576) (xy 373.914071 -269.891808) (xy 373.960345 -269.915386) (xy 374.002361 -269.945912)
			(xy 374.039084 -269.982635) (xy 374.06961 -270.024651) (xy 374.093188 -270.070925) (xy 374.109236 -270.120318)
			(xy 374.117361 -270.171613) (xy 374.11787 -270.19758) (xy 374.117361 -270.223547) (xy 374.397271 -270.223547)
			(xy 374.397271 -270.171613) (xy 374.405396 -270.120318) (xy 374.421444 -270.070925) (xy 374.445022 -270.024651)
			(xy 374.475548 -269.982635) (xy 374.512271 -269.945912) (xy 374.554287 -269.915386) (xy 374.600561 -269.891808)
			(xy 374.649954 -269.87576) (xy 374.701249 -269.867635) (xy 374.753183 -269.867635) (xy 374.804478 -269.87576)
			(xy 374.853871 -269.891808) (xy 374.900145 -269.915386) (xy 374.942161 -269.945912) (xy 374.978884 -269.982635)
			(xy 375.00941 -270.024651) (xy 375.032988 -270.070925) (xy 375.049036 -270.120318) (xy 375.057161 -270.171613)
			(xy 375.05767 -270.19758) (xy 375.057161 -270.223547) (xy 375.337071 -270.223547) (xy 375.337071 -270.171613)
			(xy 375.345196 -270.120318) (xy 375.361244 -270.070925) (xy 375.384822 -270.024651) (xy 375.415348 -269.982635)
			(xy 375.452071 -269.945912) (xy 375.494087 -269.915386) (xy 375.540361 -269.891808) (xy 375.589754 -269.87576)
			(xy 375.641049 -269.867635) (xy 375.692983 -269.867635) (xy 375.744278 -269.87576) (xy 375.793671 -269.891808)
			(xy 375.839945 -269.915386) (xy 375.881961 -269.945912) (xy 375.918684 -269.982635) (xy 375.94921 -270.024651)
			(xy 375.972788 -270.070925) (xy 375.988836 -270.120318) (xy 375.996961 -270.171613) (xy 375.99747 -270.19758)
			(xy 375.996961 -270.223547) (xy 376.276871 -270.223547) (xy 376.276871 -270.171613) (xy 376.284996 -270.120318)
			(xy 376.301044 -270.070925) (xy 376.324622 -270.024651) (xy 376.355148 -269.982635) (xy 376.391871 -269.945912)
			(xy 376.433887 -269.915386) (xy 376.480161 -269.891808) (xy 376.529554 -269.87576) (xy 376.580849 -269.867635)
			(xy 376.632783 -269.867635) (xy 376.684078 -269.87576) (xy 376.733471 -269.891808) (xy 376.779745 -269.915386)
			(xy 376.821761 -269.945912) (xy 376.858484 -269.982635) (xy 376.88901 -270.024651) (xy 376.912588 -270.070925)
			(xy 376.928636 -270.120318) (xy 376.936761 -270.171613) (xy 376.93727 -270.19758) (xy 376.936761 -270.223547)
			(xy 377.216671 -270.223547) (xy 377.216671 -270.171613) (xy 377.224796 -270.120318) (xy 377.240844 -270.070925)
			(xy 377.264422 -270.024651) (xy 377.294948 -269.982635) (xy 377.331671 -269.945912) (xy 377.373687 -269.915386)
			(xy 377.419961 -269.891808) (xy 377.469354 -269.87576) (xy 377.520649 -269.867635) (xy 377.572583 -269.867635)
			(xy 377.623878 -269.87576) (xy 377.673271 -269.891808) (xy 377.719545 -269.915386) (xy 377.761561 -269.945912)
			(xy 377.798284 -269.982635) (xy 377.82881 -270.024651) (xy 377.852388 -270.070925) (xy 377.868436 -270.120318)
			(xy 377.876561 -270.171613) (xy 377.87707 -270.19758) (xy 377.876561 -270.223547) (xy 378.156471 -270.223547)
			(xy 378.156471 -270.171613) (xy 378.164596 -270.120318) (xy 378.180644 -270.070925) (xy 378.204222 -270.024651)
			(xy 378.234748 -269.982635) (xy 378.271471 -269.945912) (xy 378.313487 -269.915386) (xy 378.359761 -269.891808)
			(xy 378.409154 -269.87576) (xy 378.460449 -269.867635) (xy 378.512383 -269.867635) (xy 378.563678 -269.87576)
			(xy 378.613071 -269.891808) (xy 378.659345 -269.915386) (xy 378.701361 -269.945912) (xy 378.738084 -269.982635)
			(xy 378.76861 -270.024651) (xy 378.792188 -270.070925) (xy 378.808236 -270.120318) (xy 378.816361 -270.171613)
			(xy 378.81687 -270.19758) (xy 378.816361 -270.223547) (xy 378.808236 -270.274842) (xy 378.792188 -270.324235)
			(xy 378.76861 -270.370509) (xy 378.738084 -270.412525) (xy 378.701361 -270.449248) (xy 378.659345 -270.479774)
			(xy 378.613071 -270.503352) (xy 378.563678 -270.5194) (xy 378.512383 -270.527525) (xy 378.460449 -270.527525)
			(xy 378.409154 -270.5194) (xy 378.359761 -270.503352) (xy 378.313487 -270.479774) (xy 378.271471 -270.449248)
			(xy 378.234748 -270.412525) (xy 378.204222 -270.370509) (xy 378.180644 -270.324235) (xy 378.164596 -270.274842)
			(xy 378.156471 -270.223547) (xy 377.876561 -270.223547) (xy 377.868436 -270.274842) (xy 377.852388 -270.324235)
			(xy 377.82881 -270.370509) (xy 377.798284 -270.412525) (xy 377.761561 -270.449248) (xy 377.719545 -270.479774)
			(xy 377.673271 -270.503352) (xy 377.623878 -270.5194) (xy 377.572583 -270.527525) (xy 377.520649 -270.527525)
			(xy 377.469354 -270.5194) (xy 377.419961 -270.503352) (xy 377.373687 -270.479774) (xy 377.331671 -270.449248)
			(xy 377.294948 -270.412525) (xy 377.264422 -270.370509) (xy 377.240844 -270.324235) (xy 377.224796 -270.274842)
			(xy 377.216671 -270.223547) (xy 376.936761 -270.223547) (xy 376.928636 -270.274842) (xy 376.912588 -270.324235)
			(xy 376.88901 -270.370509) (xy 376.858484 -270.412525) (xy 376.821761 -270.449248) (xy 376.779745 -270.479774)
			(xy 376.733471 -270.503352) (xy 376.684078 -270.5194) (xy 376.632783 -270.527525) (xy 376.580849 -270.527525)
			(xy 376.529554 -270.5194) (xy 376.480161 -270.503352) (xy 376.433887 -270.479774) (xy 376.391871 -270.449248)
			(xy 376.355148 -270.412525) (xy 376.324622 -270.370509) (xy 376.301044 -270.324235) (xy 376.284996 -270.274842)
			(xy 376.276871 -270.223547) (xy 375.996961 -270.223547) (xy 375.988836 -270.274842) (xy 375.972788 -270.324235)
			(xy 375.94921 -270.370509) (xy 375.918684 -270.412525) (xy 375.881961 -270.449248) (xy 375.839945 -270.479774)
			(xy 375.793671 -270.503352) (xy 375.744278 -270.5194) (xy 375.692983 -270.527525) (xy 375.641049 -270.527525)
			(xy 375.589754 -270.5194) (xy 375.540361 -270.503352) (xy 375.494087 -270.479774) (xy 375.452071 -270.449248)
			(xy 375.415348 -270.412525) (xy 375.384822 -270.370509) (xy 375.361244 -270.324235) (xy 375.345196 -270.274842)
			(xy 375.337071 -270.223547) (xy 375.057161 -270.223547) (xy 375.049036 -270.274842) (xy 375.032988 -270.324235)
			(xy 375.00941 -270.370509) (xy 374.978884 -270.412525) (xy 374.942161 -270.449248) (xy 374.900145 -270.479774)
			(xy 374.853871 -270.503352) (xy 374.804478 -270.5194) (xy 374.753183 -270.527525) (xy 374.701249 -270.527525)
			(xy 374.649954 -270.5194) (xy 374.600561 -270.503352) (xy 374.554287 -270.479774) (xy 374.512271 -270.449248)
			(xy 374.475548 -270.412525) (xy 374.445022 -270.370509) (xy 374.421444 -270.324235) (xy 374.405396 -270.274842)
			(xy 374.397271 -270.223547) (xy 374.117361 -270.223547) (xy 374.109236 -270.274842) (xy 374.093188 -270.324235)
			(xy 374.06961 -270.370509) (xy 374.039084 -270.412525) (xy 374.002361 -270.449248) (xy 373.960345 -270.479774)
			(xy 373.914071 -270.503352) (xy 373.864678 -270.5194) (xy 373.813383 -270.527525) (xy 373.761449 -270.527525)
			(xy 373.710154 -270.5194) (xy 373.660761 -270.503352) (xy 373.614487 -270.479774) (xy 373.572471 -270.449248)
			(xy 373.535748 -270.412525) (xy 373.505222 -270.370509) (xy 373.481644 -270.324235) (xy 373.465596 -270.274842)
			(xy 373.457471 -270.223547) (xy 373.177561 -270.223547) (xy 373.169436 -270.274842) (xy 373.153388 -270.324235)
			(xy 373.12981 -270.370509) (xy 373.099284 -270.412525) (xy 373.062561 -270.449248) (xy 373.020545 -270.479774)
			(xy 372.974271 -270.503352) (xy 372.924878 -270.5194) (xy 372.873583 -270.527525) (xy 372.821649 -270.527525)
			(xy 372.770354 -270.5194) (xy 372.720961 -270.503352) (xy 372.674687 -270.479774) (xy 372.632671 -270.449248)
			(xy 372.595948 -270.412525) (xy 372.565422 -270.370509) (xy 372.541844 -270.324235) (xy 372.525796 -270.274842)
			(xy 372.517671 -270.223547) (xy 372.237725 -270.223547) (xy 372.237725 -270.223565) (xy 372.229602 -270.274855)
			(xy 372.213555 -270.324243) (xy 372.18998 -270.370514) (xy 372.159457 -270.412526) (xy 372.122738 -270.449247)
			(xy 372.080727 -270.479772) (xy 372.034458 -270.503349) (xy 371.985071 -270.519398) (xy 371.933781 -270.527524)
			(xy 371.907816 -270.528034) (xy 371.881358 -270.527485) (xy 371.829119 -270.519044) (xy 371.778896 -270.502374)
			(xy 371.731978 -270.477904) (xy 371.710458 -270.462502) (xy 371.597936 -270.575024) (xy 371.58748 -270.586098)
			(xy 371.573163 -270.612966) (xy 371.567406 -270.642862) (xy 371.570722 -270.673126) (xy 371.582816 -270.701066)
			(xy 371.602611 -270.724196) (xy 371.615208 -270.732758) (xy 371.638249 -270.748056) (xy 371.679303 -270.78511)
			(xy 371.713611 -270.828486) (xy 371.740213 -270.876971) (xy 371.758366 -270.929211) (xy 371.767563 -270.983744)
			(xy 371.768116 -271.011396) (xy 371.767607 -271.037363) (xy 372.047517 -271.037363) (xy 372.047517 -270.985429)
			(xy 372.055642 -270.934134) (xy 372.07169 -270.884741) (xy 372.095268 -270.838467) (xy 372.125794 -270.796451)
			(xy 372.162517 -270.759728) (xy 372.204533 -270.729202) (xy 372.250807 -270.705624) (xy 372.3002 -270.689576)
			(xy 372.351495 -270.681451) (xy 372.403429 -270.681451) (xy 372.454724 -270.689576) (xy 372.504117 -270.705624)
			(xy 372.550391 -270.729202) (xy 372.592407 -270.759728) (xy 372.62913 -270.796451) (xy 372.659656 -270.838467)
			(xy 372.683234 -270.884741) (xy 372.699282 -270.934134) (xy 372.707407 -270.985429) (xy 372.707916 -271.011396)
			(xy 372.707407 -271.037363) (xy 372.987317 -271.037363) (xy 372.987317 -270.985429) (xy 372.995442 -270.934134)
			(xy 373.01149 -270.884741) (xy 373.035068 -270.838467) (xy 373.065594 -270.796451) (xy 373.102317 -270.759728)
			(xy 373.144333 -270.729202) (xy 373.190607 -270.705624) (xy 373.24 -270.689576) (xy 373.291295 -270.681451)
			(xy 373.343229 -270.681451) (xy 373.394524 -270.689576) (xy 373.443917 -270.705624) (xy 373.490191 -270.729202)
			(xy 373.532207 -270.759728) (xy 373.56893 -270.796451) (xy 373.599456 -270.838467) (xy 373.623034 -270.884741)
			(xy 373.639082 -270.934134) (xy 373.647207 -270.985429) (xy 373.647716 -271.011396) (xy 373.647207 -271.037363)
			(xy 373.927117 -271.037363) (xy 373.927117 -270.985429) (xy 373.935242 -270.934134) (xy 373.95129 -270.884741)
			(xy 373.974868 -270.838467) (xy 374.005394 -270.796451) (xy 374.042117 -270.759728) (xy 374.084133 -270.729202)
			(xy 374.130407 -270.705624) (xy 374.1798 -270.689576) (xy 374.231095 -270.681451) (xy 374.283029 -270.681451)
			(xy 374.334324 -270.689576) (xy 374.383717 -270.705624) (xy 374.429991 -270.729202) (xy 374.472007 -270.759728)
			(xy 374.50873 -270.796451) (xy 374.539256 -270.838467) (xy 374.562834 -270.884741) (xy 374.578882 -270.934134)
			(xy 374.587007 -270.985429) (xy 374.587516 -271.011396) (xy 374.587007 -271.037363) (xy 374.866917 -271.037363)
			(xy 374.866917 -270.985429) (xy 374.875042 -270.934134) (xy 374.89109 -270.884741) (xy 374.914668 -270.838467)
			(xy 374.945194 -270.796451) (xy 374.981917 -270.759728) (xy 375.023933 -270.729202) (xy 375.070207 -270.705624)
			(xy 375.1196 -270.689576) (xy 375.170895 -270.681451) (xy 375.222829 -270.681451) (xy 375.274124 -270.689576)
			(xy 375.323517 -270.705624) (xy 375.369791 -270.729202) (xy 375.411807 -270.759728) (xy 375.44853 -270.796451)
			(xy 375.479056 -270.838467) (xy 375.502634 -270.884741) (xy 375.518682 -270.934134) (xy 375.526807 -270.985429)
			(xy 375.527316 -271.011396) (xy 375.526807 -271.037363) (xy 375.806717 -271.037363) (xy 375.806717 -270.985429)
			(xy 375.814842 -270.934134) (xy 375.83089 -270.884741) (xy 375.854468 -270.838467) (xy 375.884994 -270.796451)
			(xy 375.921717 -270.759728) (xy 375.963733 -270.729202) (xy 376.010007 -270.705624) (xy 376.0594 -270.689576)
			(xy 376.110695 -270.681451) (xy 376.162629 -270.681451) (xy 376.213924 -270.689576) (xy 376.263317 -270.705624)
			(xy 376.309591 -270.729202) (xy 376.351607 -270.759728) (xy 376.38833 -270.796451) (xy 376.418856 -270.838467)
			(xy 376.442434 -270.884741) (xy 376.458482 -270.934134) (xy 376.466607 -270.985429) (xy 376.467116 -271.011396)
			(xy 376.466607 -271.037363) (xy 376.746517 -271.037363) (xy 376.746517 -270.985429) (xy 376.754642 -270.934134)
			(xy 376.77069 -270.884741) (xy 376.794268 -270.838467) (xy 376.824794 -270.796451) (xy 376.861517 -270.759728)
			(xy 376.903533 -270.729202) (xy 376.949807 -270.705624) (xy 376.9992 -270.689576) (xy 377.050495 -270.681451)
			(xy 377.102429 -270.681451) (xy 377.153724 -270.689576) (xy 377.203117 -270.705624) (xy 377.249391 -270.729202)
			(xy 377.291407 -270.759728) (xy 377.32813 -270.796451) (xy 377.358656 -270.838467) (xy 377.382234 -270.884741)
			(xy 377.398282 -270.934134) (xy 377.406407 -270.985429) (xy 377.406916 -271.011396) (xy 377.406407 -271.037363)
			(xy 377.686317 -271.037363) (xy 377.686317 -270.985429) (xy 377.694442 -270.934134) (xy 377.71049 -270.884741)
			(xy 377.734068 -270.838467) (xy 377.764594 -270.796451) (xy 377.801317 -270.759728) (xy 377.843333 -270.729202)
			(xy 377.889607 -270.705624) (xy 377.939 -270.689576) (xy 377.990295 -270.681451) (xy 378.042229 -270.681451)
			(xy 378.093524 -270.689576) (xy 378.142917 -270.705624) (xy 378.189191 -270.729202) (xy 378.231207 -270.759728)
			(xy 378.26793 -270.796451) (xy 378.298456 -270.838467) (xy 378.322034 -270.884741) (xy 378.338082 -270.934134)
			(xy 378.346207 -270.985429) (xy 378.346716 -271.011396) (xy 378.346207 -271.037363) (xy 378.626117 -271.037363)
			(xy 378.626117 -270.985429) (xy 378.634242 -270.934134) (xy 378.65029 -270.884741) (xy 378.673868 -270.838467)
			(xy 378.704394 -270.796451) (xy 378.741117 -270.759728) (xy 378.783133 -270.729202) (xy 378.829407 -270.705624)
			(xy 378.8788 -270.689576) (xy 378.930095 -270.681451) (xy 378.982029 -270.681451) (xy 379.033324 -270.689576)
			(xy 379.082717 -270.705624) (xy 379.128991 -270.729202) (xy 379.171007 -270.759728) (xy 379.20773 -270.796451)
			(xy 379.238256 -270.838467) (xy 379.261834 -270.884741) (xy 379.277882 -270.934134) (xy 379.286007 -270.985429)
			(xy 379.286516 -271.011396) (xy 379.286007 -271.037363) (xy 379.277882 -271.088658) (xy 379.261834 -271.138051)
			(xy 379.238256 -271.184325) (xy 379.20773 -271.226341) (xy 379.171007 -271.263064) (xy 379.128991 -271.29359)
			(xy 379.082717 -271.317168) (xy 379.033324 -271.333216) (xy 378.982029 -271.341341) (xy 378.930095 -271.341341)
			(xy 378.8788 -271.333216) (xy 378.829407 -271.317168) (xy 378.783133 -271.29359) (xy 378.741117 -271.263064)
			(xy 378.704394 -271.226341) (xy 378.673868 -271.184325) (xy 378.65029 -271.138051) (xy 378.634242 -271.088658)
			(xy 378.626117 -271.037363) (xy 378.346207 -271.037363) (xy 378.338082 -271.088658) (xy 378.322034 -271.138051)
			(xy 378.298456 -271.184325) (xy 378.26793 -271.226341) (xy 378.231207 -271.263064) (xy 378.189191 -271.29359)
			(xy 378.142917 -271.317168) (xy 378.093524 -271.333216) (xy 378.042229 -271.341341) (xy 377.990295 -271.341341)
			(xy 377.939 -271.333216) (xy 377.889607 -271.317168) (xy 377.843333 -271.29359) (xy 377.801317 -271.263064)
			(xy 377.764594 -271.226341) (xy 377.734068 -271.184325) (xy 377.71049 -271.138051) (xy 377.694442 -271.088658)
			(xy 377.686317 -271.037363) (xy 377.406407 -271.037363) (xy 377.398282 -271.088658) (xy 377.382234 -271.138051)
			(xy 377.358656 -271.184325) (xy 377.32813 -271.226341) (xy 377.291407 -271.263064) (xy 377.249391 -271.29359)
			(xy 377.203117 -271.317168) (xy 377.153724 -271.333216) (xy 377.102429 -271.341341) (xy 377.050495 -271.341341)
			(xy 376.9992 -271.333216) (xy 376.949807 -271.317168) (xy 376.903533 -271.29359) (xy 376.861517 -271.263064)
			(xy 376.824794 -271.226341) (xy 376.794268 -271.184325) (xy 376.77069 -271.138051) (xy 376.754642 -271.088658)
			(xy 376.746517 -271.037363) (xy 376.466607 -271.037363) (xy 376.458482 -271.088658) (xy 376.442434 -271.138051)
			(xy 376.418856 -271.184325) (xy 376.38833 -271.226341) (xy 376.351607 -271.263064) (xy 376.309591 -271.29359)
			(xy 376.263317 -271.317168) (xy 376.213924 -271.333216) (xy 376.162629 -271.341341) (xy 376.110695 -271.341341)
			(xy 376.0594 -271.333216) (xy 376.010007 -271.317168) (xy 375.963733 -271.29359) (xy 375.921717 -271.263064)
			(xy 375.884994 -271.226341) (xy 375.854468 -271.184325) (xy 375.83089 -271.138051) (xy 375.814842 -271.088658)
			(xy 375.806717 -271.037363) (xy 375.526807 -271.037363) (xy 375.518682 -271.088658) (xy 375.502634 -271.138051)
			(xy 375.479056 -271.184325) (xy 375.44853 -271.226341) (xy 375.411807 -271.263064) (xy 375.369791 -271.29359)
			(xy 375.323517 -271.317168) (xy 375.274124 -271.333216) (xy 375.222829 -271.341341) (xy 375.170895 -271.341341)
			(xy 375.1196 -271.333216) (xy 375.070207 -271.317168) (xy 375.023933 -271.29359) (xy 374.981917 -271.263064)
			(xy 374.945194 -271.226341) (xy 374.914668 -271.184325) (xy 374.89109 -271.138051) (xy 374.875042 -271.088658)
			(xy 374.866917 -271.037363) (xy 374.587007 -271.037363) (xy 374.578882 -271.088658) (xy 374.562834 -271.138051)
			(xy 374.539256 -271.184325) (xy 374.50873 -271.226341) (xy 374.472007 -271.263064) (xy 374.429991 -271.29359)
			(xy 374.383717 -271.317168) (xy 374.334324 -271.333216) (xy 374.283029 -271.341341) (xy 374.231095 -271.341341)
			(xy 374.1798 -271.333216) (xy 374.130407 -271.317168) (xy 374.084133 -271.29359) (xy 374.042117 -271.263064)
			(xy 374.005394 -271.226341) (xy 373.974868 -271.184325) (xy 373.95129 -271.138051) (xy 373.935242 -271.088658)
			(xy 373.927117 -271.037363) (xy 373.647207 -271.037363) (xy 373.639082 -271.088658) (xy 373.623034 -271.138051)
			(xy 373.599456 -271.184325) (xy 373.56893 -271.226341) (xy 373.532207 -271.263064) (xy 373.490191 -271.29359)
			(xy 373.443917 -271.317168) (xy 373.394524 -271.333216) (xy 373.343229 -271.341341) (xy 373.291295 -271.341341)
			(xy 373.24 -271.333216) (xy 373.190607 -271.317168) (xy 373.144333 -271.29359) (xy 373.102317 -271.263064)
			(xy 373.065594 -271.226341) (xy 373.035068 -271.184325) (xy 373.01149 -271.138051) (xy 372.995442 -271.088658)
			(xy 372.987317 -271.037363) (xy 372.707407 -271.037363) (xy 372.699282 -271.088658) (xy 372.683234 -271.138051)
			(xy 372.659656 -271.184325) (xy 372.62913 -271.226341) (xy 372.592407 -271.263064) (xy 372.550391 -271.29359)
			(xy 372.504117 -271.317168) (xy 372.454724 -271.333216) (xy 372.403429 -271.341341) (xy 372.351495 -271.341341)
			(xy 372.3002 -271.333216) (xy 372.250807 -271.317168) (xy 372.204533 -271.29359) (xy 372.162517 -271.263064)
			(xy 372.125794 -271.226341) (xy 372.095268 -271.184325) (xy 372.07169 -271.138051) (xy 372.055642 -271.088658)
			(xy 372.047517 -271.037363) (xy 371.767607 -271.037363) (xy 371.759482 -271.088658) (xy 371.743434 -271.138051)
			(xy 371.719856 -271.184325) (xy 371.68933 -271.226341) (xy 371.652607 -271.263064) (xy 371.610591 -271.29359)
			(xy 371.564317 -271.317168) (xy 371.514924 -271.333216) (xy 371.463629 -271.341341) (xy 371.411695 -271.341341)
			(xy 371.3604 -271.333216) (xy 371.311007 -271.317168) (xy 371.264733 -271.29359) (xy 371.222717 -271.263064)
			(xy 371.185994 -271.226341) (xy 371.155468 -271.184325) (xy 371.13189 -271.138051) (xy 371.115842 -271.088658)
			(xy 371.107717 -271.037363) (xy 371.107208 -271.011396) (xy 371.107208 -271.010634) (xy 371.107583 -270.988448)
			(xy 371.113573 -270.944482) (xy 371.119146 -270.923004) (xy 371.122413 -270.91003) (xy 371.122613 -270.88328)
			(xy 371.115844 -270.857401) (xy 371.102574 -270.834174) (xy 371.083716 -270.815202) (xy 371.06057 -270.801791)
			(xy 371.034732 -270.794866) (xy 371.021356 -270.79448) (xy 370.914422 -270.79448) (xy 370.901064 -270.794845)
			(xy 370.875278 -270.801842) (xy 370.852189 -270.815286) (xy 370.833374 -270.834256) (xy 370.820121 -270.857455)
			(xy 370.813336 -270.883298) (xy 370.813483 -270.910015) (xy 370.816632 -270.923004) (xy 370.822164 -270.94449)
			(xy 370.828157 -270.988451) (xy 370.82857 -271.010634) (xy 370.82857 -271.011396) (xy 370.828061 -271.037363)
			(xy 370.819936 -271.088658) (xy 370.803888 -271.138051) (xy 370.78031 -271.184325) (xy 370.749784 -271.226341)
			(xy 370.713061 -271.263064) (xy 370.671045 -271.29359) (xy 370.624771 -271.317168) (xy 370.575378 -271.333216)
			(xy 370.524083 -271.341341) (xy 370.472149 -271.341341) (xy 370.420854 -271.333216) (xy 370.371461 -271.317168)
			(xy 370.325187 -271.29359) (xy 370.283171 -271.263064) (xy 370.246448 -271.226341) (xy 370.215922 -271.184325)
			(xy 370.192344 -271.138051) (xy 370.176296 -271.088658) (xy 370.168171 -271.037363) (xy 370.167662 -271.011396)
			(xy 370.167662 -271.010634) (xy 370.168039 -270.988448) (xy 370.174028 -270.944482) (xy 370.1796 -270.923004)
			(xy 370.182814 -270.91002) (xy 370.183013 -270.883281) (xy 370.176248 -270.85741) (xy 370.162986 -270.83419)
			(xy 370.144139 -270.81522) (xy 370.121006 -270.801806) (xy 370.095181 -270.794872) (xy 370.08181 -270.79448)
			(xy 369.974368 -270.79448) (xy 369.961011 -270.794883) (xy 369.935227 -270.80187) (xy 369.912136 -270.815305)
			(xy 369.89332 -270.834269) (xy 369.880065 -270.857464) (xy 369.87328 -270.883303) (xy 369.873428 -270.910017)
			(xy 369.876578 -270.923004) (xy 369.882109 -270.94449) (xy 369.888103 -270.988451) (xy 369.888516 -271.010634)
			(xy 369.888516 -271.011396) (xy 369.888007 -271.037363) (xy 369.879882 -271.088658) (xy 369.863834 -271.138051)
			(xy 369.840256 -271.184325) (xy 369.80973 -271.226341) (xy 369.773007 -271.263064) (xy 369.730991 -271.29359)
			(xy 369.684717 -271.317168) (xy 369.635324 -271.333216) (xy 369.584029 -271.341341) (xy 369.532095 -271.341341)
			(xy 369.4808 -271.333216) (xy 369.431407 -271.317168) (xy 369.385133 -271.29359) (xy 369.343117 -271.263064)
			(xy 369.306394 -271.226341) (xy 369.275868 -271.184325) (xy 369.25229 -271.138051) (xy 369.236242 -271.088658)
			(xy 369.228117 -271.037363) (xy 369.227608 -271.011396) (xy 369.227608 -271.010634) (xy 369.227983 -270.988448)
			(xy 369.233973 -270.944482) (xy 369.239546 -270.923004) (xy 369.242813 -270.91003) (xy 369.243013 -270.88328)
			(xy 369.236244 -270.857401) (xy 369.222974 -270.834174) (xy 369.204116 -270.815202) (xy 369.18097 -270.801791)
			(xy 369.155132 -270.794866) (xy 369.141756 -270.79448) (xy 369.034568 -270.79448) (xy 369.021211 -270.794883)
			(xy 368.995427 -270.80187) (xy 368.972336 -270.815305) (xy 368.95352 -270.834269) (xy 368.940265 -270.857464)
			(xy 368.93348 -270.883303) (xy 368.933628 -270.910017) (xy 368.936778 -270.923004) (xy 368.942309 -270.94449)
			(xy 368.948303 -270.988451) (xy 368.948716 -271.010634) (xy 368.948716 -271.011396) (xy 368.948207 -271.037363)
			(xy 368.940082 -271.088658) (xy 368.924034 -271.138051) (xy 368.900456 -271.184325) (xy 368.86993 -271.226341)
			(xy 368.833207 -271.263064) (xy 368.791191 -271.29359) (xy 368.744917 -271.317168) (xy 368.695524 -271.333216)
			(xy 368.644229 -271.341341) (xy 368.592295 -271.341341) (xy 368.541 -271.333216) (xy 368.491607 -271.317168)
			(xy 368.445333 -271.29359) (xy 368.403317 -271.263064) (xy 368.366594 -271.226341) (xy 368.336068 -271.184325)
			(xy 368.31249 -271.138051) (xy 368.296442 -271.088658) (xy 368.288317 -271.037363) (xy 368.287808 -271.011396)
			(xy 368.287808 -271.010634) (xy 368.288183 -270.988448) (xy 368.294173 -270.944482) (xy 368.299746 -270.923004)
			(xy 368.303013 -270.91003) (xy 368.303213 -270.88328) (xy 368.296444 -270.857401) (xy 368.283174 -270.834174)
			(xy 368.264316 -270.815202) (xy 368.24117 -270.801791) (xy 368.215332 -270.794866) (xy 368.201956 -270.79448)
			(xy 368.094768 -270.79448) (xy 368.081411 -270.794883) (xy 368.055627 -270.80187) (xy 368.032536 -270.815305)
			(xy 368.01372 -270.834269) (xy 368.000465 -270.857464) (xy 367.99368 -270.883303) (xy 367.993828 -270.910017)
			(xy 367.996978 -270.923004) (xy 368.002509 -270.94449) (xy 368.008503 -270.988451) (xy 368.008916 -271.010634)
			(xy 368.008916 -271.011396) (xy 368.008407 -271.037363) (xy 368.000282 -271.088658) (xy 367.984234 -271.138051)
			(xy 367.960656 -271.184325) (xy 367.93013 -271.226341) (xy 367.893407 -271.263064) (xy 367.851391 -271.29359)
			(xy 367.805117 -271.317168) (xy 367.755724 -271.333216) (xy 367.704429 -271.341341) (xy 367.652495 -271.341341)
			(xy 367.6012 -271.333216) (xy 367.551807 -271.317168) (xy 367.505533 -271.29359) (xy 367.463517 -271.263064)
			(xy 367.426794 -271.226341) (xy 367.396268 -271.184325) (xy 367.37269 -271.138051) (xy 367.356642 -271.088658)
			(xy 367.348517 -271.037363) (xy 367.348008 -271.011396) (xy 367.348008 -271.010634) (xy 367.348383 -270.988448)
			(xy 367.354373 -270.944482) (xy 367.359946 -270.923004) (xy 367.363213 -270.91003) (xy 367.363413 -270.88328)
			(xy 367.356644 -270.857401) (xy 367.343374 -270.834174) (xy 367.324516 -270.815202) (xy 367.30137 -270.801791)
			(xy 367.275532 -270.794866) (xy 367.262156 -270.79448) (xy 367.154968 -270.79448) (xy 367.141611 -270.794883)
			(xy 367.115827 -270.80187) (xy 367.092736 -270.815305) (xy 367.07392 -270.834269) (xy 367.060665 -270.857464)
			(xy 367.05388 -270.883303) (xy 367.054028 -270.910017) (xy 367.057178 -270.923004) (xy 367.062709 -270.94449)
			(xy 367.068703 -270.988451) (xy 367.069116 -271.010634) (xy 367.069116 -271.011396) (xy 367.068607 -271.037363)
			(xy 367.060482 -271.088658) (xy 367.044434 -271.138051) (xy 367.020856 -271.184325) (xy 366.99033 -271.226341)
			(xy 366.953607 -271.263064) (xy 366.911591 -271.29359) (xy 366.865317 -271.317168) (xy 366.815924 -271.333216)
			(xy 366.764629 -271.341341) (xy 366.712695 -271.341341) (xy 366.6614 -271.333216) (xy 366.612007 -271.317168)
			(xy 366.565733 -271.29359) (xy 366.523717 -271.263064) (xy 366.486994 -271.226341) (xy 366.456468 -271.184325)
			(xy 366.43289 -271.138051) (xy 366.416842 -271.088658) (xy 366.408717 -271.037363) (xy 366.408208 -271.011396)
			(xy 366.408208 -271.010634) (xy 366.408583 -270.988448) (xy 366.414573 -270.944482) (xy 366.420146 -270.923004)
			(xy 366.423413 -270.91003) (xy 366.423613 -270.88328) (xy 366.416844 -270.857401) (xy 366.403574 -270.834174)
			(xy 366.384716 -270.815202) (xy 366.36157 -270.801791) (xy 366.335732 -270.794866) (xy 366.322356 -270.79448)
			(xy 366.215168 -270.79448) (xy 366.201811 -270.794883) (xy 366.176027 -270.80187) (xy 366.152936 -270.815305)
			(xy 366.13412 -270.834269) (xy 366.120865 -270.857464) (xy 366.11408 -270.883303) (xy 366.114228 -270.910017)
			(xy 366.117378 -270.923004) (xy 366.122909 -270.94449) (xy 366.128903 -270.988451) (xy 366.129316 -271.010634)
			(xy 366.129316 -271.011396) (xy 366.128807 -271.037363) (xy 366.120682 -271.088658) (xy 366.104634 -271.138051)
			(xy 366.081056 -271.184325) (xy 366.05053 -271.226341) (xy 366.013807 -271.263064) (xy 365.971791 -271.29359)
			(xy 365.925517 -271.317168) (xy 365.876124 -271.333216) (xy 365.824829 -271.341341) (xy 365.772895 -271.341341)
			(xy 365.7216 -271.333216) (xy 365.672207 -271.317168) (xy 365.625933 -271.29359) (xy 365.583917 -271.263064)
			(xy 365.547194 -271.226341) (xy 365.516668 -271.184325) (xy 365.49309 -271.138051) (xy 365.477042 -271.088658)
			(xy 365.468917 -271.037363) (xy 365.468408 -271.011396) (xy 365.468408 -271.010634) (xy 365.468783 -270.988448)
			(xy 365.474773 -270.944482) (xy 365.480346 -270.923004) (xy 365.483613 -270.91003) (xy 365.483813 -270.88328)
			(xy 365.477044 -270.857401) (xy 365.463774 -270.834174) (xy 365.444916 -270.815202) (xy 365.42177 -270.801791)
			(xy 365.395932 -270.794866) (xy 365.382556 -270.79448) (xy 365.275368 -270.79448) (xy 365.262011 -270.794883)
			(xy 365.236227 -270.80187) (xy 365.213136 -270.815305) (xy 365.19432 -270.834269) (xy 365.181065 -270.857464)
			(xy 365.17428 -270.883303) (xy 365.174428 -270.910017) (xy 365.177578 -270.923004) (xy 365.183109 -270.94449)
			(xy 365.189103 -270.988451) (xy 365.189516 -271.010634) (xy 365.189516 -271.011396) (xy 365.189007 -271.037363)
			(xy 365.180882 -271.088658) (xy 365.164834 -271.138051) (xy 365.141256 -271.184325) (xy 365.11073 -271.226341)
			(xy 365.074007 -271.263064) (xy 365.031991 -271.29359) (xy 364.985717 -271.317168) (xy 364.936324 -271.333216)
			(xy 364.885029 -271.341341) (xy 364.833095 -271.341341) (xy 364.7818 -271.333216) (xy 364.732407 -271.317168)
			(xy 364.686133 -271.29359) (xy 364.644117 -271.263064) (xy 364.607394 -271.226341) (xy 364.576868 -271.184325)
			(xy 364.55329 -271.138051) (xy 364.537242 -271.088658) (xy 364.529117 -271.037363) (xy 364.528608 -271.011396)
			(xy 364.528608 -271.010634) (xy 364.528983 -270.988448) (xy 364.534973 -270.944482) (xy 364.540546 -270.923004)
			(xy 364.543813 -270.91003) (xy 364.544013 -270.88328) (xy 364.537244 -270.857401) (xy 364.523974 -270.834174)
			(xy 364.505116 -270.815202) (xy 364.48197 -270.801791) (xy 364.456132 -270.794866) (xy 364.442756 -270.79448)
			(xy 364.335568 -270.79448) (xy 364.322211 -270.794883) (xy 364.296427 -270.80187) (xy 364.273336 -270.815305)
			(xy 364.25452 -270.834269) (xy 364.241265 -270.857464) (xy 364.23448 -270.883303) (xy 364.234628 -270.910017)
			(xy 364.237778 -270.923004) (xy 364.243309 -270.94449) (xy 364.249303 -270.988451) (xy 364.249716 -271.010634)
			(xy 364.249716 -271.011396) (xy 364.249207 -271.037363) (xy 364.241082 -271.088658) (xy 364.225034 -271.138051)
			(xy 364.201456 -271.184325) (xy 364.17093 -271.226341) (xy 364.134207 -271.263064) (xy 364.092191 -271.29359)
			(xy 364.045917 -271.317168) (xy 363.996524 -271.333216) (xy 363.945229 -271.341341) (xy 363.893295 -271.341341)
			(xy 363.842 -271.333216) (xy 363.792607 -271.317168) (xy 363.746333 -271.29359) (xy 363.704317 -271.263064)
			(xy 363.667594 -271.226341) (xy 363.637068 -271.184325) (xy 363.61349 -271.138051) (xy 363.597442 -271.088658)
			(xy 363.589317 -271.037363) (xy 363.588808 -271.011396) (xy 363.588808 -271.010634) (xy 363.589183 -270.988448)
			(xy 363.595173 -270.944482) (xy 363.600746 -270.923004) (xy 363.604013 -270.91003) (xy 363.604213 -270.88328)
			(xy 363.597444 -270.857401) (xy 363.584174 -270.834174) (xy 363.565316 -270.815202) (xy 363.54217 -270.801791)
			(xy 363.516332 -270.794866) (xy 363.502956 -270.79448) (xy 363.395768 -270.79448) (xy 363.382411 -270.794883)
			(xy 363.356627 -270.80187) (xy 363.333536 -270.815305) (xy 363.31472 -270.834269) (xy 363.301465 -270.857464)
			(xy 363.29468 -270.883303) (xy 363.294828 -270.910017) (xy 363.297978 -270.923004) (xy 363.303509 -270.94449)
			(xy 363.309503 -270.988451) (xy 363.309916 -271.010634) (xy 363.309916 -271.011396) (xy 363.309407 -271.037363)
			(xy 363.301282 -271.088658) (xy 363.285234 -271.138051) (xy 363.261656 -271.184325) (xy 363.23113 -271.226341)
			(xy 363.194407 -271.263064) (xy 363.152391 -271.29359) (xy 363.106117 -271.317168) (xy 363.056724 -271.333216)
			(xy 363.005429 -271.341341) (xy 362.953495 -271.341341) (xy 362.9022 -271.333216) (xy 362.852807 -271.317168)
			(xy 362.806533 -271.29359) (xy 362.764517 -271.263064) (xy 362.727794 -271.226341) (xy 362.697268 -271.184325)
			(xy 362.67369 -271.138051) (xy 362.657642 -271.088658) (xy 362.649517 -271.037363) (xy 362.649008 -271.011396)
			(xy 362.649008 -271.010634) (xy 362.649383 -270.988448) (xy 362.655373 -270.944482) (xy 362.660946 -270.923004)
			(xy 362.664213 -270.91003) (xy 362.664413 -270.88328) (xy 362.657644 -270.857401) (xy 362.644374 -270.834174)
			(xy 362.625516 -270.815202) (xy 362.60237 -270.801791) (xy 362.576532 -270.794866) (xy 362.563156 -270.79448)
			(xy 362.455968 -270.79448) (xy 362.442611 -270.794883) (xy 362.416827 -270.80187) (xy 362.393736 -270.815305)
			(xy 362.37492 -270.834269) (xy 362.361665 -270.857464) (xy 362.35488 -270.883303) (xy 362.355028 -270.910017)
			(xy 362.358178 -270.923004) (xy 362.363709 -270.94449) (xy 362.369703 -270.988451) (xy 362.370116 -271.010634)
			(xy 362.370116 -271.011396) (xy 362.369607 -271.037363) (xy 362.361482 -271.088658) (xy 362.345434 -271.138051)
			(xy 362.321856 -271.184325) (xy 362.29133 -271.226341) (xy 362.254607 -271.263064) (xy 362.212591 -271.29359)
			(xy 362.166317 -271.317168) (xy 362.116924 -271.333216) (xy 362.065629 -271.341341) (xy 362.013695 -271.341341)
			(xy 361.9624 -271.333216) (xy 361.913007 -271.317168) (xy 361.866733 -271.29359) (xy 361.824717 -271.263064)
			(xy 361.787994 -271.226341) (xy 361.757468 -271.184325) (xy 361.73389 -271.138051) (xy 361.717842 -271.088658)
			(xy 361.709717 -271.037363) (xy 361.709208 -271.011396) (xy 361.709208 -271.010634) (xy 361.709583 -270.988448)
			(xy 361.715573 -270.944482) (xy 361.721146 -270.923004) (xy 361.724413 -270.91003) (xy 361.724613 -270.88328)
			(xy 361.717844 -270.857401) (xy 361.704574 -270.834174) (xy 361.685716 -270.815202) (xy 361.66257 -270.801791)
			(xy 361.636732 -270.794866) (xy 361.623356 -270.79448) (xy 361.516168 -270.79448) (xy 361.502811 -270.794883)
			(xy 361.477027 -270.80187) (xy 361.453936 -270.815305) (xy 361.43512 -270.834269) (xy 361.421865 -270.857464)
			(xy 361.41508 -270.883303) (xy 361.415228 -270.910017) (xy 361.418378 -270.923004) (xy 361.423909 -270.94449)
			(xy 361.429903 -270.988451) (xy 361.430316 -271.010634) (xy 361.430316 -271.011396) (xy 361.429807 -271.037363)
			(xy 361.421682 -271.088658) (xy 361.405634 -271.138051) (xy 361.382056 -271.184325) (xy 361.35153 -271.226341)
			(xy 361.314807 -271.263064) (xy 361.272791 -271.29359) (xy 361.226517 -271.317168) (xy 361.177124 -271.333216)
			(xy 361.125829 -271.341341) (xy 361.073895 -271.341341) (xy 361.0226 -271.333216) (xy 360.973207 -271.317168)
			(xy 360.926933 -271.29359) (xy 360.884917 -271.263064) (xy 360.848194 -271.226341) (xy 360.817668 -271.184325)
			(xy 360.79409 -271.138051) (xy 360.778042 -271.088658) (xy 360.769917 -271.037363) (xy 360.769408 -271.011396)
			(xy 360.769918 -270.985519) (xy 360.777999 -270.934398) (xy 360.793947 -270.885162) (xy 360.817374 -270.839013)
			(xy 360.847706 -270.797077) (xy 360.884202 -270.760381) (xy 360.90479 -270.744696) (xy 360.916287 -270.735621)
			(xy 360.934024 -270.712332) (xy 360.944431 -270.684969) (xy 360.946652 -270.655778) (xy 360.940506 -270.627156)
			(xy 360.926496 -270.601451) (xy 360.916474 -270.590772) (xy 360.805476 -270.479774) (xy 360.772964 -270.495522)
			(xy 360.750538 -270.505784) (xy 360.703393 -270.520263) (xy 360.654621 -270.527581) (xy 360.629962 -270.528034)
			(xy 360.603993 -270.52758) (xy 360.552695 -270.519449) (xy 360.5033 -270.503394) (xy 360.457024 -270.47981)
			(xy 360.415008 -270.449277) (xy 360.378285 -270.412548) (xy 360.34776 -270.370526) (xy 360.324184 -270.324247)
			(xy 360.308137 -270.274849) (xy 360.300016 -270.223549) (xy 360.299508 -270.19758) (xy 360.299977 -270.172922)
			(xy 360.307292 -270.124152) (xy 360.321771 -270.077009) (xy 360.33202 -270.054578) (xy 360.347768 -270.022066)
			(xy 359.995724 -269.670022) (xy 359.970806 -269.654991) (xy 359.926202 -269.617623) (xy 359.888829 -269.573024)
			(xy 359.873804 -269.548102) (xy 359.717086 -269.391384) (xy 359.707036 -269.38191) (xy 359.682983 -269.368349)
			(xy 359.656177 -269.361726) (xy 359.628576 -269.362523) (xy 359.602197 -269.370684) (xy 359.578967 -269.385611)
			(xy 359.560584 -269.406214) (xy 359.54839 -269.430988) (xy 359.545382 -269.44447) (xy 359.540285 -269.469408)
			(xy 359.523312 -269.517396) (xy 359.499186 -269.562216) (xy 359.468477 -269.602809) (xy 359.43191 -269.638217)
			(xy 359.390349 -269.667603) (xy 359.344775 -269.690273) (xy 359.296266 -269.705692) (xy 359.245966 -269.713494)
			(xy 359.220516 -269.713964) (xy 359.194548 -269.713456) (xy 359.14325 -269.705334) (xy 359.093855 -269.689287)
			(xy 359.047578 -269.66571) (xy 359.005559 -269.635184) (xy 358.968833 -269.598461) (xy 358.938303 -269.556445)
			(xy 358.914723 -269.510169) (xy 358.898672 -269.460775) (xy 358.890546 -269.409478) (xy 358.890062 -269.38351)
			(xy 358.890546 -269.358059) (xy 358.898323 -269.307754) (xy 358.913725 -269.259238) (xy 358.936387 -269.21366)
			(xy 358.965774 -269.172097) (xy 359.001189 -269.135535) (xy 359.041794 -269.104839) (xy 359.086627 -269.080735)
			(xy 359.134627 -269.063794) (xy 359.159556 -269.058644) (xy 359.173045 -269.055664) (xy 359.197826 -269.043478)
			(xy 359.218435 -269.025097) (xy 359.233363 -269.001864) (xy 359.241518 -268.975481) (xy 359.242304 -268.947877)
			(xy 359.235663 -268.921072) (xy 359.222081 -268.897028) (xy 359.212642 -268.88694) (xy 359.128568 -268.802866)
			(xy 359.118837 -268.793751) (xy 359.095756 -268.780425) (xy 359.070012 -268.773527) (xy 359.04336 -268.773527)
			(xy 359.017616 -268.780425) (xy 358.994535 -268.793751) (xy 358.984804 -268.802866) (xy 358.966078 -268.82097)
			(xy 358.923992 -268.851651) (xy 358.877615 -268.875353) (xy 358.828095 -268.891488) (xy 358.776657 -268.899659)
			(xy 358.750616 -268.900148) (xy 358.724647 -268.899656) (xy 358.673348 -268.891534) (xy 358.623951 -268.875486)
			(xy 358.577673 -268.851907) (xy 358.535653 -268.82138) (xy 358.498927 -268.784654) (xy 358.468398 -268.742636)
			(xy 358.444818 -268.696358) (xy 358.428769 -268.646962) (xy 358.420644 -268.595663) (xy 358.420162 -268.569694)
			(xy 358.420656 -268.543652) (xy 358.428815 -268.492211) (xy 358.444945 -268.442688) (xy 358.468647 -268.39631)
			(xy 358.499334 -268.354226) (xy 358.517444 -268.335506) (xy 358.526569 -268.32578) (xy 358.539907 -268.302696)
			(xy 358.546814 -268.276947) (xy 358.546818 -268.250287) (xy 358.53992 -268.224535) (xy 358.52659 -268.201447)
			(xy 358.517444 -268.191742) (xy 358.393492 -268.06779) (xy 358.365298 -268.075156) (xy 358.344476 -268.080364)
			(xy 358.301923 -268.085973) (xy 358.280462 -268.086332) (xy 358.254493 -268.08588) (xy 358.203194 -268.077749)
			(xy 358.153799 -268.061694) (xy 358.107524 -268.038109) (xy 358.065507 -268.007577) (xy 358.028784 -267.970847)
			(xy 357.998259 -267.928825) (xy 357.974683 -267.882545) (xy 357.958637 -267.833147) (xy 357.950516 -267.781847)
			(xy 357.950008 -267.755878) (xy 357.95077 -267.734542) (xy 357.951215 -267.720689) (xy 357.945467 -267.693586)
			(xy 357.932636 -267.66903) (xy 357.91367 -267.648833) (xy 357.889967 -267.634487) (xy 357.863277 -267.62705)
			(xy 357.849424 -267.626592) (xy 357.7717 -267.626592) (xy 357.757853 -267.627035) (xy 357.731183 -267.634503)
			(xy 357.7075 -267.648863) (xy 357.688547 -267.669057) (xy 357.675717 -267.693602) (xy 357.669954 -267.720692)
			(xy 357.670354 -267.734542) (xy 357.671116 -267.755878) (xy 357.670607 -267.781845) (xy 357.662482 -267.83314)
			(xy 357.646434 -267.882533) (xy 357.622856 -267.928807) (xy 357.59233 -267.970823) (xy 357.555607 -268.007546)
			(xy 357.513591 -268.038072) (xy 357.467317 -268.06165) (xy 357.417924 -268.077698) (xy 357.366629 -268.085823)
			(xy 357.314695 -268.085823) (xy 357.2634 -268.077698) (xy 357.214007 -268.06165) (xy 357.167733 -268.038072)
			(xy 357.125717 -268.007546) (xy 357.088994 -267.970823) (xy 357.058468 -267.928807) (xy 357.03489 -267.882533)
			(xy 357.018842 -267.83314) (xy 357.010717 -267.781845) (xy 357.010208 -267.755878) (xy 357.01097 -267.734542)
			(xy 357.011415 -267.720689) (xy 357.005667 -267.693586) (xy 356.992836 -267.66903) (xy 356.97387 -267.648833)
			(xy 356.950167 -267.634487) (xy 356.923477 -267.62705) (xy 356.909624 -267.626592) (xy 356.8319 -267.626592)
			(xy 356.818053 -267.627035) (xy 356.791383 -267.634503) (xy 356.7677 -267.648863) (xy 356.748747 -267.669057)
			(xy 356.735917 -267.693602) (xy 356.730154 -267.720692) (xy 356.730554 -267.734542) (xy 356.731316 -267.755878)
			(xy 356.730807 -267.781845) (xy 356.722682 -267.83314) (xy 356.706634 -267.882533) (xy 356.683056 -267.928807)
			(xy 356.65253 -267.970823) (xy 356.615807 -268.007546) (xy 356.573791 -268.038072) (xy 356.527517 -268.06165)
			(xy 356.478124 -268.077698) (xy 356.426829 -268.085823) (xy 356.374895 -268.085823) (xy 356.3236 -268.077698)
			(xy 356.274207 -268.06165) (xy 356.227933 -268.038072) (xy 356.185917 -268.007546) (xy 356.149194 -267.970823)
			(xy 356.118668 -267.928807) (xy 356.09509 -267.882533) (xy 356.079042 -267.83314) (xy 356.070917 -267.781845)
			(xy 356.070408 -267.755878) (xy 356.07117 -267.734542) (xy 356.071615 -267.720689) (xy 356.065867 -267.693586)
			(xy 356.053036 -267.66903) (xy 356.03407 -267.648833) (xy 356.010367 -267.634487) (xy 355.983677 -267.62705)
			(xy 355.969824 -267.626592) (xy 355.8921 -267.626592) (xy 355.878253 -267.627035) (xy 355.851583 -267.634503)
			(xy 355.8279 -267.648863) (xy 355.808947 -267.669057) (xy 355.796117 -267.693602) (xy 355.790354 -267.720692)
			(xy 355.790754 -267.734542) (xy 355.791516 -267.755878) (xy 355.791007 -267.781845) (xy 355.782882 -267.83314)
			(xy 355.766834 -267.882533) (xy 355.743256 -267.928807) (xy 355.71273 -267.970823) (xy 355.676007 -268.007546)
			(xy 355.633991 -268.038072) (xy 355.587717 -268.06165) (xy 355.538324 -268.077698) (xy 355.487029 -268.085823)
			(xy 355.435095 -268.085823) (xy 355.3838 -268.077698) (xy 355.334407 -268.06165) (xy 355.288133 -268.038072)
			(xy 355.246117 -268.007546) (xy 355.209394 -267.970823) (xy 355.178868 -267.928807) (xy 355.15529 -267.882533)
			(xy 355.139242 -267.83314) (xy 355.131117 -267.781845) (xy 355.130608 -267.755878) (xy 355.13137 -267.734542)
			(xy 355.131815 -267.720689) (xy 355.126067 -267.693586) (xy 355.113236 -267.66903) (xy 355.09427 -267.648833)
			(xy 355.070567 -267.634487) (xy 355.043877 -267.62705) (xy 355.030024 -267.626592) (xy 354.9523 -267.626592)
			(xy 354.938453 -267.627035) (xy 354.911783 -267.634503) (xy 354.8881 -267.648863) (xy 354.869147 -267.669057)
			(xy 354.856317 -267.693602) (xy 354.850554 -267.720692) (xy 354.850954 -267.734542) (xy 354.851716 -267.755878)
			(xy 354.851207 -267.781845) (xy 354.843082 -267.83314) (xy 354.827034 -267.882533) (xy 354.803456 -267.928807)
			(xy 354.77293 -267.970823) (xy 354.736207 -268.007546) (xy 354.694191 -268.038072) (xy 354.647917 -268.06165)
			(xy 354.598524 -268.077698) (xy 354.547229 -268.085823) (xy 354.495295 -268.085823) (xy 354.444 -268.077698)
			(xy 354.394607 -268.06165) (xy 354.348333 -268.038072) (xy 354.306317 -268.007546) (xy 354.269594 -267.970823)
			(xy 354.239068 -267.928807) (xy 354.21549 -267.882533) (xy 354.199442 -267.83314) (xy 354.191317 -267.781845)
			(xy 354.190808 -267.755878) (xy 354.19157 -267.734542) (xy 354.192015 -267.720689) (xy 354.186267 -267.693586)
			(xy 354.173436 -267.66903) (xy 354.15447 -267.648833) (xy 354.130767 -267.634487) (xy 354.104077 -267.62705)
			(xy 354.090224 -267.626592) (xy 354.0125 -267.626592) (xy 353.998653 -267.627035) (xy 353.971983 -267.634503)
			(xy 353.9483 -267.648863) (xy 353.929347 -267.669057) (xy 353.916517 -267.693602) (xy 353.910754 -267.720692)
			(xy 353.911154 -267.734542) (xy 353.911916 -267.755878) (xy 353.911407 -267.781845) (xy 353.903282 -267.83314)
			(xy 353.887234 -267.882533) (xy 353.863656 -267.928807) (xy 353.83313 -267.970823) (xy 353.796407 -268.007546)
			(xy 353.754391 -268.038072) (xy 353.708117 -268.06165) (xy 353.658724 -268.077698) (xy 353.607429 -268.085823)
			(xy 353.555495 -268.085823) (xy 353.5042 -268.077698) (xy 353.454807 -268.06165) (xy 353.408533 -268.038072)
			(xy 353.366517 -268.007546) (xy 353.329794 -267.970823) (xy 353.299268 -267.928807) (xy 353.27569 -267.882533)
			(xy 353.259642 -267.83314) (xy 353.251517 -267.781845) (xy 353.251008 -267.755878) (xy 353.25177 -267.734542)
			(xy 353.252215 -267.720689) (xy 353.246467 -267.693586) (xy 353.233636 -267.66903) (xy 353.21467 -267.648833)
			(xy 353.190967 -267.634487) (xy 353.164277 -267.62705) (xy 353.150424 -267.626592) (xy 353.0727 -267.626592)
			(xy 353.058853 -267.627035) (xy 353.032183 -267.634503) (xy 353.0085 -267.648863) (xy 352.989547 -267.669057)
			(xy 352.976717 -267.693602) (xy 352.970954 -267.720692) (xy 352.971354 -267.734542) (xy 352.972116 -267.755878)
			(xy 352.971607 -267.781845) (xy 352.963482 -267.83314) (xy 352.947434 -267.882533) (xy 352.923856 -267.928807)
			(xy 352.89333 -267.970823) (xy 352.856607 -268.007546) (xy 352.814591 -268.038072) (xy 352.768317 -268.06165)
			(xy 352.718924 -268.077698) (xy 352.667629 -268.085823) (xy 352.615695 -268.085823) (xy 352.5644 -268.077698)
			(xy 352.515007 -268.06165) (xy 352.468733 -268.038072) (xy 352.426717 -268.007546) (xy 352.389994 -267.970823)
			(xy 352.359468 -267.928807) (xy 352.33589 -267.882533) (xy 352.319842 -267.83314) (xy 352.311717 -267.781845)
			(xy 352.311208 -267.755878) (xy 352.311667 -267.72971) (xy 352.319933 -267.678031) (xy 352.33624 -267.628301)
			(xy 352.36018 -267.581761) (xy 352.391154 -267.539575) (xy 352.42839 -267.502798) (xy 352.470955 -267.472347)
			(xy 352.517787 -267.448985) (xy 352.542602 -267.440664) (xy 352.556708 -267.435722) (xy 352.581415 -267.418922)
			(xy 352.600209 -267.395695) (xy 352.611484 -267.368027) (xy 352.614277 -267.33828) (xy 352.608349 -267.308996)
			(xy 352.594208 -267.282677) (xy 352.584004 -267.271754) (xy 352.516948 -267.204698) (xy 352.506001 -267.194471)
			(xy 352.479595 -267.180349) (xy 352.45023 -267.174483) (xy 352.420425 -267.177376) (xy 352.392737 -267.188781)
			(xy 352.380804 -267.19784) (xy 352.35853 -267.215268) (xy 352.309283 -267.243066) (xy 352.256017 -267.262057)
			(xy 352.200292 -267.271687) (xy 352.172016 -267.272262) (xy 352.146048 -267.271756) (xy 352.09475 -267.263634)
			(xy 352.045354 -267.247587) (xy 351.999077 -267.22401) (xy 351.957058 -267.193484) (xy 351.920332 -267.15676)
			(xy 351.889803 -267.114743) (xy 351.866222 -267.068468) (xy 351.850172 -267.019074) (xy 351.842045 -266.967776)
			(xy 351.841562 -266.941808) (xy 351.842101 -266.915215) (xy 351.850637 -266.862717) (xy 351.867475 -266.812266)
			(xy 351.892179 -266.765164) (xy 351.92411 -266.722629) (xy 351.942908 -266.70381) (xy 351.943162 -266.703302)
			(xy 351.979484 -266.667234) (xy 351.930716 -266.618212) (xy 351.930716 -266.540996) (xy 351.930347 -266.527396)
			(xy 351.923162 -266.501163) (xy 351.909303 -266.477759) (xy 351.889754 -266.458847) (xy 351.865904 -266.445771)
			(xy 351.839447 -266.439458) (xy 351.812263 -266.440357) (xy 351.799144 -266.443968) (xy 351.775411 -266.450838)
			(xy 351.726564 -266.458241) (xy 351.701862 -266.4587) (xy 351.6759 -266.458096) (xy 351.624617 -266.449968)
			(xy 351.575236 -266.433918) (xy 351.528974 -266.410342) (xy 351.486969 -266.379819) (xy 351.450256 -266.343102)
			(xy 351.419738 -266.301093) (xy 351.396167 -266.254828) (xy 351.380123 -266.205446) (xy 351.372001 -266.154162)
			(xy 351.372001 -266.102238) (xy 351.380123 -266.050954) (xy 351.396167 -266.001572) (xy 351.419738 -265.955307)
			(xy 351.450256 -265.913298) (xy 351.486969 -265.876581) (xy 351.528974 -265.846058) (xy 351.575236 -265.822482)
			(xy 351.624617 -265.806432) (xy 351.6759 -265.798304) (xy 351.701862 -265.797792) (xy 351.726563 -265.798275)
			(xy 351.775408 -265.805673) (xy 351.799144 -265.812524) (xy 351.812266 -265.816034) (xy 351.839403 -265.816855)
			(xy 351.865801 -265.810508) (xy 351.889599 -265.797441) (xy 351.909121 -265.778573) (xy 351.922993 -265.755235)
			(xy 351.930237 -265.729069) (xy 351.930716 -265.715496) (xy 351.930716 -265.539728) (xy 351.914062 -265.521284)
			(xy 351.885934 -265.480318) (xy 351.864253 -265.435604) (xy 351.849507 -265.388149) (xy 351.84203 -265.339022)
			(xy 351.841562 -265.314176) (xy 351.842056 -265.28933) (xy 351.849518 -265.240202) (xy 351.864255 -265.192746)
			(xy 351.885935 -265.148033) (xy 351.914068 -265.107073) (xy 351.930716 -265.088624) (xy 351.930716 -264.91311)
			(xy 351.930336 -264.899511) (xy 351.923153 -264.873278) (xy 351.909297 -264.849874) (xy 351.88975 -264.830961)
			(xy 351.865902 -264.817884) (xy 351.839446 -264.811571) (xy 351.812262 -264.812471) (xy 351.799144 -264.816082)
			(xy 351.775412 -264.822952) (xy 351.726564 -264.830355) (xy 351.701862 -264.830814) (xy 351.675894 -264.830382)
			(xy 351.624597 -264.822252) (xy 351.575203 -264.806198) (xy 351.528929 -264.782615) (xy 351.486914 -264.752085)
			(xy 351.450191 -264.715358) (xy 351.419665 -264.673338) (xy 351.396088 -264.627061) (xy 351.380039 -264.577666)
			(xy 351.371915 -264.526368) (xy 351.092001 -264.526368) (xy 351.083882 -264.577622) (xy 351.067834 -264.627015)
			(xy 351.044256 -264.673289) (xy 351.01373 -264.715305) (xy 350.977007 -264.752028) (xy 350.934991 -264.782554)
			(xy 350.888717 -264.806132) (xy 350.839324 -264.82218) (xy 350.788029 -264.830305) (xy 350.736095 -264.830305)
			(xy 350.6848 -264.82218) (xy 350.635407 -264.806132) (xy 350.589133 -264.782554) (xy 350.547117 -264.752028)
			(xy 350.510394 -264.715305) (xy 350.479868 -264.673289) (xy 350.45629 -264.627015) (xy 350.440242 -264.577622)
			(xy 350.432117 -264.526327) (xy 350.152207 -264.526327) (xy 350.144082 -264.577622) (xy 350.128034 -264.627015)
			(xy 350.104456 -264.673289) (xy 350.07393 -264.715305) (xy 350.037207 -264.752028) (xy 349.995191 -264.782554)
			(xy 349.948917 -264.806132) (xy 349.899524 -264.82218) (xy 349.848229 -264.830305) (xy 349.796295 -264.830305)
			(xy 349.745 -264.82218) (xy 349.695607 -264.806132) (xy 349.649333 -264.782554) (xy 349.607317 -264.752028)
			(xy 349.570594 -264.715305) (xy 349.540068 -264.673289) (xy 349.51649 -264.627015) (xy 349.500442 -264.577622)
			(xy 349.492317 -264.526327) (xy 349.212407 -264.526327) (xy 349.204282 -264.577622) (xy 349.188234 -264.627015)
			(xy 349.164656 -264.673289) (xy 349.13413 -264.715305) (xy 349.097407 -264.752028) (xy 349.055391 -264.782554)
			(xy 349.009117 -264.806132) (xy 348.959724 -264.82218) (xy 348.908429 -264.830305) (xy 348.856495 -264.830305)
			(xy 348.8052 -264.82218) (xy 348.755807 -264.806132) (xy 348.709533 -264.782554) (xy 348.667517 -264.752028)
			(xy 348.630794 -264.715305) (xy 348.600268 -264.673289) (xy 348.57669 -264.627015) (xy 348.560642 -264.577622)
			(xy 348.552517 -264.526327) (xy 348.272607 -264.526327) (xy 348.264482 -264.577622) (xy 348.248434 -264.627015)
			(xy 348.224856 -264.673289) (xy 348.19433 -264.715305) (xy 348.157607 -264.752028) (xy 348.115591 -264.782554)
			(xy 348.069317 -264.806132) (xy 348.019924 -264.82218) (xy 347.968629 -264.830305) (xy 347.916695 -264.830305)
			(xy 347.8654 -264.82218) (xy 347.816007 -264.806132) (xy 347.769733 -264.782554) (xy 347.727717 -264.752028)
			(xy 347.690994 -264.715305) (xy 347.660468 -264.673289) (xy 347.63689 -264.627015) (xy 347.620842 -264.577622)
			(xy 347.612717 -264.526327) (xy 347.332807 -264.526327) (xy 347.324682 -264.577622) (xy 347.308634 -264.627015)
			(xy 347.285056 -264.673289) (xy 347.25453 -264.715305) (xy 347.217807 -264.752028) (xy 347.175791 -264.782554)
			(xy 347.129517 -264.806132) (xy 347.080124 -264.82218) (xy 347.028829 -264.830305) (xy 346.976895 -264.830305)
			(xy 346.9256 -264.82218) (xy 346.876207 -264.806132) (xy 346.829933 -264.782554) (xy 346.787917 -264.752028)
			(xy 346.751194 -264.715305) (xy 346.720668 -264.673289) (xy 346.69709 -264.627015) (xy 346.681042 -264.577622)
			(xy 346.672917 -264.526327) (xy 346.393261 -264.526327) (xy 346.385136 -264.577622) (xy 346.369088 -264.627015)
			(xy 346.34551 -264.673289) (xy 346.314984 -264.715305) (xy 346.278261 -264.752028) (xy 346.236245 -264.782554)
			(xy 346.189971 -264.806132) (xy 346.140578 -264.82218) (xy 346.089283 -264.830305) (xy 346.037349 -264.830305)
			(xy 345.986054 -264.82218) (xy 345.936661 -264.806132) (xy 345.890387 -264.782554) (xy 345.848371 -264.752028)
			(xy 345.811648 -264.715305) (xy 345.781122 -264.673289) (xy 345.757544 -264.627015) (xy 345.741496 -264.577622)
			(xy 345.733371 -264.526327) (xy 345.453207 -264.526327) (xy 345.445082 -264.577622) (xy 345.429034 -264.627015)
			(xy 345.405456 -264.673289) (xy 345.37493 -264.715305) (xy 345.338207 -264.752028) (xy 345.296191 -264.782554)
			(xy 345.249917 -264.806132) (xy 345.200524 -264.82218) (xy 345.149229 -264.830305) (xy 345.097295 -264.830305)
			(xy 345.046 -264.82218) (xy 344.996607 -264.806132) (xy 344.950333 -264.782554) (xy 344.908317 -264.752028)
			(xy 344.871594 -264.715305) (xy 344.841068 -264.673289) (xy 344.81749 -264.627015) (xy 344.801442 -264.577622)
			(xy 344.793317 -264.526327) (xy 344.513407 -264.526327) (xy 344.505282 -264.577622) (xy 344.489234 -264.627015)
			(xy 344.465656 -264.673289) (xy 344.43513 -264.715305) (xy 344.398407 -264.752028) (xy 344.356391 -264.782554)
			(xy 344.310117 -264.806132) (xy 344.260724 -264.82218) (xy 344.209429 -264.830305) (xy 344.157495 -264.830305)
			(xy 344.1062 -264.82218) (xy 344.056807 -264.806132) (xy 344.010533 -264.782554) (xy 343.968517 -264.752028)
			(xy 343.931794 -264.715305) (xy 343.901268 -264.673289) (xy 343.87769 -264.627015) (xy 343.861642 -264.577622)
			(xy 343.853517 -264.526327) (xy 343.573607 -264.526327) (xy 343.565482 -264.577622) (xy 343.549434 -264.627015)
			(xy 343.525856 -264.673289) (xy 343.49533 -264.715305) (xy 343.458607 -264.752028) (xy 343.416591 -264.782554)
			(xy 343.370317 -264.806132) (xy 343.320924 -264.82218) (xy 343.269629 -264.830305) (xy 343.217695 -264.830305)
			(xy 343.1664 -264.82218) (xy 343.117007 -264.806132) (xy 343.070733 -264.782554) (xy 343.028717 -264.752028)
			(xy 342.991994 -264.715305) (xy 342.961468 -264.673289) (xy 342.93789 -264.627015) (xy 342.921842 -264.577622)
			(xy 342.913717 -264.526327) (xy 342.633807 -264.526327) (xy 342.625682 -264.577622) (xy 342.609634 -264.627015)
			(xy 342.586056 -264.673289) (xy 342.55553 -264.715305) (xy 342.518807 -264.752028) (xy 342.476791 -264.782554)
			(xy 342.430517 -264.806132) (xy 342.381124 -264.82218) (xy 342.329829 -264.830305) (xy 342.277895 -264.830305)
			(xy 342.2266 -264.82218) (xy 342.177207 -264.806132) (xy 342.130933 -264.782554) (xy 342.088917 -264.752028)
			(xy 342.052194 -264.715305) (xy 342.021668 -264.673289) (xy 341.99809 -264.627015) (xy 341.982042 -264.577622)
			(xy 341.973917 -264.526327) (xy 341.694007 -264.526327) (xy 341.685882 -264.577622) (xy 341.669834 -264.627015)
			(xy 341.646256 -264.673289) (xy 341.61573 -264.715305) (xy 341.579007 -264.752028) (xy 341.536991 -264.782554)
			(xy 341.490717 -264.806132) (xy 341.441324 -264.82218) (xy 341.390029 -264.830305) (xy 341.338095 -264.830305)
			(xy 341.2868 -264.82218) (xy 341.237407 -264.806132) (xy 341.191133 -264.782554) (xy 341.149117 -264.752028)
			(xy 341.112394 -264.715305) (xy 341.081868 -264.673289) (xy 341.05829 -264.627015) (xy 341.042242 -264.577622)
			(xy 341.034117 -264.526327) (xy 340.754207 -264.526327) (xy 340.746082 -264.577622) (xy 340.730034 -264.627015)
			(xy 340.706456 -264.673289) (xy 340.67593 -264.715305) (xy 340.639207 -264.752028) (xy 340.597191 -264.782554)
			(xy 340.550917 -264.806132) (xy 340.501524 -264.82218) (xy 340.450229 -264.830305) (xy 340.398295 -264.830305)
			(xy 340.347 -264.82218) (xy 340.297607 -264.806132) (xy 340.251333 -264.782554) (xy 340.209317 -264.752028)
			(xy 340.172594 -264.715305) (xy 340.142068 -264.673289) (xy 340.11849 -264.627015) (xy 340.102442 -264.577622)
			(xy 340.094317 -264.526327) (xy 339.813996 -264.526327) (xy 339.812066 -264.551309) (xy 339.800349 -264.601028)
			(xy 339.781128 -264.648356) (xy 339.754859 -264.692166) (xy 339.722168 -264.731417) (xy 339.683832 -264.765176)
			(xy 339.662516 -264.779252) (xy 339.651848 -264.78611) (xy 339.627464 -264.828528) (xy 339.627464 -264.9474)
			(xy 339.62778 -264.955786) (xy 339.633281 -264.97163) (xy 339.643675 -264.984793) (xy 339.650578 -264.989564)
			(xy 339.718142 -265.02741) (xy 339.723391 -265.029899) (xy 339.734687 -265.032598) (xy 339.740494 -265.032744)
			(xy 339.767418 -265.032744) (xy 339.772591 -265.03259) (xy 339.782707 -265.030416) (xy 339.787484 -265.028426)
			(xy 339.791548 -265.02614) (xy 339.816481 -265.012743) (xy 339.86979 -264.993733) (xy 339.925556 -264.984065)
			(xy 339.953854 -264.983468) (xy 339.954362 -264.983468) (xy 339.980355 -264.983948) (xy 340.031702 -264.992075)
			(xy 340.081145 -265.008136) (xy 340.127467 -265.031733) (xy 340.169527 -265.062287) (xy 340.206289 -265.099044)
			(xy 340.236847 -265.141101) (xy 340.26045 -265.18742) (xy 340.276516 -265.236861) (xy 340.284649 -265.288207)
			(xy 340.284649 -265.340143) (xy 340.564471 -265.340143) (xy 340.564471 -265.288209) (xy 340.572596 -265.236914)
			(xy 340.588644 -265.187521) (xy 340.612222 -265.141247) (xy 340.642748 -265.099231) (xy 340.679471 -265.062508)
			(xy 340.721487 -265.031982) (xy 340.767761 -265.008404) (xy 340.817154 -264.992356) (xy 340.868449 -264.984231)
			(xy 340.920383 -264.984231) (xy 340.971678 -264.992356) (xy 341.021071 -265.008404) (xy 341.067345 -265.031982)
			(xy 341.109361 -265.062508) (xy 341.146084 -265.099231) (xy 341.17661 -265.141247) (xy 341.200188 -265.187521)
			(xy 341.216236 -265.236914) (xy 341.224361 -265.288209) (xy 341.22487 -265.314176) (xy 341.224361 -265.340143)
			(xy 341.504271 -265.340143) (xy 341.504271 -265.288209) (xy 341.512396 -265.236914) (xy 341.528444 -265.187521)
			(xy 341.552022 -265.141247) (xy 341.582548 -265.099231) (xy 341.619271 -265.062508) (xy 341.661287 -265.031982)
			(xy 341.707561 -265.008404) (xy 341.756954 -264.992356) (xy 341.808249 -264.984231) (xy 341.860183 -264.984231)
			(xy 341.911478 -264.992356) (xy 341.960871 -265.008404) (xy 342.007145 -265.031982) (xy 342.049161 -265.062508)
			(xy 342.085884 -265.099231) (xy 342.11641 -265.141247) (xy 342.139988 -265.187521) (xy 342.156036 -265.236914)
			(xy 342.164161 -265.288209) (xy 342.16467 -265.314176) (xy 342.164161 -265.340143) (xy 342.444071 -265.340143)
			(xy 342.444071 -265.288209) (xy 342.452196 -265.236914) (xy 342.468244 -265.187521) (xy 342.491822 -265.141247)
			(xy 342.522348 -265.099231) (xy 342.559071 -265.062508) (xy 342.601087 -265.031982) (xy 342.647361 -265.008404)
			(xy 342.696754 -264.992356) (xy 342.748049 -264.984231) (xy 342.799983 -264.984231) (xy 342.851278 -264.992356)
			(xy 342.900671 -265.008404) (xy 342.946945 -265.031982) (xy 342.988961 -265.062508) (xy 343.025684 -265.099231)
			(xy 343.05621 -265.141247) (xy 343.079788 -265.187521) (xy 343.095836 -265.236914) (xy 343.103961 -265.288209)
			(xy 343.10447 -265.314176) (xy 343.103961 -265.340143) (xy 343.383871 -265.340143) (xy 343.383871 -265.288209)
			(xy 343.391996 -265.236914) (xy 343.408044 -265.187521) (xy 343.431622 -265.141247) (xy 343.462148 -265.099231)
			(xy 343.498871 -265.062508) (xy 343.540887 -265.031982) (xy 343.587161 -265.008404) (xy 343.636554 -264.992356)
			(xy 343.687849 -264.984231) (xy 343.739783 -264.984231) (xy 343.791078 -264.992356) (xy 343.840471 -265.008404)
			(xy 343.886745 -265.031982) (xy 343.928761 -265.062508) (xy 343.965484 -265.099231) (xy 343.99601 -265.141247)
			(xy 344.019588 -265.187521) (xy 344.035636 -265.236914) (xy 344.043761 -265.288209) (xy 344.04427 -265.314176)
			(xy 344.043761 -265.340143) (xy 344.323671 -265.340143) (xy 344.323671 -265.288209) (xy 344.331796 -265.236914)
			(xy 344.347844 -265.187521) (xy 344.371422 -265.141247) (xy 344.401948 -265.099231) (xy 344.438671 -265.062508)
			(xy 344.480687 -265.031982) (xy 344.526961 -265.008404) (xy 344.576354 -264.992356) (xy 344.627649 -264.984231)
			(xy 344.679583 -264.984231) (xy 344.730878 -264.992356) (xy 344.780271 -265.008404) (xy 344.826545 -265.031982)
			(xy 344.868561 -265.062508) (xy 344.905284 -265.099231) (xy 344.93581 -265.141247) (xy 344.959388 -265.187521)
			(xy 344.975436 -265.236914) (xy 344.983561 -265.288209) (xy 344.98407 -265.314176) (xy 344.983561 -265.340143)
			(xy 345.263471 -265.340143) (xy 345.263471 -265.288209) (xy 345.271596 -265.236914) (xy 345.287644 -265.187521)
			(xy 345.311222 -265.141247) (xy 345.341748 -265.099231) (xy 345.378471 -265.062508) (xy 345.420487 -265.031982)
			(xy 345.466761 -265.008404) (xy 345.516154 -264.992356) (xy 345.567449 -264.984231) (xy 345.619383 -264.984231)
			(xy 345.670678 -264.992356) (xy 345.720071 -265.008404) (xy 345.766345 -265.031982) (xy 345.808361 -265.062508)
			(xy 345.845084 -265.099231) (xy 345.87561 -265.141247) (xy 345.899188 -265.187521) (xy 345.915236 -265.236914)
			(xy 345.923361 -265.288209) (xy 345.92387 -265.314176) (xy 345.923361 -265.340143) (xy 346.203017 -265.340143)
			(xy 346.203017 -265.288209) (xy 346.211142 -265.236914) (xy 346.22719 -265.187521) (xy 346.250768 -265.141247)
			(xy 346.281294 -265.099231) (xy 346.318017 -265.062508) (xy 346.360033 -265.031982) (xy 346.406307 -265.008404)
			(xy 346.4557 -264.992356) (xy 346.506995 -264.984231) (xy 346.558929 -264.984231) (xy 346.610224 -264.992356)
			(xy 346.659617 -265.008404) (xy 346.705891 -265.031982) (xy 346.747907 -265.062508) (xy 346.78463 -265.099231)
			(xy 346.815156 -265.141247) (xy 346.838734 -265.187521) (xy 346.854782 -265.236914) (xy 346.862907 -265.288209)
			(xy 346.863416 -265.314176) (xy 346.862907 -265.340143) (xy 347.143071 -265.340143) (xy 347.143071 -265.288209)
			(xy 347.151196 -265.236914) (xy 347.167244 -265.187521) (xy 347.190822 -265.141247) (xy 347.221348 -265.099231)
			(xy 347.258071 -265.062508) (xy 347.300087 -265.031982) (xy 347.346361 -265.008404) (xy 347.395754 -264.992356)
			(xy 347.447049 -264.984231) (xy 347.498983 -264.984231) (xy 347.550278 -264.992356) (xy 347.599671 -265.008404)
			(xy 347.645945 -265.031982) (xy 347.687961 -265.062508) (xy 347.724684 -265.099231) (xy 347.75521 -265.141247)
			(xy 347.778788 -265.187521) (xy 347.794836 -265.236914) (xy 347.802961 -265.288209) (xy 347.80347 -265.314176)
			(xy 347.802961 -265.340143) (xy 348.082871 -265.340143) (xy 348.082871 -265.288209) (xy 348.090996 -265.236914)
			(xy 348.107044 -265.187521) (xy 348.130622 -265.141247) (xy 348.161148 -265.099231) (xy 348.197871 -265.062508)
			(xy 348.239887 -265.031982) (xy 348.286161 -265.008404) (xy 348.335554 -264.992356) (xy 348.386849 -264.984231)
			(xy 348.438783 -264.984231) (xy 348.490078 -264.992356) (xy 348.539471 -265.008404) (xy 348.585745 -265.031982)
			(xy 348.627761 -265.062508) (xy 348.664484 -265.099231) (xy 348.69501 -265.141247) (xy 348.718588 -265.187521)
			(xy 348.734636 -265.236914) (xy 348.742761 -265.288209) (xy 348.74327 -265.314176) (xy 348.742761 -265.340143)
			(xy 349.022671 -265.340143) (xy 349.022671 -265.288209) (xy 349.030796 -265.236914) (xy 349.046844 -265.187521)
			(xy 349.070422 -265.141247) (xy 349.100948 -265.099231) (xy 349.137671 -265.062508) (xy 349.179687 -265.031982)
			(xy 349.225961 -265.008404) (xy 349.275354 -264.992356) (xy 349.326649 -264.984231) (xy 349.378583 -264.984231)
			(xy 349.429878 -264.992356) (xy 349.479271 -265.008404) (xy 349.525545 -265.031982) (xy 349.567561 -265.062508)
			(xy 349.604284 -265.099231) (xy 349.63481 -265.141247) (xy 349.658388 -265.187521) (xy 349.674436 -265.236914)
			(xy 349.682561 -265.288209) (xy 349.68307 -265.314176) (xy 349.682561 -265.340143) (xy 349.962471 -265.340143)
			(xy 349.962471 -265.288209) (xy 349.970596 -265.236914) (xy 349.986644 -265.187521) (xy 350.010222 -265.141247)
			(xy 350.040748 -265.099231) (xy 350.077471 -265.062508) (xy 350.119487 -265.031982) (xy 350.165761 -265.008404)
			(xy 350.215154 -264.992356) (xy 350.266449 -264.984231) (xy 350.318383 -264.984231) (xy 350.369678 -264.992356)
			(xy 350.419071 -265.008404) (xy 350.465345 -265.031982) (xy 350.507361 -265.062508) (xy 350.544084 -265.099231)
			(xy 350.57461 -265.141247) (xy 350.598188 -265.187521) (xy 350.614236 -265.236914) (xy 350.622361 -265.288209)
			(xy 350.62287 -265.314176) (xy 350.622361 -265.340143) (xy 350.902271 -265.340143) (xy 350.902271 -265.288209)
			(xy 350.910396 -265.236914) (xy 350.926444 -265.187521) (xy 350.950022 -265.141247) (xy 350.980548 -265.099231)
			(xy 351.017271 -265.062508) (xy 351.059287 -265.031982) (xy 351.105561 -265.008404) (xy 351.154954 -264.992356)
			(xy 351.206249 -264.984231) (xy 351.258183 -264.984231) (xy 351.309478 -264.992356) (xy 351.358871 -265.008404)
			(xy 351.405145 -265.031982) (xy 351.447161 -265.062508) (xy 351.483884 -265.099231) (xy 351.51441 -265.141247)
			(xy 351.537988 -265.187521) (xy 351.554036 -265.236914) (xy 351.562161 -265.288209) (xy 351.56267 -265.314176)
			(xy 351.562161 -265.340143) (xy 351.554036 -265.391438) (xy 351.537988 -265.440831) (xy 351.51441 -265.487105)
			(xy 351.483884 -265.529121) (xy 351.447161 -265.565844) (xy 351.405145 -265.59637) (xy 351.358871 -265.619948)
			(xy 351.309478 -265.635996) (xy 351.258183 -265.644121) (xy 351.206249 -265.644121) (xy 351.154954 -265.635996)
			(xy 351.105561 -265.619948) (xy 351.059287 -265.59637) (xy 351.017271 -265.565844) (xy 350.980548 -265.529121)
			(xy 350.950022 -265.487105) (xy 350.926444 -265.440831) (xy 350.910396 -265.391438) (xy 350.902271 -265.340143)
			(xy 350.622361 -265.340143) (xy 350.614236 -265.391438) (xy 350.598188 -265.440831) (xy 350.57461 -265.487105)
			(xy 350.544084 -265.529121) (xy 350.507361 -265.565844) (xy 350.465345 -265.59637) (xy 350.419071 -265.619948)
			(xy 350.369678 -265.635996) (xy 350.318383 -265.644121) (xy 350.266449 -265.644121) (xy 350.215154 -265.635996)
			(xy 350.165761 -265.619948) (xy 350.119487 -265.59637) (xy 350.077471 -265.565844) (xy 350.040748 -265.529121)
			(xy 350.010222 -265.487105) (xy 349.986644 -265.440831) (xy 349.970596 -265.391438) (xy 349.962471 -265.340143)
			(xy 349.682561 -265.340143) (xy 349.674436 -265.391438) (xy 349.658388 -265.440831) (xy 349.63481 -265.487105)
			(xy 349.604284 -265.529121) (xy 349.567561 -265.565844) (xy 349.525545 -265.59637) (xy 349.479271 -265.619948)
			(xy 349.429878 -265.635996) (xy 349.378583 -265.644121) (xy 349.326649 -265.644121) (xy 349.275354 -265.635996)
			(xy 349.225961 -265.619948) (xy 349.179687 -265.59637) (xy 349.137671 -265.565844) (xy 349.100948 -265.529121)
			(xy 349.070422 -265.487105) (xy 349.046844 -265.440831) (xy 349.030796 -265.391438) (xy 349.022671 -265.340143)
			(xy 348.742761 -265.340143) (xy 348.734636 -265.391438) (xy 348.718588 -265.440831) (xy 348.69501 -265.487105)
			(xy 348.664484 -265.529121) (xy 348.627761 -265.565844) (xy 348.585745 -265.59637) (xy 348.539471 -265.619948)
			(xy 348.490078 -265.635996) (xy 348.438783 -265.644121) (xy 348.386849 -265.644121) (xy 348.335554 -265.635996)
			(xy 348.286161 -265.619948) (xy 348.239887 -265.59637) (xy 348.197871 -265.565844) (xy 348.161148 -265.529121)
			(xy 348.130622 -265.487105) (xy 348.107044 -265.440831) (xy 348.090996 -265.391438) (xy 348.082871 -265.340143)
			(xy 347.802961 -265.340143) (xy 347.794836 -265.391438) (xy 347.778788 -265.440831) (xy 347.75521 -265.487105)
			(xy 347.724684 -265.529121) (xy 347.687961 -265.565844) (xy 347.645945 -265.59637) (xy 347.599671 -265.619948)
			(xy 347.550278 -265.635996) (xy 347.498983 -265.644121) (xy 347.447049 -265.644121) (xy 347.395754 -265.635996)
			(xy 347.346361 -265.619948) (xy 347.300087 -265.59637) (xy 347.258071 -265.565844) (xy 347.221348 -265.529121)
			(xy 347.190822 -265.487105) (xy 347.167244 -265.440831) (xy 347.151196 -265.391438) (xy 347.143071 -265.340143)
			(xy 346.862907 -265.340143) (xy 346.854782 -265.391438) (xy 346.838734 -265.440831) (xy 346.815156 -265.487105)
			(xy 346.78463 -265.529121) (xy 346.747907 -265.565844) (xy 346.705891 -265.59637) (xy 346.659617 -265.619948)
			(xy 346.610224 -265.635996) (xy 346.558929 -265.644121) (xy 346.506995 -265.644121) (xy 346.4557 -265.635996)
			(xy 346.406307 -265.619948) (xy 346.360033 -265.59637) (xy 346.318017 -265.565844) (xy 346.281294 -265.529121)
			(xy 346.250768 -265.487105) (xy 346.22719 -265.440831) (xy 346.211142 -265.391438) (xy 346.203017 -265.340143)
			(xy 345.923361 -265.340143) (xy 345.915236 -265.391438) (xy 345.899188 -265.440831) (xy 345.87561 -265.487105)
			(xy 345.845084 -265.529121) (xy 345.808361 -265.565844) (xy 345.766345 -265.59637) (xy 345.720071 -265.619948)
			(xy 345.670678 -265.635996) (xy 345.619383 -265.644121) (xy 345.567449 -265.644121) (xy 345.516154 -265.635996)
			(xy 345.466761 -265.619948) (xy 345.420487 -265.59637) (xy 345.378471 -265.565844) (xy 345.341748 -265.529121)
			(xy 345.311222 -265.487105) (xy 345.287644 -265.440831) (xy 345.271596 -265.391438) (xy 345.263471 -265.340143)
			(xy 344.983561 -265.340143) (xy 344.975436 -265.391438) (xy 344.959388 -265.440831) (xy 344.93581 -265.487105)
			(xy 344.905284 -265.529121) (xy 344.868561 -265.565844) (xy 344.826545 -265.59637) (xy 344.780271 -265.619948)
			(xy 344.730878 -265.635996) (xy 344.679583 -265.644121) (xy 344.627649 -265.644121) (xy 344.576354 -265.635996)
			(xy 344.526961 -265.619948) (xy 344.480687 -265.59637) (xy 344.438671 -265.565844) (xy 344.401948 -265.529121)
			(xy 344.371422 -265.487105) (xy 344.347844 -265.440831) (xy 344.331796 -265.391438) (xy 344.323671 -265.340143)
			(xy 344.043761 -265.340143) (xy 344.035636 -265.391438) (xy 344.019588 -265.440831) (xy 343.99601 -265.487105)
			(xy 343.965484 -265.529121) (xy 343.928761 -265.565844) (xy 343.886745 -265.59637) (xy 343.840471 -265.619948)
			(xy 343.791078 -265.635996) (xy 343.739783 -265.644121) (xy 343.687849 -265.644121) (xy 343.636554 -265.635996)
			(xy 343.587161 -265.619948) (xy 343.540887 -265.59637) (xy 343.498871 -265.565844) (xy 343.462148 -265.529121)
			(xy 343.431622 -265.487105) (xy 343.408044 -265.440831) (xy 343.391996 -265.391438) (xy 343.383871 -265.340143)
			(xy 343.103961 -265.340143) (xy 343.095836 -265.391438) (xy 343.079788 -265.440831) (xy 343.05621 -265.487105)
			(xy 343.025684 -265.529121) (xy 342.988961 -265.565844) (xy 342.946945 -265.59637) (xy 342.900671 -265.619948)
			(xy 342.851278 -265.635996) (xy 342.799983 -265.644121) (xy 342.748049 -265.644121) (xy 342.696754 -265.635996)
			(xy 342.647361 -265.619948) (xy 342.601087 -265.59637) (xy 342.559071 -265.565844) (xy 342.522348 -265.529121)
			(xy 342.491822 -265.487105) (xy 342.468244 -265.440831) (xy 342.452196 -265.391438) (xy 342.444071 -265.340143)
			(xy 342.164161 -265.340143) (xy 342.156036 -265.391438) (xy 342.139988 -265.440831) (xy 342.11641 -265.487105)
			(xy 342.085884 -265.529121) (xy 342.049161 -265.565844) (xy 342.007145 -265.59637) (xy 341.960871 -265.619948)
			(xy 341.911478 -265.635996) (xy 341.860183 -265.644121) (xy 341.808249 -265.644121) (xy 341.756954 -265.635996)
			(xy 341.707561 -265.619948) (xy 341.661287 -265.59637) (xy 341.619271 -265.565844) (xy 341.582548 -265.529121)
			(xy 341.552022 -265.487105) (xy 341.528444 -265.440831) (xy 341.512396 -265.391438) (xy 341.504271 -265.340143)
			(xy 341.224361 -265.340143) (xy 341.216236 -265.391438) (xy 341.200188 -265.440831) (xy 341.17661 -265.487105)
			(xy 341.146084 -265.529121) (xy 341.109361 -265.565844) (xy 341.067345 -265.59637) (xy 341.021071 -265.619948)
			(xy 340.971678 -265.635996) (xy 340.920383 -265.644121) (xy 340.868449 -265.644121) (xy 340.817154 -265.635996)
			(xy 340.767761 -265.619948) (xy 340.721487 -265.59637) (xy 340.679471 -265.565844) (xy 340.642748 -265.529121)
			(xy 340.612222 -265.487105) (xy 340.588644 -265.440831) (xy 340.572596 -265.391438) (xy 340.564471 -265.340143)
			(xy 340.284649 -265.340143) (xy 340.284649 -265.340193) (xy 340.276516 -265.391539) (xy 340.26045 -265.44098)
			(xy 340.236847 -265.487299) (xy 340.206289 -265.529356) (xy 340.169527 -265.566113) (xy 340.127467 -265.596667)
			(xy 340.081145 -265.620264) (xy 340.031702 -265.636325) (xy 339.980355 -265.644452) (xy 339.954362 -265.644884)
			(xy 339.954108 -265.644884) (xy 339.942896 -265.644794) (xy 339.920524 -265.64327) (xy 339.909404 -265.641836)
			(xy 339.905848 -265.641328) (xy 339.904324 -265.641328) (xy 339.87308 -265.635826) (xy 339.81335 -265.614473)
			(xy 339.785706 -265.59891) (xy 339.780118 -265.595608) (xy 339.75421 -265.588242) (xy 339.748194 -265.588365)
			(xy 339.736499 -265.591184) (xy 339.731096 -265.59383) (xy 339.709506 -265.605768) (xy 339.653118 -265.637264)
			(xy 339.645528 -265.641901) (xy 339.633963 -265.655398) (xy 339.62779 -265.672065) (xy 339.627464 -265.680952)
			(xy 339.627464 -265.800078) (xy 339.651848 -265.84275) (xy 339.662516 -265.849608) (xy 339.683763 -265.863731)
			(xy 339.722038 -265.897461) (xy 339.754676 -265.936672) (xy 339.7809 -265.980432) (xy 339.800089 -266.027702)
			(xy 339.811786 -266.07736) (xy 339.815714 -266.128225) (xy 339.813703 -266.154213) (xy 340.094317 -266.154213)
			(xy 340.094317 -266.102279) (xy 340.102442 -266.050984) (xy 340.11849 -266.001591) (xy 340.142068 -265.955317)
			(xy 340.172594 -265.913301) (xy 340.209317 -265.876578) (xy 340.251333 -265.846052) (xy 340.297607 -265.822474)
			(xy 340.347 -265.806426) (xy 340.398295 -265.798301) (xy 340.450229 -265.798301) (xy 340.501524 -265.806426)
			(xy 340.550917 -265.822474) (xy 340.597191 -265.846052) (xy 340.639207 -265.876578) (xy 340.67593 -265.913301)
			(xy 340.706456 -265.955317) (xy 340.730034 -266.001591) (xy 340.746082 -266.050984) (xy 340.754207 -266.102279)
			(xy 340.754716 -266.128246) (xy 340.754207 -266.154213) (xy 341.034117 -266.154213) (xy 341.034117 -266.102279)
			(xy 341.042242 -266.050984) (xy 341.05829 -266.001591) (xy 341.081868 -265.955317) (xy 341.112394 -265.913301)
			(xy 341.149117 -265.876578) (xy 341.191133 -265.846052) (xy 341.237407 -265.822474) (xy 341.2868 -265.806426)
			(xy 341.338095 -265.798301) (xy 341.390029 -265.798301) (xy 341.441324 -265.806426) (xy 341.490717 -265.822474)
			(xy 341.536991 -265.846052) (xy 341.579007 -265.876578) (xy 341.61573 -265.913301) (xy 341.646256 -265.955317)
			(xy 341.669834 -266.001591) (xy 341.685882 -266.050984) (xy 341.694007 -266.102279) (xy 341.694516 -266.128246)
			(xy 341.694007 -266.154213) (xy 341.973917 -266.154213) (xy 341.973917 -266.102279) (xy 341.982042 -266.050984)
			(xy 341.99809 -266.001591) (xy 342.021668 -265.955317) (xy 342.052194 -265.913301) (xy 342.088917 -265.876578)
			(xy 342.130933 -265.846052) (xy 342.177207 -265.822474) (xy 342.2266 -265.806426) (xy 342.277895 -265.798301)
			(xy 342.329829 -265.798301) (xy 342.381124 -265.806426) (xy 342.430517 -265.822474) (xy 342.476791 -265.846052)
			(xy 342.518807 -265.876578) (xy 342.55553 -265.913301) (xy 342.586056 -265.955317) (xy 342.609634 -266.001591)
			(xy 342.625682 -266.050984) (xy 342.633807 -266.102279) (xy 342.634316 -266.128246) (xy 342.633807 -266.154213)
			(xy 342.913717 -266.154213) (xy 342.913717 -266.102279) (xy 342.921842 -266.050984) (xy 342.93789 -266.001591)
			(xy 342.961468 -265.955317) (xy 342.991994 -265.913301) (xy 343.028717 -265.876578) (xy 343.070733 -265.846052)
			(xy 343.117007 -265.822474) (xy 343.1664 -265.806426) (xy 343.217695 -265.798301) (xy 343.269629 -265.798301)
			(xy 343.320924 -265.806426) (xy 343.370317 -265.822474) (xy 343.416591 -265.846052) (xy 343.458607 -265.876578)
			(xy 343.49533 -265.913301) (xy 343.525856 -265.955317) (xy 343.549434 -266.001591) (xy 343.565482 -266.050984)
			(xy 343.573607 -266.102279) (xy 343.574116 -266.128246) (xy 343.573607 -266.154213) (xy 343.853517 -266.154213)
			(xy 343.853517 -266.102279) (xy 343.861642 -266.050984) (xy 343.87769 -266.001591) (xy 343.901268 -265.955317)
			(xy 343.931794 -265.913301) (xy 343.968517 -265.876578) (xy 344.010533 -265.846052) (xy 344.056807 -265.822474)
			(xy 344.1062 -265.806426) (xy 344.157495 -265.798301) (xy 344.209429 -265.798301) (xy 344.260724 -265.806426)
			(xy 344.310117 -265.822474) (xy 344.356391 -265.846052) (xy 344.398407 -265.876578) (xy 344.43513 -265.913301)
			(xy 344.465656 -265.955317) (xy 344.489234 -266.001591) (xy 344.505282 -266.050984) (xy 344.513407 -266.102279)
			(xy 344.513916 -266.128246) (xy 344.513407 -266.154213) (xy 344.793317 -266.154213) (xy 344.793317 -266.102279)
			(xy 344.801442 -266.050984) (xy 344.81749 -266.001591) (xy 344.841068 -265.955317) (xy 344.871594 -265.913301)
			(xy 344.908317 -265.876578) (xy 344.950333 -265.846052) (xy 344.996607 -265.822474) (xy 345.046 -265.806426)
			(xy 345.097295 -265.798301) (xy 345.149229 -265.798301) (xy 345.200524 -265.806426) (xy 345.249917 -265.822474)
			(xy 345.296191 -265.846052) (xy 345.338207 -265.876578) (xy 345.37493 -265.913301) (xy 345.405456 -265.955317)
			(xy 345.429034 -266.001591) (xy 345.445082 -266.050984) (xy 345.453207 -266.102279) (xy 345.453716 -266.128246)
			(xy 345.453207 -266.154213) (xy 345.733117 -266.154213) (xy 345.733117 -266.102279) (xy 345.741242 -266.050984)
			(xy 345.75729 -266.001591) (xy 345.780868 -265.955317) (xy 345.811394 -265.913301) (xy 345.848117 -265.876578)
			(xy 345.890133 -265.846052) (xy 345.936407 -265.822474) (xy 345.9858 -265.806426) (xy 346.037095 -265.798301)
			(xy 346.089029 -265.798301) (xy 346.140324 -265.806426) (xy 346.189717 -265.822474) (xy 346.235991 -265.846052)
			(xy 346.278007 -265.876578) (xy 346.31473 -265.913301) (xy 346.345256 -265.955317) (xy 346.368834 -266.001591)
			(xy 346.384882 -266.050984) (xy 346.393007 -266.102279) (xy 346.393516 -266.128246) (xy 346.393007 -266.154213)
			(xy 346.672917 -266.154213) (xy 346.672917 -266.102279) (xy 346.681042 -266.050984) (xy 346.69709 -266.001591)
			(xy 346.720668 -265.955317) (xy 346.751194 -265.913301) (xy 346.787917 -265.876578) (xy 346.829933 -265.846052)
			(xy 346.876207 -265.822474) (xy 346.9256 -265.806426) (xy 346.976895 -265.798301) (xy 347.028829 -265.798301)
			(xy 347.080124 -265.806426) (xy 347.129517 -265.822474) (xy 347.175791 -265.846052) (xy 347.217807 -265.876578)
			(xy 347.25453 -265.913301) (xy 347.285056 -265.955317) (xy 347.308634 -266.001591) (xy 347.324682 -266.050984)
			(xy 347.332807 -266.102279) (xy 347.333316 -266.128246) (xy 347.332807 -266.154213) (xy 347.612717 -266.154213)
			(xy 347.612717 -266.102279) (xy 347.620842 -266.050984) (xy 347.63689 -266.001591) (xy 347.660468 -265.955317)
			(xy 347.690994 -265.913301) (xy 347.727717 -265.876578) (xy 347.769733 -265.846052) (xy 347.816007 -265.822474)
			(xy 347.8654 -265.806426) (xy 347.916695 -265.798301) (xy 347.968629 -265.798301) (xy 348.019924 -265.806426)
			(xy 348.069317 -265.822474) (xy 348.115591 -265.846052) (xy 348.157607 -265.876578) (xy 348.19433 -265.913301)
			(xy 348.224856 -265.955317) (xy 348.248434 -266.001591) (xy 348.264482 -266.050984) (xy 348.272607 -266.102279)
			(xy 348.273116 -266.128246) (xy 348.272607 -266.154213) (xy 348.552517 -266.154213) (xy 348.552517 -266.102279)
			(xy 348.560642 -266.050984) (xy 348.57669 -266.001591) (xy 348.600268 -265.955317) (xy 348.630794 -265.913301)
			(xy 348.667517 -265.876578) (xy 348.709533 -265.846052) (xy 348.755807 -265.822474) (xy 348.8052 -265.806426)
			(xy 348.856495 -265.798301) (xy 348.908429 -265.798301) (xy 348.959724 -265.806426) (xy 349.009117 -265.822474)
			(xy 349.055391 -265.846052) (xy 349.097407 -265.876578) (xy 349.13413 -265.913301) (xy 349.164656 -265.955317)
			(xy 349.188234 -266.001591) (xy 349.204282 -266.050984) (xy 349.212407 -266.102279) (xy 349.212916 -266.128246)
			(xy 349.212407 -266.154213) (xy 349.492317 -266.154213) (xy 349.492317 -266.102279) (xy 349.500442 -266.050984)
			(xy 349.51649 -266.001591) (xy 349.540068 -265.955317) (xy 349.570594 -265.913301) (xy 349.607317 -265.876578)
			(xy 349.649333 -265.846052) (xy 349.695607 -265.822474) (xy 349.745 -265.806426) (xy 349.796295 -265.798301)
			(xy 349.848229 -265.798301) (xy 349.899524 -265.806426) (xy 349.948917 -265.822474) (xy 349.995191 -265.846052)
			(xy 350.037207 -265.876578) (xy 350.07393 -265.913301) (xy 350.104456 -265.955317) (xy 350.128034 -266.001591)
			(xy 350.144082 -266.050984) (xy 350.152207 -266.102279) (xy 350.152716 -266.128246) (xy 350.152207 -266.154213)
			(xy 350.432117 -266.154213) (xy 350.432117 -266.102279) (xy 350.440242 -266.050984) (xy 350.45629 -266.001591)
			(xy 350.479868 -265.955317) (xy 350.510394 -265.913301) (xy 350.547117 -265.876578) (xy 350.589133 -265.846052)
			(xy 350.635407 -265.822474) (xy 350.6848 -265.806426) (xy 350.736095 -265.798301) (xy 350.788029 -265.798301)
			(xy 350.839324 -265.806426) (xy 350.888717 -265.822474) (xy 350.934991 -265.846052) (xy 350.977007 -265.876578)
			(xy 351.01373 -265.913301) (xy 351.044256 -265.955317) (xy 351.067834 -266.001591) (xy 351.083882 -266.050984)
			(xy 351.092007 -266.102279) (xy 351.092516 -266.128246) (xy 351.092007 -266.154213) (xy 351.083882 -266.205508)
			(xy 351.067834 -266.254901) (xy 351.044256 -266.301175) (xy 351.01373 -266.343191) (xy 350.977007 -266.379914)
			(xy 350.934991 -266.41044) (xy 350.888717 -266.434018) (xy 350.839324 -266.450066) (xy 350.788029 -266.458191)
			(xy 350.736095 -266.458191) (xy 350.6848 -266.450066) (xy 350.635407 -266.434018) (xy 350.589133 -266.41044)
			(xy 350.547117 -266.379914) (xy 350.510394 -266.343191) (xy 350.479868 -266.301175) (xy 350.45629 -266.254901)
			(xy 350.440242 -266.205508) (xy 350.432117 -266.154213) (xy 350.152207 -266.154213) (xy 350.144082 -266.205508)
			(xy 350.128034 -266.254901) (xy 350.104456 -266.301175) (xy 350.07393 -266.343191) (xy 350.037207 -266.379914)
			(xy 349.995191 -266.41044) (xy 349.948917 -266.434018) (xy 349.899524 -266.450066) (xy 349.848229 -266.458191)
			(xy 349.796295 -266.458191) (xy 349.745 -266.450066) (xy 349.695607 -266.434018) (xy 349.649333 -266.41044)
			(xy 349.607317 -266.379914) (xy 349.570594 -266.343191) (xy 349.540068 -266.301175) (xy 349.51649 -266.254901)
			(xy 349.500442 -266.205508) (xy 349.492317 -266.154213) (xy 349.212407 -266.154213) (xy 349.204282 -266.205508)
			(xy 349.188234 -266.254901) (xy 349.164656 -266.301175) (xy 349.13413 -266.343191) (xy 349.097407 -266.379914)
			(xy 349.055391 -266.41044) (xy 349.009117 -266.434018) (xy 348.959724 -266.450066) (xy 348.908429 -266.458191)
			(xy 348.856495 -266.458191) (xy 348.8052 -266.450066) (xy 348.755807 -266.434018) (xy 348.709533 -266.41044)
			(xy 348.667517 -266.379914) (xy 348.630794 -266.343191) (xy 348.600268 -266.301175) (xy 348.57669 -266.254901)
			(xy 348.560642 -266.205508) (xy 348.552517 -266.154213) (xy 348.272607 -266.154213) (xy 348.264482 -266.205508)
			(xy 348.248434 -266.254901) (xy 348.224856 -266.301175) (xy 348.19433 -266.343191) (xy 348.157607 -266.379914)
			(xy 348.115591 -266.41044) (xy 348.069317 -266.434018) (xy 348.019924 -266.450066) (xy 347.968629 -266.458191)
			(xy 347.916695 -266.458191) (xy 347.8654 -266.450066) (xy 347.816007 -266.434018) (xy 347.769733 -266.41044)
			(xy 347.727717 -266.379914) (xy 347.690994 -266.343191) (xy 347.660468 -266.301175) (xy 347.63689 -266.254901)
			(xy 347.620842 -266.205508) (xy 347.612717 -266.154213) (xy 347.332807 -266.154213) (xy 347.324682 -266.205508)
			(xy 347.308634 -266.254901) (xy 347.285056 -266.301175) (xy 347.25453 -266.343191) (xy 347.217807 -266.379914)
			(xy 347.175791 -266.41044) (xy 347.129517 -266.434018) (xy 347.080124 -266.450066) (xy 347.028829 -266.458191)
			(xy 346.976895 -266.458191) (xy 346.9256 -266.450066) (xy 346.876207 -266.434018) (xy 346.829933 -266.41044)
			(xy 346.787917 -266.379914) (xy 346.751194 -266.343191) (xy 346.720668 -266.301175) (xy 346.69709 -266.254901)
			(xy 346.681042 -266.205508) (xy 346.672917 -266.154213) (xy 346.393007 -266.154213) (xy 346.384882 -266.205508)
			(xy 346.368834 -266.254901) (xy 346.345256 -266.301175) (xy 346.31473 -266.343191) (xy 346.278007 -266.379914)
			(xy 346.235991 -266.41044) (xy 346.189717 -266.434018) (xy 346.140324 -266.450066) (xy 346.089029 -266.458191)
			(xy 346.037095 -266.458191) (xy 345.9858 -266.450066) (xy 345.936407 -266.434018) (xy 345.890133 -266.41044)
			(xy 345.848117 -266.379914) (xy 345.811394 -266.343191) (xy 345.780868 -266.301175) (xy 345.75729 -266.254901)
			(xy 345.741242 -266.205508) (xy 345.733117 -266.154213) (xy 345.453207 -266.154213) (xy 345.445082 -266.205508)
			(xy 345.429034 -266.254901) (xy 345.405456 -266.301175) (xy 345.37493 -266.343191) (xy 345.338207 -266.379914)
			(xy 345.296191 -266.41044) (xy 345.249917 -266.434018) (xy 345.200524 -266.450066) (xy 345.149229 -266.458191)
			(xy 345.097295 -266.458191) (xy 345.046 -266.450066) (xy 344.996607 -266.434018) (xy 344.950333 -266.41044)
			(xy 344.908317 -266.379914) (xy 344.871594 -266.343191) (xy 344.841068 -266.301175) (xy 344.81749 -266.254901)
			(xy 344.801442 -266.205508) (xy 344.793317 -266.154213) (xy 344.513407 -266.154213) (xy 344.505282 -266.205508)
			(xy 344.489234 -266.254901) (xy 344.465656 -266.301175) (xy 344.43513 -266.343191) (xy 344.398407 -266.379914)
			(xy 344.356391 -266.41044) (xy 344.310117 -266.434018) (xy 344.260724 -266.450066) (xy 344.209429 -266.458191)
			(xy 344.157495 -266.458191) (xy 344.1062 -266.450066) (xy 344.056807 -266.434018) (xy 344.010533 -266.41044)
			(xy 343.968517 -266.379914) (xy 343.931794 -266.343191) (xy 343.901268 -266.301175) (xy 343.87769 -266.254901)
			(xy 343.861642 -266.205508) (xy 343.853517 -266.154213) (xy 343.573607 -266.154213) (xy 343.565482 -266.205508)
			(xy 343.549434 -266.254901) (xy 343.525856 -266.301175) (xy 343.49533 -266.343191) (xy 343.458607 -266.379914)
			(xy 343.416591 -266.41044) (xy 343.370317 -266.434018) (xy 343.320924 -266.450066) (xy 343.269629 -266.458191)
			(xy 343.217695 -266.458191) (xy 343.1664 -266.450066) (xy 343.117007 -266.434018) (xy 343.070733 -266.41044)
			(xy 343.028717 -266.379914) (xy 342.991994 -266.343191) (xy 342.961468 -266.301175) (xy 342.93789 -266.254901)
			(xy 342.921842 -266.205508) (xy 342.913717 -266.154213) (xy 342.633807 -266.154213) (xy 342.625682 -266.205508)
			(xy 342.609634 -266.254901) (xy 342.586056 -266.301175) (xy 342.55553 -266.343191) (xy 342.518807 -266.379914)
			(xy 342.476791 -266.41044) (xy 342.430517 -266.434018) (xy 342.381124 -266.450066) (xy 342.329829 -266.458191)
			(xy 342.277895 -266.458191) (xy 342.2266 -266.450066) (xy 342.177207 -266.434018) (xy 342.130933 -266.41044)
			(xy 342.088917 -266.379914) (xy 342.052194 -266.343191) (xy 342.021668 -266.301175) (xy 341.99809 -266.254901)
			(xy 341.982042 -266.205508) (xy 341.973917 -266.154213) (xy 341.694007 -266.154213) (xy 341.685882 -266.205508)
			(xy 341.669834 -266.254901) (xy 341.646256 -266.301175) (xy 341.61573 -266.343191) (xy 341.579007 -266.379914)
			(xy 341.536991 -266.41044) (xy 341.490717 -266.434018) (xy 341.441324 -266.450066) (xy 341.390029 -266.458191)
			(xy 341.338095 -266.458191) (xy 341.2868 -266.450066) (xy 341.237407 -266.434018) (xy 341.191133 -266.41044)
			(xy 341.149117 -266.379914) (xy 341.112394 -266.343191) (xy 341.081868 -266.301175) (xy 341.05829 -266.254901)
			(xy 341.042242 -266.205508) (xy 341.034117 -266.154213) (xy 340.754207 -266.154213) (xy 340.746082 -266.205508)
			(xy 340.730034 -266.254901) (xy 340.706456 -266.301175) (xy 340.67593 -266.343191) (xy 340.639207 -266.379914)
			(xy 340.597191 -266.41044) (xy 340.550917 -266.434018) (xy 340.501524 -266.450066) (xy 340.450229 -266.458191)
			(xy 340.398295 -266.458191) (xy 340.347 -266.450066) (xy 340.297607 -266.434018) (xy 340.251333 -266.41044)
			(xy 340.209317 -266.379914) (xy 340.172594 -266.343191) (xy 340.142068 -266.301175) (xy 340.11849 -266.254901)
			(xy 340.102442 -266.205508) (xy 340.094317 -266.154213) (xy 339.813703 -266.154213) (xy 339.811778 -266.179089)
			(xy 339.800074 -266.228745) (xy 339.780878 -266.276013) (xy 339.754647 -266.319769) (xy 339.722004 -266.358975)
			(xy 339.683724 -266.392699) (xy 339.662516 -266.406884) (xy 339.651848 -266.413742) (xy 339.627464 -266.456414)
			(xy 339.627464 -266.575286) (xy 339.627778 -266.583673) (xy 339.633276 -266.59952) (xy 339.643668 -266.612687)
			(xy 339.650578 -266.61745) (xy 339.718142 -266.655296) (xy 339.723391 -266.657786) (xy 339.734687 -266.660486)
			(xy 339.740494 -266.66063) (xy 339.76691 -266.66063) (xy 339.791294 -266.654026) (xy 339.795612 -266.65174)
			(xy 339.820105 -266.638972) (xy 339.872286 -266.620869) (xy 339.926746 -266.611671) (xy 339.954362 -266.6111)
			(xy 339.954616 -266.6111) (xy 339.980602 -266.611611) (xy 340.031933 -266.619743) (xy 340.08136 -266.635805)
			(xy 340.127666 -266.659401) (xy 340.169711 -266.689951) (xy 340.20646 -266.726701) (xy 340.237007 -266.768747)
			(xy 340.260601 -266.815055) (xy 340.276661 -266.864483) (xy 340.284791 -266.915814) (xy 340.284791 -266.967775)
			(xy 340.564471 -266.967775) (xy 340.564471 -266.915841) (xy 340.572596 -266.864546) (xy 340.588644 -266.815153)
			(xy 340.612222 -266.768879) (xy 340.642748 -266.726863) (xy 340.679471 -266.69014) (xy 340.721487 -266.659614)
			(xy 340.767761 -266.636036) (xy 340.817154 -266.619988) (xy 340.868449 -266.611863) (xy 340.920383 -266.611863)
			(xy 340.971678 -266.619988) (xy 341.021071 -266.636036) (xy 341.067345 -266.659614) (xy 341.109361 -266.69014)
			(xy 341.146084 -266.726863) (xy 341.17661 -266.768879) (xy 341.200188 -266.815153) (xy 341.216236 -266.864546)
			(xy 341.224361 -266.915841) (xy 341.22487 -266.941808) (xy 341.224361 -266.967775) (xy 341.504271 -266.967775)
			(xy 341.504271 -266.915841) (xy 341.512396 -266.864546) (xy 341.528444 -266.815153) (xy 341.552022 -266.768879)
			(xy 341.582548 -266.726863) (xy 341.619271 -266.69014) (xy 341.661287 -266.659614) (xy 341.707561 -266.636036)
			(xy 341.756954 -266.619988) (xy 341.808249 -266.611863) (xy 341.860183 -266.611863) (xy 341.911478 -266.619988)
			(xy 341.960871 -266.636036) (xy 342.007145 -266.659614) (xy 342.049161 -266.69014) (xy 342.085884 -266.726863)
			(xy 342.11641 -266.768879) (xy 342.139988 -266.815153) (xy 342.156036 -266.864546) (xy 342.164161 -266.915841)
			(xy 342.16467 -266.941808) (xy 342.164161 -266.967775) (xy 342.444071 -266.967775) (xy 342.444071 -266.915841)
			(xy 342.452196 -266.864546) (xy 342.468244 -266.815153) (xy 342.491822 -266.768879) (xy 342.522348 -266.726863)
			(xy 342.559071 -266.69014) (xy 342.601087 -266.659614) (xy 342.647361 -266.636036) (xy 342.696754 -266.619988)
			(xy 342.748049 -266.611863) (xy 342.799983 -266.611863) (xy 342.851278 -266.619988) (xy 342.900671 -266.636036)
			(xy 342.946945 -266.659614) (xy 342.988961 -266.69014) (xy 343.025684 -266.726863) (xy 343.05621 -266.768879)
			(xy 343.079788 -266.815153) (xy 343.095836 -266.864546) (xy 343.103961 -266.915841) (xy 343.10447 -266.941808)
			(xy 343.103961 -266.967775) (xy 343.383871 -266.967775) (xy 343.383871 -266.915841) (xy 343.391996 -266.864546)
			(xy 343.408044 -266.815153) (xy 343.431622 -266.768879) (xy 343.462148 -266.726863) (xy 343.498871 -266.69014)
			(xy 343.540887 -266.659614) (xy 343.587161 -266.636036) (xy 343.636554 -266.619988) (xy 343.687849 -266.611863)
			(xy 343.739783 -266.611863) (xy 343.791078 -266.619988) (xy 343.840471 -266.636036) (xy 343.886745 -266.659614)
			(xy 343.928761 -266.69014) (xy 343.965484 -266.726863) (xy 343.99601 -266.768879) (xy 344.019588 -266.815153)
			(xy 344.035636 -266.864546) (xy 344.043761 -266.915841) (xy 344.04427 -266.941808) (xy 344.043761 -266.967775)
			(xy 344.323671 -266.967775) (xy 344.323671 -266.915841) (xy 344.331796 -266.864546) (xy 344.347844 -266.815153)
			(xy 344.371422 -266.768879) (xy 344.401948 -266.726863) (xy 344.438671 -266.69014) (xy 344.480687 -266.659614)
			(xy 344.526961 -266.636036) (xy 344.576354 -266.619988) (xy 344.627649 -266.611863) (xy 344.679583 -266.611863)
			(xy 344.730878 -266.619988) (xy 344.780271 -266.636036) (xy 344.826545 -266.659614) (xy 344.868561 -266.69014)
			(xy 344.905284 -266.726863) (xy 344.93581 -266.768879) (xy 344.959388 -266.815153) (xy 344.975436 -266.864546)
			(xy 344.983561 -266.915841) (xy 344.98407 -266.941808) (xy 344.983561 -266.967775) (xy 345.263217 -266.967775)
			(xy 345.263217 -266.915841) (xy 345.271342 -266.864546) (xy 345.28739 -266.815153) (xy 345.310968 -266.768879)
			(xy 345.341494 -266.726863) (xy 345.378217 -266.69014) (xy 345.420233 -266.659614) (xy 345.466507 -266.636036)
			(xy 345.5159 -266.619988) (xy 345.567195 -266.611863) (xy 345.619129 -266.611863) (xy 345.670424 -266.619988)
			(xy 345.719817 -266.636036) (xy 345.766091 -266.659614) (xy 345.808107 -266.69014) (xy 345.84483 -266.726863)
			(xy 345.875356 -266.768879) (xy 345.898934 -266.815153) (xy 345.914982 -266.864546) (xy 345.923107 -266.915841)
			(xy 345.923616 -266.941808) (xy 345.923107 -266.967775) (xy 346.203271 -266.967775) (xy 346.203271 -266.915841)
			(xy 346.211396 -266.864546) (xy 346.227444 -266.815153) (xy 346.251022 -266.768879) (xy 346.281548 -266.726863)
			(xy 346.318271 -266.69014) (xy 346.360287 -266.659614) (xy 346.406561 -266.636036) (xy 346.455954 -266.619988)
			(xy 346.507249 -266.611863) (xy 346.559183 -266.611863) (xy 346.610478 -266.619988) (xy 346.659871 -266.636036)
			(xy 346.706145 -266.659614) (xy 346.748161 -266.69014) (xy 346.784884 -266.726863) (xy 346.81541 -266.768879)
			(xy 346.838988 -266.815153) (xy 346.855036 -266.864546) (xy 346.863161 -266.915841) (xy 346.86367 -266.941808)
			(xy 346.863161 -266.967775) (xy 347.143071 -266.967775) (xy 347.143071 -266.915841) (xy 347.151196 -266.864546)
			(xy 347.167244 -266.815153) (xy 347.190822 -266.768879) (xy 347.221348 -266.726863) (xy 347.258071 -266.69014)
			(xy 347.300087 -266.659614) (xy 347.346361 -266.636036) (xy 347.395754 -266.619988) (xy 347.447049 -266.611863)
			(xy 347.498983 -266.611863) (xy 347.550278 -266.619988) (xy 347.599671 -266.636036) (xy 347.645945 -266.659614)
			(xy 347.687961 -266.69014) (xy 347.724684 -266.726863) (xy 347.75521 -266.768879) (xy 347.778788 -266.815153)
			(xy 347.794836 -266.864546) (xy 347.802961 -266.915841) (xy 347.80347 -266.941808) (xy 347.802961 -266.967775)
			(xy 348.082871 -266.967775) (xy 348.082871 -266.915841) (xy 348.090996 -266.864546) (xy 348.107044 -266.815153)
			(xy 348.130622 -266.768879) (xy 348.161148 -266.726863) (xy 348.197871 -266.69014) (xy 348.239887 -266.659614)
			(xy 348.286161 -266.636036) (xy 348.335554 -266.619988) (xy 348.386849 -266.611863) (xy 348.438783 -266.611863)
			(xy 348.490078 -266.619988) (xy 348.539471 -266.636036) (xy 348.585745 -266.659614) (xy 348.627761 -266.69014)
			(xy 348.664484 -266.726863) (xy 348.69501 -266.768879) (xy 348.718588 -266.815153) (xy 348.734636 -266.864546)
			(xy 348.742761 -266.915841) (xy 348.74327 -266.941808) (xy 348.742761 -266.967775) (xy 349.022671 -266.967775)
			(xy 349.022671 -266.915841) (xy 349.030796 -266.864546) (xy 349.046844 -266.815153) (xy 349.070422 -266.768879)
			(xy 349.100948 -266.726863) (xy 349.137671 -266.69014) (xy 349.179687 -266.659614) (xy 349.225961 -266.636036)
			(xy 349.275354 -266.619988) (xy 349.326649 -266.611863) (xy 349.378583 -266.611863) (xy 349.429878 -266.619988)
			(xy 349.479271 -266.636036) (xy 349.525545 -266.659614) (xy 349.567561 -266.69014) (xy 349.604284 -266.726863)
			(xy 349.63481 -266.768879) (xy 349.658388 -266.815153) (xy 349.674436 -266.864546) (xy 349.682561 -266.915841)
			(xy 349.68307 -266.941808) (xy 349.682561 -266.967775) (xy 349.962471 -266.967775) (xy 349.962471 -266.915841)
			(xy 349.970596 -266.864546) (xy 349.986644 -266.815153) (xy 350.010222 -266.768879) (xy 350.040748 -266.726863)
			(xy 350.077471 -266.69014) (xy 350.119487 -266.659614) (xy 350.165761 -266.636036) (xy 350.215154 -266.619988)
			(xy 350.266449 -266.611863) (xy 350.318383 -266.611863) (xy 350.369678 -266.619988) (xy 350.419071 -266.636036)
			(xy 350.465345 -266.659614) (xy 350.507361 -266.69014) (xy 350.544084 -266.726863) (xy 350.57461 -266.768879)
			(xy 350.598188 -266.815153) (xy 350.614236 -266.864546) (xy 350.622361 -266.915841) (xy 350.62287 -266.941808)
			(xy 350.622361 -266.967775) (xy 350.902271 -266.967775) (xy 350.902271 -266.915841) (xy 350.910396 -266.864546)
			(xy 350.926444 -266.815153) (xy 350.950022 -266.768879) (xy 350.980548 -266.726863) (xy 351.017271 -266.69014)
			(xy 351.059287 -266.659614) (xy 351.105561 -266.636036) (xy 351.154954 -266.619988) (xy 351.206249 -266.611863)
			(xy 351.258183 -266.611863) (xy 351.309478 -266.619988) (xy 351.358871 -266.636036) (xy 351.405145 -266.659614)
			(xy 351.447161 -266.69014) (xy 351.483884 -266.726863) (xy 351.51441 -266.768879) (xy 351.537988 -266.815153)
			(xy 351.554036 -266.864546) (xy 351.562161 -266.915841) (xy 351.56267 -266.941808) (xy 351.562161 -266.967775)
			(xy 351.554036 -267.01907) (xy 351.537988 -267.068463) (xy 351.51441 -267.114737) (xy 351.483884 -267.156753)
			(xy 351.447161 -267.193476) (xy 351.405145 -267.224002) (xy 351.358871 -267.24758) (xy 351.309478 -267.263628)
			(xy 351.258183 -267.271753) (xy 351.206249 -267.271753) (xy 351.154954 -267.263628) (xy 351.105561 -267.24758)
			(xy 351.059287 -267.224002) (xy 351.017271 -267.193476) (xy 350.980548 -267.156753) (xy 350.950022 -267.114737)
			(xy 350.926444 -267.068463) (xy 350.910396 -267.01907) (xy 350.902271 -266.967775) (xy 350.622361 -266.967775)
			(xy 350.614236 -267.01907) (xy 350.598188 -267.068463) (xy 350.57461 -267.114737) (xy 350.544084 -267.156753)
			(xy 350.507361 -267.193476) (xy 350.465345 -267.224002) (xy 350.419071 -267.24758) (xy 350.369678 -267.263628)
			(xy 350.318383 -267.271753) (xy 350.266449 -267.271753) (xy 350.215154 -267.263628) (xy 350.165761 -267.24758)
			(xy 350.119487 -267.224002) (xy 350.077471 -267.193476) (xy 350.040748 -267.156753) (xy 350.010222 -267.114737)
			(xy 349.986644 -267.068463) (xy 349.970596 -267.01907) (xy 349.962471 -266.967775) (xy 349.682561 -266.967775)
			(xy 349.674436 -267.01907) (xy 349.658388 -267.068463) (xy 349.63481 -267.114737) (xy 349.604284 -267.156753)
			(xy 349.567561 -267.193476) (xy 349.525545 -267.224002) (xy 349.479271 -267.24758) (xy 349.429878 -267.263628)
			(xy 349.378583 -267.271753) (xy 349.326649 -267.271753) (xy 349.275354 -267.263628) (xy 349.225961 -267.24758)
			(xy 349.179687 -267.224002) (xy 349.137671 -267.193476) (xy 349.100948 -267.156753) (xy 349.070422 -267.114737)
			(xy 349.046844 -267.068463) (xy 349.030796 -267.01907) (xy 349.022671 -266.967775) (xy 348.742761 -266.967775)
			(xy 348.734636 -267.01907) (xy 348.718588 -267.068463) (xy 348.69501 -267.114737) (xy 348.664484 -267.156753)
			(xy 348.627761 -267.193476) (xy 348.585745 -267.224002) (xy 348.539471 -267.24758) (xy 348.490078 -267.263628)
			(xy 348.438783 -267.271753) (xy 348.386849 -267.271753) (xy 348.335554 -267.263628) (xy 348.286161 -267.24758)
			(xy 348.239887 -267.224002) (xy 348.197871 -267.193476) (xy 348.161148 -267.156753) (xy 348.130622 -267.114737)
			(xy 348.107044 -267.068463) (xy 348.090996 -267.01907) (xy 348.082871 -266.967775) (xy 347.802961 -266.967775)
			(xy 347.794836 -267.01907) (xy 347.778788 -267.068463) (xy 347.75521 -267.114737) (xy 347.724684 -267.156753)
			(xy 347.687961 -267.193476) (xy 347.645945 -267.224002) (xy 347.599671 -267.24758) (xy 347.550278 -267.263628)
			(xy 347.498983 -267.271753) (xy 347.447049 -267.271753) (xy 347.395754 -267.263628) (xy 347.346361 -267.24758)
			(xy 347.300087 -267.224002) (xy 347.258071 -267.193476) (xy 347.221348 -267.156753) (xy 347.190822 -267.114737)
			(xy 347.167244 -267.068463) (xy 347.151196 -267.01907) (xy 347.143071 -266.967775) (xy 346.863161 -266.967775)
			(xy 346.855036 -267.01907) (xy 346.838988 -267.068463) (xy 346.81541 -267.114737) (xy 346.784884 -267.156753)
			(xy 346.748161 -267.193476) (xy 346.706145 -267.224002) (xy 346.659871 -267.24758) (xy 346.610478 -267.263628)
			(xy 346.559183 -267.271753) (xy 346.507249 -267.271753) (xy 346.455954 -267.263628) (xy 346.406561 -267.24758)
			(xy 346.360287 -267.224002) (xy 346.318271 -267.193476) (xy 346.281548 -267.156753) (xy 346.251022 -267.114737)
			(xy 346.227444 -267.068463) (xy 346.211396 -267.01907) (xy 346.203271 -266.967775) (xy 345.923107 -266.967775)
			(xy 345.914982 -267.01907) (xy 345.898934 -267.068463) (xy 345.875356 -267.114737) (xy 345.84483 -267.156753)
			(xy 345.808107 -267.193476) (xy 345.766091 -267.224002) (xy 345.719817 -267.24758) (xy 345.670424 -267.263628)
			(xy 345.619129 -267.271753) (xy 345.567195 -267.271753) (xy 345.5159 -267.263628) (xy 345.466507 -267.24758)
			(xy 345.420233 -267.224002) (xy 345.378217 -267.193476) (xy 345.341494 -267.156753) (xy 345.310968 -267.114737)
			(xy 345.28739 -267.068463) (xy 345.271342 -267.01907) (xy 345.263217 -266.967775) (xy 344.983561 -266.967775)
			(xy 344.975436 -267.01907) (xy 344.959388 -267.068463) (xy 344.93581 -267.114737) (xy 344.905284 -267.156753)
			(xy 344.868561 -267.193476) (xy 344.826545 -267.224002) (xy 344.780271 -267.24758) (xy 344.730878 -267.263628)
			(xy 344.679583 -267.271753) (xy 344.627649 -267.271753) (xy 344.576354 -267.263628) (xy 344.526961 -267.24758)
			(xy 344.480687 -267.224002) (xy 344.438671 -267.193476) (xy 344.401948 -267.156753) (xy 344.371422 -267.114737)
			(xy 344.347844 -267.068463) (xy 344.331796 -267.01907) (xy 344.323671 -266.967775) (xy 344.043761 -266.967775)
			(xy 344.035636 -267.01907) (xy 344.019588 -267.068463) (xy 343.99601 -267.114737) (xy 343.965484 -267.156753)
			(xy 343.928761 -267.193476) (xy 343.886745 -267.224002) (xy 343.840471 -267.24758) (xy 343.791078 -267.263628)
			(xy 343.739783 -267.271753) (xy 343.687849 -267.271753) (xy 343.636554 -267.263628) (xy 343.587161 -267.24758)
			(xy 343.540887 -267.224002) (xy 343.498871 -267.193476) (xy 343.462148 -267.156753) (xy 343.431622 -267.114737)
			(xy 343.408044 -267.068463) (xy 343.391996 -267.01907) (xy 343.383871 -266.967775) (xy 343.103961 -266.967775)
			(xy 343.095836 -267.01907) (xy 343.079788 -267.068463) (xy 343.05621 -267.114737) (xy 343.025684 -267.156753)
			(xy 342.988961 -267.193476) (xy 342.946945 -267.224002) (xy 342.900671 -267.24758) (xy 342.851278 -267.263628)
			(xy 342.799983 -267.271753) (xy 342.748049 -267.271753) (xy 342.696754 -267.263628) (xy 342.647361 -267.24758)
			(xy 342.601087 -267.224002) (xy 342.559071 -267.193476) (xy 342.522348 -267.156753) (xy 342.491822 -267.114737)
			(xy 342.468244 -267.068463) (xy 342.452196 -267.01907) (xy 342.444071 -266.967775) (xy 342.164161 -266.967775)
			(xy 342.156036 -267.01907) (xy 342.139988 -267.068463) (xy 342.11641 -267.114737) (xy 342.085884 -267.156753)
			(xy 342.049161 -267.193476) (xy 342.007145 -267.224002) (xy 341.960871 -267.24758) (xy 341.911478 -267.263628)
			(xy 341.860183 -267.271753) (xy 341.808249 -267.271753) (xy 341.756954 -267.263628) (xy 341.707561 -267.24758)
			(xy 341.661287 -267.224002) (xy 341.619271 -267.193476) (xy 341.582548 -267.156753) (xy 341.552022 -267.114737)
			(xy 341.528444 -267.068463) (xy 341.512396 -267.01907) (xy 341.504271 -266.967775) (xy 341.224361 -266.967775)
			(xy 341.216236 -267.01907) (xy 341.200188 -267.068463) (xy 341.17661 -267.114737) (xy 341.146084 -267.156753)
			(xy 341.109361 -267.193476) (xy 341.067345 -267.224002) (xy 341.021071 -267.24758) (xy 340.971678 -267.263628)
			(xy 340.920383 -267.271753) (xy 340.868449 -267.271753) (xy 340.817154 -267.263628) (xy 340.767761 -267.24758)
			(xy 340.721487 -267.224002) (xy 340.679471 -267.193476) (xy 340.642748 -267.156753) (xy 340.612222 -267.114737)
			(xy 340.588644 -267.068463) (xy 340.572596 -267.01907) (xy 340.564471 -266.967775) (xy 340.284791 -266.967775)
			(xy 340.284791 -266.967786) (xy 340.276661 -267.019117) (xy 340.260601 -267.068545) (xy 340.237007 -267.114853)
			(xy 340.20646 -267.156899) (xy 340.169711 -267.193649) (xy 340.127666 -267.224199) (xy 340.08136 -267.247795)
			(xy 340.031933 -267.263857) (xy 339.980602 -267.271989) (xy 339.954616 -267.272516) (xy 339.931701 -267.272126)
			(xy 339.886311 -267.265792) (xy 339.842232 -267.253245) (xy 339.80031 -267.234724) (xy 339.780626 -267.222986)
			(xy 339.780372 -267.222986) (xy 339.772615 -267.218587) (xy 339.755157 -267.215014) (xy 339.737542 -267.217716)
			(xy 339.729572 -267.221716) (xy 339.691218 -267.243306) (xy 339.65134 -267.265658) (xy 339.644241 -267.270415)
			(xy 339.633502 -267.283691) (xy 339.62781 -267.299792) (xy 339.627464 -267.30833) (xy 339.627464 -267.42771)
			(xy 339.651848 -267.470382) (xy 339.662516 -267.47724) (xy 339.683768 -267.491363) (xy 339.722054 -267.525095)
			(xy 339.754701 -267.564308) (xy 339.780935 -267.608073) (xy 339.800133 -267.65535) (xy 339.811837 -267.705015)
			(xy 339.815771 -267.755888) (xy 339.813766 -267.781845) (xy 340.094317 -267.781845) (xy 340.094317 -267.729911)
			(xy 340.102442 -267.678616) (xy 340.11849 -267.629223) (xy 340.142068 -267.582949) (xy 340.172594 -267.540933)
			(xy 340.209317 -267.50421) (xy 340.251333 -267.473684) (xy 340.297607 -267.450106) (xy 340.347 -267.434058)
			(xy 340.398295 -267.425933) (xy 340.450229 -267.425933) (xy 340.501524 -267.434058) (xy 340.550917 -267.450106)
			(xy 340.597191 -267.473684) (xy 340.639207 -267.50421) (xy 340.67593 -267.540933) (xy 340.706456 -267.582949)
			(xy 340.730034 -267.629223) (xy 340.746082 -267.678616) (xy 340.754207 -267.729911) (xy 340.754716 -267.755878)
			(xy 340.754207 -267.781845) (xy 341.034117 -267.781845) (xy 341.034117 -267.729911) (xy 341.042242 -267.678616)
			(xy 341.05829 -267.629223) (xy 341.081868 -267.582949) (xy 341.112394 -267.540933) (xy 341.149117 -267.50421)
			(xy 341.191133 -267.473684) (xy 341.237407 -267.450106) (xy 341.2868 -267.434058) (xy 341.338095 -267.425933)
			(xy 341.390029 -267.425933) (xy 341.441324 -267.434058) (xy 341.490717 -267.450106) (xy 341.536991 -267.473684)
			(xy 341.579007 -267.50421) (xy 341.61573 -267.540933) (xy 341.646256 -267.582949) (xy 341.669834 -267.629223)
			(xy 341.685882 -267.678616) (xy 341.694007 -267.729911) (xy 341.694516 -267.755878) (xy 341.694007 -267.781845)
			(xy 341.973917 -267.781845) (xy 341.973917 -267.729911) (xy 341.982042 -267.678616) (xy 341.99809 -267.629223)
			(xy 342.021668 -267.582949) (xy 342.052194 -267.540933) (xy 342.088917 -267.50421) (xy 342.130933 -267.473684)
			(xy 342.177207 -267.450106) (xy 342.2266 -267.434058) (xy 342.277895 -267.425933) (xy 342.329829 -267.425933)
			(xy 342.381124 -267.434058) (xy 342.430517 -267.450106) (xy 342.476791 -267.473684) (xy 342.518807 -267.50421)
			(xy 342.55553 -267.540933) (xy 342.586056 -267.582949) (xy 342.609634 -267.629223) (xy 342.625682 -267.678616)
			(xy 342.633807 -267.729911) (xy 342.634316 -267.755878) (xy 342.633807 -267.781845) (xy 342.913717 -267.781845)
			(xy 342.913717 -267.729911) (xy 342.921842 -267.678616) (xy 342.93789 -267.629223) (xy 342.961468 -267.582949)
			(xy 342.991994 -267.540933) (xy 343.028717 -267.50421) (xy 343.070733 -267.473684) (xy 343.117007 -267.450106)
			(xy 343.1664 -267.434058) (xy 343.217695 -267.425933) (xy 343.269629 -267.425933) (xy 343.320924 -267.434058)
			(xy 343.370317 -267.450106) (xy 343.416591 -267.473684) (xy 343.458607 -267.50421) (xy 343.49533 -267.540933)
			(xy 343.525856 -267.582949) (xy 343.549434 -267.629223) (xy 343.565482 -267.678616) (xy 343.573607 -267.729911)
			(xy 343.574116 -267.755878) (xy 343.573607 -267.781845) (xy 343.853517 -267.781845) (xy 343.853517 -267.729911)
			(xy 343.861642 -267.678616) (xy 343.87769 -267.629223) (xy 343.901268 -267.582949) (xy 343.931794 -267.540933)
			(xy 343.968517 -267.50421) (xy 344.010533 -267.473684) (xy 344.056807 -267.450106) (xy 344.1062 -267.434058)
			(xy 344.157495 -267.425933) (xy 344.209429 -267.425933) (xy 344.260724 -267.434058) (xy 344.310117 -267.450106)
			(xy 344.356391 -267.473684) (xy 344.398407 -267.50421) (xy 344.43513 -267.540933) (xy 344.465656 -267.582949)
			(xy 344.489234 -267.629223) (xy 344.505282 -267.678616) (xy 344.513407 -267.729911) (xy 344.513916 -267.755878)
			(xy 344.513407 -267.781845) (xy 344.793571 -267.781845) (xy 344.793571 -267.729911) (xy 344.801696 -267.678616)
			(xy 344.817744 -267.629223) (xy 344.841322 -267.582949) (xy 344.871848 -267.540933) (xy 344.908571 -267.50421)
			(xy 344.950587 -267.473684) (xy 344.996861 -267.450106) (xy 345.046254 -267.434058) (xy 345.097549 -267.425933)
			(xy 345.149483 -267.425933) (xy 345.200778 -267.434058) (xy 345.250171 -267.450106) (xy 345.296445 -267.473684)
			(xy 345.338461 -267.50421) (xy 345.375184 -267.540933) (xy 345.40571 -267.582949) (xy 345.429288 -267.629223)
			(xy 345.445336 -267.678616) (xy 345.453461 -267.729911) (xy 345.45397 -267.755878) (xy 345.453461 -267.781845)
			(xy 345.733117 -267.781845) (xy 345.733117 -267.729911) (xy 345.741242 -267.678616) (xy 345.75729 -267.629223)
			(xy 345.780868 -267.582949) (xy 345.811394 -267.540933) (xy 345.848117 -267.50421) (xy 345.890133 -267.473684)
			(xy 345.936407 -267.450106) (xy 345.9858 -267.434058) (xy 346.037095 -267.425933) (xy 346.089029 -267.425933)
			(xy 346.140324 -267.434058) (xy 346.189717 -267.450106) (xy 346.235991 -267.473684) (xy 346.278007 -267.50421)
			(xy 346.31473 -267.540933) (xy 346.345256 -267.582949) (xy 346.368834 -267.629223) (xy 346.384882 -267.678616)
			(xy 346.393007 -267.729911) (xy 346.393516 -267.755878) (xy 346.393007 -267.781845) (xy 346.672917 -267.781845)
			(xy 346.672917 -267.729911) (xy 346.681042 -267.678616) (xy 346.69709 -267.629223) (xy 346.720668 -267.582949)
			(xy 346.751194 -267.540933) (xy 346.787917 -267.50421) (xy 346.829933 -267.473684) (xy 346.876207 -267.450106)
			(xy 346.9256 -267.434058) (xy 346.976895 -267.425933) (xy 347.028829 -267.425933) (xy 347.080124 -267.434058)
			(xy 347.129517 -267.450106) (xy 347.175791 -267.473684) (xy 347.217807 -267.50421) (xy 347.25453 -267.540933)
			(xy 347.285056 -267.582949) (xy 347.308634 -267.629223) (xy 347.324682 -267.678616) (xy 347.332807 -267.729911)
			(xy 347.333316 -267.755878) (xy 347.332807 -267.781845) (xy 347.612717 -267.781845) (xy 347.612717 -267.729911)
			(xy 347.620842 -267.678616) (xy 347.63689 -267.629223) (xy 347.660468 -267.582949) (xy 347.690994 -267.540933)
			(xy 347.727717 -267.50421) (xy 347.769733 -267.473684) (xy 347.816007 -267.450106) (xy 347.8654 -267.434058)
			(xy 347.916695 -267.425933) (xy 347.968629 -267.425933) (xy 348.019924 -267.434058) (xy 348.069317 -267.450106)
			(xy 348.115591 -267.473684) (xy 348.157607 -267.50421) (xy 348.19433 -267.540933) (xy 348.224856 -267.582949)
			(xy 348.248434 -267.629223) (xy 348.264482 -267.678616) (xy 348.272607 -267.729911) (xy 348.273116 -267.755878)
			(xy 348.272607 -267.781845) (xy 348.552517 -267.781845) (xy 348.552517 -267.729911) (xy 348.560642 -267.678616)
			(xy 348.57669 -267.629223) (xy 348.600268 -267.582949) (xy 348.630794 -267.540933) (xy 348.667517 -267.50421)
			(xy 348.709533 -267.473684) (xy 348.755807 -267.450106) (xy 348.8052 -267.434058) (xy 348.856495 -267.425933)
			(xy 348.908429 -267.425933) (xy 348.959724 -267.434058) (xy 349.009117 -267.450106) (xy 349.055391 -267.473684)
			(xy 349.097407 -267.50421) (xy 349.13413 -267.540933) (xy 349.164656 -267.582949) (xy 349.188234 -267.629223)
			(xy 349.204282 -267.678616) (xy 349.212407 -267.729911) (xy 349.212916 -267.755878) (xy 349.212407 -267.781845)
			(xy 349.492317 -267.781845) (xy 349.492317 -267.729911) (xy 349.500442 -267.678616) (xy 349.51649 -267.629223)
			(xy 349.540068 -267.582949) (xy 349.570594 -267.540933) (xy 349.607317 -267.50421) (xy 349.649333 -267.473684)
			(xy 349.695607 -267.450106) (xy 349.745 -267.434058) (xy 349.796295 -267.425933) (xy 349.848229 -267.425933)
			(xy 349.899524 -267.434058) (xy 349.948917 -267.450106) (xy 349.995191 -267.473684) (xy 350.037207 -267.50421)
			(xy 350.07393 -267.540933) (xy 350.104456 -267.582949) (xy 350.128034 -267.629223) (xy 350.144082 -267.678616)
			(xy 350.152207 -267.729911) (xy 350.152716 -267.755878) (xy 350.152207 -267.781845) (xy 350.432117 -267.781845)
			(xy 350.432117 -267.729911) (xy 350.440242 -267.678616) (xy 350.45629 -267.629223) (xy 350.479868 -267.582949)
			(xy 350.510394 -267.540933) (xy 350.547117 -267.50421) (xy 350.589133 -267.473684) (xy 350.635407 -267.450106)
			(xy 350.6848 -267.434058) (xy 350.736095 -267.425933) (xy 350.788029 -267.425933) (xy 350.839324 -267.434058)
			(xy 350.888717 -267.450106) (xy 350.934991 -267.473684) (xy 350.977007 -267.50421) (xy 351.01373 -267.540933)
			(xy 351.044256 -267.582949) (xy 351.067834 -267.629223) (xy 351.083882 -267.678616) (xy 351.092007 -267.729911)
			(xy 351.092516 -267.755878) (xy 351.092007 -267.781845) (xy 351.371917 -267.781845) (xy 351.371917 -267.729911)
			(xy 351.380042 -267.678616) (xy 351.39609 -267.629223) (xy 351.419668 -267.582949) (xy 351.450194 -267.540933)
			(xy 351.486917 -267.50421) (xy 351.528933 -267.473684) (xy 351.575207 -267.450106) (xy 351.6246 -267.434058)
			(xy 351.675895 -267.425933) (xy 351.727829 -267.425933) (xy 351.779124 -267.434058) (xy 351.828517 -267.450106)
			(xy 351.874791 -267.473684) (xy 351.916807 -267.50421) (xy 351.95353 -267.540933) (xy 351.984056 -267.582949)
			(xy 352.007634 -267.629223) (xy 352.023682 -267.678616) (xy 352.031807 -267.729911) (xy 352.032316 -267.755878)
			(xy 352.031807 -267.781845) (xy 352.023682 -267.83314) (xy 352.007634 -267.882533) (xy 351.984056 -267.928807)
			(xy 351.95353 -267.970823) (xy 351.916807 -268.007546) (xy 351.874791 -268.038072) (xy 351.828517 -268.06165)
			(xy 351.779124 -268.077698) (xy 351.727829 -268.085823) (xy 351.675895 -268.085823) (xy 351.6246 -268.077698)
			(xy 351.575207 -268.06165) (xy 351.528933 -268.038072) (xy 351.486917 -268.007546) (xy 351.450194 -267.970823)
			(xy 351.419668 -267.928807) (xy 351.39609 -267.882533) (xy 351.380042 -267.83314) (xy 351.371917 -267.781845)
			(xy 351.092007 -267.781845) (xy 351.083882 -267.83314) (xy 351.067834 -267.882533) (xy 351.044256 -267.928807)
			(xy 351.01373 -267.970823) (xy 350.977007 -268.007546) (xy 350.934991 -268.038072) (xy 350.888717 -268.06165)
			(xy 350.839324 -268.077698) (xy 350.788029 -268.085823) (xy 350.736095 -268.085823) (xy 350.6848 -268.077698)
			(xy 350.635407 -268.06165) (xy 350.589133 -268.038072) (xy 350.547117 -268.007546) (xy 350.510394 -267.970823)
			(xy 350.479868 -267.928807) (xy 350.45629 -267.882533) (xy 350.440242 -267.83314) (xy 350.432117 -267.781845)
			(xy 350.152207 -267.781845) (xy 350.144082 -267.83314) (xy 350.128034 -267.882533) (xy 350.104456 -267.928807)
			(xy 350.07393 -267.970823) (xy 350.037207 -268.007546) (xy 349.995191 -268.038072) (xy 349.948917 -268.06165)
			(xy 349.899524 -268.077698) (xy 349.848229 -268.085823) (xy 349.796295 -268.085823) (xy 349.745 -268.077698)
			(xy 349.695607 -268.06165) (xy 349.649333 -268.038072) (xy 349.607317 -268.007546) (xy 349.570594 -267.970823)
			(xy 349.540068 -267.928807) (xy 349.51649 -267.882533) (xy 349.500442 -267.83314) (xy 349.492317 -267.781845)
			(xy 349.212407 -267.781845) (xy 349.204282 -267.83314) (xy 349.188234 -267.882533) (xy 349.164656 -267.928807)
			(xy 349.13413 -267.970823) (xy 349.097407 -268.007546) (xy 349.055391 -268.038072) (xy 349.009117 -268.06165)
			(xy 348.959724 -268.077698) (xy 348.908429 -268.085823) (xy 348.856495 -268.085823) (xy 348.8052 -268.077698)
			(xy 348.755807 -268.06165) (xy 348.709533 -268.038072) (xy 348.667517 -268.007546) (xy 348.630794 -267.970823)
			(xy 348.600268 -267.928807) (xy 348.57669 -267.882533) (xy 348.560642 -267.83314) (xy 348.552517 -267.781845)
			(xy 348.272607 -267.781845) (xy 348.264482 -267.83314) (xy 348.248434 -267.882533) (xy 348.224856 -267.928807)
			(xy 348.19433 -267.970823) (xy 348.157607 -268.007546) (xy 348.115591 -268.038072) (xy 348.069317 -268.06165)
			(xy 348.019924 -268.077698) (xy 347.968629 -268.085823) (xy 347.916695 -268.085823) (xy 347.8654 -268.077698)
			(xy 347.816007 -268.06165) (xy 347.769733 -268.038072) (xy 347.727717 -268.007546) (xy 347.690994 -267.970823)
			(xy 347.660468 -267.928807) (xy 347.63689 -267.882533) (xy 347.620842 -267.83314) (xy 347.612717 -267.781845)
			(xy 347.332807 -267.781845) (xy 347.324682 -267.83314) (xy 347.308634 -267.882533) (xy 347.285056 -267.928807)
			(xy 347.25453 -267.970823) (xy 347.217807 -268.007546) (xy 347.175791 -268.038072) (xy 347.129517 -268.06165)
			(xy 347.080124 -268.077698) (xy 347.028829 -268.085823) (xy 346.976895 -268.085823) (xy 346.9256 -268.077698)
			(xy 346.876207 -268.06165) (xy 346.829933 -268.038072) (xy 346.787917 -268.007546) (xy 346.751194 -267.970823)
			(xy 346.720668 -267.928807) (xy 346.69709 -267.882533) (xy 346.681042 -267.83314) (xy 346.672917 -267.781845)
			(xy 346.393007 -267.781845) (xy 346.384882 -267.83314) (xy 346.368834 -267.882533) (xy 346.345256 -267.928807)
			(xy 346.31473 -267.970823) (xy 346.278007 -268.007546) (xy 346.235991 -268.038072) (xy 346.189717 -268.06165)
			(xy 346.140324 -268.077698) (xy 346.089029 -268.085823) (xy 346.037095 -268.085823) (xy 345.9858 -268.077698)
			(xy 345.936407 -268.06165) (xy 345.890133 -268.038072) (xy 345.848117 -268.007546) (xy 345.811394 -267.970823)
			(xy 345.780868 -267.928807) (xy 345.75729 -267.882533) (xy 345.741242 -267.83314) (xy 345.733117 -267.781845)
			(xy 345.453461 -267.781845) (xy 345.445336 -267.83314) (xy 345.429288 -267.882533) (xy 345.40571 -267.928807)
			(xy 345.375184 -267.970823) (xy 345.338461 -268.007546) (xy 345.296445 -268.038072) (xy 345.250171 -268.06165)
			(xy 345.200778 -268.077698) (xy 345.149483 -268.085823) (xy 345.097549 -268.085823) (xy 345.046254 -268.077698)
			(xy 344.996861 -268.06165) (xy 344.950587 -268.038072) (xy 344.908571 -268.007546) (xy 344.871848 -267.970823)
			(xy 344.841322 -267.928807) (xy 344.817744 -267.882533) (xy 344.801696 -267.83314) (xy 344.793571 -267.781845)
			(xy 344.513407 -267.781845) (xy 344.505282 -267.83314) (xy 344.489234 -267.882533) (xy 344.465656 -267.928807)
			(xy 344.43513 -267.970823) (xy 344.398407 -268.007546) (xy 344.356391 -268.038072) (xy 344.310117 -268.06165)
			(xy 344.260724 -268.077698) (xy 344.209429 -268.085823) (xy 344.157495 -268.085823) (xy 344.1062 -268.077698)
			(xy 344.056807 -268.06165) (xy 344.010533 -268.038072) (xy 343.968517 -268.007546) (xy 343.931794 -267.970823)
			(xy 343.901268 -267.928807) (xy 343.87769 -267.882533) (xy 343.861642 -267.83314) (xy 343.853517 -267.781845)
			(xy 343.573607 -267.781845) (xy 343.565482 -267.83314) (xy 343.549434 -267.882533) (xy 343.525856 -267.928807)
			(xy 343.49533 -267.970823) (xy 343.458607 -268.007546) (xy 343.416591 -268.038072) (xy 343.370317 -268.06165)
			(xy 343.320924 -268.077698) (xy 343.269629 -268.085823) (xy 343.217695 -268.085823) (xy 343.1664 -268.077698)
			(xy 343.117007 -268.06165) (xy 343.070733 -268.038072) (xy 343.028717 -268.007546) (xy 342.991994 -267.970823)
			(xy 342.961468 -267.928807) (xy 342.93789 -267.882533) (xy 342.921842 -267.83314) (xy 342.913717 -267.781845)
			(xy 342.633807 -267.781845) (xy 342.625682 -267.83314) (xy 342.609634 -267.882533) (xy 342.586056 -267.928807)
			(xy 342.55553 -267.970823) (xy 342.518807 -268.007546) (xy 342.476791 -268.038072) (xy 342.430517 -268.06165)
			(xy 342.381124 -268.077698) (xy 342.329829 -268.085823) (xy 342.277895 -268.085823) (xy 342.2266 -268.077698)
			(xy 342.177207 -268.06165) (xy 342.130933 -268.038072) (xy 342.088917 -268.007546) (xy 342.052194 -267.970823)
			(xy 342.021668 -267.928807) (xy 341.99809 -267.882533) (xy 341.982042 -267.83314) (xy 341.973917 -267.781845)
			(xy 341.694007 -267.781845) (xy 341.685882 -267.83314) (xy 341.669834 -267.882533) (xy 341.646256 -267.928807)
			(xy 341.61573 -267.970823) (xy 341.579007 -268.007546) (xy 341.536991 -268.038072) (xy 341.490717 -268.06165)
			(xy 341.441324 -268.077698) (xy 341.390029 -268.085823) (xy 341.338095 -268.085823) (xy 341.2868 -268.077698)
			(xy 341.237407 -268.06165) (xy 341.191133 -268.038072) (xy 341.149117 -268.007546) (xy 341.112394 -267.970823)
			(xy 341.081868 -267.928807) (xy 341.05829 -267.882533) (xy 341.042242 -267.83314) (xy 341.034117 -267.781845)
			(xy 340.754207 -267.781845) (xy 340.746082 -267.83314) (xy 340.730034 -267.882533) (xy 340.706456 -267.928807)
			(xy 340.67593 -267.970823) (xy 340.639207 -268.007546) (xy 340.597191 -268.038072) (xy 340.550917 -268.06165)
			(xy 340.501524 -268.077698) (xy 340.450229 -268.085823) (xy 340.398295 -268.085823) (xy 340.347 -268.077698)
			(xy 340.297607 -268.06165) (xy 340.251333 -268.038072) (xy 340.209317 -268.007546) (xy 340.172594 -267.970823)
			(xy 340.142068 -267.928807) (xy 340.11849 -267.882533) (xy 340.102442 -267.83314) (xy 340.094317 -267.781845)
			(xy 339.813766 -267.781845) (xy 339.811841 -267.806762) (xy 339.80014 -267.856428) (xy 339.780946 -267.903705)
			(xy 339.754715 -267.947472) (xy 339.72207 -267.986688) (xy 339.683787 -268.020423) (xy 339.662516 -268.034516)
			(xy 339.651848 -268.041374) (xy 339.627464 -268.084046) (xy 339.627464 -268.203172) (xy 339.627776 -268.21156)
			(xy 339.633271 -268.227411) (xy 339.643662 -268.240581) (xy 339.650578 -268.245336) (xy 339.718142 -268.283182)
			(xy 339.723391 -268.285672) (xy 339.734687 -268.288373) (xy 339.740494 -268.288516) (xy 339.76691 -268.288516)
			(xy 339.791294 -268.281912) (xy 339.795612 -268.279626) (xy 339.820105 -268.266858) (xy 339.872286 -268.248756)
			(xy 339.926747 -268.239558) (xy 339.954362 -268.238986) (xy 339.954616 -268.238986) (xy 339.980603 -268.239497)
			(xy 340.031936 -268.247629) (xy 340.081366 -268.263692) (xy 340.127674 -268.287289) (xy 340.16972 -268.31784)
			(xy 340.206471 -268.354592) (xy 340.237019 -268.39664) (xy 340.260614 -268.442949) (xy 340.276674 -268.492379)
			(xy 340.284805 -268.543713) (xy 340.284805 -268.595661) (xy 340.564471 -268.595661) (xy 340.564471 -268.543727)
			(xy 340.572596 -268.492432) (xy 340.588644 -268.443039) (xy 340.612222 -268.396765) (xy 340.642748 -268.354749)
			(xy 340.679471 -268.318026) (xy 340.721487 -268.2875) (xy 340.767761 -268.263922) (xy 340.817154 -268.247874)
			(xy 340.868449 -268.239749) (xy 340.920383 -268.239749) (xy 340.971678 -268.247874) (xy 341.021071 -268.263922)
			(xy 341.067345 -268.2875) (xy 341.109361 -268.318026) (xy 341.146084 -268.354749) (xy 341.17661 -268.396765)
			(xy 341.200188 -268.443039) (xy 341.216236 -268.492432) (xy 341.224361 -268.543727) (xy 341.22487 -268.569694)
			(xy 341.224361 -268.595661) (xy 341.504271 -268.595661) (xy 341.504271 -268.543727) (xy 341.512396 -268.492432)
			(xy 341.528444 -268.443039) (xy 341.552022 -268.396765) (xy 341.582548 -268.354749) (xy 341.619271 -268.318026)
			(xy 341.661287 -268.2875) (xy 341.707561 -268.263922) (xy 341.756954 -268.247874) (xy 341.808249 -268.239749)
			(xy 341.860183 -268.239749) (xy 341.911478 -268.247874) (xy 341.960871 -268.263922) (xy 342.007145 -268.2875)
			(xy 342.049161 -268.318026) (xy 342.085884 -268.354749) (xy 342.11641 -268.396765) (xy 342.139988 -268.443039)
			(xy 342.156036 -268.492432) (xy 342.164161 -268.543727) (xy 342.16467 -268.569694) (xy 342.164161 -268.595661)
			(xy 342.443817 -268.595661) (xy 342.443817 -268.543727) (xy 342.451942 -268.492432) (xy 342.46799 -268.443039)
			(xy 342.491568 -268.396765) (xy 342.522094 -268.354749) (xy 342.558817 -268.318026) (xy 342.600833 -268.2875)
			(xy 342.647107 -268.263922) (xy 342.6965 -268.247874) (xy 342.747795 -268.239749) (xy 342.799729 -268.239749)
			(xy 342.851024 -268.247874) (xy 342.900417 -268.263922) (xy 342.946691 -268.2875) (xy 342.988707 -268.318026)
			(xy 343.02543 -268.354749) (xy 343.055956 -268.396765) (xy 343.079534 -268.443039) (xy 343.095582 -268.492432)
			(xy 343.103707 -268.543727) (xy 343.104216 -268.569694) (xy 343.103707 -268.595661) (xy 343.383871 -268.595661)
			(xy 343.383871 -268.543727) (xy 343.391996 -268.492432) (xy 343.408044 -268.443039) (xy 343.431622 -268.396765)
			(xy 343.462148 -268.354749) (xy 343.498871 -268.318026) (xy 343.540887 -268.2875) (xy 343.587161 -268.263922)
			(xy 343.636554 -268.247874) (xy 343.687849 -268.239749) (xy 343.739783 -268.239749) (xy 343.791078 -268.247874)
			(xy 343.840471 -268.263922) (xy 343.886745 -268.2875) (xy 343.928761 -268.318026) (xy 343.965484 -268.354749)
			(xy 343.99601 -268.396765) (xy 344.019588 -268.443039) (xy 344.035636 -268.492432) (xy 344.043761 -268.543727)
			(xy 344.04427 -268.569694) (xy 344.043761 -268.595661) (xy 344.323671 -268.595661) (xy 344.323671 -268.543727)
			(xy 344.331796 -268.492432) (xy 344.347844 -268.443039) (xy 344.371422 -268.396765) (xy 344.401948 -268.354749)
			(xy 344.438671 -268.318026) (xy 344.480687 -268.2875) (xy 344.526961 -268.263922) (xy 344.576354 -268.247874)
			(xy 344.627649 -268.239749) (xy 344.679583 -268.239749) (xy 344.730878 -268.247874) (xy 344.780271 -268.263922)
			(xy 344.826545 -268.2875) (xy 344.868561 -268.318026) (xy 344.905284 -268.354749) (xy 344.93581 -268.396765)
			(xy 344.959388 -268.443039) (xy 344.975436 -268.492432) (xy 344.983561 -268.543727) (xy 344.98407 -268.569694)
			(xy 344.983561 -268.595661) (xy 345.263471 -268.595661) (xy 345.263471 -268.543727) (xy 345.271596 -268.492432)
			(xy 345.287644 -268.443039) (xy 345.311222 -268.396765) (xy 345.341748 -268.354749) (xy 345.378471 -268.318026)
			(xy 345.420487 -268.2875) (xy 345.466761 -268.263922) (xy 345.516154 -268.247874) (xy 345.567449 -268.239749)
			(xy 345.619383 -268.239749) (xy 345.670678 -268.247874) (xy 345.720071 -268.263922) (xy 345.766345 -268.2875)
			(xy 345.808361 -268.318026) (xy 345.845084 -268.354749) (xy 345.87561 -268.396765) (xy 345.899188 -268.443039)
			(xy 345.915236 -268.492432) (xy 345.923361 -268.543727) (xy 345.92387 -268.569694) (xy 345.923361 -268.595661)
			(xy 346.203271 -268.595661) (xy 346.203271 -268.543727) (xy 346.211396 -268.492432) (xy 346.227444 -268.443039)
			(xy 346.251022 -268.396765) (xy 346.281548 -268.354749) (xy 346.318271 -268.318026) (xy 346.360287 -268.2875)
			(xy 346.406561 -268.263922) (xy 346.455954 -268.247874) (xy 346.507249 -268.239749) (xy 346.559183 -268.239749)
			(xy 346.610478 -268.247874) (xy 346.659871 -268.263922) (xy 346.706145 -268.2875) (xy 346.748161 -268.318026)
			(xy 346.784884 -268.354749) (xy 346.81541 -268.396765) (xy 346.838988 -268.443039) (xy 346.855036 -268.492432)
			(xy 346.863161 -268.543727) (xy 346.86367 -268.569694) (xy 346.863161 -268.595661) (xy 347.143071 -268.595661)
			(xy 347.143071 -268.543727) (xy 347.151196 -268.492432) (xy 347.167244 -268.443039) (xy 347.190822 -268.396765)
			(xy 347.221348 -268.354749) (xy 347.258071 -268.318026) (xy 347.300087 -268.2875) (xy 347.346361 -268.263922)
			(xy 347.395754 -268.247874) (xy 347.447049 -268.239749) (xy 347.498983 -268.239749) (xy 347.550278 -268.247874)
			(xy 347.599671 -268.263922) (xy 347.645945 -268.2875) (xy 347.687961 -268.318026) (xy 347.724684 -268.354749)
			(xy 347.75521 -268.396765) (xy 347.778788 -268.443039) (xy 347.794836 -268.492432) (xy 347.802961 -268.543727)
			(xy 347.80347 -268.569694) (xy 347.802961 -268.595661) (xy 348.082871 -268.595661) (xy 348.082871 -268.543727)
			(xy 348.090996 -268.492432) (xy 348.107044 -268.443039) (xy 348.130622 -268.396765) (xy 348.161148 -268.354749)
			(xy 348.197871 -268.318026) (xy 348.239887 -268.2875) (xy 348.286161 -268.263922) (xy 348.335554 -268.247874)
			(xy 348.386849 -268.239749) (xy 348.438783 -268.239749) (xy 348.490078 -268.247874) (xy 348.539471 -268.263922)
			(xy 348.585745 -268.2875) (xy 348.627761 -268.318026) (xy 348.664484 -268.354749) (xy 348.69501 -268.396765)
			(xy 348.718588 -268.443039) (xy 348.734636 -268.492432) (xy 348.742761 -268.543727) (xy 348.74327 -268.569694)
			(xy 348.742761 -268.595661) (xy 349.022417 -268.595661) (xy 349.022417 -268.543727) (xy 349.030542 -268.492432)
			(xy 349.04659 -268.443039) (xy 349.070168 -268.396765) (xy 349.100694 -268.354749) (xy 349.137417 -268.318026)
			(xy 349.179433 -268.2875) (xy 349.225707 -268.263922) (xy 349.2751 -268.247874) (xy 349.326395 -268.239749)
			(xy 349.378329 -268.239749) (xy 349.429624 -268.247874) (xy 349.479017 -268.263922) (xy 349.525291 -268.2875)
			(xy 349.567307 -268.318026) (xy 349.60403 -268.354749) (xy 349.634556 -268.396765) (xy 349.658134 -268.443039)
			(xy 349.674182 -268.492432) (xy 349.682307 -268.543727) (xy 349.682816 -268.569694) (xy 349.682307 -268.595661)
			(xy 349.962471 -268.595661) (xy 349.962471 -268.543727) (xy 349.970596 -268.492432) (xy 349.986644 -268.443039)
			(xy 350.010222 -268.396765) (xy 350.040748 -268.354749) (xy 350.077471 -268.318026) (xy 350.119487 -268.2875)
			(xy 350.165761 -268.263922) (xy 350.215154 -268.247874) (xy 350.266449 -268.239749) (xy 350.318383 -268.239749)
			(xy 350.369678 -268.247874) (xy 350.419071 -268.263922) (xy 350.465345 -268.2875) (xy 350.507361 -268.318026)
			(xy 350.544084 -268.354749) (xy 350.57461 -268.396765) (xy 350.598188 -268.443039) (xy 350.614236 -268.492432)
			(xy 350.622361 -268.543727) (xy 350.62287 -268.569694) (xy 350.622361 -268.595661) (xy 350.902271 -268.595661)
			(xy 350.902271 -268.543727) (xy 350.910396 -268.492432) (xy 350.926444 -268.443039) (xy 350.950022 -268.396765)
			(xy 350.980548 -268.354749) (xy 351.017271 -268.318026) (xy 351.059287 -268.2875) (xy 351.105561 -268.263922)
			(xy 351.154954 -268.247874) (xy 351.206249 -268.239749) (xy 351.258183 -268.239749) (xy 351.309478 -268.247874)
			(xy 351.358871 -268.263922) (xy 351.405145 -268.2875) (xy 351.447161 -268.318026) (xy 351.483884 -268.354749)
			(xy 351.51441 -268.396765) (xy 351.537988 -268.443039) (xy 351.554036 -268.492432) (xy 351.562161 -268.543727)
			(xy 351.56267 -268.569694) (xy 351.562161 -268.595661) (xy 351.842071 -268.595661) (xy 351.842071 -268.543727)
			(xy 351.850196 -268.492432) (xy 351.866244 -268.443039) (xy 351.889822 -268.396765) (xy 351.920348 -268.354749)
			(xy 351.957071 -268.318026) (xy 351.999087 -268.2875) (xy 352.045361 -268.263922) (xy 352.094754 -268.247874)
			(xy 352.146049 -268.239749) (xy 352.197983 -268.239749) (xy 352.249278 -268.247874) (xy 352.298671 -268.263922)
			(xy 352.344945 -268.2875) (xy 352.386961 -268.318026) (xy 352.423684 -268.354749) (xy 352.45421 -268.396765)
			(xy 352.477788 -268.443039) (xy 352.493836 -268.492432) (xy 352.501961 -268.543727) (xy 352.50247 -268.569694)
			(xy 352.501961 -268.595661) (xy 352.781871 -268.595661) (xy 352.781871 -268.543727) (xy 352.789996 -268.492432)
			(xy 352.806044 -268.443039) (xy 352.829622 -268.396765) (xy 352.860148 -268.354749) (xy 352.896871 -268.318026)
			(xy 352.938887 -268.2875) (xy 352.985161 -268.263922) (xy 353.034554 -268.247874) (xy 353.085849 -268.239749)
			(xy 353.137783 -268.239749) (xy 353.189078 -268.247874) (xy 353.238471 -268.263922) (xy 353.284745 -268.2875)
			(xy 353.326761 -268.318026) (xy 353.363484 -268.354749) (xy 353.39401 -268.396765) (xy 353.417588 -268.443039)
			(xy 353.433636 -268.492432) (xy 353.441761 -268.543727) (xy 353.44227 -268.569694) (xy 353.441761 -268.595661)
			(xy 353.721671 -268.595661) (xy 353.721671 -268.543727) (xy 353.729796 -268.492432) (xy 353.745844 -268.443039)
			(xy 353.769422 -268.396765) (xy 353.799948 -268.354749) (xy 353.836671 -268.318026) (xy 353.878687 -268.2875)
			(xy 353.924961 -268.263922) (xy 353.974354 -268.247874) (xy 354.025649 -268.239749) (xy 354.077583 -268.239749)
			(xy 354.128878 -268.247874) (xy 354.178271 -268.263922) (xy 354.224545 -268.2875) (xy 354.266561 -268.318026)
			(xy 354.303284 -268.354749) (xy 354.33381 -268.396765) (xy 354.357388 -268.443039) (xy 354.373436 -268.492432)
			(xy 354.381561 -268.543727) (xy 354.38207 -268.569694) (xy 354.381561 -268.595661) (xy 354.661471 -268.595661)
			(xy 354.661471 -268.543727) (xy 354.669596 -268.492432) (xy 354.685644 -268.443039) (xy 354.709222 -268.396765)
			(xy 354.739748 -268.354749) (xy 354.776471 -268.318026) (xy 354.818487 -268.2875) (xy 354.864761 -268.263922)
			(xy 354.914154 -268.247874) (xy 354.965449 -268.239749) (xy 355.017383 -268.239749) (xy 355.068678 -268.247874)
			(xy 355.118071 -268.263922) (xy 355.164345 -268.2875) (xy 355.206361 -268.318026) (xy 355.243084 -268.354749)
			(xy 355.27361 -268.396765) (xy 355.297188 -268.443039) (xy 355.313236 -268.492432) (xy 355.321361 -268.543727)
			(xy 355.32187 -268.569694) (xy 355.321361 -268.595661) (xy 355.601271 -268.595661) (xy 355.601271 -268.543727)
			(xy 355.609396 -268.492432) (xy 355.625444 -268.443039) (xy 355.649022 -268.396765) (xy 355.679548 -268.354749)
			(xy 355.716271 -268.318026) (xy 355.758287 -268.2875) (xy 355.804561 -268.263922) (xy 355.853954 -268.247874)
			(xy 355.905249 -268.239749) (xy 355.957183 -268.239749) (xy 356.008478 -268.247874) (xy 356.057871 -268.263922)
			(xy 356.104145 -268.2875) (xy 356.146161 -268.318026) (xy 356.182884 -268.354749) (xy 356.21341 -268.396765)
			(xy 356.236988 -268.443039) (xy 356.253036 -268.492432) (xy 356.261161 -268.543727) (xy 356.26167 -268.569694)
			(xy 356.261161 -268.595661) (xy 356.540817 -268.595661) (xy 356.540817 -268.543727) (xy 356.548942 -268.492432)
			(xy 356.56499 -268.443039) (xy 356.588568 -268.396765) (xy 356.619094 -268.354749) (xy 356.655817 -268.318026)
			(xy 356.697833 -268.2875) (xy 356.744107 -268.263922) (xy 356.7935 -268.247874) (xy 356.844795 -268.239749)
			(xy 356.896729 -268.239749) (xy 356.948024 -268.247874) (xy 356.997417 -268.263922) (xy 357.043691 -268.2875)
			(xy 357.085707 -268.318026) (xy 357.12243 -268.354749) (xy 357.152956 -268.396765) (xy 357.176534 -268.443039)
			(xy 357.192582 -268.492432) (xy 357.200707 -268.543727) (xy 357.201216 -268.569694) (xy 357.200707 -268.595661)
			(xy 357.480617 -268.595661) (xy 357.480617 -268.543727) (xy 357.488742 -268.492432) (xy 357.50479 -268.443039)
			(xy 357.528368 -268.396765) (xy 357.558894 -268.354749) (xy 357.595617 -268.318026) (xy 357.637633 -268.2875)
			(xy 357.683907 -268.263922) (xy 357.7333 -268.247874) (xy 357.784595 -268.239749) (xy 357.836529 -268.239749)
			(xy 357.887824 -268.247874) (xy 357.937217 -268.263922) (xy 357.983491 -268.2875) (xy 358.025507 -268.318026)
			(xy 358.06223 -268.354749) (xy 358.092756 -268.396765) (xy 358.116334 -268.443039) (xy 358.132382 -268.492432)
			(xy 358.140507 -268.543727) (xy 358.141016 -268.569694) (xy 358.140507 -268.595661) (xy 358.132382 -268.646956)
			(xy 358.116334 -268.696349) (xy 358.092756 -268.742623) (xy 358.06223 -268.784639) (xy 358.025507 -268.821362)
			(xy 357.983491 -268.851888) (xy 357.937217 -268.875466) (xy 357.887824 -268.891514) (xy 357.836529 -268.899639)
			(xy 357.784595 -268.899639) (xy 357.7333 -268.891514) (xy 357.683907 -268.875466) (xy 357.637633 -268.851888)
			(xy 357.595617 -268.821362) (xy 357.558894 -268.784639) (xy 357.528368 -268.742623) (xy 357.50479 -268.696349)
			(xy 357.488742 -268.646956) (xy 357.480617 -268.595661) (xy 357.200707 -268.595661) (xy 357.192582 -268.646956)
			(xy 357.176534 -268.696349) (xy 357.152956 -268.742623) (xy 357.12243 -268.784639) (xy 357.085707 -268.821362)
			(xy 357.043691 -268.851888) (xy 356.997417 -268.875466) (xy 356.948024 -268.891514) (xy 356.896729 -268.899639)
			(xy 356.844795 -268.899639) (xy 356.7935 -268.891514) (xy 356.744107 -268.875466) (xy 356.697833 -268.851888)
			(xy 356.655817 -268.821362) (xy 356.619094 -268.784639) (xy 356.588568 -268.742623) (xy 356.56499 -268.696349)
			(xy 356.548942 -268.646956) (xy 356.540817 -268.595661) (xy 356.261161 -268.595661) (xy 356.253036 -268.646956)
			(xy 356.236988 -268.696349) (xy 356.21341 -268.742623) (xy 356.182884 -268.784639) (xy 356.146161 -268.821362)
			(xy 356.104145 -268.851888) (xy 356.057871 -268.875466) (xy 356.008478 -268.891514) (xy 355.957183 -268.899639)
			(xy 355.905249 -268.899639) (xy 355.853954 -268.891514) (xy 355.804561 -268.875466) (xy 355.758287 -268.851888)
			(xy 355.716271 -268.821362) (xy 355.679548 -268.784639) (xy 355.649022 -268.742623) (xy 355.625444 -268.696349)
			(xy 355.609396 -268.646956) (xy 355.601271 -268.595661) (xy 355.321361 -268.595661) (xy 355.313236 -268.646956)
			(xy 355.297188 -268.696349) (xy 355.27361 -268.742623) (xy 355.243084 -268.784639) (xy 355.206361 -268.821362)
			(xy 355.164345 -268.851888) (xy 355.118071 -268.875466) (xy 355.068678 -268.891514) (xy 355.017383 -268.899639)
			(xy 354.965449 -268.899639) (xy 354.914154 -268.891514) (xy 354.864761 -268.875466) (xy 354.818487 -268.851888)
			(xy 354.776471 -268.821362) (xy 354.739748 -268.784639) (xy 354.709222 -268.742623) (xy 354.685644 -268.696349)
			(xy 354.669596 -268.646956) (xy 354.661471 -268.595661) (xy 354.381561 -268.595661) (xy 354.373436 -268.646956)
			(xy 354.357388 -268.696349) (xy 354.33381 -268.742623) (xy 354.303284 -268.784639) (xy 354.266561 -268.821362)
			(xy 354.224545 -268.851888) (xy 354.178271 -268.875466) (xy 354.128878 -268.891514) (xy 354.077583 -268.899639)
			(xy 354.025649 -268.899639) (xy 353.974354 -268.891514) (xy 353.924961 -268.875466) (xy 353.878687 -268.851888)
			(xy 353.836671 -268.821362) (xy 353.799948 -268.784639) (xy 353.769422 -268.742623) (xy 353.745844 -268.696349)
			(xy 353.729796 -268.646956) (xy 353.721671 -268.595661) (xy 353.441761 -268.595661) (xy 353.433636 -268.646956)
			(xy 353.417588 -268.696349) (xy 353.39401 -268.742623) (xy 353.363484 -268.784639) (xy 353.326761 -268.821362)
			(xy 353.284745 -268.851888) (xy 353.238471 -268.875466) (xy 353.189078 -268.891514) (xy 353.137783 -268.899639)
			(xy 353.085849 -268.899639) (xy 353.034554 -268.891514) (xy 352.985161 -268.875466) (xy 352.938887 -268.851888)
			(xy 352.896871 -268.821362) (xy 352.860148 -268.784639) (xy 352.829622 -268.742623) (xy 352.806044 -268.696349)
			(xy 352.789996 -268.646956) (xy 352.781871 -268.595661) (xy 352.501961 -268.595661) (xy 352.493836 -268.646956)
			(xy 352.477788 -268.696349) (xy 352.45421 -268.742623) (xy 352.423684 -268.784639) (xy 352.386961 -268.821362)
			(xy 352.344945 -268.851888) (xy 352.298671 -268.875466) (xy 352.249278 -268.891514) (xy 352.197983 -268.899639)
			(xy 352.146049 -268.899639) (xy 352.094754 -268.891514) (xy 352.045361 -268.875466) (xy 351.999087 -268.851888)
			(xy 351.957071 -268.821362) (xy 351.920348 -268.784639) (xy 351.889822 -268.742623) (xy 351.866244 -268.696349)
			(xy 351.850196 -268.646956) (xy 351.842071 -268.595661) (xy 351.562161 -268.595661) (xy 351.554036 -268.646956)
			(xy 351.537988 -268.696349) (xy 351.51441 -268.742623) (xy 351.483884 -268.784639) (xy 351.447161 -268.821362)
			(xy 351.405145 -268.851888) (xy 351.358871 -268.875466) (xy 351.309478 -268.891514) (xy 351.258183 -268.899639)
			(xy 351.206249 -268.899639) (xy 351.154954 -268.891514) (xy 351.105561 -268.875466) (xy 351.059287 -268.851888)
			(xy 351.017271 -268.821362) (xy 350.980548 -268.784639) (xy 350.950022 -268.742623) (xy 350.926444 -268.696349)
			(xy 350.910396 -268.646956) (xy 350.902271 -268.595661) (xy 350.622361 -268.595661) (xy 350.614236 -268.646956)
			(xy 350.598188 -268.696349) (xy 350.57461 -268.742623) (xy 350.544084 -268.784639) (xy 350.507361 -268.821362)
			(xy 350.465345 -268.851888) (xy 350.419071 -268.875466) (xy 350.369678 -268.891514) (xy 350.318383 -268.899639)
			(xy 350.266449 -268.899639) (xy 350.215154 -268.891514) (xy 350.165761 -268.875466) (xy 350.119487 -268.851888)
			(xy 350.077471 -268.821362) (xy 350.040748 -268.784639) (xy 350.010222 -268.742623) (xy 349.986644 -268.696349)
			(xy 349.970596 -268.646956) (xy 349.962471 -268.595661) (xy 349.682307 -268.595661) (xy 349.674182 -268.646956)
			(xy 349.658134 -268.696349) (xy 349.634556 -268.742623) (xy 349.60403 -268.784639) (xy 349.567307 -268.821362)
			(xy 349.525291 -268.851888) (xy 349.479017 -268.875466) (xy 349.429624 -268.891514) (xy 349.378329 -268.899639)
			(xy 349.326395 -268.899639) (xy 349.2751 -268.891514) (xy 349.225707 -268.875466) (xy 349.179433 -268.851888)
			(xy 349.137417 -268.821362) (xy 349.100694 -268.784639) (xy 349.070168 -268.742623) (xy 349.04659 -268.696349)
			(xy 349.030542 -268.646956) (xy 349.022417 -268.595661) (xy 348.742761 -268.595661) (xy 348.734636 -268.646956)
			(xy 348.718588 -268.696349) (xy 348.69501 -268.742623) (xy 348.664484 -268.784639) (xy 348.627761 -268.821362)
			(xy 348.585745 -268.851888) (xy 348.539471 -268.875466) (xy 348.490078 -268.891514) (xy 348.438783 -268.899639)
			(xy 348.386849 -268.899639) (xy 348.335554 -268.891514) (xy 348.286161 -268.875466) (xy 348.239887 -268.851888)
			(xy 348.197871 -268.821362) (xy 348.161148 -268.784639) (xy 348.130622 -268.742623) (xy 348.107044 -268.696349)
			(xy 348.090996 -268.646956) (xy 348.082871 -268.595661) (xy 347.802961 -268.595661) (xy 347.794836 -268.646956)
			(xy 347.778788 -268.696349) (xy 347.75521 -268.742623) (xy 347.724684 -268.784639) (xy 347.687961 -268.821362)
			(xy 347.645945 -268.851888) (xy 347.599671 -268.875466) (xy 347.550278 -268.891514) (xy 347.498983 -268.899639)
			(xy 347.447049 -268.899639) (xy 347.395754 -268.891514) (xy 347.346361 -268.875466) (xy 347.300087 -268.851888)
			(xy 347.258071 -268.821362) (xy 347.221348 -268.784639) (xy 347.190822 -268.742623) (xy 347.167244 -268.696349)
			(xy 347.151196 -268.646956) (xy 347.143071 -268.595661) (xy 346.863161 -268.595661) (xy 346.855036 -268.646956)
			(xy 346.838988 -268.696349) (xy 346.81541 -268.742623) (xy 346.784884 -268.784639) (xy 346.748161 -268.821362)
			(xy 346.706145 -268.851888) (xy 346.659871 -268.875466) (xy 346.610478 -268.891514) (xy 346.559183 -268.899639)
			(xy 346.507249 -268.899639) (xy 346.455954 -268.891514) (xy 346.406561 -268.875466) (xy 346.360287 -268.851888)
			(xy 346.318271 -268.821362) (xy 346.281548 -268.784639) (xy 346.251022 -268.742623) (xy 346.227444 -268.696349)
			(xy 346.211396 -268.646956) (xy 346.203271 -268.595661) (xy 345.923361 -268.595661) (xy 345.915236 -268.646956)
			(xy 345.899188 -268.696349) (xy 345.87561 -268.742623) (xy 345.845084 -268.784639) (xy 345.808361 -268.821362)
			(xy 345.766345 -268.851888) (xy 345.720071 -268.875466) (xy 345.670678 -268.891514) (xy 345.619383 -268.899639)
			(xy 345.567449 -268.899639) (xy 345.516154 -268.891514) (xy 345.466761 -268.875466) (xy 345.420487 -268.851888)
			(xy 345.378471 -268.821362) (xy 345.341748 -268.784639) (xy 345.311222 -268.742623) (xy 345.287644 -268.696349)
			(xy 345.271596 -268.646956) (xy 345.263471 -268.595661) (xy 344.983561 -268.595661) (xy 344.975436 -268.646956)
			(xy 344.959388 -268.696349) (xy 344.93581 -268.742623) (xy 344.905284 -268.784639) (xy 344.868561 -268.821362)
			(xy 344.826545 -268.851888) (xy 344.780271 -268.875466) (xy 344.730878 -268.891514) (xy 344.679583 -268.899639)
			(xy 344.627649 -268.899639) (xy 344.576354 -268.891514) (xy 344.526961 -268.875466) (xy 344.480687 -268.851888)
			(xy 344.438671 -268.821362) (xy 344.401948 -268.784639) (xy 344.371422 -268.742623) (xy 344.347844 -268.696349)
			(xy 344.331796 -268.646956) (xy 344.323671 -268.595661) (xy 344.043761 -268.595661) (xy 344.035636 -268.646956)
			(xy 344.019588 -268.696349) (xy 343.99601 -268.742623) (xy 343.965484 -268.784639) (xy 343.928761 -268.821362)
			(xy 343.886745 -268.851888) (xy 343.840471 -268.875466) (xy 343.791078 -268.891514) (xy 343.739783 -268.899639)
			(xy 343.687849 -268.899639) (xy 343.636554 -268.891514) (xy 343.587161 -268.875466) (xy 343.540887 -268.851888)
			(xy 343.498871 -268.821362) (xy 343.462148 -268.784639) (xy 343.431622 -268.742623) (xy 343.408044 -268.696349)
			(xy 343.391996 -268.646956) (xy 343.383871 -268.595661) (xy 343.103707 -268.595661) (xy 343.095582 -268.646956)
			(xy 343.079534 -268.696349) (xy 343.055956 -268.742623) (xy 343.02543 -268.784639) (xy 342.988707 -268.821362)
			(xy 342.946691 -268.851888) (xy 342.900417 -268.875466) (xy 342.851024 -268.891514) (xy 342.799729 -268.899639)
			(xy 342.747795 -268.899639) (xy 342.6965 -268.891514) (xy 342.647107 -268.875466) (xy 342.600833 -268.851888)
			(xy 342.558817 -268.821362) (xy 342.522094 -268.784639) (xy 342.491568 -268.742623) (xy 342.46799 -268.696349)
			(xy 342.451942 -268.646956) (xy 342.443817 -268.595661) (xy 342.164161 -268.595661) (xy 342.156036 -268.646956)
			(xy 342.139988 -268.696349) (xy 342.11641 -268.742623) (xy 342.085884 -268.784639) (xy 342.049161 -268.821362)
			(xy 342.007145 -268.851888) (xy 341.960871 -268.875466) (xy 341.911478 -268.891514) (xy 341.860183 -268.899639)
			(xy 341.808249 -268.899639) (xy 341.756954 -268.891514) (xy 341.707561 -268.875466) (xy 341.661287 -268.851888)
			(xy 341.619271 -268.821362) (xy 341.582548 -268.784639) (xy 341.552022 -268.742623) (xy 341.528444 -268.696349)
			(xy 341.512396 -268.646956) (xy 341.504271 -268.595661) (xy 341.224361 -268.595661) (xy 341.216236 -268.646956)
			(xy 341.200188 -268.696349) (xy 341.17661 -268.742623) (xy 341.146084 -268.784639) (xy 341.109361 -268.821362)
			(xy 341.067345 -268.851888) (xy 341.021071 -268.875466) (xy 340.971678 -268.891514) (xy 340.920383 -268.899639)
			(xy 340.868449 -268.899639) (xy 340.817154 -268.891514) (xy 340.767761 -268.875466) (xy 340.721487 -268.851888)
			(xy 340.679471 -268.821362) (xy 340.642748 -268.784639) (xy 340.612222 -268.742623) (xy 340.588644 -268.696349)
			(xy 340.572596 -268.646956) (xy 340.564471 -268.595661) (xy 340.284805 -268.595661) (xy 340.284805 -268.595687)
			(xy 340.276674 -268.647021) (xy 340.260614 -268.696451) (xy 340.237019 -268.74276) (xy 340.206471 -268.784808)
			(xy 340.16972 -268.82156) (xy 340.127674 -268.852111) (xy 340.081366 -268.875708) (xy 340.031936 -268.891771)
			(xy 339.980603 -268.899903) (xy 339.954616 -268.900402) (xy 339.931701 -268.900012) (xy 339.886311 -268.893678)
			(xy 339.842232 -268.88113) (xy 339.800311 -268.862608) (xy 339.780626 -268.850872) (xy 339.780372 -268.850872)
			(xy 339.772615 -268.846474) (xy 339.755157 -268.842902) (xy 339.737542 -268.845603) (xy 339.729572 -268.849602)
			(xy 339.691218 -268.871192) (xy 339.65134 -268.893544) (xy 339.64424 -268.8983) (xy 339.633496 -268.911576)
			(xy 339.627801 -268.927677) (xy 339.627464 -268.936216) (xy 339.627464 -269.055342) (xy 339.651848 -269.09776)
			(xy 339.662516 -269.104618) (xy 339.683794 -269.118747) (xy 339.722127 -269.152501) (xy 339.754816 -269.191745)
			(xy 339.781083 -269.235549) (xy 339.800304 -269.282869) (xy 339.812022 -269.332582) (xy 339.815959 -269.383505)
			(xy 339.81395 -269.409477) (xy 340.094317 -269.409477) (xy 340.094317 -269.357543) (xy 340.102442 -269.306248)
			(xy 340.11849 -269.256855) (xy 340.142068 -269.210581) (xy 340.172594 -269.168565) (xy 340.209317 -269.131842)
			(xy 340.251333 -269.101316) (xy 340.297607 -269.077738) (xy 340.347 -269.06169) (xy 340.398295 -269.053565)
			(xy 340.450229 -269.053565) (xy 340.501524 -269.06169) (xy 340.550917 -269.077738) (xy 340.597191 -269.101316)
			(xy 340.639207 -269.131842) (xy 340.67593 -269.168565) (xy 340.706456 -269.210581) (xy 340.730034 -269.256855)
			(xy 340.746082 -269.306248) (xy 340.754207 -269.357543) (xy 340.754716 -269.38351) (xy 340.754207 -269.409477)
			(xy 341.034117 -269.409477) (xy 341.034117 -269.357543) (xy 341.042242 -269.306248) (xy 341.05829 -269.256855)
			(xy 341.081868 -269.210581) (xy 341.112394 -269.168565) (xy 341.149117 -269.131842) (xy 341.191133 -269.101316)
			(xy 341.237407 -269.077738) (xy 341.2868 -269.06169) (xy 341.338095 -269.053565) (xy 341.390029 -269.053565)
			(xy 341.441324 -269.06169) (xy 341.490717 -269.077738) (xy 341.536991 -269.101316) (xy 341.579007 -269.131842)
			(xy 341.61573 -269.168565) (xy 341.646256 -269.210581) (xy 341.669834 -269.256855) (xy 341.685882 -269.306248)
			(xy 341.694007 -269.357543) (xy 341.694516 -269.38351) (xy 341.694007 -269.409477) (xy 341.973917 -269.409477)
			(xy 341.973917 -269.357543) (xy 341.982042 -269.306248) (xy 341.99809 -269.256855) (xy 342.021668 -269.210581)
			(xy 342.052194 -269.168565) (xy 342.088917 -269.131842) (xy 342.130933 -269.101316) (xy 342.177207 -269.077738)
			(xy 342.2266 -269.06169) (xy 342.277895 -269.053565) (xy 342.329829 -269.053565) (xy 342.381124 -269.06169)
			(xy 342.430517 -269.077738) (xy 342.476791 -269.101316) (xy 342.518807 -269.131842) (xy 342.55553 -269.168565)
			(xy 342.586056 -269.210581) (xy 342.609634 -269.256855) (xy 342.625682 -269.306248) (xy 342.633807 -269.357543)
			(xy 342.634316 -269.38351) (xy 342.633807 -269.409477) (xy 342.913717 -269.409477) (xy 342.913717 -269.357543)
			(xy 342.921842 -269.306248) (xy 342.93789 -269.256855) (xy 342.961468 -269.210581) (xy 342.991994 -269.168565)
			(xy 343.028717 -269.131842) (xy 343.070733 -269.101316) (xy 343.117007 -269.077738) (xy 343.1664 -269.06169)
			(xy 343.217695 -269.053565) (xy 343.269629 -269.053565) (xy 343.320924 -269.06169) (xy 343.370317 -269.077738)
			(xy 343.416591 -269.101316) (xy 343.458607 -269.131842) (xy 343.49533 -269.168565) (xy 343.525856 -269.210581)
			(xy 343.549434 -269.256855) (xy 343.565482 -269.306248) (xy 343.573607 -269.357543) (xy 343.574116 -269.38351)
			(xy 343.573607 -269.409477) (xy 343.853517 -269.409477) (xy 343.853517 -269.357543) (xy 343.861642 -269.306248)
			(xy 343.87769 -269.256855) (xy 343.901268 -269.210581) (xy 343.931794 -269.168565) (xy 343.968517 -269.131842)
			(xy 344.010533 -269.101316) (xy 344.056807 -269.077738) (xy 344.1062 -269.06169) (xy 344.157495 -269.053565)
			(xy 344.209429 -269.053565) (xy 344.260724 -269.06169) (xy 344.310117 -269.077738) (xy 344.356391 -269.101316)
			(xy 344.398407 -269.131842) (xy 344.43513 -269.168565) (xy 344.465656 -269.210581) (xy 344.489234 -269.256855)
			(xy 344.505282 -269.306248) (xy 344.513407 -269.357543) (xy 344.513916 -269.38351) (xy 344.513407 -269.409477)
			(xy 344.793317 -269.409477) (xy 344.793317 -269.357543) (xy 344.801442 -269.306248) (xy 344.81749 -269.256855)
			(xy 344.841068 -269.210581) (xy 344.871594 -269.168565) (xy 344.908317 -269.131842) (xy 344.950333 -269.101316)
			(xy 344.996607 -269.077738) (xy 345.046 -269.06169) (xy 345.097295 -269.053565) (xy 345.149229 -269.053565)
			(xy 345.200524 -269.06169) (xy 345.249917 -269.077738) (xy 345.296191 -269.101316) (xy 345.338207 -269.131842)
			(xy 345.37493 -269.168565) (xy 345.405456 -269.210581) (xy 345.429034 -269.256855) (xy 345.445082 -269.306248)
			(xy 345.453207 -269.357543) (xy 345.453716 -269.38351) (xy 345.453207 -269.409477) (xy 345.733371 -269.409477)
			(xy 345.733371 -269.357543) (xy 345.741496 -269.306248) (xy 345.757544 -269.256855) (xy 345.781122 -269.210581)
			(xy 345.811648 -269.168565) (xy 345.848371 -269.131842) (xy 345.890387 -269.101316) (xy 345.936661 -269.077738)
			(xy 345.986054 -269.06169) (xy 346.037349 -269.053565) (xy 346.089283 -269.053565) (xy 346.140578 -269.06169)
			(xy 346.189971 -269.077738) (xy 346.236245 -269.101316) (xy 346.278261 -269.131842) (xy 346.314984 -269.168565)
			(xy 346.34551 -269.210581) (xy 346.369088 -269.256855) (xy 346.385136 -269.306248) (xy 346.393261 -269.357543)
			(xy 346.39377 -269.38351) (xy 346.393261 -269.409477) (xy 346.672917 -269.409477) (xy 346.672917 -269.357543)
			(xy 346.681042 -269.306248) (xy 346.69709 -269.256855) (xy 346.720668 -269.210581) (xy 346.751194 -269.168565)
			(xy 346.787917 -269.131842) (xy 346.829933 -269.101316) (xy 346.876207 -269.077738) (xy 346.9256 -269.06169)
			(xy 346.976895 -269.053565) (xy 347.028829 -269.053565) (xy 347.080124 -269.06169) (xy 347.129517 -269.077738)
			(xy 347.175791 -269.101316) (xy 347.217807 -269.131842) (xy 347.25453 -269.168565) (xy 347.285056 -269.210581)
			(xy 347.308634 -269.256855) (xy 347.324682 -269.306248) (xy 347.332807 -269.357543) (xy 347.333316 -269.38351)
			(xy 347.332807 -269.409477) (xy 347.612717 -269.409477) (xy 347.612717 -269.357543) (xy 347.620842 -269.306248)
			(xy 347.63689 -269.256855) (xy 347.660468 -269.210581) (xy 347.690994 -269.168565) (xy 347.727717 -269.131842)
			(xy 347.769733 -269.101316) (xy 347.816007 -269.077738) (xy 347.8654 -269.06169) (xy 347.916695 -269.053565)
			(xy 347.968629 -269.053565) (xy 348.019924 -269.06169) (xy 348.069317 -269.077738) (xy 348.115591 -269.101316)
			(xy 348.157607 -269.131842) (xy 348.19433 -269.168565) (xy 348.224856 -269.210581) (xy 348.248434 -269.256855)
			(xy 348.264482 -269.306248) (xy 348.272607 -269.357543) (xy 348.273116 -269.38351) (xy 348.272607 -269.409477)
			(xy 348.552517 -269.409477) (xy 348.552517 -269.357543) (xy 348.560642 -269.306248) (xy 348.57669 -269.256855)
			(xy 348.600268 -269.210581) (xy 348.630794 -269.168565) (xy 348.667517 -269.131842) (xy 348.709533 -269.101316)
			(xy 348.755807 -269.077738) (xy 348.8052 -269.06169) (xy 348.856495 -269.053565) (xy 348.908429 -269.053565)
			(xy 348.959724 -269.06169) (xy 349.009117 -269.077738) (xy 349.055391 -269.101316) (xy 349.097407 -269.131842)
			(xy 349.13413 -269.168565) (xy 349.164656 -269.210581) (xy 349.188234 -269.256855) (xy 349.204282 -269.306248)
			(xy 349.212407 -269.357543) (xy 349.212916 -269.38351) (xy 349.212407 -269.409477) (xy 349.492825 -269.409477)
			(xy 349.492825 -269.357543) (xy 349.50095 -269.306248) (xy 349.516998 -269.256855) (xy 349.540576 -269.210581)
			(xy 349.571102 -269.168565) (xy 349.607825 -269.131842) (xy 349.649841 -269.101316) (xy 349.696115 -269.077738)
			(xy 349.745508 -269.06169) (xy 349.796803 -269.053565) (xy 349.848737 -269.053565) (xy 349.900032 -269.06169)
			(xy 349.949425 -269.077738) (xy 349.995699 -269.101316) (xy 350.037715 -269.131842) (xy 350.074438 -269.168565)
			(xy 350.104964 -269.210581) (xy 350.128542 -269.256855) (xy 350.14459 -269.306248) (xy 350.152715 -269.357543)
			(xy 350.153224 -269.38351) (xy 350.152715 -269.409477) (xy 350.432117 -269.409477) (xy 350.432117 -269.357543)
			(xy 350.440242 -269.306248) (xy 350.45629 -269.256855) (xy 350.479868 -269.210581) (xy 350.510394 -269.168565)
			(xy 350.547117 -269.131842) (xy 350.589133 -269.101316) (xy 350.635407 -269.077738) (xy 350.6848 -269.06169)
			(xy 350.736095 -269.053565) (xy 350.788029 -269.053565) (xy 350.839324 -269.06169) (xy 350.888717 -269.077738)
			(xy 350.934991 -269.101316) (xy 350.977007 -269.131842) (xy 351.01373 -269.168565) (xy 351.044256 -269.210581)
			(xy 351.067834 -269.256855) (xy 351.083882 -269.306248) (xy 351.092007 -269.357543) (xy 351.092516 -269.38351)
			(xy 351.092007 -269.409477) (xy 351.371917 -269.409477) (xy 351.371917 -269.357543) (xy 351.380042 -269.306248)
			(xy 351.39609 -269.256855) (xy 351.419668 -269.210581) (xy 351.450194 -269.168565) (xy 351.486917 -269.131842)
			(xy 351.528933 -269.101316) (xy 351.575207 -269.077738) (xy 351.6246 -269.06169) (xy 351.675895 -269.053565)
			(xy 351.727829 -269.053565) (xy 351.779124 -269.06169) (xy 351.828517 -269.077738) (xy 351.874791 -269.101316)
			(xy 351.916807 -269.131842) (xy 351.95353 -269.168565) (xy 351.984056 -269.210581) (xy 352.007634 -269.256855)
			(xy 352.023682 -269.306248) (xy 352.031807 -269.357543) (xy 352.032316 -269.38351) (xy 352.031807 -269.409477)
			(xy 352.311717 -269.409477) (xy 352.311717 -269.357543) (xy 352.319842 -269.306248) (xy 352.33589 -269.256855)
			(xy 352.359468 -269.210581) (xy 352.389994 -269.168565) (xy 352.426717 -269.131842) (xy 352.468733 -269.101316)
			(xy 352.515007 -269.077738) (xy 352.5644 -269.06169) (xy 352.615695 -269.053565) (xy 352.667629 -269.053565)
			(xy 352.718924 -269.06169) (xy 352.768317 -269.077738) (xy 352.814591 -269.101316) (xy 352.856607 -269.131842)
			(xy 352.89333 -269.168565) (xy 352.923856 -269.210581) (xy 352.947434 -269.256855) (xy 352.963482 -269.306248)
			(xy 352.971607 -269.357543) (xy 352.972116 -269.38351) (xy 352.971607 -269.409477) (xy 353.251517 -269.409477)
			(xy 353.251517 -269.357543) (xy 353.259642 -269.306248) (xy 353.27569 -269.256855) (xy 353.299268 -269.210581)
			(xy 353.329794 -269.168565) (xy 353.366517 -269.131842) (xy 353.408533 -269.101316) (xy 353.454807 -269.077738)
			(xy 353.5042 -269.06169) (xy 353.555495 -269.053565) (xy 353.607429 -269.053565) (xy 353.658724 -269.06169)
			(xy 353.708117 -269.077738) (xy 353.754391 -269.101316) (xy 353.796407 -269.131842) (xy 353.83313 -269.168565)
			(xy 353.863656 -269.210581) (xy 353.887234 -269.256855) (xy 353.903282 -269.306248) (xy 353.911407 -269.357543)
			(xy 353.911916 -269.38351) (xy 353.911407 -269.409477) (xy 354.191317 -269.409477) (xy 354.191317 -269.357543)
			(xy 354.199442 -269.306248) (xy 354.21549 -269.256855) (xy 354.239068 -269.210581) (xy 354.269594 -269.168565)
			(xy 354.306317 -269.131842) (xy 354.348333 -269.101316) (xy 354.394607 -269.077738) (xy 354.444 -269.06169)
			(xy 354.495295 -269.053565) (xy 354.547229 -269.053565) (xy 354.598524 -269.06169) (xy 354.647917 -269.077738)
			(xy 354.694191 -269.101316) (xy 354.736207 -269.131842) (xy 354.77293 -269.168565) (xy 354.803456 -269.210581)
			(xy 354.827034 -269.256855) (xy 354.843082 -269.306248) (xy 354.851207 -269.357543) (xy 354.851716 -269.38351)
			(xy 354.851207 -269.409477) (xy 355.131117 -269.409477) (xy 355.131117 -269.357543) (xy 355.139242 -269.306248)
			(xy 355.15529 -269.256855) (xy 355.178868 -269.210581) (xy 355.209394 -269.168565) (xy 355.246117 -269.131842)
			(xy 355.288133 -269.101316) (xy 355.334407 -269.077738) (xy 355.3838 -269.06169) (xy 355.435095 -269.053565)
			(xy 355.487029 -269.053565) (xy 355.538324 -269.06169) (xy 355.587717 -269.077738) (xy 355.633991 -269.101316)
			(xy 355.676007 -269.131842) (xy 355.71273 -269.168565) (xy 355.743256 -269.210581) (xy 355.766834 -269.256855)
			(xy 355.782882 -269.306248) (xy 355.791007 -269.357543) (xy 355.791516 -269.38351) (xy 355.791007 -269.409477)
			(xy 356.070917 -269.409477) (xy 356.070917 -269.357543) (xy 356.079042 -269.306248) (xy 356.09509 -269.256855)
			(xy 356.118668 -269.210581) (xy 356.149194 -269.168565) (xy 356.185917 -269.131842) (xy 356.227933 -269.101316)
			(xy 356.274207 -269.077738) (xy 356.3236 -269.06169) (xy 356.374895 -269.053565) (xy 356.426829 -269.053565)
			(xy 356.478124 -269.06169) (xy 356.527517 -269.077738) (xy 356.573791 -269.101316) (xy 356.615807 -269.131842)
			(xy 356.65253 -269.168565) (xy 356.683056 -269.210581) (xy 356.706634 -269.256855) (xy 356.722682 -269.306248)
			(xy 356.730807 -269.357543) (xy 356.731316 -269.38351) (xy 356.730807 -269.409477) (xy 357.010717 -269.409477)
			(xy 357.010717 -269.357543) (xy 357.018842 -269.306248) (xy 357.03489 -269.256855) (xy 357.058468 -269.210581)
			(xy 357.088994 -269.168565) (xy 357.125717 -269.131842) (xy 357.167733 -269.101316) (xy 357.214007 -269.077738)
			(xy 357.2634 -269.06169) (xy 357.314695 -269.053565) (xy 357.366629 -269.053565) (xy 357.417924 -269.06169)
			(xy 357.467317 -269.077738) (xy 357.513591 -269.101316) (xy 357.555607 -269.131842) (xy 357.59233 -269.168565)
			(xy 357.622856 -269.210581) (xy 357.646434 -269.256855) (xy 357.662482 -269.306248) (xy 357.670607 -269.357543)
			(xy 357.671116 -269.38351) (xy 357.670607 -269.409477) (xy 357.950517 -269.409477) (xy 357.950517 -269.357543)
			(xy 357.958642 -269.306248) (xy 357.97469 -269.256855) (xy 357.998268 -269.210581) (xy 358.028794 -269.168565)
			(xy 358.065517 -269.131842) (xy 358.107533 -269.101316) (xy 358.153807 -269.077738) (xy 358.2032 -269.06169)
			(xy 358.254495 -269.053565) (xy 358.306429 -269.053565) (xy 358.357724 -269.06169) (xy 358.407117 -269.077738)
			(xy 358.453391 -269.101316) (xy 358.495407 -269.131842) (xy 358.53213 -269.168565) (xy 358.562656 -269.210581)
			(xy 358.586234 -269.256855) (xy 358.602282 -269.306248) (xy 358.610407 -269.357543) (xy 358.610916 -269.38351)
			(xy 358.610407 -269.409477) (xy 358.602282 -269.460772) (xy 358.586234 -269.510165) (xy 358.562656 -269.556439)
			(xy 358.53213 -269.598455) (xy 358.495407 -269.635178) (xy 358.453391 -269.665704) (xy 358.407117 -269.689282)
			(xy 358.357724 -269.70533) (xy 358.306429 -269.713455) (xy 358.254495 -269.713455) (xy 358.2032 -269.70533)
			(xy 358.153807 -269.689282) (xy 358.107533 -269.665704) (xy 358.065517 -269.635178) (xy 358.028794 -269.598455)
			(xy 357.998268 -269.556439) (xy 357.97469 -269.510165) (xy 357.958642 -269.460772) (xy 357.950517 -269.409477)
			(xy 357.670607 -269.409477) (xy 357.662482 -269.460772) (xy 357.646434 -269.510165) (xy 357.622856 -269.556439)
			(xy 357.59233 -269.598455) (xy 357.555607 -269.635178) (xy 357.513591 -269.665704) (xy 357.467317 -269.689282)
			(xy 357.417924 -269.70533) (xy 357.366629 -269.713455) (xy 357.314695 -269.713455) (xy 357.2634 -269.70533)
			(xy 357.214007 -269.689282) (xy 357.167733 -269.665704) (xy 357.125717 -269.635178) (xy 357.088994 -269.598455)
			(xy 357.058468 -269.556439) (xy 357.03489 -269.510165) (xy 357.018842 -269.460772) (xy 357.010717 -269.409477)
			(xy 356.730807 -269.409477) (xy 356.722682 -269.460772) (xy 356.706634 -269.510165) (xy 356.683056 -269.556439)
			(xy 356.65253 -269.598455) (xy 356.615807 -269.635178) (xy 356.573791 -269.665704) (xy 356.527517 -269.689282)
			(xy 356.478124 -269.70533) (xy 356.426829 -269.713455) (xy 356.374895 -269.713455) (xy 356.3236 -269.70533)
			(xy 356.274207 -269.689282) (xy 356.227933 -269.665704) (xy 356.185917 -269.635178) (xy 356.149194 -269.598455)
			(xy 356.118668 -269.556439) (xy 356.09509 -269.510165) (xy 356.079042 -269.460772) (xy 356.070917 -269.409477)
			(xy 355.791007 -269.409477) (xy 355.782882 -269.460772) (xy 355.766834 -269.510165) (xy 355.743256 -269.556439)
			(xy 355.71273 -269.598455) (xy 355.676007 -269.635178) (xy 355.633991 -269.665704) (xy 355.587717 -269.689282)
			(xy 355.538324 -269.70533) (xy 355.487029 -269.713455) (xy 355.435095 -269.713455) (xy 355.3838 -269.70533)
			(xy 355.334407 -269.689282) (xy 355.288133 -269.665704) (xy 355.246117 -269.635178) (xy 355.209394 -269.598455)
			(xy 355.178868 -269.556439) (xy 355.15529 -269.510165) (xy 355.139242 -269.460772) (xy 355.131117 -269.409477)
			(xy 354.851207 -269.409477) (xy 354.843082 -269.460772) (xy 354.827034 -269.510165) (xy 354.803456 -269.556439)
			(xy 354.77293 -269.598455) (xy 354.736207 -269.635178) (xy 354.694191 -269.665704) (xy 354.647917 -269.689282)
			(xy 354.598524 -269.70533) (xy 354.547229 -269.713455) (xy 354.495295 -269.713455) (xy 354.444 -269.70533)
			(xy 354.394607 -269.689282) (xy 354.348333 -269.665704) (xy 354.306317 -269.635178) (xy 354.269594 -269.598455)
			(xy 354.239068 -269.556439) (xy 354.21549 -269.510165) (xy 354.199442 -269.460772) (xy 354.191317 -269.409477)
			(xy 353.911407 -269.409477) (xy 353.903282 -269.460772) (xy 353.887234 -269.510165) (xy 353.863656 -269.556439)
			(xy 353.83313 -269.598455) (xy 353.796407 -269.635178) (xy 353.754391 -269.665704) (xy 353.708117 -269.689282)
			(xy 353.658724 -269.70533) (xy 353.607429 -269.713455) (xy 353.555495 -269.713455) (xy 353.5042 -269.70533)
			(xy 353.454807 -269.689282) (xy 353.408533 -269.665704) (xy 353.366517 -269.635178) (xy 353.329794 -269.598455)
			(xy 353.299268 -269.556439) (xy 353.27569 -269.510165) (xy 353.259642 -269.460772) (xy 353.251517 -269.409477)
			(xy 352.971607 -269.409477) (xy 352.963482 -269.460772) (xy 352.947434 -269.510165) (xy 352.923856 -269.556439)
			(xy 352.89333 -269.598455) (xy 352.856607 -269.635178) (xy 352.814591 -269.665704) (xy 352.768317 -269.689282)
			(xy 352.718924 -269.70533) (xy 352.667629 -269.713455) (xy 352.615695 -269.713455) (xy 352.5644 -269.70533)
			(xy 352.515007 -269.689282) (xy 352.468733 -269.665704) (xy 352.426717 -269.635178) (xy 352.389994 -269.598455)
			(xy 352.359468 -269.556439) (xy 352.33589 -269.510165) (xy 352.319842 -269.460772) (xy 352.311717 -269.409477)
			(xy 352.031807 -269.409477) (xy 352.023682 -269.460772) (xy 352.007634 -269.510165) (xy 351.984056 -269.556439)
			(xy 351.95353 -269.598455) (xy 351.916807 -269.635178) (xy 351.874791 -269.665704) (xy 351.828517 -269.689282)
			(xy 351.779124 -269.70533) (xy 351.727829 -269.713455) (xy 351.675895 -269.713455) (xy 351.6246 -269.70533)
			(xy 351.575207 -269.689282) (xy 351.528933 -269.665704) (xy 351.486917 -269.635178) (xy 351.450194 -269.598455)
			(xy 351.419668 -269.556439) (xy 351.39609 -269.510165) (xy 351.380042 -269.460772) (xy 351.371917 -269.409477)
			(xy 351.092007 -269.409477) (xy 351.083882 -269.460772) (xy 351.067834 -269.510165) (xy 351.044256 -269.556439)
			(xy 351.01373 -269.598455) (xy 350.977007 -269.635178) (xy 350.934991 -269.665704) (xy 350.888717 -269.689282)
			(xy 350.839324 -269.70533) (xy 350.788029 -269.713455) (xy 350.736095 -269.713455) (xy 350.6848 -269.70533)
			(xy 350.635407 -269.689282) (xy 350.589133 -269.665704) (xy 350.547117 -269.635178) (xy 350.510394 -269.598455)
			(xy 350.479868 -269.556439) (xy 350.45629 -269.510165) (xy 350.440242 -269.460772) (xy 350.432117 -269.409477)
			(xy 350.152715 -269.409477) (xy 350.14459 -269.460772) (xy 350.128542 -269.510165) (xy 350.104964 -269.556439)
			(xy 350.074438 -269.598455) (xy 350.037715 -269.635178) (xy 349.995699 -269.665704) (xy 349.949425 -269.689282)
			(xy 349.900032 -269.70533) (xy 349.848737 -269.713455) (xy 349.796803 -269.713455) (xy 349.745508 -269.70533)
			(xy 349.696115 -269.689282) (xy 349.649841 -269.665704) (xy 349.607825 -269.635178) (xy 349.571102 -269.598455)
			(xy 349.540576 -269.556439) (xy 349.516998 -269.510165) (xy 349.50095 -269.460772) (xy 349.492825 -269.409477)
			(xy 349.212407 -269.409477) (xy 349.204282 -269.460772) (xy 349.188234 -269.510165) (xy 349.164656 -269.556439)
			(xy 349.13413 -269.598455) (xy 349.097407 -269.635178) (xy 349.055391 -269.665704) (xy 349.009117 -269.689282)
			(xy 348.959724 -269.70533) (xy 348.908429 -269.713455) (xy 348.856495 -269.713455) (xy 348.8052 -269.70533)
			(xy 348.755807 -269.689282) (xy 348.709533 -269.665704) (xy 348.667517 -269.635178) (xy 348.630794 -269.598455)
			(xy 348.600268 -269.556439) (xy 348.57669 -269.510165) (xy 348.560642 -269.460772) (xy 348.552517 -269.409477)
			(xy 348.272607 -269.409477) (xy 348.264482 -269.460772) (xy 348.248434 -269.510165) (xy 348.224856 -269.556439)
			(xy 348.19433 -269.598455) (xy 348.157607 -269.635178) (xy 348.115591 -269.665704) (xy 348.069317 -269.689282)
			(xy 348.019924 -269.70533) (xy 347.968629 -269.713455) (xy 347.916695 -269.713455) (xy 347.8654 -269.70533)
			(xy 347.816007 -269.689282) (xy 347.769733 -269.665704) (xy 347.727717 -269.635178) (xy 347.690994 -269.598455)
			(xy 347.660468 -269.556439) (xy 347.63689 -269.510165) (xy 347.620842 -269.460772) (xy 347.612717 -269.409477)
			(xy 347.332807 -269.409477) (xy 347.324682 -269.460772) (xy 347.308634 -269.510165) (xy 347.285056 -269.556439)
			(xy 347.25453 -269.598455) (xy 347.217807 -269.635178) (xy 347.175791 -269.665704) (xy 347.129517 -269.689282)
			(xy 347.080124 -269.70533) (xy 347.028829 -269.713455) (xy 346.976895 -269.713455) (xy 346.9256 -269.70533)
			(xy 346.876207 -269.689282) (xy 346.829933 -269.665704) (xy 346.787917 -269.635178) (xy 346.751194 -269.598455)
			(xy 346.720668 -269.556439) (xy 346.69709 -269.510165) (xy 346.681042 -269.460772) (xy 346.672917 -269.409477)
			(xy 346.393261 -269.409477) (xy 346.385136 -269.460772) (xy 346.369088 -269.510165) (xy 346.34551 -269.556439)
			(xy 346.314984 -269.598455) (xy 346.278261 -269.635178) (xy 346.236245 -269.665704) (xy 346.189971 -269.689282)
			(xy 346.140578 -269.70533) (xy 346.089283 -269.713455) (xy 346.037349 -269.713455) (xy 345.986054 -269.70533)
			(xy 345.936661 -269.689282) (xy 345.890387 -269.665704) (xy 345.848371 -269.635178) (xy 345.811648 -269.598455)
			(xy 345.781122 -269.556439) (xy 345.757544 -269.510165) (xy 345.741496 -269.460772) (xy 345.733371 -269.409477)
			(xy 345.453207 -269.409477) (xy 345.445082 -269.460772) (xy 345.429034 -269.510165) (xy 345.405456 -269.556439)
			(xy 345.37493 -269.598455) (xy 345.338207 -269.635178) (xy 345.296191 -269.665704) (xy 345.249917 -269.689282)
			(xy 345.200524 -269.70533) (xy 345.149229 -269.713455) (xy 345.097295 -269.713455) (xy 345.046 -269.70533)
			(xy 344.996607 -269.689282) (xy 344.950333 -269.665704) (xy 344.908317 -269.635178) (xy 344.871594 -269.598455)
			(xy 344.841068 -269.556439) (xy 344.81749 -269.510165) (xy 344.801442 -269.460772) (xy 344.793317 -269.409477)
			(xy 344.513407 -269.409477) (xy 344.505282 -269.460772) (xy 344.489234 -269.510165) (xy 344.465656 -269.556439)
			(xy 344.43513 -269.598455) (xy 344.398407 -269.635178) (xy 344.356391 -269.665704) (xy 344.310117 -269.689282)
			(xy 344.260724 -269.70533) (xy 344.209429 -269.713455) (xy 344.157495 -269.713455) (xy 344.1062 -269.70533)
			(xy 344.056807 -269.689282) (xy 344.010533 -269.665704) (xy 343.968517 -269.635178) (xy 343.931794 -269.598455)
			(xy 343.901268 -269.556439) (xy 343.87769 -269.510165) (xy 343.861642 -269.460772) (xy 343.853517 -269.409477)
			(xy 343.573607 -269.409477) (xy 343.565482 -269.460772) (xy 343.549434 -269.510165) (xy 343.525856 -269.556439)
			(xy 343.49533 -269.598455) (xy 343.458607 -269.635178) (xy 343.416591 -269.665704) (xy 343.370317 -269.689282)
			(xy 343.320924 -269.70533) (xy 343.269629 -269.713455) (xy 343.217695 -269.713455) (xy 343.1664 -269.70533)
			(xy 343.117007 -269.689282) (xy 343.070733 -269.665704) (xy 343.028717 -269.635178) (xy 342.991994 -269.598455)
			(xy 342.961468 -269.556439) (xy 342.93789 -269.510165) (xy 342.921842 -269.460772) (xy 342.913717 -269.409477)
			(xy 342.633807 -269.409477) (xy 342.625682 -269.460772) (xy 342.609634 -269.510165) (xy 342.586056 -269.556439)
			(xy 342.55553 -269.598455) (xy 342.518807 -269.635178) (xy 342.476791 -269.665704) (xy 342.430517 -269.689282)
			(xy 342.381124 -269.70533) (xy 342.329829 -269.713455) (xy 342.277895 -269.713455) (xy 342.2266 -269.70533)
			(xy 342.177207 -269.689282) (xy 342.130933 -269.665704) (xy 342.088917 -269.635178) (xy 342.052194 -269.598455)
			(xy 342.021668 -269.556439) (xy 341.99809 -269.510165) (xy 341.982042 -269.460772) (xy 341.973917 -269.409477)
			(xy 341.694007 -269.409477) (xy 341.685882 -269.460772) (xy 341.669834 -269.510165) (xy 341.646256 -269.556439)
			(xy 341.61573 -269.598455) (xy 341.579007 -269.635178) (xy 341.536991 -269.665704) (xy 341.490717 -269.689282)
			(xy 341.441324 -269.70533) (xy 341.390029 -269.713455) (xy 341.338095 -269.713455) (xy 341.2868 -269.70533)
			(xy 341.237407 -269.689282) (xy 341.191133 -269.665704) (xy 341.149117 -269.635178) (xy 341.112394 -269.598455)
			(xy 341.081868 -269.556439) (xy 341.05829 -269.510165) (xy 341.042242 -269.460772) (xy 341.034117 -269.409477)
			(xy 340.754207 -269.409477) (xy 340.746082 -269.460772) (xy 340.730034 -269.510165) (xy 340.706456 -269.556439)
			(xy 340.67593 -269.598455) (xy 340.639207 -269.635178) (xy 340.597191 -269.665704) (xy 340.550917 -269.689282)
			(xy 340.501524 -269.70533) (xy 340.450229 -269.713455) (xy 340.398295 -269.713455) (xy 340.347 -269.70533)
			(xy 340.297607 -269.689282) (xy 340.251333 -269.665704) (xy 340.209317 -269.635178) (xy 340.172594 -269.598455)
			(xy 340.142068 -269.556439) (xy 340.11849 -269.510165) (xy 340.102442 -269.460772) (xy 340.094317 -269.409477)
			(xy 339.81395 -269.409477) (xy 339.81202 -269.434429) (xy 339.800301 -269.484141) (xy 339.781078 -269.531461)
			(xy 339.754809 -269.575264) (xy 339.722119 -269.614507) (xy 339.683785 -269.648259) (xy 339.662516 -269.662402)
			(xy 339.651848 -269.66926) (xy 339.627464 -269.711678) (xy 339.627464 -269.830804) (xy 339.627781 -269.83919)
			(xy 339.633283 -269.855033) (xy 339.643677 -269.868195) (xy 339.650578 -269.872968) (xy 339.718142 -269.910814)
			(xy 339.723391 -269.913303) (xy 339.734687 -269.916002) (xy 339.740494 -269.916148) (xy 339.767418 -269.916148)
			(xy 339.772591 -269.915994) (xy 339.782707 -269.91382) (xy 339.787484 -269.91183) (xy 339.791548 -269.909544)
			(xy 339.816481 -269.896147) (xy 339.86979 -269.877136) (xy 339.925556 -269.867469) (xy 339.953854 -269.866872)
			(xy 339.954362 -269.866872) (xy 339.980355 -269.867352) (xy 340.031701 -269.875479) (xy 340.081144 -269.891539)
			(xy 340.127465 -269.915136) (xy 340.169524 -269.94569) (xy 340.206286 -269.982447) (xy 340.236844 -270.024503)
			(xy 340.260446 -270.070821) (xy 340.276512 -270.120262) (xy 340.284645 -270.171607) (xy 340.284645 -270.223547)
			(xy 340.564471 -270.223547) (xy 340.564471 -270.171613) (xy 340.572596 -270.120318) (xy 340.588644 -270.070925)
			(xy 340.612222 -270.024651) (xy 340.642748 -269.982635) (xy 340.679471 -269.945912) (xy 340.721487 -269.915386)
			(xy 340.767761 -269.891808) (xy 340.817154 -269.87576) (xy 340.868449 -269.867635) (xy 340.920383 -269.867635)
			(xy 340.971678 -269.87576) (xy 341.021071 -269.891808) (xy 341.067345 -269.915386) (xy 341.109361 -269.945912)
			(xy 341.146084 -269.982635) (xy 341.17661 -270.024651) (xy 341.200188 -270.070925) (xy 341.216236 -270.120318)
			(xy 341.224361 -270.171613) (xy 341.22487 -270.19758) (xy 341.224361 -270.223547) (xy 341.504271 -270.223547)
			(xy 341.504271 -270.171613) (xy 341.512396 -270.120318) (xy 341.528444 -270.070925) (xy 341.552022 -270.024651)
			(xy 341.582548 -269.982635) (xy 341.619271 -269.945912) (xy 341.661287 -269.915386) (xy 341.707561 -269.891808)
			(xy 341.756954 -269.87576) (xy 341.808249 -269.867635) (xy 341.860183 -269.867635) (xy 341.911478 -269.87576)
			(xy 341.960871 -269.891808) (xy 342.007145 -269.915386) (xy 342.049161 -269.945912) (xy 342.085884 -269.982635)
			(xy 342.11641 -270.024651) (xy 342.139988 -270.070925) (xy 342.156036 -270.120318) (xy 342.164161 -270.171613)
			(xy 342.16467 -270.19758) (xy 342.164161 -270.223547) (xy 342.444071 -270.223547) (xy 342.444071 -270.171613)
			(xy 342.452196 -270.120318) (xy 342.468244 -270.070925) (xy 342.491822 -270.024651) (xy 342.522348 -269.982635)
			(xy 342.559071 -269.945912) (xy 342.601087 -269.915386) (xy 342.647361 -269.891808) (xy 342.696754 -269.87576)
			(xy 342.748049 -269.867635) (xy 342.799983 -269.867635) (xy 342.851278 -269.87576) (xy 342.900671 -269.891808)
			(xy 342.946945 -269.915386) (xy 342.988961 -269.945912) (xy 343.025684 -269.982635) (xy 343.05621 -270.024651)
			(xy 343.079788 -270.070925) (xy 343.095836 -270.120318) (xy 343.103961 -270.171613) (xy 343.10447 -270.19758)
			(xy 343.103961 -270.223547) (xy 343.383871 -270.223547) (xy 343.383871 -270.171613) (xy 343.391996 -270.120318)
			(xy 343.408044 -270.070925) (xy 343.431622 -270.024651) (xy 343.462148 -269.982635) (xy 343.498871 -269.945912)
			(xy 343.540887 -269.915386) (xy 343.587161 -269.891808) (xy 343.636554 -269.87576) (xy 343.687849 -269.867635)
			(xy 343.739783 -269.867635) (xy 343.791078 -269.87576) (xy 343.840471 -269.891808) (xy 343.886745 -269.915386)
			(xy 343.928761 -269.945912) (xy 343.965484 -269.982635) (xy 343.99601 -270.024651) (xy 344.019588 -270.070925)
			(xy 344.035636 -270.120318) (xy 344.043761 -270.171613) (xy 344.04427 -270.19758) (xy 344.043761 -270.223547)
			(xy 344.323671 -270.223547) (xy 344.323671 -270.171613) (xy 344.331796 -270.120318) (xy 344.347844 -270.070925)
			(xy 344.371422 -270.024651) (xy 344.401948 -269.982635) (xy 344.438671 -269.945912) (xy 344.480687 -269.915386)
			(xy 344.526961 -269.891808) (xy 344.576354 -269.87576) (xy 344.627649 -269.867635) (xy 344.679583 -269.867635)
			(xy 344.730878 -269.87576) (xy 344.780271 -269.891808) (xy 344.826545 -269.915386) (xy 344.868561 -269.945912)
			(xy 344.905284 -269.982635) (xy 344.93581 -270.024651) (xy 344.959388 -270.070925) (xy 344.975436 -270.120318)
			(xy 344.983561 -270.171613) (xy 344.98407 -270.19758) (xy 344.983561 -270.223547) (xy 345.263471 -270.223547)
			(xy 345.263471 -270.171613) (xy 345.271596 -270.120318) (xy 345.287644 -270.070925) (xy 345.311222 -270.024651)
			(xy 345.341748 -269.982635) (xy 345.378471 -269.945912) (xy 345.420487 -269.915386) (xy 345.466761 -269.891808)
			(xy 345.516154 -269.87576) (xy 345.567449 -269.867635) (xy 345.619383 -269.867635) (xy 345.670678 -269.87576)
			(xy 345.720071 -269.891808) (xy 345.766345 -269.915386) (xy 345.808361 -269.945912) (xy 345.845084 -269.982635)
			(xy 345.87561 -270.024651) (xy 345.899188 -270.070925) (xy 345.915236 -270.120318) (xy 345.923361 -270.171613)
			(xy 345.92387 -270.19758) (xy 345.923361 -270.223547) (xy 346.203017 -270.223547) (xy 346.203017 -270.171613)
			(xy 346.211142 -270.120318) (xy 346.22719 -270.070925) (xy 346.250768 -270.024651) (xy 346.281294 -269.982635)
			(xy 346.318017 -269.945912) (xy 346.360033 -269.915386) (xy 346.406307 -269.891808) (xy 346.4557 -269.87576)
			(xy 346.506995 -269.867635) (xy 346.558929 -269.867635) (xy 346.610224 -269.87576) (xy 346.659617 -269.891808)
			(xy 346.705891 -269.915386) (xy 346.747907 -269.945912) (xy 346.78463 -269.982635) (xy 346.815156 -270.024651)
			(xy 346.838734 -270.070925) (xy 346.854782 -270.120318) (xy 346.862907 -270.171613) (xy 346.863416 -270.19758)
			(xy 346.862907 -270.223547) (xy 347.143071 -270.223547) (xy 347.143071 -270.171613) (xy 347.151196 -270.120318)
			(xy 347.167244 -270.070925) (xy 347.190822 -270.024651) (xy 347.221348 -269.982635) (xy 347.258071 -269.945912)
			(xy 347.300087 -269.915386) (xy 347.346361 -269.891808) (xy 347.395754 -269.87576) (xy 347.447049 -269.867635)
			(xy 347.498983 -269.867635) (xy 347.550278 -269.87576) (xy 347.599671 -269.891808) (xy 347.645945 -269.915386)
			(xy 347.687961 -269.945912) (xy 347.724684 -269.982635) (xy 347.75521 -270.024651) (xy 347.778788 -270.070925)
			(xy 347.794836 -270.120318) (xy 347.802961 -270.171613) (xy 347.80347 -270.19758) (xy 347.802961 -270.223547)
			(xy 348.082871 -270.223547) (xy 348.082871 -270.171613) (xy 348.090996 -270.120318) (xy 348.107044 -270.070925)
			(xy 348.130622 -270.024651) (xy 348.161148 -269.982635) (xy 348.197871 -269.945912) (xy 348.239887 -269.915386)
			(xy 348.286161 -269.891808) (xy 348.335554 -269.87576) (xy 348.386849 -269.867635) (xy 348.438783 -269.867635)
			(xy 348.490078 -269.87576) (xy 348.539471 -269.891808) (xy 348.585745 -269.915386) (xy 348.627761 -269.945912)
			(xy 348.664484 -269.982635) (xy 348.69501 -270.024651) (xy 348.718588 -270.070925) (xy 348.734636 -270.120318)
			(xy 348.742761 -270.171613) (xy 348.74327 -270.19758) (xy 348.742761 -270.223547) (xy 349.022671 -270.223547)
			(xy 349.022671 -270.171613) (xy 349.030796 -270.120318) (xy 349.046844 -270.070925) (xy 349.070422 -270.024651)
			(xy 349.100948 -269.982635) (xy 349.137671 -269.945912) (xy 349.179687 -269.915386) (xy 349.225961 -269.891808)
			(xy 349.275354 -269.87576) (xy 349.326649 -269.867635) (xy 349.378583 -269.867635) (xy 349.429878 -269.87576)
			(xy 349.479271 -269.891808) (xy 349.525545 -269.915386) (xy 349.567561 -269.945912) (xy 349.604284 -269.982635)
			(xy 349.63481 -270.024651) (xy 349.658388 -270.070925) (xy 349.674436 -270.120318) (xy 349.682561 -270.171613)
			(xy 349.68307 -270.19758) (xy 349.682561 -270.223547) (xy 349.962471 -270.223547) (xy 349.962471 -270.171613)
			(xy 349.970596 -270.120318) (xy 349.986644 -270.070925) (xy 350.010222 -270.024651) (xy 350.040748 -269.982635)
			(xy 350.077471 -269.945912) (xy 350.119487 -269.915386) (xy 350.165761 -269.891808) (xy 350.215154 -269.87576)
			(xy 350.266449 -269.867635) (xy 350.318383 -269.867635) (xy 350.369678 -269.87576) (xy 350.419071 -269.891808)
			(xy 350.465345 -269.915386) (xy 350.507361 -269.945912) (xy 350.544084 -269.982635) (xy 350.57461 -270.024651)
			(xy 350.598188 -270.070925) (xy 350.614236 -270.120318) (xy 350.622361 -270.171613) (xy 350.62287 -270.19758)
			(xy 350.622361 -270.223547) (xy 350.902271 -270.223547) (xy 350.902271 -270.171613) (xy 350.910396 -270.120318)
			(xy 350.926444 -270.070925) (xy 350.950022 -270.024651) (xy 350.980548 -269.982635) (xy 351.017271 -269.945912)
			(xy 351.059287 -269.915386) (xy 351.105561 -269.891808) (xy 351.154954 -269.87576) (xy 351.206249 -269.867635)
			(xy 351.258183 -269.867635) (xy 351.309478 -269.87576) (xy 351.358871 -269.891808) (xy 351.405145 -269.915386)
			(xy 351.447161 -269.945912) (xy 351.483884 -269.982635) (xy 351.51441 -270.024651) (xy 351.537988 -270.070925)
			(xy 351.554036 -270.120318) (xy 351.562161 -270.171613) (xy 351.56267 -270.19758) (xy 351.562161 -270.223547)
			(xy 351.842071 -270.223547) (xy 351.842071 -270.171613) (xy 351.850196 -270.120318) (xy 351.866244 -270.070925)
			(xy 351.889822 -270.024651) (xy 351.920348 -269.982635) (xy 351.957071 -269.945912) (xy 351.999087 -269.915386)
			(xy 352.045361 -269.891808) (xy 352.094754 -269.87576) (xy 352.146049 -269.867635) (xy 352.197983 -269.867635)
			(xy 352.249278 -269.87576) (xy 352.298671 -269.891808) (xy 352.344945 -269.915386) (xy 352.386961 -269.945912)
			(xy 352.423684 -269.982635) (xy 352.45421 -270.024651) (xy 352.477788 -270.070925) (xy 352.493836 -270.120318)
			(xy 352.501961 -270.171613) (xy 352.50247 -270.19758) (xy 352.501961 -270.223547) (xy 352.781871 -270.223547)
			(xy 352.781871 -270.171613) (xy 352.789996 -270.120318) (xy 352.806044 -270.070925) (xy 352.829622 -270.024651)
			(xy 352.860148 -269.982635) (xy 352.896871 -269.945912) (xy 352.938887 -269.915386) (xy 352.985161 -269.891808)
			(xy 353.034554 -269.87576) (xy 353.085849 -269.867635) (xy 353.137783 -269.867635) (xy 353.189078 -269.87576)
			(xy 353.238471 -269.891808) (xy 353.284745 -269.915386) (xy 353.326761 -269.945912) (xy 353.363484 -269.982635)
			(xy 353.39401 -270.024651) (xy 353.417588 -270.070925) (xy 353.433636 -270.120318) (xy 353.441761 -270.171613)
			(xy 353.44227 -270.19758) (xy 353.441761 -270.223547) (xy 353.721671 -270.223547) (xy 353.721671 -270.171613)
			(xy 353.729796 -270.120318) (xy 353.745844 -270.070925) (xy 353.769422 -270.024651) (xy 353.799948 -269.982635)
			(xy 353.836671 -269.945912) (xy 353.878687 -269.915386) (xy 353.924961 -269.891808) (xy 353.974354 -269.87576)
			(xy 354.025649 -269.867635) (xy 354.077583 -269.867635) (xy 354.128878 -269.87576) (xy 354.178271 -269.891808)
			(xy 354.224545 -269.915386) (xy 354.266561 -269.945912) (xy 354.303284 -269.982635) (xy 354.33381 -270.024651)
			(xy 354.357388 -270.070925) (xy 354.373436 -270.120318) (xy 354.381561 -270.171613) (xy 354.38207 -270.19758)
			(xy 354.381561 -270.223547) (xy 354.661471 -270.223547) (xy 354.661471 -270.171613) (xy 354.669596 -270.120318)
			(xy 354.685644 -270.070925) (xy 354.709222 -270.024651) (xy 354.739748 -269.982635) (xy 354.776471 -269.945912)
			(xy 354.818487 -269.915386) (xy 354.864761 -269.891808) (xy 354.914154 -269.87576) (xy 354.965449 -269.867635)
			(xy 355.017383 -269.867635) (xy 355.068678 -269.87576) (xy 355.118071 -269.891808) (xy 355.164345 -269.915386)
			(xy 355.206361 -269.945912) (xy 355.243084 -269.982635) (xy 355.27361 -270.024651) (xy 355.297188 -270.070925)
			(xy 355.313236 -270.120318) (xy 355.321361 -270.171613) (xy 355.32187 -270.19758) (xy 355.321361 -270.223547)
			(xy 355.601271 -270.223547) (xy 355.601271 -270.171613) (xy 355.609396 -270.120318) (xy 355.625444 -270.070925)
			(xy 355.649022 -270.024651) (xy 355.679548 -269.982635) (xy 355.716271 -269.945912) (xy 355.758287 -269.915386)
			(xy 355.804561 -269.891808) (xy 355.853954 -269.87576) (xy 355.905249 -269.867635) (xy 355.957183 -269.867635)
			(xy 356.008478 -269.87576) (xy 356.057871 -269.891808) (xy 356.104145 -269.915386) (xy 356.146161 -269.945912)
			(xy 356.182884 -269.982635) (xy 356.21341 -270.024651) (xy 356.236988 -270.070925) (xy 356.253036 -270.120318)
			(xy 356.261161 -270.171613) (xy 356.26167 -270.19758) (xy 356.261161 -270.223547) (xy 356.540817 -270.223547)
			(xy 356.540817 -270.171613) (xy 356.548942 -270.120318) (xy 356.56499 -270.070925) (xy 356.588568 -270.024651)
			(xy 356.619094 -269.982635) (xy 356.655817 -269.945912) (xy 356.697833 -269.915386) (xy 356.744107 -269.891808)
			(xy 356.7935 -269.87576) (xy 356.844795 -269.867635) (xy 356.896729 -269.867635) (xy 356.948024 -269.87576)
			(xy 356.997417 -269.891808) (xy 357.043691 -269.915386) (xy 357.085707 -269.945912) (xy 357.12243 -269.982635)
			(xy 357.152956 -270.024651) (xy 357.176534 -270.070925) (xy 357.192582 -270.120318) (xy 357.200707 -270.171613)
			(xy 357.201216 -270.19758) (xy 357.200707 -270.223547) (xy 357.480617 -270.223547) (xy 357.480617 -270.171613)
			(xy 357.488742 -270.120318) (xy 357.50479 -270.070925) (xy 357.528368 -270.024651) (xy 357.558894 -269.982635)
			(xy 357.595617 -269.945912) (xy 357.637633 -269.915386) (xy 357.683907 -269.891808) (xy 357.7333 -269.87576)
			(xy 357.784595 -269.867635) (xy 357.836529 -269.867635) (xy 357.887824 -269.87576) (xy 357.937217 -269.891808)
			(xy 357.983491 -269.915386) (xy 358.025507 -269.945912) (xy 358.06223 -269.982635) (xy 358.092756 -270.024651)
			(xy 358.116334 -270.070925) (xy 358.132382 -270.120318) (xy 358.140507 -270.171613) (xy 358.141016 -270.19758)
			(xy 358.140507 -270.223547) (xy 358.420671 -270.223547) (xy 358.420671 -270.171613) (xy 358.428796 -270.120318)
			(xy 358.444844 -270.070925) (xy 358.468422 -270.024651) (xy 358.498948 -269.982635) (xy 358.535671 -269.945912)
			(xy 358.577687 -269.915386) (xy 358.623961 -269.891808) (xy 358.673354 -269.87576) (xy 358.724649 -269.867635)
			(xy 358.776583 -269.867635) (xy 358.827878 -269.87576) (xy 358.877271 -269.891808) (xy 358.923545 -269.915386)
			(xy 358.965561 -269.945912) (xy 359.002284 -269.982635) (xy 359.03281 -270.024651) (xy 359.056388 -270.070925)
			(xy 359.072436 -270.120318) (xy 359.080561 -270.171613) (xy 359.08107 -270.19758) (xy 359.080561 -270.223547)
			(xy 359.360217 -270.223547) (xy 359.360217 -270.171613) (xy 359.368342 -270.120318) (xy 359.38439 -270.070925)
			(xy 359.407968 -270.024651) (xy 359.438494 -269.982635) (xy 359.475217 -269.945912) (xy 359.517233 -269.915386)
			(xy 359.563507 -269.891808) (xy 359.6129 -269.87576) (xy 359.664195 -269.867635) (xy 359.716129 -269.867635)
			(xy 359.767424 -269.87576) (xy 359.816817 -269.891808) (xy 359.863091 -269.915386) (xy 359.905107 -269.945912)
			(xy 359.94183 -269.982635) (xy 359.972356 -270.024651) (xy 359.995934 -270.070925) (xy 360.011982 -270.120318)
			(xy 360.020107 -270.171613) (xy 360.020616 -270.19758) (xy 360.020107 -270.223547) (xy 360.011982 -270.274842)
			(xy 359.995934 -270.324235) (xy 359.972356 -270.370509) (xy 359.94183 -270.412525) (xy 359.905107 -270.449248)
			(xy 359.863091 -270.479774) (xy 359.816817 -270.503352) (xy 359.767424 -270.5194) (xy 359.716129 -270.527525)
			(xy 359.664195 -270.527525) (xy 359.6129 -270.5194) (xy 359.563507 -270.503352) (xy 359.517233 -270.479774)
			(xy 359.475217 -270.449248) (xy 359.438494 -270.412525) (xy 359.407968 -270.370509) (xy 359.38439 -270.324235)
			(xy 359.368342 -270.274842) (xy 359.360217 -270.223547) (xy 359.080561 -270.223547) (xy 359.072436 -270.274842)
			(xy 359.056388 -270.324235) (xy 359.03281 -270.370509) (xy 359.002284 -270.412525) (xy 358.965561 -270.449248)
			(xy 358.923545 -270.479774) (xy 358.877271 -270.503352) (xy 358.827878 -270.5194) (xy 358.776583 -270.527525)
			(xy 358.724649 -270.527525) (xy 358.673354 -270.5194) (xy 358.623961 -270.503352) (xy 358.577687 -270.479774)
			(xy 358.535671 -270.449248) (xy 358.498948 -270.412525) (xy 358.468422 -270.370509) (xy 358.444844 -270.324235)
			(xy 358.428796 -270.274842) (xy 358.420671 -270.223547) (xy 358.140507 -270.223547) (xy 358.132382 -270.274842)
			(xy 358.116334 -270.324235) (xy 358.092756 -270.370509) (xy 358.06223 -270.412525) (xy 358.025507 -270.449248)
			(xy 357.983491 -270.479774) (xy 357.937217 -270.503352) (xy 357.887824 -270.5194) (xy 357.836529 -270.527525)
			(xy 357.784595 -270.527525) (xy 357.7333 -270.5194) (xy 357.683907 -270.503352) (xy 357.637633 -270.479774)
			(xy 357.595617 -270.449248) (xy 357.558894 -270.412525) (xy 357.528368 -270.370509) (xy 357.50479 -270.324235)
			(xy 357.488742 -270.274842) (xy 357.480617 -270.223547) (xy 357.200707 -270.223547) (xy 357.192582 -270.274842)
			(xy 357.176534 -270.324235) (xy 357.152956 -270.370509) (xy 357.12243 -270.412525) (xy 357.085707 -270.449248)
			(xy 357.043691 -270.479774) (xy 356.997417 -270.503352) (xy 356.948024 -270.5194) (xy 356.896729 -270.527525)
			(xy 356.844795 -270.527525) (xy 356.7935 -270.5194) (xy 356.744107 -270.503352) (xy 356.697833 -270.479774)
			(xy 356.655817 -270.449248) (xy 356.619094 -270.412525) (xy 356.588568 -270.370509) (xy 356.56499 -270.324235)
			(xy 356.548942 -270.274842) (xy 356.540817 -270.223547) (xy 356.261161 -270.223547) (xy 356.253036 -270.274842)
			(xy 356.236988 -270.324235) (xy 356.21341 -270.370509) (xy 356.182884 -270.412525) (xy 356.146161 -270.449248)
			(xy 356.104145 -270.479774) (xy 356.057871 -270.503352) (xy 356.008478 -270.5194) (xy 355.957183 -270.527525)
			(xy 355.905249 -270.527525) (xy 355.853954 -270.5194) (xy 355.804561 -270.503352) (xy 355.758287 -270.479774)
			(xy 355.716271 -270.449248) (xy 355.679548 -270.412525) (xy 355.649022 -270.370509) (xy 355.625444 -270.324235)
			(xy 355.609396 -270.274842) (xy 355.601271 -270.223547) (xy 355.321361 -270.223547) (xy 355.313236 -270.274842)
			(xy 355.297188 -270.324235) (xy 355.27361 -270.370509) (xy 355.243084 -270.412525) (xy 355.206361 -270.449248)
			(xy 355.164345 -270.479774) (xy 355.118071 -270.503352) (xy 355.068678 -270.5194) (xy 355.017383 -270.527525)
			(xy 354.965449 -270.527525) (xy 354.914154 -270.5194) (xy 354.864761 -270.503352) (xy 354.818487 -270.479774)
			(xy 354.776471 -270.449248) (xy 354.739748 -270.412525) (xy 354.709222 -270.370509) (xy 354.685644 -270.324235)
			(xy 354.669596 -270.274842) (xy 354.661471 -270.223547) (xy 354.381561 -270.223547) (xy 354.373436 -270.274842)
			(xy 354.357388 -270.324235) (xy 354.33381 -270.370509) (xy 354.303284 -270.412525) (xy 354.266561 -270.449248)
			(xy 354.224545 -270.479774) (xy 354.178271 -270.503352) (xy 354.128878 -270.5194) (xy 354.077583 -270.527525)
			(xy 354.025649 -270.527525) (xy 353.974354 -270.5194) (xy 353.924961 -270.503352) (xy 353.878687 -270.479774)
			(xy 353.836671 -270.449248) (xy 353.799948 -270.412525) (xy 353.769422 -270.370509) (xy 353.745844 -270.324235)
			(xy 353.729796 -270.274842) (xy 353.721671 -270.223547) (xy 353.441761 -270.223547) (xy 353.433636 -270.274842)
			(xy 353.417588 -270.324235) (xy 353.39401 -270.370509) (xy 353.363484 -270.412525) (xy 353.326761 -270.449248)
			(xy 353.284745 -270.479774) (xy 353.238471 -270.503352) (xy 353.189078 -270.5194) (xy 353.137783 -270.527525)
			(xy 353.085849 -270.527525) (xy 353.034554 -270.5194) (xy 352.985161 -270.503352) (xy 352.938887 -270.479774)
			(xy 352.896871 -270.449248) (xy 352.860148 -270.412525) (xy 352.829622 -270.370509) (xy 352.806044 -270.324235)
			(xy 352.789996 -270.274842) (xy 352.781871 -270.223547) (xy 352.501961 -270.223547) (xy 352.493836 -270.274842)
			(xy 352.477788 -270.324235) (xy 352.45421 -270.370509) (xy 352.423684 -270.412525) (xy 352.386961 -270.449248)
			(xy 352.344945 -270.479774) (xy 352.298671 -270.503352) (xy 352.249278 -270.5194) (xy 352.197983 -270.527525)
			(xy 352.146049 -270.527525) (xy 352.094754 -270.5194) (xy 352.045361 -270.503352) (xy 351.999087 -270.479774)
			(xy 351.957071 -270.449248) (xy 351.920348 -270.412525) (xy 351.889822 -270.370509) (xy 351.866244 -270.324235)
			(xy 351.850196 -270.274842) (xy 351.842071 -270.223547) (xy 351.562161 -270.223547) (xy 351.554036 -270.274842)
			(xy 351.537988 -270.324235) (xy 351.51441 -270.370509) (xy 351.483884 -270.412525) (xy 351.447161 -270.449248)
			(xy 351.405145 -270.479774) (xy 351.358871 -270.503352) (xy 351.309478 -270.5194) (xy 351.258183 -270.527525)
			(xy 351.206249 -270.527525) (xy 351.154954 -270.5194) (xy 351.105561 -270.503352) (xy 351.059287 -270.479774)
			(xy 351.017271 -270.449248) (xy 350.980548 -270.412525) (xy 350.950022 -270.370509) (xy 350.926444 -270.324235)
			(xy 350.910396 -270.274842) (xy 350.902271 -270.223547) (xy 350.622361 -270.223547) (xy 350.614236 -270.274842)
			(xy 350.598188 -270.324235) (xy 350.57461 -270.370509) (xy 350.544084 -270.412525) (xy 350.507361 -270.449248)
			(xy 350.465345 -270.479774) (xy 350.419071 -270.503352) (xy 350.369678 -270.5194) (xy 350.318383 -270.527525)
			(xy 350.266449 -270.527525) (xy 350.215154 -270.5194) (xy 350.165761 -270.503352) (xy 350.119487 -270.479774)
			(xy 350.077471 -270.449248) (xy 350.040748 -270.412525) (xy 350.010222 -270.370509) (xy 349.986644 -270.324235)
			(xy 349.970596 -270.274842) (xy 349.962471 -270.223547) (xy 349.682561 -270.223547) (xy 349.674436 -270.274842)
			(xy 349.658388 -270.324235) (xy 349.63481 -270.370509) (xy 349.604284 -270.412525) (xy 349.567561 -270.449248)
			(xy 349.525545 -270.479774) (xy 349.479271 -270.503352) (xy 349.429878 -270.5194) (xy 349.378583 -270.527525)
			(xy 349.326649 -270.527525) (xy 349.275354 -270.5194) (xy 349.225961 -270.503352) (xy 349.179687 -270.479774)
			(xy 349.137671 -270.449248) (xy 349.100948 -270.412525) (xy 349.070422 -270.370509) (xy 349.046844 -270.324235)
			(xy 349.030796 -270.274842) (xy 349.022671 -270.223547) (xy 348.742761 -270.223547) (xy 348.734636 -270.274842)
			(xy 348.718588 -270.324235) (xy 348.69501 -270.370509) (xy 348.664484 -270.412525) (xy 348.627761 -270.449248)
			(xy 348.585745 -270.479774) (xy 348.539471 -270.503352) (xy 348.490078 -270.5194) (xy 348.438783 -270.527525)
			(xy 348.386849 -270.527525) (xy 348.335554 -270.5194) (xy 348.286161 -270.503352) (xy 348.239887 -270.479774)
			(xy 348.197871 -270.449248) (xy 348.161148 -270.412525) (xy 348.130622 -270.370509) (xy 348.107044 -270.324235)
			(xy 348.090996 -270.274842) (xy 348.082871 -270.223547) (xy 347.802961 -270.223547) (xy 347.794836 -270.274842)
			(xy 347.778788 -270.324235) (xy 347.75521 -270.370509) (xy 347.724684 -270.412525) (xy 347.687961 -270.449248)
			(xy 347.645945 -270.479774) (xy 347.599671 -270.503352) (xy 347.550278 -270.5194) (xy 347.498983 -270.527525)
			(xy 347.447049 -270.527525) (xy 347.395754 -270.5194) (xy 347.346361 -270.503352) (xy 347.300087 -270.479774)
			(xy 347.258071 -270.449248) (xy 347.221348 -270.412525) (xy 347.190822 -270.370509) (xy 347.167244 -270.324235)
			(xy 347.151196 -270.274842) (xy 347.143071 -270.223547) (xy 346.862907 -270.223547) (xy 346.854782 -270.274842)
			(xy 346.838734 -270.324235) (xy 346.815156 -270.370509) (xy 346.78463 -270.412525) (xy 346.747907 -270.449248)
			(xy 346.705891 -270.479774) (xy 346.659617 -270.503352) (xy 346.610224 -270.5194) (xy 346.558929 -270.527525)
			(xy 346.506995 -270.527525) (xy 346.4557 -270.5194) (xy 346.406307 -270.503352) (xy 346.360033 -270.479774)
			(xy 346.318017 -270.449248) (xy 346.281294 -270.412525) (xy 346.250768 -270.370509) (xy 346.22719 -270.324235)
			(xy 346.211142 -270.274842) (xy 346.203017 -270.223547) (xy 345.923361 -270.223547) (xy 345.915236 -270.274842)
			(xy 345.899188 -270.324235) (xy 345.87561 -270.370509) (xy 345.845084 -270.412525) (xy 345.808361 -270.449248)
			(xy 345.766345 -270.479774) (xy 345.720071 -270.503352) (xy 345.670678 -270.5194) (xy 345.619383 -270.527525)
			(xy 345.567449 -270.527525) (xy 345.516154 -270.5194) (xy 345.466761 -270.503352) (xy 345.420487 -270.479774)
			(xy 345.378471 -270.449248) (xy 345.341748 -270.412525) (xy 345.311222 -270.370509) (xy 345.287644 -270.324235)
			(xy 345.271596 -270.274842) (xy 345.263471 -270.223547) (xy 344.983561 -270.223547) (xy 344.975436 -270.274842)
			(xy 344.959388 -270.324235) (xy 344.93581 -270.370509) (xy 344.905284 -270.412525) (xy 344.868561 -270.449248)
			(xy 344.826545 -270.479774) (xy 344.780271 -270.503352) (xy 344.730878 -270.5194) (xy 344.679583 -270.527525)
			(xy 344.627649 -270.527525) (xy 344.576354 -270.5194) (xy 344.526961 -270.503352) (xy 344.480687 -270.479774)
			(xy 344.438671 -270.449248) (xy 344.401948 -270.412525) (xy 344.371422 -270.370509) (xy 344.347844 -270.324235)
			(xy 344.331796 -270.274842) (xy 344.323671 -270.223547) (xy 344.043761 -270.223547) (xy 344.035636 -270.274842)
			(xy 344.019588 -270.324235) (xy 343.99601 -270.370509) (xy 343.965484 -270.412525) (xy 343.928761 -270.449248)
			(xy 343.886745 -270.479774) (xy 343.840471 -270.503352) (xy 343.791078 -270.5194) (xy 343.739783 -270.527525)
			(xy 343.687849 -270.527525) (xy 343.636554 -270.5194) (xy 343.587161 -270.503352) (xy 343.540887 -270.479774)
			(xy 343.498871 -270.449248) (xy 343.462148 -270.412525) (xy 343.431622 -270.370509) (xy 343.408044 -270.324235)
			(xy 343.391996 -270.274842) (xy 343.383871 -270.223547) (xy 343.103961 -270.223547) (xy 343.095836 -270.274842)
			(xy 343.079788 -270.324235) (xy 343.05621 -270.370509) (xy 343.025684 -270.412525) (xy 342.988961 -270.449248)
			(xy 342.946945 -270.479774) (xy 342.900671 -270.503352) (xy 342.851278 -270.5194) (xy 342.799983 -270.527525)
			(xy 342.748049 -270.527525) (xy 342.696754 -270.5194) (xy 342.647361 -270.503352) (xy 342.601087 -270.479774)
			(xy 342.559071 -270.449248) (xy 342.522348 -270.412525) (xy 342.491822 -270.370509) (xy 342.468244 -270.324235)
			(xy 342.452196 -270.274842) (xy 342.444071 -270.223547) (xy 342.164161 -270.223547) (xy 342.156036 -270.274842)
			(xy 342.139988 -270.324235) (xy 342.11641 -270.370509) (xy 342.085884 -270.412525) (xy 342.049161 -270.449248)
			(xy 342.007145 -270.479774) (xy 341.960871 -270.503352) (xy 341.911478 -270.5194) (xy 341.860183 -270.527525)
			(xy 341.808249 -270.527525) (xy 341.756954 -270.5194) (xy 341.707561 -270.503352) (xy 341.661287 -270.479774)
			(xy 341.619271 -270.449248) (xy 341.582548 -270.412525) (xy 341.552022 -270.370509) (xy 341.528444 -270.324235)
			(xy 341.512396 -270.274842) (xy 341.504271 -270.223547) (xy 341.224361 -270.223547) (xy 341.216236 -270.274842)
			(xy 341.200188 -270.324235) (xy 341.17661 -270.370509) (xy 341.146084 -270.412525) (xy 341.109361 -270.449248)
			(xy 341.067345 -270.479774) (xy 341.021071 -270.503352) (xy 340.971678 -270.5194) (xy 340.920383 -270.527525)
			(xy 340.868449 -270.527525) (xy 340.817154 -270.5194) (xy 340.767761 -270.503352) (xy 340.721487 -270.479774)
			(xy 340.679471 -270.449248) (xy 340.642748 -270.412525) (xy 340.612222 -270.370509) (xy 340.588644 -270.324235)
			(xy 340.572596 -270.274842) (xy 340.564471 -270.223547) (xy 340.284645 -270.223547) (xy 340.284645 -270.223593)
			(xy 340.276512 -270.274938) (xy 340.260446 -270.324379) (xy 340.236844 -270.370697) (xy 340.206286 -270.412753)
			(xy 340.169524 -270.44951) (xy 340.127465 -270.480064) (xy 340.081144 -270.503661) (xy 340.031701 -270.519721)
			(xy 339.980355 -270.527848) (xy 339.954362 -270.528288) (xy 339.954108 -270.528288) (xy 339.942896 -270.528198)
			(xy 339.920524 -270.526674) (xy 339.909404 -270.52524) (xy 339.905848 -270.524732) (xy 339.904324 -270.524732)
			(xy 339.873081 -270.519228) (xy 339.813354 -270.497869) (xy 339.785706 -270.482314) (xy 339.780118 -270.479012)
			(xy 339.75421 -270.471646) (xy 339.748194 -270.471769) (xy 339.7365 -270.474588) (xy 339.731096 -270.477234)
			(xy 339.709506 -270.489172) (xy 339.653118 -270.520668) (xy 339.645529 -270.525305) (xy 339.633965 -270.538802)
			(xy 339.627793 -270.55547) (xy 339.627464 -270.564356) (xy 339.627464 -270.683228) (xy 339.651848 -270.7259)
			(xy 339.662516 -270.732758) (xy 339.683767 -270.746881) (xy 339.72205 -270.780612) (xy 339.754695 -270.819825)
			(xy 339.780926 -270.863589) (xy 339.800121 -270.910864) (xy 339.811824 -270.960527) (xy 339.815756 -271.011398)
			(xy 339.813749 -271.037363) (xy 340.094317 -271.037363) (xy 340.094317 -270.985429) (xy 340.102442 -270.934134)
			(xy 340.11849 -270.884741) (xy 340.142068 -270.838467) (xy 340.172594 -270.796451) (xy 340.209317 -270.759728)
			(xy 340.251333 -270.729202) (xy 340.297607 -270.705624) (xy 340.347 -270.689576) (xy 340.398295 -270.681451)
			(xy 340.450229 -270.681451) (xy 340.501524 -270.689576) (xy 340.550917 -270.705624) (xy 340.597191 -270.729202)
			(xy 340.639207 -270.759728) (xy 340.67593 -270.796451) (xy 340.706456 -270.838467) (xy 340.730034 -270.884741)
			(xy 340.746082 -270.934134) (xy 340.754207 -270.985429) (xy 340.754716 -271.011396) (xy 340.754207 -271.037363)
			(xy 341.034117 -271.037363) (xy 341.034117 -270.985429) (xy 341.042242 -270.934134) (xy 341.05829 -270.884741)
			(xy 341.081868 -270.838467) (xy 341.112394 -270.796451) (xy 341.149117 -270.759728) (xy 341.191133 -270.729202)
			(xy 341.237407 -270.705624) (xy 341.2868 -270.689576) (xy 341.338095 -270.681451) (xy 341.390029 -270.681451)
			(xy 341.441324 -270.689576) (xy 341.490717 -270.705624) (xy 341.536991 -270.729202) (xy 341.579007 -270.759728)
			(xy 341.61573 -270.796451) (xy 341.646256 -270.838467) (xy 341.669834 -270.884741) (xy 341.685882 -270.934134)
			(xy 341.694007 -270.985429) (xy 341.694516 -271.011396) (xy 341.694007 -271.037363) (xy 341.974171 -271.037363)
			(xy 341.974171 -270.985429) (xy 341.982296 -270.934134) (xy 341.998344 -270.884741) (xy 342.021922 -270.838467)
			(xy 342.052448 -270.796451) (xy 342.089171 -270.759728) (xy 342.131187 -270.729202) (xy 342.177461 -270.705624)
			(xy 342.226854 -270.689576) (xy 342.278149 -270.681451) (xy 342.330083 -270.681451) (xy 342.381378 -270.689576)
			(xy 342.430771 -270.705624) (xy 342.477045 -270.729202) (xy 342.519061 -270.759728) (xy 342.555784 -270.796451)
			(xy 342.58631 -270.838467) (xy 342.609888 -270.884741) (xy 342.625936 -270.934134) (xy 342.634061 -270.985429)
			(xy 342.63457 -271.011396) (xy 342.634061 -271.037363) (xy 342.913717 -271.037363) (xy 342.913717 -270.985429)
			(xy 342.921842 -270.934134) (xy 342.93789 -270.884741) (xy 342.961468 -270.838467) (xy 342.991994 -270.796451)
			(xy 343.028717 -270.759728) (xy 343.070733 -270.729202) (xy 343.117007 -270.705624) (xy 343.1664 -270.689576)
			(xy 343.217695 -270.681451) (xy 343.269629 -270.681451) (xy 343.320924 -270.689576) (xy 343.370317 -270.705624)
			(xy 343.416591 -270.729202) (xy 343.458607 -270.759728) (xy 343.49533 -270.796451) (xy 343.525856 -270.838467)
			(xy 343.549434 -270.884741) (xy 343.565482 -270.934134) (xy 343.573607 -270.985429) (xy 343.574116 -271.011396)
			(xy 343.573607 -271.037363) (xy 343.853517 -271.037363) (xy 343.853517 -270.985429) (xy 343.861642 -270.934134)
			(xy 343.87769 -270.884741) (xy 343.901268 -270.838467) (xy 343.931794 -270.796451) (xy 343.968517 -270.759728)
			(xy 344.010533 -270.729202) (xy 344.056807 -270.705624) (xy 344.1062 -270.689576) (xy 344.157495 -270.681451)
			(xy 344.209429 -270.681451) (xy 344.260724 -270.689576) (xy 344.310117 -270.705624) (xy 344.356391 -270.729202)
			(xy 344.398407 -270.759728) (xy 344.43513 -270.796451) (xy 344.465656 -270.838467) (xy 344.489234 -270.884741)
			(xy 344.505282 -270.934134) (xy 344.513407 -270.985429) (xy 344.513916 -271.011396) (xy 344.513407 -271.037363)
			(xy 344.793317 -271.037363) (xy 344.793317 -270.985429) (xy 344.801442 -270.934134) (xy 344.81749 -270.884741)
			(xy 344.841068 -270.838467) (xy 344.871594 -270.796451) (xy 344.908317 -270.759728) (xy 344.950333 -270.729202)
			(xy 344.996607 -270.705624) (xy 345.046 -270.689576) (xy 345.097295 -270.681451) (xy 345.149229 -270.681451)
			(xy 345.200524 -270.689576) (xy 345.249917 -270.705624) (xy 345.296191 -270.729202) (xy 345.338207 -270.759728)
			(xy 345.37493 -270.796451) (xy 345.405456 -270.838467) (xy 345.429034 -270.884741) (xy 345.445082 -270.934134)
			(xy 345.453207 -270.985429) (xy 345.453716 -271.011396) (xy 345.453207 -271.037363) (xy 345.733117 -271.037363)
			(xy 345.733117 -270.985429) (xy 345.741242 -270.934134) (xy 345.75729 -270.884741) (xy 345.780868 -270.838467)
			(xy 345.811394 -270.796451) (xy 345.848117 -270.759728) (xy 345.890133 -270.729202) (xy 345.936407 -270.705624)
			(xy 345.9858 -270.689576) (xy 346.037095 -270.681451) (xy 346.089029 -270.681451) (xy 346.140324 -270.689576)
			(xy 346.189717 -270.705624) (xy 346.235991 -270.729202) (xy 346.278007 -270.759728) (xy 346.31473 -270.796451)
			(xy 346.345256 -270.838467) (xy 346.368834 -270.884741) (xy 346.384882 -270.934134) (xy 346.393007 -270.985429)
			(xy 346.393516 -271.011396) (xy 346.393007 -271.037363) (xy 346.672917 -271.037363) (xy 346.672917 -270.985429)
			(xy 346.681042 -270.934134) (xy 346.69709 -270.884741) (xy 346.720668 -270.838467) (xy 346.751194 -270.796451)
			(xy 346.787917 -270.759728) (xy 346.829933 -270.729202) (xy 346.876207 -270.705624) (xy 346.9256 -270.689576)
			(xy 346.976895 -270.681451) (xy 347.028829 -270.681451) (xy 347.080124 -270.689576) (xy 347.129517 -270.705624)
			(xy 347.175791 -270.729202) (xy 347.217807 -270.759728) (xy 347.25453 -270.796451) (xy 347.285056 -270.838467)
			(xy 347.308634 -270.884741) (xy 347.324682 -270.934134) (xy 347.332807 -270.985429) (xy 347.333316 -271.011396)
			(xy 347.332807 -271.037363) (xy 347.612717 -271.037363) (xy 347.612717 -270.985429) (xy 347.620842 -270.934134)
			(xy 347.63689 -270.884741) (xy 347.660468 -270.838467) (xy 347.690994 -270.796451) (xy 347.727717 -270.759728)
			(xy 347.769733 -270.729202) (xy 347.816007 -270.705624) (xy 347.8654 -270.689576) (xy 347.916695 -270.681451)
			(xy 347.968629 -270.681451) (xy 348.019924 -270.689576) (xy 348.069317 -270.705624) (xy 348.115591 -270.729202)
			(xy 348.157607 -270.759728) (xy 348.19433 -270.796451) (xy 348.224856 -270.838467) (xy 348.248434 -270.884741)
			(xy 348.264482 -270.934134) (xy 348.272607 -270.985429) (xy 348.273116 -271.011396) (xy 348.272607 -271.037363)
			(xy 348.552771 -271.037363) (xy 348.552771 -270.985429) (xy 348.560896 -270.934134) (xy 348.576944 -270.884741)
			(xy 348.600522 -270.838467) (xy 348.631048 -270.796451) (xy 348.667771 -270.759728) (xy 348.709787 -270.729202)
			(xy 348.756061 -270.705624) (xy 348.805454 -270.689576) (xy 348.856749 -270.681451) (xy 348.908683 -270.681451)
			(xy 348.959978 -270.689576) (xy 349.009371 -270.705624) (xy 349.055645 -270.729202) (xy 349.097661 -270.759728)
			(xy 349.134384 -270.796451) (xy 349.16491 -270.838467) (xy 349.188488 -270.884741) (xy 349.204536 -270.934134)
			(xy 349.212661 -270.985429) (xy 349.21317 -271.011396) (xy 349.212661 -271.037363) (xy 349.492571 -271.037363)
			(xy 349.492571 -270.985429) (xy 349.500696 -270.934134) (xy 349.516744 -270.884741) (xy 349.540322 -270.838467)
			(xy 349.570848 -270.796451) (xy 349.607571 -270.759728) (xy 349.649587 -270.729202) (xy 349.695861 -270.705624)
			(xy 349.745254 -270.689576) (xy 349.796549 -270.681451) (xy 349.848483 -270.681451) (xy 349.899778 -270.689576)
			(xy 349.949171 -270.705624) (xy 349.995445 -270.729202) (xy 350.037461 -270.759728) (xy 350.074184 -270.796451)
			(xy 350.10471 -270.838467) (xy 350.128288 -270.884741) (xy 350.144336 -270.934134) (xy 350.152461 -270.985429)
			(xy 350.15297 -271.011396) (xy 350.152461 -271.037363) (xy 350.432117 -271.037363) (xy 350.432117 -270.985429)
			(xy 350.440242 -270.934134) (xy 350.45629 -270.884741) (xy 350.479868 -270.838467) (xy 350.510394 -270.796451)
			(xy 350.547117 -270.759728) (xy 350.589133 -270.729202) (xy 350.635407 -270.705624) (xy 350.6848 -270.689576)
			(xy 350.736095 -270.681451) (xy 350.788029 -270.681451) (xy 350.839324 -270.689576) (xy 350.888717 -270.705624)
			(xy 350.934991 -270.729202) (xy 350.977007 -270.759728) (xy 351.01373 -270.796451) (xy 351.044256 -270.838467)
			(xy 351.067834 -270.884741) (xy 351.083882 -270.934134) (xy 351.092007 -270.985429) (xy 351.092516 -271.011396)
			(xy 351.092007 -271.037363) (xy 351.371917 -271.037363) (xy 351.371917 -270.985429) (xy 351.380042 -270.934134)
			(xy 351.39609 -270.884741) (xy 351.419668 -270.838467) (xy 351.450194 -270.796451) (xy 351.486917 -270.759728)
			(xy 351.528933 -270.729202) (xy 351.575207 -270.705624) (xy 351.6246 -270.689576) (xy 351.675895 -270.681451)
			(xy 351.727829 -270.681451) (xy 351.779124 -270.689576) (xy 351.828517 -270.705624) (xy 351.874791 -270.729202)
			(xy 351.916807 -270.759728) (xy 351.95353 -270.796451) (xy 351.984056 -270.838467) (xy 352.007634 -270.884741)
			(xy 352.023682 -270.934134) (xy 352.031807 -270.985429) (xy 352.032316 -271.011396) (xy 352.031807 -271.037363)
			(xy 352.311717 -271.037363) (xy 352.311717 -270.985429) (xy 352.319842 -270.934134) (xy 352.33589 -270.884741)
			(xy 352.359468 -270.838467) (xy 352.389994 -270.796451) (xy 352.426717 -270.759728) (xy 352.468733 -270.729202)
			(xy 352.515007 -270.705624) (xy 352.5644 -270.689576) (xy 352.615695 -270.681451) (xy 352.667629 -270.681451)
			(xy 352.718924 -270.689576) (xy 352.768317 -270.705624) (xy 352.814591 -270.729202) (xy 352.856607 -270.759728)
			(xy 352.89333 -270.796451) (xy 352.923856 -270.838467) (xy 352.947434 -270.884741) (xy 352.963482 -270.934134)
			(xy 352.971607 -270.985429) (xy 352.972116 -271.011396) (xy 352.971607 -271.037363) (xy 353.251517 -271.037363)
			(xy 353.251517 -270.985429) (xy 353.259642 -270.934134) (xy 353.27569 -270.884741) (xy 353.299268 -270.838467)
			(xy 353.329794 -270.796451) (xy 353.366517 -270.759728) (xy 353.408533 -270.729202) (xy 353.454807 -270.705624)
			(xy 353.5042 -270.689576) (xy 353.555495 -270.681451) (xy 353.607429 -270.681451) (xy 353.658724 -270.689576)
			(xy 353.708117 -270.705624) (xy 353.754391 -270.729202) (xy 353.796407 -270.759728) (xy 353.83313 -270.796451)
			(xy 353.863656 -270.838467) (xy 353.887234 -270.884741) (xy 353.903282 -270.934134) (xy 353.911407 -270.985429)
			(xy 353.911916 -271.011396) (xy 353.911407 -271.037363) (xy 354.191317 -271.037363) (xy 354.191317 -270.985429)
			(xy 354.199442 -270.934134) (xy 354.21549 -270.884741) (xy 354.239068 -270.838467) (xy 354.269594 -270.796451)
			(xy 354.306317 -270.759728) (xy 354.348333 -270.729202) (xy 354.394607 -270.705624) (xy 354.444 -270.689576)
			(xy 354.495295 -270.681451) (xy 354.547229 -270.681451) (xy 354.598524 -270.689576) (xy 354.647917 -270.705624)
			(xy 354.694191 -270.729202) (xy 354.736207 -270.759728) (xy 354.77293 -270.796451) (xy 354.803456 -270.838467)
			(xy 354.827034 -270.884741) (xy 354.843082 -270.934134) (xy 354.851207 -270.985429) (xy 354.851716 -271.011396)
			(xy 354.851207 -271.037363) (xy 355.131117 -271.037363) (xy 355.131117 -270.985429) (xy 355.139242 -270.934134)
			(xy 355.15529 -270.884741) (xy 355.178868 -270.838467) (xy 355.209394 -270.796451) (xy 355.246117 -270.759728)
			(xy 355.288133 -270.729202) (xy 355.334407 -270.705624) (xy 355.3838 -270.689576) (xy 355.435095 -270.681451)
			(xy 355.487029 -270.681451) (xy 355.538324 -270.689576) (xy 355.587717 -270.705624) (xy 355.633991 -270.729202)
			(xy 355.676007 -270.759728) (xy 355.71273 -270.796451) (xy 355.743256 -270.838467) (xy 355.766834 -270.884741)
			(xy 355.782882 -270.934134) (xy 355.791007 -270.985429) (xy 355.791516 -271.011396) (xy 355.791007 -271.037363)
			(xy 356.070917 -271.037363) (xy 356.070917 -270.985429) (xy 356.079042 -270.934134) (xy 356.09509 -270.884741)
			(xy 356.118668 -270.838467) (xy 356.149194 -270.796451) (xy 356.185917 -270.759728) (xy 356.227933 -270.729202)
			(xy 356.274207 -270.705624) (xy 356.3236 -270.689576) (xy 356.374895 -270.681451) (xy 356.426829 -270.681451)
			(xy 356.478124 -270.689576) (xy 356.527517 -270.705624) (xy 356.573791 -270.729202) (xy 356.615807 -270.759728)
			(xy 356.65253 -270.796451) (xy 356.683056 -270.838467) (xy 356.706634 -270.884741) (xy 356.722682 -270.934134)
			(xy 356.730807 -270.985429) (xy 356.731316 -271.011396) (xy 356.730807 -271.037363) (xy 357.010717 -271.037363)
			(xy 357.010717 -270.985429) (xy 357.018842 -270.934134) (xy 357.03489 -270.884741) (xy 357.058468 -270.838467)
			(xy 357.088994 -270.796451) (xy 357.125717 -270.759728) (xy 357.167733 -270.729202) (xy 357.214007 -270.705624)
			(xy 357.2634 -270.689576) (xy 357.314695 -270.681451) (xy 357.366629 -270.681451) (xy 357.417924 -270.689576)
			(xy 357.467317 -270.705624) (xy 357.513591 -270.729202) (xy 357.555607 -270.759728) (xy 357.59233 -270.796451)
			(xy 357.622856 -270.838467) (xy 357.646434 -270.884741) (xy 357.662482 -270.934134) (xy 357.670607 -270.985429)
			(xy 357.671116 -271.011396) (xy 357.670607 -271.037363) (xy 357.950517 -271.037363) (xy 357.950517 -270.985429)
			(xy 357.958642 -270.934134) (xy 357.97469 -270.884741) (xy 357.998268 -270.838467) (xy 358.028794 -270.796451)
			(xy 358.065517 -270.759728) (xy 358.107533 -270.729202) (xy 358.153807 -270.705624) (xy 358.2032 -270.689576)
			(xy 358.254495 -270.681451) (xy 358.306429 -270.681451) (xy 358.357724 -270.689576) (xy 358.407117 -270.705624)
			(xy 358.453391 -270.729202) (xy 358.495407 -270.759728) (xy 358.53213 -270.796451) (xy 358.562656 -270.838467)
			(xy 358.586234 -270.884741) (xy 358.602282 -270.934134) (xy 358.610407 -270.985429) (xy 358.610916 -271.011396)
			(xy 358.610407 -271.037363) (xy 358.890571 -271.037363) (xy 358.890571 -270.985429) (xy 358.898696 -270.934134)
			(xy 358.914744 -270.884741) (xy 358.938322 -270.838467) (xy 358.968848 -270.796451) (xy 359.005571 -270.759728)
			(xy 359.047587 -270.729202) (xy 359.093861 -270.705624) (xy 359.143254 -270.689576) (xy 359.194549 -270.681451)
			(xy 359.246483 -270.681451) (xy 359.297778 -270.689576) (xy 359.347171 -270.705624) (xy 359.393445 -270.729202)
			(xy 359.435461 -270.759728) (xy 359.472184 -270.796451) (xy 359.50271 -270.838467) (xy 359.526288 -270.884741)
			(xy 359.542336 -270.934134) (xy 359.550461 -270.985429) (xy 359.55097 -271.011396) (xy 359.550461 -271.037363)
			(xy 359.830371 -271.037363) (xy 359.830371 -270.985429) (xy 359.838496 -270.934134) (xy 359.854544 -270.884741)
			(xy 359.878122 -270.838467) (xy 359.908648 -270.796451) (xy 359.945371 -270.759728) (xy 359.987387 -270.729202)
			(xy 360.033661 -270.705624) (xy 360.083054 -270.689576) (xy 360.134349 -270.681451) (xy 360.186283 -270.681451)
			(xy 360.237578 -270.689576) (xy 360.286971 -270.705624) (xy 360.333245 -270.729202) (xy 360.375261 -270.759728)
			(xy 360.411984 -270.796451) (xy 360.44251 -270.838467) (xy 360.466088 -270.884741) (xy 360.482136 -270.934134)
			(xy 360.490261 -270.985429) (xy 360.49077 -271.011396) (xy 360.490261 -271.037363) (xy 360.482136 -271.088658)
			(xy 360.466088 -271.138051) (xy 360.44251 -271.184325) (xy 360.411984 -271.226341) (xy 360.375261 -271.263064)
			(xy 360.333245 -271.29359) (xy 360.286971 -271.317168) (xy 360.237578 -271.333216) (xy 360.186283 -271.341341)
			(xy 360.134349 -271.341341) (xy 360.083054 -271.333216) (xy 360.033661 -271.317168) (xy 359.987387 -271.29359)
			(xy 359.945371 -271.263064) (xy 359.908648 -271.226341) (xy 359.878122 -271.184325) (xy 359.854544 -271.138051)
			(xy 359.838496 -271.088658) (xy 359.830371 -271.037363) (xy 359.550461 -271.037363) (xy 359.542336 -271.088658)
			(xy 359.526288 -271.138051) (xy 359.50271 -271.184325) (xy 359.472184 -271.226341) (xy 359.435461 -271.263064)
			(xy 359.393445 -271.29359) (xy 359.347171 -271.317168) (xy 359.297778 -271.333216) (xy 359.246483 -271.341341)
			(xy 359.194549 -271.341341) (xy 359.143254 -271.333216) (xy 359.093861 -271.317168) (xy 359.047587 -271.29359)
			(xy 359.005571 -271.263064) (xy 358.968848 -271.226341) (xy 358.938322 -271.184325) (xy 358.914744 -271.138051)
			(xy 358.898696 -271.088658) (xy 358.890571 -271.037363) (xy 358.610407 -271.037363) (xy 358.602282 -271.088658)
			(xy 358.586234 -271.138051) (xy 358.562656 -271.184325) (xy 358.53213 -271.226341) (xy 358.495407 -271.263064)
			(xy 358.453391 -271.29359) (xy 358.407117 -271.317168) (xy 358.357724 -271.333216) (xy 358.306429 -271.341341)
			(xy 358.254495 -271.341341) (xy 358.2032 -271.333216) (xy 358.153807 -271.317168) (xy 358.107533 -271.29359)
			(xy 358.065517 -271.263064) (xy 358.028794 -271.226341) (xy 357.998268 -271.184325) (xy 357.97469 -271.138051)
			(xy 357.958642 -271.088658) (xy 357.950517 -271.037363) (xy 357.670607 -271.037363) (xy 357.662482 -271.088658)
			(xy 357.646434 -271.138051) (xy 357.622856 -271.184325) (xy 357.59233 -271.226341) (xy 357.555607 -271.263064)
			(xy 357.513591 -271.29359) (xy 357.467317 -271.317168) (xy 357.417924 -271.333216) (xy 357.366629 -271.341341)
			(xy 357.314695 -271.341341) (xy 357.2634 -271.333216) (xy 357.214007 -271.317168) (xy 357.167733 -271.29359)
			(xy 357.125717 -271.263064) (xy 357.088994 -271.226341) (xy 357.058468 -271.184325) (xy 357.03489 -271.138051)
			(xy 357.018842 -271.088658) (xy 357.010717 -271.037363) (xy 356.730807 -271.037363) (xy 356.722682 -271.088658)
			(xy 356.706634 -271.138051) (xy 356.683056 -271.184325) (xy 356.65253 -271.226341) (xy 356.615807 -271.263064)
			(xy 356.573791 -271.29359) (xy 356.527517 -271.317168) (xy 356.478124 -271.333216) (xy 356.426829 -271.341341)
			(xy 356.374895 -271.341341) (xy 356.3236 -271.333216) (xy 356.274207 -271.317168) (xy 356.227933 -271.29359)
			(xy 356.185917 -271.263064) (xy 356.149194 -271.226341) (xy 356.118668 -271.184325) (xy 356.09509 -271.138051)
			(xy 356.079042 -271.088658) (xy 356.070917 -271.037363) (xy 355.791007 -271.037363) (xy 355.782882 -271.088658)
			(xy 355.766834 -271.138051) (xy 355.743256 -271.184325) (xy 355.71273 -271.226341) (xy 355.676007 -271.263064)
			(xy 355.633991 -271.29359) (xy 355.587717 -271.317168) (xy 355.538324 -271.333216) (xy 355.487029 -271.341341)
			(xy 355.435095 -271.341341) (xy 355.3838 -271.333216) (xy 355.334407 -271.317168) (xy 355.288133 -271.29359)
			(xy 355.246117 -271.263064) (xy 355.209394 -271.226341) (xy 355.178868 -271.184325) (xy 355.15529 -271.138051)
			(xy 355.139242 -271.088658) (xy 355.131117 -271.037363) (xy 354.851207 -271.037363) (xy 354.843082 -271.088658)
			(xy 354.827034 -271.138051) (xy 354.803456 -271.184325) (xy 354.77293 -271.226341) (xy 354.736207 -271.263064)
			(xy 354.694191 -271.29359) (xy 354.647917 -271.317168) (xy 354.598524 -271.333216) (xy 354.547229 -271.341341)
			(xy 354.495295 -271.341341) (xy 354.444 -271.333216) (xy 354.394607 -271.317168) (xy 354.348333 -271.29359)
			(xy 354.306317 -271.263064) (xy 354.269594 -271.226341) (xy 354.239068 -271.184325) (xy 354.21549 -271.138051)
			(xy 354.199442 -271.088658) (xy 354.191317 -271.037363) (xy 353.911407 -271.037363) (xy 353.903282 -271.088658)
			(xy 353.887234 -271.138051) (xy 353.863656 -271.184325) (xy 353.83313 -271.226341) (xy 353.796407 -271.263064)
			(xy 353.754391 -271.29359) (xy 353.708117 -271.317168) (xy 353.658724 -271.333216) (xy 353.607429 -271.341341)
			(xy 353.555495 -271.341341) (xy 353.5042 -271.333216) (xy 353.454807 -271.317168) (xy 353.408533 -271.29359)
			(xy 353.366517 -271.263064) (xy 353.329794 -271.226341) (xy 353.299268 -271.184325) (xy 353.27569 -271.138051)
			(xy 353.259642 -271.088658) (xy 353.251517 -271.037363) (xy 352.971607 -271.037363) (xy 352.963482 -271.088658)
			(xy 352.947434 -271.138051) (xy 352.923856 -271.184325) (xy 352.89333 -271.226341) (xy 352.856607 -271.263064)
			(xy 352.814591 -271.29359) (xy 352.768317 -271.317168) (xy 352.718924 -271.333216) (xy 352.667629 -271.341341)
			(xy 352.615695 -271.341341) (xy 352.5644 -271.333216) (xy 352.515007 -271.317168) (xy 352.468733 -271.29359)
			(xy 352.426717 -271.263064) (xy 352.389994 -271.226341) (xy 352.359468 -271.184325) (xy 352.33589 -271.138051)
			(xy 352.319842 -271.088658) (xy 352.311717 -271.037363) (xy 352.031807 -271.037363) (xy 352.023682 -271.088658)
			(xy 352.007634 -271.138051) (xy 351.984056 -271.184325) (xy 351.95353 -271.226341) (xy 351.916807 -271.263064)
			(xy 351.874791 -271.29359) (xy 351.828517 -271.317168) (xy 351.779124 -271.333216) (xy 351.727829 -271.341341)
			(xy 351.675895 -271.341341) (xy 351.6246 -271.333216) (xy 351.575207 -271.317168) (xy 351.528933 -271.29359)
			(xy 351.486917 -271.263064) (xy 351.450194 -271.226341) (xy 351.419668 -271.184325) (xy 351.39609 -271.138051)
			(xy 351.380042 -271.088658) (xy 351.371917 -271.037363) (xy 351.092007 -271.037363) (xy 351.083882 -271.088658)
			(xy 351.067834 -271.138051) (xy 351.044256 -271.184325) (xy 351.01373 -271.226341) (xy 350.977007 -271.263064)
			(xy 350.934991 -271.29359) (xy 350.888717 -271.317168) (xy 350.839324 -271.333216) (xy 350.788029 -271.341341)
			(xy 350.736095 -271.341341) (xy 350.6848 -271.333216) (xy 350.635407 -271.317168) (xy 350.589133 -271.29359)
			(xy 350.547117 -271.263064) (xy 350.510394 -271.226341) (xy 350.479868 -271.184325) (xy 350.45629 -271.138051)
			(xy 350.440242 -271.088658) (xy 350.432117 -271.037363) (xy 350.152461 -271.037363) (xy 350.144336 -271.088658)
			(xy 350.128288 -271.138051) (xy 350.10471 -271.184325) (xy 350.074184 -271.226341) (xy 350.037461 -271.263064)
			(xy 349.995445 -271.29359) (xy 349.949171 -271.317168) (xy 349.899778 -271.333216) (xy 349.848483 -271.341341)
			(xy 349.796549 -271.341341) (xy 349.745254 -271.333216) (xy 349.695861 -271.317168) (xy 349.649587 -271.29359)
			(xy 349.607571 -271.263064) (xy 349.570848 -271.226341) (xy 349.540322 -271.184325) (xy 349.516744 -271.138051)
			(xy 349.500696 -271.088658) (xy 349.492571 -271.037363) (xy 349.212661 -271.037363) (xy 349.204536 -271.088658)
			(xy 349.188488 -271.138051) (xy 349.16491 -271.184325) (xy 349.134384 -271.226341) (xy 349.097661 -271.263064)
			(xy 349.055645 -271.29359) (xy 349.009371 -271.317168) (xy 348.959978 -271.333216) (xy 348.908683 -271.341341)
			(xy 348.856749 -271.341341) (xy 348.805454 -271.333216) (xy 348.756061 -271.317168) (xy 348.709787 -271.29359)
			(xy 348.667771 -271.263064) (xy 348.631048 -271.226341) (xy 348.600522 -271.184325) (xy 348.576944 -271.138051)
			(xy 348.560896 -271.088658) (xy 348.552771 -271.037363) (xy 348.272607 -271.037363) (xy 348.264482 -271.088658)
			(xy 348.248434 -271.138051) (xy 348.224856 -271.184325) (xy 348.19433 -271.226341) (xy 348.157607 -271.263064)
			(xy 348.115591 -271.29359) (xy 348.069317 -271.317168) (xy 348.019924 -271.333216) (xy 347.968629 -271.341341)
			(xy 347.916695 -271.341341) (xy 347.8654 -271.333216) (xy 347.816007 -271.317168) (xy 347.769733 -271.29359)
			(xy 347.727717 -271.263064) (xy 347.690994 -271.226341) (xy 347.660468 -271.184325) (xy 347.63689 -271.138051)
			(xy 347.620842 -271.088658) (xy 347.612717 -271.037363) (xy 347.332807 -271.037363) (xy 347.324682 -271.088658)
			(xy 347.308634 -271.138051) (xy 347.285056 -271.184325) (xy 347.25453 -271.226341) (xy 347.217807 -271.263064)
			(xy 347.175791 -271.29359) (xy 347.129517 -271.317168) (xy 347.080124 -271.333216) (xy 347.028829 -271.341341)
			(xy 346.976895 -271.341341) (xy 346.9256 -271.333216) (xy 346.876207 -271.317168) (xy 346.829933 -271.29359)
			(xy 346.787917 -271.263064) (xy 346.751194 -271.226341) (xy 346.720668 -271.184325) (xy 346.69709 -271.138051)
			(xy 346.681042 -271.088658) (xy 346.672917 -271.037363) (xy 346.393007 -271.037363) (xy 346.384882 -271.088658)
			(xy 346.368834 -271.138051) (xy 346.345256 -271.184325) (xy 346.31473 -271.226341) (xy 346.278007 -271.263064)
			(xy 346.235991 -271.29359) (xy 346.189717 -271.317168) (xy 346.140324 -271.333216) (xy 346.089029 -271.341341)
			(xy 346.037095 -271.341341) (xy 345.9858 -271.333216) (xy 345.936407 -271.317168) (xy 345.890133 -271.29359)
			(xy 345.848117 -271.263064) (xy 345.811394 -271.226341) (xy 345.780868 -271.184325) (xy 345.75729 -271.138051)
			(xy 345.741242 -271.088658) (xy 345.733117 -271.037363) (xy 345.453207 -271.037363) (xy 345.445082 -271.088658)
			(xy 345.429034 -271.138051) (xy 345.405456 -271.184325) (xy 345.37493 -271.226341) (xy 345.338207 -271.263064)
			(xy 345.296191 -271.29359) (xy 345.249917 -271.317168) (xy 345.200524 -271.333216) (xy 345.149229 -271.341341)
			(xy 345.097295 -271.341341) (xy 345.046 -271.333216) (xy 344.996607 -271.317168) (xy 344.950333 -271.29359)
			(xy 344.908317 -271.263064) (xy 344.871594 -271.226341) (xy 344.841068 -271.184325) (xy 344.81749 -271.138051)
			(xy 344.801442 -271.088658) (xy 344.793317 -271.037363) (xy 344.513407 -271.037363) (xy 344.505282 -271.088658)
			(xy 344.489234 -271.138051) (xy 344.465656 -271.184325) (xy 344.43513 -271.226341) (xy 344.398407 -271.263064)
			(xy 344.356391 -271.29359) (xy 344.310117 -271.317168) (xy 344.260724 -271.333216) (xy 344.209429 -271.341341)
			(xy 344.157495 -271.341341) (xy 344.1062 -271.333216) (xy 344.056807 -271.317168) (xy 344.010533 -271.29359)
			(xy 343.968517 -271.263064) (xy 343.931794 -271.226341) (xy 343.901268 -271.184325) (xy 343.87769 -271.138051)
			(xy 343.861642 -271.088658) (xy 343.853517 -271.037363) (xy 343.573607 -271.037363) (xy 343.565482 -271.088658)
			(xy 343.549434 -271.138051) (xy 343.525856 -271.184325) (xy 343.49533 -271.226341) (xy 343.458607 -271.263064)
			(xy 343.416591 -271.29359) (xy 343.370317 -271.317168) (xy 343.320924 -271.333216) (xy 343.269629 -271.341341)
			(xy 343.217695 -271.341341) (xy 343.1664 -271.333216) (xy 343.117007 -271.317168) (xy 343.070733 -271.29359)
			(xy 343.028717 -271.263064) (xy 342.991994 -271.226341) (xy 342.961468 -271.184325) (xy 342.93789 -271.138051)
			(xy 342.921842 -271.088658) (xy 342.913717 -271.037363) (xy 342.634061 -271.037363) (xy 342.625936 -271.088658)
			(xy 342.609888 -271.138051) (xy 342.58631 -271.184325) (xy 342.555784 -271.226341) (xy 342.519061 -271.263064)
			(xy 342.477045 -271.29359) (xy 342.430771 -271.317168) (xy 342.381378 -271.333216) (xy 342.330083 -271.341341)
			(xy 342.278149 -271.341341) (xy 342.226854 -271.333216) (xy 342.177461 -271.317168) (xy 342.131187 -271.29359)
			(xy 342.089171 -271.263064) (xy 342.052448 -271.226341) (xy 342.021922 -271.184325) (xy 341.998344 -271.138051)
			(xy 341.982296 -271.088658) (xy 341.974171 -271.037363) (xy 341.694007 -271.037363) (xy 341.685882 -271.088658)
			(xy 341.669834 -271.138051) (xy 341.646256 -271.184325) (xy 341.61573 -271.226341) (xy 341.579007 -271.263064)
			(xy 341.536991 -271.29359) (xy 341.490717 -271.317168) (xy 341.441324 -271.333216) (xy 341.390029 -271.341341)
			(xy 341.338095 -271.341341) (xy 341.2868 -271.333216) (xy 341.237407 -271.317168) (xy 341.191133 -271.29359)
			(xy 341.149117 -271.263064) (xy 341.112394 -271.226341) (xy 341.081868 -271.184325) (xy 341.05829 -271.138051)
			(xy 341.042242 -271.088658) (xy 341.034117 -271.037363) (xy 340.754207 -271.037363) (xy 340.746082 -271.088658)
			(xy 340.730034 -271.138051) (xy 340.706456 -271.184325) (xy 340.67593 -271.226341) (xy 340.639207 -271.263064)
			(xy 340.597191 -271.29359) (xy 340.550917 -271.317168) (xy 340.501524 -271.333216) (xy 340.450229 -271.341341)
			(xy 340.398295 -271.341341) (xy 340.347 -271.333216) (xy 340.297607 -271.317168) (xy 340.251333 -271.29359)
			(xy 340.209317 -271.263064) (xy 340.172594 -271.226341) (xy 340.142068 -271.184325) (xy 340.11849 -271.138051)
			(xy 340.102442 -271.088658) (xy 340.094317 -271.037363) (xy 339.813749 -271.037363) (xy 339.811824 -271.062269)
			(xy 339.800122 -271.111932) (xy 339.780928 -271.159207) (xy 339.754697 -271.202971) (xy 339.722053 -271.242185)
			(xy 339.68377 -271.275916) (xy 339.662516 -271.290034) (xy 339.651848 -271.296892) (xy 339.627464 -271.339564)
			(xy 339.627464 -271.45869) (xy 339.627779 -271.467077) (xy 339.633278 -271.482923) (xy 339.64367 -271.496089)
			(xy 339.650578 -271.500854) (xy 339.718142 -271.5387) (xy 339.723391 -271.54119) (xy 339.734687 -271.543889)
			(xy 339.740494 -271.544034) (xy 339.76691 -271.544034) (xy 339.791294 -271.53743) (xy 339.795612 -271.535144)
			(xy 339.820105 -271.522375) (xy 339.872286 -271.504273) (xy 339.926746 -271.495074) (xy 339.954362 -271.494504)
			(xy 339.954616 -271.494504) (xy 339.980601 -271.495015) (xy 340.031932 -271.503147) (xy 340.081359 -271.519209)
			(xy 340.127664 -271.542805) (xy 340.169709 -271.573354) (xy 340.206457 -271.610103) (xy 340.237004 -271.652149)
			(xy 340.260597 -271.698456) (xy 340.276657 -271.747883) (xy 340.284787 -271.799215) (xy 340.284787 -271.851179)
			(xy 340.564471 -271.851179) (xy 340.564471 -271.799245) (xy 340.572596 -271.74795) (xy 340.588644 -271.698557)
			(xy 340.612222 -271.652283) (xy 340.642748 -271.610267) (xy 340.679471 -271.573544) (xy 340.721487 -271.543018)
			(xy 340.767761 -271.51944) (xy 340.817154 -271.503392) (xy 340.868449 -271.495267) (xy 340.920383 -271.495267)
			(xy 340.971678 -271.503392) (xy 341.021071 -271.51944) (xy 341.067345 -271.543018) (xy 341.109361 -271.573544)
			(xy 341.146084 -271.610267) (xy 341.17661 -271.652283) (xy 341.200188 -271.698557) (xy 341.216236 -271.74795)
			(xy 341.224361 -271.799245) (xy 341.22487 -271.825212) (xy 341.224361 -271.851179) (xy 341.504271 -271.851179)
			(xy 341.504271 -271.799245) (xy 341.512396 -271.74795) (xy 341.528444 -271.698557) (xy 341.552022 -271.652283)
			(xy 341.582548 -271.610267) (xy 341.619271 -271.573544) (xy 341.661287 -271.543018) (xy 341.707561 -271.51944)
			(xy 341.756954 -271.503392) (xy 341.808249 -271.495267) (xy 341.860183 -271.495267) (xy 341.911478 -271.503392)
			(xy 341.960871 -271.51944) (xy 342.007145 -271.543018) (xy 342.049161 -271.573544) (xy 342.085884 -271.610267)
			(xy 342.11641 -271.652283) (xy 342.139988 -271.698557) (xy 342.156036 -271.74795) (xy 342.164161 -271.799245)
			(xy 342.16467 -271.825212) (xy 342.164161 -271.851179) (xy 342.444071 -271.851179) (xy 342.444071 -271.799245)
			(xy 342.452196 -271.74795) (xy 342.468244 -271.698557) (xy 342.491822 -271.652283) (xy 342.522348 -271.610267)
			(xy 342.559071 -271.573544) (xy 342.601087 -271.543018) (xy 342.647361 -271.51944) (xy 342.696754 -271.503392)
			(xy 342.748049 -271.495267) (xy 342.799983 -271.495267) (xy 342.851278 -271.503392) (xy 342.900671 -271.51944)
			(xy 342.946945 -271.543018) (xy 342.988961 -271.573544) (xy 343.025684 -271.610267) (xy 343.05621 -271.652283)
			(xy 343.079788 -271.698557) (xy 343.095836 -271.74795) (xy 343.103961 -271.799245) (xy 343.10447 -271.825212)
			(xy 343.103961 -271.851179) (xy 343.383871 -271.851179) (xy 343.383871 -271.799245) (xy 343.391996 -271.74795)
			(xy 343.408044 -271.698557) (xy 343.431622 -271.652283) (xy 343.462148 -271.610267) (xy 343.498871 -271.573544)
			(xy 343.540887 -271.543018) (xy 343.587161 -271.51944) (xy 343.636554 -271.503392) (xy 343.687849 -271.495267)
			(xy 343.739783 -271.495267) (xy 343.791078 -271.503392) (xy 343.840471 -271.51944) (xy 343.886745 -271.543018)
			(xy 343.928761 -271.573544) (xy 343.965484 -271.610267) (xy 343.99601 -271.652283) (xy 344.019588 -271.698557)
			(xy 344.035636 -271.74795) (xy 344.043761 -271.799245) (xy 344.04427 -271.825212) (xy 344.043761 -271.851179)
			(xy 344.323671 -271.851179) (xy 344.323671 -271.799245) (xy 344.331796 -271.74795) (xy 344.347844 -271.698557)
			(xy 344.371422 -271.652283) (xy 344.401948 -271.610267) (xy 344.438671 -271.573544) (xy 344.480687 -271.543018)
			(xy 344.526961 -271.51944) (xy 344.576354 -271.503392) (xy 344.627649 -271.495267) (xy 344.679583 -271.495267)
			(xy 344.730878 -271.503392) (xy 344.780271 -271.51944) (xy 344.826545 -271.543018) (xy 344.868561 -271.573544)
			(xy 344.905284 -271.610267) (xy 344.93581 -271.652283) (xy 344.959388 -271.698557) (xy 344.975436 -271.74795)
			(xy 344.983561 -271.799245) (xy 344.98407 -271.825212) (xy 344.983561 -271.851179) (xy 345.263217 -271.851179)
			(xy 345.263217 -271.799245) (xy 345.271342 -271.74795) (xy 345.28739 -271.698557) (xy 345.310968 -271.652283)
			(xy 345.341494 -271.610267) (xy 345.378217 -271.573544) (xy 345.420233 -271.543018) (xy 345.466507 -271.51944)
			(xy 345.5159 -271.503392) (xy 345.567195 -271.495267) (xy 345.619129 -271.495267) (xy 345.670424 -271.503392)
			(xy 345.719817 -271.51944) (xy 345.766091 -271.543018) (xy 345.808107 -271.573544) (xy 345.84483 -271.610267)
			(xy 345.875356 -271.652283) (xy 345.898934 -271.698557) (xy 345.914982 -271.74795) (xy 345.923107 -271.799245)
			(xy 345.923616 -271.825212) (xy 345.923107 -271.851179) (xy 346.203271 -271.851179) (xy 346.203271 -271.799245)
			(xy 346.211396 -271.74795) (xy 346.227444 -271.698557) (xy 346.251022 -271.652283) (xy 346.281548 -271.610267)
			(xy 346.318271 -271.573544) (xy 346.360287 -271.543018) (xy 346.406561 -271.51944) (xy 346.455954 -271.503392)
			(xy 346.507249 -271.495267) (xy 346.559183 -271.495267) (xy 346.610478 -271.503392) (xy 346.659871 -271.51944)
			(xy 346.706145 -271.543018) (xy 346.748161 -271.573544) (xy 346.784884 -271.610267) (xy 346.81541 -271.652283)
			(xy 346.838988 -271.698557) (xy 346.855036 -271.74795) (xy 346.863161 -271.799245) (xy 346.86367 -271.825212)
			(xy 346.863161 -271.851179) (xy 347.143071 -271.851179) (xy 347.143071 -271.799245) (xy 347.151196 -271.74795)
			(xy 347.167244 -271.698557) (xy 347.190822 -271.652283) (xy 347.221348 -271.610267) (xy 347.258071 -271.573544)
			(xy 347.300087 -271.543018) (xy 347.346361 -271.51944) (xy 347.395754 -271.503392) (xy 347.447049 -271.495267)
			(xy 347.498983 -271.495267) (xy 347.550278 -271.503392) (xy 347.599671 -271.51944) (xy 347.645945 -271.543018)
			(xy 347.687961 -271.573544) (xy 347.724684 -271.610267) (xy 347.75521 -271.652283) (xy 347.778788 -271.698557)
			(xy 347.794836 -271.74795) (xy 347.802961 -271.799245) (xy 347.80347 -271.825212) (xy 347.802961 -271.851179)
			(xy 348.082871 -271.851179) (xy 348.082871 -271.799245) (xy 348.090996 -271.74795) (xy 348.107044 -271.698557)
			(xy 348.130622 -271.652283) (xy 348.161148 -271.610267) (xy 348.197871 -271.573544) (xy 348.239887 -271.543018)
			(xy 348.286161 -271.51944) (xy 348.335554 -271.503392) (xy 348.386849 -271.495267) (xy 348.438783 -271.495267)
			(xy 348.490078 -271.503392) (xy 348.539471 -271.51944) (xy 348.585745 -271.543018) (xy 348.627761 -271.573544)
			(xy 348.664484 -271.610267) (xy 348.69501 -271.652283) (xy 348.718588 -271.698557) (xy 348.734636 -271.74795)
			(xy 348.742761 -271.799245) (xy 348.74327 -271.825212) (xy 348.742761 -271.851179) (xy 349.022671 -271.851179)
			(xy 349.022671 -271.799245) (xy 349.030796 -271.74795) (xy 349.046844 -271.698557) (xy 349.070422 -271.652283)
			(xy 349.100948 -271.610267) (xy 349.137671 -271.573544) (xy 349.179687 -271.543018) (xy 349.225961 -271.51944)
			(xy 349.275354 -271.503392) (xy 349.326649 -271.495267) (xy 349.378583 -271.495267) (xy 349.429878 -271.503392)
			(xy 349.479271 -271.51944) (xy 349.525545 -271.543018) (xy 349.567561 -271.573544) (xy 349.604284 -271.610267)
			(xy 349.63481 -271.652283) (xy 349.658388 -271.698557) (xy 349.674436 -271.74795) (xy 349.682561 -271.799245)
			(xy 349.68307 -271.825212) (xy 349.682561 -271.851179) (xy 349.962471 -271.851179) (xy 349.962471 -271.799245)
			(xy 349.970596 -271.74795) (xy 349.986644 -271.698557) (xy 350.010222 -271.652283) (xy 350.040748 -271.610267)
			(xy 350.077471 -271.573544) (xy 350.119487 -271.543018) (xy 350.165761 -271.51944) (xy 350.215154 -271.503392)
			(xy 350.266449 -271.495267) (xy 350.318383 -271.495267) (xy 350.369678 -271.503392) (xy 350.419071 -271.51944)
			(xy 350.465345 -271.543018) (xy 350.507361 -271.573544) (xy 350.544084 -271.610267) (xy 350.57461 -271.652283)
			(xy 350.598188 -271.698557) (xy 350.614236 -271.74795) (xy 350.622361 -271.799245) (xy 350.62287 -271.825212)
			(xy 350.622361 -271.851179) (xy 350.902271 -271.851179) (xy 350.902271 -271.799245) (xy 350.910396 -271.74795)
			(xy 350.926444 -271.698557) (xy 350.950022 -271.652283) (xy 350.980548 -271.610267) (xy 351.017271 -271.573544)
			(xy 351.059287 -271.543018) (xy 351.105561 -271.51944) (xy 351.154954 -271.503392) (xy 351.206249 -271.495267)
			(xy 351.258183 -271.495267) (xy 351.309478 -271.503392) (xy 351.358871 -271.51944) (xy 351.405145 -271.543018)
			(xy 351.447161 -271.573544) (xy 351.483884 -271.610267) (xy 351.51441 -271.652283) (xy 351.537988 -271.698557)
			(xy 351.554036 -271.74795) (xy 351.562161 -271.799245) (xy 351.56267 -271.825212) (xy 351.562161 -271.851179)
			(xy 351.842071 -271.851179) (xy 351.842071 -271.799245) (xy 351.850196 -271.74795) (xy 351.866244 -271.698557)
			(xy 351.889822 -271.652283) (xy 351.920348 -271.610267) (xy 351.957071 -271.573544) (xy 351.999087 -271.543018)
			(xy 352.045361 -271.51944) (xy 352.094754 -271.503392) (xy 352.146049 -271.495267) (xy 352.197983 -271.495267)
			(xy 352.249278 -271.503392) (xy 352.298671 -271.51944) (xy 352.344945 -271.543018) (xy 352.386961 -271.573544)
			(xy 352.423684 -271.610267) (xy 352.45421 -271.652283) (xy 352.477788 -271.698557) (xy 352.493836 -271.74795)
			(xy 352.501961 -271.799245) (xy 352.50247 -271.825212) (xy 352.501961 -271.851179) (xy 352.781871 -271.851179)
			(xy 352.781871 -271.799245) (xy 352.789996 -271.74795) (xy 352.806044 -271.698557) (xy 352.829622 -271.652283)
			(xy 352.860148 -271.610267) (xy 352.896871 -271.573544) (xy 352.938887 -271.543018) (xy 352.985161 -271.51944)
			(xy 353.034554 -271.503392) (xy 353.085849 -271.495267) (xy 353.137783 -271.495267) (xy 353.189078 -271.503392)
			(xy 353.238471 -271.51944) (xy 353.284745 -271.543018) (xy 353.326761 -271.573544) (xy 353.363484 -271.610267)
			(xy 353.39401 -271.652283) (xy 353.417588 -271.698557) (xy 353.433636 -271.74795) (xy 353.441761 -271.799245)
			(xy 353.44227 -271.825212) (xy 353.441761 -271.851179) (xy 353.721671 -271.851179) (xy 353.721671 -271.799245)
			(xy 353.729796 -271.74795) (xy 353.745844 -271.698557) (xy 353.769422 -271.652283) (xy 353.799948 -271.610267)
			(xy 353.836671 -271.573544) (xy 353.878687 -271.543018) (xy 353.924961 -271.51944) (xy 353.974354 -271.503392)
			(xy 354.025649 -271.495267) (xy 354.077583 -271.495267) (xy 354.128878 -271.503392) (xy 354.178271 -271.51944)
			(xy 354.224545 -271.543018) (xy 354.266561 -271.573544) (xy 354.303284 -271.610267) (xy 354.33381 -271.652283)
			(xy 354.357388 -271.698557) (xy 354.373436 -271.74795) (xy 354.381561 -271.799245) (xy 354.38207 -271.825212)
			(xy 354.381561 -271.851179) (xy 354.661471 -271.851179) (xy 354.661471 -271.799245) (xy 354.669596 -271.74795)
			(xy 354.685644 -271.698557) (xy 354.709222 -271.652283) (xy 354.739748 -271.610267) (xy 354.776471 -271.573544)
			(xy 354.818487 -271.543018) (xy 354.864761 -271.51944) (xy 354.914154 -271.503392) (xy 354.965449 -271.495267)
			(xy 355.017383 -271.495267) (xy 355.068678 -271.503392) (xy 355.118071 -271.51944) (xy 355.164345 -271.543018)
			(xy 355.206361 -271.573544) (xy 355.243084 -271.610267) (xy 355.27361 -271.652283) (xy 355.297188 -271.698557)
			(xy 355.313236 -271.74795) (xy 355.321361 -271.799245) (xy 355.32187 -271.825212) (xy 355.321361 -271.851179)
			(xy 355.601271 -271.851179) (xy 355.601271 -271.799245) (xy 355.609396 -271.74795) (xy 355.625444 -271.698557)
			(xy 355.649022 -271.652283) (xy 355.679548 -271.610267) (xy 355.716271 -271.573544) (xy 355.758287 -271.543018)
			(xy 355.804561 -271.51944) (xy 355.853954 -271.503392) (xy 355.905249 -271.495267) (xy 355.957183 -271.495267)
			(xy 356.008478 -271.503392) (xy 356.057871 -271.51944) (xy 356.104145 -271.543018) (xy 356.146161 -271.573544)
			(xy 356.182884 -271.610267) (xy 356.21341 -271.652283) (xy 356.236988 -271.698557) (xy 356.253036 -271.74795)
			(xy 356.261161 -271.799245) (xy 356.26167 -271.825212) (xy 356.261161 -271.851179) (xy 356.541071 -271.851179)
			(xy 356.541071 -271.799245) (xy 356.549196 -271.74795) (xy 356.565244 -271.698557) (xy 356.588822 -271.652283)
			(xy 356.619348 -271.610267) (xy 356.656071 -271.573544) (xy 356.698087 -271.543018) (xy 356.744361 -271.51944)
			(xy 356.793754 -271.503392) (xy 356.845049 -271.495267) (xy 356.896983 -271.495267) (xy 356.948278 -271.503392)
			(xy 356.997671 -271.51944) (xy 357.043945 -271.543018) (xy 357.085961 -271.573544) (xy 357.122684 -271.610267)
			(xy 357.15321 -271.652283) (xy 357.176788 -271.698557) (xy 357.192836 -271.74795) (xy 357.200961 -271.799245)
			(xy 357.20147 -271.825212) (xy 357.200961 -271.851179) (xy 357.480363 -271.851179) (xy 357.480363 -271.799245)
			(xy 357.488488 -271.74795) (xy 357.504536 -271.698557) (xy 357.528114 -271.652283) (xy 357.55864 -271.610267)
			(xy 357.595363 -271.573544) (xy 357.637379 -271.543018) (xy 357.683653 -271.51944) (xy 357.733046 -271.503392)
			(xy 357.784341 -271.495267) (xy 357.836275 -271.495267) (xy 357.88757 -271.503392) (xy 357.936963 -271.51944)
			(xy 357.983237 -271.543018) (xy 358.025253 -271.573544) (xy 358.061976 -271.610267) (xy 358.092502 -271.652283)
			(xy 358.11608 -271.698557) (xy 358.132128 -271.74795) (xy 358.140253 -271.799245) (xy 358.140762 -271.825212)
			(xy 358.140253 -271.851179) (xy 358.420671 -271.851179) (xy 358.420671 -271.799245) (xy 358.428796 -271.74795)
			(xy 358.444844 -271.698557) (xy 358.468422 -271.652283) (xy 358.498948 -271.610267) (xy 358.535671 -271.573544)
			(xy 358.577687 -271.543018) (xy 358.623961 -271.51944) (xy 358.673354 -271.503392) (xy 358.724649 -271.495267)
			(xy 358.776583 -271.495267) (xy 358.827878 -271.503392) (xy 358.877271 -271.51944) (xy 358.923545 -271.543018)
			(xy 358.965561 -271.573544) (xy 359.002284 -271.610267) (xy 359.03281 -271.652283) (xy 359.056388 -271.698557)
			(xy 359.072436 -271.74795) (xy 359.080561 -271.799245) (xy 359.08107 -271.825212) (xy 359.080561 -271.851179)
			(xy 359.360217 -271.851179) (xy 359.360217 -271.799245) (xy 359.368342 -271.74795) (xy 359.38439 -271.698557)
			(xy 359.407968 -271.652283) (xy 359.438494 -271.610267) (xy 359.475217 -271.573544) (xy 359.517233 -271.543018)
			(xy 359.563507 -271.51944) (xy 359.6129 -271.503392) (xy 359.664195 -271.495267) (xy 359.716129 -271.495267)
			(xy 359.767424 -271.503392) (xy 359.816817 -271.51944) (xy 359.863091 -271.543018) (xy 359.905107 -271.573544)
			(xy 359.94183 -271.610267) (xy 359.972356 -271.652283) (xy 359.995934 -271.698557) (xy 360.011982 -271.74795)
			(xy 360.020107 -271.799245) (xy 360.020616 -271.825212) (xy 360.020107 -271.851179) (xy 360.300017 -271.851179)
			(xy 360.300017 -271.799245) (xy 360.308142 -271.74795) (xy 360.32419 -271.698557) (xy 360.347768 -271.652283)
			(xy 360.378294 -271.610267) (xy 360.415017 -271.573544) (xy 360.457033 -271.543018) (xy 360.503307 -271.51944)
			(xy 360.5527 -271.503392) (xy 360.603995 -271.495267) (xy 360.655929 -271.495267) (xy 360.707224 -271.503392)
			(xy 360.756617 -271.51944) (xy 360.802891 -271.543018) (xy 360.844907 -271.573544) (xy 360.88163 -271.610267)
			(xy 360.912156 -271.652283) (xy 360.935734 -271.698557) (xy 360.951782 -271.74795) (xy 360.959907 -271.799245)
			(xy 360.960416 -271.825212) (xy 360.959907 -271.851179) (xy 361.239817 -271.851179) (xy 361.239817 -271.799245)
			(xy 361.247942 -271.74795) (xy 361.26399 -271.698557) (xy 361.287568 -271.652283) (xy 361.318094 -271.610267)
			(xy 361.354817 -271.573544) (xy 361.396833 -271.543018) (xy 361.443107 -271.51944) (xy 361.4925 -271.503392)
			(xy 361.543795 -271.495267) (xy 361.595729 -271.495267) (xy 361.647024 -271.503392) (xy 361.696417 -271.51944)
			(xy 361.742691 -271.543018) (xy 361.784707 -271.573544) (xy 361.82143 -271.610267) (xy 361.851956 -271.652283)
			(xy 361.875534 -271.698557) (xy 361.891582 -271.74795) (xy 361.899707 -271.799245) (xy 361.900216 -271.825212)
			(xy 361.899707 -271.851179) (xy 362.179871 -271.851179) (xy 362.179871 -271.799245) (xy 362.187996 -271.74795)
			(xy 362.204044 -271.698557) (xy 362.227622 -271.652283) (xy 362.258148 -271.610267) (xy 362.294871 -271.573544)
			(xy 362.336887 -271.543018) (xy 362.383161 -271.51944) (xy 362.432554 -271.503392) (xy 362.483849 -271.495267)
			(xy 362.535783 -271.495267) (xy 362.587078 -271.503392) (xy 362.636471 -271.51944) (xy 362.682745 -271.543018)
			(xy 362.724761 -271.573544) (xy 362.761484 -271.610267) (xy 362.79201 -271.652283) (xy 362.815588 -271.698557)
			(xy 362.831636 -271.74795) (xy 362.839761 -271.799245) (xy 362.84027 -271.825212) (xy 362.839761 -271.851179)
			(xy 363.119671 -271.851179) (xy 363.119671 -271.799245) (xy 363.127796 -271.74795) (xy 363.143844 -271.698557)
			(xy 363.167422 -271.652283) (xy 363.197948 -271.610267) (xy 363.234671 -271.573544) (xy 363.276687 -271.543018)
			(xy 363.322961 -271.51944) (xy 363.372354 -271.503392) (xy 363.423649 -271.495267) (xy 363.475583 -271.495267)
			(xy 363.526878 -271.503392) (xy 363.576271 -271.51944) (xy 363.622545 -271.543018) (xy 363.664561 -271.573544)
			(xy 363.701284 -271.610267) (xy 363.73181 -271.652283) (xy 363.755388 -271.698557) (xy 363.771436 -271.74795)
			(xy 363.779561 -271.799245) (xy 363.78007 -271.825212) (xy 363.779561 -271.851179) (xy 364.058963 -271.851179)
			(xy 364.058963 -271.799245) (xy 364.067088 -271.74795) (xy 364.083136 -271.698557) (xy 364.106714 -271.652283)
			(xy 364.13724 -271.610267) (xy 364.173963 -271.573544) (xy 364.215979 -271.543018) (xy 364.262253 -271.51944)
			(xy 364.311646 -271.503392) (xy 364.362941 -271.495267) (xy 364.414875 -271.495267) (xy 364.46617 -271.503392)
			(xy 364.515563 -271.51944) (xy 364.561837 -271.543018) (xy 364.603853 -271.573544) (xy 364.640576 -271.610267)
			(xy 364.671102 -271.652283) (xy 364.69468 -271.698557) (xy 364.710728 -271.74795) (xy 364.718853 -271.799245)
			(xy 364.719362 -271.825212) (xy 364.718853 -271.851179) (xy 364.999271 -271.851179) (xy 364.999271 -271.799245)
			(xy 365.007396 -271.74795) (xy 365.023444 -271.698557) (xy 365.047022 -271.652283) (xy 365.077548 -271.610267)
			(xy 365.114271 -271.573544) (xy 365.156287 -271.543018) (xy 365.202561 -271.51944) (xy 365.251954 -271.503392)
			(xy 365.303249 -271.495267) (xy 365.355183 -271.495267) (xy 365.406478 -271.503392) (xy 365.455871 -271.51944)
			(xy 365.502145 -271.543018) (xy 365.544161 -271.573544) (xy 365.580884 -271.610267) (xy 365.61141 -271.652283)
			(xy 365.634988 -271.698557) (xy 365.651036 -271.74795) (xy 365.659161 -271.799245) (xy 365.65967 -271.825212)
			(xy 365.659161 -271.851179) (xy 365.938563 -271.851179) (xy 365.938563 -271.799245) (xy 365.946688 -271.74795)
			(xy 365.962736 -271.698557) (xy 365.986314 -271.652283) (xy 366.01684 -271.610267) (xy 366.053563 -271.573544)
			(xy 366.095579 -271.543018) (xy 366.141853 -271.51944) (xy 366.191246 -271.503392) (xy 366.242541 -271.495267)
			(xy 366.294475 -271.495267) (xy 366.34577 -271.503392) (xy 366.395163 -271.51944) (xy 366.441437 -271.543018)
			(xy 366.483453 -271.573544) (xy 366.520176 -271.610267) (xy 366.550702 -271.652283) (xy 366.57428 -271.698557)
			(xy 366.590328 -271.74795) (xy 366.598453 -271.799245) (xy 366.598962 -271.825212) (xy 366.598453 -271.851179)
			(xy 366.878363 -271.851179) (xy 366.878363 -271.799245) (xy 366.886488 -271.74795) (xy 366.902536 -271.698557)
			(xy 366.926114 -271.652283) (xy 366.95664 -271.610267) (xy 366.993363 -271.573544) (xy 367.035379 -271.543018)
			(xy 367.081653 -271.51944) (xy 367.131046 -271.503392) (xy 367.182341 -271.495267) (xy 367.234275 -271.495267)
			(xy 367.28557 -271.503392) (xy 367.334963 -271.51944) (xy 367.381237 -271.543018) (xy 367.423253 -271.573544)
			(xy 367.459976 -271.610267) (xy 367.490502 -271.652283) (xy 367.51408 -271.698557) (xy 367.530128 -271.74795)
			(xy 367.538253 -271.799245) (xy 367.538762 -271.825212) (xy 367.538253 -271.851179) (xy 367.818671 -271.851179)
			(xy 367.818671 -271.799245) (xy 367.826796 -271.74795) (xy 367.842844 -271.698557) (xy 367.866422 -271.652283)
			(xy 367.896948 -271.610267) (xy 367.933671 -271.573544) (xy 367.975687 -271.543018) (xy 368.021961 -271.51944)
			(xy 368.071354 -271.503392) (xy 368.122649 -271.495267) (xy 368.174583 -271.495267) (xy 368.225878 -271.503392)
			(xy 368.275271 -271.51944) (xy 368.321545 -271.543018) (xy 368.363561 -271.573544) (xy 368.400284 -271.610267)
			(xy 368.43081 -271.652283) (xy 368.454388 -271.698557) (xy 368.470436 -271.74795) (xy 368.478561 -271.799245)
			(xy 368.47907 -271.825212) (xy 368.478561 -271.851179) (xy 368.758471 -271.851179) (xy 368.758471 -271.799245)
			(xy 368.766596 -271.74795) (xy 368.782644 -271.698557) (xy 368.806222 -271.652283) (xy 368.836748 -271.610267)
			(xy 368.873471 -271.573544) (xy 368.915487 -271.543018) (xy 368.961761 -271.51944) (xy 369.011154 -271.503392)
			(xy 369.062449 -271.495267) (xy 369.114383 -271.495267) (xy 369.165678 -271.503392) (xy 369.215071 -271.51944)
			(xy 369.261345 -271.543018) (xy 369.303361 -271.573544) (xy 369.340084 -271.610267) (xy 369.37061 -271.652283)
			(xy 369.394188 -271.698557) (xy 369.410236 -271.74795) (xy 369.418361 -271.799245) (xy 369.41887 -271.825212)
			(xy 369.418361 -271.851179) (xy 369.698271 -271.851179) (xy 369.698271 -271.799245) (xy 369.706396 -271.74795)
			(xy 369.722444 -271.698557) (xy 369.746022 -271.652283) (xy 369.776548 -271.610267) (xy 369.813271 -271.573544)
			(xy 369.855287 -271.543018) (xy 369.901561 -271.51944) (xy 369.950954 -271.503392) (xy 370.002249 -271.495267)
			(xy 370.054183 -271.495267) (xy 370.105478 -271.503392) (xy 370.154871 -271.51944) (xy 370.201145 -271.543018)
			(xy 370.243161 -271.573544) (xy 370.279884 -271.610267) (xy 370.31041 -271.652283) (xy 370.333988 -271.698557)
			(xy 370.350036 -271.74795) (xy 370.358161 -271.799245) (xy 370.35867 -271.825212) (xy 370.358161 -271.851179)
			(xy 370.638071 -271.851179) (xy 370.638071 -271.799245) (xy 370.646196 -271.74795) (xy 370.662244 -271.698557)
			(xy 370.685822 -271.652283) (xy 370.716348 -271.610267) (xy 370.753071 -271.573544) (xy 370.795087 -271.543018)
			(xy 370.841361 -271.51944) (xy 370.890754 -271.503392) (xy 370.942049 -271.495267) (xy 370.993983 -271.495267)
			(xy 371.045278 -271.503392) (xy 371.094671 -271.51944) (xy 371.140945 -271.543018) (xy 371.182961 -271.573544)
			(xy 371.219684 -271.610267) (xy 371.25021 -271.652283) (xy 371.273788 -271.698557) (xy 371.289836 -271.74795)
			(xy 371.297961 -271.799245) (xy 371.29847 -271.825212) (xy 371.297961 -271.851179) (xy 371.577871 -271.851179)
			(xy 371.577871 -271.799245) (xy 371.585996 -271.74795) (xy 371.602044 -271.698557) (xy 371.625622 -271.652283)
			(xy 371.656148 -271.610267) (xy 371.692871 -271.573544) (xy 371.734887 -271.543018) (xy 371.781161 -271.51944)
			(xy 371.830554 -271.503392) (xy 371.881849 -271.495267) (xy 371.933783 -271.495267) (xy 371.985078 -271.503392)
			(xy 372.034471 -271.51944) (xy 372.080745 -271.543018) (xy 372.122761 -271.573544) (xy 372.159484 -271.610267)
			(xy 372.19001 -271.652283) (xy 372.213588 -271.698557) (xy 372.229636 -271.74795) (xy 372.237761 -271.799245)
			(xy 372.23827 -271.825212) (xy 372.237761 -271.851179) (xy 372.517671 -271.851179) (xy 372.517671 -271.799245)
			(xy 372.525796 -271.74795) (xy 372.541844 -271.698557) (xy 372.565422 -271.652283) (xy 372.595948 -271.610267)
			(xy 372.632671 -271.573544) (xy 372.674687 -271.543018) (xy 372.720961 -271.51944) (xy 372.770354 -271.503392)
			(xy 372.821649 -271.495267) (xy 372.873583 -271.495267) (xy 372.924878 -271.503392) (xy 372.974271 -271.51944)
			(xy 373.020545 -271.543018) (xy 373.062561 -271.573544) (xy 373.099284 -271.610267) (xy 373.12981 -271.652283)
			(xy 373.153388 -271.698557) (xy 373.169436 -271.74795) (xy 373.177561 -271.799245) (xy 373.17807 -271.825212)
			(xy 373.177561 -271.851179) (xy 373.457217 -271.851179) (xy 373.457217 -271.799245) (xy 373.465342 -271.74795)
			(xy 373.48139 -271.698557) (xy 373.504968 -271.652283) (xy 373.535494 -271.610267) (xy 373.572217 -271.573544)
			(xy 373.614233 -271.543018) (xy 373.660507 -271.51944) (xy 373.7099 -271.503392) (xy 373.761195 -271.495267)
			(xy 373.813129 -271.495267) (xy 373.864424 -271.503392) (xy 373.913817 -271.51944) (xy 373.960091 -271.543018)
			(xy 374.002107 -271.573544) (xy 374.03883 -271.610267) (xy 374.069356 -271.652283) (xy 374.092934 -271.698557)
			(xy 374.108982 -271.74795) (xy 374.117107 -271.799245) (xy 374.117616 -271.825212) (xy 374.117107 -271.851179)
			(xy 374.397271 -271.851179) (xy 374.397271 -271.799245) (xy 374.405396 -271.74795) (xy 374.421444 -271.698557)
			(xy 374.445022 -271.652283) (xy 374.475548 -271.610267) (xy 374.512271 -271.573544) (xy 374.554287 -271.543018)
			(xy 374.600561 -271.51944) (xy 374.649954 -271.503392) (xy 374.701249 -271.495267) (xy 374.753183 -271.495267)
			(xy 374.804478 -271.503392) (xy 374.853871 -271.51944) (xy 374.900145 -271.543018) (xy 374.942161 -271.573544)
			(xy 374.978884 -271.610267) (xy 375.00941 -271.652283) (xy 375.032988 -271.698557) (xy 375.049036 -271.74795)
			(xy 375.057161 -271.799245) (xy 375.05767 -271.825212) (xy 375.057161 -271.851179) (xy 375.337071 -271.851179)
			(xy 375.337071 -271.799245) (xy 375.345196 -271.74795) (xy 375.361244 -271.698557) (xy 375.384822 -271.652283)
			(xy 375.415348 -271.610267) (xy 375.452071 -271.573544) (xy 375.494087 -271.543018) (xy 375.540361 -271.51944)
			(xy 375.589754 -271.503392) (xy 375.641049 -271.495267) (xy 375.692983 -271.495267) (xy 375.744278 -271.503392)
			(xy 375.793671 -271.51944) (xy 375.839945 -271.543018) (xy 375.881961 -271.573544) (xy 375.918684 -271.610267)
			(xy 375.94921 -271.652283) (xy 375.972788 -271.698557) (xy 375.988836 -271.74795) (xy 375.996961 -271.799245)
			(xy 375.99747 -271.825212) (xy 375.996961 -271.851179) (xy 376.276871 -271.851179) (xy 376.276871 -271.799245)
			(xy 376.284996 -271.74795) (xy 376.301044 -271.698557) (xy 376.324622 -271.652283) (xy 376.355148 -271.610267)
			(xy 376.391871 -271.573544) (xy 376.433887 -271.543018) (xy 376.480161 -271.51944) (xy 376.529554 -271.503392)
			(xy 376.580849 -271.495267) (xy 376.632783 -271.495267) (xy 376.684078 -271.503392) (xy 376.733471 -271.51944)
			(xy 376.779745 -271.543018) (xy 376.821761 -271.573544) (xy 376.858484 -271.610267) (xy 376.88901 -271.652283)
			(xy 376.912588 -271.698557) (xy 376.928636 -271.74795) (xy 376.936761 -271.799245) (xy 376.93727 -271.825212)
			(xy 376.936761 -271.851179) (xy 377.216671 -271.851179) (xy 377.216671 -271.799245) (xy 377.224796 -271.74795)
			(xy 377.240844 -271.698557) (xy 377.264422 -271.652283) (xy 377.294948 -271.610267) (xy 377.331671 -271.573544)
			(xy 377.373687 -271.543018) (xy 377.419961 -271.51944) (xy 377.469354 -271.503392) (xy 377.520649 -271.495267)
			(xy 377.572583 -271.495267) (xy 377.623878 -271.503392) (xy 377.673271 -271.51944) (xy 377.719545 -271.543018)
			(xy 377.761561 -271.573544) (xy 377.798284 -271.610267) (xy 377.82881 -271.652283) (xy 377.852388 -271.698557)
			(xy 377.868436 -271.74795) (xy 377.876561 -271.799245) (xy 377.87707 -271.825212) (xy 377.876561 -271.851179)
			(xy 378.156471 -271.851179) (xy 378.156471 -271.799245) (xy 378.164596 -271.74795) (xy 378.180644 -271.698557)
			(xy 378.204222 -271.652283) (xy 378.234748 -271.610267) (xy 378.271471 -271.573544) (xy 378.313487 -271.543018)
			(xy 378.359761 -271.51944) (xy 378.409154 -271.503392) (xy 378.460449 -271.495267) (xy 378.512383 -271.495267)
			(xy 378.563678 -271.503392) (xy 378.613071 -271.51944) (xy 378.659345 -271.543018) (xy 378.701361 -271.573544)
			(xy 378.738084 -271.610267) (xy 378.76861 -271.652283) (xy 378.792188 -271.698557) (xy 378.808236 -271.74795)
			(xy 378.816361 -271.799245) (xy 378.81687 -271.825212) (xy 378.816361 -271.851179) (xy 378.808236 -271.902474)
			(xy 378.792188 -271.951867) (xy 378.76861 -271.998141) (xy 378.738084 -272.040157) (xy 378.701361 -272.07688)
			(xy 378.659345 -272.107406) (xy 378.613071 -272.130984) (xy 378.563678 -272.147032) (xy 378.512383 -272.155157)
			(xy 378.460449 -272.155157) (xy 378.409154 -272.147032) (xy 378.359761 -272.130984) (xy 378.313487 -272.107406)
			(xy 378.271471 -272.07688) (xy 378.234748 -272.040157) (xy 378.204222 -271.998141) (xy 378.180644 -271.951867)
			(xy 378.164596 -271.902474) (xy 378.156471 -271.851179) (xy 377.876561 -271.851179) (xy 377.868436 -271.902474)
			(xy 377.852388 -271.951867) (xy 377.82881 -271.998141) (xy 377.798284 -272.040157) (xy 377.761561 -272.07688)
			(xy 377.719545 -272.107406) (xy 377.673271 -272.130984) (xy 377.623878 -272.147032) (xy 377.572583 -272.155157)
			(xy 377.520649 -272.155157) (xy 377.469354 -272.147032) (xy 377.419961 -272.130984) (xy 377.373687 -272.107406)
			(xy 377.331671 -272.07688) (xy 377.294948 -272.040157) (xy 377.264422 -271.998141) (xy 377.240844 -271.951867)
			(xy 377.224796 -271.902474) (xy 377.216671 -271.851179) (xy 376.936761 -271.851179) (xy 376.928636 -271.902474)
			(xy 376.912588 -271.951867) (xy 376.88901 -271.998141) (xy 376.858484 -272.040157) (xy 376.821761 -272.07688)
			(xy 376.779745 -272.107406) (xy 376.733471 -272.130984) (xy 376.684078 -272.147032) (xy 376.632783 -272.155157)
			(xy 376.580849 -272.155157) (xy 376.529554 -272.147032) (xy 376.480161 -272.130984) (xy 376.433887 -272.107406)
			(xy 376.391871 -272.07688) (xy 376.355148 -272.040157) (xy 376.324622 -271.998141) (xy 376.301044 -271.951867)
			(xy 376.284996 -271.902474) (xy 376.276871 -271.851179) (xy 375.996961 -271.851179) (xy 375.988836 -271.902474)
			(xy 375.972788 -271.951867) (xy 375.94921 -271.998141) (xy 375.918684 -272.040157) (xy 375.881961 -272.07688)
			(xy 375.839945 -272.107406) (xy 375.793671 -272.130984) (xy 375.744278 -272.147032) (xy 375.692983 -272.155157)
			(xy 375.641049 -272.155157) (xy 375.589754 -272.147032) (xy 375.540361 -272.130984) (xy 375.494087 -272.107406)
			(xy 375.452071 -272.07688) (xy 375.415348 -272.040157) (xy 375.384822 -271.998141) (xy 375.361244 -271.951867)
			(xy 375.345196 -271.902474) (xy 375.337071 -271.851179) (xy 375.057161 -271.851179) (xy 375.049036 -271.902474)
			(xy 375.032988 -271.951867) (xy 375.00941 -271.998141) (xy 374.978884 -272.040157) (xy 374.942161 -272.07688)
			(xy 374.900145 -272.107406) (xy 374.853871 -272.130984) (xy 374.804478 -272.147032) (xy 374.753183 -272.155157)
			(xy 374.701249 -272.155157) (xy 374.649954 -272.147032) (xy 374.600561 -272.130984) (xy 374.554287 -272.107406)
			(xy 374.512271 -272.07688) (xy 374.475548 -272.040157) (xy 374.445022 -271.998141) (xy 374.421444 -271.951867)
			(xy 374.405396 -271.902474) (xy 374.397271 -271.851179) (xy 374.117107 -271.851179) (xy 374.108982 -271.902474)
			(xy 374.092934 -271.951867) (xy 374.069356 -271.998141) (xy 374.03883 -272.040157) (xy 374.002107 -272.07688)
			(xy 373.960091 -272.107406) (xy 373.913817 -272.130984) (xy 373.864424 -272.147032) (xy 373.813129 -272.155157)
			(xy 373.761195 -272.155157) (xy 373.7099 -272.147032) (xy 373.660507 -272.130984) (xy 373.614233 -272.107406)
			(xy 373.572217 -272.07688) (xy 373.535494 -272.040157) (xy 373.504968 -271.998141) (xy 373.48139 -271.951867)
			(xy 373.465342 -271.902474) (xy 373.457217 -271.851179) (xy 373.177561 -271.851179) (xy 373.169436 -271.902474)
			(xy 373.153388 -271.951867) (xy 373.12981 -271.998141) (xy 373.099284 -272.040157) (xy 373.062561 -272.07688)
			(xy 373.020545 -272.107406) (xy 372.974271 -272.130984) (xy 372.924878 -272.147032) (xy 372.873583 -272.155157)
			(xy 372.821649 -272.155157) (xy 372.770354 -272.147032) (xy 372.720961 -272.130984) (xy 372.674687 -272.107406)
			(xy 372.632671 -272.07688) (xy 372.595948 -272.040157) (xy 372.565422 -271.998141) (xy 372.541844 -271.951867)
			(xy 372.525796 -271.902474) (xy 372.517671 -271.851179) (xy 372.237761 -271.851179) (xy 372.229636 -271.902474)
			(xy 372.213588 -271.951867) (xy 372.19001 -271.998141) (xy 372.159484 -272.040157) (xy 372.122761 -272.07688)
			(xy 372.080745 -272.107406) (xy 372.034471 -272.130984) (xy 371.985078 -272.147032) (xy 371.933783 -272.155157)
			(xy 371.881849 -272.155157) (xy 371.830554 -272.147032) (xy 371.781161 -272.130984) (xy 371.734887 -272.107406)
			(xy 371.692871 -272.07688) (xy 371.656148 -272.040157) (xy 371.625622 -271.998141) (xy 371.602044 -271.951867)
			(xy 371.585996 -271.902474) (xy 371.577871 -271.851179) (xy 371.297961 -271.851179) (xy 371.289836 -271.902474)
			(xy 371.273788 -271.951867) (xy 371.25021 -271.998141) (xy 371.219684 -272.040157) (xy 371.182961 -272.07688)
			(xy 371.140945 -272.107406) (xy 371.094671 -272.130984) (xy 371.045278 -272.147032) (xy 370.993983 -272.155157)
			(xy 370.942049 -272.155157) (xy 370.890754 -272.147032) (xy 370.841361 -272.130984) (xy 370.795087 -272.107406)
			(xy 370.753071 -272.07688) (xy 370.716348 -272.040157) (xy 370.685822 -271.998141) (xy 370.662244 -271.951867)
			(xy 370.646196 -271.902474) (xy 370.638071 -271.851179) (xy 370.358161 -271.851179) (xy 370.350036 -271.902474)
			(xy 370.333988 -271.951867) (xy 370.31041 -271.998141) (xy 370.279884 -272.040157) (xy 370.243161 -272.07688)
			(xy 370.201145 -272.107406) (xy 370.154871 -272.130984) (xy 370.105478 -272.147032) (xy 370.054183 -272.155157)
			(xy 370.002249 -272.155157) (xy 369.950954 -272.147032) (xy 369.901561 -272.130984) (xy 369.855287 -272.107406)
			(xy 369.813271 -272.07688) (xy 369.776548 -272.040157) (xy 369.746022 -271.998141) (xy 369.722444 -271.951867)
			(xy 369.706396 -271.902474) (xy 369.698271 -271.851179) (xy 369.418361 -271.851179) (xy 369.410236 -271.902474)
			(xy 369.394188 -271.951867) (xy 369.37061 -271.998141) (xy 369.340084 -272.040157) (xy 369.303361 -272.07688)
			(xy 369.261345 -272.107406) (xy 369.215071 -272.130984) (xy 369.165678 -272.147032) (xy 369.114383 -272.155157)
			(xy 369.062449 -272.155157) (xy 369.011154 -272.147032) (xy 368.961761 -272.130984) (xy 368.915487 -272.107406)
			(xy 368.873471 -272.07688) (xy 368.836748 -272.040157) (xy 368.806222 -271.998141) (xy 368.782644 -271.951867)
			(xy 368.766596 -271.902474) (xy 368.758471 -271.851179) (xy 368.478561 -271.851179) (xy 368.470436 -271.902474)
			(xy 368.454388 -271.951867) (xy 368.43081 -271.998141) (xy 368.400284 -272.040157) (xy 368.363561 -272.07688)
			(xy 368.321545 -272.107406) (xy 368.275271 -272.130984) (xy 368.225878 -272.147032) (xy 368.174583 -272.155157)
			(xy 368.122649 -272.155157) (xy 368.071354 -272.147032) (xy 368.021961 -272.130984) (xy 367.975687 -272.107406)
			(xy 367.933671 -272.07688) (xy 367.896948 -272.040157) (xy 367.866422 -271.998141) (xy 367.842844 -271.951867)
			(xy 367.826796 -271.902474) (xy 367.818671 -271.851179) (xy 367.538253 -271.851179) (xy 367.530128 -271.902474)
			(xy 367.51408 -271.951867) (xy 367.490502 -271.998141) (xy 367.459976 -272.040157) (xy 367.423253 -272.07688)
			(xy 367.381237 -272.107406) (xy 367.334963 -272.130984) (xy 367.28557 -272.147032) (xy 367.234275 -272.155157)
			(xy 367.182341 -272.155157) (xy 367.131046 -272.147032) (xy 367.081653 -272.130984) (xy 367.035379 -272.107406)
			(xy 366.993363 -272.07688) (xy 366.95664 -272.040157) (xy 366.926114 -271.998141) (xy 366.902536 -271.951867)
			(xy 366.886488 -271.902474) (xy 366.878363 -271.851179) (xy 366.598453 -271.851179) (xy 366.590328 -271.902474)
			(xy 366.57428 -271.951867) (xy 366.550702 -271.998141) (xy 366.520176 -272.040157) (xy 366.483453 -272.07688)
			(xy 366.441437 -272.107406) (xy 366.395163 -272.130984) (xy 366.34577 -272.147032) (xy 366.294475 -272.155157)
			(xy 366.242541 -272.155157) (xy 366.191246 -272.147032) (xy 366.141853 -272.130984) (xy 366.095579 -272.107406)
			(xy 366.053563 -272.07688) (xy 366.01684 -272.040157) (xy 365.986314 -271.998141) (xy 365.962736 -271.951867)
			(xy 365.946688 -271.902474) (xy 365.938563 -271.851179) (xy 365.659161 -271.851179) (xy 365.651036 -271.902474)
			(xy 365.634988 -271.951867) (xy 365.61141 -271.998141) (xy 365.580884 -272.040157) (xy 365.544161 -272.07688)
			(xy 365.502145 -272.107406) (xy 365.455871 -272.130984) (xy 365.406478 -272.147032) (xy 365.355183 -272.155157)
			(xy 365.303249 -272.155157) (xy 365.251954 -272.147032) (xy 365.202561 -272.130984) (xy 365.156287 -272.107406)
			(xy 365.114271 -272.07688) (xy 365.077548 -272.040157) (xy 365.047022 -271.998141) (xy 365.023444 -271.951867)
			(xy 365.007396 -271.902474) (xy 364.999271 -271.851179) (xy 364.718853 -271.851179) (xy 364.710728 -271.902474)
			(xy 364.69468 -271.951867) (xy 364.671102 -271.998141) (xy 364.640576 -272.040157) (xy 364.603853 -272.07688)
			(xy 364.561837 -272.107406) (xy 364.515563 -272.130984) (xy 364.46617 -272.147032) (xy 364.414875 -272.155157)
			(xy 364.362941 -272.155157) (xy 364.311646 -272.147032) (xy 364.262253 -272.130984) (xy 364.215979 -272.107406)
			(xy 364.173963 -272.07688) (xy 364.13724 -272.040157) (xy 364.106714 -271.998141) (xy 364.083136 -271.951867)
			(xy 364.067088 -271.902474) (xy 364.058963 -271.851179) (xy 363.779561 -271.851179) (xy 363.771436 -271.902474)
			(xy 363.755388 -271.951867) (xy 363.73181 -271.998141) (xy 363.701284 -272.040157) (xy 363.664561 -272.07688)
			(xy 363.622545 -272.107406) (xy 363.576271 -272.130984) (xy 363.526878 -272.147032) (xy 363.475583 -272.155157)
			(xy 363.423649 -272.155157) (xy 363.372354 -272.147032) (xy 363.322961 -272.130984) (xy 363.276687 -272.107406)
			(xy 363.234671 -272.07688) (xy 363.197948 -272.040157) (xy 363.167422 -271.998141) (xy 363.143844 -271.951867)
			(xy 363.127796 -271.902474) (xy 363.119671 -271.851179) (xy 362.839761 -271.851179) (xy 362.831636 -271.902474)
			(xy 362.815588 -271.951867) (xy 362.79201 -271.998141) (xy 362.761484 -272.040157) (xy 362.724761 -272.07688)
			(xy 362.682745 -272.107406) (xy 362.636471 -272.130984) (xy 362.587078 -272.147032) (xy 362.535783 -272.155157)
			(xy 362.483849 -272.155157) (xy 362.432554 -272.147032) (xy 362.383161 -272.130984) (xy 362.336887 -272.107406)
			(xy 362.294871 -272.07688) (xy 362.258148 -272.040157) (xy 362.227622 -271.998141) (xy 362.204044 -271.951867)
			(xy 362.187996 -271.902474) (xy 362.179871 -271.851179) (xy 361.899707 -271.851179) (xy 361.891582 -271.902474)
			(xy 361.875534 -271.951867) (xy 361.851956 -271.998141) (xy 361.82143 -272.040157) (xy 361.784707 -272.07688)
			(xy 361.742691 -272.107406) (xy 361.696417 -272.130984) (xy 361.647024 -272.147032) (xy 361.595729 -272.155157)
			(xy 361.543795 -272.155157) (xy 361.4925 -272.147032) (xy 361.443107 -272.130984) (xy 361.396833 -272.107406)
			(xy 361.354817 -272.07688) (xy 361.318094 -272.040157) (xy 361.287568 -271.998141) (xy 361.26399 -271.951867)
			(xy 361.247942 -271.902474) (xy 361.239817 -271.851179) (xy 360.959907 -271.851179) (xy 360.951782 -271.902474)
			(xy 360.935734 -271.951867) (xy 360.912156 -271.998141) (xy 360.88163 -272.040157) (xy 360.844907 -272.07688)
			(xy 360.802891 -272.107406) (xy 360.756617 -272.130984) (xy 360.707224 -272.147032) (xy 360.655929 -272.155157)
			(xy 360.603995 -272.155157) (xy 360.5527 -272.147032) (xy 360.503307 -272.130984) (xy 360.457033 -272.107406)
			(xy 360.415017 -272.07688) (xy 360.378294 -272.040157) (xy 360.347768 -271.998141) (xy 360.32419 -271.951867)
			(xy 360.308142 -271.902474) (xy 360.300017 -271.851179) (xy 360.020107 -271.851179) (xy 360.011982 -271.902474)
			(xy 359.995934 -271.951867) (xy 359.972356 -271.998141) (xy 359.94183 -272.040157) (xy 359.905107 -272.07688)
			(xy 359.863091 -272.107406) (xy 359.816817 -272.130984) (xy 359.767424 -272.147032) (xy 359.716129 -272.155157)
			(xy 359.664195 -272.155157) (xy 359.6129 -272.147032) (xy 359.563507 -272.130984) (xy 359.517233 -272.107406)
			(xy 359.475217 -272.07688) (xy 359.438494 -272.040157) (xy 359.407968 -271.998141) (xy 359.38439 -271.951867)
			(xy 359.368342 -271.902474) (xy 359.360217 -271.851179) (xy 359.080561 -271.851179) (xy 359.072436 -271.902474)
			(xy 359.056388 -271.951867) (xy 359.03281 -271.998141) (xy 359.002284 -272.040157) (xy 358.965561 -272.07688)
			(xy 358.923545 -272.107406) (xy 358.877271 -272.130984) (xy 358.827878 -272.147032) (xy 358.776583 -272.155157)
			(xy 358.724649 -272.155157) (xy 358.673354 -272.147032) (xy 358.623961 -272.130984) (xy 358.577687 -272.107406)
			(xy 358.535671 -272.07688) (xy 358.498948 -272.040157) (xy 358.468422 -271.998141) (xy 358.444844 -271.951867)
			(xy 358.428796 -271.902474) (xy 358.420671 -271.851179) (xy 358.140253 -271.851179) (xy 358.132128 -271.902474)
			(xy 358.11608 -271.951867) (xy 358.092502 -271.998141) (xy 358.061976 -272.040157) (xy 358.025253 -272.07688)
			(xy 357.983237 -272.107406) (xy 357.936963 -272.130984) (xy 357.88757 -272.147032) (xy 357.836275 -272.155157)
			(xy 357.784341 -272.155157) (xy 357.733046 -272.147032) (xy 357.683653 -272.130984) (xy 357.637379 -272.107406)
			(xy 357.595363 -272.07688) (xy 357.55864 -272.040157) (xy 357.528114 -271.998141) (xy 357.504536 -271.951867)
			(xy 357.488488 -271.902474) (xy 357.480363 -271.851179) (xy 357.200961 -271.851179) (xy 357.192836 -271.902474)
			(xy 357.176788 -271.951867) (xy 357.15321 -271.998141) (xy 357.122684 -272.040157) (xy 357.085961 -272.07688)
			(xy 357.043945 -272.107406) (xy 356.997671 -272.130984) (xy 356.948278 -272.147032) (xy 356.896983 -272.155157)
			(xy 356.845049 -272.155157) (xy 356.793754 -272.147032) (xy 356.744361 -272.130984) (xy 356.698087 -272.107406)
			(xy 356.656071 -272.07688) (xy 356.619348 -272.040157) (xy 356.588822 -271.998141) (xy 356.565244 -271.951867)
			(xy 356.549196 -271.902474) (xy 356.541071 -271.851179) (xy 356.261161 -271.851179) (xy 356.253036 -271.902474)
			(xy 356.236988 -271.951867) (xy 356.21341 -271.998141) (xy 356.182884 -272.040157) (xy 356.146161 -272.07688)
			(xy 356.104145 -272.107406) (xy 356.057871 -272.130984) (xy 356.008478 -272.147032) (xy 355.957183 -272.155157)
			(xy 355.905249 -272.155157) (xy 355.853954 -272.147032) (xy 355.804561 -272.130984) (xy 355.758287 -272.107406)
			(xy 355.716271 -272.07688) (xy 355.679548 -272.040157) (xy 355.649022 -271.998141) (xy 355.625444 -271.951867)
			(xy 355.609396 -271.902474) (xy 355.601271 -271.851179) (xy 355.321361 -271.851179) (xy 355.313236 -271.902474)
			(xy 355.297188 -271.951867) (xy 355.27361 -271.998141) (xy 355.243084 -272.040157) (xy 355.206361 -272.07688)
			(xy 355.164345 -272.107406) (xy 355.118071 -272.130984) (xy 355.068678 -272.147032) (xy 355.017383 -272.155157)
			(xy 354.965449 -272.155157) (xy 354.914154 -272.147032) (xy 354.864761 -272.130984) (xy 354.818487 -272.107406)
			(xy 354.776471 -272.07688) (xy 354.739748 -272.040157) (xy 354.709222 -271.998141) (xy 354.685644 -271.951867)
			(xy 354.669596 -271.902474) (xy 354.661471 -271.851179) (xy 354.381561 -271.851179) (xy 354.373436 -271.902474)
			(xy 354.357388 -271.951867) (xy 354.33381 -271.998141) (xy 354.303284 -272.040157) (xy 354.266561 -272.07688)
			(xy 354.224545 -272.107406) (xy 354.178271 -272.130984) (xy 354.128878 -272.147032) (xy 354.077583 -272.155157)
			(xy 354.025649 -272.155157) (xy 353.974354 -272.147032) (xy 353.924961 -272.130984) (xy 353.878687 -272.107406)
			(xy 353.836671 -272.07688) (xy 353.799948 -272.040157) (xy 353.769422 -271.998141) (xy 353.745844 -271.951867)
			(xy 353.729796 -271.902474) (xy 353.721671 -271.851179) (xy 353.441761 -271.851179) (xy 353.433636 -271.902474)
			(xy 353.417588 -271.951867) (xy 353.39401 -271.998141) (xy 353.363484 -272.040157) (xy 353.326761 -272.07688)
			(xy 353.284745 -272.107406) (xy 353.238471 -272.130984) (xy 353.189078 -272.147032) (xy 353.137783 -272.155157)
			(xy 353.085849 -272.155157) (xy 353.034554 -272.147032) (xy 352.985161 -272.130984) (xy 352.938887 -272.107406)
			(xy 352.896871 -272.07688) (xy 352.860148 -272.040157) (xy 352.829622 -271.998141) (xy 352.806044 -271.951867)
			(xy 352.789996 -271.902474) (xy 352.781871 -271.851179) (xy 352.501961 -271.851179) (xy 352.493836 -271.902474)
			(xy 352.477788 -271.951867) (xy 352.45421 -271.998141) (xy 352.423684 -272.040157) (xy 352.386961 -272.07688)
			(xy 352.344945 -272.107406) (xy 352.298671 -272.130984) (xy 352.249278 -272.147032) (xy 352.197983 -272.155157)
			(xy 352.146049 -272.155157) (xy 352.094754 -272.147032) (xy 352.045361 -272.130984) (xy 351.999087 -272.107406)
			(xy 351.957071 -272.07688) (xy 351.920348 -272.040157) (xy 351.889822 -271.998141) (xy 351.866244 -271.951867)
			(xy 351.850196 -271.902474) (xy 351.842071 -271.851179) (xy 351.562161 -271.851179) (xy 351.554036 -271.902474)
			(xy 351.537988 -271.951867) (xy 351.51441 -271.998141) (xy 351.483884 -272.040157) (xy 351.447161 -272.07688)
			(xy 351.405145 -272.107406) (xy 351.358871 -272.130984) (xy 351.309478 -272.147032) (xy 351.258183 -272.155157)
			(xy 351.206249 -272.155157) (xy 351.154954 -272.147032) (xy 351.105561 -272.130984) (xy 351.059287 -272.107406)
			(xy 351.017271 -272.07688) (xy 350.980548 -272.040157) (xy 350.950022 -271.998141) (xy 350.926444 -271.951867)
			(xy 350.910396 -271.902474) (xy 350.902271 -271.851179) (xy 350.622361 -271.851179) (xy 350.614236 -271.902474)
			(xy 350.598188 -271.951867) (xy 350.57461 -271.998141) (xy 350.544084 -272.040157) (xy 350.507361 -272.07688)
			(xy 350.465345 -272.107406) (xy 350.419071 -272.130984) (xy 350.369678 -272.147032) (xy 350.318383 -272.155157)
			(xy 350.266449 -272.155157) (xy 350.215154 -272.147032) (xy 350.165761 -272.130984) (xy 350.119487 -272.107406)
			(xy 350.077471 -272.07688) (xy 350.040748 -272.040157) (xy 350.010222 -271.998141) (xy 349.986644 -271.951867)
			(xy 349.970596 -271.902474) (xy 349.962471 -271.851179) (xy 349.682561 -271.851179) (xy 349.674436 -271.902474)
			(xy 349.658388 -271.951867) (xy 349.63481 -271.998141) (xy 349.604284 -272.040157) (xy 349.567561 -272.07688)
			(xy 349.525545 -272.107406) (xy 349.479271 -272.130984) (xy 349.429878 -272.147032) (xy 349.378583 -272.155157)
			(xy 349.326649 -272.155157) (xy 349.275354 -272.147032) (xy 349.225961 -272.130984) (xy 349.179687 -272.107406)
			(xy 349.137671 -272.07688) (xy 349.100948 -272.040157) (xy 349.070422 -271.998141) (xy 349.046844 -271.951867)
			(xy 349.030796 -271.902474) (xy 349.022671 -271.851179) (xy 348.742761 -271.851179) (xy 348.734636 -271.902474)
			(xy 348.718588 -271.951867) (xy 348.69501 -271.998141) (xy 348.664484 -272.040157) (xy 348.627761 -272.07688)
			(xy 348.585745 -272.107406) (xy 348.539471 -272.130984) (xy 348.490078 -272.147032) (xy 348.438783 -272.155157)
			(xy 348.386849 -272.155157) (xy 348.335554 -272.147032) (xy 348.286161 -272.130984) (xy 348.239887 -272.107406)
			(xy 348.197871 -272.07688) (xy 348.161148 -272.040157) (xy 348.130622 -271.998141) (xy 348.107044 -271.951867)
			(xy 348.090996 -271.902474) (xy 348.082871 -271.851179) (xy 347.802961 -271.851179) (xy 347.794836 -271.902474)
			(xy 347.778788 -271.951867) (xy 347.75521 -271.998141) (xy 347.724684 -272.040157) (xy 347.687961 -272.07688)
			(xy 347.645945 -272.107406) (xy 347.599671 -272.130984) (xy 347.550278 -272.147032) (xy 347.498983 -272.155157)
			(xy 347.447049 -272.155157) (xy 347.395754 -272.147032) (xy 347.346361 -272.130984) (xy 347.300087 -272.107406)
			(xy 347.258071 -272.07688) (xy 347.221348 -272.040157) (xy 347.190822 -271.998141) (xy 347.167244 -271.951867)
			(xy 347.151196 -271.902474) (xy 347.143071 -271.851179) (xy 346.863161 -271.851179) (xy 346.855036 -271.902474)
			(xy 346.838988 -271.951867) (xy 346.81541 -271.998141) (xy 346.784884 -272.040157) (xy 346.748161 -272.07688)
			(xy 346.706145 -272.107406) (xy 346.659871 -272.130984) (xy 346.610478 -272.147032) (xy 346.559183 -272.155157)
			(xy 346.507249 -272.155157) (xy 346.455954 -272.147032) (xy 346.406561 -272.130984) (xy 346.360287 -272.107406)
			(xy 346.318271 -272.07688) (xy 346.281548 -272.040157) (xy 346.251022 -271.998141) (xy 346.227444 -271.951867)
			(xy 346.211396 -271.902474) (xy 346.203271 -271.851179) (xy 345.923107 -271.851179) (xy 345.914982 -271.902474)
			(xy 345.898934 -271.951867) (xy 345.875356 -271.998141) (xy 345.84483 -272.040157) (xy 345.808107 -272.07688)
			(xy 345.766091 -272.107406) (xy 345.719817 -272.130984) (xy 345.670424 -272.147032) (xy 345.619129 -272.155157)
			(xy 345.567195 -272.155157) (xy 345.5159 -272.147032) (xy 345.466507 -272.130984) (xy 345.420233 -272.107406)
			(xy 345.378217 -272.07688) (xy 345.341494 -272.040157) (xy 345.310968 -271.998141) (xy 345.28739 -271.951867)
			(xy 345.271342 -271.902474) (xy 345.263217 -271.851179) (xy 344.983561 -271.851179) (xy 344.975436 -271.902474)
			(xy 344.959388 -271.951867) (xy 344.93581 -271.998141) (xy 344.905284 -272.040157) (xy 344.868561 -272.07688)
			(xy 344.826545 -272.107406) (xy 344.780271 -272.130984) (xy 344.730878 -272.147032) (xy 344.679583 -272.155157)
			(xy 344.627649 -272.155157) (xy 344.576354 -272.147032) (xy 344.526961 -272.130984) (xy 344.480687 -272.107406)
			(xy 344.438671 -272.07688) (xy 344.401948 -272.040157) (xy 344.371422 -271.998141) (xy 344.347844 -271.951867)
			(xy 344.331796 -271.902474) (xy 344.323671 -271.851179) (xy 344.043761 -271.851179) (xy 344.035636 -271.902474)
			(xy 344.019588 -271.951867) (xy 343.99601 -271.998141) (xy 343.965484 -272.040157) (xy 343.928761 -272.07688)
			(xy 343.886745 -272.107406) (xy 343.840471 -272.130984) (xy 343.791078 -272.147032) (xy 343.739783 -272.155157)
			(xy 343.687849 -272.155157) (xy 343.636554 -272.147032) (xy 343.587161 -272.130984) (xy 343.540887 -272.107406)
			(xy 343.498871 -272.07688) (xy 343.462148 -272.040157) (xy 343.431622 -271.998141) (xy 343.408044 -271.951867)
			(xy 343.391996 -271.902474) (xy 343.383871 -271.851179) (xy 343.103961 -271.851179) (xy 343.095836 -271.902474)
			(xy 343.079788 -271.951867) (xy 343.05621 -271.998141) (xy 343.025684 -272.040157) (xy 342.988961 -272.07688)
			(xy 342.946945 -272.107406) (xy 342.900671 -272.130984) (xy 342.851278 -272.147032) (xy 342.799983 -272.155157)
			(xy 342.748049 -272.155157) (xy 342.696754 -272.147032) (xy 342.647361 -272.130984) (xy 342.601087 -272.107406)
			(xy 342.559071 -272.07688) (xy 342.522348 -272.040157) (xy 342.491822 -271.998141) (xy 342.468244 -271.951867)
			(xy 342.452196 -271.902474) (xy 342.444071 -271.851179) (xy 342.164161 -271.851179) (xy 342.156036 -271.902474)
			(xy 342.139988 -271.951867) (xy 342.11641 -271.998141) (xy 342.085884 -272.040157) (xy 342.049161 -272.07688)
			(xy 342.007145 -272.107406) (xy 341.960871 -272.130984) (xy 341.911478 -272.147032) (xy 341.860183 -272.155157)
			(xy 341.808249 -272.155157) (xy 341.756954 -272.147032) (xy 341.707561 -272.130984) (xy 341.661287 -272.107406)
			(xy 341.619271 -272.07688) (xy 341.582548 -272.040157) (xy 341.552022 -271.998141) (xy 341.528444 -271.951867)
			(xy 341.512396 -271.902474) (xy 341.504271 -271.851179) (xy 341.224361 -271.851179) (xy 341.216236 -271.902474)
			(xy 341.200188 -271.951867) (xy 341.17661 -271.998141) (xy 341.146084 -272.040157) (xy 341.109361 -272.07688)
			(xy 341.067345 -272.107406) (xy 341.021071 -272.130984) (xy 340.971678 -272.147032) (xy 340.920383 -272.155157)
			(xy 340.868449 -272.155157) (xy 340.817154 -272.147032) (xy 340.767761 -272.130984) (xy 340.721487 -272.107406)
			(xy 340.679471 -272.07688) (xy 340.642748 -272.040157) (xy 340.612222 -271.998141) (xy 340.588644 -271.951867)
			(xy 340.572596 -271.902474) (xy 340.564471 -271.851179) (xy 340.284787 -271.851179) (xy 340.284787 -271.851185)
			(xy 340.276657 -271.902517) (xy 340.260597 -271.951944) (xy 340.237004 -271.998251) (xy 340.206457 -272.040297)
			(xy 340.169709 -272.077046) (xy 340.127664 -272.107595) (xy 340.081359 -272.131191) (xy 340.031932 -272.147253)
			(xy 339.980601 -272.155385) (xy 339.954616 -272.15592) (xy 339.931701 -272.15553) (xy 339.88631 -272.149196)
			(xy 339.842231 -272.136649) (xy 339.80031 -272.118128) (xy 339.780626 -272.10639) (xy 339.780372 -272.10639)
			(xy 339.772615 -272.10199) (xy 339.755157 -272.098418) (xy 339.737542 -272.101119) (xy 339.729572 -272.10512)
			(xy 339.691218 -272.12671) (xy 339.65134 -272.149062) (xy 339.644242 -272.153819) (xy 339.633503 -272.167096)
			(xy 339.627813 -272.183196) (xy 339.627464 -272.191734) (xy 339.627464 -272.311114) (xy 339.651848 -272.353786)
			(xy 339.662516 -272.360644) (xy 339.683768 -272.374767) (xy 339.722053 -272.408498) (xy 339.7547 -272.447712)
			(xy 339.780933 -272.491477) (xy 339.80013 -272.538753) (xy 339.811834 -272.588417) (xy 339.815768 -272.63929)
			(xy 339.813762 -272.665249) (xy 340.094317 -272.665249) (xy 340.094317 -272.613315) (xy 340.102442 -272.56202)
			(xy 340.11849 -272.512627) (xy 340.142068 -272.466353) (xy 340.172594 -272.424337) (xy 340.209317 -272.387614)
			(xy 340.251333 -272.357088) (xy 340.297607 -272.33351) (xy 340.347 -272.317462) (xy 340.398295 -272.309337)
			(xy 340.450229 -272.309337) (xy 340.501524 -272.317462) (xy 340.550917 -272.33351) (xy 340.597191 -272.357088)
			(xy 340.639207 -272.387614) (xy 340.67593 -272.424337) (xy 340.706456 -272.466353) (xy 340.730034 -272.512627)
			(xy 340.746082 -272.56202) (xy 340.754207 -272.613315) (xy 340.754716 -272.639282) (xy 340.754207 -272.665249)
			(xy 341.034117 -272.665249) (xy 341.034117 -272.613315) (xy 341.042242 -272.56202) (xy 341.05829 -272.512627)
			(xy 341.081868 -272.466353) (xy 341.112394 -272.424337) (xy 341.149117 -272.387614) (xy 341.191133 -272.357088)
			(xy 341.237407 -272.33351) (xy 341.2868 -272.317462) (xy 341.338095 -272.309337) (xy 341.390029 -272.309337)
			(xy 341.441324 -272.317462) (xy 341.490717 -272.33351) (xy 341.536991 -272.357088) (xy 341.579007 -272.387614)
			(xy 341.61573 -272.424337) (xy 341.646256 -272.466353) (xy 341.669834 -272.512627) (xy 341.685882 -272.56202)
			(xy 341.694007 -272.613315) (xy 341.694516 -272.639282) (xy 341.694007 -272.665249) (xy 341.973917 -272.665249)
			(xy 341.973917 -272.613315) (xy 341.982042 -272.56202) (xy 341.99809 -272.512627) (xy 342.021668 -272.466353)
			(xy 342.052194 -272.424337) (xy 342.088917 -272.387614) (xy 342.130933 -272.357088) (xy 342.177207 -272.33351)
			(xy 342.2266 -272.317462) (xy 342.277895 -272.309337) (xy 342.329829 -272.309337) (xy 342.381124 -272.317462)
			(xy 342.430517 -272.33351) (xy 342.476791 -272.357088) (xy 342.518807 -272.387614) (xy 342.55553 -272.424337)
			(xy 342.586056 -272.466353) (xy 342.609634 -272.512627) (xy 342.625682 -272.56202) (xy 342.633807 -272.613315)
			(xy 342.634316 -272.639282) (xy 342.633807 -272.665249) (xy 342.913717 -272.665249) (xy 342.913717 -272.613315)
			(xy 342.921842 -272.56202) (xy 342.93789 -272.512627) (xy 342.961468 -272.466353) (xy 342.991994 -272.424337)
			(xy 343.028717 -272.387614) (xy 343.070733 -272.357088) (xy 343.117007 -272.33351) (xy 343.1664 -272.317462)
			(xy 343.217695 -272.309337) (xy 343.269629 -272.309337) (xy 343.320924 -272.317462) (xy 343.370317 -272.33351)
			(xy 343.416591 -272.357088) (xy 343.458607 -272.387614) (xy 343.49533 -272.424337) (xy 343.525856 -272.466353)
			(xy 343.549434 -272.512627) (xy 343.565482 -272.56202) (xy 343.573607 -272.613315) (xy 343.574116 -272.639282)
			(xy 343.573607 -272.665249) (xy 343.853517 -272.665249) (xy 343.853517 -272.613315) (xy 343.861642 -272.56202)
			(xy 343.87769 -272.512627) (xy 343.901268 -272.466353) (xy 343.931794 -272.424337) (xy 343.968517 -272.387614)
			(xy 344.010533 -272.357088) (xy 344.056807 -272.33351) (xy 344.1062 -272.317462) (xy 344.157495 -272.309337)
			(xy 344.209429 -272.309337) (xy 344.260724 -272.317462) (xy 344.310117 -272.33351) (xy 344.356391 -272.357088)
			(xy 344.398407 -272.387614) (xy 344.43513 -272.424337) (xy 344.465656 -272.466353) (xy 344.489234 -272.512627)
			(xy 344.505282 -272.56202) (xy 344.513407 -272.613315) (xy 344.513916 -272.639282) (xy 344.513407 -272.665249)
			(xy 344.793571 -272.665249) (xy 344.793571 -272.613315) (xy 344.801696 -272.56202) (xy 344.817744 -272.512627)
			(xy 344.841322 -272.466353) (xy 344.871848 -272.424337) (xy 344.908571 -272.387614) (xy 344.950587 -272.357088)
			(xy 344.996861 -272.33351) (xy 345.046254 -272.317462) (xy 345.097549 -272.309337) (xy 345.149483 -272.309337)
			(xy 345.200778 -272.317462) (xy 345.250171 -272.33351) (xy 345.296445 -272.357088) (xy 345.338461 -272.387614)
			(xy 345.375184 -272.424337) (xy 345.40571 -272.466353) (xy 345.429288 -272.512627) (xy 345.445336 -272.56202)
			(xy 345.453461 -272.613315) (xy 345.45397 -272.639282) (xy 345.453461 -272.665249) (xy 345.733117 -272.665249)
			(xy 345.733117 -272.613315) (xy 345.741242 -272.56202) (xy 345.75729 -272.512627) (xy 345.780868 -272.466353)
			(xy 345.811394 -272.424337) (xy 345.848117 -272.387614) (xy 345.890133 -272.357088) (xy 345.936407 -272.33351)
			(xy 345.9858 -272.317462) (xy 346.037095 -272.309337) (xy 346.089029 -272.309337) (xy 346.140324 -272.317462)
			(xy 346.189717 -272.33351) (xy 346.235991 -272.357088) (xy 346.278007 -272.387614) (xy 346.31473 -272.424337)
			(xy 346.345256 -272.466353) (xy 346.368834 -272.512627) (xy 346.384882 -272.56202) (xy 346.393007 -272.613315)
			(xy 346.393516 -272.639282) (xy 346.393007 -272.665249) (xy 346.672917 -272.665249) (xy 346.672917 -272.613315)
			(xy 346.681042 -272.56202) (xy 346.69709 -272.512627) (xy 346.720668 -272.466353) (xy 346.751194 -272.424337)
			(xy 346.787917 -272.387614) (xy 346.829933 -272.357088) (xy 346.876207 -272.33351) (xy 346.9256 -272.317462)
			(xy 346.976895 -272.309337) (xy 347.028829 -272.309337) (xy 347.080124 -272.317462) (xy 347.129517 -272.33351)
			(xy 347.175791 -272.357088) (xy 347.217807 -272.387614) (xy 347.25453 -272.424337) (xy 347.285056 -272.466353)
			(xy 347.308634 -272.512627) (xy 347.324682 -272.56202) (xy 347.332807 -272.613315) (xy 347.333316 -272.639282)
			(xy 347.332807 -272.665249) (xy 347.612717 -272.665249) (xy 347.612717 -272.613315) (xy 347.620842 -272.56202)
			(xy 347.63689 -272.512627) (xy 347.660468 -272.466353) (xy 347.690994 -272.424337) (xy 347.727717 -272.387614)
			(xy 347.769733 -272.357088) (xy 347.816007 -272.33351) (xy 347.8654 -272.317462) (xy 347.916695 -272.309337)
			(xy 347.968629 -272.309337) (xy 348.019924 -272.317462) (xy 348.069317 -272.33351) (xy 348.115591 -272.357088)
			(xy 348.157607 -272.387614) (xy 348.19433 -272.424337) (xy 348.224856 -272.466353) (xy 348.248434 -272.512627)
			(xy 348.264482 -272.56202) (xy 348.272607 -272.613315) (xy 348.273116 -272.639282) (xy 348.272607 -272.665249)
			(xy 348.552517 -272.665249) (xy 348.552517 -272.613315) (xy 348.560642 -272.56202) (xy 348.57669 -272.512627)
			(xy 348.600268 -272.466353) (xy 348.630794 -272.424337) (xy 348.667517 -272.387614) (xy 348.709533 -272.357088)
			(xy 348.755807 -272.33351) (xy 348.8052 -272.317462) (xy 348.856495 -272.309337) (xy 348.908429 -272.309337)
			(xy 348.959724 -272.317462) (xy 349.009117 -272.33351) (xy 349.055391 -272.357088) (xy 349.097407 -272.387614)
			(xy 349.13413 -272.424337) (xy 349.164656 -272.466353) (xy 349.188234 -272.512627) (xy 349.204282 -272.56202)
			(xy 349.212407 -272.613315) (xy 349.212916 -272.639282) (xy 349.212407 -272.665249) (xy 349.492317 -272.665249)
			(xy 349.492317 -272.613315) (xy 349.500442 -272.56202) (xy 349.51649 -272.512627) (xy 349.540068 -272.466353)
			(xy 349.570594 -272.424337) (xy 349.607317 -272.387614) (xy 349.649333 -272.357088) (xy 349.695607 -272.33351)
			(xy 349.745 -272.317462) (xy 349.796295 -272.309337) (xy 349.848229 -272.309337) (xy 349.899524 -272.317462)
			(xy 349.948917 -272.33351) (xy 349.995191 -272.357088) (xy 350.037207 -272.387614) (xy 350.07393 -272.424337)
			(xy 350.104456 -272.466353) (xy 350.128034 -272.512627) (xy 350.144082 -272.56202) (xy 350.152207 -272.613315)
			(xy 350.152716 -272.639282) (xy 350.152207 -272.665249) (xy 350.432117 -272.665249) (xy 350.432117 -272.613315)
			(xy 350.440242 -272.56202) (xy 350.45629 -272.512627) (xy 350.479868 -272.466353) (xy 350.510394 -272.424337)
			(xy 350.547117 -272.387614) (xy 350.589133 -272.357088) (xy 350.635407 -272.33351) (xy 350.6848 -272.317462)
			(xy 350.736095 -272.309337) (xy 350.788029 -272.309337) (xy 350.839324 -272.317462) (xy 350.888717 -272.33351)
			(xy 350.934991 -272.357088) (xy 350.977007 -272.387614) (xy 351.01373 -272.424337) (xy 351.044256 -272.466353)
			(xy 351.067834 -272.512627) (xy 351.083882 -272.56202) (xy 351.092007 -272.613315) (xy 351.092516 -272.639282)
			(xy 351.092007 -272.665249) (xy 351.371917 -272.665249) (xy 351.371917 -272.613315) (xy 351.380042 -272.56202)
			(xy 351.39609 -272.512627) (xy 351.419668 -272.466353) (xy 351.450194 -272.424337) (xy 351.486917 -272.387614)
			(xy 351.528933 -272.357088) (xy 351.575207 -272.33351) (xy 351.6246 -272.317462) (xy 351.675895 -272.309337)
			(xy 351.727829 -272.309337) (xy 351.779124 -272.317462) (xy 351.828517 -272.33351) (xy 351.874791 -272.357088)
			(xy 351.916807 -272.387614) (xy 351.95353 -272.424337) (xy 351.984056 -272.466353) (xy 352.007634 -272.512627)
			(xy 352.023682 -272.56202) (xy 352.031807 -272.613315) (xy 352.032316 -272.639282) (xy 352.031807 -272.665249)
			(xy 352.311717 -272.665249) (xy 352.311717 -272.613315) (xy 352.319842 -272.56202) (xy 352.33589 -272.512627)
			(xy 352.359468 -272.466353) (xy 352.389994 -272.424337) (xy 352.426717 -272.387614) (xy 352.468733 -272.357088)
			(xy 352.515007 -272.33351) (xy 352.5644 -272.317462) (xy 352.615695 -272.309337) (xy 352.667629 -272.309337)
			(xy 352.718924 -272.317462) (xy 352.768317 -272.33351) (xy 352.814591 -272.357088) (xy 352.856607 -272.387614)
			(xy 352.89333 -272.424337) (xy 352.923856 -272.466353) (xy 352.947434 -272.512627) (xy 352.963482 -272.56202)
			(xy 352.971607 -272.613315) (xy 352.972116 -272.639282) (xy 352.971607 -272.665249) (xy 353.251517 -272.665249)
			(xy 353.251517 -272.613315) (xy 353.259642 -272.56202) (xy 353.27569 -272.512627) (xy 353.299268 -272.466353)
			(xy 353.329794 -272.424337) (xy 353.366517 -272.387614) (xy 353.408533 -272.357088) (xy 353.454807 -272.33351)
			(xy 353.5042 -272.317462) (xy 353.555495 -272.309337) (xy 353.607429 -272.309337) (xy 353.658724 -272.317462)
			(xy 353.708117 -272.33351) (xy 353.754391 -272.357088) (xy 353.796407 -272.387614) (xy 353.83313 -272.424337)
			(xy 353.863656 -272.466353) (xy 353.887234 -272.512627) (xy 353.903282 -272.56202) (xy 353.911407 -272.613315)
			(xy 353.911916 -272.639282) (xy 353.911407 -272.665249) (xy 354.191317 -272.665249) (xy 354.191317 -272.613315)
			(xy 354.199442 -272.56202) (xy 354.21549 -272.512627) (xy 354.239068 -272.466353) (xy 354.269594 -272.424337)
			(xy 354.306317 -272.387614) (xy 354.348333 -272.357088) (xy 354.394607 -272.33351) (xy 354.444 -272.317462)
			(xy 354.495295 -272.309337) (xy 354.547229 -272.309337) (xy 354.598524 -272.317462) (xy 354.647917 -272.33351)
			(xy 354.694191 -272.357088) (xy 354.736207 -272.387614) (xy 354.77293 -272.424337) (xy 354.803456 -272.466353)
			(xy 354.827034 -272.512627) (xy 354.843082 -272.56202) (xy 354.851207 -272.613315) (xy 354.851716 -272.639282)
			(xy 354.851207 -272.665249) (xy 355.131117 -272.665249) (xy 355.131117 -272.613315) (xy 355.139242 -272.56202)
			(xy 355.15529 -272.512627) (xy 355.178868 -272.466353) (xy 355.209394 -272.424337) (xy 355.246117 -272.387614)
			(xy 355.288133 -272.357088) (xy 355.334407 -272.33351) (xy 355.3838 -272.317462) (xy 355.435095 -272.309337)
			(xy 355.487029 -272.309337) (xy 355.538324 -272.317462) (xy 355.587717 -272.33351) (xy 355.633991 -272.357088)
			(xy 355.676007 -272.387614) (xy 355.71273 -272.424337) (xy 355.743256 -272.466353) (xy 355.766834 -272.512627)
			(xy 355.782882 -272.56202) (xy 355.791007 -272.613315) (xy 355.791516 -272.639282) (xy 355.791007 -272.665249)
			(xy 356.070917 -272.665249) (xy 356.070917 -272.613315) (xy 356.079042 -272.56202) (xy 356.09509 -272.512627)
			(xy 356.118668 -272.466353) (xy 356.149194 -272.424337) (xy 356.185917 -272.387614) (xy 356.227933 -272.357088)
			(xy 356.274207 -272.33351) (xy 356.3236 -272.317462) (xy 356.374895 -272.309337) (xy 356.426829 -272.309337)
			(xy 356.478124 -272.317462) (xy 356.527517 -272.33351) (xy 356.573791 -272.357088) (xy 356.615807 -272.387614)
			(xy 356.65253 -272.424337) (xy 356.683056 -272.466353) (xy 356.706634 -272.512627) (xy 356.722682 -272.56202)
			(xy 356.730807 -272.613315) (xy 356.731316 -272.639282) (xy 356.730807 -272.665249) (xy 357.010717 -272.665249)
			(xy 357.010717 -272.613315) (xy 357.018842 -272.56202) (xy 357.03489 -272.512627) (xy 357.058468 -272.466353)
			(xy 357.088994 -272.424337) (xy 357.125717 -272.387614) (xy 357.167733 -272.357088) (xy 357.214007 -272.33351)
			(xy 357.2634 -272.317462) (xy 357.314695 -272.309337) (xy 357.366629 -272.309337) (xy 357.417924 -272.317462)
			(xy 357.467317 -272.33351) (xy 357.513591 -272.357088) (xy 357.555607 -272.387614) (xy 357.59233 -272.424337)
			(xy 357.622856 -272.466353) (xy 357.646434 -272.512627) (xy 357.662482 -272.56202) (xy 357.670607 -272.613315)
			(xy 357.671116 -272.639282) (xy 357.670607 -272.665249) (xy 357.950517 -272.665249) (xy 357.950517 -272.613315)
			(xy 357.958642 -272.56202) (xy 357.97469 -272.512627) (xy 357.998268 -272.466353) (xy 358.028794 -272.424337)
			(xy 358.065517 -272.387614) (xy 358.107533 -272.357088) (xy 358.153807 -272.33351) (xy 358.2032 -272.317462)
			(xy 358.254495 -272.309337) (xy 358.306429 -272.309337) (xy 358.357724 -272.317462) (xy 358.407117 -272.33351)
			(xy 358.453391 -272.357088) (xy 358.495407 -272.387614) (xy 358.53213 -272.424337) (xy 358.562656 -272.466353)
			(xy 358.586234 -272.512627) (xy 358.602282 -272.56202) (xy 358.610407 -272.613315) (xy 358.610916 -272.639282)
			(xy 358.610407 -272.665249) (xy 358.890571 -272.665249) (xy 358.890571 -272.613315) (xy 358.898696 -272.56202)
			(xy 358.914744 -272.512627) (xy 358.938322 -272.466353) (xy 358.968848 -272.424337) (xy 359.005571 -272.387614)
			(xy 359.047587 -272.357088) (xy 359.093861 -272.33351) (xy 359.143254 -272.317462) (xy 359.194549 -272.309337)
			(xy 359.246483 -272.309337) (xy 359.297778 -272.317462) (xy 359.347171 -272.33351) (xy 359.393445 -272.357088)
			(xy 359.435461 -272.387614) (xy 359.472184 -272.424337) (xy 359.50271 -272.466353) (xy 359.526288 -272.512627)
			(xy 359.542336 -272.56202) (xy 359.550461 -272.613315) (xy 359.55097 -272.639282) (xy 359.550461 -272.665249)
			(xy 359.830371 -272.665249) (xy 359.830371 -272.613315) (xy 359.838496 -272.56202) (xy 359.854544 -272.512627)
			(xy 359.878122 -272.466353) (xy 359.908648 -272.424337) (xy 359.945371 -272.387614) (xy 359.987387 -272.357088)
			(xy 360.033661 -272.33351) (xy 360.083054 -272.317462) (xy 360.134349 -272.309337) (xy 360.186283 -272.309337)
			(xy 360.237578 -272.317462) (xy 360.286971 -272.33351) (xy 360.333245 -272.357088) (xy 360.375261 -272.387614)
			(xy 360.411984 -272.424337) (xy 360.44251 -272.466353) (xy 360.466088 -272.512627) (xy 360.482136 -272.56202)
			(xy 360.490261 -272.613315) (xy 360.49077 -272.639282) (xy 360.490261 -272.665249) (xy 360.769917 -272.665249)
			(xy 360.769917 -272.613315) (xy 360.778042 -272.56202) (xy 360.79409 -272.512627) (xy 360.817668 -272.466353)
			(xy 360.848194 -272.424337) (xy 360.884917 -272.387614) (xy 360.926933 -272.357088) (xy 360.973207 -272.33351)
			(xy 361.0226 -272.317462) (xy 361.073895 -272.309337) (xy 361.125829 -272.309337) (xy 361.177124 -272.317462)
			(xy 361.226517 -272.33351) (xy 361.272791 -272.357088) (xy 361.314807 -272.387614) (xy 361.35153 -272.424337)
			(xy 361.382056 -272.466353) (xy 361.405634 -272.512627) (xy 361.421682 -272.56202) (xy 361.429807 -272.613315)
			(xy 361.430316 -272.639282) (xy 361.429807 -272.665249) (xy 361.709717 -272.665249) (xy 361.709717 -272.613315)
			(xy 361.717842 -272.56202) (xy 361.73389 -272.512627) (xy 361.757468 -272.466353) (xy 361.787994 -272.424337)
			(xy 361.824717 -272.387614) (xy 361.866733 -272.357088) (xy 361.913007 -272.33351) (xy 361.9624 -272.317462)
			(xy 362.013695 -272.309337) (xy 362.065629 -272.309337) (xy 362.116924 -272.317462) (xy 362.166317 -272.33351)
			(xy 362.212591 -272.357088) (xy 362.254607 -272.387614) (xy 362.29133 -272.424337) (xy 362.321856 -272.466353)
			(xy 362.345434 -272.512627) (xy 362.361482 -272.56202) (xy 362.369607 -272.613315) (xy 362.370116 -272.639282)
			(xy 362.369607 -272.665249) (xy 362.649517 -272.665249) (xy 362.649517 -272.613315) (xy 362.657642 -272.56202)
			(xy 362.67369 -272.512627) (xy 362.697268 -272.466353) (xy 362.727794 -272.424337) (xy 362.764517 -272.387614)
			(xy 362.806533 -272.357088) (xy 362.852807 -272.33351) (xy 362.9022 -272.317462) (xy 362.953495 -272.309337)
			(xy 363.005429 -272.309337) (xy 363.056724 -272.317462) (xy 363.106117 -272.33351) (xy 363.152391 -272.357088)
			(xy 363.194407 -272.387614) (xy 363.23113 -272.424337) (xy 363.261656 -272.466353) (xy 363.285234 -272.512627)
			(xy 363.301282 -272.56202) (xy 363.309407 -272.613315) (xy 363.309916 -272.639282) (xy 363.309407 -272.665249)
			(xy 363.589317 -272.665249) (xy 363.589317 -272.613315) (xy 363.597442 -272.56202) (xy 363.61349 -272.512627)
			(xy 363.637068 -272.466353) (xy 363.667594 -272.424337) (xy 363.704317 -272.387614) (xy 363.746333 -272.357088)
			(xy 363.792607 -272.33351) (xy 363.842 -272.317462) (xy 363.893295 -272.309337) (xy 363.945229 -272.309337)
			(xy 363.996524 -272.317462) (xy 364.045917 -272.33351) (xy 364.092191 -272.357088) (xy 364.134207 -272.387614)
			(xy 364.17093 -272.424337) (xy 364.201456 -272.466353) (xy 364.225034 -272.512627) (xy 364.241082 -272.56202)
			(xy 364.249207 -272.613315) (xy 364.249716 -272.639282) (xy 364.249207 -272.665249) (xy 364.529117 -272.665249)
			(xy 364.529117 -272.613315) (xy 364.537242 -272.56202) (xy 364.55329 -272.512627) (xy 364.576868 -272.466353)
			(xy 364.607394 -272.424337) (xy 364.644117 -272.387614) (xy 364.686133 -272.357088) (xy 364.732407 -272.33351)
			(xy 364.7818 -272.317462) (xy 364.833095 -272.309337) (xy 364.885029 -272.309337) (xy 364.936324 -272.317462)
			(xy 364.985717 -272.33351) (xy 365.031991 -272.357088) (xy 365.074007 -272.387614) (xy 365.11073 -272.424337)
			(xy 365.141256 -272.466353) (xy 365.164834 -272.512627) (xy 365.180882 -272.56202) (xy 365.189007 -272.613315)
			(xy 365.189516 -272.639282) (xy 365.189007 -272.665249) (xy 365.468917 -272.665249) (xy 365.468917 -272.613315)
			(xy 365.477042 -272.56202) (xy 365.49309 -272.512627) (xy 365.516668 -272.466353) (xy 365.547194 -272.424337)
			(xy 365.583917 -272.387614) (xy 365.625933 -272.357088) (xy 365.672207 -272.33351) (xy 365.7216 -272.317462)
			(xy 365.772895 -272.309337) (xy 365.824829 -272.309337) (xy 365.876124 -272.317462) (xy 365.925517 -272.33351)
			(xy 365.971791 -272.357088) (xy 366.013807 -272.387614) (xy 366.05053 -272.424337) (xy 366.081056 -272.466353)
			(xy 366.104634 -272.512627) (xy 366.120682 -272.56202) (xy 366.128807 -272.613315) (xy 366.129316 -272.639282)
			(xy 366.128807 -272.665249) (xy 366.408717 -272.665249) (xy 366.408717 -272.613315) (xy 366.416842 -272.56202)
			(xy 366.43289 -272.512627) (xy 366.456468 -272.466353) (xy 366.486994 -272.424337) (xy 366.523717 -272.387614)
			(xy 366.565733 -272.357088) (xy 366.612007 -272.33351) (xy 366.6614 -272.317462) (xy 366.712695 -272.309337)
			(xy 366.764629 -272.309337) (xy 366.815924 -272.317462) (xy 366.865317 -272.33351) (xy 366.911591 -272.357088)
			(xy 366.953607 -272.387614) (xy 366.99033 -272.424337) (xy 367.020856 -272.466353) (xy 367.044434 -272.512627)
			(xy 367.060482 -272.56202) (xy 367.068607 -272.613315) (xy 367.069116 -272.639282) (xy 367.068607 -272.665249)
			(xy 367.348517 -272.665249) (xy 367.348517 -272.613315) (xy 367.356642 -272.56202) (xy 367.37269 -272.512627)
			(xy 367.396268 -272.466353) (xy 367.426794 -272.424337) (xy 367.463517 -272.387614) (xy 367.505533 -272.357088)
			(xy 367.551807 -272.33351) (xy 367.6012 -272.317462) (xy 367.652495 -272.309337) (xy 367.704429 -272.309337)
			(xy 367.755724 -272.317462) (xy 367.805117 -272.33351) (xy 367.851391 -272.357088) (xy 367.893407 -272.387614)
			(xy 367.93013 -272.424337) (xy 367.960656 -272.466353) (xy 367.984234 -272.512627) (xy 368.000282 -272.56202)
			(xy 368.008407 -272.613315) (xy 368.008916 -272.639282) (xy 368.008407 -272.665249) (xy 368.288317 -272.665249)
			(xy 368.288317 -272.613315) (xy 368.296442 -272.56202) (xy 368.31249 -272.512627) (xy 368.336068 -272.466353)
			(xy 368.366594 -272.424337) (xy 368.403317 -272.387614) (xy 368.445333 -272.357088) (xy 368.491607 -272.33351)
			(xy 368.541 -272.317462) (xy 368.592295 -272.309337) (xy 368.644229 -272.309337) (xy 368.695524 -272.317462)
			(xy 368.744917 -272.33351) (xy 368.791191 -272.357088) (xy 368.833207 -272.387614) (xy 368.86993 -272.424337)
			(xy 368.900456 -272.466353) (xy 368.924034 -272.512627) (xy 368.940082 -272.56202) (xy 368.948207 -272.613315)
			(xy 368.948716 -272.639282) (xy 368.948207 -272.665249) (xy 369.228117 -272.665249) (xy 369.228117 -272.613315)
			(xy 369.236242 -272.56202) (xy 369.25229 -272.512627) (xy 369.275868 -272.466353) (xy 369.306394 -272.424337)
			(xy 369.343117 -272.387614) (xy 369.385133 -272.357088) (xy 369.431407 -272.33351) (xy 369.4808 -272.317462)
			(xy 369.532095 -272.309337) (xy 369.584029 -272.309337) (xy 369.635324 -272.317462) (xy 369.684717 -272.33351)
			(xy 369.730991 -272.357088) (xy 369.773007 -272.387614) (xy 369.80973 -272.424337) (xy 369.840256 -272.466353)
			(xy 369.863834 -272.512627) (xy 369.879882 -272.56202) (xy 369.888007 -272.613315) (xy 369.888516 -272.639282)
			(xy 369.888007 -272.665249) (xy 370.167917 -272.665249) (xy 370.167917 -272.613315) (xy 370.176042 -272.56202)
			(xy 370.19209 -272.512627) (xy 370.215668 -272.466353) (xy 370.246194 -272.424337) (xy 370.282917 -272.387614)
			(xy 370.324933 -272.357088) (xy 370.371207 -272.33351) (xy 370.4206 -272.317462) (xy 370.471895 -272.309337)
			(xy 370.523829 -272.309337) (xy 370.575124 -272.317462) (xy 370.624517 -272.33351) (xy 370.670791 -272.357088)
			(xy 370.712807 -272.387614) (xy 370.74953 -272.424337) (xy 370.780056 -272.466353) (xy 370.803634 -272.512627)
			(xy 370.819682 -272.56202) (xy 370.827807 -272.613315) (xy 370.828316 -272.639282) (xy 370.827807 -272.665249)
			(xy 371.107717 -272.665249) (xy 371.107717 -272.613315) (xy 371.115842 -272.56202) (xy 371.13189 -272.512627)
			(xy 371.155468 -272.466353) (xy 371.185994 -272.424337) (xy 371.222717 -272.387614) (xy 371.264733 -272.357088)
			(xy 371.311007 -272.33351) (xy 371.3604 -272.317462) (xy 371.411695 -272.309337) (xy 371.463629 -272.309337)
			(xy 371.514924 -272.317462) (xy 371.564317 -272.33351) (xy 371.610591 -272.357088) (xy 371.652607 -272.387614)
			(xy 371.68933 -272.424337) (xy 371.719856 -272.466353) (xy 371.743434 -272.512627) (xy 371.759482 -272.56202)
			(xy 371.767607 -272.613315) (xy 371.768116 -272.639282) (xy 371.767607 -272.665249) (xy 372.047517 -272.665249)
			(xy 372.047517 -272.613315) (xy 372.055642 -272.56202) (xy 372.07169 -272.512627) (xy 372.095268 -272.466353)
			(xy 372.125794 -272.424337) (xy 372.162517 -272.387614) (xy 372.204533 -272.357088) (xy 372.250807 -272.33351)
			(xy 372.3002 -272.317462) (xy 372.351495 -272.309337) (xy 372.403429 -272.309337) (xy 372.454724 -272.317462)
			(xy 372.504117 -272.33351) (xy 372.550391 -272.357088) (xy 372.592407 -272.387614) (xy 372.62913 -272.424337)
			(xy 372.659656 -272.466353) (xy 372.683234 -272.512627) (xy 372.699282 -272.56202) (xy 372.707407 -272.613315)
			(xy 372.707916 -272.639282) (xy 372.707407 -272.665249) (xy 372.987571 -272.665249) (xy 372.987571 -272.613315)
			(xy 372.995696 -272.56202) (xy 373.011744 -272.512627) (xy 373.035322 -272.466353) (xy 373.065848 -272.424337)
			(xy 373.102571 -272.387614) (xy 373.144587 -272.357088) (xy 373.190861 -272.33351) (xy 373.240254 -272.317462)
			(xy 373.291549 -272.309337) (xy 373.343483 -272.309337) (xy 373.394778 -272.317462) (xy 373.444171 -272.33351)
			(xy 373.490445 -272.357088) (xy 373.532461 -272.387614) (xy 373.569184 -272.424337) (xy 373.59971 -272.466353)
			(xy 373.623288 -272.512627) (xy 373.639336 -272.56202) (xy 373.647461 -272.613315) (xy 373.64797 -272.639282)
			(xy 373.647461 -272.665249) (xy 373.927117 -272.665249) (xy 373.927117 -272.613315) (xy 373.935242 -272.56202)
			(xy 373.95129 -272.512627) (xy 373.974868 -272.466353) (xy 374.005394 -272.424337) (xy 374.042117 -272.387614)
			(xy 374.084133 -272.357088) (xy 374.130407 -272.33351) (xy 374.1798 -272.317462) (xy 374.231095 -272.309337)
			(xy 374.283029 -272.309337) (xy 374.334324 -272.317462) (xy 374.383717 -272.33351) (xy 374.429991 -272.357088)
			(xy 374.472007 -272.387614) (xy 374.50873 -272.424337) (xy 374.539256 -272.466353) (xy 374.562834 -272.512627)
			(xy 374.578882 -272.56202) (xy 374.587007 -272.613315) (xy 374.587516 -272.639282) (xy 374.587007 -272.665249)
			(xy 374.866917 -272.665249) (xy 374.866917 -272.613315) (xy 374.875042 -272.56202) (xy 374.89109 -272.512627)
			(xy 374.914668 -272.466353) (xy 374.945194 -272.424337) (xy 374.981917 -272.387614) (xy 375.023933 -272.357088)
			(xy 375.070207 -272.33351) (xy 375.1196 -272.317462) (xy 375.170895 -272.309337) (xy 375.222829 -272.309337)
			(xy 375.274124 -272.317462) (xy 375.323517 -272.33351) (xy 375.369791 -272.357088) (xy 375.411807 -272.387614)
			(xy 375.44853 -272.424337) (xy 375.479056 -272.466353) (xy 375.502634 -272.512627) (xy 375.518682 -272.56202)
			(xy 375.526807 -272.613315) (xy 375.527316 -272.639282) (xy 375.526807 -272.665249) (xy 375.806717 -272.665249)
			(xy 375.806717 -272.613315) (xy 375.814842 -272.56202) (xy 375.83089 -272.512627) (xy 375.854468 -272.466353)
			(xy 375.884994 -272.424337) (xy 375.921717 -272.387614) (xy 375.963733 -272.357088) (xy 376.010007 -272.33351)
			(xy 376.0594 -272.317462) (xy 376.110695 -272.309337) (xy 376.162629 -272.309337) (xy 376.213924 -272.317462)
			(xy 376.263317 -272.33351) (xy 376.309591 -272.357088) (xy 376.351607 -272.387614) (xy 376.38833 -272.424337)
			(xy 376.418856 -272.466353) (xy 376.442434 -272.512627) (xy 376.458482 -272.56202) (xy 376.466607 -272.613315)
			(xy 376.467116 -272.639282) (xy 376.466607 -272.665249) (xy 376.746517 -272.665249) (xy 376.746517 -272.613315)
			(xy 376.754642 -272.56202) (xy 376.77069 -272.512627) (xy 376.794268 -272.466353) (xy 376.824794 -272.424337)
			(xy 376.861517 -272.387614) (xy 376.903533 -272.357088) (xy 376.949807 -272.33351) (xy 376.9992 -272.317462)
			(xy 377.050495 -272.309337) (xy 377.102429 -272.309337) (xy 377.153724 -272.317462) (xy 377.203117 -272.33351)
			(xy 377.249391 -272.357088) (xy 377.291407 -272.387614) (xy 377.32813 -272.424337) (xy 377.358656 -272.466353)
			(xy 377.382234 -272.512627) (xy 377.398282 -272.56202) (xy 377.406407 -272.613315) (xy 377.406916 -272.639282)
			(xy 377.406407 -272.665249) (xy 377.686317 -272.665249) (xy 377.686317 -272.613315) (xy 377.694442 -272.56202)
			(xy 377.71049 -272.512627) (xy 377.734068 -272.466353) (xy 377.764594 -272.424337) (xy 377.801317 -272.387614)
			(xy 377.843333 -272.357088) (xy 377.889607 -272.33351) (xy 377.939 -272.317462) (xy 377.990295 -272.309337)
			(xy 378.042229 -272.309337) (xy 378.093524 -272.317462) (xy 378.142917 -272.33351) (xy 378.189191 -272.357088)
			(xy 378.231207 -272.387614) (xy 378.26793 -272.424337) (xy 378.298456 -272.466353) (xy 378.322034 -272.512627)
			(xy 378.338082 -272.56202) (xy 378.346207 -272.613315) (xy 378.346716 -272.639282) (xy 378.346207 -272.665249)
			(xy 378.626117 -272.665249) (xy 378.626117 -272.613315) (xy 378.634242 -272.56202) (xy 378.65029 -272.512627)
			(xy 378.673868 -272.466353) (xy 378.704394 -272.424337) (xy 378.741117 -272.387614) (xy 378.783133 -272.357088)
			(xy 378.829407 -272.33351) (xy 378.8788 -272.317462) (xy 378.930095 -272.309337) (xy 378.982029 -272.309337)
			(xy 379.033324 -272.317462) (xy 379.082717 -272.33351) (xy 379.128991 -272.357088) (xy 379.171007 -272.387614)
			(xy 379.20773 -272.424337) (xy 379.238256 -272.466353) (xy 379.261834 -272.512627) (xy 379.277882 -272.56202)
			(xy 379.286007 -272.613315) (xy 379.286516 -272.639282) (xy 379.286007 -272.665249) (xy 379.277882 -272.716544)
			(xy 379.261834 -272.765937) (xy 379.238256 -272.812211) (xy 379.20773 -272.854227) (xy 379.171007 -272.89095)
			(xy 379.128991 -272.921476) (xy 379.082717 -272.945054) (xy 379.033324 -272.961102) (xy 378.982029 -272.969227)
			(xy 378.930095 -272.969227) (xy 378.8788 -272.961102) (xy 378.829407 -272.945054) (xy 378.783133 -272.921476)
			(xy 378.741117 -272.89095) (xy 378.704394 -272.854227) (xy 378.673868 -272.812211) (xy 378.65029 -272.765937)
			(xy 378.634242 -272.716544) (xy 378.626117 -272.665249) (xy 378.346207 -272.665249) (xy 378.338082 -272.716544)
			(xy 378.322034 -272.765937) (xy 378.298456 -272.812211) (xy 378.26793 -272.854227) (xy 378.231207 -272.89095)
			(xy 378.189191 -272.921476) (xy 378.142917 -272.945054) (xy 378.093524 -272.961102) (xy 378.042229 -272.969227)
			(xy 377.990295 -272.969227) (xy 377.939 -272.961102) (xy 377.889607 -272.945054) (xy 377.843333 -272.921476)
			(xy 377.801317 -272.89095) (xy 377.764594 -272.854227) (xy 377.734068 -272.812211) (xy 377.71049 -272.765937)
			(xy 377.694442 -272.716544) (xy 377.686317 -272.665249) (xy 377.406407 -272.665249) (xy 377.398282 -272.716544)
			(xy 377.382234 -272.765937) (xy 377.358656 -272.812211) (xy 377.32813 -272.854227) (xy 377.291407 -272.89095)
			(xy 377.249391 -272.921476) (xy 377.203117 -272.945054) (xy 377.153724 -272.961102) (xy 377.102429 -272.969227)
			(xy 377.050495 -272.969227) (xy 376.9992 -272.961102) (xy 376.949807 -272.945054) (xy 376.903533 -272.921476)
			(xy 376.861517 -272.89095) (xy 376.824794 -272.854227) (xy 376.794268 -272.812211) (xy 376.77069 -272.765937)
			(xy 376.754642 -272.716544) (xy 376.746517 -272.665249) (xy 376.466607 -272.665249) (xy 376.458482 -272.716544)
			(xy 376.442434 -272.765937) (xy 376.418856 -272.812211) (xy 376.38833 -272.854227) (xy 376.351607 -272.89095)
			(xy 376.309591 -272.921476) (xy 376.263317 -272.945054) (xy 376.213924 -272.961102) (xy 376.162629 -272.969227)
			(xy 376.110695 -272.969227) (xy 376.0594 -272.961102) (xy 376.010007 -272.945054) (xy 375.963733 -272.921476)
			(xy 375.921717 -272.89095) (xy 375.884994 -272.854227) (xy 375.854468 -272.812211) (xy 375.83089 -272.765937)
			(xy 375.814842 -272.716544) (xy 375.806717 -272.665249) (xy 375.526807 -272.665249) (xy 375.518682 -272.716544)
			(xy 375.502634 -272.765937) (xy 375.479056 -272.812211) (xy 375.44853 -272.854227) (xy 375.411807 -272.89095)
			(xy 375.369791 -272.921476) (xy 375.323517 -272.945054) (xy 375.274124 -272.961102) (xy 375.222829 -272.969227)
			(xy 375.170895 -272.969227) (xy 375.1196 -272.961102) (xy 375.070207 -272.945054) (xy 375.023933 -272.921476)
			(xy 374.981917 -272.89095) (xy 374.945194 -272.854227) (xy 374.914668 -272.812211) (xy 374.89109 -272.765937)
			(xy 374.875042 -272.716544) (xy 374.866917 -272.665249) (xy 374.587007 -272.665249) (xy 374.578882 -272.716544)
			(xy 374.562834 -272.765937) (xy 374.539256 -272.812211) (xy 374.50873 -272.854227) (xy 374.472007 -272.89095)
			(xy 374.429991 -272.921476) (xy 374.383717 -272.945054) (xy 374.334324 -272.961102) (xy 374.283029 -272.969227)
			(xy 374.231095 -272.969227) (xy 374.1798 -272.961102) (xy 374.130407 -272.945054) (xy 374.084133 -272.921476)
			(xy 374.042117 -272.89095) (xy 374.005394 -272.854227) (xy 373.974868 -272.812211) (xy 373.95129 -272.765937)
			(xy 373.935242 -272.716544) (xy 373.927117 -272.665249) (xy 373.647461 -272.665249) (xy 373.639336 -272.716544)
			(xy 373.623288 -272.765937) (xy 373.59971 -272.812211) (xy 373.569184 -272.854227) (xy 373.532461 -272.89095)
			(xy 373.490445 -272.921476) (xy 373.444171 -272.945054) (xy 373.394778 -272.961102) (xy 373.343483 -272.969227)
			(xy 373.291549 -272.969227) (xy 373.240254 -272.961102) (xy 373.190861 -272.945054) (xy 373.144587 -272.921476)
			(xy 373.102571 -272.89095) (xy 373.065848 -272.854227) (xy 373.035322 -272.812211) (xy 373.011744 -272.765937)
			(xy 372.995696 -272.716544) (xy 372.987571 -272.665249) (xy 372.707407 -272.665249) (xy 372.699282 -272.716544)
			(xy 372.683234 -272.765937) (xy 372.659656 -272.812211) (xy 372.62913 -272.854227) (xy 372.592407 -272.89095)
			(xy 372.550391 -272.921476) (xy 372.504117 -272.945054) (xy 372.454724 -272.961102) (xy 372.403429 -272.969227)
			(xy 372.351495 -272.969227) (xy 372.3002 -272.961102) (xy 372.250807 -272.945054) (xy 372.204533 -272.921476)
			(xy 372.162517 -272.89095) (xy 372.125794 -272.854227) (xy 372.095268 -272.812211) (xy 372.07169 -272.765937)
			(xy 372.055642 -272.716544) (xy 372.047517 -272.665249) (xy 371.767607 -272.665249) (xy 371.759482 -272.716544)
			(xy 371.743434 -272.765937) (xy 371.719856 -272.812211) (xy 371.68933 -272.854227) (xy 371.652607 -272.89095)
			(xy 371.610591 -272.921476) (xy 371.564317 -272.945054) (xy 371.514924 -272.961102) (xy 371.463629 -272.969227)
			(xy 371.411695 -272.969227) (xy 371.3604 -272.961102) (xy 371.311007 -272.945054) (xy 371.264733 -272.921476)
			(xy 371.222717 -272.89095) (xy 371.185994 -272.854227) (xy 371.155468 -272.812211) (xy 371.13189 -272.765937)
			(xy 371.115842 -272.716544) (xy 371.107717 -272.665249) (xy 370.827807 -272.665249) (xy 370.819682 -272.716544)
			(xy 370.803634 -272.765937) (xy 370.780056 -272.812211) (xy 370.74953 -272.854227) (xy 370.712807 -272.89095)
			(xy 370.670791 -272.921476) (xy 370.624517 -272.945054) (xy 370.575124 -272.961102) (xy 370.523829 -272.969227)
			(xy 370.471895 -272.969227) (xy 370.4206 -272.961102) (xy 370.371207 -272.945054) (xy 370.324933 -272.921476)
			(xy 370.282917 -272.89095) (xy 370.246194 -272.854227) (xy 370.215668 -272.812211) (xy 370.19209 -272.765937)
			(xy 370.176042 -272.716544) (xy 370.167917 -272.665249) (xy 369.888007 -272.665249) (xy 369.879882 -272.716544)
			(xy 369.863834 -272.765937) (xy 369.840256 -272.812211) (xy 369.80973 -272.854227) (xy 369.773007 -272.89095)
			(xy 369.730991 -272.921476) (xy 369.684717 -272.945054) (xy 369.635324 -272.961102) (xy 369.584029 -272.969227)
			(xy 369.532095 -272.969227) (xy 369.4808 -272.961102) (xy 369.431407 -272.945054) (xy 369.385133 -272.921476)
			(xy 369.343117 -272.89095) (xy 369.306394 -272.854227) (xy 369.275868 -272.812211) (xy 369.25229 -272.765937)
			(xy 369.236242 -272.716544) (xy 369.228117 -272.665249) (xy 368.948207 -272.665249) (xy 368.940082 -272.716544)
			(xy 368.924034 -272.765937) (xy 368.900456 -272.812211) (xy 368.86993 -272.854227) (xy 368.833207 -272.89095)
			(xy 368.791191 -272.921476) (xy 368.744917 -272.945054) (xy 368.695524 -272.961102) (xy 368.644229 -272.969227)
			(xy 368.592295 -272.969227) (xy 368.541 -272.961102) (xy 368.491607 -272.945054) (xy 368.445333 -272.921476)
			(xy 368.403317 -272.89095) (xy 368.366594 -272.854227) (xy 368.336068 -272.812211) (xy 368.31249 -272.765937)
			(xy 368.296442 -272.716544) (xy 368.288317 -272.665249) (xy 368.008407 -272.665249) (xy 368.000282 -272.716544)
			(xy 367.984234 -272.765937) (xy 367.960656 -272.812211) (xy 367.93013 -272.854227) (xy 367.893407 -272.89095)
			(xy 367.851391 -272.921476) (xy 367.805117 -272.945054) (xy 367.755724 -272.961102) (xy 367.704429 -272.969227)
			(xy 367.652495 -272.969227) (xy 367.6012 -272.961102) (xy 367.551807 -272.945054) (xy 367.505533 -272.921476)
			(xy 367.463517 -272.89095) (xy 367.426794 -272.854227) (xy 367.396268 -272.812211) (xy 367.37269 -272.765937)
			(xy 367.356642 -272.716544) (xy 367.348517 -272.665249) (xy 367.068607 -272.665249) (xy 367.060482 -272.716544)
			(xy 367.044434 -272.765937) (xy 367.020856 -272.812211) (xy 366.99033 -272.854227) (xy 366.953607 -272.89095)
			(xy 366.911591 -272.921476) (xy 366.865317 -272.945054) (xy 366.815924 -272.961102) (xy 366.764629 -272.969227)
			(xy 366.712695 -272.969227) (xy 366.6614 -272.961102) (xy 366.612007 -272.945054) (xy 366.565733 -272.921476)
			(xy 366.523717 -272.89095) (xy 366.486994 -272.854227) (xy 366.456468 -272.812211) (xy 366.43289 -272.765937)
			(xy 366.416842 -272.716544) (xy 366.408717 -272.665249) (xy 366.128807 -272.665249) (xy 366.120682 -272.716544)
			(xy 366.104634 -272.765937) (xy 366.081056 -272.812211) (xy 366.05053 -272.854227) (xy 366.013807 -272.89095)
			(xy 365.971791 -272.921476) (xy 365.925517 -272.945054) (xy 365.876124 -272.961102) (xy 365.824829 -272.969227)
			(xy 365.772895 -272.969227) (xy 365.7216 -272.961102) (xy 365.672207 -272.945054) (xy 365.625933 -272.921476)
			(xy 365.583917 -272.89095) (xy 365.547194 -272.854227) (xy 365.516668 -272.812211) (xy 365.49309 -272.765937)
			(xy 365.477042 -272.716544) (xy 365.468917 -272.665249) (xy 365.189007 -272.665249) (xy 365.180882 -272.716544)
			(xy 365.164834 -272.765937) (xy 365.141256 -272.812211) (xy 365.11073 -272.854227) (xy 365.074007 -272.89095)
			(xy 365.031991 -272.921476) (xy 364.985717 -272.945054) (xy 364.936324 -272.961102) (xy 364.885029 -272.969227)
			(xy 364.833095 -272.969227) (xy 364.7818 -272.961102) (xy 364.732407 -272.945054) (xy 364.686133 -272.921476)
			(xy 364.644117 -272.89095) (xy 364.607394 -272.854227) (xy 364.576868 -272.812211) (xy 364.55329 -272.765937)
			(xy 364.537242 -272.716544) (xy 364.529117 -272.665249) (xy 364.249207 -272.665249) (xy 364.241082 -272.716544)
			(xy 364.225034 -272.765937) (xy 364.201456 -272.812211) (xy 364.17093 -272.854227) (xy 364.134207 -272.89095)
			(xy 364.092191 -272.921476) (xy 364.045917 -272.945054) (xy 363.996524 -272.961102) (xy 363.945229 -272.969227)
			(xy 363.893295 -272.969227) (xy 363.842 -272.961102) (xy 363.792607 -272.945054) (xy 363.746333 -272.921476)
			(xy 363.704317 -272.89095) (xy 363.667594 -272.854227) (xy 363.637068 -272.812211) (xy 363.61349 -272.765937)
			(xy 363.597442 -272.716544) (xy 363.589317 -272.665249) (xy 363.309407 -272.665249) (xy 363.301282 -272.716544)
			(xy 363.285234 -272.765937) (xy 363.261656 -272.812211) (xy 363.23113 -272.854227) (xy 363.194407 -272.89095)
			(xy 363.152391 -272.921476) (xy 363.106117 -272.945054) (xy 363.056724 -272.961102) (xy 363.005429 -272.969227)
			(xy 362.953495 -272.969227) (xy 362.9022 -272.961102) (xy 362.852807 -272.945054) (xy 362.806533 -272.921476)
			(xy 362.764517 -272.89095) (xy 362.727794 -272.854227) (xy 362.697268 -272.812211) (xy 362.67369 -272.765937)
			(xy 362.657642 -272.716544) (xy 362.649517 -272.665249) (xy 362.369607 -272.665249) (xy 362.361482 -272.716544)
			(xy 362.345434 -272.765937) (xy 362.321856 -272.812211) (xy 362.29133 -272.854227) (xy 362.254607 -272.89095)
			(xy 362.212591 -272.921476) (xy 362.166317 -272.945054) (xy 362.116924 -272.961102) (xy 362.065629 -272.969227)
			(xy 362.013695 -272.969227) (xy 361.9624 -272.961102) (xy 361.913007 -272.945054) (xy 361.866733 -272.921476)
			(xy 361.824717 -272.89095) (xy 361.787994 -272.854227) (xy 361.757468 -272.812211) (xy 361.73389 -272.765937)
			(xy 361.717842 -272.716544) (xy 361.709717 -272.665249) (xy 361.429807 -272.665249) (xy 361.421682 -272.716544)
			(xy 361.405634 -272.765937) (xy 361.382056 -272.812211) (xy 361.35153 -272.854227) (xy 361.314807 -272.89095)
			(xy 361.272791 -272.921476) (xy 361.226517 -272.945054) (xy 361.177124 -272.961102) (xy 361.125829 -272.969227)
			(xy 361.073895 -272.969227) (xy 361.0226 -272.961102) (xy 360.973207 -272.945054) (xy 360.926933 -272.921476)
			(xy 360.884917 -272.89095) (xy 360.848194 -272.854227) (xy 360.817668 -272.812211) (xy 360.79409 -272.765937)
			(xy 360.778042 -272.716544) (xy 360.769917 -272.665249) (xy 360.490261 -272.665249) (xy 360.482136 -272.716544)
			(xy 360.466088 -272.765937) (xy 360.44251 -272.812211) (xy 360.411984 -272.854227) (xy 360.375261 -272.89095)
			(xy 360.333245 -272.921476) (xy 360.286971 -272.945054) (xy 360.237578 -272.961102) (xy 360.186283 -272.969227)
			(xy 360.134349 -272.969227) (xy 360.083054 -272.961102) (xy 360.033661 -272.945054) (xy 359.987387 -272.921476)
			(xy 359.945371 -272.89095) (xy 359.908648 -272.854227) (xy 359.878122 -272.812211) (xy 359.854544 -272.765937)
			(xy 359.838496 -272.716544) (xy 359.830371 -272.665249) (xy 359.550461 -272.665249) (xy 359.542336 -272.716544)
			(xy 359.526288 -272.765937) (xy 359.50271 -272.812211) (xy 359.472184 -272.854227) (xy 359.435461 -272.89095)
			(xy 359.393445 -272.921476) (xy 359.347171 -272.945054) (xy 359.297778 -272.961102) (xy 359.246483 -272.969227)
			(xy 359.194549 -272.969227) (xy 359.143254 -272.961102) (xy 359.093861 -272.945054) (xy 359.047587 -272.921476)
			(xy 359.005571 -272.89095) (xy 358.968848 -272.854227) (xy 358.938322 -272.812211) (xy 358.914744 -272.765937)
			(xy 358.898696 -272.716544) (xy 358.890571 -272.665249) (xy 358.610407 -272.665249) (xy 358.602282 -272.716544)
			(xy 358.586234 -272.765937) (xy 358.562656 -272.812211) (xy 358.53213 -272.854227) (xy 358.495407 -272.89095)
			(xy 358.453391 -272.921476) (xy 358.407117 -272.945054) (xy 358.357724 -272.961102) (xy 358.306429 -272.969227)
			(xy 358.254495 -272.969227) (xy 358.2032 -272.961102) (xy 358.153807 -272.945054) (xy 358.107533 -272.921476)
			(xy 358.065517 -272.89095) (xy 358.028794 -272.854227) (xy 357.998268 -272.812211) (xy 357.97469 -272.765937)
			(xy 357.958642 -272.716544) (xy 357.950517 -272.665249) (xy 357.670607 -272.665249) (xy 357.662482 -272.716544)
			(xy 357.646434 -272.765937) (xy 357.622856 -272.812211) (xy 357.59233 -272.854227) (xy 357.555607 -272.89095)
			(xy 357.513591 -272.921476) (xy 357.467317 -272.945054) (xy 357.417924 -272.961102) (xy 357.366629 -272.969227)
			(xy 357.314695 -272.969227) (xy 357.2634 -272.961102) (xy 357.214007 -272.945054) (xy 357.167733 -272.921476)
			(xy 357.125717 -272.89095) (xy 357.088994 -272.854227) (xy 357.058468 -272.812211) (xy 357.03489 -272.765937)
			(xy 357.018842 -272.716544) (xy 357.010717 -272.665249) (xy 356.730807 -272.665249) (xy 356.722682 -272.716544)
			(xy 356.706634 -272.765937) (xy 356.683056 -272.812211) (xy 356.65253 -272.854227) (xy 356.615807 -272.89095)
			(xy 356.573791 -272.921476) (xy 356.527517 -272.945054) (xy 356.478124 -272.961102) (xy 356.426829 -272.969227)
			(xy 356.374895 -272.969227) (xy 356.3236 -272.961102) (xy 356.274207 -272.945054) (xy 356.227933 -272.921476)
			(xy 356.185917 -272.89095) (xy 356.149194 -272.854227) (xy 356.118668 -272.812211) (xy 356.09509 -272.765937)
			(xy 356.079042 -272.716544) (xy 356.070917 -272.665249) (xy 355.791007 -272.665249) (xy 355.782882 -272.716544)
			(xy 355.766834 -272.765937) (xy 355.743256 -272.812211) (xy 355.71273 -272.854227) (xy 355.676007 -272.89095)
			(xy 355.633991 -272.921476) (xy 355.587717 -272.945054) (xy 355.538324 -272.961102) (xy 355.487029 -272.969227)
			(xy 355.435095 -272.969227) (xy 355.3838 -272.961102) (xy 355.334407 -272.945054) (xy 355.288133 -272.921476)
			(xy 355.246117 -272.89095) (xy 355.209394 -272.854227) (xy 355.178868 -272.812211) (xy 355.15529 -272.765937)
			(xy 355.139242 -272.716544) (xy 355.131117 -272.665249) (xy 354.851207 -272.665249) (xy 354.843082 -272.716544)
			(xy 354.827034 -272.765937) (xy 354.803456 -272.812211) (xy 354.77293 -272.854227) (xy 354.736207 -272.89095)
			(xy 354.694191 -272.921476) (xy 354.647917 -272.945054) (xy 354.598524 -272.961102) (xy 354.547229 -272.969227)
			(xy 354.495295 -272.969227) (xy 354.444 -272.961102) (xy 354.394607 -272.945054) (xy 354.348333 -272.921476)
			(xy 354.306317 -272.89095) (xy 354.269594 -272.854227) (xy 354.239068 -272.812211) (xy 354.21549 -272.765937)
			(xy 354.199442 -272.716544) (xy 354.191317 -272.665249) (xy 353.911407 -272.665249) (xy 353.903282 -272.716544)
			(xy 353.887234 -272.765937) (xy 353.863656 -272.812211) (xy 353.83313 -272.854227) (xy 353.796407 -272.89095)
			(xy 353.754391 -272.921476) (xy 353.708117 -272.945054) (xy 353.658724 -272.961102) (xy 353.607429 -272.969227)
			(xy 353.555495 -272.969227) (xy 353.5042 -272.961102) (xy 353.454807 -272.945054) (xy 353.408533 -272.921476)
			(xy 353.366517 -272.89095) (xy 353.329794 -272.854227) (xy 353.299268 -272.812211) (xy 353.27569 -272.765937)
			(xy 353.259642 -272.716544) (xy 353.251517 -272.665249) (xy 352.971607 -272.665249) (xy 352.963482 -272.716544)
			(xy 352.947434 -272.765937) (xy 352.923856 -272.812211) (xy 352.89333 -272.854227) (xy 352.856607 -272.89095)
			(xy 352.814591 -272.921476) (xy 352.768317 -272.945054) (xy 352.718924 -272.961102) (xy 352.667629 -272.969227)
			(xy 352.615695 -272.969227) (xy 352.5644 -272.961102) (xy 352.515007 -272.945054) (xy 352.468733 -272.921476)
			(xy 352.426717 -272.89095) (xy 352.389994 -272.854227) (xy 352.359468 -272.812211) (xy 352.33589 -272.765937)
			(xy 352.319842 -272.716544) (xy 352.311717 -272.665249) (xy 352.031807 -272.665249) (xy 352.023682 -272.716544)
			(xy 352.007634 -272.765937) (xy 351.984056 -272.812211) (xy 351.95353 -272.854227) (xy 351.916807 -272.89095)
			(xy 351.874791 -272.921476) (xy 351.828517 -272.945054) (xy 351.779124 -272.961102) (xy 351.727829 -272.969227)
			(xy 351.675895 -272.969227) (xy 351.6246 -272.961102) (xy 351.575207 -272.945054) (xy 351.528933 -272.921476)
			(xy 351.486917 -272.89095) (xy 351.450194 -272.854227) (xy 351.419668 -272.812211) (xy 351.39609 -272.765937)
			(xy 351.380042 -272.716544) (xy 351.371917 -272.665249) (xy 351.092007 -272.665249) (xy 351.083882 -272.716544)
			(xy 351.067834 -272.765937) (xy 351.044256 -272.812211) (xy 351.01373 -272.854227) (xy 350.977007 -272.89095)
			(xy 350.934991 -272.921476) (xy 350.888717 -272.945054) (xy 350.839324 -272.961102) (xy 350.788029 -272.969227)
			(xy 350.736095 -272.969227) (xy 350.6848 -272.961102) (xy 350.635407 -272.945054) (xy 350.589133 -272.921476)
			(xy 350.547117 -272.89095) (xy 350.510394 -272.854227) (xy 350.479868 -272.812211) (xy 350.45629 -272.765937)
			(xy 350.440242 -272.716544) (xy 350.432117 -272.665249) (xy 350.152207 -272.665249) (xy 350.144082 -272.716544)
			(xy 350.128034 -272.765937) (xy 350.104456 -272.812211) (xy 350.07393 -272.854227) (xy 350.037207 -272.89095)
			(xy 349.995191 -272.921476) (xy 349.948917 -272.945054) (xy 349.899524 -272.961102) (xy 349.848229 -272.969227)
			(xy 349.796295 -272.969227) (xy 349.745 -272.961102) (xy 349.695607 -272.945054) (xy 349.649333 -272.921476)
			(xy 349.607317 -272.89095) (xy 349.570594 -272.854227) (xy 349.540068 -272.812211) (xy 349.51649 -272.765937)
			(xy 349.500442 -272.716544) (xy 349.492317 -272.665249) (xy 349.212407 -272.665249) (xy 349.204282 -272.716544)
			(xy 349.188234 -272.765937) (xy 349.164656 -272.812211) (xy 349.13413 -272.854227) (xy 349.097407 -272.89095)
			(xy 349.055391 -272.921476) (xy 349.009117 -272.945054) (xy 348.959724 -272.961102) (xy 348.908429 -272.969227)
			(xy 348.856495 -272.969227) (xy 348.8052 -272.961102) (xy 348.755807 -272.945054) (xy 348.709533 -272.921476)
			(xy 348.667517 -272.89095) (xy 348.630794 -272.854227) (xy 348.600268 -272.812211) (xy 348.57669 -272.765937)
			(xy 348.560642 -272.716544) (xy 348.552517 -272.665249) (xy 348.272607 -272.665249) (xy 348.264482 -272.716544)
			(xy 348.248434 -272.765937) (xy 348.224856 -272.812211) (xy 348.19433 -272.854227) (xy 348.157607 -272.89095)
			(xy 348.115591 -272.921476) (xy 348.069317 -272.945054) (xy 348.019924 -272.961102) (xy 347.968629 -272.969227)
			(xy 347.916695 -272.969227) (xy 347.8654 -272.961102) (xy 347.816007 -272.945054) (xy 347.769733 -272.921476)
			(xy 347.727717 -272.89095) (xy 347.690994 -272.854227) (xy 347.660468 -272.812211) (xy 347.63689 -272.765937)
			(xy 347.620842 -272.716544) (xy 347.612717 -272.665249) (xy 347.332807 -272.665249) (xy 347.324682 -272.716544)
			(xy 347.308634 -272.765937) (xy 347.285056 -272.812211) (xy 347.25453 -272.854227) (xy 347.217807 -272.89095)
			(xy 347.175791 -272.921476) (xy 347.129517 -272.945054) (xy 347.080124 -272.961102) (xy 347.028829 -272.969227)
			(xy 346.976895 -272.969227) (xy 346.9256 -272.961102) (xy 346.876207 -272.945054) (xy 346.829933 -272.921476)
			(xy 346.787917 -272.89095) (xy 346.751194 -272.854227) (xy 346.720668 -272.812211) (xy 346.69709 -272.765937)
			(xy 346.681042 -272.716544) (xy 346.672917 -272.665249) (xy 346.393007 -272.665249) (xy 346.384882 -272.716544)
			(xy 346.368834 -272.765937) (xy 346.345256 -272.812211) (xy 346.31473 -272.854227) (xy 346.278007 -272.89095)
			(xy 346.235991 -272.921476) (xy 346.189717 -272.945054) (xy 346.140324 -272.961102) (xy 346.089029 -272.969227)
			(xy 346.037095 -272.969227) (xy 345.9858 -272.961102) (xy 345.936407 -272.945054) (xy 345.890133 -272.921476)
			(xy 345.848117 -272.89095) (xy 345.811394 -272.854227) (xy 345.780868 -272.812211) (xy 345.75729 -272.765937)
			(xy 345.741242 -272.716544) (xy 345.733117 -272.665249) (xy 345.453461 -272.665249) (xy 345.445336 -272.716544)
			(xy 345.429288 -272.765937) (xy 345.40571 -272.812211) (xy 345.375184 -272.854227) (xy 345.338461 -272.89095)
			(xy 345.296445 -272.921476) (xy 345.250171 -272.945054) (xy 345.200778 -272.961102) (xy 345.149483 -272.969227)
			(xy 345.097549 -272.969227) (xy 345.046254 -272.961102) (xy 344.996861 -272.945054) (xy 344.950587 -272.921476)
			(xy 344.908571 -272.89095) (xy 344.871848 -272.854227) (xy 344.841322 -272.812211) (xy 344.817744 -272.765937)
			(xy 344.801696 -272.716544) (xy 344.793571 -272.665249) (xy 344.513407 -272.665249) (xy 344.505282 -272.716544)
			(xy 344.489234 -272.765937) (xy 344.465656 -272.812211) (xy 344.43513 -272.854227) (xy 344.398407 -272.89095)
			(xy 344.356391 -272.921476) (xy 344.310117 -272.945054) (xy 344.260724 -272.961102) (xy 344.209429 -272.969227)
			(xy 344.157495 -272.969227) (xy 344.1062 -272.961102) (xy 344.056807 -272.945054) (xy 344.010533 -272.921476)
			(xy 343.968517 -272.89095) (xy 343.931794 -272.854227) (xy 343.901268 -272.812211) (xy 343.87769 -272.765937)
			(xy 343.861642 -272.716544) (xy 343.853517 -272.665249) (xy 343.573607 -272.665249) (xy 343.565482 -272.716544)
			(xy 343.549434 -272.765937) (xy 343.525856 -272.812211) (xy 343.49533 -272.854227) (xy 343.458607 -272.89095)
			(xy 343.416591 -272.921476) (xy 343.370317 -272.945054) (xy 343.320924 -272.961102) (xy 343.269629 -272.969227)
			(xy 343.217695 -272.969227) (xy 343.1664 -272.961102) (xy 343.117007 -272.945054) (xy 343.070733 -272.921476)
			(xy 343.028717 -272.89095) (xy 342.991994 -272.854227) (xy 342.961468 -272.812211) (xy 342.93789 -272.765937)
			(xy 342.921842 -272.716544) (xy 342.913717 -272.665249) (xy 342.633807 -272.665249) (xy 342.625682 -272.716544)
			(xy 342.609634 -272.765937) (xy 342.586056 -272.812211) (xy 342.55553 -272.854227) (xy 342.518807 -272.89095)
			(xy 342.476791 -272.921476) (xy 342.430517 -272.945054) (xy 342.381124 -272.961102) (xy 342.329829 -272.969227)
			(xy 342.277895 -272.969227) (xy 342.2266 -272.961102) (xy 342.177207 -272.945054) (xy 342.130933 -272.921476)
			(xy 342.088917 -272.89095) (xy 342.052194 -272.854227) (xy 342.021668 -272.812211) (xy 341.99809 -272.765937)
			(xy 341.982042 -272.716544) (xy 341.973917 -272.665249) (xy 341.694007 -272.665249) (xy 341.685882 -272.716544)
			(xy 341.669834 -272.765937) (xy 341.646256 -272.812211) (xy 341.61573 -272.854227) (xy 341.579007 -272.89095)
			(xy 341.536991 -272.921476) (xy 341.490717 -272.945054) (xy 341.441324 -272.961102) (xy 341.390029 -272.969227)
			(xy 341.338095 -272.969227) (xy 341.2868 -272.961102) (xy 341.237407 -272.945054) (xy 341.191133 -272.921476)
			(xy 341.149117 -272.89095) (xy 341.112394 -272.854227) (xy 341.081868 -272.812211) (xy 341.05829 -272.765937)
			(xy 341.042242 -272.716544) (xy 341.034117 -272.665249) (xy 340.754207 -272.665249) (xy 340.746082 -272.716544)
			(xy 340.730034 -272.765937) (xy 340.706456 -272.812211) (xy 340.67593 -272.854227) (xy 340.639207 -272.89095)
			(xy 340.597191 -272.921476) (xy 340.550917 -272.945054) (xy 340.501524 -272.961102) (xy 340.450229 -272.969227)
			(xy 340.398295 -272.969227) (xy 340.347 -272.961102) (xy 340.297607 -272.945054) (xy 340.251333 -272.921476)
			(xy 340.209317 -272.89095) (xy 340.172594 -272.854227) (xy 340.142068 -272.812211) (xy 340.11849 -272.765937)
			(xy 340.102442 -272.716544) (xy 340.094317 -272.665249) (xy 339.813762 -272.665249) (xy 339.811837 -272.690164)
			(xy 339.800136 -272.739829) (xy 339.780942 -272.787106) (xy 339.754711 -272.830872) (xy 339.722066 -272.870088)
			(xy 339.683784 -272.903821) (xy 339.662516 -272.91792) (xy 339.651848 -272.924778) (xy 339.627464 -272.96745)
			(xy 339.627464 -273.086576) (xy 339.627777 -273.094964) (xy 339.633272 -273.110814) (xy 339.643664 -273.123983)
			(xy 339.650578 -273.12874) (xy 339.718142 -273.166586) (xy 339.723391 -273.169076) (xy 339.734687 -273.171777)
			(xy 339.740494 -273.17192) (xy 339.76691 -273.17192) (xy 339.791294 -273.165316) (xy 339.795612 -273.16303)
			(xy 339.820105 -273.150262) (xy 339.872286 -273.13216) (xy 339.926747 -273.122962) (xy 339.954362 -273.12239)
			(xy 339.954616 -273.12239) (xy 339.980603 -273.122901) (xy 340.031935 -273.131033) (xy 340.081364 -273.147096)
			(xy 340.127672 -273.170693) (xy 340.169718 -273.201243) (xy 340.206467 -273.237994) (xy 340.237016 -273.280042)
			(xy 340.26061 -273.326351) (xy 340.27667 -273.37578) (xy 340.284801 -273.427113) (xy 340.284801 -273.479065)
			(xy 340.564471 -273.479065) (xy 340.564471 -273.427131) (xy 340.572596 -273.375836) (xy 340.588644 -273.326443)
			(xy 340.612222 -273.280169) (xy 340.642748 -273.238153) (xy 340.679471 -273.20143) (xy 340.721487 -273.170904)
			(xy 340.767761 -273.147326) (xy 340.817154 -273.131278) (xy 340.868449 -273.123153) (xy 340.920383 -273.123153)
			(xy 340.971678 -273.131278) (xy 341.021071 -273.147326) (xy 341.067345 -273.170904) (xy 341.109361 -273.20143)
			(xy 341.146084 -273.238153) (xy 341.17661 -273.280169) (xy 341.200188 -273.326443) (xy 341.216236 -273.375836)
			(xy 341.224361 -273.427131) (xy 341.22487 -273.453098) (xy 341.224361 -273.479065) (xy 341.504271 -273.479065)
			(xy 341.504271 -273.427131) (xy 341.512396 -273.375836) (xy 341.528444 -273.326443) (xy 341.552022 -273.280169)
			(xy 341.582548 -273.238153) (xy 341.619271 -273.20143) (xy 341.661287 -273.170904) (xy 341.707561 -273.147326)
			(xy 341.756954 -273.131278) (xy 341.808249 -273.123153) (xy 341.860183 -273.123153) (xy 341.911478 -273.131278)
			(xy 341.960871 -273.147326) (xy 342.007145 -273.170904) (xy 342.049161 -273.20143) (xy 342.085884 -273.238153)
			(xy 342.11641 -273.280169) (xy 342.139988 -273.326443) (xy 342.156036 -273.375836) (xy 342.164161 -273.427131)
			(xy 342.16467 -273.453098) (xy 342.164161 -273.479065) (xy 342.443817 -273.479065) (xy 342.443817 -273.427131)
			(xy 342.451942 -273.375836) (xy 342.46799 -273.326443) (xy 342.491568 -273.280169) (xy 342.522094 -273.238153)
			(xy 342.558817 -273.20143) (xy 342.600833 -273.170904) (xy 342.647107 -273.147326) (xy 342.6965 -273.131278)
			(xy 342.747795 -273.123153) (xy 342.799729 -273.123153) (xy 342.851024 -273.131278) (xy 342.900417 -273.147326)
			(xy 342.946691 -273.170904) (xy 342.988707 -273.20143) (xy 343.02543 -273.238153) (xy 343.055956 -273.280169)
			(xy 343.079534 -273.326443) (xy 343.095582 -273.375836) (xy 343.103707 -273.427131) (xy 343.104216 -273.453098)
			(xy 343.103707 -273.479065) (xy 343.383871 -273.479065) (xy 343.383871 -273.427131) (xy 343.391996 -273.375836)
			(xy 343.408044 -273.326443) (xy 343.431622 -273.280169) (xy 343.462148 -273.238153) (xy 343.498871 -273.20143)
			(xy 343.540887 -273.170904) (xy 343.587161 -273.147326) (xy 343.636554 -273.131278) (xy 343.687849 -273.123153)
			(xy 343.739783 -273.123153) (xy 343.791078 -273.131278) (xy 343.840471 -273.147326) (xy 343.886745 -273.170904)
			(xy 343.928761 -273.20143) (xy 343.965484 -273.238153) (xy 343.99601 -273.280169) (xy 344.019588 -273.326443)
			(xy 344.035636 -273.375836) (xy 344.043761 -273.427131) (xy 344.04427 -273.453098) (xy 344.043761 -273.479065)
			(xy 344.323671 -273.479065) (xy 344.323671 -273.427131) (xy 344.331796 -273.375836) (xy 344.347844 -273.326443)
			(xy 344.371422 -273.280169) (xy 344.401948 -273.238153) (xy 344.438671 -273.20143) (xy 344.480687 -273.170904)
			(xy 344.526961 -273.147326) (xy 344.576354 -273.131278) (xy 344.627649 -273.123153) (xy 344.679583 -273.123153)
			(xy 344.730878 -273.131278) (xy 344.780271 -273.147326) (xy 344.826545 -273.170904) (xy 344.868561 -273.20143)
			(xy 344.905284 -273.238153) (xy 344.93581 -273.280169) (xy 344.959388 -273.326443) (xy 344.975436 -273.375836)
			(xy 344.983561 -273.427131) (xy 344.98407 -273.453098) (xy 344.983561 -273.479065) (xy 345.263471 -273.479065)
			(xy 345.263471 -273.427131) (xy 345.271596 -273.375836) (xy 345.287644 -273.326443) (xy 345.311222 -273.280169)
			(xy 345.341748 -273.238153) (xy 345.378471 -273.20143) (xy 345.420487 -273.170904) (xy 345.466761 -273.147326)
			(xy 345.516154 -273.131278) (xy 345.567449 -273.123153) (xy 345.619383 -273.123153) (xy 345.670678 -273.131278)
			(xy 345.720071 -273.147326) (xy 345.766345 -273.170904) (xy 345.808361 -273.20143) (xy 345.845084 -273.238153)
			(xy 345.87561 -273.280169) (xy 345.899188 -273.326443) (xy 345.915236 -273.375836) (xy 345.923361 -273.427131)
			(xy 345.92387 -273.453098) (xy 345.923361 -273.479065) (xy 346.203271 -273.479065) (xy 346.203271 -273.427131)
			(xy 346.211396 -273.375836) (xy 346.227444 -273.326443) (xy 346.251022 -273.280169) (xy 346.281548 -273.238153)
			(xy 346.318271 -273.20143) (xy 346.360287 -273.170904) (xy 346.406561 -273.147326) (xy 346.455954 -273.131278)
			(xy 346.507249 -273.123153) (xy 346.559183 -273.123153) (xy 346.610478 -273.131278) (xy 346.659871 -273.147326)
			(xy 346.706145 -273.170904) (xy 346.748161 -273.20143) (xy 346.784884 -273.238153) (xy 346.81541 -273.280169)
			(xy 346.838988 -273.326443) (xy 346.855036 -273.375836) (xy 346.863161 -273.427131) (xy 346.86367 -273.453098)
			(xy 346.863161 -273.479065) (xy 347.143071 -273.479065) (xy 347.143071 -273.427131) (xy 347.151196 -273.375836)
			(xy 347.167244 -273.326443) (xy 347.190822 -273.280169) (xy 347.221348 -273.238153) (xy 347.258071 -273.20143)
			(xy 347.300087 -273.170904) (xy 347.346361 -273.147326) (xy 347.395754 -273.131278) (xy 347.447049 -273.123153)
			(xy 347.498983 -273.123153) (xy 347.550278 -273.131278) (xy 347.599671 -273.147326) (xy 347.645945 -273.170904)
			(xy 347.687961 -273.20143) (xy 347.724684 -273.238153) (xy 347.75521 -273.280169) (xy 347.778788 -273.326443)
			(xy 347.794836 -273.375836) (xy 347.802961 -273.427131) (xy 347.80347 -273.453098) (xy 347.802961 -273.479065)
			(xy 348.082871 -273.479065) (xy 348.082871 -273.427131) (xy 348.090996 -273.375836) (xy 348.107044 -273.326443)
			(xy 348.130622 -273.280169) (xy 348.161148 -273.238153) (xy 348.197871 -273.20143) (xy 348.239887 -273.170904)
			(xy 348.286161 -273.147326) (xy 348.335554 -273.131278) (xy 348.386849 -273.123153) (xy 348.438783 -273.123153)
			(xy 348.490078 -273.131278) (xy 348.539471 -273.147326) (xy 348.585745 -273.170904) (xy 348.627761 -273.20143)
			(xy 348.664484 -273.238153) (xy 348.69501 -273.280169) (xy 348.718588 -273.326443) (xy 348.734636 -273.375836)
			(xy 348.742761 -273.427131) (xy 348.74327 -273.453098) (xy 348.742761 -273.479065) (xy 349.022417 -273.479065)
			(xy 349.022417 -273.427131) (xy 349.030542 -273.375836) (xy 349.04659 -273.326443) (xy 349.070168 -273.280169)
			(xy 349.100694 -273.238153) (xy 349.137417 -273.20143) (xy 349.179433 -273.170904) (xy 349.225707 -273.147326)
			(xy 349.2751 -273.131278) (xy 349.326395 -273.123153) (xy 349.378329 -273.123153) (xy 349.429624 -273.131278)
			(xy 349.479017 -273.147326) (xy 349.525291 -273.170904) (xy 349.567307 -273.20143) (xy 349.60403 -273.238153)
			(xy 349.634556 -273.280169) (xy 349.658134 -273.326443) (xy 349.674182 -273.375836) (xy 349.682307 -273.427131)
			(xy 349.682816 -273.453098) (xy 349.682307 -273.479065) (xy 349.962471 -273.479065) (xy 349.962471 -273.427131)
			(xy 349.970596 -273.375836) (xy 349.986644 -273.326443) (xy 350.010222 -273.280169) (xy 350.040748 -273.238153)
			(xy 350.077471 -273.20143) (xy 350.119487 -273.170904) (xy 350.165761 -273.147326) (xy 350.215154 -273.131278)
			(xy 350.266449 -273.123153) (xy 350.318383 -273.123153) (xy 350.369678 -273.131278) (xy 350.419071 -273.147326)
			(xy 350.465345 -273.170904) (xy 350.507361 -273.20143) (xy 350.544084 -273.238153) (xy 350.57461 -273.280169)
			(xy 350.598188 -273.326443) (xy 350.614236 -273.375836) (xy 350.622361 -273.427131) (xy 350.62287 -273.453098)
			(xy 350.622361 -273.479065) (xy 350.902017 -273.479065) (xy 350.902017 -273.427131) (xy 350.910142 -273.375836)
			(xy 350.92619 -273.326443) (xy 350.949768 -273.280169) (xy 350.980294 -273.238153) (xy 351.017017 -273.20143)
			(xy 351.059033 -273.170904) (xy 351.105307 -273.147326) (xy 351.1547 -273.131278) (xy 351.205995 -273.123153)
			(xy 351.257929 -273.123153) (xy 351.309224 -273.131278) (xy 351.358617 -273.147326) (xy 351.404891 -273.170904)
			(xy 351.446907 -273.20143) (xy 351.48363 -273.238153) (xy 351.514156 -273.280169) (xy 351.537734 -273.326443)
			(xy 351.553782 -273.375836) (xy 351.561907 -273.427131) (xy 351.562416 -273.453098) (xy 351.561907 -273.479065)
			(xy 351.842071 -273.479065) (xy 351.842071 -273.427131) (xy 351.850196 -273.375836) (xy 351.866244 -273.326443)
			(xy 351.889822 -273.280169) (xy 351.920348 -273.238153) (xy 351.957071 -273.20143) (xy 351.999087 -273.170904)
			(xy 352.045361 -273.147326) (xy 352.094754 -273.131278) (xy 352.146049 -273.123153) (xy 352.197983 -273.123153)
			(xy 352.249278 -273.131278) (xy 352.298671 -273.147326) (xy 352.344945 -273.170904) (xy 352.386961 -273.20143)
			(xy 352.423684 -273.238153) (xy 352.45421 -273.280169) (xy 352.477788 -273.326443) (xy 352.493836 -273.375836)
			(xy 352.501961 -273.427131) (xy 352.50247 -273.453098) (xy 352.501961 -273.479065) (xy 353.721671 -273.479065)
			(xy 353.721671 -273.427131) (xy 353.729796 -273.375836) (xy 353.745844 -273.326443) (xy 353.769422 -273.280169)
			(xy 353.799948 -273.238153) (xy 353.836671 -273.20143) (xy 353.878687 -273.170904) (xy 353.924961 -273.147326)
			(xy 353.974354 -273.131278) (xy 354.025649 -273.123153) (xy 354.077583 -273.123153) (xy 354.128878 -273.131278)
			(xy 354.178271 -273.147326) (xy 354.224545 -273.170904) (xy 354.266561 -273.20143) (xy 354.303284 -273.238153)
			(xy 354.33381 -273.280169) (xy 354.357388 -273.326443) (xy 354.373436 -273.375836) (xy 354.381561 -273.427131)
			(xy 354.38207 -273.453098) (xy 354.381561 -273.479065) (xy 354.661471 -273.479065) (xy 354.661471 -273.427131)
			(xy 354.669596 -273.375836) (xy 354.685644 -273.326443) (xy 354.709222 -273.280169) (xy 354.739748 -273.238153)
			(xy 354.776471 -273.20143) (xy 354.818487 -273.170904) (xy 354.864761 -273.147326) (xy 354.914154 -273.131278)
			(xy 354.965449 -273.123153) (xy 355.017383 -273.123153) (xy 355.068678 -273.131278) (xy 355.118071 -273.147326)
			(xy 355.164345 -273.170904) (xy 355.206361 -273.20143) (xy 355.243084 -273.238153) (xy 355.27361 -273.280169)
			(xy 355.297188 -273.326443) (xy 355.313236 -273.375836) (xy 355.321361 -273.427131) (xy 355.32187 -273.453098)
			(xy 355.321361 -273.479065) (xy 355.601271 -273.479065) (xy 355.601271 -273.427131) (xy 355.609396 -273.375836)
			(xy 355.625444 -273.326443) (xy 355.649022 -273.280169) (xy 355.679548 -273.238153) (xy 355.716271 -273.20143)
			(xy 355.758287 -273.170904) (xy 355.804561 -273.147326) (xy 355.853954 -273.131278) (xy 355.905249 -273.123153)
			(xy 355.957183 -273.123153) (xy 356.008478 -273.131278) (xy 356.057871 -273.147326) (xy 356.104145 -273.170904)
			(xy 356.146161 -273.20143) (xy 356.182884 -273.238153) (xy 356.21341 -273.280169) (xy 356.236988 -273.326443)
			(xy 356.253036 -273.375836) (xy 356.261161 -273.427131) (xy 356.26167 -273.453098) (xy 356.540308 -273.453098)
			(xy 356.540817 -273.427131) (xy 356.548942 -273.375836) (xy 356.56499 -273.326443) (xy 356.588568 -273.280169)
			(xy 356.619094 -273.238153) (xy 356.655817 -273.20143) (xy 356.697833 -273.170904) (xy 356.744107 -273.147326)
			(xy 356.7935 -273.131278) (xy 356.844795 -273.123153) (xy 356.896729 -273.123153) (xy 356.948024 -273.131278)
			(xy 356.997417 -273.147326) (xy 357.043691 -273.170904) (xy 357.085707 -273.20143) (xy 357.12243 -273.238153)
			(xy 357.152956 -273.280169) (xy 357.176534 -273.326443) (xy 357.192582 -273.375836) (xy 357.200707 -273.427131)
			(xy 357.201216 -273.453098) (xy 357.200623 -273.479065) (xy 357.480617 -273.479065) (xy 357.480617 -273.427131)
			(xy 357.488742 -273.375836) (xy 357.50479 -273.326443) (xy 357.528368 -273.280169) (xy 357.558894 -273.238153)
			(xy 357.595617 -273.20143) (xy 357.637633 -273.170904) (xy 357.683907 -273.147326) (xy 357.7333 -273.131278)
			(xy 357.784595 -273.123153) (xy 357.836529 -273.123153) (xy 357.887824 -273.131278) (xy 357.937217 -273.147326)
			(xy 357.983491 -273.170904) (xy 358.025507 -273.20143) (xy 358.06223 -273.238153) (xy 358.092756 -273.280169)
			(xy 358.116334 -273.326443) (xy 358.132382 -273.375836) (xy 358.140507 -273.427131) (xy 358.141016 -273.453098)
			(xy 358.140507 -273.479065) (xy 358.420671 -273.479065) (xy 358.420671 -273.427131) (xy 358.428796 -273.375836)
			(xy 358.444844 -273.326443) (xy 358.468422 -273.280169) (xy 358.498948 -273.238153) (xy 358.535671 -273.20143)
			(xy 358.577687 -273.170904) (xy 358.623961 -273.147326) (xy 358.673354 -273.131278) (xy 358.724649 -273.123153)
			(xy 358.776583 -273.123153) (xy 358.827878 -273.131278) (xy 358.877271 -273.147326) (xy 358.923545 -273.170904)
			(xy 358.965561 -273.20143) (xy 359.002284 -273.238153) (xy 359.03281 -273.280169) (xy 359.056388 -273.326443)
			(xy 359.072436 -273.375836) (xy 359.080561 -273.427131) (xy 359.08107 -273.453098) (xy 359.080561 -273.479065)
			(xy 359.360217 -273.479065) (xy 359.360217 -273.427131) (xy 359.368342 -273.375836) (xy 359.38439 -273.326443)
			(xy 359.407968 -273.280169) (xy 359.438494 -273.238153) (xy 359.475217 -273.20143) (xy 359.517233 -273.170904)
			(xy 359.563507 -273.147326) (xy 359.6129 -273.131278) (xy 359.664195 -273.123153) (xy 359.716129 -273.123153)
			(xy 359.767424 -273.131278) (xy 359.816817 -273.147326) (xy 359.863091 -273.170904) (xy 359.905107 -273.20143)
			(xy 359.94183 -273.238153) (xy 359.972356 -273.280169) (xy 359.995934 -273.326443) (xy 360.011982 -273.375836)
			(xy 360.020107 -273.427131) (xy 360.020616 -273.453098) (xy 360.020107 -273.479065) (xy 360.300017 -273.479065)
			(xy 360.300017 -273.427131) (xy 360.308142 -273.375836) (xy 360.32419 -273.326443) (xy 360.347768 -273.280169)
			(xy 360.378294 -273.238153) (xy 360.415017 -273.20143) (xy 360.457033 -273.170904) (xy 360.503307 -273.147326)
			(xy 360.5527 -273.131278) (xy 360.603995 -273.123153) (xy 360.655929 -273.123153) (xy 360.707224 -273.131278)
			(xy 360.756617 -273.147326) (xy 360.802891 -273.170904) (xy 360.844907 -273.20143) (xy 360.88163 -273.238153)
			(xy 360.912156 -273.280169) (xy 360.935734 -273.326443) (xy 360.951782 -273.375836) (xy 360.959907 -273.427131)
			(xy 360.960416 -273.453098) (xy 360.959907 -273.479065) (xy 361.239817 -273.479065) (xy 361.239817 -273.427131)
			(xy 361.247942 -273.375836) (xy 361.26399 -273.326443) (xy 361.287568 -273.280169) (xy 361.318094 -273.238153)
			(xy 361.354817 -273.20143) (xy 361.396833 -273.170904) (xy 361.443107 -273.147326) (xy 361.4925 -273.131278)
			(xy 361.543795 -273.123153) (xy 361.595729 -273.123153) (xy 361.647024 -273.131278) (xy 361.696417 -273.147326)
			(xy 361.742691 -273.170904) (xy 361.784707 -273.20143) (xy 361.82143 -273.238153) (xy 361.851956 -273.280169)
			(xy 361.875534 -273.326443) (xy 361.891582 -273.375836) (xy 361.899707 -273.427131) (xy 361.900216 -273.453098)
			(xy 361.899707 -273.479065) (xy 362.179617 -273.479065) (xy 362.179617 -273.427131) (xy 362.187742 -273.375836)
			(xy 362.20379 -273.326443) (xy 362.227368 -273.280169) (xy 362.257894 -273.238153) (xy 362.294617 -273.20143)
			(xy 362.336633 -273.170904) (xy 362.382907 -273.147326) (xy 362.4323 -273.131278) (xy 362.483595 -273.123153)
			(xy 362.535529 -273.123153) (xy 362.586824 -273.131278) (xy 362.636217 -273.147326) (xy 362.682491 -273.170904)
			(xy 362.724507 -273.20143) (xy 362.76123 -273.238153) (xy 362.791756 -273.280169) (xy 362.815334 -273.326443)
			(xy 362.831382 -273.375836) (xy 362.839507 -273.427131) (xy 362.840016 -273.453098) (xy 362.839507 -273.479065)
			(xy 363.119417 -273.479065) (xy 363.119417 -273.427131) (xy 363.127542 -273.375836) (xy 363.14359 -273.326443)
			(xy 363.167168 -273.280169) (xy 363.197694 -273.238153) (xy 363.234417 -273.20143) (xy 363.276433 -273.170904)
			(xy 363.322707 -273.147326) (xy 363.3721 -273.131278) (xy 363.423395 -273.123153) (xy 363.475329 -273.123153)
			(xy 363.526624 -273.131278) (xy 363.576017 -273.147326) (xy 363.622291 -273.170904) (xy 363.664307 -273.20143)
			(xy 363.70103 -273.238153) (xy 363.731556 -273.280169) (xy 363.755134 -273.326443) (xy 363.771182 -273.375836)
			(xy 363.779307 -273.427131) (xy 363.779816 -273.453098) (xy 363.779307 -273.479065) (xy 364.059471 -273.479065)
			(xy 364.059471 -273.427131) (xy 364.067596 -273.375836) (xy 364.083644 -273.326443) (xy 364.107222 -273.280169)
			(xy 364.137748 -273.238153) (xy 364.174471 -273.20143) (xy 364.216487 -273.170904) (xy 364.262761 -273.147326)
			(xy 364.312154 -273.131278) (xy 364.363449 -273.123153) (xy 364.415383 -273.123153) (xy 364.466678 -273.131278)
			(xy 364.516071 -273.147326) (xy 364.562345 -273.170904) (xy 364.604361 -273.20143) (xy 364.641084 -273.238153)
			(xy 364.67161 -273.280169) (xy 364.695188 -273.326443) (xy 364.711236 -273.375836) (xy 364.719361 -273.427131)
			(xy 364.71987 -273.453098) (xy 364.719361 -273.479065) (xy 364.999271 -273.479065) (xy 364.999271 -273.427131)
			(xy 365.007396 -273.375836) (xy 365.023444 -273.326443) (xy 365.047022 -273.280169) (xy 365.077548 -273.238153)
			(xy 365.114271 -273.20143) (xy 365.156287 -273.170904) (xy 365.202561 -273.147326) (xy 365.251954 -273.131278)
			(xy 365.303249 -273.123153) (xy 365.355183 -273.123153) (xy 365.406478 -273.131278) (xy 365.455871 -273.147326)
			(xy 365.502145 -273.170904) (xy 365.544161 -273.20143) (xy 365.580884 -273.238153) (xy 365.61141 -273.280169)
			(xy 365.634988 -273.326443) (xy 365.651036 -273.375836) (xy 365.659161 -273.427131) (xy 365.65967 -273.453098)
			(xy 365.659161 -273.479065) (xy 365.939071 -273.479065) (xy 365.939071 -273.427131) (xy 365.947196 -273.375836)
			(xy 365.963244 -273.326443) (xy 365.986822 -273.280169) (xy 366.017348 -273.238153) (xy 366.054071 -273.20143)
			(xy 366.096087 -273.170904) (xy 366.142361 -273.147326) (xy 366.191754 -273.131278) (xy 366.243049 -273.123153)
			(xy 366.294983 -273.123153) (xy 366.346278 -273.131278) (xy 366.395671 -273.147326) (xy 366.441945 -273.170904)
			(xy 366.483961 -273.20143) (xy 366.520684 -273.238153) (xy 366.55121 -273.280169) (xy 366.574788 -273.326443)
			(xy 366.590836 -273.375836) (xy 366.598961 -273.427131) (xy 366.59947 -273.453098) (xy 366.598961 -273.479065)
			(xy 366.878871 -273.479065) (xy 366.878871 -273.427131) (xy 366.886996 -273.375836) (xy 366.903044 -273.326443)
			(xy 366.926622 -273.280169) (xy 366.957148 -273.238153) (xy 366.993871 -273.20143) (xy 367.035887 -273.170904)
			(xy 367.082161 -273.147326) (xy 367.131554 -273.131278) (xy 367.182849 -273.123153) (xy 367.234783 -273.123153)
			(xy 367.286078 -273.131278) (xy 367.335471 -273.147326) (xy 367.381745 -273.170904) (xy 367.423761 -273.20143)
			(xy 367.460484 -273.238153) (xy 367.49101 -273.280169) (xy 367.514588 -273.326443) (xy 367.530636 -273.375836)
			(xy 367.538761 -273.427131) (xy 367.53927 -273.453098) (xy 367.538761 -273.479065) (xy 367.818671 -273.479065)
			(xy 367.818671 -273.427131) (xy 367.826796 -273.375836) (xy 367.842844 -273.326443) (xy 367.866422 -273.280169)
			(xy 367.896948 -273.238153) (xy 367.933671 -273.20143) (xy 367.975687 -273.170904) (xy 368.021961 -273.147326)
			(xy 368.071354 -273.131278) (xy 368.122649 -273.123153) (xy 368.174583 -273.123153) (xy 368.225878 -273.131278)
			(xy 368.275271 -273.147326) (xy 368.321545 -273.170904) (xy 368.363561 -273.20143) (xy 368.400284 -273.238153)
			(xy 368.43081 -273.280169) (xy 368.454388 -273.326443) (xy 368.470436 -273.375836) (xy 368.478561 -273.427131)
			(xy 368.47907 -273.453098) (xy 368.478561 -273.479065) (xy 368.758471 -273.479065) (xy 368.758471 -273.427131)
			(xy 368.766596 -273.375836) (xy 368.782644 -273.326443) (xy 368.806222 -273.280169) (xy 368.836748 -273.238153)
			(xy 368.873471 -273.20143) (xy 368.915487 -273.170904) (xy 368.961761 -273.147326) (xy 369.011154 -273.131278)
			(xy 369.062449 -273.123153) (xy 369.114383 -273.123153) (xy 369.165678 -273.131278) (xy 369.215071 -273.147326)
			(xy 369.261345 -273.170904) (xy 369.303361 -273.20143) (xy 369.340084 -273.238153) (xy 369.37061 -273.280169)
			(xy 369.394188 -273.326443) (xy 369.410236 -273.375836) (xy 369.418361 -273.427131) (xy 369.41887 -273.453098)
			(xy 369.418361 -273.479065) (xy 369.698271 -273.479065) (xy 369.698271 -273.427131) (xy 369.706396 -273.375836)
			(xy 369.722444 -273.326443) (xy 369.746022 -273.280169) (xy 369.776548 -273.238153) (xy 369.813271 -273.20143)
			(xy 369.855287 -273.170904) (xy 369.901561 -273.147326) (xy 369.950954 -273.131278) (xy 370.002249 -273.123153)
			(xy 370.054183 -273.123153) (xy 370.105478 -273.131278) (xy 370.154871 -273.147326) (xy 370.201145 -273.170904)
			(xy 370.243161 -273.20143) (xy 370.279884 -273.238153) (xy 370.31041 -273.280169) (xy 370.333988 -273.326443)
			(xy 370.350036 -273.375836) (xy 370.358161 -273.427131) (xy 370.35867 -273.453098) (xy 370.358161 -273.479065)
			(xy 370.637817 -273.479065) (xy 370.637817 -273.427131) (xy 370.645942 -273.375836) (xy 370.66199 -273.326443)
			(xy 370.685568 -273.280169) (xy 370.716094 -273.238153) (xy 370.752817 -273.20143) (xy 370.794833 -273.170904)
			(xy 370.841107 -273.147326) (xy 370.8905 -273.131278) (xy 370.941795 -273.123153) (xy 370.993729 -273.123153)
			(xy 371.045024 -273.131278) (xy 371.094417 -273.147326) (xy 371.140691 -273.170904) (xy 371.182707 -273.20143)
			(xy 371.21943 -273.238153) (xy 371.249956 -273.280169) (xy 371.273534 -273.326443) (xy 371.289582 -273.375836)
			(xy 371.297707 -273.427131) (xy 371.298216 -273.453098) (xy 371.297707 -273.479065) (xy 371.577871 -273.479065)
			(xy 371.577871 -273.427131) (xy 371.585996 -273.375836) (xy 371.602044 -273.326443) (xy 371.625622 -273.280169)
			(xy 371.656148 -273.238153) (xy 371.692871 -273.20143) (xy 371.734887 -273.170904) (xy 371.781161 -273.147326)
			(xy 371.830554 -273.131278) (xy 371.881849 -273.123153) (xy 371.933783 -273.123153) (xy 371.985078 -273.131278)
			(xy 372.034471 -273.147326) (xy 372.080745 -273.170904) (xy 372.122761 -273.20143) (xy 372.159484 -273.238153)
			(xy 372.19001 -273.280169) (xy 372.213588 -273.326443) (xy 372.229636 -273.375836) (xy 372.237761 -273.427131)
			(xy 372.23827 -273.453098) (xy 372.237761 -273.479065) (xy 372.517671 -273.479065) (xy 372.517671 -273.427131)
			(xy 372.525796 -273.375836) (xy 372.541844 -273.326443) (xy 372.565422 -273.280169) (xy 372.595948 -273.238153)
			(xy 372.632671 -273.20143) (xy 372.674687 -273.170904) (xy 372.720961 -273.147326) (xy 372.770354 -273.131278)
			(xy 372.821649 -273.123153) (xy 372.873583 -273.123153) (xy 372.924878 -273.131278) (xy 372.974271 -273.147326)
			(xy 373.020545 -273.170904) (xy 373.062561 -273.20143) (xy 373.099284 -273.238153) (xy 373.12981 -273.280169)
			(xy 373.153388 -273.326443) (xy 373.169436 -273.375836) (xy 373.177561 -273.427131) (xy 373.17807 -273.453098)
			(xy 373.177561 -273.479065) (xy 373.457471 -273.479065) (xy 373.457471 -273.427131) (xy 373.465596 -273.375836)
			(xy 373.481644 -273.326443) (xy 373.505222 -273.280169) (xy 373.535748 -273.238153) (xy 373.572471 -273.20143)
			(xy 373.614487 -273.170904) (xy 373.660761 -273.147326) (xy 373.710154 -273.131278) (xy 373.761449 -273.123153)
			(xy 373.813383 -273.123153) (xy 373.864678 -273.131278) (xy 373.914071 -273.147326) (xy 373.960345 -273.170904)
			(xy 374.002361 -273.20143) (xy 374.039084 -273.238153) (xy 374.06961 -273.280169) (xy 374.093188 -273.326443)
			(xy 374.109236 -273.375836) (xy 374.117361 -273.427131) (xy 374.11787 -273.453098) (xy 374.117361 -273.479065)
			(xy 374.397271 -273.479065) (xy 374.397271 -273.427131) (xy 374.405396 -273.375836) (xy 374.421444 -273.326443)
			(xy 374.445022 -273.280169) (xy 374.475548 -273.238153) (xy 374.512271 -273.20143) (xy 374.554287 -273.170904)
			(xy 374.600561 -273.147326) (xy 374.649954 -273.131278) (xy 374.701249 -273.123153) (xy 374.753183 -273.123153)
			(xy 374.804478 -273.131278) (xy 374.853871 -273.147326) (xy 374.900145 -273.170904) (xy 374.942161 -273.20143)
			(xy 374.978884 -273.238153) (xy 375.00941 -273.280169) (xy 375.032988 -273.326443) (xy 375.049036 -273.375836)
			(xy 375.057161 -273.427131) (xy 375.05767 -273.453098) (xy 375.057161 -273.479065) (xy 375.337071 -273.479065)
			(xy 375.337071 -273.427131) (xy 375.345196 -273.375836) (xy 375.361244 -273.326443) (xy 375.384822 -273.280169)
			(xy 375.415348 -273.238153) (xy 375.452071 -273.20143) (xy 375.494087 -273.170904) (xy 375.540361 -273.147326)
			(xy 375.589754 -273.131278) (xy 375.641049 -273.123153) (xy 375.692983 -273.123153) (xy 375.744278 -273.131278)
			(xy 375.793671 -273.147326) (xy 375.839945 -273.170904) (xy 375.881961 -273.20143) (xy 375.918684 -273.238153)
			(xy 375.94921 -273.280169) (xy 375.972788 -273.326443) (xy 375.988836 -273.375836) (xy 375.996961 -273.427131)
			(xy 375.99747 -273.453098) (xy 375.996961 -273.479065) (xy 376.276871 -273.479065) (xy 376.276871 -273.427131)
			(xy 376.284996 -273.375836) (xy 376.301044 -273.326443) (xy 376.324622 -273.280169) (xy 376.355148 -273.238153)
			(xy 376.391871 -273.20143) (xy 376.433887 -273.170904) (xy 376.480161 -273.147326) (xy 376.529554 -273.131278)
			(xy 376.580849 -273.123153) (xy 376.632783 -273.123153) (xy 376.684078 -273.131278) (xy 376.733471 -273.147326)
			(xy 376.779745 -273.170904) (xy 376.821761 -273.20143) (xy 376.858484 -273.238153) (xy 376.88901 -273.280169)
			(xy 376.912588 -273.326443) (xy 376.928636 -273.375836) (xy 376.936761 -273.427131) (xy 376.93727 -273.453098)
			(xy 376.936761 -273.479065) (xy 377.216671 -273.479065) (xy 377.216671 -273.427131) (xy 377.224796 -273.375836)
			(xy 377.240844 -273.326443) (xy 377.264422 -273.280169) (xy 377.294948 -273.238153) (xy 377.331671 -273.20143)
			(xy 377.373687 -273.170904) (xy 377.419961 -273.147326) (xy 377.469354 -273.131278) (xy 377.520649 -273.123153)
			(xy 377.572583 -273.123153) (xy 377.623878 -273.131278) (xy 377.673271 -273.147326) (xy 377.719545 -273.170904)
			(xy 377.761561 -273.20143) (xy 377.798284 -273.238153) (xy 377.82881 -273.280169) (xy 377.852388 -273.326443)
			(xy 377.868436 -273.375836) (xy 377.876561 -273.427131) (xy 377.87707 -273.453098) (xy 377.876561 -273.479065)
			(xy 378.156471 -273.479065) (xy 378.156471 -273.427131) (xy 378.164596 -273.375836) (xy 378.180644 -273.326443)
			(xy 378.204222 -273.280169) (xy 378.234748 -273.238153) (xy 378.271471 -273.20143) (xy 378.313487 -273.170904)
			(xy 378.359761 -273.147326) (xy 378.409154 -273.131278) (xy 378.460449 -273.123153) (xy 378.512383 -273.123153)
			(xy 378.563678 -273.131278) (xy 378.613071 -273.147326) (xy 378.659345 -273.170904) (xy 378.701361 -273.20143)
			(xy 378.738084 -273.238153) (xy 378.76861 -273.280169) (xy 378.792188 -273.326443) (xy 378.808236 -273.375836)
			(xy 378.816361 -273.427131) (xy 378.81687 -273.453098) (xy 378.816361 -273.479065) (xy 378.808236 -273.53036)
			(xy 378.792188 -273.579753) (xy 378.76861 -273.626027) (xy 378.738084 -273.668043) (xy 378.701361 -273.704766)
			(xy 378.659345 -273.735292) (xy 378.613071 -273.75887) (xy 378.563678 -273.774918) (xy 378.512383 -273.783043)
			(xy 378.460449 -273.783043) (xy 378.409154 -273.774918) (xy 378.359761 -273.75887) (xy 378.313487 -273.735292)
			(xy 378.271471 -273.704766) (xy 378.234748 -273.668043) (xy 378.204222 -273.626027) (xy 378.180644 -273.579753)
			(xy 378.164596 -273.53036) (xy 378.156471 -273.479065) (xy 377.876561 -273.479065) (xy 377.868436 -273.53036)
			(xy 377.852388 -273.579753) (xy 377.82881 -273.626027) (xy 377.798284 -273.668043) (xy 377.761561 -273.704766)
			(xy 377.719545 -273.735292) (xy 377.673271 -273.75887) (xy 377.623878 -273.774918) (xy 377.572583 -273.783043)
			(xy 377.520649 -273.783043) (xy 377.469354 -273.774918) (xy 377.419961 -273.75887) (xy 377.373687 -273.735292)
			(xy 377.331671 -273.704766) (xy 377.294948 -273.668043) (xy 377.264422 -273.626027) (xy 377.240844 -273.579753)
			(xy 377.224796 -273.53036) (xy 377.216671 -273.479065) (xy 376.936761 -273.479065) (xy 376.928636 -273.53036)
			(xy 376.912588 -273.579753) (xy 376.88901 -273.626027) (xy 376.858484 -273.668043) (xy 376.821761 -273.704766)
			(xy 376.779745 -273.735292) (xy 376.733471 -273.75887) (xy 376.684078 -273.774918) (xy 376.632783 -273.783043)
			(xy 376.580849 -273.783043) (xy 376.529554 -273.774918) (xy 376.480161 -273.75887) (xy 376.433887 -273.735292)
			(xy 376.391871 -273.704766) (xy 376.355148 -273.668043) (xy 376.324622 -273.626027) (xy 376.301044 -273.579753)
			(xy 376.284996 -273.53036) (xy 376.276871 -273.479065) (xy 375.996961 -273.479065) (xy 375.988836 -273.53036)
			(xy 375.972788 -273.579753) (xy 375.94921 -273.626027) (xy 375.918684 -273.668043) (xy 375.881961 -273.704766)
			(xy 375.839945 -273.735292) (xy 375.793671 -273.75887) (xy 375.744278 -273.774918) (xy 375.692983 -273.783043)
			(xy 375.641049 -273.783043) (xy 375.589754 -273.774918) (xy 375.540361 -273.75887) (xy 375.494087 -273.735292)
			(xy 375.452071 -273.704766) (xy 375.415348 -273.668043) (xy 375.384822 -273.626027) (xy 375.361244 -273.579753)
			(xy 375.345196 -273.53036) (xy 375.337071 -273.479065) (xy 375.057161 -273.479065) (xy 375.049036 -273.53036)
			(xy 375.032988 -273.579753) (xy 375.00941 -273.626027) (xy 374.978884 -273.668043) (xy 374.942161 -273.704766)
			(xy 374.900145 -273.735292) (xy 374.853871 -273.75887) (xy 374.804478 -273.774918) (xy 374.753183 -273.783043)
			(xy 374.701249 -273.783043) (xy 374.649954 -273.774918) (xy 374.600561 -273.75887) (xy 374.554287 -273.735292)
			(xy 374.512271 -273.704766) (xy 374.475548 -273.668043) (xy 374.445022 -273.626027) (xy 374.421444 -273.579753)
			(xy 374.405396 -273.53036) (xy 374.397271 -273.479065) (xy 374.117361 -273.479065) (xy 374.109236 -273.53036)
			(xy 374.093188 -273.579753) (xy 374.06961 -273.626027) (xy 374.039084 -273.668043) (xy 374.002361 -273.704766)
			(xy 373.960345 -273.735292) (xy 373.914071 -273.75887) (xy 373.864678 -273.774918) (xy 373.813383 -273.783043)
			(xy 373.761449 -273.783043) (xy 373.710154 -273.774918) (xy 373.660761 -273.75887) (xy 373.614487 -273.735292)
			(xy 373.572471 -273.704766) (xy 373.535748 -273.668043) (xy 373.505222 -273.626027) (xy 373.481644 -273.579753)
			(xy 373.465596 -273.53036) (xy 373.457471 -273.479065) (xy 373.177561 -273.479065) (xy 373.169436 -273.53036)
			(xy 373.153388 -273.579753) (xy 373.12981 -273.626027) (xy 373.099284 -273.668043) (xy 373.062561 -273.704766)
			(xy 373.020545 -273.735292) (xy 372.974271 -273.75887) (xy 372.924878 -273.774918) (xy 372.873583 -273.783043)
			(xy 372.821649 -273.783043) (xy 372.770354 -273.774918) (xy 372.720961 -273.75887) (xy 372.674687 -273.735292)
			(xy 372.632671 -273.704766) (xy 372.595948 -273.668043) (xy 372.565422 -273.626027) (xy 372.541844 -273.579753)
			(xy 372.525796 -273.53036) (xy 372.517671 -273.479065) (xy 372.237761 -273.479065) (xy 372.229636 -273.53036)
			(xy 372.213588 -273.579753) (xy 372.19001 -273.626027) (xy 372.159484 -273.668043) (xy 372.122761 -273.704766)
			(xy 372.080745 -273.735292) (xy 372.034471 -273.75887) (xy 371.985078 -273.774918) (xy 371.933783 -273.783043)
			(xy 371.881849 -273.783043) (xy 371.830554 -273.774918) (xy 371.781161 -273.75887) (xy 371.734887 -273.735292)
			(xy 371.692871 -273.704766) (xy 371.656148 -273.668043) (xy 371.625622 -273.626027) (xy 371.602044 -273.579753)
			(xy 371.585996 -273.53036) (xy 371.577871 -273.479065) (xy 371.297707 -273.479065) (xy 371.289582 -273.53036)
			(xy 371.273534 -273.579753) (xy 371.249956 -273.626027) (xy 371.21943 -273.668043) (xy 371.182707 -273.704766)
			(xy 371.140691 -273.735292) (xy 371.094417 -273.75887) (xy 371.045024 -273.774918) (xy 370.993729 -273.783043)
			(xy 370.941795 -273.783043) (xy 370.8905 -273.774918) (xy 370.841107 -273.75887) (xy 370.794833 -273.735292)
			(xy 370.752817 -273.704766) (xy 370.716094 -273.668043) (xy 370.685568 -273.626027) (xy 370.66199 -273.579753)
			(xy 370.645942 -273.53036) (xy 370.637817 -273.479065) (xy 370.358161 -273.479065) (xy 370.350036 -273.53036)
			(xy 370.333988 -273.579753) (xy 370.31041 -273.626027) (xy 370.279884 -273.668043) (xy 370.243161 -273.704766)
			(xy 370.201145 -273.735292) (xy 370.154871 -273.75887) (xy 370.105478 -273.774918) (xy 370.054183 -273.783043)
			(xy 370.002249 -273.783043) (xy 369.950954 -273.774918) (xy 369.901561 -273.75887) (xy 369.855287 -273.735292)
			(xy 369.813271 -273.704766) (xy 369.776548 -273.668043) (xy 369.746022 -273.626027) (xy 369.722444 -273.579753)
			(xy 369.706396 -273.53036) (xy 369.698271 -273.479065) (xy 369.418361 -273.479065) (xy 369.410236 -273.53036)
			(xy 369.394188 -273.579753) (xy 369.37061 -273.626027) (xy 369.340084 -273.668043) (xy 369.303361 -273.704766)
			(xy 369.261345 -273.735292) (xy 369.215071 -273.75887) (xy 369.165678 -273.774918) (xy 369.114383 -273.783043)
			(xy 369.062449 -273.783043) (xy 369.011154 -273.774918) (xy 368.961761 -273.75887) (xy 368.915487 -273.735292)
			(xy 368.873471 -273.704766) (xy 368.836748 -273.668043) (xy 368.806222 -273.626027) (xy 368.782644 -273.579753)
			(xy 368.766596 -273.53036) (xy 368.758471 -273.479065) (xy 368.478561 -273.479065) (xy 368.470436 -273.53036)
			(xy 368.454388 -273.579753) (xy 368.43081 -273.626027) (xy 368.400284 -273.668043) (xy 368.363561 -273.704766)
			(xy 368.321545 -273.735292) (xy 368.275271 -273.75887) (xy 368.225878 -273.774918) (xy 368.174583 -273.783043)
			(xy 368.122649 -273.783043) (xy 368.071354 -273.774918) (xy 368.021961 -273.75887) (xy 367.975687 -273.735292)
			(xy 367.933671 -273.704766) (xy 367.896948 -273.668043) (xy 367.866422 -273.626027) (xy 367.842844 -273.579753)
			(xy 367.826796 -273.53036) (xy 367.818671 -273.479065) (xy 367.538761 -273.479065) (xy 367.530636 -273.53036)
			(xy 367.514588 -273.579753) (xy 367.49101 -273.626027) (xy 367.460484 -273.668043) (xy 367.423761 -273.704766)
			(xy 367.381745 -273.735292) (xy 367.335471 -273.75887) (xy 367.286078 -273.774918) (xy 367.234783 -273.783043)
			(xy 367.182849 -273.783043) (xy 367.131554 -273.774918) (xy 367.082161 -273.75887) (xy 367.035887 -273.735292)
			(xy 366.993871 -273.704766) (xy 366.957148 -273.668043) (xy 366.926622 -273.626027) (xy 366.903044 -273.579753)
			(xy 366.886996 -273.53036) (xy 366.878871 -273.479065) (xy 366.598961 -273.479065) (xy 366.590836 -273.53036)
			(xy 366.574788 -273.579753) (xy 366.55121 -273.626027) (xy 366.520684 -273.668043) (xy 366.483961 -273.704766)
			(xy 366.441945 -273.735292) (xy 366.395671 -273.75887) (xy 366.346278 -273.774918) (xy 366.294983 -273.783043)
			(xy 366.243049 -273.783043) (xy 366.191754 -273.774918) (xy 366.142361 -273.75887) (xy 366.096087 -273.735292)
			(xy 366.054071 -273.704766) (xy 366.017348 -273.668043) (xy 365.986822 -273.626027) (xy 365.963244 -273.579753)
			(xy 365.947196 -273.53036) (xy 365.939071 -273.479065) (xy 365.659161 -273.479065) (xy 365.651036 -273.53036)
			(xy 365.634988 -273.579753) (xy 365.61141 -273.626027) (xy 365.580884 -273.668043) (xy 365.544161 -273.704766)
			(xy 365.502145 -273.735292) (xy 365.455871 -273.75887) (xy 365.406478 -273.774918) (xy 365.355183 -273.783043)
			(xy 365.303249 -273.783043) (xy 365.251954 -273.774918) (xy 365.202561 -273.75887) (xy 365.156287 -273.735292)
			(xy 365.114271 -273.704766) (xy 365.077548 -273.668043) (xy 365.047022 -273.626027) (xy 365.023444 -273.579753)
			(xy 365.007396 -273.53036) (xy 364.999271 -273.479065) (xy 364.719361 -273.479065) (xy 364.711236 -273.53036)
			(xy 364.695188 -273.579753) (xy 364.67161 -273.626027) (xy 364.641084 -273.668043) (xy 364.604361 -273.704766)
			(xy 364.562345 -273.735292) (xy 364.516071 -273.75887) (xy 364.466678 -273.774918) (xy 364.415383 -273.783043)
			(xy 364.363449 -273.783043) (xy 364.312154 -273.774918) (xy 364.262761 -273.75887) (xy 364.216487 -273.735292)
			(xy 364.174471 -273.704766) (xy 364.137748 -273.668043) (xy 364.107222 -273.626027) (xy 364.083644 -273.579753)
			(xy 364.067596 -273.53036) (xy 364.059471 -273.479065) (xy 363.779307 -273.479065) (xy 363.771182 -273.53036)
			(xy 363.755134 -273.579753) (xy 363.731556 -273.626027) (xy 363.70103 -273.668043) (xy 363.664307 -273.704766)
			(xy 363.622291 -273.735292) (xy 363.576017 -273.75887) (xy 363.526624 -273.774918) (xy 363.475329 -273.783043)
			(xy 363.423395 -273.783043) (xy 363.3721 -273.774918) (xy 363.322707 -273.75887) (xy 363.276433 -273.735292)
			(xy 363.234417 -273.704766) (xy 363.197694 -273.668043) (xy 363.167168 -273.626027) (xy 363.14359 -273.579753)
			(xy 363.127542 -273.53036) (xy 363.119417 -273.479065) (xy 362.839507 -273.479065) (xy 362.831382 -273.53036)
			(xy 362.815334 -273.579753) (xy 362.791756 -273.626027) (xy 362.76123 -273.668043) (xy 362.724507 -273.704766)
			(xy 362.682491 -273.735292) (xy 362.636217 -273.75887) (xy 362.586824 -273.774918) (xy 362.535529 -273.783043)
			(xy 362.483595 -273.783043) (xy 362.4323 -273.774918) (xy 362.382907 -273.75887) (xy 362.336633 -273.735292)
			(xy 362.294617 -273.704766) (xy 362.257894 -273.668043) (xy 362.227368 -273.626027) (xy 362.20379 -273.579753)
			(xy 362.187742 -273.53036) (xy 362.179617 -273.479065) (xy 361.899707 -273.479065) (xy 361.891582 -273.53036)
			(xy 361.875534 -273.579753) (xy 361.851956 -273.626027) (xy 361.82143 -273.668043) (xy 361.784707 -273.704766)
			(xy 361.742691 -273.735292) (xy 361.696417 -273.75887) (xy 361.647024 -273.774918) (xy 361.595729 -273.783043)
			(xy 361.543795 -273.783043) (xy 361.4925 -273.774918) (xy 361.443107 -273.75887) (xy 361.396833 -273.735292)
			(xy 361.354817 -273.704766) (xy 361.318094 -273.668043) (xy 361.287568 -273.626027) (xy 361.26399 -273.579753)
			(xy 361.247942 -273.53036) (xy 361.239817 -273.479065) (xy 360.959907 -273.479065) (xy 360.951782 -273.53036)
			(xy 360.935734 -273.579753) (xy 360.912156 -273.626027) (xy 360.88163 -273.668043) (xy 360.844907 -273.704766)
			(xy 360.802891 -273.735292) (xy 360.756617 -273.75887) (xy 360.707224 -273.774918) (xy 360.655929 -273.783043)
			(xy 360.603995 -273.783043) (xy 360.5527 -273.774918) (xy 360.503307 -273.75887) (xy 360.457033 -273.735292)
			(xy 360.415017 -273.704766) (xy 360.378294 -273.668043) (xy 360.347768 -273.626027) (xy 360.32419 -273.579753)
			(xy 360.308142 -273.53036) (xy 360.300017 -273.479065) (xy 360.020107 -273.479065) (xy 360.011982 -273.53036)
			(xy 359.995934 -273.579753) (xy 359.972356 -273.626027) (xy 359.94183 -273.668043) (xy 359.905107 -273.704766)
			(xy 359.863091 -273.735292) (xy 359.816817 -273.75887) (xy 359.767424 -273.774918) (xy 359.716129 -273.783043)
			(xy 359.664195 -273.783043) (xy 359.6129 -273.774918) (xy 359.563507 -273.75887) (xy 359.517233 -273.735292)
			(xy 359.475217 -273.704766) (xy 359.438494 -273.668043) (xy 359.407968 -273.626027) (xy 359.38439 -273.579753)
			(xy 359.368342 -273.53036) (xy 359.360217 -273.479065) (xy 359.080561 -273.479065) (xy 359.072436 -273.53036)
			(xy 359.056388 -273.579753) (xy 359.03281 -273.626027) (xy 359.002284 -273.668043) (xy 358.965561 -273.704766)
			(xy 358.923545 -273.735292) (xy 358.877271 -273.75887) (xy 358.827878 -273.774918) (xy 358.776583 -273.783043)
			(xy 358.724649 -273.783043) (xy 358.673354 -273.774918) (xy 358.623961 -273.75887) (xy 358.577687 -273.735292)
			(xy 358.535671 -273.704766) (xy 358.498948 -273.668043) (xy 358.468422 -273.626027) (xy 358.444844 -273.579753)
			(xy 358.428796 -273.53036) (xy 358.420671 -273.479065) (xy 358.140507 -273.479065) (xy 358.132382 -273.53036)
			(xy 358.116334 -273.579753) (xy 358.092756 -273.626027) (xy 358.06223 -273.668043) (xy 358.025507 -273.704766)
			(xy 357.983491 -273.735292) (xy 357.937217 -273.75887) (xy 357.887824 -273.774918) (xy 357.836529 -273.783043)
			(xy 357.784595 -273.783043) (xy 357.7333 -273.774918) (xy 357.683907 -273.75887) (xy 357.637633 -273.735292)
			(xy 357.595617 -273.704766) (xy 357.558894 -273.668043) (xy 357.528368 -273.626027) (xy 357.50479 -273.579753)
			(xy 357.488742 -273.53036) (xy 357.480617 -273.479065) (xy 357.200623 -273.479065) (xy 357.200579 -273.481014)
			(xy 357.191137 -273.536044) (xy 357.18242 -273.562572) (xy 357.1748 -273.58467) (xy 357.378508 -273.93773)
			(xy 357.401622 -273.942048) (xy 357.426537 -273.947246) (xy 357.47452 -273.964207) (xy 357.519337 -273.98832)
			(xy 357.559929 -274.019016) (xy 357.595339 -274.055571) (xy 357.624728 -274.097119) (xy 357.647404 -274.142681)
			(xy 357.662829 -274.191179) (xy 357.670641 -274.241468) (xy 357.671116 -274.266914) (xy 357.670607 -274.292881)
			(xy 357.950517 -274.292881) (xy 357.950517 -274.240947) (xy 357.958642 -274.189652) (xy 357.97469 -274.140259)
			(xy 357.998268 -274.093985) (xy 358.028794 -274.051969) (xy 358.065517 -274.015246) (xy 358.107533 -273.98472)
			(xy 358.153807 -273.961142) (xy 358.2032 -273.945094) (xy 358.254495 -273.936969) (xy 358.306429 -273.936969)
			(xy 358.357724 -273.945094) (xy 358.407117 -273.961142) (xy 358.453391 -273.98472) (xy 358.495407 -274.015246)
			(xy 358.53213 -274.051969) (xy 358.562656 -274.093985) (xy 358.586234 -274.140259) (xy 358.602282 -274.189652)
			(xy 358.610407 -274.240947) (xy 358.610916 -274.266914) (xy 358.610407 -274.292881) (xy 358.890571 -274.292881)
			(xy 358.890571 -274.240947) (xy 358.898696 -274.189652) (xy 358.914744 -274.140259) (xy 358.938322 -274.093985)
			(xy 358.968848 -274.051969) (xy 359.005571 -274.015246) (xy 359.047587 -273.98472) (xy 359.093861 -273.961142)
			(xy 359.143254 -273.945094) (xy 359.194549 -273.936969) (xy 359.246483 -273.936969) (xy 359.297778 -273.945094)
			(xy 359.347171 -273.961142) (xy 359.393445 -273.98472) (xy 359.435461 -274.015246) (xy 359.472184 -274.051969)
			(xy 359.50271 -274.093985) (xy 359.526288 -274.140259) (xy 359.542336 -274.189652) (xy 359.550461 -274.240947)
			(xy 359.55097 -274.266914) (xy 359.550461 -274.292881) (xy 359.830371 -274.292881) (xy 359.830371 -274.240947)
			(xy 359.838496 -274.189652) (xy 359.854544 -274.140259) (xy 359.878122 -274.093985) (xy 359.908648 -274.051969)
			(xy 359.945371 -274.015246) (xy 359.987387 -273.98472) (xy 360.033661 -273.961142) (xy 360.083054 -273.945094)
			(xy 360.134349 -273.936969) (xy 360.186283 -273.936969) (xy 360.237578 -273.945094) (xy 360.286971 -273.961142)
			(xy 360.333245 -273.98472) (xy 360.375261 -274.015246) (xy 360.411984 -274.051969) (xy 360.44251 -274.093985)
			(xy 360.466088 -274.140259) (xy 360.482136 -274.189652) (xy 360.490261 -274.240947) (xy 360.49077 -274.266914)
			(xy 360.490261 -274.292881) (xy 360.769917 -274.292881) (xy 360.769917 -274.240947) (xy 360.778042 -274.189652)
			(xy 360.79409 -274.140259) (xy 360.817668 -274.093985) (xy 360.848194 -274.051969) (xy 360.884917 -274.015246)
			(xy 360.926933 -273.98472) (xy 360.973207 -273.961142) (xy 361.0226 -273.945094) (xy 361.073895 -273.936969)
			(xy 361.125829 -273.936969) (xy 361.177124 -273.945094) (xy 361.226517 -273.961142) (xy 361.272791 -273.98472)
			(xy 361.314807 -274.015246) (xy 361.35153 -274.051969) (xy 361.382056 -274.093985) (xy 361.405634 -274.140259)
			(xy 361.421682 -274.189652) (xy 361.429807 -274.240947) (xy 361.430316 -274.266914) (xy 361.429807 -274.292881)
			(xy 361.709717 -274.292881) (xy 361.709717 -274.240947) (xy 361.717842 -274.189652) (xy 361.73389 -274.140259)
			(xy 361.757468 -274.093985) (xy 361.787994 -274.051969) (xy 361.824717 -274.015246) (xy 361.866733 -273.98472)
			(xy 361.913007 -273.961142) (xy 361.9624 -273.945094) (xy 362.013695 -273.936969) (xy 362.065629 -273.936969)
			(xy 362.116924 -273.945094) (xy 362.166317 -273.961142) (xy 362.212591 -273.98472) (xy 362.254607 -274.015246)
			(xy 362.29133 -274.051969) (xy 362.321856 -274.093985) (xy 362.345434 -274.140259) (xy 362.361482 -274.189652)
			(xy 362.369607 -274.240947) (xy 362.370116 -274.266914) (xy 362.369607 -274.292881) (xy 362.649517 -274.292881)
			(xy 362.649517 -274.240947) (xy 362.657642 -274.189652) (xy 362.67369 -274.140259) (xy 362.697268 -274.093985)
			(xy 362.727794 -274.051969) (xy 362.764517 -274.015246) (xy 362.806533 -273.98472) (xy 362.852807 -273.961142)
			(xy 362.9022 -273.945094) (xy 362.953495 -273.936969) (xy 363.005429 -273.936969) (xy 363.056724 -273.945094)
			(xy 363.106117 -273.961142) (xy 363.152391 -273.98472) (xy 363.194407 -274.015246) (xy 363.23113 -274.051969)
			(xy 363.261656 -274.093985) (xy 363.285234 -274.140259) (xy 363.301282 -274.189652) (xy 363.309407 -274.240947)
			(xy 363.309916 -274.266914) (xy 363.309407 -274.292881) (xy 363.589571 -274.292881) (xy 363.589571 -274.240947)
			(xy 363.597696 -274.189652) (xy 363.613744 -274.140259) (xy 363.637322 -274.093985) (xy 363.667848 -274.051969)
			(xy 363.704571 -274.015246) (xy 363.746587 -273.98472) (xy 363.792861 -273.961142) (xy 363.842254 -273.945094)
			(xy 363.893549 -273.936969) (xy 363.945483 -273.936969) (xy 363.996778 -273.945094) (xy 364.046171 -273.961142)
			(xy 364.092445 -273.98472) (xy 364.134461 -274.015246) (xy 364.171184 -274.051969) (xy 364.20171 -274.093985)
			(xy 364.225288 -274.140259) (xy 364.241336 -274.189652) (xy 364.249461 -274.240947) (xy 364.24997 -274.266914)
			(xy 364.249461 -274.292881) (xy 364.529371 -274.292881) (xy 364.529371 -274.240947) (xy 364.537496 -274.189652)
			(xy 364.553544 -274.140259) (xy 364.577122 -274.093985) (xy 364.607648 -274.051969) (xy 364.644371 -274.015246)
			(xy 364.686387 -273.98472) (xy 364.732661 -273.961142) (xy 364.782054 -273.945094) (xy 364.833349 -273.936969)
			(xy 364.885283 -273.936969) (xy 364.936578 -273.945094) (xy 364.985971 -273.961142) (xy 365.032245 -273.98472)
			(xy 365.074261 -274.015246) (xy 365.110984 -274.051969) (xy 365.14151 -274.093985) (xy 365.165088 -274.140259)
			(xy 365.181136 -274.189652) (xy 365.189261 -274.240947) (xy 365.18977 -274.266914) (xy 365.189261 -274.292881)
			(xy 365.469171 -274.292881) (xy 365.469171 -274.240947) (xy 365.477296 -274.189652) (xy 365.493344 -274.140259)
			(xy 365.516922 -274.093985) (xy 365.547448 -274.051969) (xy 365.584171 -274.015246) (xy 365.626187 -273.98472)
			(xy 365.672461 -273.961142) (xy 365.721854 -273.945094) (xy 365.773149 -273.936969) (xy 365.825083 -273.936969)
			(xy 365.876378 -273.945094) (xy 365.925771 -273.961142) (xy 365.972045 -273.98472) (xy 366.014061 -274.015246)
			(xy 366.050784 -274.051969) (xy 366.08131 -274.093985) (xy 366.104888 -274.140259) (xy 366.120936 -274.189652)
			(xy 366.129061 -274.240947) (xy 366.12957 -274.266914) (xy 366.129061 -274.292881) (xy 366.408717 -274.292881)
			(xy 366.408717 -274.240947) (xy 366.416842 -274.189652) (xy 366.43289 -274.140259) (xy 366.456468 -274.093985)
			(xy 366.486994 -274.051969) (xy 366.523717 -274.015246) (xy 366.565733 -273.98472) (xy 366.612007 -273.961142)
			(xy 366.6614 -273.945094) (xy 366.712695 -273.936969) (xy 366.764629 -273.936969) (xy 366.815924 -273.945094)
			(xy 366.865317 -273.961142) (xy 366.911591 -273.98472) (xy 366.953607 -274.015246) (xy 366.99033 -274.051969)
			(xy 367.020856 -274.093985) (xy 367.044434 -274.140259) (xy 367.060482 -274.189652) (xy 367.068607 -274.240947)
			(xy 367.069116 -274.266914) (xy 367.068607 -274.292881) (xy 367.348517 -274.292881) (xy 367.348517 -274.240947)
			(xy 367.356642 -274.189652) (xy 367.37269 -274.140259) (xy 367.396268 -274.093985) (xy 367.426794 -274.051969)
			(xy 367.463517 -274.015246) (xy 367.505533 -273.98472) (xy 367.551807 -273.961142) (xy 367.6012 -273.945094)
			(xy 367.652495 -273.936969) (xy 367.704429 -273.936969) (xy 367.755724 -273.945094) (xy 367.805117 -273.961142)
			(xy 367.851391 -273.98472) (xy 367.893407 -274.015246) (xy 367.93013 -274.051969) (xy 367.960656 -274.093985)
			(xy 367.984234 -274.140259) (xy 368.000282 -274.189652) (xy 368.008407 -274.240947) (xy 368.008916 -274.266914)
			(xy 368.008407 -274.292881) (xy 368.288317 -274.292881) (xy 368.288317 -274.240947) (xy 368.296442 -274.189652)
			(xy 368.31249 -274.140259) (xy 368.336068 -274.093985) (xy 368.366594 -274.051969) (xy 368.403317 -274.015246)
			(xy 368.445333 -273.98472) (xy 368.491607 -273.961142) (xy 368.541 -273.945094) (xy 368.592295 -273.936969)
			(xy 368.644229 -273.936969) (xy 368.695524 -273.945094) (xy 368.744917 -273.961142) (xy 368.791191 -273.98472)
			(xy 368.833207 -274.015246) (xy 368.86993 -274.051969) (xy 368.900456 -274.093985) (xy 368.924034 -274.140259)
			(xy 368.940082 -274.189652) (xy 368.948207 -274.240947) (xy 368.948716 -274.266914) (xy 368.948207 -274.292881)
			(xy 369.228371 -274.292881) (xy 369.228371 -274.240947) (xy 369.236496 -274.189652) (xy 369.252544 -274.140259)
			(xy 369.276122 -274.093985) (xy 369.306648 -274.051969) (xy 369.343371 -274.015246) (xy 369.385387 -273.98472)
			(xy 369.431661 -273.961142) (xy 369.481054 -273.945094) (xy 369.532349 -273.936969) (xy 369.584283 -273.936969)
			(xy 369.635578 -273.945094) (xy 369.684971 -273.961142) (xy 369.731245 -273.98472) (xy 369.773261 -274.015246)
			(xy 369.809984 -274.051969) (xy 369.84051 -274.093985) (xy 369.864088 -274.140259) (xy 369.880136 -274.189652)
			(xy 369.888261 -274.240947) (xy 369.88877 -274.266914) (xy 369.888261 -274.292881) (xy 370.167917 -274.292881)
			(xy 370.167917 -274.240947) (xy 370.176042 -274.189652) (xy 370.19209 -274.140259) (xy 370.215668 -274.093985)
			(xy 370.246194 -274.051969) (xy 370.282917 -274.015246) (xy 370.324933 -273.98472) (xy 370.371207 -273.961142)
			(xy 370.4206 -273.945094) (xy 370.471895 -273.936969) (xy 370.523829 -273.936969) (xy 370.575124 -273.945094)
			(xy 370.624517 -273.961142) (xy 370.670791 -273.98472) (xy 370.712807 -274.015246) (xy 370.74953 -274.051969)
			(xy 370.780056 -274.093985) (xy 370.803634 -274.140259) (xy 370.819682 -274.189652) (xy 370.827807 -274.240947)
			(xy 370.828316 -274.266914) (xy 370.827807 -274.292881) (xy 371.107717 -274.292881) (xy 371.107717 -274.240947)
			(xy 371.115842 -274.189652) (xy 371.13189 -274.140259) (xy 371.155468 -274.093985) (xy 371.185994 -274.051969)
			(xy 371.222717 -274.015246) (xy 371.264733 -273.98472) (xy 371.311007 -273.961142) (xy 371.3604 -273.945094)
			(xy 371.411695 -273.936969) (xy 371.463629 -273.936969) (xy 371.514924 -273.945094) (xy 371.564317 -273.961142)
			(xy 371.610591 -273.98472) (xy 371.652607 -274.015246) (xy 371.68933 -274.051969) (xy 371.719856 -274.093985)
			(xy 371.743434 -274.140259) (xy 371.759482 -274.189652) (xy 371.767607 -274.240947) (xy 371.768116 -274.266914)
			(xy 371.767607 -274.292881) (xy 372.047517 -274.292881) (xy 372.047517 -274.240947) (xy 372.055642 -274.189652)
			(xy 372.07169 -274.140259) (xy 372.095268 -274.093985) (xy 372.125794 -274.051969) (xy 372.162517 -274.015246)
			(xy 372.204533 -273.98472) (xy 372.250807 -273.961142) (xy 372.3002 -273.945094) (xy 372.351495 -273.936969)
			(xy 372.403429 -273.936969) (xy 372.454724 -273.945094) (xy 372.504117 -273.961142) (xy 372.550391 -273.98472)
			(xy 372.592407 -274.015246) (xy 372.62913 -274.051969) (xy 372.659656 -274.093985) (xy 372.683234 -274.140259)
			(xy 372.699282 -274.189652) (xy 372.707407 -274.240947) (xy 372.707916 -274.266914) (xy 372.707407 -274.292881)
			(xy 372.987317 -274.292881) (xy 372.987317 -274.240947) (xy 372.995442 -274.189652) (xy 373.01149 -274.140259)
			(xy 373.035068 -274.093985) (xy 373.065594 -274.051969) (xy 373.102317 -274.015246) (xy 373.144333 -273.98472)
			(xy 373.190607 -273.961142) (xy 373.24 -273.945094) (xy 373.291295 -273.936969) (xy 373.343229 -273.936969)
			(xy 373.394524 -273.945094) (xy 373.443917 -273.961142) (xy 373.490191 -273.98472) (xy 373.532207 -274.015246)
			(xy 373.56893 -274.051969) (xy 373.599456 -274.093985) (xy 373.623034 -274.140259) (xy 373.639082 -274.189652)
			(xy 373.647207 -274.240947) (xy 373.647716 -274.266914) (xy 373.647207 -274.292881) (xy 373.927371 -274.292881)
			(xy 373.927371 -274.240947) (xy 373.935496 -274.189652) (xy 373.951544 -274.140259) (xy 373.975122 -274.093985)
			(xy 374.005648 -274.051969) (xy 374.042371 -274.015246) (xy 374.084387 -273.98472) (xy 374.130661 -273.961142)
			(xy 374.180054 -273.945094) (xy 374.231349 -273.936969) (xy 374.283283 -273.936969) (xy 374.334578 -273.945094)
			(xy 374.383971 -273.961142) (xy 374.430245 -273.98472) (xy 374.472261 -274.015246) (xy 374.508984 -274.051969)
			(xy 374.53951 -274.093985) (xy 374.563088 -274.140259) (xy 374.579136 -274.189652) (xy 374.587261 -274.240947)
			(xy 374.58777 -274.266914) (xy 374.587261 -274.292881) (xy 374.866917 -274.292881) (xy 374.866917 -274.240947)
			(xy 374.875042 -274.189652) (xy 374.89109 -274.140259) (xy 374.914668 -274.093985) (xy 374.945194 -274.051969)
			(xy 374.981917 -274.015246) (xy 375.023933 -273.98472) (xy 375.070207 -273.961142) (xy 375.1196 -273.945094)
			(xy 375.170895 -273.936969) (xy 375.222829 -273.936969) (xy 375.274124 -273.945094) (xy 375.323517 -273.961142)
			(xy 375.369791 -273.98472) (xy 375.411807 -274.015246) (xy 375.44853 -274.051969) (xy 375.479056 -274.093985)
			(xy 375.502634 -274.140259) (xy 375.518682 -274.189652) (xy 375.526807 -274.240947) (xy 375.527316 -274.266914)
			(xy 375.526807 -274.292881) (xy 375.806717 -274.292881) (xy 375.806717 -274.240947) (xy 375.814842 -274.189652)
			(xy 375.83089 -274.140259) (xy 375.854468 -274.093985) (xy 375.884994 -274.051969) (xy 375.921717 -274.015246)
			(xy 375.963733 -273.98472) (xy 376.010007 -273.961142) (xy 376.0594 -273.945094) (xy 376.110695 -273.936969)
			(xy 376.162629 -273.936969) (xy 376.213924 -273.945094) (xy 376.263317 -273.961142) (xy 376.309591 -273.98472)
			(xy 376.351607 -274.015246) (xy 376.38833 -274.051969) (xy 376.418856 -274.093985) (xy 376.442434 -274.140259)
			(xy 376.458482 -274.189652) (xy 376.466607 -274.240947) (xy 376.467116 -274.266914) (xy 376.466607 -274.292881)
			(xy 376.746517 -274.292881) (xy 376.746517 -274.240947) (xy 376.754642 -274.189652) (xy 376.77069 -274.140259)
			(xy 376.794268 -274.093985) (xy 376.824794 -274.051969) (xy 376.861517 -274.015246) (xy 376.903533 -273.98472)
			(xy 376.949807 -273.961142) (xy 376.9992 -273.945094) (xy 377.050495 -273.936969) (xy 377.102429 -273.936969)
			(xy 377.153724 -273.945094) (xy 377.203117 -273.961142) (xy 377.249391 -273.98472) (xy 377.291407 -274.015246)
			(xy 377.32813 -274.051969) (xy 377.358656 -274.093985) (xy 377.382234 -274.140259) (xy 377.398282 -274.189652)
			(xy 377.406407 -274.240947) (xy 377.406916 -274.266914) (xy 377.406407 -274.292881) (xy 377.686317 -274.292881)
			(xy 377.686317 -274.240947) (xy 377.694442 -274.189652) (xy 377.71049 -274.140259) (xy 377.734068 -274.093985)
			(xy 377.764594 -274.051969) (xy 377.801317 -274.015246) (xy 377.843333 -273.98472) (xy 377.889607 -273.961142)
			(xy 377.939 -273.945094) (xy 377.990295 -273.936969) (xy 378.042229 -273.936969) (xy 378.093524 -273.945094)
			(xy 378.142917 -273.961142) (xy 378.189191 -273.98472) (xy 378.231207 -274.015246) (xy 378.26793 -274.051969)
			(xy 378.298456 -274.093985) (xy 378.322034 -274.140259) (xy 378.338082 -274.189652) (xy 378.346207 -274.240947)
			(xy 378.346716 -274.266914) (xy 378.346207 -274.292881) (xy 378.626117 -274.292881) (xy 378.626117 -274.240947)
			(xy 378.634242 -274.189652) (xy 378.65029 -274.140259) (xy 378.673868 -274.093985) (xy 378.704394 -274.051969)
			(xy 378.741117 -274.015246) (xy 378.783133 -273.98472) (xy 378.829407 -273.961142) (xy 378.8788 -273.945094)
			(xy 378.930095 -273.936969) (xy 378.982029 -273.936969) (xy 379.033324 -273.945094) (xy 379.082717 -273.961142)
			(xy 379.128991 -273.98472) (xy 379.171007 -274.015246) (xy 379.20773 -274.051969) (xy 379.238256 -274.093985)
			(xy 379.261834 -274.140259) (xy 379.277882 -274.189652) (xy 379.286007 -274.240947) (xy 379.286516 -274.266914)
			(xy 379.286007 -274.292881) (xy 379.277882 -274.344176) (xy 379.261834 -274.393569) (xy 379.238256 -274.439843)
			(xy 379.20773 -274.481859) (xy 379.171007 -274.518582) (xy 379.128991 -274.549108) (xy 379.082717 -274.572686)
			(xy 379.033324 -274.588734) (xy 378.982029 -274.596859) (xy 378.930095 -274.596859) (xy 378.8788 -274.588734)
			(xy 378.829407 -274.572686) (xy 378.783133 -274.549108) (xy 378.741117 -274.518582) (xy 378.704394 -274.481859)
			(xy 378.673868 -274.439843) (xy 378.65029 -274.393569) (xy 378.634242 -274.344176) (xy 378.626117 -274.292881)
			(xy 378.346207 -274.292881) (xy 378.338082 -274.344176) (xy 378.322034 -274.393569) (xy 378.298456 -274.439843)
			(xy 378.26793 -274.481859) (xy 378.231207 -274.518582) (xy 378.189191 -274.549108) (xy 378.142917 -274.572686)
			(xy 378.093524 -274.588734) (xy 378.042229 -274.596859) (xy 377.990295 -274.596859) (xy 377.939 -274.588734)
			(xy 377.889607 -274.572686) (xy 377.843333 -274.549108) (xy 377.801317 -274.518582) (xy 377.764594 -274.481859)
			(xy 377.734068 -274.439843) (xy 377.71049 -274.393569) (xy 377.694442 -274.344176) (xy 377.686317 -274.292881)
			(xy 377.406407 -274.292881) (xy 377.398282 -274.344176) (xy 377.382234 -274.393569) (xy 377.358656 -274.439843)
			(xy 377.32813 -274.481859) (xy 377.291407 -274.518582) (xy 377.249391 -274.549108) (xy 377.203117 -274.572686)
			(xy 377.153724 -274.588734) (xy 377.102429 -274.596859) (xy 377.050495 -274.596859) (xy 376.9992 -274.588734)
			(xy 376.949807 -274.572686) (xy 376.903533 -274.549108) (xy 376.861517 -274.518582) (xy 376.824794 -274.481859)
			(xy 376.794268 -274.439843) (xy 376.77069 -274.393569) (xy 376.754642 -274.344176) (xy 376.746517 -274.292881)
			(xy 376.466607 -274.292881) (xy 376.458482 -274.344176) (xy 376.442434 -274.393569) (xy 376.418856 -274.439843)
			(xy 376.38833 -274.481859) (xy 376.351607 -274.518582) (xy 376.309591 -274.549108) (xy 376.263317 -274.572686)
			(xy 376.213924 -274.588734) (xy 376.162629 -274.596859) (xy 376.110695 -274.596859) (xy 376.0594 -274.588734)
			(xy 376.010007 -274.572686) (xy 375.963733 -274.549108) (xy 375.921717 -274.518582) (xy 375.884994 -274.481859)
			(xy 375.854468 -274.439843) (xy 375.83089 -274.393569) (xy 375.814842 -274.344176) (xy 375.806717 -274.292881)
			(xy 375.526807 -274.292881) (xy 375.518682 -274.344176) (xy 375.502634 -274.393569) (xy 375.479056 -274.439843)
			(xy 375.44853 -274.481859) (xy 375.411807 -274.518582) (xy 375.369791 -274.549108) (xy 375.323517 -274.572686)
			(xy 375.274124 -274.588734) (xy 375.222829 -274.596859) (xy 375.170895 -274.596859) (xy 375.1196 -274.588734)
			(xy 375.070207 -274.572686) (xy 375.023933 -274.549108) (xy 374.981917 -274.518582) (xy 374.945194 -274.481859)
			(xy 374.914668 -274.439843) (xy 374.89109 -274.393569) (xy 374.875042 -274.344176) (xy 374.866917 -274.292881)
			(xy 374.587261 -274.292881) (xy 374.579136 -274.344176) (xy 374.563088 -274.393569) (xy 374.53951 -274.439843)
			(xy 374.508984 -274.481859) (xy 374.472261 -274.518582) (xy 374.430245 -274.549108) (xy 374.383971 -274.572686)
			(xy 374.334578 -274.588734) (xy 374.283283 -274.596859) (xy 374.231349 -274.596859) (xy 374.180054 -274.588734)
			(xy 374.130661 -274.572686) (xy 374.084387 -274.549108) (xy 374.042371 -274.518582) (xy 374.005648 -274.481859)
			(xy 373.975122 -274.439843) (xy 373.951544 -274.393569) (xy 373.935496 -274.344176) (xy 373.927371 -274.292881)
			(xy 373.647207 -274.292881) (xy 373.639082 -274.344176) (xy 373.623034 -274.393569) (xy 373.599456 -274.439843)
			(xy 373.56893 -274.481859) (xy 373.532207 -274.518582) (xy 373.490191 -274.549108) (xy 373.443917 -274.572686)
			(xy 373.394524 -274.588734) (xy 373.343229 -274.596859) (xy 373.291295 -274.596859) (xy 373.24 -274.588734)
			(xy 373.190607 -274.572686) (xy 373.144333 -274.549108) (xy 373.102317 -274.518582) (xy 373.065594 -274.481859)
			(xy 373.035068 -274.439843) (xy 373.01149 -274.393569) (xy 372.995442 -274.344176) (xy 372.987317 -274.292881)
			(xy 372.707407 -274.292881) (xy 372.699282 -274.344176) (xy 372.683234 -274.393569) (xy 372.659656 -274.439843)
			(xy 372.62913 -274.481859) (xy 372.592407 -274.518582) (xy 372.550391 -274.549108) (xy 372.504117 -274.572686)
			(xy 372.454724 -274.588734) (xy 372.403429 -274.596859) (xy 372.351495 -274.596859) (xy 372.3002 -274.588734)
			(xy 372.250807 -274.572686) (xy 372.204533 -274.549108) (xy 372.162517 -274.518582) (xy 372.125794 -274.481859)
			(xy 372.095268 -274.439843) (xy 372.07169 -274.393569) (xy 372.055642 -274.344176) (xy 372.047517 -274.292881)
			(xy 371.767607 -274.292881) (xy 371.759482 -274.344176) (xy 371.743434 -274.393569) (xy 371.719856 -274.439843)
			(xy 371.68933 -274.481859) (xy 371.652607 -274.518582) (xy 371.610591 -274.549108) (xy 371.564317 -274.572686)
			(xy 371.514924 -274.588734) (xy 371.463629 -274.596859) (xy 371.411695 -274.596859) (xy 371.3604 -274.588734)
			(xy 371.311007 -274.572686) (xy 371.264733 -274.549108) (xy 371.222717 -274.518582) (xy 371.185994 -274.481859)
			(xy 371.155468 -274.439843) (xy 371.13189 -274.393569) (xy 371.115842 -274.344176) (xy 371.107717 -274.292881)
			(xy 370.827807 -274.292881) (xy 370.819682 -274.344176) (xy 370.803634 -274.393569) (xy 370.780056 -274.439843)
			(xy 370.74953 -274.481859) (xy 370.712807 -274.518582) (xy 370.670791 -274.549108) (xy 370.624517 -274.572686)
			(xy 370.575124 -274.588734) (xy 370.523829 -274.596859) (xy 370.471895 -274.596859) (xy 370.4206 -274.588734)
			(xy 370.371207 -274.572686) (xy 370.324933 -274.549108) (xy 370.282917 -274.518582) (xy 370.246194 -274.481859)
			(xy 370.215668 -274.439843) (xy 370.19209 -274.393569) (xy 370.176042 -274.344176) (xy 370.167917 -274.292881)
			(xy 369.888261 -274.292881) (xy 369.880136 -274.344176) (xy 369.864088 -274.393569) (xy 369.84051 -274.439843)
			(xy 369.809984 -274.481859) (xy 369.773261 -274.518582) (xy 369.731245 -274.549108) (xy 369.684971 -274.572686)
			(xy 369.635578 -274.588734) (xy 369.584283 -274.596859) (xy 369.532349 -274.596859) (xy 369.481054 -274.588734)
			(xy 369.431661 -274.572686) (xy 369.385387 -274.549108) (xy 369.343371 -274.518582) (xy 369.306648 -274.481859)
			(xy 369.276122 -274.439843) (xy 369.252544 -274.393569) (xy 369.236496 -274.344176) (xy 369.228371 -274.292881)
			(xy 368.948207 -274.292881) (xy 368.940082 -274.344176) (xy 368.924034 -274.393569) (xy 368.900456 -274.439843)
			(xy 368.86993 -274.481859) (xy 368.833207 -274.518582) (xy 368.791191 -274.549108) (xy 368.744917 -274.572686)
			(xy 368.695524 -274.588734) (xy 368.644229 -274.596859) (xy 368.592295 -274.596859) (xy 368.541 -274.588734)
			(xy 368.491607 -274.572686) (xy 368.445333 -274.549108) (xy 368.403317 -274.518582) (xy 368.366594 -274.481859)
			(xy 368.336068 -274.439843) (xy 368.31249 -274.393569) (xy 368.296442 -274.344176) (xy 368.288317 -274.292881)
			(xy 368.008407 -274.292881) (xy 368.000282 -274.344176) (xy 367.984234 -274.393569) (xy 367.960656 -274.439843)
			(xy 367.93013 -274.481859) (xy 367.893407 -274.518582) (xy 367.851391 -274.549108) (xy 367.805117 -274.572686)
			(xy 367.755724 -274.588734) (xy 367.704429 -274.596859) (xy 367.652495 -274.596859) (xy 367.6012 -274.588734)
			(xy 367.551807 -274.572686) (xy 367.505533 -274.549108) (xy 367.463517 -274.518582) (xy 367.426794 -274.481859)
			(xy 367.396268 -274.439843) (xy 367.37269 -274.393569) (xy 367.356642 -274.344176) (xy 367.348517 -274.292881)
			(xy 367.068607 -274.292881) (xy 367.060482 -274.344176) (xy 367.044434 -274.393569) (xy 367.020856 -274.439843)
			(xy 366.99033 -274.481859) (xy 366.953607 -274.518582) (xy 366.911591 -274.549108) (xy 366.865317 -274.572686)
			(xy 366.815924 -274.588734) (xy 366.764629 -274.596859) (xy 366.712695 -274.596859) (xy 366.6614 -274.588734)
			(xy 366.612007 -274.572686) (xy 366.565733 -274.549108) (xy 366.523717 -274.518582) (xy 366.486994 -274.481859)
			(xy 366.456468 -274.439843) (xy 366.43289 -274.393569) (xy 366.416842 -274.344176) (xy 366.408717 -274.292881)
			(xy 366.129061 -274.292881) (xy 366.120936 -274.344176) (xy 366.104888 -274.393569) (xy 366.08131 -274.439843)
			(xy 366.050784 -274.481859) (xy 366.014061 -274.518582) (xy 365.972045 -274.549108) (xy 365.925771 -274.572686)
			(xy 365.876378 -274.588734) (xy 365.825083 -274.596859) (xy 365.773149 -274.596859) (xy 365.721854 -274.588734)
			(xy 365.672461 -274.572686) (xy 365.626187 -274.549108) (xy 365.584171 -274.518582) (xy 365.547448 -274.481859)
			(xy 365.516922 -274.439843) (xy 365.493344 -274.393569) (xy 365.477296 -274.344176) (xy 365.469171 -274.292881)
			(xy 365.189261 -274.292881) (xy 365.181136 -274.344176) (xy 365.165088 -274.393569) (xy 365.14151 -274.439843)
			(xy 365.110984 -274.481859) (xy 365.074261 -274.518582) (xy 365.032245 -274.549108) (xy 364.985971 -274.572686)
			(xy 364.936578 -274.588734) (xy 364.885283 -274.596859) (xy 364.833349 -274.596859) (xy 364.782054 -274.588734)
			(xy 364.732661 -274.572686) (xy 364.686387 -274.549108) (xy 364.644371 -274.518582) (xy 364.607648 -274.481859)
			(xy 364.577122 -274.439843) (xy 364.553544 -274.393569) (xy 364.537496 -274.344176) (xy 364.529371 -274.292881)
			(xy 364.249461 -274.292881) (xy 364.241336 -274.344176) (xy 364.225288 -274.393569) (xy 364.20171 -274.439843)
			(xy 364.171184 -274.481859) (xy 364.134461 -274.518582) (xy 364.092445 -274.549108) (xy 364.046171 -274.572686)
			(xy 363.996778 -274.588734) (xy 363.945483 -274.596859) (xy 363.893549 -274.596859) (xy 363.842254 -274.588734)
			(xy 363.792861 -274.572686) (xy 363.746587 -274.549108) (xy 363.704571 -274.518582) (xy 363.667848 -274.481859)
			(xy 363.637322 -274.439843) (xy 363.613744 -274.393569) (xy 363.597696 -274.344176) (xy 363.589571 -274.292881)
			(xy 363.309407 -274.292881) (xy 363.301282 -274.344176) (xy 363.285234 -274.393569) (xy 363.261656 -274.439843)
			(xy 363.23113 -274.481859) (xy 363.194407 -274.518582) (xy 363.152391 -274.549108) (xy 363.106117 -274.572686)
			(xy 363.056724 -274.588734) (xy 363.005429 -274.596859) (xy 362.953495 -274.596859) (xy 362.9022 -274.588734)
			(xy 362.852807 -274.572686) (xy 362.806533 -274.549108) (xy 362.764517 -274.518582) (xy 362.727794 -274.481859)
			(xy 362.697268 -274.439843) (xy 362.67369 -274.393569) (xy 362.657642 -274.344176) (xy 362.649517 -274.292881)
			(xy 362.369607 -274.292881) (xy 362.361482 -274.344176) (xy 362.345434 -274.393569) (xy 362.321856 -274.439843)
			(xy 362.29133 -274.481859) (xy 362.254607 -274.518582) (xy 362.212591 -274.549108) (xy 362.166317 -274.572686)
			(xy 362.116924 -274.588734) (xy 362.065629 -274.596859) (xy 362.013695 -274.596859) (xy 361.9624 -274.588734)
			(xy 361.913007 -274.572686) (xy 361.866733 -274.549108) (xy 361.824717 -274.518582) (xy 361.787994 -274.481859)
			(xy 361.757468 -274.439843) (xy 361.73389 -274.393569) (xy 361.717842 -274.344176) (xy 361.709717 -274.292881)
			(xy 361.429807 -274.292881) (xy 361.421682 -274.344176) (xy 361.405634 -274.393569) (xy 361.382056 -274.439843)
			(xy 361.35153 -274.481859) (xy 361.314807 -274.518582) (xy 361.272791 -274.549108) (xy 361.226517 -274.572686)
			(xy 361.177124 -274.588734) (xy 361.125829 -274.596859) (xy 361.073895 -274.596859) (xy 361.0226 -274.588734)
			(xy 360.973207 -274.572686) (xy 360.926933 -274.549108) (xy 360.884917 -274.518582) (xy 360.848194 -274.481859)
			(xy 360.817668 -274.439843) (xy 360.79409 -274.393569) (xy 360.778042 -274.344176) (xy 360.769917 -274.292881)
			(xy 360.490261 -274.292881) (xy 360.482136 -274.344176) (xy 360.466088 -274.393569) (xy 360.44251 -274.439843)
			(xy 360.411984 -274.481859) (xy 360.375261 -274.518582) (xy 360.333245 -274.549108) (xy 360.286971 -274.572686)
			(xy 360.237578 -274.588734) (xy 360.186283 -274.596859) (xy 360.134349 -274.596859) (xy 360.083054 -274.588734)
			(xy 360.033661 -274.572686) (xy 359.987387 -274.549108) (xy 359.945371 -274.518582) (xy 359.908648 -274.481859)
			(xy 359.878122 -274.439843) (xy 359.854544 -274.393569) (xy 359.838496 -274.344176) (xy 359.830371 -274.292881)
			(xy 359.550461 -274.292881) (xy 359.542336 -274.344176) (xy 359.526288 -274.393569) (xy 359.50271 -274.439843)
			(xy 359.472184 -274.481859) (xy 359.435461 -274.518582) (xy 359.393445 -274.549108) (xy 359.347171 -274.572686)
			(xy 359.297778 -274.588734) (xy 359.246483 -274.596859) (xy 359.194549 -274.596859) (xy 359.143254 -274.588734)
			(xy 359.093861 -274.572686) (xy 359.047587 -274.549108) (xy 359.005571 -274.518582) (xy 358.968848 -274.481859)
			(xy 358.938322 -274.439843) (xy 358.914744 -274.393569) (xy 358.898696 -274.344176) (xy 358.890571 -274.292881)
			(xy 358.610407 -274.292881) (xy 358.602282 -274.344176) (xy 358.586234 -274.393569) (xy 358.562656 -274.439843)
			(xy 358.53213 -274.481859) (xy 358.495407 -274.518582) (xy 358.453391 -274.549108) (xy 358.407117 -274.572686)
			(xy 358.357724 -274.588734) (xy 358.306429 -274.596859) (xy 358.254495 -274.596859) (xy 358.2032 -274.588734)
			(xy 358.153807 -274.572686) (xy 358.107533 -274.549108) (xy 358.065517 -274.518582) (xy 358.028794 -274.481859)
			(xy 357.998268 -274.439843) (xy 357.97469 -274.393569) (xy 357.958642 -274.344176) (xy 357.950517 -274.292881)
			(xy 357.670607 -274.292881) (xy 357.662482 -274.344176) (xy 357.646434 -274.393569) (xy 357.622856 -274.439843)
			(xy 357.59233 -274.481859) (xy 357.555607 -274.518582) (xy 357.513591 -274.549108) (xy 357.467317 -274.572686)
			(xy 357.417924 -274.588734) (xy 357.366629 -274.596859) (xy 357.314695 -274.596859) (xy 357.2634 -274.588734)
			(xy 357.214007 -274.572686) (xy 357.167733 -274.549108) (xy 357.125717 -274.518582) (xy 357.088994 -274.481859)
			(xy 357.058468 -274.439843) (xy 357.03489 -274.393569) (xy 357.018842 -274.344176) (xy 357.010717 -274.292881)
			(xy 357.010208 -274.266914) (xy 357.010764 -274.238928) (xy 357.020212 -274.18376) (xy 357.029004 -274.157186)
			(xy 357.036624 -274.135088) (xy 356.832916 -273.782282) (xy 356.810056 -273.777964) (xy 356.785115 -273.77282)
			(xy 356.737088 -273.755894) (xy 356.692226 -273.731801) (xy 356.65159 -273.701112) (xy 356.616142 -273.664553)
			(xy 356.586722 -273.62299) (xy 356.564025 -273.577405) (xy 356.548588 -273.528879) (xy 356.540778 -273.478559)
			(xy 356.540308 -273.453098) (xy 356.26167 -273.453098) (xy 356.261161 -273.479065) (xy 356.253036 -273.53036)
			(xy 356.236988 -273.579753) (xy 356.21341 -273.626027) (xy 356.182884 -273.668043) (xy 356.146161 -273.704766)
			(xy 356.104145 -273.735292) (xy 356.057871 -273.75887) (xy 356.008478 -273.774918) (xy 355.957183 -273.783043)
			(xy 355.905249 -273.783043) (xy 355.853954 -273.774918) (xy 355.804561 -273.75887) (xy 355.758287 -273.735292)
			(xy 355.716271 -273.704766) (xy 355.679548 -273.668043) (xy 355.649022 -273.626027) (xy 355.625444 -273.579753)
			(xy 355.609396 -273.53036) (xy 355.601271 -273.479065) (xy 355.321361 -273.479065) (xy 355.313236 -273.53036)
			(xy 355.297188 -273.579753) (xy 355.27361 -273.626027) (xy 355.243084 -273.668043) (xy 355.206361 -273.704766)
			(xy 355.164345 -273.735292) (xy 355.118071 -273.75887) (xy 355.068678 -273.774918) (xy 355.017383 -273.783043)
			(xy 354.965449 -273.783043) (xy 354.914154 -273.774918) (xy 354.864761 -273.75887) (xy 354.818487 -273.735292)
			(xy 354.776471 -273.704766) (xy 354.739748 -273.668043) (xy 354.709222 -273.626027) (xy 354.685644 -273.579753)
			(xy 354.669596 -273.53036) (xy 354.661471 -273.479065) (xy 354.381561 -273.479065) (xy 354.373436 -273.53036)
			(xy 354.357388 -273.579753) (xy 354.33381 -273.626027) (xy 354.303284 -273.668043) (xy 354.266561 -273.704766)
			(xy 354.224545 -273.735292) (xy 354.178271 -273.75887) (xy 354.128878 -273.774918) (xy 354.077583 -273.783043)
			(xy 354.025649 -273.783043) (xy 353.974354 -273.774918) (xy 353.924961 -273.75887) (xy 353.878687 -273.735292)
			(xy 353.836671 -273.704766) (xy 353.799948 -273.668043) (xy 353.769422 -273.626027) (xy 353.745844 -273.579753)
			(xy 353.729796 -273.53036) (xy 353.721671 -273.479065) (xy 352.501961 -273.479065) (xy 352.493836 -273.53036)
			(xy 352.477788 -273.579753) (xy 352.45421 -273.626027) (xy 352.423684 -273.668043) (xy 352.386961 -273.704766)
			(xy 352.344945 -273.735292) (xy 352.298671 -273.75887) (xy 352.249278 -273.774918) (xy 352.197983 -273.783043)
			(xy 352.146049 -273.783043) (xy 352.094754 -273.774918) (xy 352.045361 -273.75887) (xy 351.999087 -273.735292)
			(xy 351.957071 -273.704766) (xy 351.920348 -273.668043) (xy 351.889822 -273.626027) (xy 351.866244 -273.579753)
			(xy 351.850196 -273.53036) (xy 351.842071 -273.479065) (xy 351.561907 -273.479065) (xy 351.553782 -273.53036)
			(xy 351.537734 -273.579753) (xy 351.514156 -273.626027) (xy 351.48363 -273.668043) (xy 351.446907 -273.704766)
			(xy 351.404891 -273.735292) (xy 351.358617 -273.75887) (xy 351.309224 -273.774918) (xy 351.257929 -273.783043)
			(xy 351.205995 -273.783043) (xy 351.1547 -273.774918) (xy 351.105307 -273.75887) (xy 351.059033 -273.735292)
			(xy 351.017017 -273.704766) (xy 350.980294 -273.668043) (xy 350.949768 -273.626027) (xy 350.92619 -273.579753)
			(xy 350.910142 -273.53036) (xy 350.902017 -273.479065) (xy 350.622361 -273.479065) (xy 350.614236 -273.53036)
			(xy 350.598188 -273.579753) (xy 350.57461 -273.626027) (xy 350.544084 -273.668043) (xy 350.507361 -273.704766)
			(xy 350.465345 -273.735292) (xy 350.419071 -273.75887) (xy 350.369678 -273.774918) (xy 350.318383 -273.783043)
			(xy 350.266449 -273.783043) (xy 350.215154 -273.774918) (xy 350.165761 -273.75887) (xy 350.119487 -273.735292)
			(xy 350.077471 -273.704766) (xy 350.040748 -273.668043) (xy 350.010222 -273.626027) (xy 349.986644 -273.579753)
			(xy 349.970596 -273.53036) (xy 349.962471 -273.479065) (xy 349.682307 -273.479065) (xy 349.674182 -273.53036)
			(xy 349.658134 -273.579753) (xy 349.634556 -273.626027) (xy 349.60403 -273.668043) (xy 349.567307 -273.704766)
			(xy 349.525291 -273.735292) (xy 349.479017 -273.75887) (xy 349.429624 -273.774918) (xy 349.378329 -273.783043)
			(xy 349.326395 -273.783043) (xy 349.2751 -273.774918) (xy 349.225707 -273.75887) (xy 349.179433 -273.735292)
			(xy 349.137417 -273.704766) (xy 349.100694 -273.668043) (xy 349.070168 -273.626027) (xy 349.04659 -273.579753)
			(xy 349.030542 -273.53036) (xy 349.022417 -273.479065) (xy 348.742761 -273.479065) (xy 348.734636 -273.53036)
			(xy 348.718588 -273.579753) (xy 348.69501 -273.626027) (xy 348.664484 -273.668043) (xy 348.627761 -273.704766)
			(xy 348.585745 -273.735292) (xy 348.539471 -273.75887) (xy 348.490078 -273.774918) (xy 348.438783 -273.783043)
			(xy 348.386849 -273.783043) (xy 348.335554 -273.774918) (xy 348.286161 -273.75887) (xy 348.239887 -273.735292)
			(xy 348.197871 -273.704766) (xy 348.161148 -273.668043) (xy 348.130622 -273.626027) (xy 348.107044 -273.579753)
			(xy 348.090996 -273.53036) (xy 348.082871 -273.479065) (xy 347.802961 -273.479065) (xy 347.794836 -273.53036)
			(xy 347.778788 -273.579753) (xy 347.75521 -273.626027) (xy 347.724684 -273.668043) (xy 347.687961 -273.704766)
			(xy 347.645945 -273.735292) (xy 347.599671 -273.75887) (xy 347.550278 -273.774918) (xy 347.498983 -273.783043)
			(xy 347.447049 -273.783043) (xy 347.395754 -273.774918) (xy 347.346361 -273.75887) (xy 347.300087 -273.735292)
			(xy 347.258071 -273.704766) (xy 347.221348 -273.668043) (xy 347.190822 -273.626027) (xy 347.167244 -273.579753)
			(xy 347.151196 -273.53036) (xy 347.143071 -273.479065) (xy 346.863161 -273.479065) (xy 346.855036 -273.53036)
			(xy 346.838988 -273.579753) (xy 346.81541 -273.626027) (xy 346.784884 -273.668043) (xy 346.748161 -273.704766)
			(xy 346.706145 -273.735292) (xy 346.659871 -273.75887) (xy 346.610478 -273.774918) (xy 346.559183 -273.783043)
			(xy 346.507249 -273.783043) (xy 346.455954 -273.774918) (xy 346.406561 -273.75887) (xy 346.360287 -273.735292)
			(xy 346.318271 -273.704766) (xy 346.281548 -273.668043) (xy 346.251022 -273.626027) (xy 346.227444 -273.579753)
			(xy 346.211396 -273.53036) (xy 346.203271 -273.479065) (xy 345.923361 -273.479065) (xy 345.915236 -273.53036)
			(xy 345.899188 -273.579753) (xy 345.87561 -273.626027) (xy 345.845084 -273.668043) (xy 345.808361 -273.704766)
			(xy 345.766345 -273.735292) (xy 345.720071 -273.75887) (xy 345.670678 -273.774918) (xy 345.619383 -273.783043)
			(xy 345.567449 -273.783043) (xy 345.516154 -273.774918) (xy 345.466761 -273.75887) (xy 345.420487 -273.735292)
			(xy 345.378471 -273.704766) (xy 345.341748 -273.668043) (xy 345.311222 -273.626027) (xy 345.287644 -273.579753)
			(xy 345.271596 -273.53036) (xy 345.263471 -273.479065) (xy 344.983561 -273.479065) (xy 344.975436 -273.53036)
			(xy 344.959388 -273.579753) (xy 344.93581 -273.626027) (xy 344.905284 -273.668043) (xy 344.868561 -273.704766)
			(xy 344.826545 -273.735292) (xy 344.780271 -273.75887) (xy 344.730878 -273.774918) (xy 344.679583 -273.783043)
			(xy 344.627649 -273.783043) (xy 344.576354 -273.774918) (xy 344.526961 -273.75887) (xy 344.480687 -273.735292)
			(xy 344.438671 -273.704766) (xy 344.401948 -273.668043) (xy 344.371422 -273.626027) (xy 344.347844 -273.579753)
			(xy 344.331796 -273.53036) (xy 344.323671 -273.479065) (xy 344.043761 -273.479065) (xy 344.035636 -273.53036)
			(xy 344.019588 -273.579753) (xy 343.99601 -273.626027) (xy 343.965484 -273.668043) (xy 343.928761 -273.704766)
			(xy 343.886745 -273.735292) (xy 343.840471 -273.75887) (xy 343.791078 -273.774918) (xy 343.739783 -273.783043)
			(xy 343.687849 -273.783043) (xy 343.636554 -273.774918) (xy 343.587161 -273.75887) (xy 343.540887 -273.735292)
			(xy 343.498871 -273.704766) (xy 343.462148 -273.668043) (xy 343.431622 -273.626027) (xy 343.408044 -273.579753)
			(xy 343.391996 -273.53036) (xy 343.383871 -273.479065) (xy 343.103707 -273.479065) (xy 343.095582 -273.53036)
			(xy 343.079534 -273.579753) (xy 343.055956 -273.626027) (xy 343.02543 -273.668043) (xy 342.988707 -273.704766)
			(xy 342.946691 -273.735292) (xy 342.900417 -273.75887) (xy 342.851024 -273.774918) (xy 342.799729 -273.783043)
			(xy 342.747795 -273.783043) (xy 342.6965 -273.774918) (xy 342.647107 -273.75887) (xy 342.600833 -273.735292)
			(xy 342.558817 -273.704766) (xy 342.522094 -273.668043) (xy 342.491568 -273.626027) (xy 342.46799 -273.579753)
			(xy 342.451942 -273.53036) (xy 342.443817 -273.479065) (xy 342.164161 -273.479065) (xy 342.156036 -273.53036)
			(xy 342.139988 -273.579753) (xy 342.11641 -273.626027) (xy 342.085884 -273.668043) (xy 342.049161 -273.704766)
			(xy 342.007145 -273.735292) (xy 341.960871 -273.75887) (xy 341.911478 -273.774918) (xy 341.860183 -273.783043)
			(xy 341.808249 -273.783043) (xy 341.756954 -273.774918) (xy 341.707561 -273.75887) (xy 341.661287 -273.735292)
			(xy 341.619271 -273.704766) (xy 341.582548 -273.668043) (xy 341.552022 -273.626027) (xy 341.528444 -273.579753)
			(xy 341.512396 -273.53036) (xy 341.504271 -273.479065) (xy 341.224361 -273.479065) (xy 341.216236 -273.53036)
			(xy 341.200188 -273.579753) (xy 341.17661 -273.626027) (xy 341.146084 -273.668043) (xy 341.109361 -273.704766)
			(xy 341.067345 -273.735292) (xy 341.021071 -273.75887) (xy 340.971678 -273.774918) (xy 340.920383 -273.783043)
			(xy 340.868449 -273.783043) (xy 340.817154 -273.774918) (xy 340.767761 -273.75887) (xy 340.721487 -273.735292)
			(xy 340.679471 -273.704766) (xy 340.642748 -273.668043) (xy 340.612222 -273.626027) (xy 340.588644 -273.579753)
			(xy 340.572596 -273.53036) (xy 340.564471 -273.479065) (xy 340.284801 -273.479065) (xy 340.284801 -273.479087)
			(xy 340.27667 -273.53042) (xy 340.26061 -273.579849) (xy 340.237016 -273.626158) (xy 340.206467 -273.668206)
			(xy 340.169718 -273.704957) (xy 340.127672 -273.735507) (xy 340.081364 -273.759104) (xy 340.031935 -273.775167)
			(xy 339.980603 -273.783299) (xy 339.954616 -273.783806) (xy 339.931701 -273.783416) (xy 339.886311 -273.777082)
			(xy 339.842232 -273.764534) (xy 339.800311 -273.746013) (xy 339.780626 -273.734276) (xy 339.780372 -273.734276)
			(xy 339.772615 -273.729878) (xy 339.755157 -273.726306) (xy 339.737542 -273.729006) (xy 339.729572 -273.733006)
			(xy 339.691218 -273.754596) (xy 339.65134 -273.776948) (xy 339.64424 -273.781704) (xy 339.633498 -273.79498)
			(xy 339.627804 -273.811081) (xy 339.627464 -273.81962) (xy 339.627464 -273.938746) (xy 339.651848 -273.981164)
			(xy 339.662516 -273.988022) (xy 339.683794 -274.002151) (xy 339.722126 -274.035904) (xy 339.754814 -274.075149)
			(xy 339.781081 -274.118952) (xy 339.800301 -274.166272) (xy 339.812019 -274.215985) (xy 339.815955 -274.266908)
			(xy 339.813946 -274.292881) (xy 340.094317 -274.292881) (xy 340.094317 -274.240947) (xy 340.102442 -274.189652)
			(xy 340.11849 -274.140259) (xy 340.142068 -274.093985) (xy 340.172594 -274.051969) (xy 340.209317 -274.015246)
			(xy 340.251333 -273.98472) (xy 340.297607 -273.961142) (xy 340.347 -273.945094) (xy 340.398295 -273.936969)
			(xy 340.450229 -273.936969) (xy 340.501524 -273.945094) (xy 340.550917 -273.961142) (xy 340.597191 -273.98472)
			(xy 340.639207 -274.015246) (xy 340.67593 -274.051969) (xy 340.706456 -274.093985) (xy 340.730034 -274.140259)
			(xy 340.746082 -274.189652) (xy 340.754207 -274.240947) (xy 340.754716 -274.266914) (xy 340.754207 -274.292881)
			(xy 341.034117 -274.292881) (xy 341.034117 -274.240947) (xy 341.042242 -274.189652) (xy 341.05829 -274.140259)
			(xy 341.081868 -274.093985) (xy 341.112394 -274.051969) (xy 341.149117 -274.015246) (xy 341.191133 -273.98472)
			(xy 341.237407 -273.961142) (xy 341.2868 -273.945094) (xy 341.338095 -273.936969) (xy 341.390029 -273.936969)
			(xy 341.441324 -273.945094) (xy 341.490717 -273.961142) (xy 341.536991 -273.98472) (xy 341.579007 -274.015246)
			(xy 341.61573 -274.051969) (xy 341.646256 -274.093985) (xy 341.669834 -274.140259) (xy 341.685882 -274.189652)
			(xy 341.694007 -274.240947) (xy 341.694516 -274.266914) (xy 341.694007 -274.292881) (xy 341.973917 -274.292881)
			(xy 341.973917 -274.240947) (xy 341.982042 -274.189652) (xy 341.99809 -274.140259) (xy 342.021668 -274.093985)
			(xy 342.052194 -274.051969) (xy 342.088917 -274.015246) (xy 342.130933 -273.98472) (xy 342.177207 -273.961142)
			(xy 342.2266 -273.945094) (xy 342.277895 -273.936969) (xy 342.329829 -273.936969) (xy 342.381124 -273.945094)
			(xy 342.430517 -273.961142) (xy 342.476791 -273.98472) (xy 342.518807 -274.015246) (xy 342.55553 -274.051969)
			(xy 342.586056 -274.093985) (xy 342.609634 -274.140259) (xy 342.625682 -274.189652) (xy 342.633807 -274.240947)
			(xy 342.634316 -274.266914) (xy 342.633807 -274.292881) (xy 342.913717 -274.292881) (xy 342.913717 -274.240947)
			(xy 342.921842 -274.189652) (xy 342.93789 -274.140259) (xy 342.961468 -274.093985) (xy 342.991994 -274.051969)
			(xy 343.028717 -274.015246) (xy 343.070733 -273.98472) (xy 343.117007 -273.961142) (xy 343.1664 -273.945094)
			(xy 343.217695 -273.936969) (xy 343.269629 -273.936969) (xy 343.320924 -273.945094) (xy 343.370317 -273.961142)
			(xy 343.416591 -273.98472) (xy 343.458607 -274.015246) (xy 343.49533 -274.051969) (xy 343.525856 -274.093985)
			(xy 343.549434 -274.140259) (xy 343.565482 -274.189652) (xy 343.573607 -274.240947) (xy 343.574116 -274.266914)
			(xy 343.573607 -274.292881) (xy 343.853517 -274.292881) (xy 343.853517 -274.240947) (xy 343.861642 -274.189652)
			(xy 343.87769 -274.140259) (xy 343.901268 -274.093985) (xy 343.931794 -274.051969) (xy 343.968517 -274.015246)
			(xy 344.010533 -273.98472) (xy 344.056807 -273.961142) (xy 344.1062 -273.945094) (xy 344.157495 -273.936969)
			(xy 344.209429 -273.936969) (xy 344.260724 -273.945094) (xy 344.310117 -273.961142) (xy 344.356391 -273.98472)
			(xy 344.398407 -274.015246) (xy 344.43513 -274.051969) (xy 344.465656 -274.093985) (xy 344.489234 -274.140259)
			(xy 344.505282 -274.189652) (xy 344.513407 -274.240947) (xy 344.513916 -274.266914) (xy 344.513407 -274.292881)
			(xy 344.793317 -274.292881) (xy 344.793317 -274.240947) (xy 344.801442 -274.189652) (xy 344.81749 -274.140259)
			(xy 344.841068 -274.093985) (xy 344.871594 -274.051969) (xy 344.908317 -274.015246) (xy 344.950333 -273.98472)
			(xy 344.996607 -273.961142) (xy 345.046 -273.945094) (xy 345.097295 -273.936969) (xy 345.149229 -273.936969)
			(xy 345.200524 -273.945094) (xy 345.249917 -273.961142) (xy 345.296191 -273.98472) (xy 345.338207 -274.015246)
			(xy 345.37493 -274.051969) (xy 345.405456 -274.093985) (xy 345.429034 -274.140259) (xy 345.445082 -274.189652)
			(xy 345.453207 -274.240947) (xy 345.453716 -274.266914) (xy 345.453207 -274.292881) (xy 345.733117 -274.292881)
			(xy 345.733117 -274.240947) (xy 345.741242 -274.189652) (xy 345.75729 -274.140259) (xy 345.780868 -274.093985)
			(xy 345.811394 -274.051969) (xy 345.848117 -274.015246) (xy 345.890133 -273.98472) (xy 345.936407 -273.961142)
			(xy 345.9858 -273.945094) (xy 346.037095 -273.936969) (xy 346.089029 -273.936969) (xy 346.140324 -273.945094)
			(xy 346.189717 -273.961142) (xy 346.235991 -273.98472) (xy 346.278007 -274.015246) (xy 346.31473 -274.051969)
			(xy 346.345256 -274.093985) (xy 346.368834 -274.140259) (xy 346.384882 -274.189652) (xy 346.393007 -274.240947)
			(xy 346.393516 -274.266914) (xy 346.393007 -274.292881) (xy 346.672917 -274.292881) (xy 346.672917 -274.240947)
			(xy 346.681042 -274.189652) (xy 346.69709 -274.140259) (xy 346.720668 -274.093985) (xy 346.751194 -274.051969)
			(xy 346.787917 -274.015246) (xy 346.829933 -273.98472) (xy 346.876207 -273.961142) (xy 346.9256 -273.945094)
			(xy 346.976895 -273.936969) (xy 347.028829 -273.936969) (xy 347.080124 -273.945094) (xy 347.129517 -273.961142)
			(xy 347.175791 -273.98472) (xy 347.217807 -274.015246) (xy 347.25453 -274.051969) (xy 347.285056 -274.093985)
			(xy 347.308634 -274.140259) (xy 347.324682 -274.189652) (xy 347.332807 -274.240947) (xy 347.333316 -274.266914)
			(xy 347.332807 -274.292881) (xy 347.612717 -274.292881) (xy 347.612717 -274.240947) (xy 347.620842 -274.189652)
			(xy 347.63689 -274.140259) (xy 347.660468 -274.093985) (xy 347.690994 -274.051969) (xy 347.727717 -274.015246)
			(xy 347.769733 -273.98472) (xy 347.816007 -273.961142) (xy 347.8654 -273.945094) (xy 347.916695 -273.936969)
			(xy 347.968629 -273.936969) (xy 348.019924 -273.945094) (xy 348.069317 -273.961142) (xy 348.115591 -273.98472)
			(xy 348.157607 -274.015246) (xy 348.19433 -274.051969) (xy 348.224856 -274.093985) (xy 348.248434 -274.140259)
			(xy 348.264482 -274.189652) (xy 348.272607 -274.240947) (xy 348.273116 -274.266914) (xy 348.272607 -274.292881)
			(xy 348.552517 -274.292881) (xy 348.552517 -274.240947) (xy 348.560642 -274.189652) (xy 348.57669 -274.140259)
			(xy 348.600268 -274.093985) (xy 348.630794 -274.051969) (xy 348.667517 -274.015246) (xy 348.709533 -273.98472)
			(xy 348.755807 -273.961142) (xy 348.8052 -273.945094) (xy 348.856495 -273.936969) (xy 348.908429 -273.936969)
			(xy 348.959724 -273.945094) (xy 349.009117 -273.961142) (xy 349.055391 -273.98472) (xy 349.097407 -274.015246)
			(xy 349.13413 -274.051969) (xy 349.164656 -274.093985) (xy 349.188234 -274.140259) (xy 349.204282 -274.189652)
			(xy 349.212407 -274.240947) (xy 349.212916 -274.266914) (xy 349.212407 -274.292881) (xy 349.492317 -274.292881)
			(xy 349.492317 -274.240947) (xy 349.500442 -274.189652) (xy 349.51649 -274.140259) (xy 349.540068 -274.093985)
			(xy 349.570594 -274.051969) (xy 349.607317 -274.015246) (xy 349.649333 -273.98472) (xy 349.695607 -273.961142)
			(xy 349.745 -273.945094) (xy 349.796295 -273.936969) (xy 349.848229 -273.936969) (xy 349.899524 -273.945094)
			(xy 349.948917 -273.961142) (xy 349.995191 -273.98472) (xy 350.037207 -274.015246) (xy 350.07393 -274.051969)
			(xy 350.104456 -274.093985) (xy 350.128034 -274.140259) (xy 350.144082 -274.189652) (xy 350.152207 -274.240947)
			(xy 350.152716 -274.266914) (xy 350.152207 -274.292881) (xy 350.432117 -274.292881) (xy 350.432117 -274.240947)
			(xy 350.440242 -274.189652) (xy 350.45629 -274.140259) (xy 350.479868 -274.093985) (xy 350.510394 -274.051969)
			(xy 350.547117 -274.015246) (xy 350.589133 -273.98472) (xy 350.635407 -273.961142) (xy 350.6848 -273.945094)
			(xy 350.736095 -273.936969) (xy 350.788029 -273.936969) (xy 350.839324 -273.945094) (xy 350.888717 -273.961142)
			(xy 350.934991 -273.98472) (xy 350.977007 -274.015246) (xy 351.01373 -274.051969) (xy 351.044256 -274.093985)
			(xy 351.067834 -274.140259) (xy 351.083882 -274.189652) (xy 351.092007 -274.240947) (xy 351.092516 -274.266914)
			(xy 351.371408 -274.266914) (xy 351.371917 -274.240947) (xy 351.380042 -274.189652) (xy 351.39609 -274.140259)
			(xy 351.419668 -274.093985) (xy 351.450194 -274.051969) (xy 351.486917 -274.015246) (xy 351.528933 -273.98472)
			(xy 351.575207 -273.961142) (xy 351.6246 -273.945094) (xy 351.675895 -273.936969) (xy 351.727829 -273.936969)
			(xy 351.779124 -273.945094) (xy 351.828517 -273.961142) (xy 351.874791 -273.98472) (xy 351.916807 -274.015246)
			(xy 351.95353 -274.051969) (xy 351.984056 -274.093985) (xy 352.007634 -274.140259) (xy 352.023682 -274.189652)
			(xy 352.031807 -274.240947) (xy 352.032316 -274.266914) (xy 352.032316 -274.267168) (xy 352.031773 -274.292881)
			(xy 352.311717 -274.292881) (xy 352.311717 -274.240947) (xy 352.319842 -274.189652) (xy 352.33589 -274.140259)
			(xy 352.359468 -274.093985) (xy 352.389994 -274.051969) (xy 352.426717 -274.015246) (xy 352.468733 -273.98472)
			(xy 352.515007 -273.961142) (xy 352.5644 -273.945094) (xy 352.615695 -273.936969) (xy 352.667629 -273.936969)
			(xy 352.718924 -273.945094) (xy 352.768317 -273.961142) (xy 352.814591 -273.98472) (xy 352.856607 -274.015246)
			(xy 352.89333 -274.051969) (xy 352.923856 -274.093985) (xy 352.947434 -274.140259) (xy 352.963482 -274.189652)
			(xy 352.971607 -274.240947) (xy 352.972116 -274.266914) (xy 352.971607 -274.292881) (xy 354.191317 -274.292881)
			(xy 354.191317 -274.240947) (xy 354.199442 -274.189652) (xy 354.21549 -274.140259) (xy 354.239068 -274.093985)
			(xy 354.269594 -274.051969) (xy 354.306317 -274.015246) (xy 354.348333 -273.98472) (xy 354.394607 -273.961142)
			(xy 354.444 -273.945094) (xy 354.495295 -273.936969) (xy 354.547229 -273.936969) (xy 354.598524 -273.945094)
			(xy 354.647917 -273.961142) (xy 354.694191 -273.98472) (xy 354.736207 -274.015246) (xy 354.77293 -274.051969)
			(xy 354.803456 -274.093985) (xy 354.827034 -274.140259) (xy 354.843082 -274.189652) (xy 354.851207 -274.240947)
			(xy 354.851716 -274.266914) (xy 354.851207 -274.292881) (xy 356.071171 -274.292881) (xy 356.071171 -274.240947)
			(xy 356.079296 -274.189652) (xy 356.095344 -274.140259) (xy 356.118922 -274.093985) (xy 356.149448 -274.051969)
			(xy 356.186171 -274.015246) (xy 356.228187 -273.98472) (xy 356.274461 -273.961142) (xy 356.323854 -273.945094)
			(xy 356.375149 -273.936969) (xy 356.427083 -273.936969) (xy 356.478378 -273.945094) (xy 356.527771 -273.961142)
			(xy 356.574045 -273.98472) (xy 356.616061 -274.015246) (xy 356.652784 -274.051969) (xy 356.68331 -274.093985)
			(xy 356.706888 -274.140259) (xy 356.722936 -274.189652) (xy 356.731061 -274.240947) (xy 356.73157 -274.266914)
			(xy 356.731061 -274.292881) (xy 356.722936 -274.344176) (xy 356.706888 -274.393569) (xy 356.68331 -274.439843)
			(xy 356.652784 -274.481859) (xy 356.616061 -274.518582) (xy 356.574045 -274.549108) (xy 356.527771 -274.572686)
			(xy 356.478378 -274.588734) (xy 356.427083 -274.596859) (xy 356.375149 -274.596859) (xy 356.323854 -274.588734)
			(xy 356.274461 -274.572686) (xy 356.228187 -274.549108) (xy 356.186171 -274.518582) (xy 356.149448 -274.481859)
			(xy 356.118922 -274.439843) (xy 356.095344 -274.393569) (xy 356.079296 -274.344176) (xy 356.071171 -274.292881)
			(xy 354.851207 -274.292881) (xy 354.843082 -274.344176) (xy 354.827034 -274.393569) (xy 354.803456 -274.439843)
			(xy 354.77293 -274.481859) (xy 354.736207 -274.518582) (xy 354.694191 -274.549108) (xy 354.647917 -274.572686)
			(xy 354.598524 -274.588734) (xy 354.547229 -274.596859) (xy 354.495295 -274.596859) (xy 354.444 -274.588734)
			(xy 354.394607 -274.572686) (xy 354.348333 -274.549108) (xy 354.306317 -274.518582) (xy 354.269594 -274.481859)
			(xy 354.239068 -274.439843) (xy 354.21549 -274.393569) (xy 354.199442 -274.344176) (xy 354.191317 -274.292881)
			(xy 352.971607 -274.292881) (xy 352.963482 -274.344176) (xy 352.947434 -274.393569) (xy 352.923856 -274.439843)
			(xy 352.89333 -274.481859) (xy 352.856607 -274.518582) (xy 352.814591 -274.549108) (xy 352.768317 -274.572686)
			(xy 352.718924 -274.588734) (xy 352.667629 -274.596859) (xy 352.615695 -274.596859) (xy 352.5644 -274.588734)
			(xy 352.515007 -274.572686) (xy 352.468733 -274.549108) (xy 352.426717 -274.518582) (xy 352.389994 -274.481859)
			(xy 352.359468 -274.439843) (xy 352.33589 -274.393569) (xy 352.319842 -274.344176) (xy 352.311717 -274.292881)
			(xy 352.031773 -274.292881) (xy 352.031729 -274.294949) (xy 352.022415 -274.349725) (xy 352.013774 -274.376134)
			(xy 352.0059 -274.398232) (xy 352.209862 -274.751546) (xy 352.232976 -274.755864) (xy 352.257903 -274.761008)
			(xy 352.305887 -274.777977) (xy 352.350704 -274.802099) (xy 352.391295 -274.832803) (xy 352.426703 -274.869364)
			(xy 352.456091 -274.910919) (xy 352.478764 -274.956486) (xy 352.494187 -275.004989) (xy 352.501996 -275.055282)
			(xy 352.50247 -275.08073) (xy 352.501961 -275.106697) (xy 352.493836 -275.157992) (xy 352.477788 -275.207385)
			(xy 352.45421 -275.253659) (xy 352.423684 -275.295675) (xy 352.386961 -275.332398) (xy 352.344945 -275.362924)
			(xy 352.298671 -275.386502) (xy 352.249278 -275.40255) (xy 352.197983 -275.410675) (xy 352.146049 -275.410675)
			(xy 352.094754 -275.40255) (xy 352.045361 -275.386502) (xy 351.999087 -275.362924) (xy 351.957071 -275.332398)
			(xy 351.920348 -275.295675) (xy 351.889822 -275.253659) (xy 351.866244 -275.207385) (xy 351.850196 -275.157992)
			(xy 351.842071 -275.106697) (xy 351.841562 -275.08073) (xy 351.842119 -275.052744) (xy 351.851566 -274.997576)
			(xy 351.860358 -274.971002) (xy 351.867978 -274.948904) (xy 351.66427 -274.596098) (xy 351.64141 -274.59178)
			(xy 351.616463 -274.58661) (xy 351.568399 -274.569722) (xy 351.523497 -274.545656) (xy 351.482822 -274.514983)
			(xy 351.447337 -274.478431) (xy 351.417883 -274.436864) (xy 351.395158 -274.391269) (xy 351.379702 -274.342726)
			(xy 351.37188 -274.292386) (xy 351.371408 -274.266914) (xy 351.092516 -274.266914) (xy 351.092007 -274.292881)
			(xy 351.083882 -274.344176) (xy 351.067834 -274.393569) (xy 351.044256 -274.439843) (xy 351.01373 -274.481859)
			(xy 350.977007 -274.518582) (xy 350.934991 -274.549108) (xy 350.888717 -274.572686) (xy 350.839324 -274.588734)
			(xy 350.788029 -274.596859) (xy 350.736095 -274.596859) (xy 350.6848 -274.588734) (xy 350.635407 -274.572686)
			(xy 350.589133 -274.549108) (xy 350.547117 -274.518582) (xy 350.510394 -274.481859) (xy 350.479868 -274.439843)
			(xy 350.45629 -274.393569) (xy 350.440242 -274.344176) (xy 350.432117 -274.292881) (xy 350.152207 -274.292881)
			(xy 350.144082 -274.344176) (xy 350.128034 -274.393569) (xy 350.104456 -274.439843) (xy 350.07393 -274.481859)
			(xy 350.037207 -274.518582) (xy 349.995191 -274.549108) (xy 349.948917 -274.572686) (xy 349.899524 -274.588734)
			(xy 349.848229 -274.596859) (xy 349.796295 -274.596859) (xy 349.745 -274.588734) (xy 349.695607 -274.572686)
			(xy 349.649333 -274.549108) (xy 349.607317 -274.518582) (xy 349.570594 -274.481859) (xy 349.540068 -274.439843)
			(xy 349.51649 -274.393569) (xy 349.500442 -274.344176) (xy 349.492317 -274.292881) (xy 349.212407 -274.292881)
			(xy 349.204282 -274.344176) (xy 349.188234 -274.393569) (xy 349.164656 -274.439843) (xy 349.13413 -274.481859)
			(xy 349.097407 -274.518582) (xy 349.055391 -274.549108) (xy 349.009117 -274.572686) (xy 348.959724 -274.588734)
			(xy 348.908429 -274.596859) (xy 348.856495 -274.596859) (xy 348.8052 -274.588734) (xy 348.755807 -274.572686)
			(xy 348.709533 -274.549108) (xy 348.667517 -274.518582) (xy 348.630794 -274.481859) (xy 348.600268 -274.439843)
			(xy 348.57669 -274.393569) (xy 348.560642 -274.344176) (xy 348.552517 -274.292881) (xy 348.272607 -274.292881)
			(xy 348.264482 -274.344176) (xy 348.248434 -274.393569) (xy 348.224856 -274.439843) (xy 348.19433 -274.481859)
			(xy 348.157607 -274.518582) (xy 348.115591 -274.549108) (xy 348.069317 -274.572686) (xy 348.019924 -274.588734)
			(xy 347.968629 -274.596859) (xy 347.916695 -274.596859) (xy 347.8654 -274.588734) (xy 347.816007 -274.572686)
			(xy 347.769733 -274.549108) (xy 347.727717 -274.518582) (xy 347.690994 -274.481859) (xy 347.660468 -274.439843)
			(xy 347.63689 -274.393569) (xy 347.620842 -274.344176) (xy 347.612717 -274.292881) (xy 347.332807 -274.292881)
			(xy 347.324682 -274.344176) (xy 347.308634 -274.393569) (xy 347.285056 -274.439843) (xy 347.25453 -274.481859)
			(xy 347.217807 -274.518582) (xy 347.175791 -274.549108) (xy 347.129517 -274.572686) (xy 347.080124 -274.588734)
			(xy 347.028829 -274.596859) (xy 346.976895 -274.596859) (xy 346.9256 -274.588734) (xy 346.876207 -274.572686)
			(xy 346.829933 -274.549108) (xy 346.787917 -274.518582) (xy 346.751194 -274.481859) (xy 346.720668 -274.439843)
			(xy 346.69709 -274.393569) (xy 346.681042 -274.344176) (xy 346.672917 -274.292881) (xy 346.393007 -274.292881)
			(xy 346.384882 -274.344176) (xy 346.368834 -274.393569) (xy 346.345256 -274.439843) (xy 346.31473 -274.481859)
			(xy 346.278007 -274.518582) (xy 346.235991 -274.549108) (xy 346.189717 -274.572686) (xy 346.140324 -274.588734)
			(xy 346.089029 -274.596859) (xy 346.037095 -274.596859) (xy 345.9858 -274.588734) (xy 345.936407 -274.572686)
			(xy 345.890133 -274.549108) (xy 345.848117 -274.518582) (xy 345.811394 -274.481859) (xy 345.780868 -274.439843)
			(xy 345.75729 -274.393569) (xy 345.741242 -274.344176) (xy 345.733117 -274.292881) (xy 345.453207 -274.292881)
			(xy 345.445082 -274.344176) (xy 345.429034 -274.393569) (xy 345.405456 -274.439843) (xy 345.37493 -274.481859)
			(xy 345.338207 -274.518582) (xy 345.296191 -274.549108) (xy 345.249917 -274.572686) (xy 345.200524 -274.588734)
			(xy 345.149229 -274.596859) (xy 345.097295 -274.596859) (xy 345.046 -274.588734) (xy 344.996607 -274.572686)
			(xy 344.950333 -274.549108) (xy 344.908317 -274.518582) (xy 344.871594 -274.481859) (xy 344.841068 -274.439843)
			(xy 344.81749 -274.393569) (xy 344.801442 -274.344176) (xy 344.793317 -274.292881) (xy 344.513407 -274.292881)
			(xy 344.505282 -274.344176) (xy 344.489234 -274.393569) (xy 344.465656 -274.439843) (xy 344.43513 -274.481859)
			(xy 344.398407 -274.518582) (xy 344.356391 -274.549108) (xy 344.310117 -274.572686) (xy 344.260724 -274.588734)
			(xy 344.209429 -274.596859) (xy 344.157495 -274.596859) (xy 344.1062 -274.588734) (xy 344.056807 -274.572686)
			(xy 344.010533 -274.549108) (xy 343.968517 -274.518582) (xy 343.931794 -274.481859) (xy 343.901268 -274.439843)
			(xy 343.87769 -274.393569) (xy 343.861642 -274.344176) (xy 343.853517 -274.292881) (xy 343.573607 -274.292881)
			(xy 343.565482 -274.344176) (xy 343.549434 -274.393569) (xy 343.525856 -274.439843) (xy 343.49533 -274.481859)
			(xy 343.458607 -274.518582) (xy 343.416591 -274.549108) (xy 343.370317 -274.572686) (xy 343.320924 -274.588734)
			(xy 343.269629 -274.596859) (xy 343.217695 -274.596859) (xy 343.1664 -274.588734) (xy 343.117007 -274.572686)
			(xy 343.070733 -274.549108) (xy 343.028717 -274.518582) (xy 342.991994 -274.481859) (xy 342.961468 -274.439843)
			(xy 342.93789 -274.393569) (xy 342.921842 -274.344176) (xy 342.913717 -274.292881) (xy 342.633807 -274.292881)
			(xy 342.625682 -274.344176) (xy 342.609634 -274.393569) (xy 342.586056 -274.439843) (xy 342.55553 -274.481859)
			(xy 342.518807 -274.518582) (xy 342.476791 -274.549108) (xy 342.430517 -274.572686) (xy 342.381124 -274.588734)
			(xy 342.329829 -274.596859) (xy 342.277895 -274.596859) (xy 342.2266 -274.588734) (xy 342.177207 -274.572686)
			(xy 342.130933 -274.549108) (xy 342.088917 -274.518582) (xy 342.052194 -274.481859) (xy 342.021668 -274.439843)
			(xy 341.99809 -274.393569) (xy 341.982042 -274.344176) (xy 341.973917 -274.292881) (xy 341.694007 -274.292881)
			(xy 341.685882 -274.344176) (xy 341.669834 -274.393569) (xy 341.646256 -274.439843) (xy 341.61573 -274.481859)
			(xy 341.579007 -274.518582) (xy 341.536991 -274.549108) (xy 341.490717 -274.572686) (xy 341.441324 -274.588734)
			(xy 341.390029 -274.596859) (xy 341.338095 -274.596859) (xy 341.2868 -274.588734) (xy 341.237407 -274.572686)
			(xy 341.191133 -274.549108) (xy 341.149117 -274.518582) (xy 341.112394 -274.481859) (xy 341.081868 -274.439843)
			(xy 341.05829 -274.393569) (xy 341.042242 -274.344176) (xy 341.034117 -274.292881) (xy 340.754207 -274.292881)
			(xy 340.746082 -274.344176) (xy 340.730034 -274.393569) (xy 340.706456 -274.439843) (xy 340.67593 -274.481859)
			(xy 340.639207 -274.518582) (xy 340.597191 -274.549108) (xy 340.550917 -274.572686) (xy 340.501524 -274.588734)
			(xy 340.450229 -274.596859) (xy 340.398295 -274.596859) (xy 340.347 -274.588734) (xy 340.297607 -274.572686)
			(xy 340.251333 -274.549108) (xy 340.209317 -274.518582) (xy 340.172594 -274.481859) (xy 340.142068 -274.439843)
			(xy 340.11849 -274.393569) (xy 340.102442 -274.344176) (xy 340.094317 -274.292881) (xy 339.813946 -274.292881)
			(xy 339.812017 -274.31783) (xy 339.800297 -274.367542) (xy 339.781074 -274.414862) (xy 339.754805 -274.458663)
			(xy 339.722116 -274.497906) (xy 339.683782 -274.531658) (xy 339.662516 -274.545806) (xy 339.651848 -274.552664)
			(xy 339.627464 -274.595082) (xy 339.627464 -274.713954) (xy 339.627773 -274.722344) (xy 339.633264 -274.738199)
			(xy 339.643654 -274.751374) (xy 339.650578 -274.756118) (xy 339.718142 -274.793964) (xy 339.723391 -274.796451)
			(xy 339.734687 -274.799147) (xy 339.740494 -274.799298) (xy 339.767418 -274.799298) (xy 339.772591 -274.799145)
			(xy 339.782708 -274.796972) (xy 339.787484 -274.79498) (xy 339.791548 -274.792694) (xy 339.816482 -274.779299)
			(xy 339.869791 -274.760291) (xy 339.925556 -274.750625) (xy 339.953854 -274.750022) (xy 339.954362 -274.750022)
			(xy 339.980351 -274.750502) (xy 340.031689 -274.758628) (xy 340.081125 -274.774685) (xy 340.127439 -274.798279)
			(xy 340.169492 -274.828828) (xy 340.206247 -274.865579) (xy 340.236801 -274.907629) (xy 340.2604 -274.95394)
			(xy 340.276463 -275.003374) (xy 340.284595 -275.054711) (xy 340.284595 -275.106689) (xy 340.284594 -275.106697)
			(xy 340.564471 -275.106697) (xy 340.564471 -275.054763) (xy 340.572596 -275.003468) (xy 340.588644 -274.954075)
			(xy 340.612222 -274.907801) (xy 340.642748 -274.865785) (xy 340.679471 -274.829062) (xy 340.721487 -274.798536)
			(xy 340.767761 -274.774958) (xy 340.817154 -274.75891) (xy 340.868449 -274.750785) (xy 340.920383 -274.750785)
			(xy 340.971678 -274.75891) (xy 341.021071 -274.774958) (xy 341.067345 -274.798536) (xy 341.109361 -274.829062)
			(xy 341.146084 -274.865785) (xy 341.17661 -274.907801) (xy 341.200188 -274.954075) (xy 341.216236 -275.003468)
			(xy 341.224361 -275.054763) (xy 341.22487 -275.08073) (xy 341.224361 -275.106697) (xy 341.504271 -275.106697)
			(xy 341.504271 -275.054763) (xy 341.512396 -275.003468) (xy 341.528444 -274.954075) (xy 341.552022 -274.907801)
			(xy 341.582548 -274.865785) (xy 341.619271 -274.829062) (xy 341.661287 -274.798536) (xy 341.707561 -274.774958)
			(xy 341.756954 -274.75891) (xy 341.808249 -274.750785) (xy 341.860183 -274.750785) (xy 341.911478 -274.75891)
			(xy 341.960871 -274.774958) (xy 342.007145 -274.798536) (xy 342.049161 -274.829062) (xy 342.085884 -274.865785)
			(xy 342.11641 -274.907801) (xy 342.139988 -274.954075) (xy 342.156036 -275.003468) (xy 342.164161 -275.054763)
			(xy 342.16467 -275.08073) (xy 342.164161 -275.106697) (xy 342.444071 -275.106697) (xy 342.444071 -275.054763)
			(xy 342.452196 -275.003468) (xy 342.468244 -274.954075) (xy 342.491822 -274.907801) (xy 342.522348 -274.865785)
			(xy 342.559071 -274.829062) (xy 342.601087 -274.798536) (xy 342.647361 -274.774958) (xy 342.696754 -274.75891)
			(xy 342.748049 -274.750785) (xy 342.799983 -274.750785) (xy 342.851278 -274.75891) (xy 342.900671 -274.774958)
			(xy 342.946945 -274.798536) (xy 342.988961 -274.829062) (xy 343.025684 -274.865785) (xy 343.05621 -274.907801)
			(xy 343.079788 -274.954075) (xy 343.095836 -275.003468) (xy 343.103961 -275.054763) (xy 343.10447 -275.08073)
			(xy 343.103961 -275.106697) (xy 343.383871 -275.106697) (xy 343.383871 -275.054763) (xy 343.391996 -275.003468)
			(xy 343.408044 -274.954075) (xy 343.431622 -274.907801) (xy 343.462148 -274.865785) (xy 343.498871 -274.829062)
			(xy 343.540887 -274.798536) (xy 343.587161 -274.774958) (xy 343.636554 -274.75891) (xy 343.687849 -274.750785)
			(xy 343.739783 -274.750785) (xy 343.791078 -274.75891) (xy 343.840471 -274.774958) (xy 343.886745 -274.798536)
			(xy 343.928761 -274.829062) (xy 343.965484 -274.865785) (xy 343.99601 -274.907801) (xy 344.019588 -274.954075)
			(xy 344.035636 -275.003468) (xy 344.043761 -275.054763) (xy 344.04427 -275.08073) (xy 344.043761 -275.106697)
			(xy 344.323671 -275.106697) (xy 344.323671 -275.054763) (xy 344.331796 -275.003468) (xy 344.347844 -274.954075)
			(xy 344.371422 -274.907801) (xy 344.401948 -274.865785) (xy 344.438671 -274.829062) (xy 344.480687 -274.798536)
			(xy 344.526961 -274.774958) (xy 344.576354 -274.75891) (xy 344.627649 -274.750785) (xy 344.679583 -274.750785)
			(xy 344.730878 -274.75891) (xy 344.780271 -274.774958) (xy 344.826545 -274.798536) (xy 344.868561 -274.829062)
			(xy 344.905284 -274.865785) (xy 344.93581 -274.907801) (xy 344.959388 -274.954075) (xy 344.975436 -275.003468)
			(xy 344.983561 -275.054763) (xy 344.98407 -275.08073) (xy 344.983561 -275.106697) (xy 345.263471 -275.106697)
			(xy 345.263471 -275.054763) (xy 345.271596 -275.003468) (xy 345.287644 -274.954075) (xy 345.311222 -274.907801)
			(xy 345.341748 -274.865785) (xy 345.378471 -274.829062) (xy 345.420487 -274.798536) (xy 345.466761 -274.774958)
			(xy 345.516154 -274.75891) (xy 345.567449 -274.750785) (xy 345.619383 -274.750785) (xy 345.670678 -274.75891)
			(xy 345.720071 -274.774958) (xy 345.766345 -274.798536) (xy 345.808361 -274.829062) (xy 345.845084 -274.865785)
			(xy 345.87561 -274.907801) (xy 345.899188 -274.954075) (xy 345.915236 -275.003468) (xy 345.923361 -275.054763)
			(xy 345.92387 -275.08073) (xy 345.923361 -275.106697) (xy 346.203017 -275.106697) (xy 346.203017 -275.054763)
			(xy 346.211142 -275.003468) (xy 346.22719 -274.954075) (xy 346.250768 -274.907801) (xy 346.281294 -274.865785)
			(xy 346.318017 -274.829062) (xy 346.360033 -274.798536) (xy 346.406307 -274.774958) (xy 346.4557 -274.75891)
			(xy 346.506995 -274.750785) (xy 346.558929 -274.750785) (xy 346.610224 -274.75891) (xy 346.659617 -274.774958)
			(xy 346.705891 -274.798536) (xy 346.747907 -274.829062) (xy 346.78463 -274.865785) (xy 346.815156 -274.907801)
			(xy 346.838734 -274.954075) (xy 346.854782 -275.003468) (xy 346.862907 -275.054763) (xy 346.863416 -275.08073)
			(xy 346.862907 -275.106697) (xy 347.143071 -275.106697) (xy 347.143071 -275.054763) (xy 347.151196 -275.003468)
			(xy 347.167244 -274.954075) (xy 347.190822 -274.907801) (xy 347.221348 -274.865785) (xy 347.258071 -274.829062)
			(xy 347.300087 -274.798536) (xy 347.346361 -274.774958) (xy 347.395754 -274.75891) (xy 347.447049 -274.750785)
			(xy 347.498983 -274.750785) (xy 347.550278 -274.75891) (xy 347.599671 -274.774958) (xy 347.645945 -274.798536)
			(xy 347.687961 -274.829062) (xy 347.724684 -274.865785) (xy 347.75521 -274.907801) (xy 347.778788 -274.954075)
			(xy 347.794836 -275.003468) (xy 347.802961 -275.054763) (xy 347.80347 -275.08073) (xy 347.802961 -275.106697)
			(xy 348.082871 -275.106697) (xy 348.082871 -275.054763) (xy 348.090996 -275.003468) (xy 348.107044 -274.954075)
			(xy 348.130622 -274.907801) (xy 348.161148 -274.865785) (xy 348.197871 -274.829062) (xy 348.239887 -274.798536)
			(xy 348.286161 -274.774958) (xy 348.335554 -274.75891) (xy 348.386849 -274.750785) (xy 348.438783 -274.750785)
			(xy 348.490078 -274.75891) (xy 348.539471 -274.774958) (xy 348.585745 -274.798536) (xy 348.627761 -274.829062)
			(xy 348.664484 -274.865785) (xy 348.69501 -274.907801) (xy 348.718588 -274.954075) (xy 348.734636 -275.003468)
			(xy 348.742761 -275.054763) (xy 348.74327 -275.08073) (xy 348.742762 -275.106668) (xy 349.962459 -275.106668)
			(xy 349.962459 -275.054732) (xy 349.970584 -275.003436) (xy 349.986633 -274.954043) (xy 350.010212 -274.907768)
			(xy 350.04074 -274.865752) (xy 350.077464 -274.829029) (xy 350.119482 -274.798503) (xy 350.165758 -274.774927)
			(xy 350.215152 -274.75888) (xy 350.266448 -274.750758) (xy 350.292416 -274.750276) (xy 350.318052 -274.750756)
			(xy 350.368707 -274.758683) (xy 350.417529 -274.774344) (xy 350.463343 -274.797362) (xy 350.50505 -274.827184)
			(xy 350.541646 -274.863094) (xy 350.557338 -274.883372) (xy 350.967294 -274.883372) (xy 350.982971 -274.863082)
			(xy 351.019571 -274.827174) (xy 351.06128 -274.797354) (xy 351.107098 -274.774339) (xy 351.155922 -274.758682)
			(xy 351.206579 -274.750759) (xy 351.232216 -274.750276) (xy 351.258185 -274.750727) (xy 351.309482 -274.758854)
			(xy 351.358877 -274.774905) (xy 351.405153 -274.798486) (xy 351.447171 -274.829015) (xy 351.483895 -274.865741)
			(xy 351.514423 -274.90776) (xy 351.538001 -274.954037) (xy 351.55405 -275.003433) (xy 351.562175 -275.054731)
			(xy 351.562175 -275.106669) (xy 351.55405 -275.157967) (xy 351.538001 -275.207363) (xy 351.514423 -275.25364)
			(xy 351.483895 -275.295659) (xy 351.447171 -275.332385) (xy 351.405153 -275.362914) (xy 351.358877 -275.386495)
			(xy 351.309482 -275.402546) (xy 351.258185 -275.410673) (xy 351.232216 -275.411184) (xy 351.20658 -275.410697)
			(xy 351.155924 -275.402774) (xy 351.107102 -275.387116) (xy 351.061287 -275.364099) (xy 351.019581 -275.334277)
			(xy 350.982985 -275.298367) (xy 350.967294 -275.278088) (xy 350.557338 -275.278088) (xy 350.541631 -275.298354)
			(xy 350.505039 -275.334266) (xy 350.463336 -275.36409) (xy 350.417524 -275.387109) (xy 350.368705 -275.402771)
			(xy 350.318051 -275.410698) (xy 350.292416 -275.411184) (xy 350.266448 -275.410642) (xy 350.215152 -275.40252)
			(xy 350.165758 -275.386473) (xy 350.119482 -275.362897) (xy 350.077464 -275.332371) (xy 350.04074 -275.295648)
			(xy 350.010212 -275.253632) (xy 349.986633 -275.207357) (xy 349.970584 -275.157964) (xy 349.962459 -275.106668)
			(xy 348.742762 -275.106668) (xy 348.742761 -275.106697) (xy 348.734636 -275.157992) (xy 348.718588 -275.207385)
			(xy 348.69501 -275.253659) (xy 348.664484 -275.295675) (xy 348.627761 -275.332398) (xy 348.585745 -275.362924)
			(xy 348.539471 -275.386502) (xy 348.490078 -275.40255) (xy 348.438783 -275.410675) (xy 348.386849 -275.410675)
			(xy 348.335554 -275.40255) (xy 348.286161 -275.386502) (xy 348.239887 -275.362924) (xy 348.197871 -275.332398)
			(xy 348.161148 -275.295675) (xy 348.130622 -275.253659) (xy 348.107044 -275.207385) (xy 348.090996 -275.157992)
			(xy 348.082871 -275.106697) (xy 347.802961 -275.106697) (xy 347.794836 -275.157992) (xy 347.778788 -275.207385)
			(xy 347.75521 -275.253659) (xy 347.724684 -275.295675) (xy 347.687961 -275.332398) (xy 347.645945 -275.362924)
			(xy 347.599671 -275.386502) (xy 347.550278 -275.40255) (xy 347.498983 -275.410675) (xy 347.447049 -275.410675)
			(xy 347.395754 -275.40255) (xy 347.346361 -275.386502) (xy 347.300087 -275.362924) (xy 347.258071 -275.332398)
			(xy 347.221348 -275.295675) (xy 347.190822 -275.253659) (xy 347.167244 -275.207385) (xy 347.151196 -275.157992)
			(xy 347.143071 -275.106697) (xy 346.862907 -275.106697) (xy 346.854782 -275.157992) (xy 346.838734 -275.207385)
			(xy 346.815156 -275.253659) (xy 346.78463 -275.295675) (xy 346.747907 -275.332398) (xy 346.705891 -275.362924)
			(xy 346.659617 -275.386502) (xy 346.610224 -275.40255) (xy 346.558929 -275.410675) (xy 346.506995 -275.410675)
			(xy 346.4557 -275.40255) (xy 346.406307 -275.386502) (xy 346.360033 -275.362924) (xy 346.318017 -275.332398)
			(xy 346.281294 -275.295675) (xy 346.250768 -275.253659) (xy 346.22719 -275.207385) (xy 346.211142 -275.157992)
			(xy 346.203017 -275.106697) (xy 345.923361 -275.106697) (xy 345.915236 -275.157992) (xy 345.899188 -275.207385)
			(xy 345.87561 -275.253659) (xy 345.845084 -275.295675) (xy 345.808361 -275.332398) (xy 345.766345 -275.362924)
			(xy 345.720071 -275.386502) (xy 345.670678 -275.40255) (xy 345.619383 -275.410675) (xy 345.567449 -275.410675)
			(xy 345.516154 -275.40255) (xy 345.466761 -275.386502) (xy 345.420487 -275.362924) (xy 345.378471 -275.332398)
			(xy 345.341748 -275.295675) (xy 345.311222 -275.253659) (xy 345.287644 -275.207385) (xy 345.271596 -275.157992)
			(xy 345.263471 -275.106697) (xy 344.983561 -275.106697) (xy 344.975436 -275.157992) (xy 344.959388 -275.207385)
			(xy 344.93581 -275.253659) (xy 344.905284 -275.295675) (xy 344.868561 -275.332398) (xy 344.826545 -275.362924)
			(xy 344.780271 -275.386502) (xy 344.730878 -275.40255) (xy 344.679583 -275.410675) (xy 344.627649 -275.410675)
			(xy 344.576354 -275.40255) (xy 344.526961 -275.386502) (xy 344.480687 -275.362924) (xy 344.438671 -275.332398)
			(xy 344.401948 -275.295675) (xy 344.371422 -275.253659) (xy 344.347844 -275.207385) (xy 344.331796 -275.157992)
			(xy 344.323671 -275.106697) (xy 344.043761 -275.106697) (xy 344.035636 -275.157992) (xy 344.019588 -275.207385)
			(xy 343.99601 -275.253659) (xy 343.965484 -275.295675) (xy 343.928761 -275.332398) (xy 343.886745 -275.362924)
			(xy 343.840471 -275.386502) (xy 343.791078 -275.40255) (xy 343.739783 -275.410675) (xy 343.687849 -275.410675)
			(xy 343.636554 -275.40255) (xy 343.587161 -275.386502) (xy 343.540887 -275.362924) (xy 343.498871 -275.332398)
			(xy 343.462148 -275.295675) (xy 343.431622 -275.253659) (xy 343.408044 -275.207385) (xy 343.391996 -275.157992)
			(xy 343.383871 -275.106697) (xy 343.103961 -275.106697) (xy 343.095836 -275.157992) (xy 343.079788 -275.207385)
			(xy 343.05621 -275.253659) (xy 343.025684 -275.295675) (xy 342.988961 -275.332398) (xy 342.946945 -275.362924)
			(xy 342.900671 -275.386502) (xy 342.851278 -275.40255) (xy 342.799983 -275.410675) (xy 342.748049 -275.410675)
			(xy 342.696754 -275.40255) (xy 342.647361 -275.386502) (xy 342.601087 -275.362924) (xy 342.559071 -275.332398)
			(xy 342.522348 -275.295675) (xy 342.491822 -275.253659) (xy 342.468244 -275.207385) (xy 342.452196 -275.157992)
			(xy 342.444071 -275.106697) (xy 342.164161 -275.106697) (xy 342.156036 -275.157992) (xy 342.139988 -275.207385)
			(xy 342.11641 -275.253659) (xy 342.085884 -275.295675) (xy 342.049161 -275.332398) (xy 342.007145 -275.362924)
			(xy 341.960871 -275.386502) (xy 341.911478 -275.40255) (xy 341.860183 -275.410675) (xy 341.808249 -275.410675)
			(xy 341.756954 -275.40255) (xy 341.707561 -275.386502) (xy 341.661287 -275.362924) (xy 341.619271 -275.332398)
			(xy 341.582548 -275.295675) (xy 341.552022 -275.253659) (xy 341.528444 -275.207385) (xy 341.512396 -275.157992)
			(xy 341.504271 -275.106697) (xy 341.224361 -275.106697) (xy 341.216236 -275.157992) (xy 341.200188 -275.207385)
			(xy 341.17661 -275.253659) (xy 341.146084 -275.295675) (xy 341.109361 -275.332398) (xy 341.067345 -275.362924)
			(xy 341.021071 -275.386502) (xy 340.971678 -275.40255) (xy 340.920383 -275.410675) (xy 340.868449 -275.410675)
			(xy 340.817154 -275.40255) (xy 340.767761 -275.386502) (xy 340.721487 -275.362924) (xy 340.679471 -275.332398)
			(xy 340.642748 -275.295675) (xy 340.612222 -275.253659) (xy 340.588644 -275.207385) (xy 340.572596 -275.157992)
			(xy 340.564471 -275.106697) (xy 340.284594 -275.106697) (xy 340.276463 -275.158026) (xy 340.2604 -275.20746)
			(xy 340.236801 -275.253771) (xy 340.206248 -275.295821) (xy 340.169492 -275.332572) (xy 340.127439 -275.363121)
			(xy 340.081125 -275.386715) (xy 340.031689 -275.402772) (xy 339.980351 -275.410898) (xy 339.954362 -275.411438)
			(xy 339.954108 -275.411438) (xy 339.942896 -275.411348) (xy 339.920524 -275.409824) (xy 339.909404 -275.40839)
			(xy 339.905848 -275.407882) (xy 339.904324 -275.407882) (xy 339.873081 -275.402379) (xy 339.813352 -275.381024)
			(xy 339.785706 -275.365464) (xy 339.780118 -275.362162) (xy 339.75421 -275.354796) (xy 339.748194 -275.354919)
			(xy 339.736498 -275.357735) (xy 339.731096 -275.360384) (xy 339.709506 -275.372322) (xy 339.653118 -275.403818)
			(xy 339.645534 -275.408457) (xy 339.633983 -275.421957) (xy 339.627828 -275.438623) (xy 339.627464 -275.447506)
			(xy 339.627464 -275.566632) (xy 339.651848 -275.609304) (xy 339.662516 -275.616162) (xy 339.683767 -275.630285)
			(xy 339.722049 -275.664016) (xy 339.754693 -275.703229) (xy 339.780924 -275.746992) (xy 339.800118 -275.794267)
			(xy 339.811821 -275.843929) (xy 339.815752 -275.8948) (xy 339.813745 -275.920767) (xy 340.094317 -275.920767)
			(xy 340.094317 -275.868833) (xy 340.102442 -275.817538) (xy 340.11849 -275.768145) (xy 340.142068 -275.721871)
			(xy 340.172594 -275.679855) (xy 340.209317 -275.643132) (xy 340.251333 -275.612606) (xy 340.297607 -275.589028)
			(xy 340.347 -275.57298) (xy 340.398295 -275.564855) (xy 340.450229 -275.564855) (xy 340.501524 -275.57298)
			(xy 340.550917 -275.589028) (xy 340.597191 -275.612606) (xy 340.639207 -275.643132) (xy 340.67593 -275.679855)
			(xy 340.706456 -275.721871) (xy 340.730034 -275.768145) (xy 340.746082 -275.817538) (xy 340.754207 -275.868833)
			(xy 340.754716 -275.8948) (xy 340.754207 -275.920767) (xy 341.034117 -275.920767) (xy 341.034117 -275.868833)
			(xy 341.042242 -275.817538) (xy 341.05829 -275.768145) (xy 341.081868 -275.721871) (xy 341.112394 -275.679855)
			(xy 341.149117 -275.643132) (xy 341.191133 -275.612606) (xy 341.237407 -275.589028) (xy 341.2868 -275.57298)
			(xy 341.338095 -275.564855) (xy 341.390029 -275.564855) (xy 341.441324 -275.57298) (xy 341.490717 -275.589028)
			(xy 341.536991 -275.612606) (xy 341.579007 -275.643132) (xy 341.61573 -275.679855) (xy 341.646256 -275.721871)
			(xy 341.669834 -275.768145) (xy 341.685882 -275.817538) (xy 341.694007 -275.868833) (xy 341.694516 -275.8948)
			(xy 341.694007 -275.920767) (xy 341.974171 -275.920767) (xy 341.974171 -275.868833) (xy 341.982296 -275.817538)
			(xy 341.998344 -275.768145) (xy 342.021922 -275.721871) (xy 342.052448 -275.679855) (xy 342.089171 -275.643132)
			(xy 342.131187 -275.612606) (xy 342.177461 -275.589028) (xy 342.226854 -275.57298) (xy 342.278149 -275.564855)
			(xy 342.330083 -275.564855) (xy 342.381378 -275.57298) (xy 342.430771 -275.589028) (xy 342.477045 -275.612606)
			(xy 342.519061 -275.643132) (xy 342.555784 -275.679855) (xy 342.58631 -275.721871) (xy 342.609888 -275.768145)
			(xy 342.625936 -275.817538) (xy 342.634061 -275.868833) (xy 342.63457 -275.8948) (xy 342.634061 -275.920767)
			(xy 342.913717 -275.920767) (xy 342.913717 -275.868833) (xy 342.921842 -275.817538) (xy 342.93789 -275.768145)
			(xy 342.961468 -275.721871) (xy 342.991994 -275.679855) (xy 343.028717 -275.643132) (xy 343.070733 -275.612606)
			(xy 343.117007 -275.589028) (xy 343.1664 -275.57298) (xy 343.217695 -275.564855) (xy 343.269629 -275.564855)
			(xy 343.320924 -275.57298) (xy 343.370317 -275.589028) (xy 343.416591 -275.612606) (xy 343.458607 -275.643132)
			(xy 343.49533 -275.679855) (xy 343.525856 -275.721871) (xy 343.549434 -275.768145) (xy 343.565482 -275.817538)
			(xy 343.573607 -275.868833) (xy 343.574116 -275.8948) (xy 343.573607 -275.920767) (xy 343.853517 -275.920767)
			(xy 343.853517 -275.868833) (xy 343.861642 -275.817538) (xy 343.87769 -275.768145) (xy 343.901268 -275.721871)
			(xy 343.931794 -275.679855) (xy 343.968517 -275.643132) (xy 344.010533 -275.612606) (xy 344.056807 -275.589028)
			(xy 344.1062 -275.57298) (xy 344.157495 -275.564855) (xy 344.209429 -275.564855) (xy 344.260724 -275.57298)
			(xy 344.310117 -275.589028) (xy 344.356391 -275.612606) (xy 344.398407 -275.643132) (xy 344.43513 -275.679855)
			(xy 344.465656 -275.721871) (xy 344.489234 -275.768145) (xy 344.505282 -275.817538) (xy 344.513407 -275.868833)
			(xy 344.513916 -275.8948) (xy 344.513407 -275.920767) (xy 344.793317 -275.920767) (xy 344.793317 -275.868833)
			(xy 344.801442 -275.817538) (xy 344.81749 -275.768145) (xy 344.841068 -275.721871) (xy 344.871594 -275.679855)
			(xy 344.908317 -275.643132) (xy 344.950333 -275.612606) (xy 344.996607 -275.589028) (xy 345.046 -275.57298)
			(xy 345.097295 -275.564855) (xy 345.149229 -275.564855) (xy 345.200524 -275.57298) (xy 345.249917 -275.589028)
			(xy 345.296191 -275.612606) (xy 345.338207 -275.643132) (xy 345.37493 -275.679855) (xy 345.405456 -275.721871)
			(xy 345.429034 -275.768145) (xy 345.445082 -275.817538) (xy 345.453207 -275.868833) (xy 345.453716 -275.8948)
			(xy 345.453207 -275.920767) (xy 345.733117 -275.920767) (xy 345.733117 -275.868833) (xy 345.741242 -275.817538)
			(xy 345.75729 -275.768145) (xy 345.780868 -275.721871) (xy 345.811394 -275.679855) (xy 345.848117 -275.643132)
			(xy 345.890133 -275.612606) (xy 345.936407 -275.589028) (xy 345.9858 -275.57298) (xy 346.037095 -275.564855)
			(xy 346.089029 -275.564855) (xy 346.140324 -275.57298) (xy 346.189717 -275.589028) (xy 346.235991 -275.612606)
			(xy 346.278007 -275.643132) (xy 346.31473 -275.679855) (xy 346.345256 -275.721871) (xy 346.368834 -275.768145)
			(xy 346.384882 -275.817538) (xy 346.393007 -275.868833) (xy 346.393516 -275.8948) (xy 346.393007 -275.920767)
			(xy 346.672917 -275.920767) (xy 346.672917 -275.868833) (xy 346.681042 -275.817538) (xy 346.69709 -275.768145)
			(xy 346.720668 -275.721871) (xy 346.751194 -275.679855) (xy 346.787917 -275.643132) (xy 346.829933 -275.612606)
			(xy 346.876207 -275.589028) (xy 346.9256 -275.57298) (xy 346.976895 -275.564855) (xy 347.028829 -275.564855)
			(xy 347.080124 -275.57298) (xy 347.129517 -275.589028) (xy 347.175791 -275.612606) (xy 347.217807 -275.643132)
			(xy 347.25453 -275.679855) (xy 347.285056 -275.721871) (xy 347.308634 -275.768145) (xy 347.324682 -275.817538)
			(xy 347.332807 -275.868833) (xy 347.333316 -275.8948) (xy 347.332807 -275.920767) (xy 347.612717 -275.920767)
			(xy 347.612717 -275.868833) (xy 347.620842 -275.817538) (xy 347.63689 -275.768145) (xy 347.660468 -275.721871)
			(xy 347.690994 -275.679855) (xy 347.727717 -275.643132) (xy 347.769733 -275.612606) (xy 347.816007 -275.589028)
			(xy 347.8654 -275.57298) (xy 347.916695 -275.564855) (xy 347.968629 -275.564855) (xy 348.019924 -275.57298)
			(xy 348.069317 -275.589028) (xy 348.115591 -275.612606) (xy 348.157607 -275.643132) (xy 348.19433 -275.679855)
			(xy 348.224856 -275.721871) (xy 348.248434 -275.768145) (xy 348.264482 -275.817538) (xy 348.272607 -275.868833)
			(xy 348.273116 -275.8948) (xy 348.272607 -275.920767) (xy 348.552771 -275.920767) (xy 348.552771 -275.868833)
			(xy 348.560896 -275.817538) (xy 348.576944 -275.768145) (xy 348.600522 -275.721871) (xy 348.631048 -275.679855)
			(xy 348.667771 -275.643132) (xy 348.709787 -275.612606) (xy 348.756061 -275.589028) (xy 348.805454 -275.57298)
			(xy 348.856749 -275.564855) (xy 348.908683 -275.564855) (xy 348.959978 -275.57298) (xy 349.009371 -275.589028)
			(xy 349.055645 -275.612606) (xy 349.097661 -275.643132) (xy 349.134384 -275.679855) (xy 349.16491 -275.721871)
			(xy 349.188488 -275.768145) (xy 349.204536 -275.817538) (xy 349.212661 -275.868833) (xy 349.21317 -275.8948)
			(xy 349.212661 -275.920767) (xy 349.492317 -275.920767) (xy 349.492317 -275.868833) (xy 349.500442 -275.817538)
			(xy 349.51649 -275.768145) (xy 349.540068 -275.721871) (xy 349.570594 -275.679855) (xy 349.607317 -275.643132)
			(xy 349.649333 -275.612606) (xy 349.695607 -275.589028) (xy 349.745 -275.57298) (xy 349.796295 -275.564855)
			(xy 349.848229 -275.564855) (xy 349.899524 -275.57298) (xy 349.948917 -275.589028) (xy 349.995191 -275.612606)
			(xy 350.037207 -275.643132) (xy 350.07393 -275.679855) (xy 350.104456 -275.721871) (xy 350.128034 -275.768145)
			(xy 350.144082 -275.817538) (xy 350.152207 -275.868833) (xy 350.152716 -275.8948) (xy 350.152207 -275.920767)
			(xy 350.144082 -275.972062) (xy 350.128034 -276.021455) (xy 350.104456 -276.067729) (xy 350.07393 -276.109745)
			(xy 350.037207 -276.146468) (xy 349.995191 -276.176994) (xy 349.948917 -276.200572) (xy 349.899524 -276.21662)
			(xy 349.848229 -276.224745) (xy 349.796295 -276.224745) (xy 349.745 -276.21662) (xy 349.695607 -276.200572)
			(xy 349.649333 -276.176994) (xy 349.607317 -276.146468) (xy 349.570594 -276.109745) (xy 349.540068 -276.067729)
			(xy 349.51649 -276.021455) (xy 349.500442 -275.972062) (xy 349.492317 -275.920767) (xy 349.212661 -275.920767)
			(xy 349.204536 -275.972062) (xy 349.188488 -276.021455) (xy 349.16491 -276.067729) (xy 349.134384 -276.109745)
			(xy 349.097661 -276.146468) (xy 349.055645 -276.176994) (xy 349.009371 -276.200572) (xy 348.959978 -276.21662)
			(xy 348.908683 -276.224745) (xy 348.856749 -276.224745) (xy 348.805454 -276.21662) (xy 348.756061 -276.200572)
			(xy 348.709787 -276.176994) (xy 348.667771 -276.146468) (xy 348.631048 -276.109745) (xy 348.600522 -276.067729)
			(xy 348.576944 -276.021455) (xy 348.560896 -275.972062) (xy 348.552771 -275.920767) (xy 348.272607 -275.920767)
			(xy 348.264482 -275.972062) (xy 348.248434 -276.021455) (xy 348.224856 -276.067729) (xy 348.19433 -276.109745)
			(xy 348.157607 -276.146468) (xy 348.115591 -276.176994) (xy 348.069317 -276.200572) (xy 348.019924 -276.21662)
			(xy 347.968629 -276.224745) (xy 347.916695 -276.224745) (xy 347.8654 -276.21662) (xy 347.816007 -276.200572)
			(xy 347.769733 -276.176994) (xy 347.727717 -276.146468) (xy 347.690994 -276.109745) (xy 347.660468 -276.067729)
			(xy 347.63689 -276.021455) (xy 347.620842 -275.972062) (xy 347.612717 -275.920767) (xy 347.332807 -275.920767)
			(xy 347.324682 -275.972062) (xy 347.308634 -276.021455) (xy 347.285056 -276.067729) (xy 347.25453 -276.109745)
			(xy 347.217807 -276.146468) (xy 347.175791 -276.176994) (xy 347.129517 -276.200572) (xy 347.080124 -276.21662)
			(xy 347.028829 -276.224745) (xy 346.976895 -276.224745) (xy 346.9256 -276.21662) (xy 346.876207 -276.200572)
			(xy 346.829933 -276.176994) (xy 346.787917 -276.146468) (xy 346.751194 -276.109745) (xy 346.720668 -276.067729)
			(xy 346.69709 -276.021455) (xy 346.681042 -275.972062) (xy 346.672917 -275.920767) (xy 346.393007 -275.920767)
			(xy 346.384882 -275.972062) (xy 346.368834 -276.021455) (xy 346.345256 -276.067729) (xy 346.31473 -276.109745)
			(xy 346.278007 -276.146468) (xy 346.235991 -276.176994) (xy 346.189717 -276.200572) (xy 346.140324 -276.21662)
			(xy 346.089029 -276.224745) (xy 346.037095 -276.224745) (xy 345.9858 -276.21662) (xy 345.936407 -276.200572)
			(xy 345.890133 -276.176994) (xy 345.848117 -276.146468) (xy 345.811394 -276.109745) (xy 345.780868 -276.067729)
			(xy 345.75729 -276.021455) (xy 345.741242 -275.972062) (xy 345.733117 -275.920767) (xy 345.453207 -275.920767)
			(xy 345.445082 -275.972062) (xy 345.429034 -276.021455) (xy 345.405456 -276.067729) (xy 345.37493 -276.109745)
			(xy 345.338207 -276.146468) (xy 345.296191 -276.176994) (xy 345.249917 -276.200572) (xy 345.200524 -276.21662)
			(xy 345.149229 -276.224745) (xy 345.097295 -276.224745) (xy 345.046 -276.21662) (xy 344.996607 -276.200572)
			(xy 344.950333 -276.176994) (xy 344.908317 -276.146468) (xy 344.871594 -276.109745) (xy 344.841068 -276.067729)
			(xy 344.81749 -276.021455) (xy 344.801442 -275.972062) (xy 344.793317 -275.920767) (xy 344.513407 -275.920767)
			(xy 344.505282 -275.972062) (xy 344.489234 -276.021455) (xy 344.465656 -276.067729) (xy 344.43513 -276.109745)
			(xy 344.398407 -276.146468) (xy 344.356391 -276.176994) (xy 344.310117 -276.200572) (xy 344.260724 -276.21662)
			(xy 344.209429 -276.224745) (xy 344.157495 -276.224745) (xy 344.1062 -276.21662) (xy 344.056807 -276.200572)
			(xy 344.010533 -276.176994) (xy 343.968517 -276.146468) (xy 343.931794 -276.109745) (xy 343.901268 -276.067729)
			(xy 343.87769 -276.021455) (xy 343.861642 -275.972062) (xy 343.853517 -275.920767) (xy 343.573607 -275.920767)
			(xy 343.565482 -275.972062) (xy 343.549434 -276.021455) (xy 343.525856 -276.067729) (xy 343.49533 -276.109745)
			(xy 343.458607 -276.146468) (xy 343.416591 -276.176994) (xy 343.370317 -276.200572) (xy 343.320924 -276.21662)
			(xy 343.269629 -276.224745) (xy 343.217695 -276.224745) (xy 343.1664 -276.21662) (xy 343.117007 -276.200572)
			(xy 343.070733 -276.176994) (xy 343.028717 -276.146468) (xy 342.991994 -276.109745) (xy 342.961468 -276.067729)
			(xy 342.93789 -276.021455) (xy 342.921842 -275.972062) (xy 342.913717 -275.920767) (xy 342.634061 -275.920767)
			(xy 342.625936 -275.972062) (xy 342.609888 -276.021455) (xy 342.58631 -276.067729) (xy 342.555784 -276.109745)
			(xy 342.519061 -276.146468) (xy 342.477045 -276.176994) (xy 342.430771 -276.200572) (xy 342.381378 -276.21662)
			(xy 342.330083 -276.224745) (xy 342.278149 -276.224745) (xy 342.226854 -276.21662) (xy 342.177461 -276.200572)
			(xy 342.131187 -276.176994) (xy 342.089171 -276.146468) (xy 342.052448 -276.109745) (xy 342.021922 -276.067729)
			(xy 341.998344 -276.021455) (xy 341.982296 -275.972062) (xy 341.974171 -275.920767) (xy 341.694007 -275.920767)
			(xy 341.685882 -275.972062) (xy 341.669834 -276.021455) (xy 341.646256 -276.067729) (xy 341.61573 -276.109745)
			(xy 341.579007 -276.146468) (xy 341.536991 -276.176994) (xy 341.490717 -276.200572) (xy 341.441324 -276.21662)
			(xy 341.390029 -276.224745) (xy 341.338095 -276.224745) (xy 341.2868 -276.21662) (xy 341.237407 -276.200572)
			(xy 341.191133 -276.176994) (xy 341.149117 -276.146468) (xy 341.112394 -276.109745) (xy 341.081868 -276.067729)
			(xy 341.05829 -276.021455) (xy 341.042242 -275.972062) (xy 341.034117 -275.920767) (xy 340.754207 -275.920767)
			(xy 340.746082 -275.972062) (xy 340.730034 -276.021455) (xy 340.706456 -276.067729) (xy 340.67593 -276.109745)
			(xy 340.639207 -276.146468) (xy 340.597191 -276.176994) (xy 340.550917 -276.200572) (xy 340.501524 -276.21662)
			(xy 340.450229 -276.224745) (xy 340.398295 -276.224745) (xy 340.347 -276.21662) (xy 340.297607 -276.200572)
			(xy 340.251333 -276.176994) (xy 340.209317 -276.146468) (xy 340.172594 -276.109745) (xy 340.142068 -276.067729)
			(xy 340.11849 -276.021455) (xy 340.102442 -275.972062) (xy 340.094317 -275.920767) (xy 339.813745 -275.920767)
			(xy 339.811821 -275.945671) (xy 339.800118 -275.995333) (xy 339.780924 -276.042608) (xy 339.754693 -276.086371)
			(xy 339.722049 -276.125584) (xy 339.683767 -276.159315) (xy 339.662516 -276.173438) (xy 339.651848 -276.180296)
			(xy 339.627464 -276.222968) (xy 339.627464 -276.342094) (xy 339.627779 -276.35048) (xy 339.633279 -276.366326)
			(xy 339.643672 -276.37949) (xy 339.650578 -276.384258) (xy 339.718142 -276.422104) (xy 339.723391 -276.424593)
			(xy 339.734687 -276.427293) (xy 339.740494 -276.427438) (xy 339.76691 -276.427438) (xy 339.791294 -276.420834)
			(xy 339.795612 -276.418548) (xy 339.820105 -276.405779) (xy 339.872286 -276.387676) (xy 339.926746 -276.378478)
			(xy 339.954362 -276.377908) (xy 339.954616 -276.377908) (xy 339.980601 -276.378419) (xy 340.031931 -276.386551)
			(xy 340.081357 -276.402612) (xy 340.127662 -276.426208) (xy 340.169706 -276.456757) (xy 340.206454 -276.493506)
			(xy 340.237 -276.535551) (xy 340.260594 -276.581858) (xy 340.276653 -276.631284) (xy 340.284783 -276.682615)
			(xy 340.284783 -276.734583) (xy 340.564471 -276.734583) (xy 340.564471 -276.682649) (xy 340.572596 -276.631354)
			(xy 340.588644 -276.581961) (xy 340.612222 -276.535687) (xy 340.642748 -276.493671) (xy 340.679471 -276.456948)
			(xy 340.721487 -276.426422) (xy 340.767761 -276.402844) (xy 340.817154 -276.386796) (xy 340.868449 -276.378671)
			(xy 340.920383 -276.378671) (xy 340.971678 -276.386796) (xy 341.021071 -276.402844) (xy 341.067345 -276.426422)
			(xy 341.109361 -276.456948) (xy 341.146084 -276.493671) (xy 341.17661 -276.535687) (xy 341.200188 -276.581961)
			(xy 341.216236 -276.631354) (xy 341.224361 -276.682649) (xy 341.22487 -276.708616) (xy 341.224361 -276.734583)
			(xy 341.504271 -276.734583) (xy 341.504271 -276.682649) (xy 341.512396 -276.631354) (xy 341.528444 -276.581961)
			(xy 341.552022 -276.535687) (xy 341.582548 -276.493671) (xy 341.619271 -276.456948) (xy 341.661287 -276.426422)
			(xy 341.707561 -276.402844) (xy 341.756954 -276.386796) (xy 341.808249 -276.378671) (xy 341.860183 -276.378671)
			(xy 341.911478 -276.386796) (xy 341.960871 -276.402844) (xy 342.007145 -276.426422) (xy 342.049161 -276.456948)
			(xy 342.085884 -276.493671) (xy 342.11641 -276.535687) (xy 342.139988 -276.581961) (xy 342.156036 -276.631354)
			(xy 342.164161 -276.682649) (xy 342.16467 -276.708616) (xy 342.164161 -276.734583) (xy 342.444071 -276.734583)
			(xy 342.444071 -276.682649) (xy 342.452196 -276.631354) (xy 342.468244 -276.581961) (xy 342.491822 -276.535687)
			(xy 342.522348 -276.493671) (xy 342.559071 -276.456948) (xy 342.601087 -276.426422) (xy 342.647361 -276.402844)
			(xy 342.696754 -276.386796) (xy 342.748049 -276.378671) (xy 342.799983 -276.378671) (xy 342.851278 -276.386796)
			(xy 342.900671 -276.402844) (xy 342.946945 -276.426422) (xy 342.988961 -276.456948) (xy 343.025684 -276.493671)
			(xy 343.05621 -276.535687) (xy 343.079788 -276.581961) (xy 343.095836 -276.631354) (xy 343.103961 -276.682649)
			(xy 343.10447 -276.708616) (xy 343.103961 -276.734583) (xy 343.383871 -276.734583) (xy 343.383871 -276.682649)
			(xy 343.391996 -276.631354) (xy 343.408044 -276.581961) (xy 343.431622 -276.535687) (xy 343.462148 -276.493671)
			(xy 343.498871 -276.456948) (xy 343.540887 -276.426422) (xy 343.587161 -276.402844) (xy 343.636554 -276.386796)
			(xy 343.687849 -276.378671) (xy 343.739783 -276.378671) (xy 343.791078 -276.386796) (xy 343.840471 -276.402844)
			(xy 343.886745 -276.426422) (xy 343.928761 -276.456948) (xy 343.965484 -276.493671) (xy 343.99601 -276.535687)
			(xy 344.019588 -276.581961) (xy 344.035636 -276.631354) (xy 344.043761 -276.682649) (xy 344.04427 -276.708616)
			(xy 344.043761 -276.734583) (xy 344.323671 -276.734583) (xy 344.323671 -276.682649) (xy 344.331796 -276.631354)
			(xy 344.347844 -276.581961) (xy 344.371422 -276.535687) (xy 344.401948 -276.493671) (xy 344.438671 -276.456948)
			(xy 344.480687 -276.426422) (xy 344.526961 -276.402844) (xy 344.576354 -276.386796) (xy 344.627649 -276.378671)
			(xy 344.679583 -276.378671) (xy 344.730878 -276.386796) (xy 344.780271 -276.402844) (xy 344.826545 -276.426422)
			(xy 344.868561 -276.456948) (xy 344.905284 -276.493671) (xy 344.93581 -276.535687) (xy 344.959388 -276.581961)
			(xy 344.975436 -276.631354) (xy 344.983561 -276.682649) (xy 344.98407 -276.708616) (xy 344.983561 -276.734583)
			(xy 345.263217 -276.734583) (xy 345.263217 -276.682649) (xy 345.271342 -276.631354) (xy 345.28739 -276.581961)
			(xy 345.310968 -276.535687) (xy 345.341494 -276.493671) (xy 345.378217 -276.456948) (xy 345.420233 -276.426422)
			(xy 345.466507 -276.402844) (xy 345.5159 -276.386796) (xy 345.567195 -276.378671) (xy 345.619129 -276.378671)
			(xy 345.670424 -276.386796) (xy 345.719817 -276.402844) (xy 345.766091 -276.426422) (xy 345.808107 -276.456948)
			(xy 345.84483 -276.493671) (xy 345.875356 -276.535687) (xy 345.898934 -276.581961) (xy 345.914982 -276.631354)
			(xy 345.923107 -276.682649) (xy 345.923616 -276.708616) (xy 345.923107 -276.734583) (xy 346.203271 -276.734583)
			(xy 346.203271 -276.682649) (xy 346.211396 -276.631354) (xy 346.227444 -276.581961) (xy 346.251022 -276.535687)
			(xy 346.281548 -276.493671) (xy 346.318271 -276.456948) (xy 346.360287 -276.426422) (xy 346.406561 -276.402844)
			(xy 346.455954 -276.386796) (xy 346.507249 -276.378671) (xy 346.559183 -276.378671) (xy 346.610478 -276.386796)
			(xy 346.659871 -276.402844) (xy 346.706145 -276.426422) (xy 346.748161 -276.456948) (xy 346.784884 -276.493671)
			(xy 346.81541 -276.535687) (xy 346.838988 -276.581961) (xy 346.855036 -276.631354) (xy 346.863161 -276.682649)
			(xy 346.86367 -276.708616) (xy 346.863161 -276.734583) (xy 347.143071 -276.734583) (xy 347.143071 -276.682649)
			(xy 347.151196 -276.631354) (xy 347.167244 -276.581961) (xy 347.190822 -276.535687) (xy 347.221348 -276.493671)
			(xy 347.258071 -276.456948) (xy 347.300087 -276.426422) (xy 347.346361 -276.402844) (xy 347.395754 -276.386796)
			(xy 347.447049 -276.378671) (xy 347.498983 -276.378671) (xy 347.550278 -276.386796) (xy 347.599671 -276.402844)
			(xy 347.645945 -276.426422) (xy 347.687961 -276.456948) (xy 347.724684 -276.493671) (xy 347.75521 -276.535687)
			(xy 347.778788 -276.581961) (xy 347.794836 -276.631354) (xy 347.802961 -276.682649) (xy 347.80347 -276.708616)
			(xy 347.802961 -276.734583) (xy 348.082871 -276.734583) (xy 348.082871 -276.682649) (xy 348.090996 -276.631354)
			(xy 348.107044 -276.581961) (xy 348.130622 -276.535687) (xy 348.161148 -276.493671) (xy 348.197871 -276.456948)
			(xy 348.239887 -276.426422) (xy 348.286161 -276.402844) (xy 348.335554 -276.386796) (xy 348.386849 -276.378671)
			(xy 348.438783 -276.378671) (xy 348.490078 -276.386796) (xy 348.539471 -276.402844) (xy 348.585745 -276.426422)
			(xy 348.627761 -276.456948) (xy 348.664484 -276.493671) (xy 348.69501 -276.535687) (xy 348.718588 -276.581961)
			(xy 348.734636 -276.631354) (xy 348.742761 -276.682649) (xy 348.74327 -276.708616) (xy 348.742761 -276.734583)
			(xy 349.022671 -276.734583) (xy 349.022671 -276.682649) (xy 349.030796 -276.631354) (xy 349.046844 -276.581961)
			(xy 349.070422 -276.535687) (xy 349.100948 -276.493671) (xy 349.137671 -276.456948) (xy 349.179687 -276.426422)
			(xy 349.225961 -276.402844) (xy 349.275354 -276.386796) (xy 349.326649 -276.378671) (xy 349.378583 -276.378671)
			(xy 349.429878 -276.386796) (xy 349.479271 -276.402844) (xy 349.525545 -276.426422) (xy 349.567561 -276.456948)
			(xy 349.604284 -276.493671) (xy 349.63481 -276.535687) (xy 349.658388 -276.581961) (xy 349.674436 -276.631354)
			(xy 349.682561 -276.682649) (xy 349.68307 -276.708616) (xy 349.961708 -276.708616) (xy 349.96215 -276.683164)
			(xy 349.969939 -276.63286) (xy 349.985351 -276.584346) (xy 350.008021 -276.53877) (xy 350.037413 -276.497209)
			(xy 350.072832 -276.460648) (xy 350.113438 -276.429952) (xy 350.158272 -276.405846) (xy 350.206273 -276.388902)
			(xy 350.231202 -276.38375) (xy 350.254316 -276.379432) (xy 350.458024 -276.026372) (xy 350.450404 -276.004274)
			(xy 350.441653 -275.977755) (xy 350.432207 -275.92272) (xy 350.431608 -275.8948) (xy 350.432117 -275.868833)
			(xy 350.440242 -275.817538) (xy 350.45629 -275.768145) (xy 350.479868 -275.721871) (xy 350.510394 -275.679855)
			(xy 350.547117 -275.643132) (xy 350.589133 -275.612606) (xy 350.635407 -275.589028) (xy 350.6848 -275.57298)
			(xy 350.736095 -275.564855) (xy 350.788029 -275.564855) (xy 350.839324 -275.57298) (xy 350.888717 -275.589028)
			(xy 350.934991 -275.612606) (xy 350.977007 -275.643132) (xy 351.01373 -275.679855) (xy 351.044256 -275.721871)
			(xy 351.067834 -275.768145) (xy 351.083882 -275.817538) (xy 351.092007 -275.868833) (xy 351.092516 -275.8948)
			(xy 351.092022 -275.920262) (xy 351.091944 -275.920767) (xy 351.371917 -275.920767) (xy 351.371917 -275.868833)
			(xy 351.380042 -275.817538) (xy 351.39609 -275.768145) (xy 351.419668 -275.721871) (xy 351.450194 -275.679855)
			(xy 351.486917 -275.643132) (xy 351.528933 -275.612606) (xy 351.575207 -275.589028) (xy 351.6246 -275.57298)
			(xy 351.675895 -275.564855) (xy 351.727829 -275.564855) (xy 351.779124 -275.57298) (xy 351.828517 -275.589028)
			(xy 351.874791 -275.612606) (xy 351.916807 -275.643132) (xy 351.95353 -275.679855) (xy 351.984056 -275.721871)
			(xy 352.007634 -275.768145) (xy 352.023682 -275.817538) (xy 352.031807 -275.868833) (xy 352.032316 -275.8948)
			(xy 352.311208 -275.8948) (xy 352.311726 -275.869351) (xy 352.319503 -275.81905) (xy 352.334904 -275.770538)
			(xy 352.357563 -275.724961) (xy 352.386946 -275.683401) (xy 352.422355 -275.646838) (xy 352.462954 -275.61614)
			(xy 352.507781 -275.592033) (xy 352.555776 -275.575087) (xy 352.580702 -275.569934) (xy 352.603816 -275.565616)
			(xy 352.807778 -275.212302) (xy 352.799904 -275.190204) (xy 352.791292 -275.163853) (xy 352.781971 -275.109208)
			(xy 352.781362 -275.081492) (xy 352.781362 -275.08073) (xy 352.781871 -275.054763) (xy 352.789996 -275.003468)
			(xy 352.806044 -274.954075) (xy 352.829622 -274.907801) (xy 352.860148 -274.865785) (xy 352.896871 -274.829062)
			(xy 352.938887 -274.798536) (xy 352.985161 -274.774958) (xy 353.034554 -274.75891) (xy 353.085849 -274.750785)
			(xy 353.137783 -274.750785) (xy 353.189078 -274.75891) (xy 353.238471 -274.774958) (xy 353.284745 -274.798536)
			(xy 353.326761 -274.829062) (xy 353.363484 -274.865785) (xy 353.39401 -274.907801) (xy 353.417588 -274.954075)
			(xy 353.433636 -275.003468) (xy 353.441761 -275.054763) (xy 353.44227 -275.08073) (xy 353.44184 -275.106194)
			(xy 353.441762 -275.106697) (xy 353.721417 -275.106697) (xy 353.721417 -275.054763) (xy 353.729542 -275.003468)
			(xy 353.74559 -274.954075) (xy 353.769168 -274.907801) (xy 353.799694 -274.865785) (xy 353.836417 -274.829062)
			(xy 353.878433 -274.798536) (xy 353.924707 -274.774958) (xy 353.9741 -274.75891) (xy 354.025395 -274.750785)
			(xy 354.077329 -274.750785) (xy 354.128624 -274.75891) (xy 354.178017 -274.774958) (xy 354.224291 -274.798536)
			(xy 354.266307 -274.829062) (xy 354.30303 -274.865785) (xy 354.333556 -274.907801) (xy 354.357134 -274.954075)
			(xy 354.373182 -275.003468) (xy 354.381307 -275.054763) (xy 354.381816 -275.08073) (xy 354.381307 -275.106697)
			(xy 354.661471 -275.106697) (xy 354.661471 -275.054763) (xy 354.669596 -275.003468) (xy 354.685644 -274.954075)
			(xy 354.709222 -274.907801) (xy 354.739748 -274.865785) (xy 354.776471 -274.829062) (xy 354.818487 -274.798536)
			(xy 354.864761 -274.774958) (xy 354.914154 -274.75891) (xy 354.965449 -274.750785) (xy 355.017383 -274.750785)
			(xy 355.068678 -274.75891) (xy 355.118071 -274.774958) (xy 355.164345 -274.798536) (xy 355.206361 -274.829062)
			(xy 355.243084 -274.865785) (xy 355.27361 -274.907801) (xy 355.297188 -274.954075) (xy 355.313236 -275.003468)
			(xy 355.321361 -275.054763) (xy 355.32187 -275.08073) (xy 355.600762 -275.08073) (xy 355.601271 -275.054763)
			(xy 355.609396 -275.003468) (xy 355.625444 -274.954075) (xy 355.649022 -274.907801) (xy 355.679548 -274.865785)
			(xy 355.716271 -274.829062) (xy 355.758287 -274.798536) (xy 355.804561 -274.774958) (xy 355.853954 -274.75891)
			(xy 355.905249 -274.750785) (xy 355.957183 -274.750785) (xy 356.008478 -274.75891) (xy 356.057871 -274.774958)
			(xy 356.104145 -274.798536) (xy 356.146161 -274.829062) (xy 356.182884 -274.865785) (xy 356.21341 -274.907801)
			(xy 356.236988 -274.954075) (xy 356.253036 -275.003468) (xy 356.261161 -275.054763) (xy 356.26167 -275.08073)
			(xy 356.261165 -275.106697) (xy 356.540817 -275.106697) (xy 356.540817 -275.054763) (xy 356.548942 -275.003468)
			(xy 356.56499 -274.954075) (xy 356.588568 -274.907801) (xy 356.619094 -274.865785) (xy 356.655817 -274.829062)
			(xy 356.697833 -274.798536) (xy 356.744107 -274.774958) (xy 356.7935 -274.75891) (xy 356.844795 -274.750785)
			(xy 356.896729 -274.750785) (xy 356.948024 -274.75891) (xy 356.997417 -274.774958) (xy 357.043691 -274.798536)
			(xy 357.085707 -274.829062) (xy 357.12243 -274.865785) (xy 357.152956 -274.907801) (xy 357.176534 -274.954075)
			(xy 357.192582 -275.003468) (xy 357.200707 -275.054763) (xy 357.201216 -275.08073) (xy 357.200707 -275.106697)
			(xy 357.192582 -275.157992) (xy 357.176534 -275.207385) (xy 357.152956 -275.253659) (xy 357.12243 -275.295675)
			(xy 357.085707 -275.332398) (xy 357.043691 -275.362924) (xy 356.997417 -275.386502) (xy 356.948024 -275.40255)
			(xy 356.896729 -275.410675) (xy 356.844795 -275.410675) (xy 356.7935 -275.40255) (xy 356.744107 -275.386502)
			(xy 356.697833 -275.362924) (xy 356.655817 -275.332398) (xy 356.619094 -275.295675) (xy 356.588568 -275.253659)
			(xy 356.56499 -275.207385) (xy 356.548942 -275.157992) (xy 356.540817 -275.106697) (xy 356.261165 -275.106697)
			(xy 356.261126 -275.108716) (xy 356.25167 -275.163884) (xy 356.242874 -275.190458) (xy 356.235254 -275.212556)
			(xy 356.438962 -275.565616) (xy 356.462076 -275.569934) (xy 356.486996 -275.575106) (xy 356.534978 -275.592073)
			(xy 356.579793 -275.616192) (xy 356.620384 -275.646893) (xy 356.655792 -275.68345) (xy 356.68518 -275.725001)
			(xy 356.707855 -275.770564) (xy 356.723281 -275.819063) (xy 356.731094 -275.869353) (xy 356.73157 -275.8948)
			(xy 356.731061 -275.920767) (xy 356.722936 -275.972062) (xy 356.706888 -276.021455) (xy 356.68331 -276.067729)
			(xy 356.652784 -276.109745) (xy 356.616061 -276.146468) (xy 356.574045 -276.176994) (xy 356.527771 -276.200572)
			(xy 356.478378 -276.21662) (xy 356.427083 -276.224745) (xy 356.375149 -276.224745) (xy 356.323854 -276.21662)
			(xy 356.274461 -276.200572) (xy 356.228187 -276.176994) (xy 356.186171 -276.146468) (xy 356.149448 -276.109745)
			(xy 356.118922 -276.067729) (xy 356.095344 -276.021455) (xy 356.079296 -275.972062) (xy 356.071171 -275.920767)
			(xy 356.070662 -275.8948) (xy 356.071211 -275.866814) (xy 356.080663 -275.811646) (xy 356.089458 -275.785072)
			(xy 356.097078 -275.762974) (xy 355.89337 -275.409914) (xy 355.870256 -275.405596) (xy 355.845325 -275.400467)
			(xy 355.797339 -275.383499) (xy 355.752519 -275.359378) (xy 355.711925 -275.328673) (xy 355.676516 -275.29211)
			(xy 355.647129 -275.250552) (xy 355.624458 -275.204982) (xy 355.609037 -275.156476) (xy 355.601233 -275.106179)
			(xy 355.600762 -275.08073) (xy 355.32187 -275.08073) (xy 355.321361 -275.106697) (xy 355.313236 -275.157992)
			(xy 355.297188 -275.207385) (xy 355.27361 -275.253659) (xy 355.243084 -275.295675) (xy 355.206361 -275.332398)
			(xy 355.164345 -275.362924) (xy 355.118071 -275.386502) (xy 355.068678 -275.40255) (xy 355.017383 -275.410675)
			(xy 354.965449 -275.410675) (xy 354.914154 -275.40255) (xy 354.864761 -275.386502) (xy 354.818487 -275.362924)
			(xy 354.776471 -275.332398) (xy 354.739748 -275.295675) (xy 354.709222 -275.253659) (xy 354.685644 -275.207385)
			(xy 354.669596 -275.157992) (xy 354.661471 -275.106697) (xy 354.381307 -275.106697) (xy 354.373182 -275.157992)
			(xy 354.357134 -275.207385) (xy 354.333556 -275.253659) (xy 354.30303 -275.295675) (xy 354.266307 -275.332398)
			(xy 354.224291 -275.362924) (xy 354.178017 -275.386502) (xy 354.128624 -275.40255) (xy 354.077329 -275.410675)
			(xy 354.025395 -275.410675) (xy 353.9741 -275.40255) (xy 353.924707 -275.386502) (xy 353.878433 -275.362924)
			(xy 353.836417 -275.332398) (xy 353.799694 -275.295675) (xy 353.769168 -275.253659) (xy 353.74559 -275.207385)
			(xy 353.729542 -275.157992) (xy 353.721417 -275.106697) (xy 353.441762 -275.106697) (xy 353.434036 -275.156521)
			(xy 353.418602 -275.205055) (xy 353.395903 -275.250645) (xy 353.366478 -275.292213) (xy 353.331023 -275.328773)
			(xy 353.290378 -275.35946) (xy 353.245505 -275.383546) (xy 353.197468 -275.400462) (xy 353.172522 -275.405596)
			(xy 353.149408 -275.409914) (xy 352.9457 -275.762974) (xy 352.95332 -275.785072) (xy 352.962052 -275.811662)
			(xy 352.971503 -275.86682) (xy 352.972116 -275.8948) (xy 352.971607 -275.920767) (xy 353.251771 -275.920767)
			(xy 353.251771 -275.868833) (xy 353.259896 -275.817538) (xy 353.275944 -275.768145) (xy 353.299522 -275.721871)
			(xy 353.330048 -275.679855) (xy 353.366771 -275.643132) (xy 353.408787 -275.612606) (xy 353.455061 -275.589028)
			(xy 353.504454 -275.57298) (xy 353.555749 -275.564855) (xy 353.607683 -275.564855) (xy 353.658978 -275.57298)
			(xy 353.708371 -275.589028) (xy 353.754645 -275.612606) (xy 353.796661 -275.643132) (xy 353.833384 -275.679855)
			(xy 353.86391 -275.721871) (xy 353.887488 -275.768145) (xy 353.903536 -275.817538) (xy 353.911661 -275.868833)
			(xy 353.91217 -275.8948) (xy 353.911661 -275.920765) (xy 354.191355 -275.920765) (xy 354.191355 -275.868835)
			(xy 354.199478 -275.817543) (xy 354.215525 -275.768154) (xy 354.239099 -275.721883) (xy 354.269621 -275.679868)
			(xy 354.30634 -275.643146) (xy 354.34835 -275.612619) (xy 354.394619 -275.589039) (xy 354.444006 -275.572987)
			(xy 354.495297 -275.564858) (xy 354.521262 -275.564346) (xy 354.546884 -275.564818) (xy 354.597512 -275.572743)
			(xy 354.646312 -275.588379) (xy 354.692119 -275.611352) (xy 354.733835 -275.641112) (xy 354.770465 -275.676948)
			(xy 354.786184 -275.697188) (xy 355.19614 -275.697188) (xy 355.211851 -275.67694) (xy 355.248471 -275.641089)
			(xy 355.290186 -275.611321) (xy 355.335996 -275.58835) (xy 355.384804 -275.572726) (xy 355.435438 -275.564824)
			(xy 355.461062 -275.564346) (xy 355.487033 -275.564826) (xy 355.538337 -275.572946) (xy 355.587739 -275.588993)
			(xy 355.634021 -275.61257) (xy 355.676046 -275.643098) (xy 355.712777 -275.679825) (xy 355.74331 -275.721846)
			(xy 355.766893 -275.768126) (xy 355.782945 -275.817526) (xy 355.791071 -275.868829) (xy 355.791071 -275.920771)
			(xy 355.782945 -275.972074) (xy 355.766893 -276.021474) (xy 355.74331 -276.067754) (xy 355.712777 -276.109775)
			(xy 355.676046 -276.146502) (xy 355.634021 -276.17703) (xy 355.587739 -276.200607) (xy 355.538337 -276.216654)
			(xy 355.487033 -276.224774) (xy 355.461062 -276.225254) (xy 355.435441 -276.224765) (xy 355.384814 -276.216843)
			(xy 355.336014 -276.20121) (xy 355.290207 -276.178241) (xy 355.24849 -276.148484) (xy 355.211859 -276.112651)
			(xy 355.19614 -276.092412) (xy 354.786184 -276.092412) (xy 354.770459 -276.112648) (xy 354.733842 -276.1485)
			(xy 354.69213 -276.178269) (xy 354.646322 -276.201243) (xy 354.597517 -276.216869) (xy 354.546885 -276.224775)
			(xy 354.521262 -276.225254) (xy 354.495297 -276.224742) (xy 354.444006 -276.216613) (xy 354.394619 -276.200561)
			(xy 354.34835 -276.176981) (xy 354.30634 -276.146454) (xy 354.269621 -276.109732) (xy 354.239099 -276.067717)
			(xy 354.215525 -276.021446) (xy 354.199478 -275.972057) (xy 354.191355 -275.920765) (xy 353.911661 -275.920765)
			(xy 353.911661 -275.920767) (xy 353.903536 -275.972062) (xy 353.887488 -276.021455) (xy 353.86391 -276.067729)
			(xy 353.833384 -276.109745) (xy 353.796661 -276.146468) (xy 353.754645 -276.176994) (xy 353.708371 -276.200572)
			(xy 353.658978 -276.21662) (xy 353.607683 -276.224745) (xy 353.555749 -276.224745) (xy 353.504454 -276.21662)
			(xy 353.455061 -276.200572) (xy 353.408787 -276.176994) (xy 353.366771 -276.146468) (xy 353.330048 -276.109745)
			(xy 353.299522 -276.067729) (xy 353.275944 -276.021455) (xy 353.259896 -275.972062) (xy 353.251771 -275.920767)
			(xy 352.971607 -275.920767) (xy 352.963482 -275.972062) (xy 352.947434 -276.021455) (xy 352.923856 -276.067729)
			(xy 352.89333 -276.109745) (xy 352.856607 -276.146468) (xy 352.814591 -276.176994) (xy 352.768317 -276.200572)
			(xy 352.718924 -276.21662) (xy 352.667629 -276.224745) (xy 352.615695 -276.224745) (xy 352.5644 -276.21662)
			(xy 352.515007 -276.200572) (xy 352.468733 -276.176994) (xy 352.426717 -276.146468) (xy 352.389994 -276.109745)
			(xy 352.359468 -276.067729) (xy 352.33589 -276.021455) (xy 352.319842 -275.972062) (xy 352.311717 -275.920767)
			(xy 352.311208 -275.8948) (xy 352.032316 -275.8948) (xy 352.031807 -275.920767) (xy 352.023682 -275.972062)
			(xy 352.007634 -276.021455) (xy 351.984056 -276.067729) (xy 351.95353 -276.109745) (xy 351.916807 -276.146468)
			(xy 351.874791 -276.176994) (xy 351.828517 -276.200572) (xy 351.779124 -276.21662) (xy 351.727829 -276.224745)
			(xy 351.675895 -276.224745) (xy 351.6246 -276.21662) (xy 351.575207 -276.200572) (xy 351.528933 -276.176994)
			(xy 351.486917 -276.146468) (xy 351.450194 -276.109745) (xy 351.419668 -276.067729) (xy 351.39609 -276.021455)
			(xy 351.380042 -275.972062) (xy 351.371917 -275.920767) (xy 351.091944 -275.920767) (xy 351.084223 -275.970584)
			(xy 351.068796 -276.019114) (xy 351.046105 -276.064702) (xy 351.016688 -276.106268) (xy 350.981241 -276.142829)
			(xy 350.940604 -276.173518) (xy 350.89574 -276.197608) (xy 350.84771 -276.214528) (xy 350.822768 -276.219666)
			(xy 350.799908 -276.223984) (xy 350.5962 -276.57679) (xy 350.60382 -276.598888) (xy 350.612555 -276.625477)
			(xy 350.622004 -276.680636) (xy 350.622616 -276.708616) (xy 350.901762 -276.708616) (xy 350.902271 -276.682649)
			(xy 350.910396 -276.631354) (xy 350.926444 -276.581961) (xy 350.950022 -276.535687) (xy 350.980548 -276.493671)
			(xy 351.017271 -276.456948) (xy 351.059287 -276.426422) (xy 351.105561 -276.402844) (xy 351.154954 -276.386796)
			(xy 351.206249 -276.378671) (xy 351.258183 -276.378671) (xy 351.309478 -276.386796) (xy 351.358871 -276.402844)
			(xy 351.405145 -276.426422) (xy 351.447161 -276.456948) (xy 351.483884 -276.493671) (xy 351.51441 -276.535687)
			(xy 351.537988 -276.581961) (xy 351.554036 -276.631354) (xy 351.562161 -276.682649) (xy 351.56267 -276.708616)
			(xy 351.562163 -276.734569) (xy 351.842045 -276.734569) (xy 351.842045 -276.682631) (xy 351.85017 -276.631333)
			(xy 351.86622 -276.581937) (xy 351.8898 -276.535661) (xy 351.920329 -276.493643) (xy 351.957055 -276.456919)
			(xy 351.999075 -276.426392) (xy 352.045352 -276.402814) (xy 352.094749 -276.386766) (xy 352.146047 -276.378644)
			(xy 352.172016 -276.378162) (xy 352.197635 -276.378701) (xy 352.248258 -276.386617) (xy 352.297056 -276.402242)
			(xy 352.342862 -276.425202) (xy 352.384581 -276.454949) (xy 352.421216 -276.490771) (xy 352.436938 -276.511004)
			(xy 352.846894 -276.511004) (xy 352.862636 -276.490782) (xy 352.899249 -276.454928) (xy 352.940957 -276.425157)
			(xy 352.986762 -276.402181) (xy 353.035564 -276.386551) (xy 353.086194 -276.378643) (xy 353.111816 -276.378162)
			(xy 353.137784 -276.37864) (xy 353.189079 -276.386767) (xy 353.238472 -276.402818) (xy 353.284746 -276.426398)
			(xy 353.326762 -276.456926) (xy 353.363485 -276.493651) (xy 353.394011 -276.535668) (xy 353.417588 -276.581943)
			(xy 353.433637 -276.631336) (xy 353.441761 -276.682632) (xy 353.441761 -276.734568) (xy 353.441759 -276.734583)
			(xy 353.721417 -276.734583) (xy 353.721417 -276.682649) (xy 353.729542 -276.631354) (xy 353.74559 -276.581961)
			(xy 353.769168 -276.535687) (xy 353.799694 -276.493671) (xy 353.836417 -276.456948) (xy 353.878433 -276.426422)
			(xy 353.924707 -276.402844) (xy 353.9741 -276.386796) (xy 354.025395 -276.378671) (xy 354.077329 -276.378671)
			(xy 354.128624 -276.386796) (xy 354.178017 -276.402844) (xy 354.224291 -276.426422) (xy 354.266307 -276.456948)
			(xy 354.30303 -276.493671) (xy 354.333556 -276.535687) (xy 354.357134 -276.581961) (xy 354.373182 -276.631354)
			(xy 354.381307 -276.682649) (xy 354.381816 -276.708616) (xy 354.381307 -276.734583) (xy 354.373182 -276.785878)
			(xy 354.357134 -276.835271) (xy 354.333556 -276.881545) (xy 354.30303 -276.923561) (xy 354.266307 -276.960284)
			(xy 354.224291 -276.99081) (xy 354.178017 -277.014388) (xy 354.128624 -277.030436) (xy 354.077329 -277.038561)
			(xy 354.025395 -277.038561) (xy 353.9741 -277.030436) (xy 353.924707 -277.014388) (xy 353.878433 -276.99081)
			(xy 353.836417 -276.960284) (xy 353.799694 -276.923561) (xy 353.769168 -276.881545) (xy 353.74559 -276.835271)
			(xy 353.729542 -276.785878) (xy 353.721417 -276.734583) (xy 353.441759 -276.734583) (xy 353.433637 -276.785864)
			(xy 353.417588 -276.835257) (xy 353.394011 -276.881532) (xy 353.363485 -276.923549) (xy 353.326762 -276.960274)
			(xy 353.284746 -276.990802) (xy 353.238472 -277.014382) (xy 353.189079 -277.030433) (xy 353.137784 -277.03856)
			(xy 353.111816 -277.03907) (xy 353.086194 -277.038607) (xy 353.035566 -277.030679) (xy 352.986766 -277.015041)
			(xy 352.940959 -276.992066) (xy 352.899243 -276.962305) (xy 352.862613 -276.926468) (xy 352.846894 -276.906228)
			(xy 352.436938 -276.906228) (xy 352.421244 -276.926489) (xy 352.38462 -276.962339) (xy 352.342902 -276.992105)
			(xy 352.297088 -277.015074) (xy 352.248277 -277.030695) (xy 352.197641 -277.038594) (xy 352.172016 -277.03907)
			(xy 352.146047 -277.038556) (xy 352.094749 -277.030434) (xy 352.045352 -277.014386) (xy 351.999075 -276.990808)
			(xy 351.957055 -276.960281) (xy 351.920329 -276.923557) (xy 351.8898 -276.881539) (xy 351.86622 -276.835263)
			(xy 351.85017 -276.785867) (xy 351.842045 -276.734569) (xy 351.562163 -276.734569) (xy 351.562123 -276.736602)
			(xy 351.552669 -276.79177) (xy 351.543874 -276.818344) (xy 351.536 -276.840442) (xy 351.739708 -277.193248)
			(xy 351.762822 -277.197566) (xy 351.787741 -277.202747) (xy 351.835725 -277.219709) (xy 351.880543 -277.243824)
			(xy 351.921136 -277.274522) (xy 351.956545 -277.311079) (xy 351.985934 -277.35263) (xy 352.008609 -277.398194)
			(xy 352.024033 -277.446694) (xy 352.031843 -277.496985) (xy 352.032316 -277.522432) (xy 352.031807 -277.548399)
			(xy 352.311717 -277.548399) (xy 352.311717 -277.496465) (xy 352.319842 -277.44517) (xy 352.33589 -277.395777)
			(xy 352.359468 -277.349503) (xy 352.389994 -277.307487) (xy 352.426717 -277.270764) (xy 352.468733 -277.240238)
			(xy 352.515007 -277.21666) (xy 352.5644 -277.200612) (xy 352.615695 -277.192487) (xy 352.667629 -277.192487)
			(xy 352.718924 -277.200612) (xy 352.768317 -277.21666) (xy 352.814591 -277.240238) (xy 352.856607 -277.270764)
			(xy 352.89333 -277.307487) (xy 352.923856 -277.349503) (xy 352.947434 -277.395777) (xy 352.963482 -277.44517)
			(xy 352.971607 -277.496465) (xy 352.972116 -277.522432) (xy 352.971607 -277.548399) (xy 353.251517 -277.548399)
			(xy 353.251517 -277.496465) (xy 353.259642 -277.44517) (xy 353.27569 -277.395777) (xy 353.299268 -277.349503)
			(xy 353.329794 -277.307487) (xy 353.366517 -277.270764) (xy 353.408533 -277.240238) (xy 353.454807 -277.21666)
			(xy 353.5042 -277.200612) (xy 353.555495 -277.192487) (xy 353.607429 -277.192487) (xy 353.658724 -277.200612)
			(xy 353.708117 -277.21666) (xy 353.754391 -277.240238) (xy 353.796407 -277.270764) (xy 353.83313 -277.307487)
			(xy 353.863656 -277.349503) (xy 353.887234 -277.395777) (xy 353.903282 -277.44517) (xy 353.911407 -277.496465)
			(xy 353.911916 -277.522432) (xy 354.190808 -277.522432) (xy 354.191264 -277.496981) (xy 354.199051 -277.446677)
			(xy 354.214461 -277.398163) (xy 354.237129 -277.352587) (xy 354.266519 -277.311026) (xy 354.301936 -277.274465)
			(xy 354.342541 -277.243769) (xy 354.387374 -277.219663) (xy 354.435373 -277.202718) (xy 354.460302 -277.197566)
			(xy 354.483416 -277.193248) (xy 354.687378 -276.839934) (xy 354.679504 -276.817836) (xy 354.670884 -276.791421)
			(xy 354.661558 -276.736649) (xy 354.660962 -276.70887) (xy 354.660962 -276.708616) (xy 354.661471 -276.682649)
			(xy 354.669596 -276.631354) (xy 354.685644 -276.581961) (xy 354.709222 -276.535687) (xy 354.739748 -276.493671)
			(xy 354.776471 -276.456948) (xy 354.818487 -276.426422) (xy 354.864761 -276.402844) (xy 354.914154 -276.386796)
			(xy 354.965449 -276.378671) (xy 355.017383 -276.378671) (xy 355.068678 -276.386796) (xy 355.118071 -276.402844)
			(xy 355.164345 -276.426422) (xy 355.206361 -276.456948) (xy 355.243084 -276.493671) (xy 355.27361 -276.535687)
			(xy 355.297188 -276.581961) (xy 355.313236 -276.631354) (xy 355.321361 -276.682649) (xy 355.32187 -276.708616)
			(xy 355.321389 -276.734089) (xy 355.321312 -276.734583) (xy 355.601271 -276.734583) (xy 355.601271 -276.682649)
			(xy 355.609396 -276.631354) (xy 355.625444 -276.581961) (xy 355.649022 -276.535687) (xy 355.679548 -276.493671)
			(xy 355.716271 -276.456948) (xy 355.758287 -276.426422) (xy 355.804561 -276.402844) (xy 355.853954 -276.386796)
			(xy 355.905249 -276.378671) (xy 355.957183 -276.378671) (xy 356.008478 -276.386796) (xy 356.057871 -276.402844)
			(xy 356.104145 -276.426422) (xy 356.146161 -276.456948) (xy 356.182884 -276.493671) (xy 356.21341 -276.535687)
			(xy 356.236988 -276.581961) (xy 356.253036 -276.631354) (xy 356.261161 -276.682649) (xy 356.26167 -276.708616)
			(xy 356.261161 -276.734583) (xy 356.253036 -276.785878) (xy 356.236988 -276.835271) (xy 356.21341 -276.881545)
			(xy 356.182884 -276.923561) (xy 356.146161 -276.960284) (xy 356.104145 -276.99081) (xy 356.057871 -277.014388)
			(xy 356.008478 -277.030436) (xy 355.957183 -277.038561) (xy 355.905249 -277.038561) (xy 355.853954 -277.030436)
			(xy 355.804561 -277.014388) (xy 355.758287 -276.99081) (xy 355.716271 -276.960284) (xy 355.679548 -276.923561)
			(xy 355.649022 -276.881545) (xy 355.625444 -276.835271) (xy 355.609396 -276.785878) (xy 355.601271 -276.734583)
			(xy 355.321312 -276.734583) (xy 355.313568 -276.784431) (xy 355.298113 -276.832977) (xy 355.275391 -276.878575)
			(xy 355.24594 -276.920146) (xy 355.210458 -276.956705) (xy 355.169786 -276.987385) (xy 355.124887 -277.01146)
			(xy 355.076825 -277.028358) (xy 355.051868 -277.033482) (xy 355.029008 -277.0378) (xy 354.8253 -277.390606)
			(xy 354.83292 -277.412704) (xy 354.841659 -277.439292) (xy 354.851106 -277.494451) (xy 354.851716 -277.522432)
			(xy 355.130608 -277.522432) (xy 355.131117 -277.496465) (xy 355.139242 -277.44517) (xy 355.15529 -277.395777)
			(xy 355.178868 -277.349503) (xy 355.209394 -277.307487) (xy 355.246117 -277.270764) (xy 355.288133 -277.240238)
			(xy 355.334407 -277.21666) (xy 355.3838 -277.200612) (xy 355.435095 -277.192487) (xy 355.487029 -277.192487)
			(xy 355.538324 -277.200612) (xy 355.587717 -277.21666) (xy 355.633991 -277.240238) (xy 355.676007 -277.270764)
			(xy 355.71273 -277.307487) (xy 355.743256 -277.349503) (xy 355.766834 -277.395777) (xy 355.782882 -277.44517)
			(xy 355.791007 -277.496465) (xy 355.791516 -277.522432) (xy 355.791516 -277.523194) (xy 355.790931 -277.550912)
			(xy 355.781605 -277.605559) (xy 355.772974 -277.631906) (xy 355.7651 -277.654004) (xy 355.969062 -278.007318)
			(xy 355.992176 -278.011636) (xy 356.017097 -278.016806) (xy 356.065078 -278.033774) (xy 356.109894 -278.057893)
			(xy 356.150485 -278.088593) (xy 356.185893 -278.125151) (xy 356.215281 -278.166702) (xy 356.237956 -278.212265)
			(xy 356.253382 -278.260765) (xy 356.261194 -278.311055) (xy 356.26167 -278.336502) (xy 356.261161 -278.362469)
			(xy 356.253036 -278.413764) (xy 356.236988 -278.463157) (xy 356.21341 -278.509431) (xy 356.182884 -278.551447)
			(xy 356.146161 -278.58817) (xy 356.104145 -278.618696) (xy 356.057871 -278.642274) (xy 356.008478 -278.658322)
			(xy 355.957183 -278.666447) (xy 355.905249 -278.666447) (xy 355.853954 -278.658322) (xy 355.804561 -278.642274)
			(xy 355.758287 -278.618696) (xy 355.716271 -278.58817) (xy 355.679548 -278.551447) (xy 355.649022 -278.509431)
			(xy 355.625444 -278.463157) (xy 355.609396 -278.413764) (xy 355.601271 -278.362469) (xy 355.600762 -278.336502)
			(xy 355.601312 -278.308516) (xy 355.610763 -278.253348) (xy 355.619558 -278.226774) (xy 355.627178 -278.204676)
			(xy 355.42347 -277.851616) (xy 355.400356 -277.847298) (xy 355.375423 -277.842122) (xy 355.327398 -277.825198)
			(xy 355.282538 -277.801109) (xy 355.241903 -277.770423) (xy 355.206455 -277.733869) (xy 355.177034 -277.69231)
			(xy 355.154334 -277.64673) (xy 355.138895 -277.598208) (xy 355.13108 -277.547892) (xy 355.130608 -277.522432)
			(xy 354.851716 -277.522432) (xy 354.851207 -277.548399) (xy 354.843082 -277.599694) (xy 354.827034 -277.649087)
			(xy 354.803456 -277.695361) (xy 354.77293 -277.737377) (xy 354.736207 -277.7741) (xy 354.694191 -277.804626)
			(xy 354.647917 -277.828204) (xy 354.598524 -277.844252) (xy 354.547229 -277.852377) (xy 354.495295 -277.852377)
			(xy 354.444 -277.844252) (xy 354.394607 -277.828204) (xy 354.348333 -277.804626) (xy 354.306317 -277.7741)
			(xy 354.269594 -277.737377) (xy 354.239068 -277.695361) (xy 354.21549 -277.649087) (xy 354.199442 -277.599694)
			(xy 354.191317 -277.548399) (xy 354.190808 -277.522432) (xy 353.911916 -277.522432) (xy 353.911407 -277.548399)
			(xy 353.903282 -277.599694) (xy 353.887234 -277.649087) (xy 353.863656 -277.695361) (xy 353.83313 -277.737377)
			(xy 353.796407 -277.7741) (xy 353.754391 -277.804626) (xy 353.708117 -277.828204) (xy 353.658724 -277.844252)
			(xy 353.607429 -277.852377) (xy 353.555495 -277.852377) (xy 353.5042 -277.844252) (xy 353.454807 -277.828204)
			(xy 353.408533 -277.804626) (xy 353.366517 -277.7741) (xy 353.329794 -277.737377) (xy 353.299268 -277.695361)
			(xy 353.27569 -277.649087) (xy 353.259642 -277.599694) (xy 353.251517 -277.548399) (xy 352.971607 -277.548399)
			(xy 352.963482 -277.599694) (xy 352.947434 -277.649087) (xy 352.923856 -277.695361) (xy 352.89333 -277.737377)
			(xy 352.856607 -277.7741) (xy 352.814591 -277.804626) (xy 352.768317 -277.828204) (xy 352.718924 -277.844252)
			(xy 352.667629 -277.852377) (xy 352.615695 -277.852377) (xy 352.5644 -277.844252) (xy 352.515007 -277.828204)
			(xy 352.468733 -277.804626) (xy 352.426717 -277.7741) (xy 352.389994 -277.737377) (xy 352.359468 -277.695361)
			(xy 352.33589 -277.649087) (xy 352.319842 -277.599694) (xy 352.311717 -277.548399) (xy 352.031807 -277.548399)
			(xy 352.023682 -277.599694) (xy 352.007634 -277.649087) (xy 351.984056 -277.695361) (xy 351.95353 -277.737377)
			(xy 351.916807 -277.7741) (xy 351.874791 -277.804626) (xy 351.828517 -277.828204) (xy 351.779124 -277.844252)
			(xy 351.727829 -277.852377) (xy 351.675895 -277.852377) (xy 351.6246 -277.844252) (xy 351.575207 -277.828204)
			(xy 351.528933 -277.804626) (xy 351.486917 -277.7741) (xy 351.450194 -277.737377) (xy 351.419668 -277.695361)
			(xy 351.39609 -277.649087) (xy 351.380042 -277.599694) (xy 351.371917 -277.548399) (xy 351.371408 -277.522432)
			(xy 351.371968 -277.494447) (xy 351.381413 -277.439279) (xy 351.390204 -277.412704) (xy 351.397824 -277.390606)
			(xy 351.194116 -277.0378) (xy 351.171256 -277.033482) (xy 351.146322 -277.028366) (xy 351.098334 -277.011397)
			(xy 351.053514 -276.987274) (xy 351.01292 -276.956568) (xy 350.977511 -276.920003) (xy 350.948124 -276.878444)
			(xy 350.925453 -276.832872) (xy 350.910035 -276.784364) (xy 350.902232 -276.734066) (xy 350.901762 -276.708616)
			(xy 350.622616 -276.708616) (xy 350.622107 -276.734583) (xy 350.613982 -276.785878) (xy 350.597934 -276.835271)
			(xy 350.574356 -276.881545) (xy 350.54383 -276.923561) (xy 350.507107 -276.960284) (xy 350.465091 -276.99081)
			(xy 350.418817 -277.014388) (xy 350.369424 -277.030436) (xy 350.318129 -277.038561) (xy 350.266195 -277.038561)
			(xy 350.2149 -277.030436) (xy 350.165507 -277.014388) (xy 350.119233 -276.99081) (xy 350.077217 -276.960284)
			(xy 350.040494 -276.923561) (xy 350.009968 -276.881545) (xy 349.98639 -276.835271) (xy 349.970342 -276.785878)
			(xy 349.962217 -276.734583) (xy 349.961708 -276.708616) (xy 349.68307 -276.708616) (xy 349.682561 -276.734583)
			(xy 349.674436 -276.785878) (xy 349.658388 -276.835271) (xy 349.63481 -276.881545) (xy 349.604284 -276.923561)
			(xy 349.567561 -276.960284) (xy 349.525545 -276.99081) (xy 349.479271 -277.014388) (xy 349.429878 -277.030436)
			(xy 349.378583 -277.038561) (xy 349.326649 -277.038561) (xy 349.275354 -277.030436) (xy 349.225961 -277.014388)
			(xy 349.179687 -276.99081) (xy 349.137671 -276.960284) (xy 349.100948 -276.923561) (xy 349.070422 -276.881545)
			(xy 349.046844 -276.835271) (xy 349.030796 -276.785878) (xy 349.022671 -276.734583) (xy 348.742761 -276.734583)
			(xy 348.734636 -276.785878) (xy 348.718588 -276.835271) (xy 348.69501 -276.881545) (xy 348.664484 -276.923561)
			(xy 348.627761 -276.960284) (xy 348.585745 -276.99081) (xy 348.539471 -277.014388) (xy 348.490078 -277.030436)
			(xy 348.438783 -277.038561) (xy 348.386849 -277.038561) (xy 348.335554 -277.030436) (xy 348.286161 -277.014388)
			(xy 348.239887 -276.99081) (xy 348.197871 -276.960284) (xy 348.161148 -276.923561) (xy 348.130622 -276.881545)
			(xy 348.107044 -276.835271) (xy 348.090996 -276.785878) (xy 348.082871 -276.734583) (xy 347.802961 -276.734583)
			(xy 347.794836 -276.785878) (xy 347.778788 -276.835271) (xy 347.75521 -276.881545) (xy 347.724684 -276.923561)
			(xy 347.687961 -276.960284) (xy 347.645945 -276.99081) (xy 347.599671 -277.014388) (xy 347.550278 -277.030436)
			(xy 347.498983 -277.038561) (xy 347.447049 -277.038561) (xy 347.395754 -277.030436) (xy 347.346361 -277.014388)
			(xy 347.300087 -276.99081) (xy 347.258071 -276.960284) (xy 347.221348 -276.923561) (xy 347.190822 -276.881545)
			(xy 347.167244 -276.835271) (xy 347.151196 -276.785878) (xy 347.143071 -276.734583) (xy 346.863161 -276.734583)
			(xy 346.855036 -276.785878) (xy 346.838988 -276.835271) (xy 346.81541 -276.881545) (xy 346.784884 -276.923561)
			(xy 346.748161 -276.960284) (xy 346.706145 -276.99081) (xy 346.659871 -277.014388) (xy 346.610478 -277.030436)
			(xy 346.559183 -277.038561) (xy 346.507249 -277.038561) (xy 346.455954 -277.030436) (xy 346.406561 -277.014388)
			(xy 346.360287 -276.99081) (xy 346.318271 -276.960284) (xy 346.281548 -276.923561) (xy 346.251022 -276.881545)
			(xy 346.227444 -276.835271) (xy 346.211396 -276.785878) (xy 346.203271 -276.734583) (xy 345.923107 -276.734583)
			(xy 345.914982 -276.785878) (xy 345.898934 -276.835271) (xy 345.875356 -276.881545) (xy 345.84483 -276.923561)
			(xy 345.808107 -276.960284) (xy 345.766091 -276.99081) (xy 345.719817 -277.014388) (xy 345.670424 -277.030436)
			(xy 345.619129 -277.038561) (xy 345.567195 -277.038561) (xy 345.5159 -277.030436) (xy 345.466507 -277.014388)
			(xy 345.420233 -276.99081) (xy 345.378217 -276.960284) (xy 345.341494 -276.923561) (xy 345.310968 -276.881545)
			(xy 345.28739 -276.835271) (xy 345.271342 -276.785878) (xy 345.263217 -276.734583) (xy 344.983561 -276.734583)
			(xy 344.975436 -276.785878) (xy 344.959388 -276.835271) (xy 344.93581 -276.881545) (xy 344.905284 -276.923561)
			(xy 344.868561 -276.960284) (xy 344.826545 -276.99081) (xy 344.780271 -277.014388) (xy 344.730878 -277.030436)
			(xy 344.679583 -277.038561) (xy 344.627649 -277.038561) (xy 344.576354 -277.030436) (xy 344.526961 -277.014388)
			(xy 344.480687 -276.99081) (xy 344.438671 -276.960284) (xy 344.401948 -276.923561) (xy 344.371422 -276.881545)
			(xy 344.347844 -276.835271) (xy 344.331796 -276.785878) (xy 344.323671 -276.734583) (xy 344.043761 -276.734583)
			(xy 344.035636 -276.785878) (xy 344.019588 -276.835271) (xy 343.99601 -276.881545) (xy 343.965484 -276.923561)
			(xy 343.928761 -276.960284) (xy 343.886745 -276.99081) (xy 343.840471 -277.014388) (xy 343.791078 -277.030436)
			(xy 343.739783 -277.038561) (xy 343.687849 -277.038561) (xy 343.636554 -277.030436) (xy 343.587161 -277.014388)
			(xy 343.540887 -276.99081) (xy 343.498871 -276.960284) (xy 343.462148 -276.923561) (xy 343.431622 -276.881545)
			(xy 343.408044 -276.835271) (xy 343.391996 -276.785878) (xy 343.383871 -276.734583) (xy 343.103961 -276.734583)
			(xy 343.095836 -276.785878) (xy 343.079788 -276.835271) (xy 343.05621 -276.881545) (xy 343.025684 -276.923561)
			(xy 342.988961 -276.960284) (xy 342.946945 -276.99081) (xy 342.900671 -277.014388) (xy 342.851278 -277.030436)
			(xy 342.799983 -277.038561) (xy 342.748049 -277.038561) (xy 342.696754 -277.030436) (xy 342.647361 -277.014388)
			(xy 342.601087 -276.99081) (xy 342.559071 -276.960284) (xy 342.522348 -276.923561) (xy 342.491822 -276.881545)
			(xy 342.468244 -276.835271) (xy 342.452196 -276.785878) (xy 342.444071 -276.734583) (xy 342.164161 -276.734583)
			(xy 342.156036 -276.785878) (xy 342.139988 -276.835271) (xy 342.11641 -276.881545) (xy 342.085884 -276.923561)
			(xy 342.049161 -276.960284) (xy 342.007145 -276.99081) (xy 341.960871 -277.014388) (xy 341.911478 -277.030436)
			(xy 341.860183 -277.038561) (xy 341.808249 -277.038561) (xy 341.756954 -277.030436) (xy 341.707561 -277.014388)
			(xy 341.661287 -276.99081) (xy 341.619271 -276.960284) (xy 341.582548 -276.923561) (xy 341.552022 -276.881545)
			(xy 341.528444 -276.835271) (xy 341.512396 -276.785878) (xy 341.504271 -276.734583) (xy 341.224361 -276.734583)
			(xy 341.216236 -276.785878) (xy 341.200188 -276.835271) (xy 341.17661 -276.881545) (xy 341.146084 -276.923561)
			(xy 341.109361 -276.960284) (xy 341.067345 -276.99081) (xy 341.021071 -277.014388) (xy 340.971678 -277.030436)
			(xy 340.920383 -277.038561) (xy 340.868449 -277.038561) (xy 340.817154 -277.030436) (xy 340.767761 -277.014388)
			(xy 340.721487 -276.99081) (xy 340.679471 -276.960284) (xy 340.642748 -276.923561) (xy 340.612222 -276.881545)
			(xy 340.588644 -276.835271) (xy 340.572596 -276.785878) (xy 340.564471 -276.734583) (xy 340.284783 -276.734583)
			(xy 340.284783 -276.734585) (xy 340.276653 -276.785916) (xy 340.260594 -276.835342) (xy 340.237 -276.881649)
			(xy 340.206454 -276.923694) (xy 340.169706 -276.960443) (xy 340.127662 -276.990992) (xy 340.081357 -277.014588)
			(xy 340.031931 -277.030649) (xy 339.980601 -277.038781) (xy 339.954616 -277.039324) (xy 339.931701 -277.038934)
			(xy 339.88631 -277.0326) (xy 339.842231 -277.020053) (xy 339.80031 -277.001533) (xy 339.780626 -276.989794)
			(xy 339.780372 -276.989794) (xy 339.772615 -276.985394) (xy 339.755157 -276.981821) (xy 339.737542 -276.984523)
			(xy 339.729572 -276.988524) (xy 339.691218 -277.010114) (xy 339.65134 -277.032466) (xy 339.644242 -277.037223)
			(xy 339.633504 -277.0505) (xy 339.627816 -277.0666) (xy 339.627464 -277.075138) (xy 339.627464 -277.194264)
			(xy 339.651848 -277.236936) (xy 339.662516 -277.243794) (xy 339.683764 -277.257917) (xy 339.722041 -277.291647)
			(xy 339.754681 -277.330859) (xy 339.780908 -277.37462) (xy 339.800098 -277.421891) (xy 339.811797 -277.47155)
			(xy 339.815725 -277.522417) (xy 339.813716 -277.548399) (xy 340.094317 -277.548399) (xy 340.094317 -277.496465)
			(xy 340.102442 -277.44517) (xy 340.11849 -277.395777) (xy 340.142068 -277.349503) (xy 340.172594 -277.307487)
			(xy 340.209317 -277.270764) (xy 340.251333 -277.240238) (xy 340.297607 -277.21666) (xy 340.347 -277.200612)
			(xy 340.398295 -277.192487) (xy 340.450229 -277.192487) (xy 340.501524 -277.200612) (xy 340.550917 -277.21666)
			(xy 340.597191 -277.240238) (xy 340.639207 -277.270764) (xy 340.67593 -277.307487) (xy 340.706456 -277.349503)
			(xy 340.730034 -277.395777) (xy 340.746082 -277.44517) (xy 340.754207 -277.496465) (xy 340.754716 -277.522432)
			(xy 340.754207 -277.548399) (xy 341.034117 -277.548399) (xy 341.034117 -277.496465) (xy 341.042242 -277.44517)
			(xy 341.05829 -277.395777) (xy 341.081868 -277.349503) (xy 341.112394 -277.307487) (xy 341.149117 -277.270764)
			(xy 341.191133 -277.240238) (xy 341.237407 -277.21666) (xy 341.2868 -277.200612) (xy 341.338095 -277.192487)
			(xy 341.390029 -277.192487) (xy 341.441324 -277.200612) (xy 341.490717 -277.21666) (xy 341.536991 -277.240238)
			(xy 341.579007 -277.270764) (xy 341.61573 -277.307487) (xy 341.646256 -277.349503) (xy 341.669834 -277.395777)
			(xy 341.685882 -277.44517) (xy 341.694007 -277.496465) (xy 341.694516 -277.522432) (xy 341.694007 -277.548399)
			(xy 341.973917 -277.548399) (xy 341.973917 -277.496465) (xy 341.982042 -277.44517) (xy 341.99809 -277.395777)
			(xy 342.021668 -277.349503) (xy 342.052194 -277.307487) (xy 342.088917 -277.270764) (xy 342.130933 -277.240238)
			(xy 342.177207 -277.21666) (xy 342.2266 -277.200612) (xy 342.277895 -277.192487) (xy 342.329829 -277.192487)
			(xy 342.381124 -277.200612) (xy 342.430517 -277.21666) (xy 342.476791 -277.240238) (xy 342.518807 -277.270764)
			(xy 342.55553 -277.307487) (xy 342.586056 -277.349503) (xy 342.609634 -277.395777) (xy 342.625682 -277.44517)
			(xy 342.633807 -277.496465) (xy 342.634316 -277.522432) (xy 342.633807 -277.548399) (xy 342.913717 -277.548399)
			(xy 342.913717 -277.496465) (xy 342.921842 -277.44517) (xy 342.93789 -277.395777) (xy 342.961468 -277.349503)
			(xy 342.991994 -277.307487) (xy 343.028717 -277.270764) (xy 343.070733 -277.240238) (xy 343.117007 -277.21666)
			(xy 343.1664 -277.200612) (xy 343.217695 -277.192487) (xy 343.269629 -277.192487) (xy 343.320924 -277.200612)
			(xy 343.370317 -277.21666) (xy 343.416591 -277.240238) (xy 343.458607 -277.270764) (xy 343.49533 -277.307487)
			(xy 343.525856 -277.349503) (xy 343.549434 -277.395777) (xy 343.565482 -277.44517) (xy 343.573607 -277.496465)
			(xy 343.574116 -277.522432) (xy 343.573607 -277.548399) (xy 343.853517 -277.548399) (xy 343.853517 -277.496465)
			(xy 343.861642 -277.44517) (xy 343.87769 -277.395777) (xy 343.901268 -277.349503) (xy 343.931794 -277.307487)
			(xy 343.968517 -277.270764) (xy 344.010533 -277.240238) (xy 344.056807 -277.21666) (xy 344.1062 -277.200612)
			(xy 344.157495 -277.192487) (xy 344.209429 -277.192487) (xy 344.260724 -277.200612) (xy 344.310117 -277.21666)
			(xy 344.356391 -277.240238) (xy 344.398407 -277.270764) (xy 344.43513 -277.307487) (xy 344.465656 -277.349503)
			(xy 344.489234 -277.395777) (xy 344.505282 -277.44517) (xy 344.513407 -277.496465) (xy 344.513916 -277.522432)
			(xy 344.513407 -277.548399) (xy 344.793317 -277.548399) (xy 344.793317 -277.496465) (xy 344.801442 -277.44517)
			(xy 344.81749 -277.395777) (xy 344.841068 -277.349503) (xy 344.871594 -277.307487) (xy 344.908317 -277.270764)
			(xy 344.950333 -277.240238) (xy 344.996607 -277.21666) (xy 345.046 -277.200612) (xy 345.097295 -277.192487)
			(xy 345.149229 -277.192487) (xy 345.200524 -277.200612) (xy 345.249917 -277.21666) (xy 345.296191 -277.240238)
			(xy 345.338207 -277.270764) (xy 345.37493 -277.307487) (xy 345.405456 -277.349503) (xy 345.429034 -277.395777)
			(xy 345.445082 -277.44517) (xy 345.453207 -277.496465) (xy 345.453716 -277.522432) (xy 345.453207 -277.548399)
			(xy 345.733117 -277.548399) (xy 345.733117 -277.496465) (xy 345.741242 -277.44517) (xy 345.75729 -277.395777)
			(xy 345.780868 -277.349503) (xy 345.811394 -277.307487) (xy 345.848117 -277.270764) (xy 345.890133 -277.240238)
			(xy 345.936407 -277.21666) (xy 345.9858 -277.200612) (xy 346.037095 -277.192487) (xy 346.089029 -277.192487)
			(xy 346.140324 -277.200612) (xy 346.189717 -277.21666) (xy 346.235991 -277.240238) (xy 346.278007 -277.270764)
			(xy 346.31473 -277.307487) (xy 346.345256 -277.349503) (xy 346.368834 -277.395777) (xy 346.384882 -277.44517)
			(xy 346.393007 -277.496465) (xy 346.393516 -277.522432) (xy 346.393007 -277.548399) (xy 346.672917 -277.548399)
			(xy 346.672917 -277.496465) (xy 346.681042 -277.44517) (xy 346.69709 -277.395777) (xy 346.720668 -277.349503)
			(xy 346.751194 -277.307487) (xy 346.787917 -277.270764) (xy 346.829933 -277.240238) (xy 346.876207 -277.21666)
			(xy 346.9256 -277.200612) (xy 346.976895 -277.192487) (xy 347.028829 -277.192487) (xy 347.080124 -277.200612)
			(xy 347.129517 -277.21666) (xy 347.175791 -277.240238) (xy 347.217807 -277.270764) (xy 347.25453 -277.307487)
			(xy 347.285056 -277.349503) (xy 347.308634 -277.395777) (xy 347.324682 -277.44517) (xy 347.332807 -277.496465)
			(xy 347.333316 -277.522432) (xy 347.332807 -277.548399) (xy 347.612717 -277.548399) (xy 347.612717 -277.496465)
			(xy 347.620842 -277.44517) (xy 347.63689 -277.395777) (xy 347.660468 -277.349503) (xy 347.690994 -277.307487)
			(xy 347.727717 -277.270764) (xy 347.769733 -277.240238) (xy 347.816007 -277.21666) (xy 347.8654 -277.200612)
			(xy 347.916695 -277.192487) (xy 347.968629 -277.192487) (xy 348.019924 -277.200612) (xy 348.069317 -277.21666)
			(xy 348.115591 -277.240238) (xy 348.157607 -277.270764) (xy 348.19433 -277.307487) (xy 348.224856 -277.349503)
			(xy 348.248434 -277.395777) (xy 348.264482 -277.44517) (xy 348.272607 -277.496465) (xy 348.273116 -277.522432)
			(xy 348.272607 -277.548399) (xy 348.552517 -277.548399) (xy 348.552517 -277.496465) (xy 348.560642 -277.44517)
			(xy 348.57669 -277.395777) (xy 348.600268 -277.349503) (xy 348.630794 -277.307487) (xy 348.667517 -277.270764)
			(xy 348.709533 -277.240238) (xy 348.755807 -277.21666) (xy 348.8052 -277.200612) (xy 348.856495 -277.192487)
			(xy 348.908429 -277.192487) (xy 348.959724 -277.200612) (xy 349.009117 -277.21666) (xy 349.055391 -277.240238)
			(xy 349.097407 -277.270764) (xy 349.13413 -277.307487) (xy 349.164656 -277.349503) (xy 349.188234 -277.395777)
			(xy 349.204282 -277.44517) (xy 349.212407 -277.496465) (xy 349.212916 -277.522432) (xy 349.212407 -277.548399)
			(xy 349.492571 -277.548399) (xy 349.492571 -277.496465) (xy 349.500696 -277.44517) (xy 349.516744 -277.395777)
			(xy 349.540322 -277.349503) (xy 349.570848 -277.307487) (xy 349.607571 -277.270764) (xy 349.649587 -277.240238)
			(xy 349.695861 -277.21666) (xy 349.745254 -277.200612) (xy 349.796549 -277.192487) (xy 349.848483 -277.192487)
			(xy 349.899778 -277.200612) (xy 349.949171 -277.21666) (xy 349.995445 -277.240238) (xy 350.037461 -277.270764)
			(xy 350.074184 -277.307487) (xy 350.10471 -277.349503) (xy 350.128288 -277.395777) (xy 350.144336 -277.44517)
			(xy 350.152461 -277.496465) (xy 350.15297 -277.522432) (xy 350.152461 -277.548399) (xy 350.144336 -277.599694)
			(xy 350.128288 -277.649087) (xy 350.10471 -277.695361) (xy 350.074184 -277.737377) (xy 350.037461 -277.7741)
			(xy 349.995445 -277.804626) (xy 349.949171 -277.828204) (xy 349.899778 -277.844252) (xy 349.848483 -277.852377)
			(xy 349.796549 -277.852377) (xy 349.745254 -277.844252) (xy 349.695861 -277.828204) (xy 349.649587 -277.804626)
			(xy 349.607571 -277.7741) (xy 349.570848 -277.737377) (xy 349.540322 -277.695361) (xy 349.516744 -277.649087)
			(xy 349.500696 -277.599694) (xy 349.492571 -277.548399) (xy 349.212407 -277.548399) (xy 349.204282 -277.599694)
			(xy 349.188234 -277.649087) (xy 349.164656 -277.695361) (xy 349.13413 -277.737377) (xy 349.097407 -277.7741)
			(xy 349.055391 -277.804626) (xy 349.009117 -277.828204) (xy 348.959724 -277.844252) (xy 348.908429 -277.852377)
			(xy 348.856495 -277.852377) (xy 348.8052 -277.844252) (xy 348.755807 -277.828204) (xy 348.709533 -277.804626)
			(xy 348.667517 -277.7741) (xy 348.630794 -277.737377) (xy 348.600268 -277.695361) (xy 348.57669 -277.649087)
			(xy 348.560642 -277.599694) (xy 348.552517 -277.548399) (xy 348.272607 -277.548399) (xy 348.264482 -277.599694)
			(xy 348.248434 -277.649087) (xy 348.224856 -277.695361) (xy 348.19433 -277.737377) (xy 348.157607 -277.7741)
			(xy 348.115591 -277.804626) (xy 348.069317 -277.828204) (xy 348.019924 -277.844252) (xy 347.968629 -277.852377)
			(xy 347.916695 -277.852377) (xy 347.8654 -277.844252) (xy 347.816007 -277.828204) (xy 347.769733 -277.804626)
			(xy 347.727717 -277.7741) (xy 347.690994 -277.737377) (xy 347.660468 -277.695361) (xy 347.63689 -277.649087)
			(xy 347.620842 -277.599694) (xy 347.612717 -277.548399) (xy 347.332807 -277.548399) (xy 347.324682 -277.599694)
			(xy 347.308634 -277.649087) (xy 347.285056 -277.695361) (xy 347.25453 -277.737377) (xy 347.217807 -277.7741)
			(xy 347.175791 -277.804626) (xy 347.129517 -277.828204) (xy 347.080124 -277.844252) (xy 347.028829 -277.852377)
			(xy 346.976895 -277.852377) (xy 346.9256 -277.844252) (xy 346.876207 -277.828204) (xy 346.829933 -277.804626)
			(xy 346.787917 -277.7741) (xy 346.751194 -277.737377) (xy 346.720668 -277.695361) (xy 346.69709 -277.649087)
			(xy 346.681042 -277.599694) (xy 346.672917 -277.548399) (xy 346.393007 -277.548399) (xy 346.384882 -277.599694)
			(xy 346.368834 -277.649087) (xy 346.345256 -277.695361) (xy 346.31473 -277.737377) (xy 346.278007 -277.7741)
			(xy 346.235991 -277.804626) (xy 346.189717 -277.828204) (xy 346.140324 -277.844252) (xy 346.089029 -277.852377)
			(xy 346.037095 -277.852377) (xy 345.9858 -277.844252) (xy 345.936407 -277.828204) (xy 345.890133 -277.804626)
			(xy 345.848117 -277.7741) (xy 345.811394 -277.737377) (xy 345.780868 -277.695361) (xy 345.75729 -277.649087)
			(xy 345.741242 -277.599694) (xy 345.733117 -277.548399) (xy 345.453207 -277.548399) (xy 345.445082 -277.599694)
			(xy 345.429034 -277.649087) (xy 345.405456 -277.695361) (xy 345.37493 -277.737377) (xy 345.338207 -277.7741)
			(xy 345.296191 -277.804626) (xy 345.249917 -277.828204) (xy 345.200524 -277.844252) (xy 345.149229 -277.852377)
			(xy 345.097295 -277.852377) (xy 345.046 -277.844252) (xy 344.996607 -277.828204) (xy 344.950333 -277.804626)
			(xy 344.908317 -277.7741) (xy 344.871594 -277.737377) (xy 344.841068 -277.695361) (xy 344.81749 -277.649087)
			(xy 344.801442 -277.599694) (xy 344.793317 -277.548399) (xy 344.513407 -277.548399) (xy 344.505282 -277.599694)
			(xy 344.489234 -277.649087) (xy 344.465656 -277.695361) (xy 344.43513 -277.737377) (xy 344.398407 -277.7741)
			(xy 344.356391 -277.804626) (xy 344.310117 -277.828204) (xy 344.260724 -277.844252) (xy 344.209429 -277.852377)
			(xy 344.157495 -277.852377) (xy 344.1062 -277.844252) (xy 344.056807 -277.828204) (xy 344.010533 -277.804626)
			(xy 343.968517 -277.7741) (xy 343.931794 -277.737377) (xy 343.901268 -277.695361) (xy 343.87769 -277.649087)
			(xy 343.861642 -277.599694) (xy 343.853517 -277.548399) (xy 343.573607 -277.548399) (xy 343.565482 -277.599694)
			(xy 343.549434 -277.649087) (xy 343.525856 -277.695361) (xy 343.49533 -277.737377) (xy 343.458607 -277.7741)
			(xy 343.416591 -277.804626) (xy 343.370317 -277.828204) (xy 343.320924 -277.844252) (xy 343.269629 -277.852377)
			(xy 343.217695 -277.852377) (xy 343.1664 -277.844252) (xy 343.117007 -277.828204) (xy 343.070733 -277.804626)
			(xy 343.028717 -277.7741) (xy 342.991994 -277.737377) (xy 342.961468 -277.695361) (xy 342.93789 -277.649087)
			(xy 342.921842 -277.599694) (xy 342.913717 -277.548399) (xy 342.633807 -277.548399) (xy 342.625682 -277.599694)
			(xy 342.609634 -277.649087) (xy 342.586056 -277.695361) (xy 342.55553 -277.737377) (xy 342.518807 -277.7741)
			(xy 342.476791 -277.804626) (xy 342.430517 -277.828204) (xy 342.381124 -277.844252) (xy 342.329829 -277.852377)
			(xy 342.277895 -277.852377) (xy 342.2266 -277.844252) (xy 342.177207 -277.828204) (xy 342.130933 -277.804626)
			(xy 342.088917 -277.7741) (xy 342.052194 -277.737377) (xy 342.021668 -277.695361) (xy 341.99809 -277.649087)
			(xy 341.982042 -277.599694) (xy 341.973917 -277.548399) (xy 341.694007 -277.548399) (xy 341.685882 -277.599694)
			(xy 341.669834 -277.649087) (xy 341.646256 -277.695361) (xy 341.61573 -277.737377) (xy 341.579007 -277.7741)
			(xy 341.536991 -277.804626) (xy 341.490717 -277.828204) (xy 341.441324 -277.844252) (xy 341.390029 -277.852377)
			(xy 341.338095 -277.852377) (xy 341.2868 -277.844252) (xy 341.237407 -277.828204) (xy 341.191133 -277.804626)
			(xy 341.149117 -277.7741) (xy 341.112394 -277.737377) (xy 341.081868 -277.695361) (xy 341.05829 -277.649087)
			(xy 341.042242 -277.599694) (xy 341.034117 -277.548399) (xy 340.754207 -277.548399) (xy 340.746082 -277.599694)
			(xy 340.730034 -277.649087) (xy 340.706456 -277.695361) (xy 340.67593 -277.737377) (xy 340.639207 -277.7741)
			(xy 340.597191 -277.804626) (xy 340.550917 -277.828204) (xy 340.501524 -277.844252) (xy 340.450229 -277.852377)
			(xy 340.398295 -277.852377) (xy 340.347 -277.844252) (xy 340.297607 -277.828204) (xy 340.251333 -277.804626)
			(xy 340.209317 -277.7741) (xy 340.172594 -277.737377) (xy 340.142068 -277.695361) (xy 340.11849 -277.649087)
			(xy 340.102442 -277.599694) (xy 340.094317 -277.548399) (xy 339.813716 -277.548399) (xy 339.811791 -277.573284)
			(xy 339.800088 -277.622942) (xy 339.780892 -277.670211) (xy 339.754661 -277.71397) (xy 339.722017 -277.753178)
			(xy 339.683737 -277.786904) (xy 339.662516 -277.80107) (xy 339.651848 -277.807928) (xy 339.627464 -277.8506)
			(xy 339.627464 -277.96998) (xy 339.627777 -277.978368) (xy 339.633274 -277.994216) (xy 339.643666 -278.007385)
			(xy 339.650578 -278.012144) (xy 339.718142 -278.04999) (xy 339.723391 -278.05248) (xy 339.734687 -278.05518)
			(xy 339.740494 -278.055324) (xy 339.76691 -278.055324) (xy 339.791294 -278.04872) (xy 339.795612 -278.046434)
			(xy 339.820105 -278.033666) (xy 339.872286 -278.015564) (xy 339.926747 -278.006365) (xy 339.954362 -278.005794)
			(xy 339.954616 -278.005794) (xy 339.980602 -278.006305) (xy 340.031934 -278.014437) (xy 340.081363 -278.0305)
			(xy 340.12767 -278.054096) (xy 340.169715 -278.084646) (xy 340.206464 -278.121397) (xy 340.237012 -278.163444)
			(xy 340.260607 -278.209752) (xy 340.276666 -278.259181) (xy 340.284797 -278.310514) (xy 340.284797 -278.362469)
			(xy 340.564471 -278.362469) (xy 340.564471 -278.310535) (xy 340.572596 -278.25924) (xy 340.588644 -278.209847)
			(xy 340.612222 -278.163573) (xy 340.642748 -278.121557) (xy 340.679471 -278.084834) (xy 340.721487 -278.054308)
			(xy 340.767761 -278.03073) (xy 340.817154 -278.014682) (xy 340.868449 -278.006557) (xy 340.920383 -278.006557)
			(xy 340.971678 -278.014682) (xy 341.021071 -278.03073) (xy 341.067345 -278.054308) (xy 341.109361 -278.084834)
			(xy 341.146084 -278.121557) (xy 341.17661 -278.163573) (xy 341.200188 -278.209847) (xy 341.216236 -278.25924)
			(xy 341.224361 -278.310535) (xy 341.22487 -278.336502) (xy 341.224361 -278.362469) (xy 341.504271 -278.362469)
			(xy 341.504271 -278.310535) (xy 341.512396 -278.25924) (xy 341.528444 -278.209847) (xy 341.552022 -278.163573)
			(xy 341.582548 -278.121557) (xy 341.619271 -278.084834) (xy 341.661287 -278.054308) (xy 341.707561 -278.03073)
			(xy 341.756954 -278.014682) (xy 341.808249 -278.006557) (xy 341.860183 -278.006557) (xy 341.911478 -278.014682)
			(xy 341.960871 -278.03073) (xy 342.007145 -278.054308) (xy 342.049161 -278.084834) (xy 342.085884 -278.121557)
			(xy 342.11641 -278.163573) (xy 342.139988 -278.209847) (xy 342.156036 -278.25924) (xy 342.164161 -278.310535)
			(xy 342.16467 -278.336502) (xy 342.164161 -278.362469) (xy 342.444071 -278.362469) (xy 342.444071 -278.310535)
			(xy 342.452196 -278.25924) (xy 342.468244 -278.209847) (xy 342.491822 -278.163573) (xy 342.522348 -278.121557)
			(xy 342.559071 -278.084834) (xy 342.601087 -278.054308) (xy 342.647361 -278.03073) (xy 342.696754 -278.014682)
			(xy 342.748049 -278.006557) (xy 342.799983 -278.006557) (xy 342.851278 -278.014682) (xy 342.900671 -278.03073)
			(xy 342.946945 -278.054308) (xy 342.988961 -278.084834) (xy 343.025684 -278.121557) (xy 343.05621 -278.163573)
			(xy 343.079788 -278.209847) (xy 343.095836 -278.25924) (xy 343.103961 -278.310535) (xy 343.10447 -278.336502)
			(xy 343.103961 -278.362469) (xy 345.263471 -278.362469) (xy 345.263471 -278.310535) (xy 345.271596 -278.25924)
			(xy 345.287644 -278.209847) (xy 345.311222 -278.163573) (xy 345.341748 -278.121557) (xy 345.378471 -278.084834)
			(xy 345.420487 -278.054308) (xy 345.466761 -278.03073) (xy 345.516154 -278.014682) (xy 345.567449 -278.006557)
			(xy 345.619383 -278.006557) (xy 345.670678 -278.014682) (xy 345.720071 -278.03073) (xy 345.766345 -278.054308)
			(xy 345.808361 -278.084834) (xy 345.845084 -278.121557) (xy 345.87561 -278.163573) (xy 345.899188 -278.209847)
			(xy 345.915236 -278.25924) (xy 345.923361 -278.310535) (xy 345.92387 -278.336502) (xy 345.923361 -278.362469)
			(xy 346.203271 -278.362469) (xy 346.203271 -278.310535) (xy 346.211396 -278.25924) (xy 346.227444 -278.209847)
			(xy 346.251022 -278.163573) (xy 346.281548 -278.121557) (xy 346.318271 -278.084834) (xy 346.360287 -278.054308)
			(xy 346.406561 -278.03073) (xy 346.455954 -278.014682) (xy 346.507249 -278.006557) (xy 346.559183 -278.006557)
			(xy 346.610478 -278.014682) (xy 346.659871 -278.03073) (xy 346.706145 -278.054308) (xy 346.748161 -278.084834)
			(xy 346.784884 -278.121557) (xy 346.81541 -278.163573) (xy 346.838988 -278.209847) (xy 346.855036 -278.25924)
			(xy 346.863161 -278.310535) (xy 346.86367 -278.336502) (xy 346.863161 -278.362469) (xy 347.143071 -278.362469)
			(xy 347.143071 -278.310535) (xy 347.151196 -278.25924) (xy 347.167244 -278.209847) (xy 347.190822 -278.163573)
			(xy 347.221348 -278.121557) (xy 347.258071 -278.084834) (xy 347.300087 -278.054308) (xy 347.346361 -278.03073)
			(xy 347.395754 -278.014682) (xy 347.447049 -278.006557) (xy 347.498983 -278.006557) (xy 347.550278 -278.014682)
			(xy 347.599671 -278.03073) (xy 347.645945 -278.054308) (xy 347.687961 -278.084834) (xy 347.724684 -278.121557)
			(xy 347.75521 -278.163573) (xy 347.778788 -278.209847) (xy 347.794836 -278.25924) (xy 347.802961 -278.310535)
			(xy 347.80347 -278.336502) (xy 347.802961 -278.362469) (xy 348.082871 -278.362469) (xy 348.082871 -278.310535)
			(xy 348.090996 -278.25924) (xy 348.107044 -278.209847) (xy 348.130622 -278.163573) (xy 348.161148 -278.121557)
			(xy 348.197871 -278.084834) (xy 348.239887 -278.054308) (xy 348.286161 -278.03073) (xy 348.335554 -278.014682)
			(xy 348.386849 -278.006557) (xy 348.438783 -278.006557) (xy 348.490078 -278.014682) (xy 348.539471 -278.03073)
			(xy 348.585745 -278.054308) (xy 348.627761 -278.084834) (xy 348.664484 -278.121557) (xy 348.69501 -278.163573)
			(xy 348.718588 -278.209847) (xy 348.734636 -278.25924) (xy 348.742761 -278.310535) (xy 348.74327 -278.336502)
			(xy 348.742761 -278.362469) (xy 349.022417 -278.362469) (xy 349.022417 -278.310535) (xy 349.030542 -278.25924)
			(xy 349.04659 -278.209847) (xy 349.070168 -278.163573) (xy 349.100694 -278.121557) (xy 349.137417 -278.084834)
			(xy 349.179433 -278.054308) (xy 349.225707 -278.03073) (xy 349.2751 -278.014682) (xy 349.326395 -278.006557)
			(xy 349.378329 -278.006557) (xy 349.429624 -278.014682) (xy 349.479017 -278.03073) (xy 349.525291 -278.054308)
			(xy 349.567307 -278.084834) (xy 349.60403 -278.121557) (xy 349.634556 -278.163573) (xy 349.658134 -278.209847)
			(xy 349.674182 -278.25924) (xy 349.682307 -278.310535) (xy 349.682816 -278.336502) (xy 349.682307 -278.362469)
			(xy 349.962471 -278.362469) (xy 349.962471 -278.310535) (xy 349.970596 -278.25924) (xy 349.986644 -278.209847)
			(xy 350.010222 -278.163573) (xy 350.040748 -278.121557) (xy 350.077471 -278.084834) (xy 350.119487 -278.054308)
			(xy 350.165761 -278.03073) (xy 350.215154 -278.014682) (xy 350.266449 -278.006557) (xy 350.318383 -278.006557)
			(xy 350.369678 -278.014682) (xy 350.419071 -278.03073) (xy 350.465345 -278.054308) (xy 350.507361 -278.084834)
			(xy 350.544084 -278.121557) (xy 350.57461 -278.163573) (xy 350.598188 -278.209847) (xy 350.614236 -278.25924)
			(xy 350.622361 -278.310535) (xy 350.62287 -278.336502) (xy 350.622361 -278.362469) (xy 350.902271 -278.362469)
			(xy 350.902271 -278.310535) (xy 350.910396 -278.25924) (xy 350.926444 -278.209847) (xy 350.950022 -278.163573)
			(xy 350.980548 -278.121557) (xy 351.017271 -278.084834) (xy 351.059287 -278.054308) (xy 351.105561 -278.03073)
			(xy 351.154954 -278.014682) (xy 351.206249 -278.006557) (xy 351.258183 -278.006557) (xy 351.309478 -278.014682)
			(xy 351.358871 -278.03073) (xy 351.405145 -278.054308) (xy 351.447161 -278.084834) (xy 351.483884 -278.121557)
			(xy 351.51441 -278.163573) (xy 351.537988 -278.209847) (xy 351.554036 -278.25924) (xy 351.562161 -278.310535)
			(xy 351.56267 -278.336502) (xy 351.562161 -278.362469) (xy 351.842071 -278.362469) (xy 351.842071 -278.310535)
			(xy 351.850196 -278.25924) (xy 351.866244 -278.209847) (xy 351.889822 -278.163573) (xy 351.920348 -278.121557)
			(xy 351.957071 -278.084834) (xy 351.999087 -278.054308) (xy 352.045361 -278.03073) (xy 352.094754 -278.014682)
			(xy 352.146049 -278.006557) (xy 352.197983 -278.006557) (xy 352.249278 -278.014682) (xy 352.298671 -278.03073)
			(xy 352.344945 -278.054308) (xy 352.386961 -278.084834) (xy 352.423684 -278.121557) (xy 352.45421 -278.163573)
			(xy 352.477788 -278.209847) (xy 352.493836 -278.25924) (xy 352.501961 -278.310535) (xy 352.50247 -278.336502)
			(xy 352.501961 -278.362469) (xy 352.781617 -278.362469) (xy 352.781617 -278.310535) (xy 352.789742 -278.25924)
			(xy 352.80579 -278.209847) (xy 352.829368 -278.163573) (xy 352.859894 -278.121557) (xy 352.896617 -278.084834)
			(xy 352.938633 -278.054308) (xy 352.984907 -278.03073) (xy 353.0343 -278.014682) (xy 353.085595 -278.006557)
			(xy 353.137529 -278.006557) (xy 353.188824 -278.014682) (xy 353.238217 -278.03073) (xy 353.284491 -278.054308)
			(xy 353.326507 -278.084834) (xy 353.36323 -278.121557) (xy 353.393756 -278.163573) (xy 353.417334 -278.209847)
			(xy 353.433382 -278.25924) (xy 353.441507 -278.310535) (xy 353.442016 -278.336502) (xy 353.441507 -278.362469)
			(xy 354.661471 -278.362469) (xy 354.661471 -278.310535) (xy 354.669596 -278.25924) (xy 354.685644 -278.209847)
			(xy 354.709222 -278.163573) (xy 354.739748 -278.121557) (xy 354.776471 -278.084834) (xy 354.818487 -278.054308)
			(xy 354.864761 -278.03073) (xy 354.914154 -278.014682) (xy 354.965449 -278.006557) (xy 355.017383 -278.006557)
			(xy 355.068678 -278.014682) (xy 355.118071 -278.03073) (xy 355.164345 -278.054308) (xy 355.206361 -278.084834)
			(xy 355.243084 -278.121557) (xy 355.27361 -278.163573) (xy 355.297188 -278.209847) (xy 355.313236 -278.25924)
			(xy 355.321361 -278.310535) (xy 355.32187 -278.336502) (xy 355.321361 -278.362469) (xy 355.313236 -278.413764)
			(xy 355.297188 -278.463157) (xy 355.27361 -278.509431) (xy 355.243084 -278.551447) (xy 355.206361 -278.58817)
			(xy 355.164345 -278.618696) (xy 355.118071 -278.642274) (xy 355.068678 -278.658322) (xy 355.017383 -278.666447)
			(xy 354.965449 -278.666447) (xy 354.914154 -278.658322) (xy 354.864761 -278.642274) (xy 354.818487 -278.618696)
			(xy 354.776471 -278.58817) (xy 354.739748 -278.551447) (xy 354.709222 -278.509431) (xy 354.685644 -278.463157)
			(xy 354.669596 -278.413764) (xy 354.661471 -278.362469) (xy 353.441507 -278.362469) (xy 353.433382 -278.413764)
			(xy 353.417334 -278.463157) (xy 353.393756 -278.509431) (xy 353.36323 -278.551447) (xy 353.326507 -278.58817)
			(xy 353.284491 -278.618696) (xy 353.238217 -278.642274) (xy 353.188824 -278.658322) (xy 353.137529 -278.666447)
			(xy 353.085595 -278.666447) (xy 353.0343 -278.658322) (xy 352.984907 -278.642274) (xy 352.938633 -278.618696)
			(xy 352.896617 -278.58817) (xy 352.859894 -278.551447) (xy 352.829368 -278.509431) (xy 352.80579 -278.463157)
			(xy 352.789742 -278.413764) (xy 352.781617 -278.362469) (xy 352.501961 -278.362469) (xy 352.493836 -278.413764)
			(xy 352.477788 -278.463157) (xy 352.45421 -278.509431) (xy 352.423684 -278.551447) (xy 352.386961 -278.58817)
			(xy 352.344945 -278.618696) (xy 352.298671 -278.642274) (xy 352.249278 -278.658322) (xy 352.197983 -278.666447)
			(xy 352.146049 -278.666447) (xy 352.094754 -278.658322) (xy 352.045361 -278.642274) (xy 351.999087 -278.618696)
			(xy 351.957071 -278.58817) (xy 351.920348 -278.551447) (xy 351.889822 -278.509431) (xy 351.866244 -278.463157)
			(xy 351.850196 -278.413764) (xy 351.842071 -278.362469) (xy 351.562161 -278.362469) (xy 351.554036 -278.413764)
			(xy 351.537988 -278.463157) (xy 351.51441 -278.509431) (xy 351.483884 -278.551447) (xy 351.447161 -278.58817)
			(xy 351.405145 -278.618696) (xy 351.358871 -278.642274) (xy 351.309478 -278.658322) (xy 351.258183 -278.666447)
			(xy 351.206249 -278.666447) (xy 351.154954 -278.658322) (xy 351.105561 -278.642274) (xy 351.059287 -278.618696)
			(xy 351.017271 -278.58817) (xy 350.980548 -278.551447) (xy 350.950022 -278.509431) (xy 350.926444 -278.463157)
			(xy 350.910396 -278.413764) (xy 350.902271 -278.362469) (xy 350.622361 -278.362469) (xy 350.614236 -278.413764)
			(xy 350.598188 -278.463157) (xy 350.57461 -278.509431) (xy 350.544084 -278.551447) (xy 350.507361 -278.58817)
			(xy 350.465345 -278.618696) (xy 350.419071 -278.642274) (xy 350.369678 -278.658322) (xy 350.318383 -278.666447)
			(xy 350.266449 -278.666447) (xy 350.215154 -278.658322) (xy 350.165761 -278.642274) (xy 350.119487 -278.618696)
			(xy 350.077471 -278.58817) (xy 350.040748 -278.551447) (xy 350.010222 -278.509431) (xy 349.986644 -278.463157)
			(xy 349.970596 -278.413764) (xy 349.962471 -278.362469) (xy 349.682307 -278.362469) (xy 349.674182 -278.413764)
			(xy 349.658134 -278.463157) (xy 349.634556 -278.509431) (xy 349.60403 -278.551447) (xy 349.567307 -278.58817)
			(xy 349.525291 -278.618696) (xy 349.479017 -278.642274) (xy 349.429624 -278.658322) (xy 349.378329 -278.666447)
			(xy 349.326395 -278.666447) (xy 349.2751 -278.658322) (xy 349.225707 -278.642274) (xy 349.179433 -278.618696)
			(xy 349.137417 -278.58817) (xy 349.100694 -278.551447) (xy 349.070168 -278.509431) (xy 349.04659 -278.463157)
			(xy 349.030542 -278.413764) (xy 349.022417 -278.362469) (xy 348.742761 -278.362469) (xy 348.734636 -278.413764)
			(xy 348.718588 -278.463157) (xy 348.69501 -278.509431) (xy 348.664484 -278.551447) (xy 348.627761 -278.58817)
			(xy 348.585745 -278.618696) (xy 348.539471 -278.642274) (xy 348.490078 -278.658322) (xy 348.438783 -278.666447)
			(xy 348.386849 -278.666447) (xy 348.335554 -278.658322) (xy 348.286161 -278.642274) (xy 348.239887 -278.618696)
			(xy 348.197871 -278.58817) (xy 348.161148 -278.551447) (xy 348.130622 -278.509431) (xy 348.107044 -278.463157)
			(xy 348.090996 -278.413764) (xy 348.082871 -278.362469) (xy 347.802961 -278.362469) (xy 347.794836 -278.413764)
			(xy 347.778788 -278.463157) (xy 347.75521 -278.509431) (xy 347.724684 -278.551447) (xy 347.687961 -278.58817)
			(xy 347.645945 -278.618696) (xy 347.599671 -278.642274) (xy 347.550278 -278.658322) (xy 347.498983 -278.666447)
			(xy 347.447049 -278.666447) (xy 347.395754 -278.658322) (xy 347.346361 -278.642274) (xy 347.300087 -278.618696)
			(xy 347.258071 -278.58817) (xy 347.221348 -278.551447) (xy 347.190822 -278.509431) (xy 347.167244 -278.463157)
			(xy 347.151196 -278.413764) (xy 347.143071 -278.362469) (xy 346.863161 -278.362469) (xy 346.855036 -278.413764)
			(xy 346.838988 -278.463157) (xy 346.81541 -278.509431) (xy 346.784884 -278.551447) (xy 346.748161 -278.58817)
			(xy 346.706145 -278.618696) (xy 346.659871 -278.642274) (xy 346.610478 -278.658322) (xy 346.559183 -278.666447)
			(xy 346.507249 -278.666447) (xy 346.455954 -278.658322) (xy 346.406561 -278.642274) (xy 346.360287 -278.618696)
			(xy 346.318271 -278.58817) (xy 346.281548 -278.551447) (xy 346.251022 -278.509431) (xy 346.227444 -278.463157)
			(xy 346.211396 -278.413764) (xy 346.203271 -278.362469) (xy 345.923361 -278.362469) (xy 345.915236 -278.413764)
			(xy 345.899188 -278.463157) (xy 345.87561 -278.509431) (xy 345.845084 -278.551447) (xy 345.808361 -278.58817)
			(xy 345.766345 -278.618696) (xy 345.720071 -278.642274) (xy 345.670678 -278.658322) (xy 345.619383 -278.666447)
			(xy 345.567449 -278.666447) (xy 345.516154 -278.658322) (xy 345.466761 -278.642274) (xy 345.420487 -278.618696)
			(xy 345.378471 -278.58817) (xy 345.341748 -278.551447) (xy 345.311222 -278.509431) (xy 345.287644 -278.463157)
			(xy 345.271596 -278.413764) (xy 345.263471 -278.362469) (xy 343.103961 -278.362469) (xy 343.095836 -278.413764)
			(xy 343.079788 -278.463157) (xy 343.05621 -278.509431) (xy 343.025684 -278.551447) (xy 342.988961 -278.58817)
			(xy 342.946945 -278.618696) (xy 342.900671 -278.642274) (xy 342.851278 -278.658322) (xy 342.799983 -278.666447)
			(xy 342.748049 -278.666447) (xy 342.696754 -278.658322) (xy 342.647361 -278.642274) (xy 342.601087 -278.618696)
			(xy 342.559071 -278.58817) (xy 342.522348 -278.551447) (xy 342.491822 -278.509431) (xy 342.468244 -278.463157)
			(xy 342.452196 -278.413764) (xy 342.444071 -278.362469) (xy 342.164161 -278.362469) (xy 342.156036 -278.413764)
			(xy 342.139988 -278.463157) (xy 342.11641 -278.509431) (xy 342.085884 -278.551447) (xy 342.049161 -278.58817)
			(xy 342.007145 -278.618696) (xy 341.960871 -278.642274) (xy 341.911478 -278.658322) (xy 341.860183 -278.666447)
			(xy 341.808249 -278.666447) (xy 341.756954 -278.658322) (xy 341.707561 -278.642274) (xy 341.661287 -278.618696)
			(xy 341.619271 -278.58817) (xy 341.582548 -278.551447) (xy 341.552022 -278.509431) (xy 341.528444 -278.463157)
			(xy 341.512396 -278.413764) (xy 341.504271 -278.362469) (xy 341.224361 -278.362469) (xy 341.216236 -278.413764)
			(xy 341.200188 -278.463157) (xy 341.17661 -278.509431) (xy 341.146084 -278.551447) (xy 341.109361 -278.58817)
			(xy 341.067345 -278.618696) (xy 341.021071 -278.642274) (xy 340.971678 -278.658322) (xy 340.920383 -278.666447)
			(xy 340.868449 -278.666447) (xy 340.817154 -278.658322) (xy 340.767761 -278.642274) (xy 340.721487 -278.618696)
			(xy 340.679471 -278.58817) (xy 340.642748 -278.551447) (xy 340.612222 -278.509431) (xy 340.588644 -278.463157)
			(xy 340.572596 -278.413764) (xy 340.564471 -278.362469) (xy 340.284797 -278.362469) (xy 340.284797 -278.362486)
			(xy 340.276666 -278.413819) (xy 340.260607 -278.463248) (xy 340.237012 -278.509556) (xy 340.206464 -278.551603)
			(xy 340.169715 -278.588354) (xy 340.12767 -278.618904) (xy 340.081363 -278.6425) (xy 340.031934 -278.658563)
			(xy 339.980602 -278.666695) (xy 339.954616 -278.66721) (xy 339.928317 -278.666704) (xy 339.876383 -278.658381)
			(xy 339.82642 -278.641943) (xy 339.77969 -278.617803) (xy 339.737369 -278.586572) (xy 339.700525 -278.549035)
			(xy 339.670087 -278.50614) (xy 339.657944 -278.482806) (xy 339.655912 -278.478488) (xy 339.649783 -278.469502)
			(xy 339.631754 -278.45737) (xy 339.621114 -278.45512) (xy 339.580728 -278.448516) (xy 339.538056 -278.441658)
			(xy 339.526736 -278.440858) (xy 339.505301 -278.448246) (xy 339.496908 -278.455882) (xy 338.8868 -279.06599)
			(xy 338.879092 -279.074498) (xy 338.871681 -279.0962) (xy 338.872576 -279.107646) (xy 338.872576 -279.1079)
			(xy 338.873872 -279.118457) (xy 338.875267 -279.139682) (xy 338.87537 -279.150318) (xy 338.874886 -279.176285)
			(xy 339.154517 -279.176285) (xy 339.154517 -279.124351) (xy 339.162642 -279.073056) (xy 339.17869 -279.023663)
			(xy 339.202268 -278.977389) (xy 339.232794 -278.935373) (xy 339.269517 -278.89865) (xy 339.311533 -278.868124)
			(xy 339.357807 -278.844546) (xy 339.4072 -278.828498) (xy 339.458495 -278.820373) (xy 339.510429 -278.820373)
			(xy 339.561724 -278.828498) (xy 339.611117 -278.844546) (xy 339.657391 -278.868124) (xy 339.699407 -278.89865)
			(xy 339.73613 -278.935373) (xy 339.766656 -278.977389) (xy 339.790234 -279.023663) (xy 339.806282 -279.073056)
			(xy 339.814407 -279.124351) (xy 339.814916 -279.150318) (xy 339.814407 -279.176285) (xy 340.094317 -279.176285)
			(xy 340.094317 -279.124351) (xy 340.102442 -279.073056) (xy 340.11849 -279.023663) (xy 340.142068 -278.977389)
			(xy 340.172594 -278.935373) (xy 340.209317 -278.89865) (xy 340.251333 -278.868124) (xy 340.297607 -278.844546)
			(xy 340.347 -278.828498) (xy 340.398295 -278.820373) (xy 340.450229 -278.820373) (xy 340.501524 -278.828498)
			(xy 340.550917 -278.844546) (xy 340.597191 -278.868124) (xy 340.639207 -278.89865) (xy 340.67593 -278.935373)
			(xy 340.706456 -278.977389) (xy 340.730034 -279.023663) (xy 340.746082 -279.073056) (xy 340.754207 -279.124351)
			(xy 340.754716 -279.150318) (xy 340.754207 -279.176285) (xy 341.034117 -279.176285) (xy 341.034117 -279.124351)
			(xy 341.042242 -279.073056) (xy 341.05829 -279.023663) (xy 341.081868 -278.977389) (xy 341.112394 -278.935373)
			(xy 341.149117 -278.89865) (xy 341.191133 -278.868124) (xy 341.237407 -278.844546) (xy 341.2868 -278.828498)
			(xy 341.338095 -278.820373) (xy 341.390029 -278.820373) (xy 341.441324 -278.828498) (xy 341.490717 -278.844546)
			(xy 341.536991 -278.868124) (xy 341.579007 -278.89865) (xy 341.61573 -278.935373) (xy 341.646256 -278.977389)
			(xy 341.669834 -279.023663) (xy 341.685882 -279.073056) (xy 341.694007 -279.124351) (xy 341.694516 -279.150318)
			(xy 341.694007 -279.176285) (xy 341.974171 -279.176285) (xy 341.974171 -279.124351) (xy 341.982296 -279.073056)
			(xy 341.998344 -279.023663) (xy 342.021922 -278.977389) (xy 342.052448 -278.935373) (xy 342.089171 -278.89865)
			(xy 342.131187 -278.868124) (xy 342.177461 -278.844546) (xy 342.226854 -278.828498) (xy 342.278149 -278.820373)
			(xy 342.330083 -278.820373) (xy 342.381378 -278.828498) (xy 342.430771 -278.844546) (xy 342.477045 -278.868124)
			(xy 342.519061 -278.89865) (xy 342.555784 -278.935373) (xy 342.58631 -278.977389) (xy 342.609888 -279.023663)
			(xy 342.625936 -279.073056) (xy 342.634061 -279.124351) (xy 342.63457 -279.150318) (xy 342.634061 -279.176285)
			(xy 342.913971 -279.176285) (xy 342.913971 -279.124351) (xy 342.922096 -279.073056) (xy 342.938144 -279.023663)
			(xy 342.961722 -278.977389) (xy 342.992248 -278.935373) (xy 343.028971 -278.89865) (xy 343.070987 -278.868124)
			(xy 343.117261 -278.844546) (xy 343.166654 -278.828498) (xy 343.217949 -278.820373) (xy 343.269883 -278.820373)
			(xy 343.321178 -278.828498) (xy 343.370571 -278.844546) (xy 343.416845 -278.868124) (xy 343.458861 -278.89865)
			(xy 343.495584 -278.935373) (xy 343.52611 -278.977389) (xy 343.549688 -279.023663) (xy 343.565736 -279.073056)
			(xy 343.573861 -279.124351) (xy 343.57437 -279.150318) (xy 343.573861 -279.176285) (xy 343.853517 -279.176285)
			(xy 343.853517 -279.124351) (xy 343.861642 -279.073056) (xy 343.87769 -279.023663) (xy 343.901268 -278.977389)
			(xy 343.931794 -278.935373) (xy 343.968517 -278.89865) (xy 344.010533 -278.868124) (xy 344.056807 -278.844546)
			(xy 344.1062 -278.828498) (xy 344.157495 -278.820373) (xy 344.209429 -278.820373) (xy 344.260724 -278.828498)
			(xy 344.310117 -278.844546) (xy 344.356391 -278.868124) (xy 344.398407 -278.89865) (xy 344.43513 -278.935373)
			(xy 344.465656 -278.977389) (xy 344.489234 -279.023663) (xy 344.505282 -279.073056) (xy 344.513407 -279.124351)
			(xy 344.513916 -279.150318) (xy 344.513407 -279.176285) (xy 345.733371 -279.176285) (xy 345.733371 -279.124351)
			(xy 345.741496 -279.073056) (xy 345.757544 -279.023663) (xy 345.781122 -278.977389) (xy 345.811648 -278.935373)
			(xy 345.848371 -278.89865) (xy 345.890387 -278.868124) (xy 345.936661 -278.844546) (xy 345.986054 -278.828498)
			(xy 346.037349 -278.820373) (xy 346.089283 -278.820373) (xy 346.140578 -278.828498) (xy 346.189971 -278.844546)
			(xy 346.236245 -278.868124) (xy 346.278261 -278.89865) (xy 346.314984 -278.935373) (xy 346.34551 -278.977389)
			(xy 346.369088 -279.023663) (xy 346.385136 -279.073056) (xy 346.393261 -279.124351) (xy 346.39377 -279.150318)
			(xy 346.393261 -279.176285) (xy 346.672917 -279.176285) (xy 346.672917 -279.124351) (xy 346.681042 -279.073056)
			(xy 346.69709 -279.023663) (xy 346.720668 -278.977389) (xy 346.751194 -278.935373) (xy 346.787917 -278.89865)
			(xy 346.829933 -278.868124) (xy 346.876207 -278.844546) (xy 346.9256 -278.828498) (xy 346.976895 -278.820373)
			(xy 347.028829 -278.820373) (xy 347.080124 -278.828498) (xy 347.129517 -278.844546) (xy 347.175791 -278.868124)
			(xy 347.217807 -278.89865) (xy 347.25453 -278.935373) (xy 347.285056 -278.977389) (xy 347.308634 -279.023663)
			(xy 347.324682 -279.073056) (xy 347.332807 -279.124351) (xy 347.333316 -279.150318) (xy 347.332807 -279.176285)
			(xy 347.612717 -279.176285) (xy 347.612717 -279.124351) (xy 347.620842 -279.073056) (xy 347.63689 -279.023663)
			(xy 347.660468 -278.977389) (xy 347.690994 -278.935373) (xy 347.727717 -278.89865) (xy 347.769733 -278.868124)
			(xy 347.816007 -278.844546) (xy 347.8654 -278.828498) (xy 347.916695 -278.820373) (xy 347.968629 -278.820373)
			(xy 348.019924 -278.828498) (xy 348.069317 -278.844546) (xy 348.115591 -278.868124) (xy 348.157607 -278.89865)
			(xy 348.19433 -278.935373) (xy 348.224856 -278.977389) (xy 348.248434 -279.023663) (xy 348.264482 -279.073056)
			(xy 348.272607 -279.124351) (xy 348.273116 -279.150318) (xy 348.272607 -279.176285) (xy 348.552771 -279.176285)
			(xy 348.552771 -279.124351) (xy 348.560896 -279.073056) (xy 348.576944 -279.023663) (xy 348.600522 -278.977389)
			(xy 348.631048 -278.935373) (xy 348.667771 -278.89865) (xy 348.709787 -278.868124) (xy 348.756061 -278.844546)
			(xy 348.805454 -278.828498) (xy 348.856749 -278.820373) (xy 348.908683 -278.820373) (xy 348.959978 -278.828498)
			(xy 349.009371 -278.844546) (xy 349.055645 -278.868124) (xy 349.097661 -278.89865) (xy 349.134384 -278.935373)
			(xy 349.16491 -278.977389) (xy 349.188488 -279.023663) (xy 349.204536 -279.073056) (xy 349.212661 -279.124351)
			(xy 349.21317 -279.150318) (xy 349.491808 -279.150318) (xy 349.492317 -279.124351) (xy 349.500442 -279.073056)
			(xy 349.51649 -279.023663) (xy 349.540068 -278.977389) (xy 349.570594 -278.935373) (xy 349.607317 -278.89865)
			(xy 349.649333 -278.868124) (xy 349.695607 -278.844546) (xy 349.745 -278.828498) (xy 349.796295 -278.820373)
			(xy 349.848229 -278.820373) (xy 349.899524 -278.828498) (xy 349.948917 -278.844546) (xy 349.995191 -278.868124)
			(xy 350.037207 -278.89865) (xy 350.07393 -278.935373) (xy 350.104456 -278.977389) (xy 350.128034 -279.023663)
			(xy 350.144082 -279.073056) (xy 350.152207 -279.124351) (xy 350.152716 -279.150318) (xy 350.152716 -279.150572)
			(xy 350.152174 -279.176264) (xy 350.432173 -279.176264) (xy 350.432173 -279.124336) (xy 350.440296 -279.073048)
			(xy 350.456341 -279.023661) (xy 350.479914 -278.977392) (xy 350.510435 -278.93538) (xy 350.547151 -278.89866)
			(xy 350.58916 -278.868134) (xy 350.635426 -278.844556) (xy 350.684811 -278.828505) (xy 350.736098 -278.820376)
			(xy 350.762062 -278.819864) (xy 350.787696 -278.820388) (xy 350.838349 -278.828306) (xy 350.88717 -278.843958)
			(xy 350.932985 -278.866968) (xy 350.974692 -278.896783) (xy 351.011291 -278.932685) (xy 351.026984 -278.95296)
			(xy 351.43694 -278.95296) (xy 351.452646 -278.932694) (xy 351.48924 -278.896784) (xy 351.530944 -278.866962)
			(xy 351.576755 -278.843943) (xy 351.625574 -278.828281) (xy 351.676227 -278.820351) (xy 351.701862 -278.819864)
			(xy 351.727835 -278.820308) (xy 351.779141 -278.828429) (xy 351.828545 -278.844476) (xy 351.874831 -278.868055)
			(xy 351.916858 -278.898585) (xy 351.95359 -278.935313) (xy 351.984125 -278.977337) (xy 352.007709 -279.023619)
			(xy 352.023762 -279.073022) (xy 352.031889 -279.124327) (xy 352.031889 -279.176273) (xy 352.031887 -279.176285)
			(xy 352.311717 -279.176285) (xy 352.311717 -279.124351) (xy 352.319842 -279.073056) (xy 352.33589 -279.023663)
			(xy 352.359468 -278.977389) (xy 352.389994 -278.935373) (xy 352.426717 -278.89865) (xy 352.468733 -278.868124)
			(xy 352.515007 -278.844546) (xy 352.5644 -278.828498) (xy 352.615695 -278.820373) (xy 352.667629 -278.820373)
			(xy 352.718924 -278.828498) (xy 352.768317 -278.844546) (xy 352.814591 -278.868124) (xy 352.856607 -278.89865)
			(xy 352.89333 -278.935373) (xy 352.923856 -278.977389) (xy 352.947434 -279.023663) (xy 352.963482 -279.073056)
			(xy 352.971607 -279.124351) (xy 352.972116 -279.150318) (xy 352.971607 -279.176285) (xy 353.251771 -279.176285)
			(xy 353.251771 -279.124351) (xy 353.259896 -279.073056) (xy 353.275944 -279.023663) (xy 353.299522 -278.977389)
			(xy 353.330048 -278.935373) (xy 353.366771 -278.89865) (xy 353.408787 -278.868124) (xy 353.455061 -278.844546)
			(xy 353.504454 -278.828498) (xy 353.555749 -278.820373) (xy 353.607683 -278.820373) (xy 353.658978 -278.828498)
			(xy 353.708371 -278.844546) (xy 353.754645 -278.868124) (xy 353.796661 -278.89865) (xy 353.833384 -278.935373)
			(xy 353.86391 -278.977389) (xy 353.887488 -279.023663) (xy 353.903536 -279.073056) (xy 353.911661 -279.124351)
			(xy 353.91217 -279.150318) (xy 353.911661 -279.176285) (xy 354.191571 -279.176285) (xy 354.191571 -279.124351)
			(xy 354.199696 -279.073056) (xy 354.215744 -279.023663) (xy 354.239322 -278.977389) (xy 354.269848 -278.935373)
			(xy 354.306571 -278.89865) (xy 354.348587 -278.868124) (xy 354.394861 -278.844546) (xy 354.444254 -278.828498)
			(xy 354.495549 -278.820373) (xy 354.547483 -278.820373) (xy 354.598778 -278.828498) (xy 354.648171 -278.844546)
			(xy 354.694445 -278.868124) (xy 354.736461 -278.89865) (xy 354.773184 -278.935373) (xy 354.80371 -278.977389)
			(xy 354.827288 -279.023663) (xy 354.843336 -279.073056) (xy 354.851461 -279.124351) (xy 354.85197 -279.150318)
			(xy 354.851461 -279.176285) (xy 354.843336 -279.22758) (xy 354.827288 -279.276973) (xy 354.80371 -279.323247)
			(xy 354.773184 -279.365263) (xy 354.736461 -279.401986) (xy 354.694445 -279.432512) (xy 354.648171 -279.45609)
			(xy 354.598778 -279.472138) (xy 354.547483 -279.480263) (xy 354.495549 -279.480263) (xy 354.444254 -279.472138)
			(xy 354.394861 -279.45609) (xy 354.348587 -279.432512) (xy 354.306571 -279.401986) (xy 354.269848 -279.365263)
			(xy 354.239322 -279.323247) (xy 354.215744 -279.276973) (xy 354.199696 -279.22758) (xy 354.191571 -279.176285)
			(xy 353.911661 -279.176285) (xy 353.903536 -279.22758) (xy 353.887488 -279.276973) (xy 353.86391 -279.323247)
			(xy 353.833384 -279.365263) (xy 353.796661 -279.401986) (xy 353.754645 -279.432512) (xy 353.708371 -279.45609)
			(xy 353.658978 -279.472138) (xy 353.607683 -279.480263) (xy 353.555749 -279.480263) (xy 353.504454 -279.472138)
			(xy 353.455061 -279.45609) (xy 353.408787 -279.432512) (xy 353.366771 -279.401986) (xy 353.330048 -279.365263)
			(xy 353.299522 -279.323247) (xy 353.275944 -279.276973) (xy 353.259896 -279.22758) (xy 353.251771 -279.176285)
			(xy 352.971607 -279.176285) (xy 352.963482 -279.22758) (xy 352.947434 -279.276973) (xy 352.923856 -279.323247)
			(xy 352.89333 -279.365263) (xy 352.856607 -279.401986) (xy 352.814591 -279.432512) (xy 352.768317 -279.45609)
			(xy 352.718924 -279.472138) (xy 352.667629 -279.480263) (xy 352.615695 -279.480263) (xy 352.5644 -279.472138)
			(xy 352.515007 -279.45609) (xy 352.468733 -279.432512) (xy 352.426717 -279.401986) (xy 352.389994 -279.365263)
			(xy 352.359468 -279.323247) (xy 352.33589 -279.276973) (xy 352.319842 -279.22758) (xy 352.311717 -279.176285)
			(xy 352.031887 -279.176285) (xy 352.023762 -279.227578) (xy 352.007709 -279.276981) (xy 351.984125 -279.323263)
			(xy 351.95359 -279.365286) (xy 351.916858 -279.402015) (xy 351.874831 -279.432545) (xy 351.828545 -279.456124)
			(xy 351.779141 -279.472171) (xy 351.727835 -279.480292) (xy 351.701862 -279.480772) (xy 351.676224 -279.480329)
			(xy 351.625566 -279.472397) (xy 351.576743 -279.456731) (xy 351.530928 -279.433706) (xy 351.489223 -279.403876)
			(xy 351.45263 -279.367958) (xy 351.43694 -279.347676) (xy 351.026984 -279.347676) (xy 351.011305 -279.367965)
			(xy 350.974708 -279.403876) (xy 350.932999 -279.433698) (xy 350.887182 -279.456714) (xy 350.838357 -279.47237)
			(xy 350.787699 -279.48029) (xy 350.762062 -279.480772) (xy 350.736098 -279.480224) (xy 350.684811 -279.472095)
			(xy 350.635426 -279.456044) (xy 350.58916 -279.432466) (xy 350.547151 -279.40194) (xy 350.510435 -279.36522)
			(xy 350.479914 -279.323208) (xy 350.456341 -279.276939) (xy 350.440296 -279.227552) (xy 350.432173 -279.176264)
			(xy 350.152174 -279.176264) (xy 350.15213 -279.178353) (xy 350.142816 -279.233129) (xy 350.134174 -279.259538)
			(xy 350.1263 -279.281636) (xy 350.330262 -279.63495) (xy 350.353376 -279.639268) (xy 350.378304 -279.644408)
			(xy 350.426288 -279.661378) (xy 350.471105 -279.6855) (xy 350.511697 -279.716204) (xy 350.547105 -279.752766)
			(xy 350.576492 -279.794321) (xy 350.599165 -279.839888) (xy 350.614588 -279.888392) (xy 350.622397 -279.938686)
			(xy 350.62287 -279.964134) (xy 350.622361 -279.990101) (xy 350.902017 -279.990101) (xy 350.902017 -279.938167)
			(xy 350.910142 -279.886872) (xy 350.92619 -279.837479) (xy 350.949768 -279.791205) (xy 350.980294 -279.749189)
			(xy 351.017017 -279.712466) (xy 351.059033 -279.68194) (xy 351.105307 -279.658362) (xy 351.1547 -279.642314)
			(xy 351.205995 -279.634189) (xy 351.257929 -279.634189) (xy 351.309224 -279.642314) (xy 351.358617 -279.658362)
			(xy 351.404891 -279.68194) (xy 351.446907 -279.712466) (xy 351.48363 -279.749189) (xy 351.514156 -279.791205)
			(xy 351.537734 -279.837479) (xy 351.553782 -279.886872) (xy 351.561907 -279.938167) (xy 351.562416 -279.964134)
			(xy 351.561907 -279.990101) (xy 351.842071 -279.990101) (xy 351.842071 -279.938167) (xy 351.850196 -279.886872)
			(xy 351.866244 -279.837479) (xy 351.889822 -279.791205) (xy 351.920348 -279.749189) (xy 351.957071 -279.712466)
			(xy 351.999087 -279.68194) (xy 352.045361 -279.658362) (xy 352.094754 -279.642314) (xy 352.146049 -279.634189)
			(xy 352.197983 -279.634189) (xy 352.249278 -279.642314) (xy 352.298671 -279.658362) (xy 352.344945 -279.68194)
			(xy 352.386961 -279.712466) (xy 352.423684 -279.749189) (xy 352.45421 -279.791205) (xy 352.477788 -279.837479)
			(xy 352.493836 -279.886872) (xy 352.501961 -279.938167) (xy 352.50247 -279.964134) (xy 352.501961 -279.990101)
			(xy 352.493836 -280.041396) (xy 352.477788 -280.090789) (xy 352.45421 -280.137063) (xy 352.423684 -280.179079)
			(xy 352.386961 -280.215802) (xy 352.344945 -280.246328) (xy 352.298671 -280.269906) (xy 352.249278 -280.285954)
			(xy 352.197983 -280.294079) (xy 352.146049 -280.294079) (xy 352.094754 -280.285954) (xy 352.045361 -280.269906)
			(xy 351.999087 -280.246328) (xy 351.957071 -280.215802) (xy 351.920348 -280.179079) (xy 351.889822 -280.137063)
			(xy 351.866244 -280.090789) (xy 351.850196 -280.041396) (xy 351.842071 -279.990101) (xy 351.561907 -279.990101)
			(xy 351.553782 -280.041396) (xy 351.537734 -280.090789) (xy 351.514156 -280.137063) (xy 351.48363 -280.179079)
			(xy 351.446907 -280.215802) (xy 351.404891 -280.246328) (xy 351.358617 -280.269906) (xy 351.309224 -280.285954)
			(xy 351.257929 -280.294079) (xy 351.205995 -280.294079) (xy 351.1547 -280.285954) (xy 351.105307 -280.269906)
			(xy 351.059033 -280.246328) (xy 351.017017 -280.215802) (xy 350.980294 -280.179079) (xy 350.949768 -280.137063)
			(xy 350.92619 -280.090789) (xy 350.910142 -280.041396) (xy 350.902017 -279.990101) (xy 350.622361 -279.990101)
			(xy 350.614236 -280.041396) (xy 350.598188 -280.090789) (xy 350.57461 -280.137063) (xy 350.544084 -280.179079)
			(xy 350.507361 -280.215802) (xy 350.465345 -280.246328) (xy 350.419071 -280.269906) (xy 350.369678 -280.285954)
			(xy 350.318383 -280.294079) (xy 350.266449 -280.294079) (xy 350.215154 -280.285954) (xy 350.165761 -280.269906)
			(xy 350.119487 -280.246328) (xy 350.077471 -280.215802) (xy 350.040748 -280.179079) (xy 350.010222 -280.137063)
			(xy 349.986644 -280.090789) (xy 349.970596 -280.041396) (xy 349.962471 -279.990101) (xy 349.961962 -279.964134)
			(xy 349.96252 -279.936148) (xy 349.971966 -279.88098) (xy 349.980758 -279.854406) (xy 349.988378 -279.832308)
			(xy 349.78467 -279.479502) (xy 349.76181 -279.475184) (xy 349.736864 -279.47001) (xy 349.6888 -279.453122)
			(xy 349.643899 -279.429057) (xy 349.603223 -279.398385) (xy 349.567738 -279.361832) (xy 349.538284 -279.320266)
			(xy 349.515559 -279.274672) (xy 349.500103 -279.22613) (xy 349.49228 -279.17579) (xy 349.491808 -279.150318)
			(xy 349.21317 -279.150318) (xy 349.212661 -279.176285) (xy 349.204536 -279.22758) (xy 349.188488 -279.276973)
			(xy 349.16491 -279.323247) (xy 349.134384 -279.365263) (xy 349.097661 -279.401986) (xy 349.055645 -279.432512)
			(xy 349.009371 -279.45609) (xy 348.959978 -279.472138) (xy 348.908683 -279.480263) (xy 348.856749 -279.480263)
			(xy 348.805454 -279.472138) (xy 348.756061 -279.45609) (xy 348.709787 -279.432512) (xy 348.667771 -279.401986)
			(xy 348.631048 -279.365263) (xy 348.600522 -279.323247) (xy 348.576944 -279.276973) (xy 348.560896 -279.22758)
			(xy 348.552771 -279.176285) (xy 348.272607 -279.176285) (xy 348.264482 -279.22758) (xy 348.248434 -279.276973)
			(xy 348.224856 -279.323247) (xy 348.19433 -279.365263) (xy 348.157607 -279.401986) (xy 348.115591 -279.432512)
			(xy 348.069317 -279.45609) (xy 348.019924 -279.472138) (xy 347.968629 -279.480263) (xy 347.916695 -279.480263)
			(xy 347.8654 -279.472138) (xy 347.816007 -279.45609) (xy 347.769733 -279.432512) (xy 347.727717 -279.401986)
			(xy 347.690994 -279.365263) (xy 347.660468 -279.323247) (xy 347.63689 -279.276973) (xy 347.620842 -279.22758)
			(xy 347.612717 -279.176285) (xy 347.332807 -279.176285) (xy 347.324682 -279.22758) (xy 347.308634 -279.276973)
			(xy 347.285056 -279.323247) (xy 347.25453 -279.365263) (xy 347.217807 -279.401986) (xy 347.175791 -279.432512)
			(xy 347.129517 -279.45609) (xy 347.080124 -279.472138) (xy 347.028829 -279.480263) (xy 346.976895 -279.480263)
			(xy 346.9256 -279.472138) (xy 346.876207 -279.45609) (xy 346.829933 -279.432512) (xy 346.787917 -279.401986)
			(xy 346.751194 -279.365263) (xy 346.720668 -279.323247) (xy 346.69709 -279.276973) (xy 346.681042 -279.22758)
			(xy 346.672917 -279.176285) (xy 346.393261 -279.176285) (xy 346.385136 -279.22758) (xy 346.369088 -279.276973)
			(xy 346.34551 -279.323247) (xy 346.314984 -279.365263) (xy 346.278261 -279.401986) (xy 346.236245 -279.432512)
			(xy 346.189971 -279.45609) (xy 346.140578 -279.472138) (xy 346.089283 -279.480263) (xy 346.037349 -279.480263)
			(xy 345.986054 -279.472138) (xy 345.936661 -279.45609) (xy 345.890387 -279.432512) (xy 345.848371 -279.401986)
			(xy 345.811648 -279.365263) (xy 345.781122 -279.323247) (xy 345.757544 -279.276973) (xy 345.741496 -279.22758)
			(xy 345.733371 -279.176285) (xy 344.513407 -279.176285) (xy 344.505282 -279.22758) (xy 344.489234 -279.276973)
			(xy 344.465656 -279.323247) (xy 344.43513 -279.365263) (xy 344.398407 -279.401986) (xy 344.356391 -279.432512)
			(xy 344.310117 -279.45609) (xy 344.260724 -279.472138) (xy 344.209429 -279.480263) (xy 344.157495 -279.480263)
			(xy 344.1062 -279.472138) (xy 344.056807 -279.45609) (xy 344.010533 -279.432512) (xy 343.968517 -279.401986)
			(xy 343.931794 -279.365263) (xy 343.901268 -279.323247) (xy 343.87769 -279.276973) (xy 343.861642 -279.22758)
			(xy 343.853517 -279.176285) (xy 343.573861 -279.176285) (xy 343.565736 -279.22758) (xy 343.549688 -279.276973)
			(xy 343.52611 -279.323247) (xy 343.495584 -279.365263) (xy 343.458861 -279.401986) (xy 343.416845 -279.432512)
			(xy 343.370571 -279.45609) (xy 343.321178 -279.472138) (xy 343.269883 -279.480263) (xy 343.217949 -279.480263)
			(xy 343.166654 -279.472138) (xy 343.117261 -279.45609) (xy 343.070987 -279.432512) (xy 343.028971 -279.401986)
			(xy 342.992248 -279.365263) (xy 342.961722 -279.323247) (xy 342.938144 -279.276973) (xy 342.922096 -279.22758)
			(xy 342.913971 -279.176285) (xy 342.634061 -279.176285) (xy 342.625936 -279.22758) (xy 342.609888 -279.276973)
			(xy 342.58631 -279.323247) (xy 342.555784 -279.365263) (xy 342.519061 -279.401986) (xy 342.477045 -279.432512)
			(xy 342.430771 -279.45609) (xy 342.381378 -279.472138) (xy 342.330083 -279.480263) (xy 342.278149 -279.480263)
			(xy 342.226854 -279.472138) (xy 342.177461 -279.45609) (xy 342.131187 -279.432512) (xy 342.089171 -279.401986)
			(xy 342.052448 -279.365263) (xy 342.021922 -279.323247) (xy 341.998344 -279.276973) (xy 341.982296 -279.22758)
			(xy 341.974171 -279.176285) (xy 341.694007 -279.176285) (xy 341.685882 -279.22758) (xy 341.669834 -279.276973)
			(xy 341.646256 -279.323247) (xy 341.61573 -279.365263) (xy 341.579007 -279.401986) (xy 341.536991 -279.432512)
			(xy 341.490717 -279.45609) (xy 341.441324 -279.472138) (xy 341.390029 -279.480263) (xy 341.338095 -279.480263)
			(xy 341.2868 -279.472138) (xy 341.237407 -279.45609) (xy 341.191133 -279.432512) (xy 341.149117 -279.401986)
			(xy 341.112394 -279.365263) (xy 341.081868 -279.323247) (xy 341.05829 -279.276973) (xy 341.042242 -279.22758)
			(xy 341.034117 -279.176285) (xy 340.754207 -279.176285) (xy 340.746082 -279.22758) (xy 340.730034 -279.276973)
			(xy 340.706456 -279.323247) (xy 340.67593 -279.365263) (xy 340.639207 -279.401986) (xy 340.597191 -279.432512)
			(xy 340.550917 -279.45609) (xy 340.501524 -279.472138) (xy 340.450229 -279.480263) (xy 340.398295 -279.480263)
			(xy 340.347 -279.472138) (xy 340.297607 -279.45609) (xy 340.251333 -279.432512) (xy 340.209317 -279.401986)
			(xy 340.172594 -279.365263) (xy 340.142068 -279.323247) (xy 340.11849 -279.276973) (xy 340.102442 -279.22758)
			(xy 340.094317 -279.176285) (xy 339.814407 -279.176285) (xy 339.806282 -279.22758) (xy 339.790234 -279.276973)
			(xy 339.766656 -279.323247) (xy 339.73613 -279.365263) (xy 339.699407 -279.401986) (xy 339.657391 -279.432512)
			(xy 339.611117 -279.45609) (xy 339.561724 -279.472138) (xy 339.510429 -279.480263) (xy 339.458495 -279.480263)
			(xy 339.4072 -279.472138) (xy 339.357807 -279.45609) (xy 339.311533 -279.432512) (xy 339.269517 -279.401986)
			(xy 339.232794 -279.365263) (xy 339.202268 -279.323247) (xy 339.17869 -279.276973) (xy 339.162642 -279.22758)
			(xy 339.154517 -279.176285) (xy 338.874886 -279.176285) (xy 338.874886 -279.176305) (xy 338.866752 -279.227639)
			(xy 338.850687 -279.277069) (xy 338.827088 -279.323377) (xy 338.796535 -279.365423) (xy 338.75978 -279.402171)
			(xy 338.717729 -279.432717) (xy 338.671417 -279.456309) (xy 338.621985 -279.472365) (xy 338.570649 -279.48049)
			(xy 338.544662 -279.481026) (xy 338.534026 -279.480925) (xy 338.512801 -279.479526) (xy 338.502244 -279.478232)
			(xy 338.50199 -279.478232) (xy 338.490542 -279.477328) (xy 338.46883 -279.484731) (xy 338.460334 -279.492456)
			(xy 338.353146 -279.599644) (xy 338.346923 -279.606501) (xy 338.339486 -279.623441) (xy 338.338668 -279.632664)
			(xy 338.337398 -279.658572) (xy 338.33562 -279.702768) (xy 338.347304 -279.734772) (xy 338.349844 -279.738074)
			(xy 338.365093 -279.757261) (xy 338.390733 -279.799028) (xy 338.410399 -279.843918) (xy 338.423719 -279.891083)
			(xy 338.43044 -279.939629) (xy 338.43087 -279.964134) (xy 338.430385 -279.990101) (xy 339.624671 -279.990101)
			(xy 339.624671 -279.938167) (xy 339.632796 -279.886872) (xy 339.648844 -279.837479) (xy 339.672422 -279.791205)
			(xy 339.702948 -279.749189) (xy 339.739671 -279.712466) (xy 339.781687 -279.68194) (xy 339.827961 -279.658362)
			(xy 339.877354 -279.642314) (xy 339.928649 -279.634189) (xy 339.980583 -279.634189) (xy 340.031878 -279.642314)
			(xy 340.081271 -279.658362) (xy 340.127545 -279.68194) (xy 340.169561 -279.712466) (xy 340.206284 -279.749189)
			(xy 340.23681 -279.791205) (xy 340.260388 -279.837479) (xy 340.276436 -279.886872) (xy 340.284561 -279.938167)
			(xy 340.28507 -279.964134) (xy 340.284561 -279.990101) (xy 340.564471 -279.990101) (xy 340.564471 -279.938167)
			(xy 340.572596 -279.886872) (xy 340.588644 -279.837479) (xy 340.612222 -279.791205) (xy 340.642748 -279.749189)
			(xy 340.679471 -279.712466) (xy 340.721487 -279.68194) (xy 340.767761 -279.658362) (xy 340.817154 -279.642314)
			(xy 340.868449 -279.634189) (xy 340.920383 -279.634189) (xy 340.971678 -279.642314) (xy 341.021071 -279.658362)
			(xy 341.067345 -279.68194) (xy 341.109361 -279.712466) (xy 341.146084 -279.749189) (xy 341.17661 -279.791205)
			(xy 341.200188 -279.837479) (xy 341.216236 -279.886872) (xy 341.224361 -279.938167) (xy 341.22487 -279.964134)
			(xy 341.224361 -279.990101) (xy 342.443817 -279.990101) (xy 342.443817 -279.938167) (xy 342.451942 -279.886872)
			(xy 342.46799 -279.837479) (xy 342.491568 -279.791205) (xy 342.522094 -279.749189) (xy 342.558817 -279.712466)
			(xy 342.600833 -279.68194) (xy 342.647107 -279.658362) (xy 342.6965 -279.642314) (xy 342.747795 -279.634189)
			(xy 342.799729 -279.634189) (xy 342.851024 -279.642314) (xy 342.900417 -279.658362) (xy 342.946691 -279.68194)
			(xy 342.988707 -279.712466) (xy 343.02543 -279.749189) (xy 343.055956 -279.791205) (xy 343.079534 -279.837479)
			(xy 343.095582 -279.886872) (xy 343.103707 -279.938167) (xy 343.104216 -279.964134) (xy 343.103707 -279.990101)
			(xy 343.383871 -279.990101) (xy 343.383871 -279.938167) (xy 343.391996 -279.886872) (xy 343.408044 -279.837479)
			(xy 343.431622 -279.791205) (xy 343.462148 -279.749189) (xy 343.498871 -279.712466) (xy 343.540887 -279.68194)
			(xy 343.587161 -279.658362) (xy 343.636554 -279.642314) (xy 343.687849 -279.634189) (xy 343.739783 -279.634189)
			(xy 343.791078 -279.642314) (xy 343.840471 -279.658362) (xy 343.886745 -279.68194) (xy 343.928761 -279.712466)
			(xy 343.965484 -279.749189) (xy 343.99601 -279.791205) (xy 344.019588 -279.837479) (xy 344.035636 -279.886872)
			(xy 344.043761 -279.938167) (xy 344.04427 -279.964134) (xy 344.323162 -279.964134) (xy 344.323671 -279.938167)
			(xy 344.331796 -279.886872) (xy 344.347844 -279.837479) (xy 344.371422 -279.791205) (xy 344.401948 -279.749189)
			(xy 344.438671 -279.712466) (xy 344.480687 -279.68194) (xy 344.526961 -279.658362) (xy 344.576354 -279.642314)
			(xy 344.627649 -279.634189) (xy 344.679583 -279.634189) (xy 344.730878 -279.642314) (xy 344.780271 -279.658362)
			(xy 344.826545 -279.68194) (xy 344.868561 -279.712466) (xy 344.905284 -279.749189) (xy 344.93581 -279.791205)
			(xy 344.959388 -279.837479) (xy 344.975436 -279.886872) (xy 344.983561 -279.938167) (xy 344.98407 -279.964134)
			(xy 344.98407 -279.964388) (xy 344.983561 -279.990101) (xy 345.263471 -279.990101) (xy 345.263471 -279.938167)
			(xy 345.271596 -279.886872) (xy 345.287644 -279.837479) (xy 345.311222 -279.791205) (xy 345.341748 -279.749189)
			(xy 345.378471 -279.712466) (xy 345.420487 -279.68194) (xy 345.466761 -279.658362) (xy 345.516154 -279.642314)
			(xy 345.567449 -279.634189) (xy 345.619383 -279.634189) (xy 345.670678 -279.642314) (xy 345.720071 -279.658362)
			(xy 345.766345 -279.68194) (xy 345.808361 -279.712466) (xy 345.845084 -279.749189) (xy 345.87561 -279.791205)
			(xy 345.899188 -279.837479) (xy 345.915236 -279.886872) (xy 345.923361 -279.938167) (xy 345.92387 -279.964134)
			(xy 345.923361 -279.990101) (xy 346.203271 -279.990101) (xy 346.203271 -279.938167) (xy 346.211396 -279.886872)
			(xy 346.227444 -279.837479) (xy 346.251022 -279.791205) (xy 346.281548 -279.749189) (xy 346.318271 -279.712466)
			(xy 346.360287 -279.68194) (xy 346.406561 -279.658362) (xy 346.455954 -279.642314) (xy 346.507249 -279.634189)
			(xy 346.559183 -279.634189) (xy 346.610478 -279.642314) (xy 346.659871 -279.658362) (xy 346.706145 -279.68194)
			(xy 346.748161 -279.712466) (xy 346.784884 -279.749189) (xy 346.81541 -279.791205) (xy 346.838988 -279.837479)
			(xy 346.855036 -279.886872) (xy 346.863161 -279.938167) (xy 346.86367 -279.964134) (xy 346.863161 -279.990101)
			(xy 348.082871 -279.990101) (xy 348.082871 -279.938167) (xy 348.090996 -279.886872) (xy 348.107044 -279.837479)
			(xy 348.130622 -279.791205) (xy 348.161148 -279.749189) (xy 348.197871 -279.712466) (xy 348.239887 -279.68194)
			(xy 348.286161 -279.658362) (xy 348.335554 -279.642314) (xy 348.386849 -279.634189) (xy 348.438783 -279.634189)
			(xy 348.490078 -279.642314) (xy 348.539471 -279.658362) (xy 348.585745 -279.68194) (xy 348.627761 -279.712466)
			(xy 348.664484 -279.749189) (xy 348.69501 -279.791205) (xy 348.718588 -279.837479) (xy 348.734636 -279.886872)
			(xy 348.742761 -279.938167) (xy 348.74327 -279.964134) (xy 348.742761 -279.990101) (xy 349.022671 -279.990101)
			(xy 349.022671 -279.938167) (xy 349.030796 -279.886872) (xy 349.046844 -279.837479) (xy 349.070422 -279.791205)
			(xy 349.100948 -279.749189) (xy 349.137671 -279.712466) (xy 349.179687 -279.68194) (xy 349.225961 -279.658362)
			(xy 349.275354 -279.642314) (xy 349.326649 -279.634189) (xy 349.378583 -279.634189) (xy 349.429878 -279.642314)
			(xy 349.479271 -279.658362) (xy 349.525545 -279.68194) (xy 349.567561 -279.712466) (xy 349.604284 -279.749189)
			(xy 349.63481 -279.791205) (xy 349.658388 -279.837479) (xy 349.674436 -279.886872) (xy 349.682561 -279.938167)
			(xy 349.68307 -279.964134) (xy 349.682561 -279.990101) (xy 349.674436 -280.041396) (xy 349.658388 -280.090789)
			(xy 349.63481 -280.137063) (xy 349.604284 -280.179079) (xy 349.567561 -280.215802) (xy 349.525545 -280.246328)
			(xy 349.479271 -280.269906) (xy 349.429878 -280.285954) (xy 349.378583 -280.294079) (xy 349.326649 -280.294079)
			(xy 349.275354 -280.285954) (xy 349.225961 -280.269906) (xy 349.179687 -280.246328) (xy 349.137671 -280.215802)
			(xy 349.100948 -280.179079) (xy 349.070422 -280.137063) (xy 349.046844 -280.090789) (xy 349.030796 -280.041396)
			(xy 349.022671 -279.990101) (xy 348.742761 -279.990101) (xy 348.734636 -280.041396) (xy 348.718588 -280.090789)
			(xy 348.69501 -280.137063) (xy 348.664484 -280.179079) (xy 348.627761 -280.215802) (xy 348.585745 -280.246328)
			(xy 348.539471 -280.269906) (xy 348.490078 -280.285954) (xy 348.438783 -280.294079) (xy 348.386849 -280.294079)
			(xy 348.335554 -280.285954) (xy 348.286161 -280.269906) (xy 348.239887 -280.246328) (xy 348.197871 -280.215802)
			(xy 348.161148 -280.179079) (xy 348.130622 -280.137063) (xy 348.107044 -280.090789) (xy 348.090996 -280.041396)
			(xy 348.082871 -279.990101) (xy 346.863161 -279.990101) (xy 346.855036 -280.041396) (xy 346.838988 -280.090789)
			(xy 346.81541 -280.137063) (xy 346.784884 -280.179079) (xy 346.748161 -280.215802) (xy 346.706145 -280.246328)
			(xy 346.659871 -280.269906) (xy 346.610478 -280.285954) (xy 346.559183 -280.294079) (xy 346.507249 -280.294079)
			(xy 346.455954 -280.285954) (xy 346.406561 -280.269906) (xy 346.360287 -280.246328) (xy 346.318271 -280.215802)
			(xy 346.281548 -280.179079) (xy 346.251022 -280.137063) (xy 346.227444 -280.090789) (xy 346.211396 -280.041396)
			(xy 346.203271 -279.990101) (xy 345.923361 -279.990101) (xy 345.915236 -280.041396) (xy 345.899188 -280.090789)
			(xy 345.87561 -280.137063) (xy 345.845084 -280.179079) (xy 345.808361 -280.215802) (xy 345.766345 -280.246328)
			(xy 345.720071 -280.269906) (xy 345.670678 -280.285954) (xy 345.619383 -280.294079) (xy 345.567449 -280.294079)
			(xy 345.516154 -280.285954) (xy 345.466761 -280.269906) (xy 345.420487 -280.246328) (xy 345.378471 -280.215802)
			(xy 345.341748 -280.179079) (xy 345.311222 -280.137063) (xy 345.287644 -280.090789) (xy 345.271596 -280.041396)
			(xy 345.263471 -279.990101) (xy 344.983561 -279.990101) (xy 344.983516 -279.992374) (xy 344.974067 -280.047542)
			(xy 344.965274 -280.074116) (xy 344.9574 -280.096214) (xy 345.161108 -280.44902) (xy 345.184222 -280.453338)
			(xy 345.209134 -280.458545) (xy 345.257117 -280.475505) (xy 345.301933 -280.499618) (xy 345.342526 -280.530313)
			(xy 345.377935 -280.566866) (xy 345.407325 -280.608413) (xy 345.430001 -280.653973) (xy 345.445427 -280.70247)
			(xy 345.45324 -280.752758) (xy 345.453716 -280.778204) (xy 345.453207 -280.804171) (xy 345.445082 -280.855466)
			(xy 345.429034 -280.904859) (xy 345.405456 -280.951133) (xy 345.37493 -280.993149) (xy 345.338207 -281.029872)
			(xy 345.296191 -281.060398) (xy 345.249917 -281.083976) (xy 345.200524 -281.100024) (xy 345.149229 -281.108149)
			(xy 345.097295 -281.108149) (xy 345.046 -281.100024) (xy 344.996607 -281.083976) (xy 344.950333 -281.060398)
			(xy 344.908317 -281.029872) (xy 344.871594 -280.993149) (xy 344.841068 -280.951133) (xy 344.81749 -280.904859)
			(xy 344.801442 -280.855466) (xy 344.793317 -280.804171) (xy 344.792808 -280.778204) (xy 344.793361 -280.750218)
			(xy 344.802811 -280.69505) (xy 344.811604 -280.668476) (xy 344.819224 -280.646378) (xy 344.615516 -280.293318)
			(xy 344.592402 -280.289) (xy 344.567492 -280.283827) (xy 344.519535 -280.266844) (xy 344.474748 -280.242713)
			(xy 344.434186 -280.212004) (xy 344.398809 -280.175444) (xy 344.369451 -280.133894) (xy 344.346807 -280.088336)
			(xy 344.33141 -280.039847) (xy 344.323625 -279.989572) (xy 344.323162 -279.964134) (xy 344.04427 -279.964134)
			(xy 344.043761 -279.990101) (xy 344.035636 -280.041396) (xy 344.019588 -280.090789) (xy 343.99601 -280.137063)
			(xy 343.965484 -280.179079) (xy 343.928761 -280.215802) (xy 343.886745 -280.246328) (xy 343.840471 -280.269906)
			(xy 343.791078 -280.285954) (xy 343.739783 -280.294079) (xy 343.687849 -280.294079) (xy 343.636554 -280.285954)
			(xy 343.587161 -280.269906) (xy 343.540887 -280.246328) (xy 343.498871 -280.215802) (xy 343.462148 -280.179079)
			(xy 343.431622 -280.137063) (xy 343.408044 -280.090789) (xy 343.391996 -280.041396) (xy 343.383871 -279.990101)
			(xy 343.103707 -279.990101) (xy 343.095582 -280.041396) (xy 343.079534 -280.090789) (xy 343.055956 -280.137063)
			(xy 343.02543 -280.179079) (xy 342.988707 -280.215802) (xy 342.946691 -280.246328) (xy 342.900417 -280.269906)
			(xy 342.851024 -280.285954) (xy 342.799729 -280.294079) (xy 342.747795 -280.294079) (xy 342.6965 -280.285954)
			(xy 342.647107 -280.269906) (xy 342.600833 -280.246328) (xy 342.558817 -280.215802) (xy 342.522094 -280.179079)
			(xy 342.491568 -280.137063) (xy 342.46799 -280.090789) (xy 342.451942 -280.041396) (xy 342.443817 -279.990101)
			(xy 341.224361 -279.990101) (xy 341.216236 -280.041396) (xy 341.200188 -280.090789) (xy 341.17661 -280.137063)
			(xy 341.146084 -280.179079) (xy 341.109361 -280.215802) (xy 341.067345 -280.246328) (xy 341.021071 -280.269906)
			(xy 340.971678 -280.285954) (xy 340.920383 -280.294079) (xy 340.868449 -280.294079) (xy 340.817154 -280.285954)
			(xy 340.767761 -280.269906) (xy 340.721487 -280.246328) (xy 340.679471 -280.215802) (xy 340.642748 -280.179079)
			(xy 340.612222 -280.137063) (xy 340.588644 -280.090789) (xy 340.572596 -280.041396) (xy 340.564471 -279.990101)
			(xy 340.284561 -279.990101) (xy 340.276436 -280.041396) (xy 340.260388 -280.090789) (xy 340.23681 -280.137063)
			(xy 340.206284 -280.179079) (xy 340.169561 -280.215802) (xy 340.127545 -280.246328) (xy 340.081271 -280.269906)
			(xy 340.031878 -280.285954) (xy 339.980583 -280.294079) (xy 339.928649 -280.294079) (xy 339.877354 -280.285954)
			(xy 339.827961 -280.269906) (xy 339.781687 -280.246328) (xy 339.739671 -280.215802) (xy 339.702948 -280.179079)
			(xy 339.672422 -280.137063) (xy 339.648844 -280.090789) (xy 339.632796 -280.041396) (xy 339.624671 -279.990101)
			(xy 338.430385 -279.990101) (xy 338.430347 -279.992117) (xy 338.421587 -280.047392) (xy 338.404287 -280.100616)
			(xy 338.378875 -280.150479) (xy 338.345975 -280.195752) (xy 338.306397 -280.235322) (xy 338.261117 -280.268212)
			(xy 338.211249 -280.293615) (xy 338.158022 -280.310904) (xy 338.102745 -280.319653) (xy 338.074762 -280.320242)
			(xy 338.050258 -280.31983) (xy 338.001713 -280.313099) (xy 337.954551 -280.29977) (xy 337.909665 -280.280095)
			(xy 337.867904 -280.254446) (xy 337.848702 -280.239216) (xy 337.8454 -280.236676) (xy 337.813396 -280.224992)
			(xy 337.7692 -280.22677) (xy 337.743292 -280.22804) (xy 337.734074 -280.228881) (xy 337.717136 -280.236307)
			(xy 337.710272 -280.242518) (xy 337.678268 -280.274522) (xy 337.670233 -280.283662) (xy 337.663091 -280.306887)
			(xy 337.664552 -280.318972) (xy 337.67268 -280.35377) (xy 337.681824 -280.39187) (xy 337.683436 -280.398052)
			(xy 337.689355 -280.409367) (xy 337.693508 -280.414222) (xy 337.709256 -280.43124) (xy 337.728306 -280.44394)
			(xy 337.728814 -280.444194) (xy 337.732116 -280.445464) (xy 337.73364 -280.445972) (xy 337.758405 -280.456102)
			(xy 337.804827 -280.482706) (xy 337.846748 -280.515953) (xy 337.883226 -280.555095) (xy 337.913442 -280.599251)
			(xy 337.936714 -280.647429) (xy 337.952521 -280.698546) (xy 337.960506 -280.751452) (xy 337.96097 -280.778204)
			(xy 337.960518 -280.803815) (xy 337.960466 -280.804171) (xy 338.214717 -280.804171) (xy 338.214717 -280.752237)
			(xy 338.222842 -280.700942) (xy 338.23889 -280.651549) (xy 338.262468 -280.605275) (xy 338.292994 -280.563259)
			(xy 338.329717 -280.526536) (xy 338.371733 -280.49601) (xy 338.418007 -280.472432) (xy 338.4674 -280.456384)
			(xy 338.518695 -280.448259) (xy 338.570629 -280.448259) (xy 338.621924 -280.456384) (xy 338.671317 -280.472432)
			(xy 338.717591 -280.49601) (xy 338.759607 -280.526536) (xy 338.79633 -280.563259) (xy 338.826856 -280.605275)
			(xy 338.850434 -280.651549) (xy 338.866482 -280.700942) (xy 338.874607 -280.752237) (xy 338.875116 -280.778204)
			(xy 340.094062 -280.778204) (xy 340.094571 -280.752237) (xy 340.102696 -280.700942) (xy 340.118744 -280.651549)
			(xy 340.142322 -280.605275) (xy 340.172848 -280.563259) (xy 340.209571 -280.526536) (xy 340.251587 -280.49601)
			(xy 340.297861 -280.472432) (xy 340.347254 -280.456384) (xy 340.398549 -280.448259) (xy 340.450483 -280.448259)
			(xy 340.501778 -280.456384) (xy 340.551171 -280.472432) (xy 340.597445 -280.49601) (xy 340.639461 -280.526536)
			(xy 340.676184 -280.563259) (xy 340.70671 -280.605275) (xy 340.730288 -280.651549) (xy 340.746336 -280.700942)
			(xy 340.754461 -280.752237) (xy 340.75497 -280.778204) (xy 340.75497 -280.778458) (xy 340.754454 -280.804171)
			(xy 341.974171 -280.804171) (xy 341.974171 -280.752237) (xy 341.982296 -280.700942) (xy 341.998344 -280.651549)
			(xy 342.021922 -280.605275) (xy 342.052448 -280.563259) (xy 342.089171 -280.526536) (xy 342.131187 -280.49601)
			(xy 342.177461 -280.472432) (xy 342.226854 -280.456384) (xy 342.278149 -280.448259) (xy 342.330083 -280.448259)
			(xy 342.381378 -280.456384) (xy 342.430771 -280.472432) (xy 342.477045 -280.49601) (xy 342.519061 -280.526536)
			(xy 342.555784 -280.563259) (xy 342.58631 -280.605275) (xy 342.609888 -280.651549) (xy 342.625936 -280.700942)
			(xy 342.634061 -280.752237) (xy 342.63457 -280.778204) (xy 342.634061 -280.804165) (xy 342.913759 -280.804165)
			(xy 342.913759 -280.752235) (xy 342.921882 -280.700944) (xy 342.937928 -280.651555) (xy 342.961502 -280.605285)
			(xy 342.992024 -280.563271) (xy 343.028742 -280.526549) (xy 343.070752 -280.496022) (xy 343.11702 -280.472443)
			(xy 343.166407 -280.456391) (xy 343.217697 -280.448262) (xy 343.243662 -280.44775) (xy 343.269284 -280.44822)
			(xy 343.319912 -280.456146) (xy 343.368712 -280.471782) (xy 343.414519 -280.494755) (xy 343.456236 -280.524516)
			(xy 343.492866 -280.560352) (xy 343.508584 -280.580592) (xy 343.918794 -280.580592) (xy 343.934533 -280.560367)
			(xy 343.971147 -280.524515) (xy 344.012856 -280.494744) (xy 344.058661 -280.471768) (xy 344.107464 -280.456139)
			(xy 344.158094 -280.448231) (xy 344.183716 -280.44775) (xy 344.209683 -280.448252) (xy 344.260976 -280.456379)
			(xy 344.310367 -280.472429) (xy 344.35664 -280.496008) (xy 344.398654 -280.526535) (xy 344.435375 -280.563258)
			(xy 344.4659 -280.605274) (xy 344.489477 -280.651547) (xy 344.505525 -280.700939) (xy 344.513649 -280.752233)
			(xy 344.513649 -280.804167) (xy 344.505525 -280.855461) (xy 344.489477 -280.904853) (xy 344.4659 -280.951126)
			(xy 344.435375 -280.993142) (xy 344.398654 -281.029865) (xy 344.35664 -281.060392) (xy 344.310367 -281.083971)
			(xy 344.260976 -281.100021) (xy 344.209683 -281.108148) (xy 344.183716 -281.108658) (xy 344.158094 -281.1082)
			(xy 344.107465 -281.100272) (xy 344.058665 -281.084633) (xy 344.012858 -281.061657) (xy 343.971142 -281.031895)
			(xy 343.934512 -280.996057) (xy 343.918794 -280.975816) (xy 343.508584 -280.975816) (xy 343.49286 -280.996053)
			(xy 343.456243 -281.031905) (xy 343.41453 -281.061674) (xy 343.368723 -281.084647) (xy 343.319917 -281.100274)
			(xy 343.269285 -281.108179) (xy 343.243662 -281.108658) (xy 343.217697 -281.108138) (xy 343.166407 -281.100009)
			(xy 343.11702 -281.083957) (xy 343.070752 -281.060378) (xy 343.028742 -281.029851) (xy 342.992024 -280.993129)
			(xy 342.961502 -280.951115) (xy 342.937928 -280.904845) (xy 342.921882 -280.855456) (xy 342.913759 -280.804165)
			(xy 342.634061 -280.804165) (xy 342.634061 -280.804171) (xy 342.625936 -280.855466) (xy 342.609888 -280.904859)
			(xy 342.58631 -280.951133) (xy 342.555784 -280.993149) (xy 342.519061 -281.029872) (xy 342.477045 -281.060398)
			(xy 342.430771 -281.083976) (xy 342.381378 -281.100024) (xy 342.330083 -281.108149) (xy 342.278149 -281.108149)
			(xy 342.226854 -281.100024) (xy 342.177461 -281.083976) (xy 342.131187 -281.060398) (xy 342.089171 -281.029872)
			(xy 342.052448 -280.993149) (xy 342.021922 -280.951133) (xy 341.998344 -280.904859) (xy 341.982296 -280.855466)
			(xy 341.974171 -280.804171) (xy 340.754454 -280.804171) (xy 340.754408 -280.806443) (xy 340.744965 -280.861611)
			(xy 340.736174 -280.888186) (xy 340.7283 -280.910284) (xy 340.932008 -281.262836) (xy 340.955122 -281.267154)
			(xy 340.980038 -281.272346) (xy 341.028021 -281.289307) (xy 341.072839 -281.313421) (xy 341.113432 -281.344118)
			(xy 341.148841 -281.380673) (xy 341.17823 -281.422223) (xy 341.200905 -281.467785) (xy 341.216331 -281.516284)
			(xy 341.224142 -281.566574) (xy 341.224616 -281.59202) (xy 341.224107 -281.617987) (xy 341.215982 -281.669282)
			(xy 341.199934 -281.718675) (xy 341.176356 -281.764949) (xy 341.14583 -281.806965) (xy 341.109107 -281.843688)
			(xy 341.067091 -281.874214) (xy 341.020817 -281.897792) (xy 340.971424 -281.91384) (xy 340.920129 -281.921965)
			(xy 340.868195 -281.921965) (xy 340.8169 -281.91384) (xy 340.767507 -281.897792) (xy 340.721233 -281.874214)
			(xy 340.679217 -281.843688) (xy 340.642494 -281.806965) (xy 340.611968 -281.764949) (xy 340.58839 -281.718675)
			(xy 340.572342 -281.669282) (xy 340.564217 -281.617987) (xy 340.563708 -281.59202) (xy 340.564329 -281.564103)
			(xy 340.573782 -281.509073) (xy 340.582504 -281.482546) (xy 340.590124 -281.460448) (xy 340.386416 -281.107388)
			(xy 340.363302 -281.10307) (xy 340.338385 -281.097925) (xy 340.290427 -281.08094) (xy 340.245637 -281.056806)
			(xy 340.205075 -281.026094) (xy 340.169697 -280.98953) (xy 340.140341 -280.947976) (xy 340.117698 -280.902415)
			(xy 340.102304 -280.853922) (xy 340.094522 -280.803643) (xy 340.094062 -280.778204) (xy 338.875116 -280.778204)
			(xy 338.874607 -280.804171) (xy 338.866482 -280.855466) (xy 338.850434 -280.904859) (xy 338.826856 -280.951133)
			(xy 338.79633 -280.993149) (xy 338.759607 -281.029872) (xy 338.717591 -281.060398) (xy 338.671317 -281.083976)
			(xy 338.621924 -281.100024) (xy 338.570629 -281.108149) (xy 338.518695 -281.108149) (xy 338.4674 -281.100024)
			(xy 338.418007 -281.083976) (xy 338.371733 -281.060398) (xy 338.329717 -281.029872) (xy 338.292994 -280.993149)
			(xy 338.262468 -280.951133) (xy 338.23889 -280.904859) (xy 338.222842 -280.855466) (xy 338.214717 -280.804171)
			(xy 337.960466 -280.804171) (xy 337.953168 -280.854508) (xy 337.938633 -280.903625) (xy 337.917214 -280.950155)
			(xy 337.889352 -280.993138) (xy 337.855622 -281.031687) (xy 337.816718 -281.065008) (xy 337.773444 -281.092414)
			(xy 337.726691 -281.113341) (xy 337.677423 -281.127356) (xy 337.652106 -281.131264) (xy 337.627468 -281.134566)
			(xy 337.439254 -281.460194) (xy 337.446874 -281.482292) (xy 337.455666 -281.508866) (xy 337.465114 -281.564034)
			(xy 337.46567 -281.59202) (xy 337.465161 -281.617987) (xy 337.744817 -281.617987) (xy 337.744817 -281.566053)
			(xy 337.752942 -281.514758) (xy 337.76899 -281.465365) (xy 337.792568 -281.419091) (xy 337.823094 -281.377075)
			(xy 337.859817 -281.340352) (xy 337.901833 -281.309826) (xy 337.948107 -281.286248) (xy 337.9975 -281.2702)
			(xy 338.048795 -281.262075) (xy 338.100729 -281.262075) (xy 338.152024 -281.2702) (xy 338.201417 -281.286248)
			(xy 338.247691 -281.309826) (xy 338.289707 -281.340352) (xy 338.32643 -281.377075) (xy 338.356956 -281.419091)
			(xy 338.380534 -281.465365) (xy 338.396582 -281.514758) (xy 338.404707 -281.566053) (xy 338.405216 -281.59202)
			(xy 338.404707 -281.617964) (xy 338.684675 -281.617964) (xy 338.684675 -281.566036) (xy 338.692798 -281.514748)
			(xy 338.708843 -281.465362) (xy 338.732416 -281.419093) (xy 338.762936 -281.377081) (xy 338.799652 -281.340361)
			(xy 338.841661 -281.309836) (xy 338.887926 -281.286258) (xy 338.937311 -281.270207) (xy 338.988598 -281.262078)
			(xy 339.014562 -281.261566) (xy 339.040182 -281.26207) (xy 339.090807 -281.269993) (xy 339.139605 -281.285625)
			(xy 339.185411 -281.308592) (xy 339.227129 -281.338345) (xy 339.263763 -281.374172) (xy 339.279484 -281.394408)
			(xy 339.68944 -281.394408) (xy 339.705157 -281.374165) (xy 339.741774 -281.338312) (xy 339.783488 -281.308543)
			(xy 339.829298 -281.285571) (xy 339.878104 -281.269946) (xy 339.928738 -281.262044) (xy 339.954362 -281.261566)
			(xy 339.980335 -281.262006) (xy 340.031642 -281.270127) (xy 340.081046 -281.286174) (xy 340.127332 -281.309753)
			(xy 340.169359 -281.340283) (xy 340.206092 -281.377012) (xy 340.236627 -281.419036) (xy 340.260211 -281.465319)
			(xy 340.276264 -281.514721) (xy 340.284391 -281.566027) (xy 340.284391 -281.617973) (xy 340.276264 -281.669279)
			(xy 340.260211 -281.718681) (xy 340.236627 -281.764964) (xy 340.206092 -281.806988) (xy 340.169359 -281.843717)
			(xy 340.127332 -281.874247) (xy 340.081046 -281.897826) (xy 340.031642 -281.913873) (xy 339.980335 -281.921994)
			(xy 339.954362 -281.922474) (xy 339.928741 -281.921977) (xy 339.878115 -281.914056) (xy 339.829315 -281.898424)
			(xy 339.783509 -281.875456) (xy 339.741791 -281.845701) (xy 339.70516 -281.80987) (xy 339.68944 -281.789632)
			(xy 339.279484 -281.789632) (xy 339.263764 -281.809872) (xy 339.227146 -281.845723) (xy 339.185432 -281.875491)
			(xy 339.139624 -281.898464) (xy 339.090818 -281.91409) (xy 339.040185 -281.921995) (xy 339.014562 -281.922474)
			(xy 338.988598 -281.921922) (xy 338.937311 -281.913793) (xy 338.887926 -281.897742) (xy 338.841661 -281.874164)
			(xy 338.799653 -281.843639) (xy 338.762936 -281.806919) (xy 338.732416 -281.764907) (xy 338.708843 -281.718638)
			(xy 338.692798 -281.669252) (xy 338.684675 -281.617964) (xy 338.404707 -281.617964) (xy 338.404707 -281.617987)
			(xy 338.396582 -281.669282) (xy 338.380534 -281.718675) (xy 338.356956 -281.764949) (xy 338.32643 -281.806965)
			(xy 338.289707 -281.843688) (xy 338.247691 -281.874214) (xy 338.201417 -281.897792) (xy 338.152024 -281.91384)
			(xy 338.100729 -281.921965) (xy 338.048795 -281.921965) (xy 337.9975 -281.91384) (xy 337.948107 -281.897792)
			(xy 337.901833 -281.874214) (xy 337.859817 -281.843688) (xy 337.823094 -281.806965) (xy 337.792568 -281.764949)
			(xy 337.76899 -281.718675) (xy 337.752942 -281.669282) (xy 337.744817 -281.617987) (xy 337.465161 -281.617987)
			(xy 337.457036 -281.669282) (xy 337.440988 -281.718675) (xy 337.41741 -281.764949) (xy 337.386884 -281.806965)
			(xy 337.350161 -281.843688) (xy 337.308145 -281.874214) (xy 337.261871 -281.897792) (xy 337.212478 -281.91384)
			(xy 337.161183 -281.921965) (xy 337.109249 -281.921965) (xy 337.057954 -281.91384) (xy 337.008561 -281.897792)
			(xy 336.962287 -281.874214) (xy 336.920271 -281.843688) (xy 336.883548 -281.806965) (xy 336.853022 -281.764949)
			(xy 336.829444 -281.718675) (xy 336.813396 -281.669282) (xy 336.805271 -281.617987) (xy 336.804762 -281.59202)
			(xy 336.805236 -281.566573) (xy 336.813047 -281.516282) (xy 336.828472 -281.467782) (xy 336.851147 -281.422219)
			(xy 336.880535 -281.380668) (xy 336.915944 -281.344111) (xy 336.956536 -281.313411) (xy 337.001353 -281.289295)
			(xy 337.049336 -281.27233) (xy 337.074256 -281.267154) (xy 337.09737 -281.262836) (xy 337.28533 -280.937462)
			(xy 337.277964 -280.92019) (xy 337.274154 -280.911046) (xy 337.270852 -280.90241) (xy 337.269582 -280.8986)
			(xy 337.267663 -280.894686) (xy 337.262679 -280.887536) (xy 337.259676 -280.884376) (xy 337.249262 -280.874724)
			(xy 337.24088 -280.86685) (xy 337.236017 -280.862711) (xy 337.224704 -280.856792) (xy 337.218528 -280.855166)
			(xy 337.180428 -280.846022) (xy 337.14563 -280.837894) (xy 337.133548 -280.836391) (xy 337.110324 -280.843569)
			(xy 337.10118 -280.85161) (xy 336.773012 -281.179778) (xy 336.76209 -281.196288) (xy 336.760312 -281.20086)
			(xy 336.743363 -281.241149) (xy 336.704031 -281.319214) (xy 336.65872 -281.393968) (xy 336.633566 -281.429714)
			(xy 336.613078 -281.457877) (xy 336.569105 -281.511891) (xy 336.545682 -281.537664) (xy 336.539332 -281.544522)
			(xy 336.52587 -281.578558) (xy 336.52587 -281.59202) (xy 336.525385 -281.618007) (xy 336.517251 -281.669341)
			(xy 336.501187 -281.71877) (xy 336.477587 -281.765078) (xy 336.447034 -281.807124) (xy 336.41028 -281.843872)
			(xy 336.368229 -281.874418) (xy 336.321917 -281.898009) (xy 336.272485 -281.914065) (xy 336.221149 -281.92219)
			(xy 336.195162 -281.922728) (xy 336.168727 -281.92221) (xy 336.116533 -281.913786) (xy 336.091276 -281.905964)
			(xy 336.087466 -281.904694) (xy 336.07121 -281.9019) (xy 336.061435 -281.902466) (xy 336.043399 -281.910042)
			(xy 336.036158 -281.916632) (xy 335.957926 -281.994864) (xy 335.951064 -282.00245) (xy 335.943585 -282.021466)
			(xy 335.943448 -282.031694) (xy 335.945734 -282.104338) (xy 335.946352 -282.113168) (xy 335.953 -282.129559)
			(xy 335.958688 -282.136342) (xy 335.962498 -282.140152) (xy 335.963514 -282.140914) (xy 335.981721 -282.157899)
			(xy 336.013718 -282.196048) (xy 336.040096 -282.238278) (xy 336.06034 -282.283768) (xy 336.074058 -282.331633)
			(xy 336.080981 -282.38094) (xy 336.08137 -282.405836) (xy 336.080992 -282.42908) (xy 336.080639 -282.431767)
			(xy 336.335365 -282.431767) (xy 336.335365 -282.379833) (xy 336.343489 -282.328538) (xy 336.359539 -282.279145)
			(xy 336.383117 -282.232871) (xy 336.413644 -282.190856) (xy 336.450368 -282.154134) (xy 336.492385 -282.123609)
			(xy 336.53866 -282.100032) (xy 336.588053 -282.083986) (xy 336.639349 -282.075864) (xy 336.665316 -282.075382)
			(xy 336.690935 -282.075913) (xy 336.741559 -282.083829) (xy 336.790357 -282.099455) (xy 336.836163 -282.122417)
			(xy 336.877882 -282.152166) (xy 336.914516 -282.18799) (xy 336.930238 -282.208224) (xy 337.340194 -282.208224)
			(xy 337.355915 -282.187985) (xy 337.392534 -282.152136) (xy 337.434248 -282.122369) (xy 337.480056 -282.099397)
			(xy 337.528861 -282.08377) (xy 337.579493 -282.075863) (xy 337.605116 -282.075382) (xy 337.631085 -282.075821)
			(xy 337.682384 -282.083948) (xy 337.73178 -282.1) (xy 337.778056 -282.123581) (xy 337.820075 -282.154111)
			(xy 337.8568 -282.190838) (xy 337.887328 -282.232857) (xy 337.910907 -282.279135) (xy 337.926956 -282.328532)
			(xy 337.935081 -282.379831) (xy 337.935081 -282.431769) (xy 337.935076 -282.431803) (xy 338.214971 -282.431803)
			(xy 338.214971 -282.379869) (xy 338.223096 -282.328574) (xy 338.239144 -282.279181) (xy 338.262722 -282.232907)
			(xy 338.293248 -282.190891) (xy 338.329971 -282.154168) (xy 338.371987 -282.123642) (xy 338.418261 -282.100064)
			(xy 338.467654 -282.084016) (xy 338.518949 -282.075891) (xy 338.570883 -282.075891) (xy 338.622178 -282.084016)
			(xy 338.671571 -282.100064) (xy 338.717845 -282.123642) (xy 338.759861 -282.154168) (xy 338.796584 -282.190891)
			(xy 338.82711 -282.232907) (xy 338.850688 -282.279181) (xy 338.866736 -282.328574) (xy 338.874861 -282.379869)
			(xy 338.87537 -282.405836) (xy 338.874861 -282.431803) (xy 338.866736 -282.483098) (xy 338.850688 -282.532491)
			(xy 338.82711 -282.578765) (xy 338.796584 -282.620781) (xy 338.759861 -282.657504) (xy 338.717845 -282.68803)
			(xy 338.671571 -282.711608) (xy 338.622178 -282.727656) (xy 338.570883 -282.735781) (xy 338.518949 -282.735781)
			(xy 338.467654 -282.727656) (xy 338.418261 -282.711608) (xy 338.371987 -282.68803) (xy 338.329971 -282.657504)
			(xy 338.293248 -282.620781) (xy 338.262722 -282.578765) (xy 338.239144 -282.532491) (xy 338.223096 -282.483098)
			(xy 338.214971 -282.431803) (xy 337.935076 -282.431803) (xy 337.926956 -282.483068) (xy 337.910907 -282.532465)
			(xy 337.887328 -282.578743) (xy 337.8568 -282.620762) (xy 337.820075 -282.657489) (xy 337.778056 -282.688019)
			(xy 337.73178 -282.7116) (xy 337.682384 -282.727652) (xy 337.631085 -282.735779) (xy 337.605116 -282.73629)
			(xy 337.579494 -282.73582) (xy 337.528867 -282.727892) (xy 337.480067 -282.712255) (xy 337.434261 -282.689282)
			(xy 337.392544 -282.659522) (xy 337.355913 -282.623687) (xy 337.340194 -282.603448) (xy 336.930238 -282.603448)
			(xy 336.914549 -282.623714) (xy 336.877924 -282.659562) (xy 336.836204 -282.689327) (xy 336.790389 -282.712295)
			(xy 336.741578 -282.727916) (xy 336.690941 -282.735814) (xy 336.665316 -282.73629) (xy 336.639349 -282.735736)
			(xy 336.588053 -282.727614) (xy 336.53866 -282.711568) (xy 336.492385 -282.687991) (xy 336.450368 -282.657466)
			(xy 336.413644 -282.620744) (xy 336.383117 -282.578729) (xy 336.359539 -282.532455) (xy 336.343489 -282.483062)
			(xy 336.335365 -282.431767) (xy 336.080639 -282.431767) (xy 336.074942 -282.475174) (xy 336.06295 -282.52009)
			(xy 336.054446 -282.541726) (xy 336.044794 -282.56484) (xy 336.233008 -282.890722) (xy 336.256122 -282.89504)
			(xy 336.281052 -282.900189) (xy 336.329055 -282.917127) (xy 336.373892 -282.941229) (xy 336.4145 -282.971925)
			(xy 336.449918 -283.008487) (xy 336.479307 -283.05005) (xy 336.501972 -283.09563) (xy 336.517376 -283.144147)
			(xy 336.525154 -283.194454) (xy 336.525616 -283.219906) (xy 336.525107 -283.245873) (xy 336.805017 -283.245873)
			(xy 336.805017 -283.193939) (xy 336.813142 -283.142644) (xy 336.82919 -283.093251) (xy 336.852768 -283.046977)
			(xy 336.883294 -283.004961) (xy 336.920017 -282.968238) (xy 336.962033 -282.937712) (xy 337.008307 -282.914134)
			(xy 337.0577 -282.898086) (xy 337.108995 -282.889961) (xy 337.160929 -282.889961) (xy 337.212224 -282.898086)
			(xy 337.261617 -282.914134) (xy 337.307891 -282.937712) (xy 337.349907 -282.968238) (xy 337.38663 -283.004961)
			(xy 337.417156 -283.046977) (xy 337.440734 -283.093251) (xy 337.456782 -283.142644) (xy 337.464907 -283.193939)
			(xy 337.465416 -283.219906) (xy 337.464907 -283.245873) (xy 337.744817 -283.245873) (xy 337.744817 -283.193939)
			(xy 337.752942 -283.142644) (xy 337.76899 -283.093251) (xy 337.792568 -283.046977) (xy 337.823094 -283.004961)
			(xy 337.859817 -282.968238) (xy 337.901833 -282.937712) (xy 337.948107 -282.914134) (xy 337.9975 -282.898086)
			(xy 338.048795 -282.889961) (xy 338.100729 -282.889961) (xy 338.152024 -282.898086) (xy 338.201417 -282.914134)
			(xy 338.247691 -282.937712) (xy 338.289707 -282.968238) (xy 338.32643 -283.004961) (xy 338.356956 -283.046977)
			(xy 338.380534 -283.093251) (xy 338.396582 -283.142644) (xy 338.404707 -283.193939) (xy 338.405216 -283.219906)
			(xy 338.684108 -283.219906) (xy 338.684632 -283.194457) (xy 338.692408 -283.144156) (xy 338.707807 -283.095644)
			(xy 338.730466 -283.050068) (xy 338.759848 -283.008507) (xy 338.795257 -282.971945) (xy 338.835855 -282.941247)
			(xy 338.880682 -282.917139) (xy 338.928676 -282.900193) (xy 338.953602 -282.89504) (xy 338.976716 -282.890722)
			(xy 339.180678 -282.537408) (xy 339.173058 -282.51531) (xy 339.164314 -282.488788) (xy 339.154864 -282.433755)
			(xy 339.154262 -282.405836) (xy 339.154771 -282.379869) (xy 339.162896 -282.328574) (xy 339.178944 -282.279181)
			(xy 339.202522 -282.232907) (xy 339.233048 -282.190891) (xy 339.269771 -282.154168) (xy 339.311787 -282.123642)
			(xy 339.358061 -282.100064) (xy 339.407454 -282.084016) (xy 339.458749 -282.075891) (xy 339.510683 -282.075891)
			(xy 339.561978 -282.084016) (xy 339.611371 -282.100064) (xy 339.657645 -282.123642) (xy 339.699661 -282.154168)
			(xy 339.736384 -282.190891) (xy 339.76691 -282.232907) (xy 339.790488 -282.279181) (xy 339.806536 -282.328574)
			(xy 339.814661 -282.379869) (xy 339.81517 -282.405836) (xy 339.814746 -282.431301) (xy 339.814668 -282.431803)
			(xy 340.094571 -282.431803) (xy 340.094571 -282.379869) (xy 340.102696 -282.328574) (xy 340.118744 -282.279181)
			(xy 340.142322 -282.232907) (xy 340.172848 -282.190891) (xy 340.209571 -282.154168) (xy 340.251587 -282.123642)
			(xy 340.297861 -282.100064) (xy 340.347254 -282.084016) (xy 340.398549 -282.075891) (xy 340.450483 -282.075891)
			(xy 340.501778 -282.084016) (xy 340.551171 -282.100064) (xy 340.597445 -282.123642) (xy 340.639461 -282.154168)
			(xy 340.676184 -282.190891) (xy 340.70671 -282.232907) (xy 340.730288 -282.279181) (xy 340.746336 -282.328574)
			(xy 340.754461 -282.379869) (xy 340.75497 -282.405836) (xy 341.033862 -282.405836) (xy 341.034278 -282.380383)
			(xy 341.042066 -282.330075) (xy 341.057478 -282.281558) (xy 341.08015 -282.235979) (xy 341.109546 -282.194417)
			(xy 341.144968 -282.157856) (xy 341.18558 -282.127161) (xy 341.230419 -282.103058) (xy 341.278425 -282.086119)
			(xy 341.303356 -282.08097) (xy 341.32647 -282.076652) (xy 341.530178 -281.723846) (xy 341.522304 -281.701748)
			(xy 341.513578 -281.675156) (xy 341.504123 -281.62) (xy 341.503508 -281.59202) (xy 341.504017 -281.566053)
			(xy 341.512142 -281.514758) (xy 341.52819 -281.465365) (xy 341.551768 -281.419091) (xy 341.582294 -281.377075)
			(xy 341.619017 -281.340352) (xy 341.661033 -281.309826) (xy 341.707307 -281.286248) (xy 341.7567 -281.2702)
			(xy 341.807995 -281.262075) (xy 341.859929 -281.262075) (xy 341.911224 -281.2702) (xy 341.960617 -281.286248)
			(xy 342.006891 -281.309826) (xy 342.048907 -281.340352) (xy 342.08563 -281.377075) (xy 342.116156 -281.419091)
			(xy 342.139734 -281.465365) (xy 342.155782 -281.514758) (xy 342.163907 -281.566053) (xy 342.164416 -281.59202)
			(xy 342.163977 -281.617473) (xy 342.163897 -281.617987) (xy 342.443817 -281.617987) (xy 342.443817 -281.566053)
			(xy 342.451942 -281.514758) (xy 342.46799 -281.465365) (xy 342.491568 -281.419091) (xy 342.522094 -281.377075)
			(xy 342.558817 -281.340352) (xy 342.600833 -281.309826) (xy 342.647107 -281.286248) (xy 342.6965 -281.2702)
			(xy 342.747795 -281.262075) (xy 342.799729 -281.262075) (xy 342.851024 -281.2702) (xy 342.900417 -281.286248)
			(xy 342.946691 -281.309826) (xy 342.988707 -281.340352) (xy 343.02543 -281.377075) (xy 343.055956 -281.419091)
			(xy 343.079534 -281.465365) (xy 343.095582 -281.514758) (xy 343.103707 -281.566053) (xy 343.104216 -281.59202)
			(xy 343.103707 -281.617987) (xy 343.095582 -281.669282) (xy 343.079534 -281.718675) (xy 343.055956 -281.764949)
			(xy 343.02543 -281.806965) (xy 342.988707 -281.843688) (xy 342.946691 -281.874214) (xy 342.900417 -281.897792)
			(xy 342.851024 -281.91384) (xy 342.799729 -281.921965) (xy 342.747795 -281.921965) (xy 342.6965 -281.91384)
			(xy 342.647107 -281.897792) (xy 342.600833 -281.874214) (xy 342.558817 -281.843688) (xy 342.522094 -281.806965)
			(xy 342.491568 -281.764949) (xy 342.46799 -281.718675) (xy 342.451942 -281.669282) (xy 342.443817 -281.617987)
			(xy 342.163897 -281.617987) (xy 342.156195 -281.66778) (xy 342.140788 -281.716298) (xy 342.11812 -281.761878)
			(xy 342.088727 -281.803441) (xy 342.053307 -281.840003) (xy 342.012697 -281.870698) (xy 341.967858 -281.8948)
			(xy 341.919853 -281.911738) (xy 341.894922 -281.916886) (xy 341.872062 -281.921204) (xy 341.668354 -282.27401)
			(xy 341.675974 -282.296108) (xy 341.684713 -282.322696) (xy 341.69416 -282.377855) (xy 341.69477 -282.405836)
			(xy 341.694261 -282.431803) (xy 341.974171 -282.431803) (xy 341.974171 -282.379869) (xy 341.982296 -282.328574)
			(xy 341.998344 -282.279181) (xy 342.021922 -282.232907) (xy 342.052448 -282.190891) (xy 342.089171 -282.154168)
			(xy 342.131187 -282.123642) (xy 342.177461 -282.100064) (xy 342.226854 -282.084016) (xy 342.278149 -282.075891)
			(xy 342.330083 -282.075891) (xy 342.381378 -282.084016) (xy 342.430771 -282.100064) (xy 342.477045 -282.123642)
			(xy 342.519061 -282.154168) (xy 342.555784 -282.190891) (xy 342.58631 -282.232907) (xy 342.609888 -282.279181)
			(xy 342.625936 -282.328574) (xy 342.634061 -282.379869) (xy 342.63457 -282.405836) (xy 342.913208 -282.405836)
			(xy 342.913668 -282.380385) (xy 342.921454 -282.330082) (xy 342.936864 -282.281568) (xy 342.959531 -282.235991)
			(xy 342.988921 -282.194431) (xy 343.024337 -282.15787) (xy 343.064942 -282.127173) (xy 343.109774 -282.103067)
			(xy 343.157773 -282.086122) (xy 343.182702 -282.08097) (xy 343.205816 -282.076652) (xy 343.409778 -281.723338)
			(xy 343.401904 -281.70124) (xy 343.393285 -281.674825) (xy 343.383958 -281.620053) (xy 343.383362 -281.592274)
			(xy 343.383362 -281.59202) (xy 343.383871 -281.566053) (xy 343.391996 -281.514758) (xy 343.408044 -281.465365)
			(xy 343.431622 -281.419091) (xy 343.462148 -281.377075) (xy 343.498871 -281.340352) (xy 343.540887 -281.309826)
			(xy 343.587161 -281.286248) (xy 343.636554 -281.2702) (xy 343.687849 -281.262075) (xy 343.739783 -281.262075)
			(xy 343.791078 -281.2702) (xy 343.840471 -281.286248) (xy 343.886745 -281.309826) (xy 343.928761 -281.340352)
			(xy 343.965484 -281.377075) (xy 343.99601 -281.419091) (xy 344.019588 -281.465365) (xy 344.035636 -281.514758)
			(xy 344.043761 -281.566053) (xy 344.04427 -281.59202) (xy 344.043793 -281.617493) (xy 344.043716 -281.617987)
			(xy 344.323671 -281.617987) (xy 344.323671 -281.566053) (xy 344.331796 -281.514758) (xy 344.347844 -281.465365)
			(xy 344.371422 -281.419091) (xy 344.401948 -281.377075) (xy 344.438671 -281.340352) (xy 344.480687 -281.309826)
			(xy 344.526961 -281.286248) (xy 344.576354 -281.2702) (xy 344.627649 -281.262075) (xy 344.679583 -281.262075)
			(xy 344.730878 -281.2702) (xy 344.780271 -281.286248) (xy 344.826545 -281.309826) (xy 344.868561 -281.340352)
			(xy 344.905284 -281.377075) (xy 344.93581 -281.419091) (xy 344.959388 -281.465365) (xy 344.975436 -281.514758)
			(xy 344.983561 -281.566053) (xy 344.98407 -281.59202) (xy 345.262962 -281.59202) (xy 345.263364 -281.566566)
			(xy 345.271154 -281.516258) (xy 345.286568 -281.46774) (xy 345.309243 -281.422161) (xy 345.33864 -281.380599)
			(xy 345.374064 -281.344038) (xy 345.414677 -281.313344) (xy 345.459517 -281.289242) (xy 345.507524 -281.272303)
			(xy 345.532456 -281.267154) (xy 345.55557 -281.262836) (xy 345.759278 -280.91003) (xy 345.751404 -280.887932)
			(xy 345.742674 -280.861341) (xy 345.733222 -280.806184) (xy 345.732608 -280.778204) (xy 345.733117 -280.752237)
			(xy 345.741242 -280.700942) (xy 345.75729 -280.651549) (xy 345.780868 -280.605275) (xy 345.811394 -280.563259)
			(xy 345.848117 -280.526536) (xy 345.890133 -280.49601) (xy 345.936407 -280.472432) (xy 345.9858 -280.456384)
			(xy 346.037095 -280.448259) (xy 346.089029 -280.448259) (xy 346.140324 -280.456384) (xy 346.189717 -280.472432)
			(xy 346.235991 -280.49601) (xy 346.278007 -280.526536) (xy 346.31473 -280.563259) (xy 346.345256 -280.605275)
			(xy 346.368834 -280.651549) (xy 346.384882 -280.700942) (xy 346.393007 -280.752237) (xy 346.393516 -280.778204)
			(xy 346.393063 -280.803657) (xy 346.392984 -280.804171) (xy 346.672917 -280.804171) (xy 346.672917 -280.752237)
			(xy 346.681042 -280.700942) (xy 346.69709 -280.651549) (xy 346.720668 -280.605275) (xy 346.751194 -280.563259)
			(xy 346.787917 -280.526536) (xy 346.829933 -280.49601) (xy 346.876207 -280.472432) (xy 346.9256 -280.456384)
			(xy 346.976895 -280.448259) (xy 347.028829 -280.448259) (xy 347.080124 -280.456384) (xy 347.129517 -280.472432)
			(xy 347.175791 -280.49601) (xy 347.217807 -280.526536) (xy 347.25453 -280.563259) (xy 347.285056 -280.605275)
			(xy 347.308634 -280.651549) (xy 347.324682 -280.700942) (xy 347.332807 -280.752237) (xy 347.333316 -280.778204)
			(xy 348.552008 -280.778204) (xy 348.552517 -280.752237) (xy 348.560642 -280.700942) (xy 348.57669 -280.651549)
			(xy 348.600268 -280.605275) (xy 348.630794 -280.563259) (xy 348.667517 -280.526536) (xy 348.709533 -280.49601)
			(xy 348.755807 -280.472432) (xy 348.8052 -280.456384) (xy 348.856495 -280.448259) (xy 348.908429 -280.448259)
			(xy 348.959724 -280.456384) (xy 349.009117 -280.472432) (xy 349.055391 -280.49601) (xy 349.097407 -280.526536)
			(xy 349.13413 -280.563259) (xy 349.164656 -280.605275) (xy 349.188234 -280.651549) (xy 349.204282 -280.700942)
			(xy 349.212407 -280.752237) (xy 349.212916 -280.778204) (xy 349.212916 -280.778458) (xy 349.21237 -280.804171)
			(xy 349.492317 -280.804171) (xy 349.492317 -280.752237) (xy 349.500442 -280.700942) (xy 349.51649 -280.651549)
			(xy 349.540068 -280.605275) (xy 349.570594 -280.563259) (xy 349.607317 -280.526536) (xy 349.649333 -280.49601)
			(xy 349.695607 -280.472432) (xy 349.745 -280.456384) (xy 349.796295 -280.448259) (xy 349.848229 -280.448259)
			(xy 349.899524 -280.456384) (xy 349.948917 -280.472432) (xy 349.995191 -280.49601) (xy 350.037207 -280.526536)
			(xy 350.07393 -280.563259) (xy 350.104456 -280.605275) (xy 350.128034 -280.651549) (xy 350.144082 -280.700942)
			(xy 350.152207 -280.752237) (xy 350.152716 -280.778204) (xy 350.152207 -280.804171) (xy 350.432371 -280.804171)
			(xy 350.432371 -280.752237) (xy 350.440496 -280.700942) (xy 350.456544 -280.651549) (xy 350.480122 -280.605275)
			(xy 350.510648 -280.563259) (xy 350.547371 -280.526536) (xy 350.589387 -280.49601) (xy 350.635661 -280.472432)
			(xy 350.685054 -280.456384) (xy 350.736349 -280.448259) (xy 350.788283 -280.448259) (xy 350.839578 -280.456384)
			(xy 350.888971 -280.472432) (xy 350.935245 -280.49601) (xy 350.977261 -280.526536) (xy 351.013984 -280.563259)
			(xy 351.04451 -280.605275) (xy 351.068088 -280.651549) (xy 351.084136 -280.700942) (xy 351.092261 -280.752237)
			(xy 351.09277 -280.778204) (xy 351.371408 -280.778204) (xy 351.371917 -280.752237) (xy 351.380042 -280.700942)
			(xy 351.39609 -280.651549) (xy 351.419668 -280.605275) (xy 351.450194 -280.563259) (xy 351.486917 -280.526536)
			(xy 351.528933 -280.49601) (xy 351.575207 -280.472432) (xy 351.6246 -280.456384) (xy 351.675895 -280.448259)
			(xy 351.727829 -280.448259) (xy 351.779124 -280.456384) (xy 351.828517 -280.472432) (xy 351.874791 -280.49601)
			(xy 351.916807 -280.526536) (xy 351.95353 -280.563259) (xy 351.984056 -280.605275) (xy 352.007634 -280.651549)
			(xy 352.023682 -280.700942) (xy 352.031807 -280.752237) (xy 352.032316 -280.778204) (xy 352.311208 -280.778204)
			(xy 352.31173 -280.752755) (xy 352.319506 -280.702454) (xy 352.334906 -280.653942) (xy 352.357565 -280.608366)
			(xy 352.386947 -280.566805) (xy 352.422356 -280.530243) (xy 352.462955 -280.499545) (xy 352.507782 -280.475437)
			(xy 352.555776 -280.458491) (xy 352.580702 -280.453338) (xy 352.603816 -280.44902) (xy 352.807778 -280.095706)
			(xy 352.799904 -280.073608) (xy 352.791292 -280.047257) (xy 352.781972 -279.992612) (xy 352.781362 -279.964896)
			(xy 352.781362 -279.964134) (xy 352.781871 -279.938167) (xy 352.789996 -279.886872) (xy 352.806044 -279.837479)
			(xy 352.829622 -279.791205) (xy 352.860148 -279.749189) (xy 352.896871 -279.712466) (xy 352.938887 -279.68194)
			(xy 352.985161 -279.658362) (xy 353.034554 -279.642314) (xy 353.085849 -279.634189) (xy 353.137783 -279.634189)
			(xy 353.189078 -279.642314) (xy 353.238471 -279.658362) (xy 353.284745 -279.68194) (xy 353.326761 -279.712466)
			(xy 353.363484 -279.749189) (xy 353.39401 -279.791205) (xy 353.417588 -279.837479) (xy 353.433636 -279.886872)
			(xy 353.441761 -279.938167) (xy 353.44227 -279.964134) (xy 353.441844 -279.989598) (xy 353.441766 -279.990101)
			(xy 353.721671 -279.990101) (xy 353.721671 -279.938167) (xy 353.729796 -279.886872) (xy 353.745844 -279.837479)
			(xy 353.769422 -279.791205) (xy 353.799948 -279.749189) (xy 353.836671 -279.712466) (xy 353.878687 -279.68194)
			(xy 353.924961 -279.658362) (xy 353.974354 -279.642314) (xy 354.025649 -279.634189) (xy 354.077583 -279.634189)
			(xy 354.128878 -279.642314) (xy 354.178271 -279.658362) (xy 354.224545 -279.68194) (xy 354.266561 -279.712466)
			(xy 354.303284 -279.749189) (xy 354.33381 -279.791205) (xy 354.357388 -279.837479) (xy 354.373436 -279.886872)
			(xy 354.381561 -279.938167) (xy 354.38207 -279.964134) (xy 354.381561 -279.990101) (xy 354.373436 -280.041396)
			(xy 354.357388 -280.090789) (xy 354.33381 -280.137063) (xy 354.303284 -280.179079) (xy 354.266561 -280.215802)
			(xy 354.224545 -280.246328) (xy 354.178271 -280.269906) (xy 354.128878 -280.285954) (xy 354.077583 -280.294079)
			(xy 354.025649 -280.294079) (xy 353.974354 -280.285954) (xy 353.924961 -280.269906) (xy 353.878687 -280.246328)
			(xy 353.836671 -280.215802) (xy 353.799948 -280.179079) (xy 353.769422 -280.137063) (xy 353.745844 -280.090789)
			(xy 353.729796 -280.041396) (xy 353.721671 -279.990101) (xy 353.441766 -279.990101) (xy 353.434039 -280.039926)
			(xy 353.418605 -280.088459) (xy 353.395905 -280.13405) (xy 353.36648 -280.175617) (xy 353.331024 -280.212177)
			(xy 353.290378 -280.242864) (xy 353.245505 -280.26695) (xy 353.197468 -280.283866) (xy 353.172522 -280.289)
			(xy 353.149408 -280.293318) (xy 352.9457 -280.646378) (xy 352.95332 -280.668476) (xy 352.962053 -280.695066)
			(xy 352.971503 -280.750224) (xy 352.972116 -280.778204) (xy 352.971607 -280.804171) (xy 352.963482 -280.855466)
			(xy 352.947434 -280.904859) (xy 352.923856 -280.951133) (xy 352.89333 -280.993149) (xy 352.856607 -281.029872)
			(xy 352.814591 -281.060398) (xy 352.768317 -281.083976) (xy 352.718924 -281.100024) (xy 352.667629 -281.108149)
			(xy 352.615695 -281.108149) (xy 352.5644 -281.100024) (xy 352.515007 -281.083976) (xy 352.468733 -281.060398)
			(xy 352.426717 -281.029872) (xy 352.389994 -280.993149) (xy 352.359468 -280.951133) (xy 352.33589 -280.904859)
			(xy 352.319842 -280.855466) (xy 352.311717 -280.804171) (xy 352.311208 -280.778204) (xy 352.032316 -280.778204)
			(xy 352.032316 -280.778458) (xy 352.031726 -280.806239) (xy 352.022414 -280.861015) (xy 352.013774 -280.887424)
			(xy 352.0059 -280.909522) (xy 352.209862 -281.262836) (xy 352.232976 -281.267154) (xy 352.257901 -281.272307)
			(xy 352.305884 -281.289276) (xy 352.3507 -281.313397) (xy 352.391292 -281.344099) (xy 352.426699 -281.380659)
			(xy 352.456087 -281.422213) (xy 352.478761 -281.467778) (xy 352.494185 -281.51628) (xy 352.501996 -281.566572)
			(xy 352.50247 -281.59202) (xy 352.501961 -281.617987) (xy 352.781871 -281.617987) (xy 352.781871 -281.566053)
			(xy 352.789996 -281.514758) (xy 352.806044 -281.465365) (xy 352.829622 -281.419091) (xy 352.860148 -281.377075)
			(xy 352.896871 -281.340352) (xy 352.938887 -281.309826) (xy 352.985161 -281.286248) (xy 353.034554 -281.2702)
			(xy 353.085849 -281.262075) (xy 353.137783 -281.262075) (xy 353.189078 -281.2702) (xy 353.238471 -281.286248)
			(xy 353.284745 -281.309826) (xy 353.326761 -281.340352) (xy 353.363484 -281.377075) (xy 353.39401 -281.419091)
			(xy 353.417588 -281.465365) (xy 353.433636 -281.514758) (xy 353.441761 -281.566053) (xy 353.44227 -281.59202)
			(xy 353.441761 -281.617987) (xy 353.433636 -281.669282) (xy 353.417588 -281.718675) (xy 353.39401 -281.764949)
			(xy 353.363484 -281.806965) (xy 353.326761 -281.843688) (xy 353.284745 -281.874214) (xy 353.238471 -281.897792)
			(xy 353.189078 -281.91384) (xy 353.137783 -281.921965) (xy 353.085849 -281.921965) (xy 353.034554 -281.91384)
			(xy 352.985161 -281.897792) (xy 352.938887 -281.874214) (xy 352.896871 -281.843688) (xy 352.860148 -281.806965)
			(xy 352.829622 -281.764949) (xy 352.806044 -281.718675) (xy 352.789996 -281.669282) (xy 352.781871 -281.617987)
			(xy 352.501961 -281.617987) (xy 352.493836 -281.669282) (xy 352.477788 -281.718675) (xy 352.45421 -281.764949)
			(xy 352.423684 -281.806965) (xy 352.386961 -281.843688) (xy 352.344945 -281.874214) (xy 352.298671 -281.897792)
			(xy 352.249278 -281.91384) (xy 352.197983 -281.921965) (xy 352.146049 -281.921965) (xy 352.094754 -281.91384)
			(xy 352.045361 -281.897792) (xy 351.999087 -281.874214) (xy 351.957071 -281.843688) (xy 351.920348 -281.806965)
			(xy 351.889822 -281.764949) (xy 351.866244 -281.718675) (xy 351.850196 -281.669282) (xy 351.842071 -281.617987)
			(xy 351.841562 -281.59202) (xy 351.842116 -281.564034) (xy 351.851565 -281.508866) (xy 351.860358 -281.482292)
			(xy 351.867978 -281.460194) (xy 351.66427 -281.107388) (xy 351.64141 -281.10307) (xy 351.61646 -281.097909)
			(xy 351.568396 -281.08102) (xy 351.523494 -281.056954) (xy 351.482818 -281.02628) (xy 351.447333 -280.989726)
			(xy 351.417879 -280.948158) (xy 351.395155 -280.902562) (xy 351.3797 -280.854018) (xy 351.371879 -280.803677)
			(xy 351.371408 -280.778204) (xy 351.09277 -280.778204) (xy 351.092261 -280.804171) (xy 351.084136 -280.855466)
			(xy 351.068088 -280.904859) (xy 351.04451 -280.951133) (xy 351.013984 -280.993149) (xy 350.977261 -281.029872)
			(xy 350.935245 -281.060398) (xy 350.888971 -281.083976) (xy 350.839578 -281.100024) (xy 350.788283 -281.108149)
			(xy 350.736349 -281.108149) (xy 350.685054 -281.100024) (xy 350.635661 -281.083976) (xy 350.589387 -281.060398)
			(xy 350.547371 -281.029872) (xy 350.510648 -280.993149) (xy 350.480122 -280.951133) (xy 350.456544 -280.904859)
			(xy 350.440496 -280.855466) (xy 350.432371 -280.804171) (xy 350.152207 -280.804171) (xy 350.144082 -280.855466)
			(xy 350.128034 -280.904859) (xy 350.104456 -280.951133) (xy 350.07393 -280.993149) (xy 350.037207 -281.029872)
			(xy 349.995191 -281.060398) (xy 349.948917 -281.083976) (xy 349.899524 -281.100024) (xy 349.848229 -281.108149)
			(xy 349.796295 -281.108149) (xy 349.745 -281.100024) (xy 349.695607 -281.083976) (xy 349.649333 -281.060398)
			(xy 349.607317 -281.029872) (xy 349.570594 -280.993149) (xy 349.540068 -280.951133) (xy 349.51649 -280.904859)
			(xy 349.500442 -280.855466) (xy 349.492317 -280.804171) (xy 349.21237 -280.804171) (xy 349.212326 -280.806239)
			(xy 349.203014 -280.861015) (xy 349.194374 -280.887424) (xy 349.1865 -280.909522) (xy 349.390462 -281.262836)
			(xy 349.413576 -281.267154) (xy 349.438501 -281.272307) (xy 349.486484 -281.289276) (xy 349.5313 -281.313397)
			(xy 349.571892 -281.344099) (xy 349.607299 -281.380659) (xy 349.636687 -281.422213) (xy 349.659361 -281.467778)
			(xy 349.674785 -281.51628) (xy 349.682596 -281.566572) (xy 349.68307 -281.59202) (xy 349.682561 -281.617987)
			(xy 349.674436 -281.669282) (xy 349.658388 -281.718675) (xy 349.63481 -281.764949) (xy 349.604284 -281.806965)
			(xy 349.567561 -281.843688) (xy 349.525545 -281.874214) (xy 349.479271 -281.897792) (xy 349.429878 -281.91384)
			(xy 349.378583 -281.921965) (xy 349.326649 -281.921965) (xy 349.275354 -281.91384) (xy 349.225961 -281.897792)
			(xy 349.179687 -281.874214) (xy 349.137671 -281.843688) (xy 349.100948 -281.806965) (xy 349.070422 -281.764949)
			(xy 349.046844 -281.718675) (xy 349.030796 -281.669282) (xy 349.022671 -281.617987) (xy 349.022162 -281.59202)
			(xy 349.022716 -281.564034) (xy 349.032165 -281.508866) (xy 349.040958 -281.482292) (xy 349.048578 -281.460194)
			(xy 348.84487 -281.107388) (xy 348.82201 -281.10307) (xy 348.79706 -281.097909) (xy 348.748996 -281.08102)
			(xy 348.704094 -281.056954) (xy 348.663418 -281.02628) (xy 348.627933 -280.989726) (xy 348.598479 -280.948158)
			(xy 348.575755 -280.902562) (xy 348.5603 -280.854018) (xy 348.552479 -280.803677) (xy 348.552008 -280.778204)
			(xy 347.333316 -280.778204) (xy 347.332807 -280.804171) (xy 347.324682 -280.855466) (xy 347.308634 -280.904859)
			(xy 347.285056 -280.951133) (xy 347.25453 -280.993149) (xy 347.217807 -281.029872) (xy 347.175791 -281.060398)
			(xy 347.129517 -281.083976) (xy 347.080124 -281.100024) (xy 347.028829 -281.108149) (xy 346.976895 -281.108149)
			(xy 346.9256 -281.100024) (xy 346.876207 -281.083976) (xy 346.829933 -281.060398) (xy 346.787917 -281.029872)
			(xy 346.751194 -280.993149) (xy 346.720668 -280.951133) (xy 346.69709 -280.904859) (xy 346.681042 -280.855466)
			(xy 346.672917 -280.804171) (xy 346.392984 -280.804171) (xy 346.385283 -280.853963) (xy 346.369878 -280.902481)
			(xy 346.347212 -280.948061) (xy 346.317821 -280.989624) (xy 346.282402 -281.026186) (xy 346.241794 -281.056881)
			(xy 346.196957 -281.080983) (xy 346.148953 -281.097921) (xy 346.124022 -281.10307) (xy 346.101162 -281.107388)
			(xy 345.897454 -281.460194) (xy 345.905074 -281.482292) (xy 345.913809 -281.508881) (xy 345.923258 -281.56404)
			(xy 345.92387 -281.59202) (xy 345.923361 -281.617987) (xy 346.203271 -281.617987) (xy 346.203271 -281.566053)
			(xy 346.211396 -281.514758) (xy 346.227444 -281.465365) (xy 346.251022 -281.419091) (xy 346.281548 -281.377075)
			(xy 346.318271 -281.340352) (xy 346.360287 -281.309826) (xy 346.406561 -281.286248) (xy 346.455954 -281.2702)
			(xy 346.507249 -281.262075) (xy 346.559183 -281.262075) (xy 346.610478 -281.2702) (xy 346.659871 -281.286248)
			(xy 346.706145 -281.309826) (xy 346.748161 -281.340352) (xy 346.784884 -281.377075) (xy 346.81541 -281.419091)
			(xy 346.838988 -281.465365) (xy 346.855036 -281.514758) (xy 346.863161 -281.566053) (xy 346.86367 -281.59202)
			(xy 346.863161 -281.617969) (xy 347.143049 -281.617969) (xy 347.143049 -281.566031) (xy 347.151174 -281.514734)
			(xy 347.167224 -281.465339) (xy 347.190803 -281.419063) (xy 347.221332 -281.377046) (xy 347.258058 -281.340322)
			(xy 347.300077 -281.309795) (xy 347.346354 -281.286218) (xy 347.395749 -281.27017) (xy 347.447047 -281.262048)
			(xy 347.473016 -281.261566) (xy 347.498635 -281.262103) (xy 347.549258 -281.270019) (xy 347.598056 -281.285644)
			(xy 347.643862 -281.308605) (xy 347.685581 -281.338352) (xy 347.722216 -281.374175) (xy 347.737938 -281.394408)
			(xy 348.147894 -281.394408) (xy 348.163638 -281.374187) (xy 348.20025 -281.338333) (xy 348.241958 -281.308561)
			(xy 348.287762 -281.285585) (xy 348.336564 -281.269955) (xy 348.387194 -281.262047) (xy 348.412816 -281.261566)
			(xy 348.438784 -281.262037) (xy 348.49008 -281.270163) (xy 348.539474 -281.286214) (xy 348.585748 -281.309794)
			(xy 348.627764 -281.340323) (xy 348.664488 -281.377048) (xy 348.695014 -281.419066) (xy 348.718592 -281.465341)
			(xy 348.73464 -281.514735) (xy 348.742765 -281.566032) (xy 348.742765 -281.617968) (xy 348.73464 -281.669265)
			(xy 348.718592 -281.718659) (xy 348.695014 -281.764934) (xy 348.664488 -281.806952) (xy 348.627764 -281.843677)
			(xy 348.585748 -281.874206) (xy 348.539474 -281.897786) (xy 348.49008 -281.913837) (xy 348.438784 -281.921963)
			(xy 348.412816 -281.922474) (xy 348.387194 -281.92201) (xy 348.336566 -281.914082) (xy 348.287766 -281.898444)
			(xy 348.24196 -281.875469) (xy 348.200243 -281.845708) (xy 348.163613 -281.809872) (xy 348.147894 -281.789632)
			(xy 347.737938 -281.789632) (xy 347.722245 -281.809894) (xy 347.685621 -281.845744) (xy 347.643902 -281.87551)
			(xy 347.598088 -281.898478) (xy 347.549278 -281.914099) (xy 347.498641 -281.921998) (xy 347.473016 -281.922474)
			(xy 347.447047 -281.921952) (xy 347.395749 -281.91383) (xy 347.346354 -281.897782) (xy 347.300077 -281.874205)
			(xy 347.258058 -281.843678) (xy 347.221332 -281.806954) (xy 347.190803 -281.764937) (xy 347.167224 -281.718661)
			(xy 347.151174 -281.669266) (xy 347.143049 -281.617969) (xy 346.863161 -281.617969) (xy 346.863161 -281.617987)
			(xy 346.855036 -281.669282) (xy 346.838988 -281.718675) (xy 346.81541 -281.764949) (xy 346.784884 -281.806965)
			(xy 346.748161 -281.843688) (xy 346.706145 -281.874214) (xy 346.659871 -281.897792) (xy 346.610478 -281.91384)
			(xy 346.559183 -281.921965) (xy 346.507249 -281.921965) (xy 346.455954 -281.91384) (xy 346.406561 -281.897792)
			(xy 346.360287 -281.874214) (xy 346.318271 -281.843688) (xy 346.281548 -281.806965) (xy 346.251022 -281.764949)
			(xy 346.227444 -281.718675) (xy 346.211396 -281.669282) (xy 346.203271 -281.617987) (xy 345.923361 -281.617987)
			(xy 345.915236 -281.669282) (xy 345.899188 -281.718675) (xy 345.87561 -281.764949) (xy 345.845084 -281.806965)
			(xy 345.808361 -281.843688) (xy 345.766345 -281.874214) (xy 345.720071 -281.897792) (xy 345.670678 -281.91384)
			(xy 345.619383 -281.921965) (xy 345.567449 -281.921965) (xy 345.516154 -281.91384) (xy 345.466761 -281.897792)
			(xy 345.420487 -281.874214) (xy 345.378471 -281.843688) (xy 345.341748 -281.806965) (xy 345.311222 -281.764949)
			(xy 345.287644 -281.718675) (xy 345.271596 -281.669282) (xy 345.263471 -281.617987) (xy 345.262962 -281.59202)
			(xy 344.98407 -281.59202) (xy 344.983561 -281.617987) (xy 344.975436 -281.669282) (xy 344.959388 -281.718675)
			(xy 344.93581 -281.764949) (xy 344.905284 -281.806965) (xy 344.868561 -281.843688) (xy 344.826545 -281.874214)
			(xy 344.780271 -281.897792) (xy 344.730878 -281.91384) (xy 344.679583 -281.921965) (xy 344.627649 -281.921965)
			(xy 344.576354 -281.91384) (xy 344.526961 -281.897792) (xy 344.480687 -281.874214) (xy 344.438671 -281.843688)
			(xy 344.401948 -281.806965) (xy 344.371422 -281.764949) (xy 344.347844 -281.718675) (xy 344.331796 -281.669282)
			(xy 344.323671 -281.617987) (xy 344.043716 -281.617987) (xy 344.035971 -281.667836) (xy 344.020516 -281.716381)
			(xy 343.997793 -281.76198) (xy 343.968342 -281.803551) (xy 343.932859 -281.840109) (xy 343.892187 -281.870789)
			(xy 343.847287 -281.894864) (xy 343.799225 -281.911762) (xy 343.774268 -281.916886) (xy 343.751408 -281.921204)
			(xy 343.5477 -282.27401) (xy 343.55532 -282.296108) (xy 343.56406 -282.322695) (xy 343.573506 -282.377855)
			(xy 343.574116 -282.405836) (xy 343.853008 -282.405836) (xy 343.853517 -282.379869) (xy 343.861642 -282.328574)
			(xy 343.87769 -282.279181) (xy 343.901268 -282.232907) (xy 343.931794 -282.190891) (xy 343.968517 -282.154168)
			(xy 344.010533 -282.123642) (xy 344.056807 -282.100064) (xy 344.1062 -282.084016) (xy 344.157495 -282.075891)
			(xy 344.209429 -282.075891) (xy 344.260724 -282.084016) (xy 344.310117 -282.100064) (xy 344.356391 -282.123642)
			(xy 344.398407 -282.154168) (xy 344.43513 -282.190891) (xy 344.465656 -282.232907) (xy 344.489234 -282.279181)
			(xy 344.505282 -282.328574) (xy 344.513407 -282.379869) (xy 344.513916 -282.405836) (xy 344.513916 -282.406598)
			(xy 344.513385 -282.431762) (xy 344.793391 -282.431762) (xy 344.793391 -282.379838) (xy 344.801513 -282.328552)
			(xy 344.817558 -282.279168) (xy 344.84113 -282.232901) (xy 344.871648 -282.190892) (xy 344.908363 -282.154173)
			(xy 344.950369 -282.12365) (xy 344.996633 -282.100072) (xy 345.046015 -282.084022) (xy 345.0973 -282.075894)
			(xy 345.123262 -282.075382) (xy 345.148883 -282.07588) (xy 345.199508 -282.083803) (xy 345.248307 -282.099436)
			(xy 345.294113 -282.122404) (xy 345.335831 -282.152158) (xy 345.372463 -282.187987) (xy 345.388184 -282.208224)
			(xy 345.79814 -282.208224) (xy 345.813834 -282.187963) (xy 345.850459 -282.152115) (xy 345.892178 -282.122351)
			(xy 345.937992 -282.099382) (xy 345.986802 -282.08376) (xy 346.037438 -282.075859) (xy 346.063062 -282.075382)
			(xy 346.089036 -282.07579) (xy 346.140345 -282.083911) (xy 346.189752 -282.09996) (xy 346.23604 -282.12354)
			(xy 346.278069 -282.154071) (xy 346.314804 -282.190802) (xy 346.34534 -282.232827) (xy 346.368926 -282.279112)
			(xy 346.38498 -282.328518) (xy 346.393107 -282.379826) (xy 346.393107 -282.431774) (xy 346.393102 -282.431803)
			(xy 346.672917 -282.431803) (xy 346.672917 -282.379869) (xy 346.681042 -282.328574) (xy 346.69709 -282.279181)
			(xy 346.720668 -282.232907) (xy 346.751194 -282.190891) (xy 346.787917 -282.154168) (xy 346.829933 -282.123642)
			(xy 346.876207 -282.100064) (xy 346.9256 -282.084016) (xy 346.976895 -282.075891) (xy 347.028829 -282.075891)
			(xy 347.080124 -282.084016) (xy 347.129517 -282.100064) (xy 347.175791 -282.123642) (xy 347.217807 -282.154168)
			(xy 347.25453 -282.190891) (xy 347.285056 -282.232907) (xy 347.308634 -282.279181) (xy 347.324682 -282.328574)
			(xy 347.332807 -282.379869) (xy 347.333316 -282.405836) (xy 347.332807 -282.431803) (xy 347.324682 -282.483098)
			(xy 347.308634 -282.532491) (xy 347.285056 -282.578765) (xy 347.25453 -282.620781) (xy 347.217807 -282.657504)
			(xy 347.175791 -282.68803) (xy 347.129517 -282.711608) (xy 347.080124 -282.727656) (xy 347.028829 -282.735781)
			(xy 346.976895 -282.735781) (xy 346.9256 -282.727656) (xy 346.876207 -282.711608) (xy 346.829933 -282.68803)
			(xy 346.787917 -282.657504) (xy 346.751194 -282.620781) (xy 346.720668 -282.578765) (xy 346.69709 -282.532491)
			(xy 346.681042 -282.483098) (xy 346.672917 -282.431803) (xy 346.393102 -282.431803) (xy 346.38498 -282.483082)
			(xy 346.368926 -282.532488) (xy 346.34534 -282.578773) (xy 346.314804 -282.620798) (xy 346.278069 -282.657529)
			(xy 346.23604 -282.68806) (xy 346.189752 -282.71164) (xy 346.140345 -282.727689) (xy 346.089036 -282.73581)
			(xy 346.063062 -282.73629) (xy 346.037442 -282.735786) (xy 345.986816 -282.727866) (xy 345.938017 -282.712235)
			(xy 345.89221 -282.689268) (xy 345.850493 -282.659514) (xy 345.81386 -282.623685) (xy 345.79814 -282.603448)
			(xy 345.388184 -282.603448) (xy 345.372468 -282.623692) (xy 345.335849 -282.659541) (xy 345.294134 -282.689309)
			(xy 345.248325 -282.712281) (xy 345.199519 -282.727906) (xy 345.148885 -282.735811) (xy 345.123262 -282.73629)
			(xy 345.0973 -282.735706) (xy 345.046015 -282.727578) (xy 344.996633 -282.711528) (xy 344.950369 -282.68795)
			(xy 344.908363 -282.657427) (xy 344.871648 -282.620708) (xy 344.84113 -282.578699) (xy 344.817558 -282.532432)
			(xy 344.801513 -282.483048) (xy 344.793391 -282.431762) (xy 344.513385 -282.431762) (xy 344.513331 -282.434316)
			(xy 344.504005 -282.488963) (xy 344.495374 -282.51531) (xy 344.4875 -282.537408) (xy 344.691462 -282.890722)
			(xy 344.714576 -282.89504) (xy 344.739497 -282.900206) (xy 344.78748 -282.917174) (xy 344.832295 -282.941294)
			(xy 344.872886 -282.971995) (xy 344.908294 -283.008553) (xy 344.937682 -283.050104) (xy 344.960357 -283.095668)
			(xy 344.975782 -283.144168) (xy 344.983595 -283.194459) (xy 344.98407 -283.219906) (xy 344.983561 -283.245873)
			(xy 345.263217 -283.245873) (xy 345.263217 -283.193939) (xy 345.271342 -283.142644) (xy 345.28739 -283.093251)
			(xy 345.310968 -283.046977) (xy 345.341494 -283.004961) (xy 345.378217 -282.968238) (xy 345.420233 -282.937712)
			(xy 345.466507 -282.914134) (xy 345.5159 -282.898086) (xy 345.567195 -282.889961) (xy 345.619129 -282.889961)
			(xy 345.670424 -282.898086) (xy 345.719817 -282.914134) (xy 345.766091 -282.937712) (xy 345.808107 -282.968238)
			(xy 345.84483 -283.004961) (xy 345.875356 -283.046977) (xy 345.898934 -283.093251) (xy 345.914982 -283.142644)
			(xy 345.923107 -283.193939) (xy 345.923616 -283.219906) (xy 345.923107 -283.245873) (xy 346.203017 -283.245873)
			(xy 346.203017 -283.193939) (xy 346.211142 -283.142644) (xy 346.22719 -283.093251) (xy 346.250768 -283.046977)
			(xy 346.281294 -283.004961) (xy 346.318017 -282.968238) (xy 346.360033 -282.937712) (xy 346.406307 -282.914134)
			(xy 346.4557 -282.898086) (xy 346.506995 -282.889961) (xy 346.558929 -282.889961) (xy 346.610224 -282.898086)
			(xy 346.659617 -282.914134) (xy 346.705891 -282.937712) (xy 346.747907 -282.968238) (xy 346.78463 -283.004961)
			(xy 346.815156 -283.046977) (xy 346.838734 -283.093251) (xy 346.854782 -283.142644) (xy 346.862907 -283.193939)
			(xy 346.863416 -283.219906) (xy 347.142562 -283.219906) (xy 347.143042 -283.194455) (xy 347.15082 -283.14415)
			(xy 347.166222 -283.095634) (xy 347.188885 -283.050055) (xy 347.218272 -283.008493) (xy 347.253688 -282.971931)
			(xy 347.294293 -282.941234) (xy 347.339126 -282.917131) (xy 347.387127 -282.90019) (xy 347.412056 -282.89504)
			(xy 347.43517 -282.890722) (xy 347.638878 -282.537916) (xy 347.631004 -282.515818) (xy 347.622271 -282.489228)
			(xy 347.61282 -282.43407) (xy 347.612208 -282.40609) (xy 347.612208 -282.405836) (xy 347.612717 -282.379869)
			(xy 347.620842 -282.328574) (xy 347.63689 -282.279181) (xy 347.660468 -282.232907) (xy 347.690994 -282.190891)
			(xy 347.727717 -282.154168) (xy 347.769733 -282.123642) (xy 347.816007 -282.100064) (xy 347.8654 -282.084016)
			(xy 347.916695 -282.075891) (xy 347.968629 -282.075891) (xy 348.019924 -282.084016) (xy 348.069317 -282.100064)
			(xy 348.115591 -282.123642) (xy 348.157607 -282.154168) (xy 348.19433 -282.190891) (xy 348.224856 -282.232907)
			(xy 348.248434 -282.279181) (xy 348.264482 -282.328574) (xy 348.272607 -282.379869) (xy 348.273116 -282.405836)
			(xy 348.272607 -282.431268) (xy 348.272524 -282.431803) (xy 348.552517 -282.431803) (xy 348.552517 -282.379869)
			(xy 348.560642 -282.328574) (xy 348.57669 -282.279181) (xy 348.600268 -282.232907) (xy 348.630794 -282.190891)
			(xy 348.667517 -282.154168) (xy 348.709533 -282.123642) (xy 348.755807 -282.100064) (xy 348.8052 -282.084016)
			(xy 348.856495 -282.075891) (xy 348.908429 -282.075891) (xy 348.959724 -282.084016) (xy 349.009117 -282.100064)
			(xy 349.055391 -282.123642) (xy 349.097407 -282.154168) (xy 349.13413 -282.190891) (xy 349.164656 -282.232907)
			(xy 349.188234 -282.279181) (xy 349.204282 -282.328574) (xy 349.212407 -282.379869) (xy 349.212916 -282.405836)
			(xy 349.491808 -282.405836) (xy 349.492268 -282.380385) (xy 349.500054 -282.330082) (xy 349.515464 -282.281568)
			(xy 349.538131 -282.235991) (xy 349.567521 -282.194431) (xy 349.602937 -282.15787) (xy 349.643542 -282.127173)
			(xy 349.688374 -282.103067) (xy 349.736373 -282.086122) (xy 349.761302 -282.08097) (xy 349.784416 -282.076652)
			(xy 349.988378 -281.723338) (xy 349.980504 -281.70124) (xy 349.971885 -281.674825) (xy 349.962558 -281.620053)
			(xy 349.961962 -281.592274) (xy 349.961962 -281.59202) (xy 349.962471 -281.566053) (xy 349.970596 -281.514758)
			(xy 349.986644 -281.465365) (xy 350.010222 -281.419091) (xy 350.040748 -281.377075) (xy 350.077471 -281.340352)
			(xy 350.119487 -281.309826) (xy 350.165761 -281.286248) (xy 350.215154 -281.2702) (xy 350.266449 -281.262075)
			(xy 350.318383 -281.262075) (xy 350.369678 -281.2702) (xy 350.419071 -281.286248) (xy 350.465345 -281.309826)
			(xy 350.507361 -281.340352) (xy 350.544084 -281.377075) (xy 350.57461 -281.419091) (xy 350.598188 -281.465365)
			(xy 350.614236 -281.514758) (xy 350.622361 -281.566053) (xy 350.62287 -281.59202) (xy 350.622393 -281.617493)
			(xy 350.622316 -281.617987) (xy 350.902017 -281.617987) (xy 350.902017 -281.566053) (xy 350.910142 -281.514758)
			(xy 350.92619 -281.465365) (xy 350.949768 -281.419091) (xy 350.980294 -281.377075) (xy 351.017017 -281.340352)
			(xy 351.059033 -281.309826) (xy 351.105307 -281.286248) (xy 351.1547 -281.2702) (xy 351.205995 -281.262075)
			(xy 351.257929 -281.262075) (xy 351.309224 -281.2702) (xy 351.358617 -281.286248) (xy 351.404891 -281.309826)
			(xy 351.446907 -281.340352) (xy 351.48363 -281.377075) (xy 351.514156 -281.419091) (xy 351.537734 -281.465365)
			(xy 351.553782 -281.514758) (xy 351.561907 -281.566053) (xy 351.562416 -281.59202) (xy 351.561907 -281.617987)
			(xy 351.553782 -281.669282) (xy 351.537734 -281.718675) (xy 351.514156 -281.764949) (xy 351.48363 -281.806965)
			(xy 351.446907 -281.843688) (xy 351.404891 -281.874214) (xy 351.358617 -281.897792) (xy 351.309224 -281.91384)
			(xy 351.257929 -281.921965) (xy 351.205995 -281.921965) (xy 351.1547 -281.91384) (xy 351.105307 -281.897792)
			(xy 351.059033 -281.874214) (xy 351.017017 -281.843688) (xy 350.980294 -281.806965) (xy 350.949768 -281.764949)
			(xy 350.92619 -281.718675) (xy 350.910142 -281.669282) (xy 350.902017 -281.617987) (xy 350.622316 -281.617987)
			(xy 350.614571 -281.667836) (xy 350.599116 -281.716381) (xy 350.576393 -281.76198) (xy 350.546942 -281.803551)
			(xy 350.511459 -281.840109) (xy 350.470787 -281.870789) (xy 350.425887 -281.894864) (xy 350.377825 -281.911762)
			(xy 350.352868 -281.916886) (xy 350.330008 -281.921204) (xy 350.1263 -282.27401) (xy 350.13392 -282.296108)
			(xy 350.14266 -282.322695) (xy 350.152106 -282.377855) (xy 350.152716 -282.405836) (xy 350.152207 -282.431803)
			(xy 350.432371 -282.431803) (xy 350.432371 -282.379869) (xy 350.440496 -282.328574) (xy 350.456544 -282.279181)
			(xy 350.480122 -282.232907) (xy 350.510648 -282.190891) (xy 350.547371 -282.154168) (xy 350.589387 -282.123642)
			(xy 350.635661 -282.100064) (xy 350.685054 -282.084016) (xy 350.736349 -282.075891) (xy 350.788283 -282.075891)
			(xy 350.839578 -282.084016) (xy 350.888971 -282.100064) (xy 350.935245 -282.123642) (xy 350.977261 -282.154168)
			(xy 351.013984 -282.190891) (xy 351.04451 -282.232907) (xy 351.068088 -282.279181) (xy 351.084136 -282.328574)
			(xy 351.092261 -282.379869) (xy 351.09277 -282.405836) (xy 351.092261 -282.431803) (xy 351.084136 -282.483098)
			(xy 351.068088 -282.532491) (xy 351.04451 -282.578765) (xy 351.013984 -282.620781) (xy 350.977261 -282.657504)
			(xy 350.935245 -282.68803) (xy 350.888971 -282.711608) (xy 350.839578 -282.727656) (xy 350.788283 -282.735781)
			(xy 350.736349 -282.735781) (xy 350.685054 -282.727656) (xy 350.635661 -282.711608) (xy 350.589387 -282.68803)
			(xy 350.547371 -282.657504) (xy 350.510648 -282.620781) (xy 350.480122 -282.578765) (xy 350.456544 -282.532491)
			(xy 350.440496 -282.483098) (xy 350.432371 -282.431803) (xy 350.152207 -282.431803) (xy 350.144082 -282.483098)
			(xy 350.128034 -282.532491) (xy 350.104456 -282.578765) (xy 350.07393 -282.620781) (xy 350.037207 -282.657504)
			(xy 349.995191 -282.68803) (xy 349.948917 -282.711608) (xy 349.899524 -282.727656) (xy 349.848229 -282.735781)
			(xy 349.796295 -282.735781) (xy 349.745 -282.727656) (xy 349.695607 -282.711608) (xy 349.649333 -282.68803)
			(xy 349.607317 -282.657504) (xy 349.570594 -282.620781) (xy 349.540068 -282.578765) (xy 349.51649 -282.532491)
			(xy 349.500442 -282.483098) (xy 349.492317 -282.431803) (xy 349.491808 -282.405836) (xy 349.212916 -282.405836)
			(xy 349.212407 -282.431803) (xy 349.204282 -282.483098) (xy 349.188234 -282.532491) (xy 349.164656 -282.578765)
			(xy 349.13413 -282.620781) (xy 349.097407 -282.657504) (xy 349.055391 -282.68803) (xy 349.009117 -282.711608)
			(xy 348.959724 -282.727656) (xy 348.908429 -282.735781) (xy 348.856495 -282.735781) (xy 348.8052 -282.727656)
			(xy 348.755807 -282.711608) (xy 348.709533 -282.68803) (xy 348.667517 -282.657504) (xy 348.630794 -282.620781)
			(xy 348.600268 -282.578765) (xy 348.57669 -282.532491) (xy 348.560642 -282.483098) (xy 348.552517 -282.431803)
			(xy 348.272524 -282.431803) (xy 348.2648 -282.481529) (xy 348.249392 -282.530003) (xy 348.226744 -282.575547)
			(xy 348.197392 -282.617088) (xy 348.162026 -282.653645) (xy 348.121482 -282.684358) (xy 348.076713 -282.708503)
			(xy 348.028777 -282.72551) (xy 348.003876 -282.730702) (xy 347.980762 -282.73502) (xy 347.777054 -283.08808)
			(xy 347.784674 -283.110178) (xy 347.793406 -283.136768) (xy 347.802857 -283.191926) (xy 347.80347 -283.219906)
			(xy 347.802961 -283.245873) (xy 348.082617 -283.245873) (xy 348.082617 -283.193939) (xy 348.090742 -283.142644)
			(xy 348.10679 -283.093251) (xy 348.130368 -283.046977) (xy 348.160894 -283.004961) (xy 348.197617 -282.968238)
			(xy 348.239633 -282.937712) (xy 348.285907 -282.914134) (xy 348.3353 -282.898086) (xy 348.386595 -282.889961)
			(xy 348.438529 -282.889961) (xy 348.489824 -282.898086) (xy 348.539217 -282.914134) (xy 348.585491 -282.937712)
			(xy 348.627507 -282.968238) (xy 348.66423 -283.004961) (xy 348.694756 -283.046977) (xy 348.718334 -283.093251)
			(xy 348.734382 -283.142644) (xy 348.742507 -283.193939) (xy 348.743016 -283.219906) (xy 348.742507 -283.24587)
			(xy 349.022635 -283.24587) (xy 349.022635 -283.19393) (xy 349.03076 -283.142631) (xy 349.046811 -283.093234)
			(xy 349.070391 -283.046956) (xy 349.100921 -283.004937) (xy 349.137649 -282.968211) (xy 349.179669 -282.937683)
			(xy 349.225948 -282.914105) (xy 349.275346 -282.898056) (xy 349.326646 -282.889934) (xy 349.352616 -282.889452)
			(xy 349.378253 -282.889902) (xy 349.428912 -282.897831) (xy 349.477735 -282.913495) (xy 349.523551 -282.936519)
			(xy 349.565256 -282.966348) (xy 349.601849 -283.002266) (xy 349.617538 -283.022548) (xy 350.027494 -283.022548)
			(xy 350.043165 -283.002253) (xy 350.079766 -282.966346) (xy 350.121478 -282.936527) (xy 350.167296 -282.913513)
			(xy 350.216121 -282.897857) (xy 350.266779 -282.889935) (xy 350.292416 -282.889452) (xy 350.318383 -282.88995)
			(xy 350.369677 -282.898077) (xy 350.419068 -282.914127) (xy 350.465341 -282.937706) (xy 350.507355 -282.968233)
			(xy 350.544077 -283.004957) (xy 350.574602 -283.046973) (xy 350.598179 -283.093247) (xy 350.614227 -283.142639)
			(xy 350.622351 -283.193933) (xy 350.622351 -283.245867) (xy 350.62235 -283.245873) (xy 350.902017 -283.245873)
			(xy 350.902017 -283.193939) (xy 350.910142 -283.142644) (xy 350.92619 -283.093251) (xy 350.949768 -283.046977)
			(xy 350.980294 -283.004961) (xy 351.017017 -282.968238) (xy 351.059033 -282.937712) (xy 351.105307 -282.914134)
			(xy 351.1547 -282.898086) (xy 351.205995 -282.889961) (xy 351.257929 -282.889961) (xy 351.309224 -282.898086)
			(xy 351.358617 -282.914134) (xy 351.404891 -282.937712) (xy 351.446907 -282.968238) (xy 351.48363 -283.004961)
			(xy 351.514156 -283.046977) (xy 351.537734 -283.093251) (xy 351.553782 -283.142644) (xy 351.561907 -283.193939)
			(xy 351.562416 -283.219906) (xy 351.561907 -283.245873) (xy 351.841817 -283.245873) (xy 351.841817 -283.193939)
			(xy 351.849942 -283.142644) (xy 351.86599 -283.093251) (xy 351.889568 -283.046977) (xy 351.920094 -283.004961)
			(xy 351.956817 -282.968238) (xy 351.998833 -282.937712) (xy 352.045107 -282.914134) (xy 352.0945 -282.898086)
			(xy 352.145795 -282.889961) (xy 352.197729 -282.889961) (xy 352.249024 -282.898086) (xy 352.298417 -282.914134)
			(xy 352.344691 -282.937712) (xy 352.386707 -282.968238) (xy 352.42343 -283.004961) (xy 352.453956 -283.046977)
			(xy 352.477534 -283.093251) (xy 352.493582 -283.142644) (xy 352.501707 -283.193939) (xy 352.502216 -283.219906)
			(xy 352.501707 -283.245873) (xy 352.493582 -283.297168) (xy 352.477534 -283.346561) (xy 352.453956 -283.392835)
			(xy 352.42343 -283.434851) (xy 352.386707 -283.471574) (xy 352.344691 -283.5021) (xy 352.298417 -283.525678)
			(xy 352.249024 -283.541726) (xy 352.197729 -283.549851) (xy 352.145795 -283.549851) (xy 352.0945 -283.541726)
			(xy 352.045107 -283.525678) (xy 351.998833 -283.5021) (xy 351.956817 -283.471574) (xy 351.920094 -283.434851)
			(xy 351.889568 -283.392835) (xy 351.86599 -283.346561) (xy 351.849942 -283.297168) (xy 351.841817 -283.245873)
			(xy 351.561907 -283.245873) (xy 351.553782 -283.297168) (xy 351.537734 -283.346561) (xy 351.514156 -283.392835)
			(xy 351.48363 -283.434851) (xy 351.446907 -283.471574) (xy 351.404891 -283.5021) (xy 351.358617 -283.525678)
			(xy 351.309224 -283.541726) (xy 351.257929 -283.549851) (xy 351.205995 -283.549851) (xy 351.1547 -283.541726)
			(xy 351.105307 -283.525678) (xy 351.059033 -283.5021) (xy 351.017017 -283.471574) (xy 350.980294 -283.434851)
			(xy 350.949768 -283.392835) (xy 350.92619 -283.346561) (xy 350.910142 -283.297168) (xy 350.902017 -283.245873)
			(xy 350.62235 -283.245873) (xy 350.614227 -283.297161) (xy 350.598179 -283.346553) (xy 350.574602 -283.392827)
			(xy 350.544077 -283.434843) (xy 350.507355 -283.471567) (xy 350.465341 -283.502094) (xy 350.419068 -283.525673)
			(xy 350.369677 -283.541723) (xy 350.318383 -283.54985) (xy 350.292416 -283.55036) (xy 350.26678 -283.549882)
			(xy 350.216123 -283.541959) (xy 350.1673 -283.526299) (xy 350.121485 -283.503281) (xy 350.079779 -283.473457)
			(xy 350.043184 -283.437544) (xy 350.027494 -283.417264) (xy 349.617538 -283.417264) (xy 349.601852 -283.437546)
			(xy 349.565253 -283.473453) (xy 349.523545 -283.503273) (xy 349.477729 -283.526289) (xy 349.428907 -283.541948)
			(xy 349.378252 -283.549874) (xy 349.352616 -283.55036) (xy 349.326646 -283.549866) (xy 349.275346 -283.541744)
			(xy 349.225948 -283.525695) (xy 349.179669 -283.502117) (xy 349.137649 -283.471589) (xy 349.100921 -283.434863)
			(xy 349.070391 -283.392844) (xy 349.046811 -283.346566) (xy 349.03076 -283.297169) (xy 349.022635 -283.24587)
			(xy 348.742507 -283.24587) (xy 348.742507 -283.245873) (xy 348.734382 -283.297168) (xy 348.718334 -283.346561)
			(xy 348.694756 -283.392835) (xy 348.66423 -283.434851) (xy 348.627507 -283.471574) (xy 348.585491 -283.5021)
			(xy 348.539217 -283.525678) (xy 348.489824 -283.541726) (xy 348.438529 -283.549851) (xy 348.386595 -283.549851)
			(xy 348.3353 -283.541726) (xy 348.285907 -283.525678) (xy 348.239633 -283.5021) (xy 348.197617 -283.471574)
			(xy 348.160894 -283.434851) (xy 348.130368 -283.392835) (xy 348.10679 -283.346561) (xy 348.090742 -283.297168)
			(xy 348.082617 -283.245873) (xy 347.802961 -283.245873) (xy 347.794836 -283.297168) (xy 347.778788 -283.346561)
			(xy 347.75521 -283.392835) (xy 347.724684 -283.434851) (xy 347.687961 -283.471574) (xy 347.645945 -283.5021)
			(xy 347.599671 -283.525678) (xy 347.550278 -283.541726) (xy 347.498983 -283.549851) (xy 347.447049 -283.549851)
			(xy 347.395754 -283.541726) (xy 347.346361 -283.525678) (xy 347.300087 -283.5021) (xy 347.258071 -283.471574)
			(xy 347.221348 -283.434851) (xy 347.190822 -283.392835) (xy 347.167244 -283.346561) (xy 347.151196 -283.297168)
			(xy 347.143071 -283.245873) (xy 347.142562 -283.219906) (xy 346.863416 -283.219906) (xy 346.862907 -283.245873)
			(xy 346.854782 -283.297168) (xy 346.838734 -283.346561) (xy 346.815156 -283.392835) (xy 346.78463 -283.434851)
			(xy 346.747907 -283.471574) (xy 346.705891 -283.5021) (xy 346.659617 -283.525678) (xy 346.610224 -283.541726)
			(xy 346.558929 -283.549851) (xy 346.506995 -283.549851) (xy 346.4557 -283.541726) (xy 346.406307 -283.525678)
			(xy 346.360033 -283.5021) (xy 346.318017 -283.471574) (xy 346.281294 -283.434851) (xy 346.250768 -283.392835)
			(xy 346.22719 -283.346561) (xy 346.211142 -283.297168) (xy 346.203017 -283.245873) (xy 345.923107 -283.245873)
			(xy 345.914982 -283.297168) (xy 345.898934 -283.346561) (xy 345.875356 -283.392835) (xy 345.84483 -283.434851)
			(xy 345.808107 -283.471574) (xy 345.766091 -283.5021) (xy 345.719817 -283.525678) (xy 345.670424 -283.541726)
			(xy 345.619129 -283.549851) (xy 345.567195 -283.549851) (xy 345.5159 -283.541726) (xy 345.466507 -283.525678)
			(xy 345.420233 -283.5021) (xy 345.378217 -283.471574) (xy 345.341494 -283.434851) (xy 345.310968 -283.392835)
			(xy 345.28739 -283.346561) (xy 345.271342 -283.297168) (xy 345.263217 -283.245873) (xy 344.983561 -283.245873)
			(xy 344.975436 -283.297168) (xy 344.959388 -283.346561) (xy 344.93581 -283.392835) (xy 344.905284 -283.434851)
			(xy 344.868561 -283.471574) (xy 344.826545 -283.5021) (xy 344.780271 -283.525678) (xy 344.730878 -283.541726)
			(xy 344.679583 -283.549851) (xy 344.627649 -283.549851) (xy 344.576354 -283.541726) (xy 344.526961 -283.525678)
			(xy 344.480687 -283.5021) (xy 344.438671 -283.471574) (xy 344.401948 -283.434851) (xy 344.371422 -283.392835)
			(xy 344.347844 -283.346561) (xy 344.331796 -283.297168) (xy 344.323671 -283.245873) (xy 344.323162 -283.219906)
			(xy 344.323713 -283.19192) (xy 344.333164 -283.136752) (xy 344.341958 -283.110178) (xy 344.349578 -283.08808)
			(xy 344.14587 -282.73502) (xy 344.122756 -282.730702) (xy 344.097824 -282.725523) (xy 344.049799 -282.708599)
			(xy 344.004939 -282.68451) (xy 343.964304 -282.653825) (xy 343.928857 -282.617271) (xy 343.899435 -282.575712)
			(xy 343.876736 -282.530133) (xy 343.861296 -282.481611) (xy 343.85348 -282.431295) (xy 343.853008 -282.405836)
			(xy 343.574116 -282.405836) (xy 343.573607 -282.431803) (xy 343.565482 -282.483098) (xy 343.549434 -282.532491)
			(xy 343.525856 -282.578765) (xy 343.49533 -282.620781) (xy 343.458607 -282.657504) (xy 343.416591 -282.68803)
			(xy 343.370317 -282.711608) (xy 343.320924 -282.727656) (xy 343.269629 -282.735781) (xy 343.217695 -282.735781)
			(xy 343.1664 -282.727656) (xy 343.117007 -282.711608) (xy 343.070733 -282.68803) (xy 343.028717 -282.657504)
			(xy 342.991994 -282.620781) (xy 342.961468 -282.578765) (xy 342.93789 -282.532491) (xy 342.921842 -282.483098)
			(xy 342.913717 -282.431803) (xy 342.913208 -282.405836) (xy 342.63457 -282.405836) (xy 342.634061 -282.431803)
			(xy 342.625936 -282.483098) (xy 342.609888 -282.532491) (xy 342.58631 -282.578765) (xy 342.555784 -282.620781)
			(xy 342.519061 -282.657504) (xy 342.477045 -282.68803) (xy 342.430771 -282.711608) (xy 342.381378 -282.727656)
			(xy 342.330083 -282.735781) (xy 342.278149 -282.735781) (xy 342.226854 -282.727656) (xy 342.177461 -282.711608)
			(xy 342.131187 -282.68803) (xy 342.089171 -282.657504) (xy 342.052448 -282.620781) (xy 342.021922 -282.578765)
			(xy 341.998344 -282.532491) (xy 341.982296 -282.483098) (xy 341.974171 -282.431803) (xy 341.694261 -282.431803)
			(xy 341.686136 -282.483098) (xy 341.670088 -282.532491) (xy 341.64651 -282.578765) (xy 341.615984 -282.620781)
			(xy 341.579261 -282.657504) (xy 341.537245 -282.68803) (xy 341.490971 -282.711608) (xy 341.441578 -282.727656)
			(xy 341.390283 -282.735781) (xy 341.338349 -282.735781) (xy 341.287054 -282.727656) (xy 341.237661 -282.711608)
			(xy 341.191387 -282.68803) (xy 341.149371 -282.657504) (xy 341.112648 -282.620781) (xy 341.082122 -282.578765)
			(xy 341.058544 -282.532491) (xy 341.042496 -282.483098) (xy 341.034371 -282.431803) (xy 341.033862 -282.405836)
			(xy 340.75497 -282.405836) (xy 340.754461 -282.431803) (xy 340.746336 -282.483098) (xy 340.730288 -282.532491)
			(xy 340.70671 -282.578765) (xy 340.676184 -282.620781) (xy 340.639461 -282.657504) (xy 340.597445 -282.68803)
			(xy 340.551171 -282.711608) (xy 340.501778 -282.727656) (xy 340.450483 -282.735781) (xy 340.398549 -282.735781)
			(xy 340.347254 -282.727656) (xy 340.297861 -282.711608) (xy 340.251587 -282.68803) (xy 340.209571 -282.657504)
			(xy 340.172848 -282.620781) (xy 340.142322 -282.578765) (xy 340.118744 -282.532491) (xy 340.102696 -282.483098)
			(xy 340.094571 -282.431803) (xy 339.814668 -282.431803) (xy 339.806941 -282.481628) (xy 339.791506 -282.530161)
			(xy 339.768806 -282.575752) (xy 339.73938 -282.617319) (xy 339.703925 -282.653879) (xy 339.663279 -282.684566)
			(xy 339.618406 -282.708652) (xy 339.570368 -282.725568) (xy 339.545422 -282.730702) (xy 339.522308 -282.73502)
			(xy 339.3186 -283.08808) (xy 339.32622 -283.110178) (xy 339.334953 -283.136768) (xy 339.344403 -283.191926)
			(xy 339.345016 -283.219906) (xy 339.344507 -283.245873) (xy 339.624417 -283.245873) (xy 339.624417 -283.193939)
			(xy 339.632542 -283.142644) (xy 339.64859 -283.093251) (xy 339.672168 -283.046977) (xy 339.702694 -283.004961)
			(xy 339.739417 -282.968238) (xy 339.781433 -282.937712) (xy 339.827707 -282.914134) (xy 339.8771 -282.898086)
			(xy 339.928395 -282.889961) (xy 339.980329 -282.889961) (xy 340.031624 -282.898086) (xy 340.081017 -282.914134)
			(xy 340.127291 -282.937712) (xy 340.169307 -282.968238) (xy 340.20603 -283.004961) (xy 340.236556 -283.046977)
			(xy 340.260134 -283.093251) (xy 340.276182 -283.142644) (xy 340.284307 -283.193939) (xy 340.284816 -283.219906)
			(xy 340.284307 -283.245865) (xy 340.564261 -283.245865) (xy 340.564261 -283.193935) (xy 340.572384 -283.142645)
			(xy 340.58843 -283.093256) (xy 340.612004 -283.046986) (xy 340.642526 -283.004972) (xy 340.679243 -282.96825)
			(xy 340.721253 -282.937724) (xy 340.767521 -282.914145) (xy 340.816908 -282.898093) (xy 340.868197 -282.889964)
			(xy 340.894162 -282.889452) (xy 340.919798 -282.889941) (xy 340.970454 -282.897862) (xy 341.019277 -282.913518)
			(xy 341.065093 -282.936535) (xy 341.106799 -282.966357) (xy 341.143394 -283.002269) (xy 341.159084 -283.022548)
			(xy 341.56904 -283.022548) (xy 341.584743 -283.002279) (xy 341.621338 -282.96637) (xy 341.663042 -282.936549)
			(xy 341.708855 -282.91353) (xy 341.757674 -282.897869) (xy 341.808327 -282.889939) (xy 341.833962 -282.889452)
			(xy 341.859934 -282.88992) (xy 341.911238 -282.89804) (xy 341.960641 -282.914087) (xy 342.006925 -282.937665)
			(xy 342.04895 -282.968194) (xy 342.085681 -283.004921) (xy 342.116215 -283.046943) (xy 342.139798 -283.093224)
			(xy 342.155851 -283.142625) (xy 342.163977 -283.193928) (xy 342.163977 -283.245872) (xy 342.163977 -283.245873)
			(xy 342.443817 -283.245873) (xy 342.443817 -283.193939) (xy 342.451942 -283.142644) (xy 342.46799 -283.093251)
			(xy 342.491568 -283.046977) (xy 342.522094 -283.004961) (xy 342.558817 -282.968238) (xy 342.600833 -282.937712)
			(xy 342.647107 -282.914134) (xy 342.6965 -282.898086) (xy 342.747795 -282.889961) (xy 342.799729 -282.889961)
			(xy 342.851024 -282.898086) (xy 342.900417 -282.914134) (xy 342.946691 -282.937712) (xy 342.988707 -282.968238)
			(xy 343.02543 -283.004961) (xy 343.055956 -283.046977) (xy 343.079534 -283.093251) (xy 343.095582 -283.142644)
			(xy 343.103707 -283.193939) (xy 343.104216 -283.219906) (xy 343.103707 -283.245873) (xy 343.383617 -283.245873)
			(xy 343.383617 -283.193939) (xy 343.391742 -283.142644) (xy 343.40779 -283.093251) (xy 343.431368 -283.046977)
			(xy 343.461894 -283.004961) (xy 343.498617 -282.968238) (xy 343.540633 -282.937712) (xy 343.586907 -282.914134)
			(xy 343.6363 -282.898086) (xy 343.687595 -282.889961) (xy 343.739529 -282.889961) (xy 343.790824 -282.898086)
			(xy 343.840217 -282.914134) (xy 343.886491 -282.937712) (xy 343.928507 -282.968238) (xy 343.96523 -283.004961)
			(xy 343.995756 -283.046977) (xy 344.019334 -283.093251) (xy 344.035382 -283.142644) (xy 344.043507 -283.193939)
			(xy 344.044016 -283.219906) (xy 344.043507 -283.245873) (xy 344.035382 -283.297168) (xy 344.019334 -283.346561)
			(xy 343.995756 -283.392835) (xy 343.96523 -283.434851) (xy 343.928507 -283.471574) (xy 343.886491 -283.5021)
			(xy 343.840217 -283.525678) (xy 343.790824 -283.541726) (xy 343.739529 -283.549851) (xy 343.687595 -283.549851)
			(xy 343.6363 -283.541726) (xy 343.586907 -283.525678) (xy 343.540633 -283.5021) (xy 343.498617 -283.471574)
			(xy 343.461894 -283.434851) (xy 343.431368 -283.392835) (xy 343.40779 -283.346561) (xy 343.391742 -283.297168)
			(xy 343.383617 -283.245873) (xy 343.103707 -283.245873) (xy 343.095582 -283.297168) (xy 343.079534 -283.346561)
			(xy 343.055956 -283.392835) (xy 343.02543 -283.434851) (xy 342.988707 -283.471574) (xy 342.946691 -283.5021)
			(xy 342.900417 -283.525678) (xy 342.851024 -283.541726) (xy 342.799729 -283.549851) (xy 342.747795 -283.549851)
			(xy 342.6965 -283.541726) (xy 342.647107 -283.525678) (xy 342.600833 -283.5021) (xy 342.558817 -283.471574)
			(xy 342.522094 -283.434851) (xy 342.491568 -283.392835) (xy 342.46799 -283.346561) (xy 342.451942 -283.297168)
			(xy 342.443817 -283.245873) (xy 342.163977 -283.245873) (xy 342.155851 -283.297175) (xy 342.139798 -283.346576)
			(xy 342.116215 -283.392857) (xy 342.085681 -283.434879) (xy 342.04895 -283.471606) (xy 342.006925 -283.502135)
			(xy 341.960641 -283.525713) (xy 341.911238 -283.54176) (xy 341.859934 -283.54988) (xy 341.833962 -283.55036)
			(xy 341.808324 -283.549921) (xy 341.757666 -283.54199) (xy 341.708842 -283.526322) (xy 341.663027 -283.503297)
			(xy 341.621322 -283.473466) (xy 341.584729 -283.437547) (xy 341.56904 -283.417264) (xy 341.159084 -283.417264)
			(xy 341.143429 -283.437572) (xy 341.106824 -283.473478) (xy 341.065109 -283.503295) (xy 341.019288 -283.526306)
			(xy 340.97046 -283.54196) (xy 340.9198 -283.549878) (xy 340.894162 -283.55036) (xy 340.868197 -283.549836)
			(xy 340.816908 -283.541707) (xy 340.767521 -283.525655) (xy 340.721253 -283.502076) (xy 340.679243 -283.47155)
			(xy 340.642526 -283.434828) (xy 340.612004 -283.392814) (xy 340.58843 -283.346544) (xy 340.572384 -283.297155)
			(xy 340.564261 -283.245865) (xy 340.284307 -283.245865) (xy 340.284307 -283.245873) (xy 340.276182 -283.297168)
			(xy 340.260134 -283.346561) (xy 340.236556 -283.392835) (xy 340.20603 -283.434851) (xy 340.169307 -283.471574)
			(xy 340.127291 -283.5021) (xy 340.081017 -283.525678) (xy 340.031624 -283.541726) (xy 339.980329 -283.549851)
			(xy 339.928395 -283.549851) (xy 339.8771 -283.541726) (xy 339.827707 -283.525678) (xy 339.781433 -283.5021)
			(xy 339.739417 -283.471574) (xy 339.702694 -283.434851) (xy 339.672168 -283.392835) (xy 339.64859 -283.346561)
			(xy 339.632542 -283.297168) (xy 339.624417 -283.245873) (xy 339.344507 -283.245873) (xy 339.336382 -283.297168)
			(xy 339.320334 -283.346561) (xy 339.296756 -283.392835) (xy 339.26623 -283.434851) (xy 339.229507 -283.471574)
			(xy 339.187491 -283.5021) (xy 339.141217 -283.525678) (xy 339.091824 -283.541726) (xy 339.040529 -283.549851)
			(xy 338.988595 -283.549851) (xy 338.9373 -283.541726) (xy 338.887907 -283.525678) (xy 338.841633 -283.5021)
			(xy 338.799617 -283.471574) (xy 338.762894 -283.434851) (xy 338.732368 -283.392835) (xy 338.70879 -283.346561)
			(xy 338.692742 -283.297168) (xy 338.684617 -283.245873) (xy 338.684108 -283.219906) (xy 338.405216 -283.219906)
			(xy 338.404707 -283.245873) (xy 338.396582 -283.297168) (xy 338.380534 -283.346561) (xy 338.356956 -283.392835)
			(xy 338.32643 -283.434851) (xy 338.289707 -283.471574) (xy 338.247691 -283.5021) (xy 338.201417 -283.525678)
			(xy 338.152024 -283.541726) (xy 338.100729 -283.549851) (xy 338.048795 -283.549851) (xy 337.9975 -283.541726)
			(xy 337.948107 -283.525678) (xy 337.901833 -283.5021) (xy 337.859817 -283.471574) (xy 337.823094 -283.434851)
			(xy 337.792568 -283.392835) (xy 337.76899 -283.346561) (xy 337.752942 -283.297168) (xy 337.744817 -283.245873)
			(xy 337.464907 -283.245873) (xy 337.456782 -283.297168) (xy 337.440734 -283.346561) (xy 337.417156 -283.392835)
			(xy 337.38663 -283.434851) (xy 337.349907 -283.471574) (xy 337.307891 -283.5021) (xy 337.261617 -283.525678)
			(xy 337.212224 -283.541726) (xy 337.160929 -283.549851) (xy 337.108995 -283.549851) (xy 337.0577 -283.541726)
			(xy 337.008307 -283.525678) (xy 336.962033 -283.5021) (xy 336.920017 -283.471574) (xy 336.883294 -283.434851)
			(xy 336.852768 -283.392835) (xy 336.82919 -283.346561) (xy 336.813142 -283.297168) (xy 336.805017 -283.245873)
			(xy 336.525107 -283.245873) (xy 336.516982 -283.297168) (xy 336.500934 -283.346561) (xy 336.477356 -283.392835)
			(xy 336.44683 -283.434851) (xy 336.410107 -283.471574) (xy 336.368091 -283.5021) (xy 336.321817 -283.525678)
			(xy 336.272424 -283.541726) (xy 336.221129 -283.549851) (xy 336.169195 -283.549851) (xy 336.1179 -283.541726)
			(xy 336.068507 -283.525678) (xy 336.022233 -283.5021) (xy 335.980217 -283.471574) (xy 335.943494 -283.434851)
			(xy 335.912968 -283.392835) (xy 335.88939 -283.346561) (xy 335.873342 -283.297168) (xy 335.865217 -283.245873)
			(xy 335.864708 -283.219906) (xy 335.865321 -283.191926) (xy 335.874772 -283.136768) (xy 335.883504 -283.110178)
			(xy 335.891124 -283.08808) (xy 335.70291 -282.762198) (xy 335.678272 -282.758896) (xy 335.675224 -282.758388)
			(xy 335.675224 -282.758642) (xy 335.664302 -282.756864) (xy 335.662016 -282.75661) (xy 335.650233 -282.754376)
			(xy 335.626972 -282.74853) (xy 335.615534 -282.744926) (xy 335.599532 -282.739338) (xy 335.59496 -282.73756)
			(xy 334.3402 -282.73756) (xy 334.239108 -282.838652) (xy 334.290162 -282.889706) (xy 334.311498 -282.889452)
			(xy 334.315562 -282.889452) (xy 334.341533 -282.889932) (xy 334.392836 -282.898052) (xy 334.442236 -282.914098)
			(xy 334.488518 -282.937676) (xy 334.530542 -282.968203) (xy 334.567272 -283.004929) (xy 334.597805 -283.046949)
			(xy 334.621387 -283.093229) (xy 334.637439 -283.142627) (xy 334.645565 -283.193929) (xy 334.645565 -283.245871)
			(xy 334.645565 -283.245873) (xy 334.925417 -283.245873) (xy 334.925417 -283.193939) (xy 334.933542 -283.142644)
			(xy 334.94959 -283.093251) (xy 334.973168 -283.046977) (xy 335.003694 -283.004961) (xy 335.040417 -282.968238)
			(xy 335.082433 -282.937712) (xy 335.128707 -282.914134) (xy 335.1781 -282.898086) (xy 335.229395 -282.889961)
			(xy 335.281329 -282.889961) (xy 335.332624 -282.898086) (xy 335.382017 -282.914134) (xy 335.428291 -282.937712)
			(xy 335.470307 -282.968238) (xy 335.50703 -283.004961) (xy 335.537556 -283.046977) (xy 335.561134 -283.093251)
			(xy 335.577182 -283.142644) (xy 335.585307 -283.193939) (xy 335.585816 -283.219906) (xy 335.585307 -283.245873)
			(xy 335.577182 -283.297168) (xy 335.561134 -283.346561) (xy 335.537556 -283.392835) (xy 335.50703 -283.434851)
			(xy 335.470307 -283.471574) (xy 335.428291 -283.5021) (xy 335.382017 -283.525678) (xy 335.332624 -283.541726)
			(xy 335.281329 -283.549851) (xy 335.229395 -283.549851) (xy 335.1781 -283.541726) (xy 335.128707 -283.525678)
			(xy 335.082433 -283.5021) (xy 335.040417 -283.471574) (xy 335.003694 -283.434851) (xy 334.973168 -283.392835)
			(xy 334.94959 -283.346561) (xy 334.933542 -283.297168) (xy 334.925417 -283.245873) (xy 334.645565 -283.245873)
			(xy 334.637439 -283.297173) (xy 334.621387 -283.346571) (xy 334.597805 -283.392851) (xy 334.567272 -283.434871)
			(xy 334.530542 -283.471597) (xy 334.488518 -283.502124) (xy 334.442236 -283.525702) (xy 334.392836 -283.541748)
			(xy 334.341533 -283.549868) (xy 334.315562 -283.55036) (xy 334.291218 -283.549924) (xy 334.243058 -283.542775)
			(xy 334.196468 -283.528636) (xy 334.152457 -283.507815) (xy 334.111978 -283.480761) (xy 334.075906 -283.44806)
			(xy 334.045023 -283.410421) (xy 334.019996 -283.368658) (xy 334.001369 -283.323674) (xy 333.995014 -283.30017)
			(xy 333.990753 -283.28545) (xy 333.974781 -283.259314) (xy 333.951784 -283.239081) (xy 333.923827 -283.226566)
			(xy 333.893418 -283.222894) (xy 333.863285 -283.228392) (xy 333.836132 -283.242569) (xy 333.824834 -283.252926)
			(xy 333.48549 -283.59227) (xy 333.48549 -284.033722) (xy 334.455262 -284.033722) (xy 334.455771 -284.007755)
			(xy 334.463896 -283.95646) (xy 334.479944 -283.907067) (xy 334.503522 -283.860793) (xy 334.534048 -283.818777)
			(xy 334.570771 -283.782054) (xy 334.612787 -283.751528) (xy 334.659061 -283.72795) (xy 334.708454 -283.711902)
			(xy 334.759749 -283.703777) (xy 334.811683 -283.703777) (xy 334.862978 -283.711902) (xy 334.912371 -283.72795)
			(xy 334.958645 -283.751528) (xy 335.000661 -283.782054) (xy 335.037384 -283.818777) (xy 335.06791 -283.860793)
			(xy 335.091488 -283.907067) (xy 335.107536 -283.95646) (xy 335.115661 -284.007755) (xy 335.11617 -284.033722)
			(xy 335.115663 -284.059689) (xy 335.395317 -284.059689) (xy 335.395317 -284.007755) (xy 335.403442 -283.95646)
			(xy 335.41949 -283.907067) (xy 335.443068 -283.860793) (xy 335.473594 -283.818777) (xy 335.510317 -283.782054)
			(xy 335.552333 -283.751528) (xy 335.598607 -283.72795) (xy 335.648 -283.711902) (xy 335.699295 -283.703777)
			(xy 335.751229 -283.703777) (xy 335.802524 -283.711902) (xy 335.851917 -283.72795) (xy 335.898191 -283.751528)
			(xy 335.940207 -283.782054) (xy 335.97693 -283.818777) (xy 336.007456 -283.860793) (xy 336.031034 -283.907067)
			(xy 336.047082 -283.95646) (xy 336.055207 -284.007755) (xy 336.055716 -284.033722) (xy 336.055207 -284.059689)
			(xy 336.335371 -284.059689) (xy 336.335371 -284.007755) (xy 336.343496 -283.95646) (xy 336.359544 -283.907067)
			(xy 336.383122 -283.860793) (xy 336.413648 -283.818777) (xy 336.450371 -283.782054) (xy 336.492387 -283.751528)
			(xy 336.538661 -283.72795) (xy 336.588054 -283.711902) (xy 336.639349 -283.703777) (xy 336.691283 -283.703777)
			(xy 336.742578 -283.711902) (xy 336.791971 -283.72795) (xy 336.838245 -283.751528) (xy 336.880261 -283.782054)
			(xy 336.916984 -283.818777) (xy 336.94751 -283.860793) (xy 336.971088 -283.907067) (xy 336.987136 -283.95646)
			(xy 336.995261 -284.007755) (xy 336.99577 -284.033722) (xy 336.995261 -284.059689) (xy 336.987136 -284.110984)
			(xy 336.971088 -284.160377) (xy 336.94751 -284.206651) (xy 336.916984 -284.248667) (xy 336.880261 -284.28539)
			(xy 336.838245 -284.315916) (xy 336.791971 -284.339494) (xy 336.742578 -284.355542) (xy 336.691283 -284.363667)
			(xy 336.639349 -284.363667) (xy 336.588054 -284.355542) (xy 336.538661 -284.339494) (xy 336.492387 -284.315916)
			(xy 336.450371 -284.28539) (xy 336.413648 -284.248667) (xy 336.383122 -284.206651) (xy 336.359544 -284.160377)
			(xy 336.343496 -284.110984) (xy 336.335371 -284.059689) (xy 336.055207 -284.059689) (xy 336.047082 -284.110984)
			(xy 336.031034 -284.160377) (xy 336.007456 -284.206651) (xy 335.97693 -284.248667) (xy 335.940207 -284.28539)
			(xy 335.898191 -284.315916) (xy 335.851917 -284.339494) (xy 335.802524 -284.355542) (xy 335.751229 -284.363667)
			(xy 335.699295 -284.363667) (xy 335.648 -284.355542) (xy 335.598607 -284.339494) (xy 335.552333 -284.315916)
			(xy 335.510317 -284.28539) (xy 335.473594 -284.248667) (xy 335.443068 -284.206651) (xy 335.41949 -284.160377)
			(xy 335.403442 -284.110984) (xy 335.395317 -284.059689) (xy 335.115663 -284.059689) (xy 335.115624 -284.061708)
			(xy 335.10617 -284.116876) (xy 335.097374 -284.14345) (xy 335.089754 -284.165548) (xy 335.293462 -284.518354)
			(xy 335.316322 -284.522672) (xy 335.341242 -284.527847) (xy 335.389227 -284.54481) (xy 335.434045 -284.568925)
			(xy 335.474638 -284.599624) (xy 335.510048 -284.636182) (xy 335.539436 -284.677733) (xy 335.562111 -284.723298)
			(xy 335.577534 -284.771799) (xy 335.585343 -284.822091) (xy 335.585816 -284.847538) (xy 335.585307 -284.873505)
			(xy 335.577182 -284.9248) (xy 335.561134 -284.974193) (xy 335.537556 -285.020467) (xy 335.50703 -285.062483)
			(xy 335.470307 -285.099206) (xy 335.428291 -285.129732) (xy 335.382017 -285.15331) (xy 335.332624 -285.169358)
			(xy 335.281329 -285.177483) (xy 335.229395 -285.177483) (xy 335.1781 -285.169358) (xy 335.128707 -285.15331)
			(xy 335.082433 -285.129732) (xy 335.040417 -285.099206) (xy 335.003694 -285.062483) (xy 334.973168 -285.020467)
			(xy 334.94959 -284.974193) (xy 334.933542 -284.9248) (xy 334.925417 -284.873505) (xy 334.924908 -284.847538)
			(xy 334.92547 -284.819553) (xy 334.934914 -284.764385) (xy 334.943704 -284.73781) (xy 334.951324 -284.715712)
			(xy 334.747616 -284.362906) (xy 334.724756 -284.358588) (xy 334.699824 -284.353466) (xy 334.651836 -284.336498)
			(xy 334.607016 -284.312376) (xy 334.566422 -284.28167) (xy 334.531013 -284.245106) (xy 334.501626 -284.203547)
			(xy 334.478955 -284.157976) (xy 334.463536 -284.109469) (xy 334.455732 -284.059172) (xy 334.455262 -284.033722)
			(xy 333.48549 -284.033722) (xy 333.48549 -284.295088) (xy 333.571596 -284.381194) (xy 333.564879 -284.388431)
			(xy 333.557277 -284.406636) (xy 333.556864 -284.4165) (xy 333.556864 -284.501336) (xy 333.556999 -284.506857)
			(xy 333.559443 -284.517626) (xy 333.56169 -284.522672) (xy 333.572866 -284.544516) (xy 333.575691 -284.549337)
			(xy 333.583128 -284.557673) (xy 333.587598 -284.561026) (xy 333.587598 -284.56128) (xy 333.612008 -284.580158)
			(xy 333.654541 -284.62486) (xy 333.67218 -284.65018) (xy 334.05064 -284.65018) (xy 334.066331 -284.6299)
			(xy 334.102926 -284.593987) (xy 334.144632 -284.564161) (xy 334.190447 -284.54114) (xy 334.239269 -284.525475)
			(xy 334.289925 -284.517545) (xy 334.315562 -284.517084) (xy 334.34153 -284.517564) (xy 334.392828 -284.525683)
			(xy 334.442224 -284.541728) (xy 334.488502 -284.565303) (xy 334.530521 -284.595827) (xy 334.567248 -284.63255)
			(xy 334.597777 -284.674566) (xy 334.621358 -284.720841) (xy 334.637408 -284.770235) (xy 334.645533 -284.821532)
			(xy 334.645533 -284.873468) (xy 334.637408 -284.924765) (xy 334.621358 -284.974159) (xy 334.597777 -285.020434)
			(xy 334.567248 -285.06245) (xy 334.530521 -285.099173) (xy 334.488502 -285.129697) (xy 334.442224 -285.153272)
			(xy 334.392828 -285.169317) (xy 334.34153 -285.177436) (xy 334.315562 -285.177992) (xy 334.289928 -285.177505)
			(xy 334.239276 -285.169574) (xy 334.190458 -285.153911) (xy 334.144649 -285.13089) (xy 334.102948 -285.101065)
			(xy 334.066358 -285.065153) (xy 334.05064 -285.044896) (xy 333.67218 -285.044896) (xy 333.654535 -285.070211)
			(xy 333.612004 -285.114913) (xy 333.587598 -285.133796) (xy 333.587598 -285.13405) (xy 333.583143 -285.137419)
			(xy 333.575715 -285.145755) (xy 333.572866 -285.15056) (xy 333.56169 -285.172404) (xy 333.559485 -285.177462)
			(xy 333.557061 -285.188225) (xy 333.556864 -285.19374) (xy 333.556864 -285.27375) (xy 333.557194 -285.282225)
			(xy 333.562827 -285.298211) (xy 333.573467 -285.311405) (xy 333.580486 -285.316168) (xy 333.633318 -285.349188)
			(xy 333.645256 -285.356808) (xy 333.65116 -285.360082) (xy 333.664163 -285.363693) (xy 333.67091 -285.36392)
			(xy 333.700628 -285.36392) (xy 333.710534 -285.359602) (xy 333.731874 -285.350453) (xy 333.776477 -285.337557)
			(xy 333.822447 -285.331035) (xy 333.845662 -285.330646) (xy 333.871657 -285.331126) (xy 333.923007 -285.339254)
			(xy 333.972454 -285.355315) (xy 334.018779 -285.378914) (xy 334.060841 -285.40947) (xy 334.097605 -285.44623)
			(xy 334.128166 -285.488289) (xy 334.15177 -285.534611) (xy 334.167837 -285.584056) (xy 334.175971 -285.635405)
			(xy 334.175971 -285.687321) (xy 334.455517 -285.687321) (xy 334.455517 -285.635387) (xy 334.463642 -285.584092)
			(xy 334.47969 -285.534699) (xy 334.503268 -285.488425) (xy 334.533794 -285.446409) (xy 334.570517 -285.409686)
			(xy 334.612533 -285.37916) (xy 334.658807 -285.355582) (xy 334.7082 -285.339534) (xy 334.759495 -285.331409)
			(xy 334.811429 -285.331409) (xy 334.862724 -285.339534) (xy 334.912117 -285.355582) (xy 334.958391 -285.37916)
			(xy 335.000407 -285.409686) (xy 335.03713 -285.446409) (xy 335.067656 -285.488425) (xy 335.091234 -285.534699)
			(xy 335.107282 -285.584092) (xy 335.115407 -285.635387) (xy 335.115916 -285.661354) (xy 335.394808 -285.661354)
			(xy 335.395284 -285.635903) (xy 335.403068 -285.585601) (xy 335.418475 -285.537087) (xy 335.44114 -285.491511)
			(xy 335.470528 -285.44995) (xy 335.505942 -285.413389) (xy 335.546545 -285.382692) (xy 335.591376 -285.358585)
			(xy 335.639374 -285.341641) (xy 335.664302 -285.336488) (xy 335.687416 -285.33217) (xy 335.891124 -284.97911)
			(xy 335.883504 -284.957012) (xy 335.874762 -284.93049) (xy 335.86531 -284.875457) (xy 335.864708 -284.847538)
			(xy 335.865217 -284.821571) (xy 335.873342 -284.770276) (xy 335.88939 -284.720883) (xy 335.912968 -284.674609)
			(xy 335.943494 -284.632593) (xy 335.980217 -284.59587) (xy 336.022233 -284.565344) (xy 336.068507 -284.541766)
			(xy 336.1179 -284.525718) (xy 336.169195 -284.517593) (xy 336.221129 -284.517593) (xy 336.272424 -284.525718)
			(xy 336.321817 -284.541766) (xy 336.368091 -284.565344) (xy 336.410107 -284.59587) (xy 336.44683 -284.632593)
			(xy 336.477356 -284.674609) (xy 336.500934 -284.720883) (xy 336.516982 -284.770276) (xy 336.525107 -284.821571)
			(xy 336.525616 -284.847538) (xy 336.525194 -284.872992) (xy 336.51741 -284.9233) (xy 336.502 -284.971818)
			(xy 336.479329 -285.017398) (xy 336.449935 -285.058961) (xy 336.414512 -285.095522) (xy 336.3739 -285.126217)
			(xy 336.32906 -285.150319) (xy 336.281054 -285.167256) (xy 336.256122 -285.172404) (xy 336.233008 -285.176722)
			(xy 336.0293 -285.529782) (xy 336.03692 -285.55188) (xy 336.04566 -285.578403) (xy 336.055113 -285.633435)
			(xy 336.055716 -285.661354) (xy 336.055207 -285.687321) (xy 336.047082 -285.738616) (xy 336.031034 -285.788009)
			(xy 336.007456 -285.834283) (xy 335.97693 -285.876299) (xy 335.940207 -285.913022) (xy 335.898191 -285.943548)
			(xy 335.851917 -285.967126) (xy 335.802524 -285.983174) (xy 335.751229 -285.991299) (xy 335.699295 -285.991299)
			(xy 335.648 -285.983174) (xy 335.598607 -285.967126) (xy 335.552333 -285.943548) (xy 335.510317 -285.913022)
			(xy 335.473594 -285.876299) (xy 335.443068 -285.834283) (xy 335.41949 -285.788009) (xy 335.403442 -285.738616)
			(xy 335.395317 -285.687321) (xy 335.394808 -285.661354) (xy 335.115916 -285.661354) (xy 335.115407 -285.687321)
			(xy 335.107282 -285.738616) (xy 335.091234 -285.788009) (xy 335.067656 -285.834283) (xy 335.03713 -285.876299)
			(xy 335.000407 -285.913022) (xy 334.958391 -285.943548) (xy 334.912117 -285.967126) (xy 334.862724 -285.983174)
			(xy 334.811429 -285.991299) (xy 334.759495 -285.991299) (xy 334.7082 -285.983174) (xy 334.658807 -285.967126)
			(xy 334.612533 -285.943548) (xy 334.570517 -285.913022) (xy 334.533794 -285.876299) (xy 334.503268 -285.834283)
			(xy 334.47969 -285.788009) (xy 334.463642 -285.738616) (xy 334.455517 -285.687321) (xy 334.175971 -285.687321)
			(xy 334.175971 -285.687395) (xy 334.167837 -285.738744) (xy 334.15177 -285.788189) (xy 334.128166 -285.834511)
			(xy 334.097605 -285.87657) (xy 334.060841 -285.91333) (xy 334.018778 -285.943886) (xy 333.972454 -285.967485)
			(xy 333.923007 -285.983546) (xy 333.871657 -285.991674) (xy 333.845662 -285.992062) (xy 333.845154 -285.992062)
			(xy 333.821146 -285.991614) (xy 333.77364 -285.984627) (xy 333.727646 -285.970837) (xy 333.705708 -285.961074)
			(xy 333.700882 -285.958788) (xy 333.679292 -285.953708) (xy 333.672255 -285.953948) (xy 333.658722 -285.957812)
			(xy 333.652622 -285.961328) (xy 333.580486 -286.00654) (xy 333.57348 -286.011306) (xy 333.56289 -286.024522)
			(xy 333.557255 -286.040492) (xy 333.556864 -286.048958) (xy 333.556864 -286.129222) (xy 333.556998 -286.134744)
			(xy 333.559439 -286.145514) (xy 333.56169 -286.150558) (xy 333.572866 -286.172402) (xy 333.57569 -286.177224)
			(xy 333.583126 -286.185562) (xy 333.587598 -286.188912) (xy 333.587598 -286.189166) (xy 333.609569 -286.206081)
			(xy 333.64849 -286.245572) (xy 333.680819 -286.290618) (xy 333.705774 -286.340131) (xy 333.722753 -286.392914)
			(xy 333.731346 -286.447691) (xy 333.731345 -286.475424) (xy 333.985108 -286.475424) (xy 333.985617 -286.449457)
			(xy 333.993742 -286.398162) (xy 334.00979 -286.348769) (xy 334.033368 -286.302495) (xy 334.063894 -286.260479)
			(xy 334.100617 -286.223756) (xy 334.142633 -286.19323) (xy 334.188907 -286.169652) (xy 334.2383 -286.153604)
			(xy 334.289595 -286.145479) (xy 334.341529 -286.145479) (xy 334.392824 -286.153604) (xy 334.442217 -286.169652)
			(xy 334.488491 -286.19323) (xy 334.530507 -286.223756) (xy 334.56723 -286.260479) (xy 334.597756 -286.302495)
			(xy 334.621334 -286.348769) (xy 334.637382 -286.398162) (xy 334.645507 -286.449457) (xy 334.646016 -286.475424)
			(xy 334.645385 -286.50334) (xy 334.635939 -286.558371) (xy 334.62722 -286.584898) (xy 334.6196 -286.606996)
			(xy 334.823562 -286.960056) (xy 334.846422 -286.964374) (xy 334.871342 -286.969547) (xy 334.919327 -286.98651)
			(xy 334.964146 -287.010626) (xy 335.004739 -287.041325) (xy 335.040148 -287.077882) (xy 335.069537 -287.119434)
			(xy 335.092211 -287.164999) (xy 335.107635 -287.213501) (xy 335.115443 -287.263793) (xy 335.115916 -287.28924)
			(xy 335.115407 -287.315207) (xy 335.107282 -287.366502) (xy 335.091234 -287.415895) (xy 335.067656 -287.462169)
			(xy 335.03713 -287.504185) (xy 335.000407 -287.540908) (xy 334.958391 -287.571434) (xy 334.912117 -287.595012)
			(xy 334.862724 -287.61106) (xy 334.811429 -287.619185) (xy 334.759495 -287.619185) (xy 334.7082 -287.61106)
			(xy 334.658807 -287.595012) (xy 334.612533 -287.571434) (xy 334.570517 -287.540908) (xy 334.533794 -287.504185)
			(xy 334.503268 -287.462169) (xy 334.47969 -287.415895) (xy 334.463642 -287.366502) (xy 334.455517 -287.315207)
			(xy 334.455008 -287.28924) (xy 334.455634 -287.261323) (xy 334.465084 -287.206293) (xy 334.473804 -287.179766)
			(xy 334.481424 -287.157668) (xy 334.277462 -286.804608) (xy 334.254602 -286.80029) (xy 334.229677 -286.795133)
			(xy 334.18169 -286.778171) (xy 334.136869 -286.754055) (xy 334.096274 -286.723355) (xy 334.060864 -286.686795)
			(xy 334.031476 -286.64524) (xy 334.008803 -286.599672) (xy 333.993383 -286.551167) (xy 333.985578 -286.500872)
			(xy 333.985108 -286.475424) (xy 333.731345 -286.475424) (xy 333.731344 -286.503138) (xy 333.722747 -286.557914)
			(xy 333.705763 -286.610695) (xy 333.680804 -286.660206) (xy 333.648471 -286.70525) (xy 333.609548 -286.744737)
			(xy 333.587598 -286.761682) (xy 333.587598 -286.761936) (xy 333.583143 -286.765304) (xy 333.575712 -286.77364)
			(xy 333.572866 -286.778446) (xy 333.56169 -286.80029) (xy 333.559484 -286.805348) (xy 333.557056 -286.816111)
			(xy 333.556864 -286.821626) (xy 333.556864 -288.718752) (xy 333.557378 -288.728503) (xy 333.564824 -288.746534)
			(xy 333.571342 -288.753804) (xy 333.694786 -288.877248) (xy 333.702035 -288.8838) (xy 333.720078 -288.891246)
			(xy 333.729838 -288.891726)
		)
		(stroke
			(width 0)
			(type solid)
		)
		(fill yes)
		(layer "In2.Cu")
		(net "PVCCFA_EHV_FIVRA_CPU0")
	)
	(gr_poly
		(pts
			(xy 87.145876 -288.89198) (xy 87.155713 -288.891442) (xy 87.17387 -288.883852) (xy 87.181182 -288.877248)
			(xy 87.18804 -288.87039) (xy 87.202518 -288.837624) (xy 87.205665 -288.785433) (xy 87.218223 -288.681624)
			(xy 87.237873 -288.578919) (xy 87.250778 -288.528252) (xy 87.252556 -288.515806) (xy 87.252398 -288.509878)
			(xy 87.249697 -288.498335) (xy 87.247222 -288.492946) (xy 87.217504 -288.433764) (xy 87.191596 -288.409888)
			(xy 87.18804 -288.40811) (xy 87.165768 -288.398369) (xy 87.124115 -288.37331) (xy 87.086581 -288.34242)
			(xy 87.053977 -288.306365) (xy 87.027005 -288.265924) (xy 87.006248 -288.221968) (xy 86.992153 -288.175446)
			(xy 86.985025 -288.127361) (xy 86.984586 -288.103056) (xy 86.985022 -288.078283) (xy 86.992403 -288.029291)
			(xy 87.007006 -287.981947) (xy 87.028507 -287.937311) (xy 87.056424 -287.89638) (xy 87.090133 -287.86007)
			(xy 87.12888 -287.829193) (xy 87.171798 -287.804439) (xy 87.217927 -287.786362) (xy 87.266237 -287.775367)
			(xy 87.29091 -287.77311) (xy 87.2998 -287.772348) (xy 87.333328 -287.757362) (xy 87.382858 -287.705292)
			(xy 87.388418 -287.698336) (xy 87.394675 -287.681677) (xy 87.39505 -287.67278) (xy 87.39505 -287.658556)
			(xy 87.509604 -287.544002) (xy 87.514938 -287.537652) (xy 87.514938 -287.480248) (xy 87.50681 -287.467802)
			(xy 87.494414 -287.447765) (xy 87.47485 -287.404902) (xy 87.461587 -287.359691) (xy 87.454894 -287.313052)
			(xy 87.454486 -287.289494) (xy 87.454486 -287.28924) (xy 87.454966 -287.263249) (xy 87.463092 -287.211905)
			(xy 87.479151 -287.162464) (xy 87.502747 -287.116145) (xy 87.533298 -287.074088) (xy 87.570053 -287.037328)
			(xy 87.612106 -287.006771) (xy 87.658422 -286.983169) (xy 87.70786 -286.967103) (xy 87.759203 -286.95897)
			(xy 87.785194 -286.958532) (xy 87.812727 -286.959081) (xy 87.867032 -286.968204) (xy 87.919075 -286.986201)
			(xy 87.967416 -287.012572) (xy 87.98941 -287.029144) (xy 88.001329 -287.037431) (xy 88.028502 -287.0476)
			(xy 88.057438 -287.04973) (xy 88.085808 -287.043647) (xy 88.111328 -287.029842) (xy 88.121998 -287.02)
			(xy 88.174068 -286.970978) (xy 88.190578 -286.901382) (xy 88.193867 -286.887066) (xy 88.192992 -286.857718)
			(xy 88.183788 -286.829837) (xy 88.167018 -286.805736) (xy 88.144075 -286.787414) (xy 88.130634 -286.781494)
			(xy 88.10311 -286.769622) (xy 88.052548 -286.737438) (xy 88.00862 -286.696662) (xy 87.990172 -286.673036)
			(xy 87.580216 -286.673036) (xy 87.564497 -286.693276) (xy 87.527867 -286.729113) (xy 87.486151 -286.758875)
			(xy 87.440344 -286.781851) (xy 87.391544 -286.79749) (xy 87.340916 -286.80542) (xy 87.315294 -286.805878)
			(xy 87.289325 -286.805368) (xy 87.238027 -286.797243) (xy 87.188632 -286.781192) (xy 87.142355 -286.757612)
			(xy 87.100337 -286.727084) (xy 87.063612 -286.690358) (xy 87.033084 -286.648339) (xy 87.009505 -286.602063)
			(xy 86.993456 -286.552667) (xy 86.985331 -286.501369) (xy 86.985331 -286.449431) (xy 86.993456 -286.398133)
			(xy 87.009505 -286.348737) (xy 87.033084 -286.302461) (xy 87.063612 -286.260442) (xy 87.100337 -286.223716)
			(xy 87.142355 -286.193188) (xy 87.188632 -286.169608) (xy 87.238027 -286.153557) (xy 87.289325 -286.145432)
			(xy 87.315294 -286.14497) (xy 87.340916 -286.145452) (xy 87.391544 -286.153362) (xy 87.440345 -286.168992)
			(xy 87.486148 -286.19197) (xy 87.527855 -286.221742) (xy 87.564466 -286.257596) (xy 87.580216 -286.277812)
			(xy 87.990172 -286.277812) (xy 88.005894 -286.257579) (xy 88.042529 -286.221757) (xy 88.084248 -286.192011)
			(xy 88.130054 -286.169051) (xy 88.178852 -286.153428) (xy 88.229475 -286.145513) (xy 88.255094 -286.14497)
			(xy 88.282423 -286.145532) (xy 88.336336 -286.154518) (xy 88.388039 -286.172245) (xy 88.436123 -286.198233)
			(xy 88.45804 -286.214566) (xy 88.469938 -286.223162) (xy 88.497284 -286.233793) (xy 88.526524 -286.236225)
			(xy 88.555251 -286.23026) (xy 88.581104 -286.216387) (xy 88.591898 -286.206438) (xy 88.64346 -286.15767)
			(xy 88.660224 -286.087312) (xy 88.663502 -286.073) (xy 88.662609 -286.043663) (xy 88.653397 -286.015797)
			(xy 88.636629 -285.991709) (xy 88.613694 -285.973395) (xy 88.60028 -285.967424) (xy 88.57779 -285.957784)
			(xy 88.535694 -285.932843) (xy 88.497738 -285.901965) (xy 88.464752 -285.865825) (xy 88.437458 -285.825215)
			(xy 88.416453 -285.781024) (xy 88.402196 -285.734217) (xy 88.395 -285.685819) (xy 88.39454 -285.661354)
			(xy 88.395053 -285.635389) (xy 88.403183 -285.584099) (xy 88.419235 -285.534712) (xy 88.442815 -285.488444)
			(xy 88.473342 -285.446434) (xy 88.510065 -285.409716) (xy 88.552079 -285.379194) (xy 88.598349 -285.35562)
			(xy 88.647738 -285.339573) (xy 88.699029 -285.33145) (xy 88.724994 -285.3309) (xy 88.734605 -285.330986)
			(xy 88.753794 -285.332132) (xy 88.763348 -285.333186) (xy 88.778114 -285.294035) (xy 88.813525 -285.218216)
			(xy 88.855398 -285.145765) (xy 88.903417 -285.077233) (xy 88.929972 -285.044896) (xy 88.914563 -285.023379)
			(xy 88.89008 -284.976462) (xy 88.873398 -284.92624) (xy 88.864946 -284.873998) (xy 88.86444 -284.847538)
			(xy 88.86492 -284.821567) (xy 88.87304 -284.770263) (xy 88.889087 -284.720861) (xy 88.912664 -284.674577)
			(xy 88.943192 -284.632552) (xy 88.979919 -284.595821) (xy 89.02194 -284.565287) (xy 89.06822 -284.541704)
			(xy 89.11762 -284.525651) (xy 89.168923 -284.517523) (xy 89.194894 -284.517084) (xy 89.222383 -284.517637)
			(xy 89.276601 -284.526747) (xy 89.328565 -284.544699) (xy 89.376844 -284.571001) (xy 89.420106 -284.604926)
			(xy 89.457162 -284.64554) (xy 89.486988 -284.691724) (xy 89.498424 -284.716728) (xy 89.539677 -284.709881)
			(xy 89.62298 -284.702505) (xy 89.664794 -284.701996) (xy 89.665048 -284.701996) (xy 89.70673 -284.702457)
			(xy 89.789778 -284.709707) (xy 89.83091 -284.716474) (xy 89.842324 -284.691443) (xy 89.872201 -284.645252)
			(xy 89.909304 -284.604637) (xy 89.952612 -284.570716) (xy 90.000932 -284.544423) (xy 90.052935 -284.526481)
			(xy 90.107189 -284.517384) (xy 90.134694 -284.51683) (xy 90.134948 -284.51683) (xy 90.1573 -284.517592)
			(xy 90.24366 -284.367986) (xy 90.265018 -284.331977) (xy 90.313091 -284.263426) (xy 90.339672 -284.23108)
			(xy 90.324265 -284.209562) (xy 90.299784 -284.162645) (xy 90.283105 -284.112423) (xy 90.274655 -284.060182)
			(xy 90.27414 -284.033722) (xy 90.274621 -284.007751) (xy 90.282743 -283.956449) (xy 90.298791 -283.907049)
			(xy 90.32237 -283.860768) (xy 90.352898 -283.818746) (xy 90.389624 -283.782016) (xy 90.431644 -283.751484)
			(xy 90.477923 -283.727902) (xy 90.527322 -283.71185) (xy 90.578623 -283.703723) (xy 90.604594 -283.703268)
			(xy 90.632083 -283.703821) (xy 90.686302 -283.71293) (xy 90.738267 -283.730883) (xy 90.786546 -283.757183)
			(xy 90.82981 -283.791107) (xy 90.866867 -283.831721) (xy 90.896696 -283.877904) (xy 90.908124 -283.902912)
			(xy 90.949377 -283.896065) (xy 91.03268 -283.888689) (xy 91.074494 -283.88818) (xy 91.116309 -283.888663)
			(xy 91.199615 -283.896038) (xy 91.240864 -283.902912) (xy 91.252245 -283.877879) (xy 91.282064 -283.831681)
			(xy 91.319121 -283.791058) (xy 91.362394 -283.757134) (xy 91.410688 -283.730844) (xy 91.462669 -283.712914)
			(xy 91.516901 -283.70384) (xy 91.544394 -283.703268) (xy 91.570363 -283.70375) (xy 91.621662 -283.711875)
			(xy 91.671057 -283.727924) (xy 91.717334 -283.751504) (xy 91.759353 -283.782033) (xy 91.796077 -283.81876)
			(xy 91.826604 -283.860779) (xy 91.850182 -283.907057) (xy 91.866229 -283.956454) (xy 91.874351 -284.007753)
			(xy 91.874848 -284.033722) (xy 91.874303 -284.060179) (xy 91.865833 -284.11241) (xy 91.849159 -284.162629)
			(xy 91.824708 -284.209555) (xy 91.809316 -284.23108) (xy 91.841932 -284.271014) (xy 91.899336 -284.356672)
			(xy 91.92387 -284.402022) (xy 91.930578 -284.413839) (xy 91.949119 -284.43369) (xy 91.972233 -284.447958)
			(xy 91.998288 -284.455635) (xy 92.025446 -284.45618) (xy 92.051788 -284.449554) (xy 92.075456 -284.436226)
			(xy 92.094778 -284.417134) (xy 92.101924 -284.405578) (xy 92.123514 -284.367986) (xy 92.14481 -284.332044)
			(xy 92.192758 -284.263621) (xy 92.219272 -284.231334) (xy 92.203859 -284.209783) (xy 92.179373 -284.1628)
			(xy 92.162691 -284.112514) (xy 92.154241 -284.060212) (xy 92.15374 -284.033722) (xy 92.154221 -284.007751)
			(xy 92.162343 -283.956449) (xy 92.178391 -283.907049) (xy 92.20197 -283.860768) (xy 92.232498 -283.818746)
			(xy 92.269224 -283.782016) (xy 92.311244 -283.751484) (xy 92.357523 -283.727902) (xy 92.406922 -283.71185)
			(xy 92.458223 -283.703723) (xy 92.484194 -283.703268) (xy 92.511683 -283.703821) (xy 92.565902 -283.71293)
			(xy 92.617867 -283.730883) (xy 92.666146 -283.757183) (xy 92.70941 -283.791107) (xy 92.746467 -283.831721)
			(xy 92.776296 -283.877904) (xy 92.787724 -283.902912) (xy 92.82904 -283.896057) (xy 92.91247 -283.888681)
			(xy 92.954348 -283.88818) (xy 92.996099 -283.888685) (xy 93.079276 -283.896059) (xy 93.120464 -283.902912)
			(xy 93.131845 -283.877879) (xy 93.161664 -283.831681) (xy 93.198721 -283.791058) (xy 93.241994 -283.757134)
			(xy 93.290288 -283.730844) (xy 93.342269 -283.712914) (xy 93.396501 -283.70384) (xy 93.423994 -283.703268)
			(xy 93.449963 -283.70375) (xy 93.501262 -283.711875) (xy 93.550657 -283.727924) (xy 93.596934 -283.751504)
			(xy 93.638953 -283.782033) (xy 93.675677 -283.81876) (xy 93.706204 -283.860779) (xy 93.729782 -283.907057)
			(xy 93.745829 -283.956454) (xy 93.753951 -284.007753) (xy 93.754448 -284.033722) (xy 93.753927 -284.060138)
			(xy 93.745512 -284.112296) (xy 93.7289 -284.162449) (xy 93.704516 -284.209318) (xy 93.68917 -284.230826)
			(xy 93.721778 -284.270766) (xy 93.779182 -284.356423) (xy 93.803724 -284.401768) (xy 93.810409 -284.413582)
			(xy 93.828909 -284.433433) (xy 93.851989 -284.447703) (xy 93.878016 -284.45538) (xy 93.905145 -284.455923)
			(xy 93.931457 -284.449291) (xy 93.955089 -284.435955) (xy 93.974368 -284.416859) (xy 93.981524 -284.405324)
			(xy 94.003114 -284.367986) (xy 94.02441 -284.332044) (xy 94.072358 -284.263621) (xy 94.098872 -284.231334)
			(xy 94.083459 -284.209783) (xy 94.058973 -284.1628) (xy 94.042291 -284.112514) (xy 94.033841 -284.060212)
			(xy 94.03334 -284.033722) (xy 94.033821 -284.007751) (xy 94.041943 -283.956449) (xy 94.057991 -283.907049)
			(xy 94.08157 -283.860768) (xy 94.112098 -283.818746) (xy 94.148824 -283.782016) (xy 94.190844 -283.751484)
			(xy 94.237123 -283.727902) (xy 94.286522 -283.71185) (xy 94.337823 -283.703723) (xy 94.363794 -283.703268)
			(xy 94.391283 -283.703821) (xy 94.445502 -283.71293) (xy 94.497467 -283.730883) (xy 94.545746 -283.757183)
			(xy 94.58901 -283.791107) (xy 94.626067 -283.831721) (xy 94.655896 -283.877904) (xy 94.667324 -283.902912)
			(xy 94.70864 -283.896057) (xy 94.79207 -283.888681) (xy 94.833948 -283.88818) (xy 94.875699 -283.888685)
			(xy 94.958876 -283.896059) (xy 95.000064 -283.902912) (xy 95.011445 -283.877879) (xy 95.041264 -283.831681)
			(xy 95.078321 -283.791058) (xy 95.121594 -283.757134) (xy 95.169888 -283.730844) (xy 95.221869 -283.712914)
			(xy 95.276101 -283.70384) (xy 95.303594 -283.703268) (xy 95.329563 -283.70375) (xy 95.380862 -283.711875)
			(xy 95.430257 -283.727924) (xy 95.476534 -283.751504) (xy 95.518553 -283.782033) (xy 95.555277 -283.81876)
			(xy 95.585804 -283.860779) (xy 95.609382 -283.907057) (xy 95.625429 -283.956454) (xy 95.633551 -284.007753)
			(xy 95.634048 -284.033722) (xy 95.633527 -284.060138) (xy 95.625112 -284.112296) (xy 95.6085 -284.162449)
			(xy 95.584116 -284.209318) (xy 95.56877 -284.230826) (xy 95.601378 -284.270766) (xy 95.658782 -284.356423)
			(xy 95.683324 -284.401768) (xy 95.690009 -284.413582) (xy 95.708509 -284.433433) (xy 95.731589 -284.447703)
			(xy 95.757616 -284.45538) (xy 95.784745 -284.455923) (xy 95.811057 -284.449291) (xy 95.834689 -284.435955)
			(xy 95.853968 -284.416859) (xy 95.861124 -284.405324) (xy 95.882714 -284.367986) (xy 95.90401 -284.332044)
			(xy 95.951958 -284.263621) (xy 95.978472 -284.231334) (xy 95.963059 -284.209783) (xy 95.938573 -284.1628)
			(xy 95.921891 -284.112514) (xy 95.913441 -284.060212) (xy 95.91294 -284.033722) (xy 95.913421 -284.007751)
			(xy 95.921543 -283.956449) (xy 95.937591 -283.907049) (xy 95.96117 -283.860768) (xy 95.991698 -283.818746)
			(xy 96.028424 -283.782016) (xy 96.070444 -283.751484) (xy 96.116723 -283.727902) (xy 96.166122 -283.71185)
			(xy 96.217423 -283.703723) (xy 96.243394 -283.703268) (xy 96.270883 -283.703821) (xy 96.325102 -283.71293)
			(xy 96.377067 -283.730883) (xy 96.425346 -283.757183) (xy 96.46861 -283.791107) (xy 96.505667 -283.831721)
			(xy 96.535496 -283.877904) (xy 96.546924 -283.902912) (xy 96.58824 -283.896057) (xy 96.67167 -283.888681)
			(xy 96.713548 -283.88818) (xy 96.755299 -283.888685) (xy 96.838476 -283.896059) (xy 96.879664 -283.902912)
			(xy 96.891045 -283.877879) (xy 96.920864 -283.831681) (xy 96.957921 -283.791058) (xy 97.001194 -283.757134)
			(xy 97.049488 -283.730844) (xy 97.101469 -283.712914) (xy 97.155701 -283.70384) (xy 97.183194 -283.703268)
			(xy 97.209163 -283.70375) (xy 97.260462 -283.711875) (xy 97.309857 -283.727924) (xy 97.356134 -283.751504)
			(xy 97.398153 -283.782033) (xy 97.434877 -283.81876) (xy 97.465404 -283.860779) (xy 97.488982 -283.907057)
			(xy 97.505029 -283.956454) (xy 97.513151 -284.007753) (xy 97.513648 -284.033722) (xy 97.513127 -284.060138)
			(xy 97.504712 -284.112296) (xy 97.4881 -284.162449) (xy 97.463716 -284.209318) (xy 97.44837 -284.230826)
			(xy 97.480978 -284.270766) (xy 97.538382 -284.356423) (xy 97.562924 -284.401768) (xy 97.569609 -284.413582)
			(xy 97.588109 -284.433433) (xy 97.611189 -284.447703) (xy 97.637216 -284.45538) (xy 97.664345 -284.455923)
			(xy 97.690657 -284.449291) (xy 97.714289 -284.435955) (xy 97.733568 -284.416859) (xy 97.740724 -284.405324)
			(xy 97.762314 -284.367986) (xy 97.78361 -284.332044) (xy 97.831558 -284.263621) (xy 97.858072 -284.231334)
			(xy 97.842659 -284.209783) (xy 97.818173 -284.1628) (xy 97.801491 -284.112514) (xy 97.793041 -284.060212)
			(xy 97.79254 -284.033722) (xy 97.793021 -284.007751) (xy 97.801143 -283.956449) (xy 97.817191 -283.907049)
			(xy 97.84077 -283.860768) (xy 97.871298 -283.818746) (xy 97.908024 -283.782016) (xy 97.950044 -283.751484)
			(xy 97.996323 -283.727902) (xy 98.045722 -283.71185) (xy 98.097023 -283.703723) (xy 98.122994 -283.703268)
			(xy 98.150483 -283.703821) (xy 98.204702 -283.71293) (xy 98.256667 -283.730883) (xy 98.304946 -283.757183)
			(xy 98.34821 -283.791107) (xy 98.385267 -283.831721) (xy 98.415096 -283.877904) (xy 98.426524 -283.902912)
			(xy 98.46784 -283.896057) (xy 98.55127 -283.888681) (xy 98.593148 -283.88818) (xy 98.634899 -283.888685)
			(xy 98.718076 -283.896059) (xy 98.759264 -283.902912) (xy 98.770645 -283.877879) (xy 98.800464 -283.831681)
			(xy 98.837521 -283.791058) (xy 98.880794 -283.757134) (xy 98.929088 -283.730844) (xy 98.981069 -283.712914)
			(xy 99.035301 -283.70384) (xy 99.062794 -283.703268) (xy 99.088763 -283.70375) (xy 99.140062 -283.711875)
			(xy 99.189457 -283.727924) (xy 99.235734 -283.751504) (xy 99.277753 -283.782033) (xy 99.314477 -283.81876)
			(xy 99.345004 -283.860779) (xy 99.368582 -283.907057) (xy 99.384629 -283.956454) (xy 99.392751 -284.007753)
			(xy 99.393248 -284.033722) (xy 99.392727 -284.060138) (xy 99.384312 -284.112296) (xy 99.3677 -284.162449)
			(xy 99.343316 -284.209318) (xy 99.32797 -284.230826) (xy 99.360578 -284.270766) (xy 99.417982 -284.356423)
			(xy 99.442524 -284.401768) (xy 99.449209 -284.413582) (xy 99.467709 -284.433433) (xy 99.490789 -284.447703)
			(xy 99.516816 -284.45538) (xy 99.543945 -284.455923) (xy 99.570257 -284.449291) (xy 99.593889 -284.435955)
			(xy 99.613168 -284.416859) (xy 99.620324 -284.405324) (xy 99.641914 -284.367986) (xy 99.66321 -284.332044)
			(xy 99.711158 -284.263621) (xy 99.737672 -284.231334) (xy 99.722259 -284.209783) (xy 99.697773 -284.1628)
			(xy 99.681091 -284.112514) (xy 99.672641 -284.060212) (xy 99.67214 -284.033722) (xy 99.672621 -284.007751)
			(xy 99.680743 -283.956449) (xy 99.696791 -283.907049) (xy 99.72037 -283.860768) (xy 99.750898 -283.818746)
			(xy 99.787624 -283.782016) (xy 99.829644 -283.751484) (xy 99.875923 -283.727902) (xy 99.925322 -283.71185)
			(xy 99.976623 -283.703723) (xy 100.002594 -283.703268) (xy 100.030083 -283.703821) (xy 100.084302 -283.71293)
			(xy 100.136267 -283.730883) (xy 100.184546 -283.757183) (xy 100.22781 -283.791107) (xy 100.264867 -283.831721)
			(xy 100.294696 -283.877904) (xy 100.306124 -283.902912) (xy 100.34744 -283.896057) (xy 100.43087 -283.888681)
			(xy 100.472748 -283.88818) (xy 100.514499 -283.888685) (xy 100.597676 -283.896059) (xy 100.638864 -283.902912)
			(xy 100.650245 -283.877879) (xy 100.680064 -283.831681) (xy 100.717121 -283.791058) (xy 100.760394 -283.757134)
			(xy 100.808688 -283.730844) (xy 100.860669 -283.712914) (xy 100.914901 -283.70384) (xy 100.942394 -283.703268)
			(xy 100.968363 -283.70375) (xy 101.019662 -283.711875) (xy 101.069057 -283.727924) (xy 101.115334 -283.751504)
			(xy 101.157353 -283.782033) (xy 101.194077 -283.81876) (xy 101.224604 -283.860779) (xy 101.248182 -283.907057)
			(xy 101.264229 -283.956454) (xy 101.272351 -284.007753) (xy 101.272848 -284.033722) (xy 101.272327 -284.060138)
			(xy 101.263912 -284.112296) (xy 101.2473 -284.162449) (xy 101.222916 -284.209318) (xy 101.20757 -284.230826)
			(xy 101.240178 -284.270766) (xy 101.297582 -284.356423) (xy 101.322124 -284.401768) (xy 101.328809 -284.413582)
			(xy 101.347309 -284.433433) (xy 101.370389 -284.447703) (xy 101.396416 -284.45538) (xy 101.423545 -284.455923)
			(xy 101.449857 -284.449291) (xy 101.473489 -284.435955) (xy 101.492768 -284.416859) (xy 101.499924 -284.405324)
			(xy 101.521514 -284.367986) (xy 101.54281 -284.332044) (xy 101.590758 -284.263621) (xy 101.617272 -284.231334)
			(xy 101.601859 -284.209783) (xy 101.577373 -284.1628) (xy 101.560691 -284.112514) (xy 101.552241 -284.060212)
			(xy 101.55174 -284.033722) (xy 101.552221 -284.007751) (xy 101.560343 -283.956449) (xy 101.576391 -283.907049)
			(xy 101.59997 -283.860768) (xy 101.630498 -283.818746) (xy 101.667224 -283.782016) (xy 101.709244 -283.751484)
			(xy 101.755523 -283.727902) (xy 101.804922 -283.71185) (xy 101.856223 -283.703723) (xy 101.882194 -283.703268)
			(xy 101.909683 -283.703821) (xy 101.963902 -283.71293) (xy 102.015867 -283.730883) (xy 102.064146 -283.757183)
			(xy 102.10741 -283.791107) (xy 102.144467 -283.831721) (xy 102.174296 -283.877904) (xy 102.185724 -283.902912)
			(xy 102.22704 -283.896057) (xy 102.31047 -283.888681) (xy 102.352348 -283.88818) (xy 102.394099 -283.888685)
			(xy 102.477276 -283.896059) (xy 102.518464 -283.902912) (xy 102.529845 -283.877879) (xy 102.559664 -283.831681)
			(xy 102.596721 -283.791058) (xy 102.639994 -283.757134) (xy 102.688288 -283.730844) (xy 102.740269 -283.712914)
			(xy 102.794501 -283.70384) (xy 102.821994 -283.703268) (xy 102.847963 -283.70375) (xy 102.899262 -283.711875)
			(xy 102.948657 -283.727924) (xy 102.994934 -283.751504) (xy 103.036953 -283.782033) (xy 103.073677 -283.81876)
			(xy 103.104204 -283.860779) (xy 103.127782 -283.907057) (xy 103.143829 -283.956454) (xy 103.151951 -284.007753)
			(xy 103.152448 -284.033722) (xy 103.151927 -284.060138) (xy 103.143512 -284.112296) (xy 103.1269 -284.162449)
			(xy 103.102516 -284.209318) (xy 103.08717 -284.230826) (xy 103.119778 -284.270766) (xy 103.177182 -284.356423)
			(xy 103.201724 -284.401768) (xy 103.208409 -284.413582) (xy 103.226909 -284.433433) (xy 103.249989 -284.447703)
			(xy 103.276016 -284.45538) (xy 103.303145 -284.455923) (xy 103.329457 -284.449291) (xy 103.353089 -284.435955)
			(xy 103.372368 -284.416859) (xy 103.379524 -284.405324) (xy 103.401114 -284.367986) (xy 103.422353 -284.332112)
			(xy 103.47017 -284.263813) (xy 103.496618 -284.231588) (xy 103.481237 -284.210056) (xy 103.45679 -284.163129)
			(xy 103.440109 -284.112913) (xy 103.431619 -284.060686) (xy 103.431086 -284.03423) (xy 103.431086 -284.033722)
			(xy 103.431567 -284.007731) (xy 103.439696 -283.95639) (xy 103.455756 -283.906952) (xy 103.479353 -283.860635)
			(xy 103.509904 -283.81858) (xy 103.546659 -283.781823) (xy 103.588711 -283.751267) (xy 103.635026 -283.727667)
			(xy 103.684463 -283.711602) (xy 103.735803 -283.70347) (xy 103.761794 -283.703014) (xy 103.77243 -283.703114)
			(xy 103.793655 -283.70451) (xy 103.804212 -283.705808) (xy 103.804466 -283.705808) (xy 103.81591 -283.7067)
			(xy 103.837608 -283.699284) (xy 103.846122 -283.691584) (xy 103.971344 -283.566362) (xy 103.977569 -283.559506)
			(xy 103.985009 -283.542566) (xy 103.985822 -283.533342) (xy 103.987092 -283.506926) (xy 103.98887 -283.463492)
			(xy 103.97744 -283.431742) (xy 103.97236 -283.425392) (xy 103.955631 -283.40332) (xy 103.929 -283.354763)
			(xy 103.910814 -283.302454) (xy 103.901579 -283.24785) (xy 103.900986 -283.22016) (xy 103.900986 -283.219906)
			(xy 103.901495 -283.193918) (xy 103.909625 -283.142583) (xy 103.925685 -283.093151) (xy 103.949281 -283.04684)
			(xy 103.97983 -283.004791) (xy 104.016582 -282.968038) (xy 104.05863 -282.937487) (xy 104.10494 -282.91389)
			(xy 104.154371 -282.897828) (xy 104.205706 -282.889696) (xy 104.231694 -282.889198) (xy 104.231948 -282.889198)
			(xy 104.259641 -282.889756) (xy 104.314254 -282.898977) (xy 104.366567 -282.91717) (xy 104.415116 -282.943826)
			(xy 104.43718 -282.960572) (xy 104.44353 -282.965652) (xy 104.47528 -282.977082) (xy 104.518714 -282.975304)
			(xy 104.54513 -282.974034) (xy 104.554346 -282.973188) (xy 104.571276 -282.965754) (xy 104.57815 -282.959556)
			(xy 104.628188 -282.909518) (xy 104.636291 -282.900262) (xy 104.643445 -282.876767) (xy 104.641904 -282.86456)
			(xy 104.621838 -282.779724) (xy 104.589072 -282.74391) (xy 104.5845 -282.742132) (xy 104.558371 -282.732465)
			(xy 104.509248 -282.706186) (xy 104.48671 -282.689808) (xy 104.463257 -282.671333) (xy 104.422276 -282.627922)
			(xy 104.405176 -282.603448) (xy 104.026716 -282.603448) (xy 104.010997 -282.623688) (xy 103.974366 -282.659524)
			(xy 103.932649 -282.689284) (xy 103.886843 -282.712259) (xy 103.838043 -282.727898) (xy 103.787416 -282.735827)
			(xy 103.761794 -282.73629) (xy 103.735824 -282.73578) (xy 103.684524 -282.727654) (xy 103.635127 -282.711603)
			(xy 103.588849 -282.688023) (xy 103.54683 -282.657493) (xy 103.510103 -282.620766) (xy 103.479574 -282.578746)
			(xy 103.455994 -282.532467) (xy 103.439944 -282.48307) (xy 103.431819 -282.43177) (xy 103.431819 -282.37983)
			(xy 103.439944 -282.32853) (xy 103.455994 -282.279133) (xy 103.479574 -282.232854) (xy 103.510103 -282.190834)
			(xy 103.54683 -282.154107) (xy 103.588849 -282.123577) (xy 103.635127 -282.099997) (xy 103.684524 -282.083946)
			(xy 103.735824 -282.07582) (xy 103.761794 -282.075382) (xy 103.787416 -282.075864) (xy 103.838048 -282.083772)
			(xy 103.886851 -282.0994) (xy 103.932658 -282.122373) (xy 103.974371 -282.152141) (xy 104.010989 -282.18799)
			(xy 104.026716 -282.208224) (xy 104.405176 -282.208224) (xy 104.419414 -282.187653) (xy 104.452735 -282.150337)
			(xy 104.490949 -282.118048) (xy 104.533305 -282.091424) (xy 104.578968 -282.070987) (xy 104.627042 -282.05714)
			(xy 104.67658 -282.050154) (xy 104.701594 -282.049728) (xy 104.729112 -282.05024) (xy 104.783493 -282.058708)
			(xy 104.835924 -282.075442) (xy 104.885156 -282.100044) (xy 104.930016 -282.131928) (xy 104.969435 -282.170335)
			(xy 105.002476 -282.21435) (xy 105.028351 -282.262925) (xy 105.03789 -282.288742) (xy 105.039668 -282.293314)
			(xy 105.075482 -282.32608) (xy 105.160318 -282.346146) (xy 105.172538 -282.347911) (xy 105.196127 -282.34072)
			(xy 105.205276 -282.33243) (xy 105.76687 -281.770836) (xy 105.773559 -281.763656) (xy 105.781175 -281.745586)
			(xy 105.781602 -281.735784) (xy 105.7783 -281.718004) (xy 105.776776 -281.71394) (xy 105.766818 -281.684514)
			(xy 105.756082 -281.623333) (xy 105.75544 -281.592274) (xy 105.75544 -281.59202) (xy 105.755959 -281.564035)
			(xy 105.764713 -281.508754) (xy 105.782007 -281.455523) (xy 105.807417 -281.405653) (xy 105.840316 -281.360373)
			(xy 105.879895 -281.320798) (xy 105.925177 -281.287903) (xy 105.975049 -281.262497) (xy 106.028281 -281.245206)
			(xy 106.083563 -281.236457) (xy 106.111548 -281.235912) (xy 106.111802 -281.235912) (xy 106.142861 -281.23656)
			(xy 106.204046 -281.247279) (xy 106.233468 -281.257248) (xy 106.237532 -281.258772) (xy 106.255312 -281.262074)
			(xy 106.265085 -281.261503) (xy 106.283112 -281.253919) (xy 106.290364 -281.247342) (xy 106.348276 -281.18943)
			(xy 106.354654 -281.182447) (xy 106.362102 -281.165082) (xy 106.362754 -281.155648) (xy 106.360722 -281.079702)
			(xy 106.344212 -281.044142) (xy 106.34345 -281.04338) (xy 106.32059 -281.021028) (xy 106.31085 -281.01037)
			(xy 106.29292 -280.987738) (xy 106.284776 -280.975816) (xy 105.906316 -280.975816) (xy 105.890598 -280.996057)
			(xy 105.853969 -281.031897) (xy 105.812252 -281.06166) (xy 105.766446 -281.084637) (xy 105.717645 -281.100277)
			(xy 105.667017 -281.108207) (xy 105.641394 -281.108658) (xy 105.615427 -281.108148) (xy 105.564132 -281.100023)
			(xy 105.514739 -281.083974) (xy 105.468466 -281.060395) (xy 105.42645 -281.029869) (xy 105.389727 -280.993145)
			(xy 105.359201 -280.951129) (xy 105.335624 -280.904855) (xy 105.319575 -280.855462) (xy 105.311451 -280.804167)
			(xy 105.311451 -280.752233) (xy 105.319575 -280.700938) (xy 105.335624 -280.651545) (xy 105.359201 -280.605271)
			(xy 105.389727 -280.563255) (xy 105.42645 -280.526531) (xy 105.468466 -280.496005) (xy 105.514739 -280.472426)
			(xy 105.564132 -280.456377) (xy 105.615427 -280.448252) (xy 105.641394 -280.44775) (xy 105.667016 -280.448232)
			(xy 105.717645 -280.456141) (xy 105.766447 -280.471771) (xy 105.812251 -280.494748) (xy 105.853959 -280.524519)
			(xy 105.890571 -280.560372) (xy 105.906316 -280.580592) (xy 106.284776 -280.580592) (xy 106.299015 -280.560023)
			(xy 106.332338 -280.522709) (xy 106.370553 -280.490424) (xy 106.412908 -280.463802) (xy 106.458571 -280.443367)
			(xy 106.506644 -280.429521) (xy 106.55618 -280.422536) (xy 106.581194 -280.422096) (xy 106.606129 -280.42252)
			(xy 106.655509 -280.429487) (xy 106.703435 -280.443272) (xy 106.748971 -280.463605) (xy 106.791227 -280.490089)
			(xy 106.829377 -280.522206) (xy 106.84637 -280.54046) (xy 106.847132 -280.541222) (xy 106.882692 -280.557732)
			(xy 106.958638 -280.559764) (xy 106.96806 -280.559068) (xy 106.985406 -280.551617) (xy 106.99242 -280.545286)
			(xy 107.676442 -279.861264) (xy 107.680252 -279.850596) (xy 107.688887 -279.82821) (xy 107.711692 -279.785996)
			(xy 107.740357 -279.747521) (xy 107.774282 -279.713591) (xy 107.812753 -279.684919) (xy 107.854963 -279.662108)
			(xy 107.877356 -279.653492) (xy 107.888024 -279.649682) (xy 108.044234 -279.493472) (xy 108.050942 -279.486232)
			(xy 108.058527 -279.468027) (xy 108.058966 -279.458166) (xy 108.058966 -278.79167) (xy 108.058596 -278.782714)
			(xy 108.052345 -278.765927) (xy 108.046774 -278.758904) (xy 107.998768 -278.707596) (xy 107.966002 -278.691848)
			(xy 107.957874 -278.690832) (xy 107.928817 -278.687559) (xy 107.872257 -278.672739) (xy 107.818884 -278.648865)
			(xy 107.770137 -278.61658) (xy 107.748324 -278.597106) (xy 107.728896 -278.578346) (xy 107.695373 -278.536006)
			(xy 107.668636 -278.489085) (xy 107.6493 -278.43866) (xy 107.637809 -278.385893) (xy 107.634427 -278.331994)
			(xy 107.639231 -278.278204) (xy 107.652113 -278.225758) (xy 107.661964 -278.200612) (xy 107.671616 -278.177498)
			(xy 107.483402 -277.851616) (xy 107.460288 -277.847298) (xy 107.435347 -277.842158) (xy 107.387321 -277.825233)
			(xy 107.342459 -277.801141) (xy 107.301825 -277.770452) (xy 107.26638 -277.733891) (xy 107.236964 -277.692326)
			(xy 107.214272 -277.64674) (xy 107.198843 -277.598213) (xy 107.191041 -277.547893) (xy 107.19054 -277.522432)
			(xy 107.191049 -277.496465) (xy 107.199174 -277.44517) (xy 107.215222 -277.395777) (xy 107.2388 -277.349503)
			(xy 107.269326 -277.307487) (xy 107.306049 -277.270764) (xy 107.348065 -277.240238) (xy 107.394339 -277.21666)
			(xy 107.443732 -277.200612) (xy 107.495027 -277.192487) (xy 107.546961 -277.192487) (xy 107.598256 -277.200612)
			(xy 107.647649 -277.21666) (xy 107.693923 -277.240238) (xy 107.735939 -277.270764) (xy 107.772662 -277.307487)
			(xy 107.803188 -277.349503) (xy 107.826766 -277.395777) (xy 107.842814 -277.44517) (xy 107.850939 -277.496465)
			(xy 107.851448 -277.522432) (xy 107.851448 -277.523194) (xy 107.850838 -277.55091) (xy 107.841515 -277.605554)
			(xy 107.832906 -277.631906) (xy 107.825032 -277.654004) (xy 107.869482 -277.730712) (xy 107.877331 -277.743262)
			(xy 107.898873 -277.763545) (xy 107.925325 -277.776804) (xy 107.954466 -277.781927) (xy 107.983853 -277.778485)
			(xy 108.011022 -277.766767) (xy 108.033693 -277.747755) (xy 108.049966 -277.723044) (xy 108.058476 -277.694706)
			(xy 108.058966 -277.679912) (xy 108.058966 -277.138384) (xy 108.058573 -277.128977) (xy 108.051644 -277.111487)
			(xy 108.045504 -277.104348) (xy 107.999276 -277.05431) (xy 107.96651 -277.038562) (xy 107.95762 -277.037546)
			(xy 107.932216 -277.034479) (xy 107.882716 -277.021518) (xy 107.835803 -277.001085) (xy 107.792599 -276.97367)
			(xy 107.754134 -276.939925) (xy 107.721326 -276.900658) (xy 107.694959 -276.856806) (xy 107.675662 -276.809415)
			(xy 107.663897 -276.759617) (xy 107.659944 -276.708602) (xy 107.663897 -276.657586) (xy 107.675661 -276.607788)
			(xy 107.694957 -276.560397) (xy 107.721324 -276.516544) (xy 107.754131 -276.477277) (xy 107.792596 -276.443532)
			(xy 107.835801 -276.416116) (xy 107.882713 -276.395684) (xy 107.932212 -276.382721) (xy 107.95762 -276.379686)
			(xy 107.96651 -276.37867) (xy 107.999276 -276.362922) (xy 108.045504 -276.312884) (xy 108.051613 -276.30573)
			(xy 108.058517 -276.288245) (xy 108.058966 -276.278848) (xy 108.058966 -275.593048) (xy 107.968796 -275.436838)
			(xy 107.951524 -275.434552) (xy 107.925591 -275.431187) (xy 107.875031 -275.417832) (xy 107.82697 -275.397223)
			(xy 107.782441 -275.369804) (xy 107.742402 -275.336166) (xy 107.707717 -275.297032) (xy 107.67913 -275.253243)
			(xy 107.657257 -275.205744) (xy 107.642569 -275.155556) (xy 107.635382 -275.103758) (xy 107.635851 -275.051467)
			(xy 107.643966 -274.999807) (xy 107.659551 -274.94989) (xy 107.682272 -274.90279) (xy 107.711639 -274.859522)
			(xy 107.747021 -274.821016) (xy 107.787657 -274.788101) (xy 107.83267 -274.761485) (xy 107.881093 -274.741741)
			(xy 107.931884 -274.729295) (xy 107.957874 -274.7264) (xy 107.966002 -274.725384) (xy 107.998768 -274.709636)
			(xy 108.046774 -274.658328) (xy 108.052356 -274.651313) (xy 108.058591 -274.63452) (xy 108.058966 -274.625562)
			(xy 108.058966 -274.028916) (xy 108.059504 -274.019079) (xy 108.06709 -274.000918) (xy 108.073698 -273.99361)
			(xy 108.432346 -273.634962) (xy 108.439587 -273.628257) (xy 108.457792 -273.620679) (xy 108.467652 -273.62023)
			(xy 108.479336 -273.62023) (xy 108.490113 -273.61971) (xy 108.50972 -273.610753) (xy 108.517182 -273.602958)
			(xy 108.550202 -273.564604) (xy 108.567982 -273.543776) (xy 108.573015 -273.536966) (xy 108.578615 -273.520996)
			(xy 108.578904 -273.512534) (xy 108.578396 -273.505168) (xy 108.578142 -273.503644) (xy 108.576467 -273.491139)
			(xy 108.574685 -273.465969) (xy 108.574586 -273.453352) (xy 108.574586 -273.453098) (xy 108.575084 -273.426449)
			(xy 108.583027 -273.373745) (xy 108.598737 -273.322815) (xy 108.621863 -273.274794) (xy 108.651887 -273.230757)
			(xy 108.688139 -273.191686) (xy 108.72981 -273.158455) (xy 108.775968 -273.131806) (xy 108.825582 -273.112334)
			(xy 108.877544 -273.100474) (xy 108.930694 -273.096491) (xy 108.983844 -273.100474) (xy 109.035806 -273.112334)
			(xy 109.08542 -273.131806) (xy 109.131578 -273.158455) (xy 109.173249 -273.191686) (xy 109.209501 -273.230757)
			(xy 109.239525 -273.274794) (xy 109.262651 -273.322815) (xy 109.278361 -273.373745) (xy 109.286304 -273.426449)
			(xy 109.286802 -273.453098) (xy 109.286802 -273.453352) (xy 109.28669 -273.465968) (xy 109.284913 -273.491138)
			(xy 109.283246 -273.503644) (xy 109.282992 -273.505168) (xy 109.282484 -273.512534) (xy 109.282814 -273.52099)
			(xy 109.288398 -273.536954) (xy 109.293406 -273.543776) (xy 109.311186 -273.564604) (xy 109.344206 -273.602958)
			(xy 109.35165 -273.610777) (xy 109.371268 -273.61974) (xy 109.382052 -273.62023) (xy 109.44479 -273.62023)
			(xy 109.455596 -273.619656) (xy 109.475219 -273.610583) (xy 109.482636 -273.602704) (xy 109.53242 -273.544792)
			(xy 109.537971 -273.537701) (xy 109.544074 -273.520774) (xy 109.544358 -273.511772) (xy 109.54385 -273.504406)
			(xy 109.541969 -273.491662) (xy 109.539938 -273.465979) (xy 109.539786 -273.453098) (xy 109.540296 -273.427111)
			(xy 109.548426 -273.375776) (xy 109.564487 -273.326346) (xy 109.588083 -273.280036) (xy 109.618633 -273.237988)
			(xy 109.655384 -273.201237) (xy 109.697432 -273.170687) (xy 109.743742 -273.147091) (xy 109.793172 -273.13103)
			(xy 109.844507 -273.1229) (xy 109.896481 -273.1229) (xy 109.947816 -273.13103) (xy 109.997246 -273.147091)
			(xy 110.043556 -273.170687) (xy 110.085604 -273.201237) (xy 110.122355 -273.237988) (xy 110.152905 -273.280036)
			(xy 110.176501 -273.326346) (xy 110.192562 -273.375776) (xy 110.200692 -273.427111) (xy 110.201202 -273.453098)
			(xy 110.201074 -273.46598) (xy 110.199043 -273.491665) (xy 110.197138 -273.504406) (xy 110.19663 -273.511772)
			(xy 110.19692 -273.520769) (xy 110.203044 -273.537683) (xy 110.208568 -273.544792) (xy 110.258352 -273.602704)
			(xy 110.265765 -273.610593) (xy 110.285387 -273.619683) (xy 110.296198 -273.62023) (xy 110.35919 -273.62023)
			(xy 110.369972 -273.619719) (xy 110.389592 -273.610774) (xy 110.397036 -273.602958) (xy 110.430056 -273.564604)
			(xy 110.447836 -273.543776) (xy 110.452864 -273.536964) (xy 110.458458 -273.520995) (xy 110.458758 -273.512534)
			(xy 110.45825 -273.505168) (xy 110.457996 -273.503644) (xy 110.456321 -273.491139) (xy 110.454539 -273.465969)
			(xy 110.45444 -273.453352) (xy 110.45444 -273.453098) (xy 110.454938 -273.426449) (xy 110.462881 -273.373745)
			(xy 110.478591 -273.322815) (xy 110.501717 -273.274794) (xy 110.531741 -273.230757) (xy 110.567993 -273.191686)
			(xy 110.609664 -273.158455) (xy 110.655822 -273.131806) (xy 110.705436 -273.112334) (xy 110.757398 -273.100474)
			(xy 110.810548 -273.096491) (xy 110.863698 -273.100474) (xy 110.91566 -273.112334) (xy 110.965274 -273.131806)
			(xy 111.011432 -273.158455) (xy 111.053103 -273.191686) (xy 111.089355 -273.230757) (xy 111.119379 -273.274794)
			(xy 111.142505 -273.322815) (xy 111.158215 -273.373745) (xy 111.166158 -273.426449) (xy 111.166656 -273.453098)
			(xy 111.166656 -273.453352) (xy 111.166544 -273.465968) (xy 111.164766 -273.491138) (xy 111.1631 -273.503644)
			(xy 111.162846 -273.505168) (xy 111.162338 -273.512534) (xy 111.162667 -273.520991) (xy 111.168247 -273.536958)
			(xy 111.17326 -273.543776) (xy 111.19104 -273.564604) (xy 111.22406 -273.602958) (xy 111.231508 -273.610768)
			(xy 111.251125 -273.61971) (xy 111.261906 -273.62023) (xy 111.298736 -273.62023) (xy 111.309513 -273.61971)
			(xy 111.32912 -273.610753) (xy 111.336582 -273.602958) (xy 111.369602 -273.564604) (xy 111.387382 -273.543776)
			(xy 111.392415 -273.536966) (xy 111.398015 -273.520996) (xy 111.398304 -273.512534) (xy 111.397796 -273.505168)
			(xy 111.397542 -273.503644) (xy 111.395867 -273.491139) (xy 111.394085 -273.465969) (xy 111.393986 -273.453352)
			(xy 111.393986 -273.453098) (xy 111.394535 -273.425115) (xy 111.40329 -273.369838) (xy 111.420585 -273.31661)
			(xy 111.445993 -273.266744) (xy 111.478889 -273.221466) (xy 111.518463 -273.181892) (xy 111.563741 -273.148995)
			(xy 111.613607 -273.123587) (xy 111.666834 -273.106291) (xy 111.722111 -273.097535) (xy 111.750094 -273.09699)
			(xy 111.775972 -273.097454) (xy 111.827182 -273.104947) (xy 111.876767 -273.119777) (xy 111.923683 -273.14163)
			(xy 111.96694 -273.170046) (xy 112.005626 -273.204426) (xy 112.038926 -273.244046) (xy 112.066139 -273.28807)
			(xy 112.08669 -273.33557) (xy 112.100146 -273.385546) (xy 112.103662 -273.411188) (xy 112.108996 -273.453098)
			(xy 112.356392 -273.453098) (xy 112.362488 -273.409156) (xy 112.366486 -273.383049) (xy 112.381699 -273.332477)
			(xy 112.404769 -273.284971) (xy 112.43511 -273.241744) (xy 112.471945 -273.2039) (xy 112.514336 -273.172403)
			(xy 112.561202 -273.148058) (xy 112.611345 -273.131485) (xy 112.663488 -273.123107) (xy 112.689894 -273.122644)
			(xy 112.715864 -273.123126) (xy 112.767164 -273.131251) (xy 112.816561 -273.1473) (xy 112.86284 -273.170879)
			(xy 112.90486 -273.201408) (xy 112.941587 -273.238134) (xy 112.972117 -273.280153) (xy 112.995697 -273.326431)
			(xy 113.011748 -273.375829) (xy 113.019873 -273.427128) (xy 113.020348 -273.453098) (xy 113.019813 -273.479065)
			(xy 113.299749 -273.479065) (xy 113.299749 -273.427131) (xy 113.307874 -273.375836) (xy 113.323922 -273.326443)
			(xy 113.3475 -273.280169) (xy 113.378026 -273.238153) (xy 113.414749 -273.20143) (xy 113.456765 -273.170904)
			(xy 113.503039 -273.147326) (xy 113.552432 -273.131278) (xy 113.603727 -273.123153) (xy 113.655661 -273.123153)
			(xy 113.706956 -273.131278) (xy 113.756349 -273.147326) (xy 113.802623 -273.170904) (xy 113.844639 -273.20143)
			(xy 113.881362 -273.238153) (xy 113.911888 -273.280169) (xy 113.935466 -273.326443) (xy 113.951514 -273.375836)
			(xy 113.959639 -273.427131) (xy 113.960148 -273.453098) (xy 113.959639 -273.479065) (xy 114.239549 -273.479065)
			(xy 114.239549 -273.427131) (xy 114.247674 -273.375836) (xy 114.263722 -273.326443) (xy 114.2873 -273.280169)
			(xy 114.317826 -273.238153) (xy 114.354549 -273.20143) (xy 114.396565 -273.170904) (xy 114.442839 -273.147326)
			(xy 114.492232 -273.131278) (xy 114.543527 -273.123153) (xy 114.595461 -273.123153) (xy 114.646756 -273.131278)
			(xy 114.696149 -273.147326) (xy 114.742423 -273.170904) (xy 114.784439 -273.20143) (xy 114.821162 -273.238153)
			(xy 114.851688 -273.280169) (xy 114.875266 -273.326443) (xy 114.891314 -273.375836) (xy 114.899439 -273.427131)
			(xy 114.899948 -273.453098) (xy 114.899439 -273.479065) (xy 115.179349 -273.479065) (xy 115.179349 -273.427131)
			(xy 115.187474 -273.375836) (xy 115.203522 -273.326443) (xy 115.2271 -273.280169) (xy 115.257626 -273.238153)
			(xy 115.294349 -273.20143) (xy 115.336365 -273.170904) (xy 115.382639 -273.147326) (xy 115.432032 -273.131278)
			(xy 115.483327 -273.123153) (xy 115.535261 -273.123153) (xy 115.586556 -273.131278) (xy 115.635949 -273.147326)
			(xy 115.682223 -273.170904) (xy 115.724239 -273.20143) (xy 115.760962 -273.238153) (xy 115.791488 -273.280169)
			(xy 115.815066 -273.326443) (xy 115.831114 -273.375836) (xy 115.839239 -273.427131) (xy 115.839748 -273.453098)
			(xy 115.839239 -273.479065) (xy 116.119403 -273.479065) (xy 116.119403 -273.427131) (xy 116.127528 -273.375836)
			(xy 116.143576 -273.326443) (xy 116.167154 -273.280169) (xy 116.19768 -273.238153) (xy 116.234403 -273.20143)
			(xy 116.276419 -273.170904) (xy 116.322693 -273.147326) (xy 116.372086 -273.131278) (xy 116.423381 -273.123153)
			(xy 116.475315 -273.123153) (xy 116.52661 -273.131278) (xy 116.576003 -273.147326) (xy 116.622277 -273.170904)
			(xy 116.664293 -273.20143) (xy 116.701016 -273.238153) (xy 116.731542 -273.280169) (xy 116.75512 -273.326443)
			(xy 116.771168 -273.375836) (xy 116.779293 -273.427131) (xy 116.779802 -273.453098) (xy 116.779293 -273.479065)
			(xy 117.059203 -273.479065) (xy 117.059203 -273.427131) (xy 117.067328 -273.375836) (xy 117.083376 -273.326443)
			(xy 117.106954 -273.280169) (xy 117.13748 -273.238153) (xy 117.174203 -273.20143) (xy 117.216219 -273.170904)
			(xy 117.262493 -273.147326) (xy 117.311886 -273.131278) (xy 117.363181 -273.123153) (xy 117.415115 -273.123153)
			(xy 117.46641 -273.131278) (xy 117.515803 -273.147326) (xy 117.562077 -273.170904) (xy 117.604093 -273.20143)
			(xy 117.640816 -273.238153) (xy 117.671342 -273.280169) (xy 117.69492 -273.326443) (xy 117.710968 -273.375836)
			(xy 117.719093 -273.427131) (xy 117.719602 -273.453098) (xy 117.719093 -273.479065) (xy 117.999003 -273.479065)
			(xy 117.999003 -273.427131) (xy 118.007128 -273.375836) (xy 118.023176 -273.326443) (xy 118.046754 -273.280169)
			(xy 118.07728 -273.238153) (xy 118.114003 -273.20143) (xy 118.156019 -273.170904) (xy 118.202293 -273.147326)
			(xy 118.251686 -273.131278) (xy 118.302981 -273.123153) (xy 118.354915 -273.123153) (xy 118.40621 -273.131278)
			(xy 118.455603 -273.147326) (xy 118.501877 -273.170904) (xy 118.543893 -273.20143) (xy 118.580616 -273.238153)
			(xy 118.611142 -273.280169) (xy 118.63472 -273.326443) (xy 118.650768 -273.375836) (xy 118.658893 -273.427131)
			(xy 118.659402 -273.453098) (xy 118.658893 -273.479065) (xy 118.938803 -273.479065) (xy 118.938803 -273.427131)
			(xy 118.946928 -273.375836) (xy 118.962976 -273.326443) (xy 118.986554 -273.280169) (xy 119.01708 -273.238153)
			(xy 119.053803 -273.20143) (xy 119.095819 -273.170904) (xy 119.142093 -273.147326) (xy 119.191486 -273.131278)
			(xy 119.242781 -273.123153) (xy 119.294715 -273.123153) (xy 119.34601 -273.131278) (xy 119.395403 -273.147326)
			(xy 119.441677 -273.170904) (xy 119.483693 -273.20143) (xy 119.520416 -273.238153) (xy 119.550942 -273.280169)
			(xy 119.57452 -273.326443) (xy 119.590568 -273.375836) (xy 119.598693 -273.427131) (xy 119.599202 -273.453098)
			(xy 119.598693 -273.479065) (xy 119.878603 -273.479065) (xy 119.878603 -273.427131) (xy 119.886728 -273.375836)
			(xy 119.902776 -273.326443) (xy 119.926354 -273.280169) (xy 119.95688 -273.238153) (xy 119.993603 -273.20143)
			(xy 120.035619 -273.170904) (xy 120.081893 -273.147326) (xy 120.131286 -273.131278) (xy 120.182581 -273.123153)
			(xy 120.234515 -273.123153) (xy 120.28581 -273.131278) (xy 120.335203 -273.147326) (xy 120.381477 -273.170904)
			(xy 120.423493 -273.20143) (xy 120.460216 -273.238153) (xy 120.490742 -273.280169) (xy 120.51432 -273.326443)
			(xy 120.530368 -273.375836) (xy 120.538493 -273.427131) (xy 120.539002 -273.453098) (xy 120.538493 -273.479065)
			(xy 120.818403 -273.479065) (xy 120.818403 -273.427131) (xy 120.826528 -273.375836) (xy 120.842576 -273.326443)
			(xy 120.866154 -273.280169) (xy 120.89668 -273.238153) (xy 120.933403 -273.20143) (xy 120.975419 -273.170904)
			(xy 121.021693 -273.147326) (xy 121.071086 -273.131278) (xy 121.122381 -273.123153) (xy 121.174315 -273.123153)
			(xy 121.22561 -273.131278) (xy 121.275003 -273.147326) (xy 121.321277 -273.170904) (xy 121.363293 -273.20143)
			(xy 121.400016 -273.238153) (xy 121.430542 -273.280169) (xy 121.45412 -273.326443) (xy 121.470168 -273.375836)
			(xy 121.478293 -273.427131) (xy 121.478802 -273.453098) (xy 121.478293 -273.479065) (xy 121.758203 -273.479065)
			(xy 121.758203 -273.427131) (xy 121.766328 -273.375836) (xy 121.782376 -273.326443) (xy 121.805954 -273.280169)
			(xy 121.83648 -273.238153) (xy 121.873203 -273.20143) (xy 121.915219 -273.170904) (xy 121.961493 -273.147326)
			(xy 122.010886 -273.131278) (xy 122.062181 -273.123153) (xy 122.114115 -273.123153) (xy 122.16541 -273.131278)
			(xy 122.214803 -273.147326) (xy 122.261077 -273.170904) (xy 122.303093 -273.20143) (xy 122.339816 -273.238153)
			(xy 122.370342 -273.280169) (xy 122.39392 -273.326443) (xy 122.409968 -273.375836) (xy 122.418093 -273.427131)
			(xy 122.418602 -273.453098) (xy 122.418093 -273.479065) (xy 122.697749 -273.479065) (xy 122.697749 -273.427131)
			(xy 122.705874 -273.375836) (xy 122.721922 -273.326443) (xy 122.7455 -273.280169) (xy 122.776026 -273.238153)
			(xy 122.812749 -273.20143) (xy 122.854765 -273.170904) (xy 122.901039 -273.147326) (xy 122.950432 -273.131278)
			(xy 123.001727 -273.123153) (xy 123.053661 -273.123153) (xy 123.104956 -273.131278) (xy 123.154349 -273.147326)
			(xy 123.200623 -273.170904) (xy 123.242639 -273.20143) (xy 123.279362 -273.238153) (xy 123.309888 -273.280169)
			(xy 123.333466 -273.326443) (xy 123.349514 -273.375836) (xy 123.357639 -273.427131) (xy 123.358148 -273.453098)
			(xy 123.357639 -273.479065) (xy 123.637803 -273.479065) (xy 123.637803 -273.427131) (xy 123.645928 -273.375836)
			(xy 123.661976 -273.326443) (xy 123.685554 -273.280169) (xy 123.71608 -273.238153) (xy 123.752803 -273.20143)
			(xy 123.794819 -273.170904) (xy 123.841093 -273.147326) (xy 123.890486 -273.131278) (xy 123.941781 -273.123153)
			(xy 123.993715 -273.123153) (xy 124.04501 -273.131278) (xy 124.094403 -273.147326) (xy 124.140677 -273.170904)
			(xy 124.182693 -273.20143) (xy 124.219416 -273.238153) (xy 124.249942 -273.280169) (xy 124.27352 -273.326443)
			(xy 124.289568 -273.375836) (xy 124.297693 -273.427131) (xy 124.298202 -273.453098) (xy 124.297693 -273.479065)
			(xy 124.577603 -273.479065) (xy 124.577603 -273.427131) (xy 124.585728 -273.375836) (xy 124.601776 -273.326443)
			(xy 124.625354 -273.280169) (xy 124.65588 -273.238153) (xy 124.692603 -273.20143) (xy 124.734619 -273.170904)
			(xy 124.780893 -273.147326) (xy 124.830286 -273.131278) (xy 124.881581 -273.123153) (xy 124.933515 -273.123153)
			(xy 124.98481 -273.131278) (xy 125.034203 -273.147326) (xy 125.080477 -273.170904) (xy 125.122493 -273.20143)
			(xy 125.159216 -273.238153) (xy 125.189742 -273.280169) (xy 125.21332 -273.326443) (xy 125.229368 -273.375836)
			(xy 125.237493 -273.427131) (xy 125.238002 -273.453098) (xy 125.237493 -273.479065) (xy 125.517403 -273.479065)
			(xy 125.517403 -273.427131) (xy 125.525528 -273.375836) (xy 125.541576 -273.326443) (xy 125.565154 -273.280169)
			(xy 125.59568 -273.238153) (xy 125.632403 -273.20143) (xy 125.674419 -273.170904) (xy 125.720693 -273.147326)
			(xy 125.770086 -273.131278) (xy 125.821381 -273.123153) (xy 125.873315 -273.123153) (xy 125.92461 -273.131278)
			(xy 125.974003 -273.147326) (xy 126.020277 -273.170904) (xy 126.062293 -273.20143) (xy 126.099016 -273.238153)
			(xy 126.129542 -273.280169) (xy 126.15312 -273.326443) (xy 126.169168 -273.375836) (xy 126.177293 -273.427131)
			(xy 126.177802 -273.453098) (xy 126.177293 -273.479065) (xy 126.457203 -273.479065) (xy 126.457203 -273.427131)
			(xy 126.465328 -273.375836) (xy 126.481376 -273.326443) (xy 126.504954 -273.280169) (xy 126.53548 -273.238153)
			(xy 126.572203 -273.20143) (xy 126.614219 -273.170904) (xy 126.660493 -273.147326) (xy 126.709886 -273.131278)
			(xy 126.761181 -273.123153) (xy 126.813115 -273.123153) (xy 126.86441 -273.131278) (xy 126.913803 -273.147326)
			(xy 126.960077 -273.170904) (xy 127.002093 -273.20143) (xy 127.038816 -273.238153) (xy 127.069342 -273.280169)
			(xy 127.09292 -273.326443) (xy 127.108968 -273.375836) (xy 127.117093 -273.427131) (xy 127.117602 -273.453098)
			(xy 127.117093 -273.479065) (xy 127.397003 -273.479065) (xy 127.397003 -273.427131) (xy 127.405128 -273.375836)
			(xy 127.421176 -273.326443) (xy 127.444754 -273.280169) (xy 127.47528 -273.238153) (xy 127.512003 -273.20143)
			(xy 127.554019 -273.170904) (xy 127.600293 -273.147326) (xy 127.649686 -273.131278) (xy 127.700981 -273.123153)
			(xy 127.752915 -273.123153) (xy 127.80421 -273.131278) (xy 127.853603 -273.147326) (xy 127.899877 -273.170904)
			(xy 127.941893 -273.20143) (xy 127.978616 -273.238153) (xy 128.009142 -273.280169) (xy 128.03272 -273.326443)
			(xy 128.048768 -273.375836) (xy 128.056893 -273.427131) (xy 128.057402 -273.453098) (xy 128.056893 -273.479065)
			(xy 128.336803 -273.479065) (xy 128.336803 -273.427131) (xy 128.344928 -273.375836) (xy 128.360976 -273.326443)
			(xy 128.384554 -273.280169) (xy 128.41508 -273.238153) (xy 128.451803 -273.20143) (xy 128.493819 -273.170904)
			(xy 128.540093 -273.147326) (xy 128.589486 -273.131278) (xy 128.640781 -273.123153) (xy 128.692715 -273.123153)
			(xy 128.74401 -273.131278) (xy 128.793403 -273.147326) (xy 128.839677 -273.170904) (xy 128.881693 -273.20143)
			(xy 128.918416 -273.238153) (xy 128.948942 -273.280169) (xy 128.97252 -273.326443) (xy 128.988568 -273.375836)
			(xy 128.996693 -273.427131) (xy 128.997202 -273.453098) (xy 128.996693 -273.479065) (xy 129.276603 -273.479065)
			(xy 129.276603 -273.427131) (xy 129.284728 -273.375836) (xy 129.300776 -273.326443) (xy 129.324354 -273.280169)
			(xy 129.35488 -273.238153) (xy 129.391603 -273.20143) (xy 129.433619 -273.170904) (xy 129.479893 -273.147326)
			(xy 129.529286 -273.131278) (xy 129.580581 -273.123153) (xy 129.632515 -273.123153) (xy 129.68381 -273.131278)
			(xy 129.733203 -273.147326) (xy 129.779477 -273.170904) (xy 129.821493 -273.20143) (xy 129.858216 -273.238153)
			(xy 129.888742 -273.280169) (xy 129.91232 -273.326443) (xy 129.928368 -273.375836) (xy 129.936493 -273.427131)
			(xy 129.937002 -273.453098) (xy 129.936493 -273.479065) (xy 130.216403 -273.479065) (xy 130.216403 -273.427131)
			(xy 130.224528 -273.375836) (xy 130.240576 -273.326443) (xy 130.264154 -273.280169) (xy 130.29468 -273.238153)
			(xy 130.331403 -273.20143) (xy 130.373419 -273.170904) (xy 130.419693 -273.147326) (xy 130.469086 -273.131278)
			(xy 130.520381 -273.123153) (xy 130.572315 -273.123153) (xy 130.62361 -273.131278) (xy 130.673003 -273.147326)
			(xy 130.719277 -273.170904) (xy 130.761293 -273.20143) (xy 130.798016 -273.238153) (xy 130.828542 -273.280169)
			(xy 130.85212 -273.326443) (xy 130.868168 -273.375836) (xy 130.876293 -273.427131) (xy 130.876802 -273.453098)
			(xy 130.876293 -273.479065) (xy 130.868168 -273.53036) (xy 130.85212 -273.579753) (xy 130.828542 -273.626027)
			(xy 130.798016 -273.668043) (xy 130.761293 -273.704766) (xy 130.719277 -273.735292) (xy 130.673003 -273.75887)
			(xy 130.62361 -273.774918) (xy 130.572315 -273.783043) (xy 130.520381 -273.783043) (xy 130.469086 -273.774918)
			(xy 130.419693 -273.75887) (xy 130.373419 -273.735292) (xy 130.331403 -273.704766) (xy 130.29468 -273.668043)
			(xy 130.264154 -273.626027) (xy 130.240576 -273.579753) (xy 130.224528 -273.53036) (xy 130.216403 -273.479065)
			(xy 129.936493 -273.479065) (xy 129.928368 -273.53036) (xy 129.91232 -273.579753) (xy 129.888742 -273.626027)
			(xy 129.858216 -273.668043) (xy 129.821493 -273.704766) (xy 129.779477 -273.735292) (xy 129.733203 -273.75887)
			(xy 129.68381 -273.774918) (xy 129.632515 -273.783043) (xy 129.580581 -273.783043) (xy 129.529286 -273.774918)
			(xy 129.479893 -273.75887) (xy 129.433619 -273.735292) (xy 129.391603 -273.704766) (xy 129.35488 -273.668043)
			(xy 129.324354 -273.626027) (xy 129.300776 -273.579753) (xy 129.284728 -273.53036) (xy 129.276603 -273.479065)
			(xy 128.996693 -273.479065) (xy 128.988568 -273.53036) (xy 128.97252 -273.579753) (xy 128.948942 -273.626027)
			(xy 128.918416 -273.668043) (xy 128.881693 -273.704766) (xy 128.839677 -273.735292) (xy 128.793403 -273.75887)
			(xy 128.74401 -273.774918) (xy 128.692715 -273.783043) (xy 128.640781 -273.783043) (xy 128.589486 -273.774918)
			(xy 128.540093 -273.75887) (xy 128.493819 -273.735292) (xy 128.451803 -273.704766) (xy 128.41508 -273.668043)
			(xy 128.384554 -273.626027) (xy 128.360976 -273.579753) (xy 128.344928 -273.53036) (xy 128.336803 -273.479065)
			(xy 128.056893 -273.479065) (xy 128.048768 -273.53036) (xy 128.03272 -273.579753) (xy 128.009142 -273.626027)
			(xy 127.978616 -273.668043) (xy 127.941893 -273.704766) (xy 127.899877 -273.735292) (xy 127.853603 -273.75887)
			(xy 127.80421 -273.774918) (xy 127.752915 -273.783043) (xy 127.700981 -273.783043) (xy 127.649686 -273.774918)
			(xy 127.600293 -273.75887) (xy 127.554019 -273.735292) (xy 127.512003 -273.704766) (xy 127.47528 -273.668043)
			(xy 127.444754 -273.626027) (xy 127.421176 -273.579753) (xy 127.405128 -273.53036) (xy 127.397003 -273.479065)
			(xy 127.117093 -273.479065) (xy 127.108968 -273.53036) (xy 127.09292 -273.579753) (xy 127.069342 -273.626027)
			(xy 127.038816 -273.668043) (xy 127.002093 -273.704766) (xy 126.960077 -273.735292) (xy 126.913803 -273.75887)
			(xy 126.86441 -273.774918) (xy 126.813115 -273.783043) (xy 126.761181 -273.783043) (xy 126.709886 -273.774918)
			(xy 126.660493 -273.75887) (xy 126.614219 -273.735292) (xy 126.572203 -273.704766) (xy 126.53548 -273.668043)
			(xy 126.504954 -273.626027) (xy 126.481376 -273.579753) (xy 126.465328 -273.53036) (xy 126.457203 -273.479065)
			(xy 126.177293 -273.479065) (xy 126.169168 -273.53036) (xy 126.15312 -273.579753) (xy 126.129542 -273.626027)
			(xy 126.099016 -273.668043) (xy 126.062293 -273.704766) (xy 126.020277 -273.735292) (xy 125.974003 -273.75887)
			(xy 125.92461 -273.774918) (xy 125.873315 -273.783043) (xy 125.821381 -273.783043) (xy 125.770086 -273.774918)
			(xy 125.720693 -273.75887) (xy 125.674419 -273.735292) (xy 125.632403 -273.704766) (xy 125.59568 -273.668043)
			(xy 125.565154 -273.626027) (xy 125.541576 -273.579753) (xy 125.525528 -273.53036) (xy 125.517403 -273.479065)
			(xy 125.237493 -273.479065) (xy 125.229368 -273.53036) (xy 125.21332 -273.579753) (xy 125.189742 -273.626027)
			(xy 125.159216 -273.668043) (xy 125.122493 -273.704766) (xy 125.080477 -273.735292) (xy 125.034203 -273.75887)
			(xy 124.98481 -273.774918) (xy 124.933515 -273.783043) (xy 124.881581 -273.783043) (xy 124.830286 -273.774918)
			(xy 124.780893 -273.75887) (xy 124.734619 -273.735292) (xy 124.692603 -273.704766) (xy 124.65588 -273.668043)
			(xy 124.625354 -273.626027) (xy 124.601776 -273.579753) (xy 124.585728 -273.53036) (xy 124.577603 -273.479065)
			(xy 124.297693 -273.479065) (xy 124.289568 -273.53036) (xy 124.27352 -273.579753) (xy 124.249942 -273.626027)
			(xy 124.219416 -273.668043) (xy 124.182693 -273.704766) (xy 124.140677 -273.735292) (xy 124.094403 -273.75887)
			(xy 124.04501 -273.774918) (xy 123.993715 -273.783043) (xy 123.941781 -273.783043) (xy 123.890486 -273.774918)
			(xy 123.841093 -273.75887) (xy 123.794819 -273.735292) (xy 123.752803 -273.704766) (xy 123.71608 -273.668043)
			(xy 123.685554 -273.626027) (xy 123.661976 -273.579753) (xy 123.645928 -273.53036) (xy 123.637803 -273.479065)
			(xy 123.357639 -273.479065) (xy 123.349514 -273.53036) (xy 123.333466 -273.579753) (xy 123.309888 -273.626027)
			(xy 123.279362 -273.668043) (xy 123.242639 -273.704766) (xy 123.200623 -273.735292) (xy 123.154349 -273.75887)
			(xy 123.104956 -273.774918) (xy 123.053661 -273.783043) (xy 123.001727 -273.783043) (xy 122.950432 -273.774918)
			(xy 122.901039 -273.75887) (xy 122.854765 -273.735292) (xy 122.812749 -273.704766) (xy 122.776026 -273.668043)
			(xy 122.7455 -273.626027) (xy 122.721922 -273.579753) (xy 122.705874 -273.53036) (xy 122.697749 -273.479065)
			(xy 122.418093 -273.479065) (xy 122.409968 -273.53036) (xy 122.39392 -273.579753) (xy 122.370342 -273.626027)
			(xy 122.339816 -273.668043) (xy 122.303093 -273.704766) (xy 122.261077 -273.735292) (xy 122.214803 -273.75887)
			(xy 122.16541 -273.774918) (xy 122.114115 -273.783043) (xy 122.062181 -273.783043) (xy 122.010886 -273.774918)
			(xy 121.961493 -273.75887) (xy 121.915219 -273.735292) (xy 121.873203 -273.704766) (xy 121.83648 -273.668043)
			(xy 121.805954 -273.626027) (xy 121.782376 -273.579753) (xy 121.766328 -273.53036) (xy 121.758203 -273.479065)
			(xy 121.478293 -273.479065) (xy 121.470168 -273.53036) (xy 121.45412 -273.579753) (xy 121.430542 -273.626027)
			(xy 121.400016 -273.668043) (xy 121.363293 -273.704766) (xy 121.321277 -273.735292) (xy 121.275003 -273.75887)
			(xy 121.22561 -273.774918) (xy 121.174315 -273.783043) (xy 121.122381 -273.783043) (xy 121.071086 -273.774918)
			(xy 121.021693 -273.75887) (xy 120.975419 -273.735292) (xy 120.933403 -273.704766) (xy 120.89668 -273.668043)
			(xy 120.866154 -273.626027) (xy 120.842576 -273.579753) (xy 120.826528 -273.53036) (xy 120.818403 -273.479065)
			(xy 120.538493 -273.479065) (xy 120.530368 -273.53036) (xy 120.51432 -273.579753) (xy 120.490742 -273.626027)
			(xy 120.460216 -273.668043) (xy 120.423493 -273.704766) (xy 120.381477 -273.735292) (xy 120.335203 -273.75887)
			(xy 120.28581 -273.774918) (xy 120.234515 -273.783043) (xy 120.182581 -273.783043) (xy 120.131286 -273.774918)
			(xy 120.081893 -273.75887) (xy 120.035619 -273.735292) (xy 119.993603 -273.704766) (xy 119.95688 -273.668043)
			(xy 119.926354 -273.626027) (xy 119.902776 -273.579753) (xy 119.886728 -273.53036) (xy 119.878603 -273.479065)
			(xy 119.598693 -273.479065) (xy 119.590568 -273.53036) (xy 119.57452 -273.579753) (xy 119.550942 -273.626027)
			(xy 119.520416 -273.668043) (xy 119.483693 -273.704766) (xy 119.441677 -273.735292) (xy 119.395403 -273.75887)
			(xy 119.34601 -273.774918) (xy 119.294715 -273.783043) (xy 119.242781 -273.783043) (xy 119.191486 -273.774918)
			(xy 119.142093 -273.75887) (xy 119.095819 -273.735292) (xy 119.053803 -273.704766) (xy 119.01708 -273.668043)
			(xy 118.986554 -273.626027) (xy 118.962976 -273.579753) (xy 118.946928 -273.53036) (xy 118.938803 -273.479065)
			(xy 118.658893 -273.479065) (xy 118.650768 -273.53036) (xy 118.63472 -273.579753) (xy 118.611142 -273.626027)
			(xy 118.580616 -273.668043) (xy 118.543893 -273.704766) (xy 118.501877 -273.735292) (xy 118.455603 -273.75887)
			(xy 118.40621 -273.774918) (xy 118.354915 -273.783043) (xy 118.302981 -273.783043) (xy 118.251686 -273.774918)
			(xy 118.202293 -273.75887) (xy 118.156019 -273.735292) (xy 118.114003 -273.704766) (xy 118.07728 -273.668043)
			(xy 118.046754 -273.626027) (xy 118.023176 -273.579753) (xy 118.007128 -273.53036) (xy 117.999003 -273.479065)
			(xy 117.719093 -273.479065) (xy 117.710968 -273.53036) (xy 117.69492 -273.579753) (xy 117.671342 -273.626027)
			(xy 117.640816 -273.668043) (xy 117.604093 -273.704766) (xy 117.562077 -273.735292) (xy 117.515803 -273.75887)
			(xy 117.46641 -273.774918) (xy 117.415115 -273.783043) (xy 117.363181 -273.783043) (xy 117.311886 -273.774918)
			(xy 117.262493 -273.75887) (xy 117.216219 -273.735292) (xy 117.174203 -273.704766) (xy 117.13748 -273.668043)
			(xy 117.106954 -273.626027) (xy 117.083376 -273.579753) (xy 117.067328 -273.53036) (xy 117.059203 -273.479065)
			(xy 116.779293 -273.479065) (xy 116.771168 -273.53036) (xy 116.75512 -273.579753) (xy 116.731542 -273.626027)
			(xy 116.701016 -273.668043) (xy 116.664293 -273.704766) (xy 116.622277 -273.735292) (xy 116.576003 -273.75887)
			(xy 116.52661 -273.774918) (xy 116.475315 -273.783043) (xy 116.423381 -273.783043) (xy 116.372086 -273.774918)
			(xy 116.322693 -273.75887) (xy 116.276419 -273.735292) (xy 116.234403 -273.704766) (xy 116.19768 -273.668043)
			(xy 116.167154 -273.626027) (xy 116.143576 -273.579753) (xy 116.127528 -273.53036) (xy 116.119403 -273.479065)
			(xy 115.839239 -273.479065) (xy 115.831114 -273.53036) (xy 115.815066 -273.579753) (xy 115.791488 -273.626027)
			(xy 115.760962 -273.668043) (xy 115.724239 -273.704766) (xy 115.682223 -273.735292) (xy 115.635949 -273.75887)
			(xy 115.586556 -273.774918) (xy 115.535261 -273.783043) (xy 115.483327 -273.783043) (xy 115.432032 -273.774918)
			(xy 115.382639 -273.75887) (xy 115.336365 -273.735292) (xy 115.294349 -273.704766) (xy 115.257626 -273.668043)
			(xy 115.2271 -273.626027) (xy 115.203522 -273.579753) (xy 115.187474 -273.53036) (xy 115.179349 -273.479065)
			(xy 114.899439 -273.479065) (xy 114.891314 -273.53036) (xy 114.875266 -273.579753) (xy 114.851688 -273.626027)
			(xy 114.821162 -273.668043) (xy 114.784439 -273.704766) (xy 114.742423 -273.735292) (xy 114.696149 -273.75887)
			(xy 114.646756 -273.774918) (xy 114.595461 -273.783043) (xy 114.543527 -273.783043) (xy 114.492232 -273.774918)
			(xy 114.442839 -273.75887) (xy 114.396565 -273.735292) (xy 114.354549 -273.704766) (xy 114.317826 -273.668043)
			(xy 114.2873 -273.626027) (xy 114.263722 -273.579753) (xy 114.247674 -273.53036) (xy 114.239549 -273.479065)
			(xy 113.959639 -273.479065) (xy 113.951514 -273.53036) (xy 113.935466 -273.579753) (xy 113.911888 -273.626027)
			(xy 113.881362 -273.668043) (xy 113.844639 -273.704766) (xy 113.802623 -273.735292) (xy 113.756349 -273.75887)
			(xy 113.706956 -273.774918) (xy 113.655661 -273.783043) (xy 113.603727 -273.783043) (xy 113.552432 -273.774918)
			(xy 113.503039 -273.75887) (xy 113.456765 -273.735292) (xy 113.414749 -273.704766) (xy 113.378026 -273.668043)
			(xy 113.3475 -273.626027) (xy 113.323922 -273.579753) (xy 113.307874 -273.53036) (xy 113.299749 -273.479065)
			(xy 113.019813 -273.479065) (xy 113.019802 -273.479581) (xy 113.011316 -273.531865) (xy 112.994608 -273.582128)
			(xy 112.970105 -273.629088) (xy 112.938434 -273.671544) (xy 112.919764 -273.690334) (xy 112.91951 -273.690588)
			(xy 112.883442 -273.72691) (xy 113.097818 -273.941286) (xy 113.122202 -273.938492) (xy 113.131569 -273.937515)
			(xy 113.150376 -273.936497) (xy 113.159794 -273.93646) (xy 113.185763 -273.936942) (xy 113.237062 -273.945067)
			(xy 113.286459 -273.961116) (xy 113.332736 -273.984696) (xy 113.374755 -274.015225) (xy 113.411481 -274.051951)
			(xy 113.442008 -274.093971) (xy 113.465587 -274.140249) (xy 113.481635 -274.189646) (xy 113.489758 -274.240945)
			(xy 113.490248 -274.266914) (xy 113.49021 -274.276332) (xy 113.489313 -274.292881) (xy 113.769649 -274.292881)
			(xy 113.769649 -274.240947) (xy 113.777774 -274.189652) (xy 113.793822 -274.140259) (xy 113.8174 -274.093985)
			(xy 113.847926 -274.051969) (xy 113.884649 -274.015246) (xy 113.926665 -273.98472) (xy 113.972939 -273.961142)
			(xy 114.022332 -273.945094) (xy 114.073627 -273.936969) (xy 114.125561 -273.936969) (xy 114.176856 -273.945094)
			(xy 114.226249 -273.961142) (xy 114.272523 -273.98472) (xy 114.314539 -274.015246) (xy 114.351262 -274.051969)
			(xy 114.381788 -274.093985) (xy 114.405366 -274.140259) (xy 114.421414 -274.189652) (xy 114.429539 -274.240947)
			(xy 114.430048 -274.266914) (xy 114.429539 -274.292881) (xy 114.709449 -274.292881) (xy 114.709449 -274.240947)
			(xy 114.717574 -274.189652) (xy 114.733622 -274.140259) (xy 114.7572 -274.093985) (xy 114.787726 -274.051969)
			(xy 114.824449 -274.015246) (xy 114.866465 -273.98472) (xy 114.912739 -273.961142) (xy 114.962132 -273.945094)
			(xy 115.013427 -273.936969) (xy 115.065361 -273.936969) (xy 115.116656 -273.945094) (xy 115.166049 -273.961142)
			(xy 115.212323 -273.98472) (xy 115.254339 -274.015246) (xy 115.291062 -274.051969) (xy 115.321588 -274.093985)
			(xy 115.345166 -274.140259) (xy 115.361214 -274.189652) (xy 115.369339 -274.240947) (xy 115.369848 -274.266914)
			(xy 115.369339 -274.292881) (xy 115.649503 -274.292881) (xy 115.649503 -274.240947) (xy 115.657628 -274.189652)
			(xy 115.673676 -274.140259) (xy 115.697254 -274.093985) (xy 115.72778 -274.051969) (xy 115.764503 -274.015246)
			(xy 115.806519 -273.98472) (xy 115.852793 -273.961142) (xy 115.902186 -273.945094) (xy 115.953481 -273.936969)
			(xy 116.005415 -273.936969) (xy 116.05671 -273.945094) (xy 116.106103 -273.961142) (xy 116.152377 -273.98472)
			(xy 116.194393 -274.015246) (xy 116.231116 -274.051969) (xy 116.261642 -274.093985) (xy 116.28522 -274.140259)
			(xy 116.301268 -274.189652) (xy 116.309393 -274.240947) (xy 116.309902 -274.266914) (xy 116.309393 -274.292881)
			(xy 116.589303 -274.292881) (xy 116.589303 -274.240947) (xy 116.597428 -274.189652) (xy 116.613476 -274.140259)
			(xy 116.637054 -274.093985) (xy 116.66758 -274.051969) (xy 116.704303 -274.015246) (xy 116.746319 -273.98472)
			(xy 116.792593 -273.961142) (xy 116.841986 -273.945094) (xy 116.893281 -273.936969) (xy 116.945215 -273.936969)
			(xy 116.99651 -273.945094) (xy 117.045903 -273.961142) (xy 117.092177 -273.98472) (xy 117.134193 -274.015246)
			(xy 117.170916 -274.051969) (xy 117.201442 -274.093985) (xy 117.22502 -274.140259) (xy 117.241068 -274.189652)
			(xy 117.249193 -274.240947) (xy 117.249702 -274.266914) (xy 117.249193 -274.292881) (xy 117.529103 -274.292881)
			(xy 117.529103 -274.240947) (xy 117.537228 -274.189652) (xy 117.553276 -274.140259) (xy 117.576854 -274.093985)
			(xy 117.60738 -274.051969) (xy 117.644103 -274.015246) (xy 117.686119 -273.98472) (xy 117.732393 -273.961142)
			(xy 117.781786 -273.945094) (xy 117.833081 -273.936969) (xy 117.885015 -273.936969) (xy 117.93631 -273.945094)
			(xy 117.985703 -273.961142) (xy 118.031977 -273.98472) (xy 118.073993 -274.015246) (xy 118.110716 -274.051969)
			(xy 118.141242 -274.093985) (xy 118.16482 -274.140259) (xy 118.180868 -274.189652) (xy 118.188993 -274.240947)
			(xy 118.189502 -274.266914) (xy 118.188993 -274.292881) (xy 118.468649 -274.292881) (xy 118.468649 -274.240947)
			(xy 118.476774 -274.189652) (xy 118.492822 -274.140259) (xy 118.5164 -274.093985) (xy 118.546926 -274.051969)
			(xy 118.583649 -274.015246) (xy 118.625665 -273.98472) (xy 118.671939 -273.961142) (xy 118.721332 -273.945094)
			(xy 118.772627 -273.936969) (xy 118.824561 -273.936969) (xy 118.875856 -273.945094) (xy 118.925249 -273.961142)
			(xy 118.971523 -273.98472) (xy 119.013539 -274.015246) (xy 119.050262 -274.051969) (xy 119.080788 -274.093985)
			(xy 119.104366 -274.140259) (xy 119.120414 -274.189652) (xy 119.128539 -274.240947) (xy 119.129048 -274.266914)
			(xy 119.128539 -274.292881) (xy 119.408449 -274.292881) (xy 119.408449 -274.240947) (xy 119.416574 -274.189652)
			(xy 119.432622 -274.140259) (xy 119.4562 -274.093985) (xy 119.486726 -274.051969) (xy 119.523449 -274.015246)
			(xy 119.565465 -273.98472) (xy 119.611739 -273.961142) (xy 119.661132 -273.945094) (xy 119.712427 -273.936969)
			(xy 119.764361 -273.936969) (xy 119.815656 -273.945094) (xy 119.865049 -273.961142) (xy 119.911323 -273.98472)
			(xy 119.953339 -274.015246) (xy 119.990062 -274.051969) (xy 120.020588 -274.093985) (xy 120.044166 -274.140259)
			(xy 120.060214 -274.189652) (xy 120.068339 -274.240947) (xy 120.068848 -274.266914) (xy 120.068339 -274.292881)
			(xy 120.348249 -274.292881) (xy 120.348249 -274.240947) (xy 120.356374 -274.189652) (xy 120.372422 -274.140259)
			(xy 120.396 -274.093985) (xy 120.426526 -274.051969) (xy 120.463249 -274.015246) (xy 120.505265 -273.98472)
			(xy 120.551539 -273.961142) (xy 120.600932 -273.945094) (xy 120.652227 -273.936969) (xy 120.704161 -273.936969)
			(xy 120.755456 -273.945094) (xy 120.804849 -273.961142) (xy 120.851123 -273.98472) (xy 120.893139 -274.015246)
			(xy 120.929862 -274.051969) (xy 120.960388 -274.093985) (xy 120.983966 -274.140259) (xy 121.000014 -274.189652)
			(xy 121.008139 -274.240947) (xy 121.008648 -274.266914) (xy 121.008139 -274.292881) (xy 121.288303 -274.292881)
			(xy 121.288303 -274.240947) (xy 121.296428 -274.189652) (xy 121.312476 -274.140259) (xy 121.336054 -274.093985)
			(xy 121.36658 -274.051969) (xy 121.403303 -274.015246) (xy 121.445319 -273.98472) (xy 121.491593 -273.961142)
			(xy 121.540986 -273.945094) (xy 121.592281 -273.936969) (xy 121.644215 -273.936969) (xy 121.69551 -273.945094)
			(xy 121.744903 -273.961142) (xy 121.791177 -273.98472) (xy 121.833193 -274.015246) (xy 121.869916 -274.051969)
			(xy 121.900442 -274.093985) (xy 121.92402 -274.140259) (xy 121.940068 -274.189652) (xy 121.948193 -274.240947)
			(xy 121.948702 -274.266914) (xy 121.948193 -274.292881) (xy 122.227849 -274.292881) (xy 122.227849 -274.240947)
			(xy 122.235974 -274.189652) (xy 122.252022 -274.140259) (xy 122.2756 -274.093985) (xy 122.306126 -274.051969)
			(xy 122.342849 -274.015246) (xy 122.384865 -273.98472) (xy 122.431139 -273.961142) (xy 122.480532 -273.945094)
			(xy 122.531827 -273.936969) (xy 122.583761 -273.936969) (xy 122.635056 -273.945094) (xy 122.684449 -273.961142)
			(xy 122.730723 -273.98472) (xy 122.772739 -274.015246) (xy 122.809462 -274.051969) (xy 122.839988 -274.093985)
			(xy 122.863566 -274.140259) (xy 122.879614 -274.189652) (xy 122.887739 -274.240947) (xy 122.888248 -274.266914)
			(xy 122.887739 -274.292881) (xy 123.167649 -274.292881) (xy 123.167649 -274.240947) (xy 123.175774 -274.189652)
			(xy 123.191822 -274.140259) (xy 123.2154 -274.093985) (xy 123.245926 -274.051969) (xy 123.282649 -274.015246)
			(xy 123.324665 -273.98472) (xy 123.370939 -273.961142) (xy 123.420332 -273.945094) (xy 123.471627 -273.936969)
			(xy 123.523561 -273.936969) (xy 123.574856 -273.945094) (xy 123.624249 -273.961142) (xy 123.670523 -273.98472)
			(xy 123.712539 -274.015246) (xy 123.749262 -274.051969) (xy 123.779788 -274.093985) (xy 123.803366 -274.140259)
			(xy 123.819414 -274.189652) (xy 123.827539 -274.240947) (xy 123.828048 -274.266914) (xy 123.827539 -274.292881)
			(xy 124.107449 -274.292881) (xy 124.107449 -274.240947) (xy 124.115574 -274.189652) (xy 124.131622 -274.140259)
			(xy 124.1552 -274.093985) (xy 124.185726 -274.051969) (xy 124.222449 -274.015246) (xy 124.264465 -273.98472)
			(xy 124.310739 -273.961142) (xy 124.360132 -273.945094) (xy 124.411427 -273.936969) (xy 124.463361 -273.936969)
			(xy 124.514656 -273.945094) (xy 124.564049 -273.961142) (xy 124.610323 -273.98472) (xy 124.652339 -274.015246)
			(xy 124.689062 -274.051969) (xy 124.719588 -274.093985) (xy 124.743166 -274.140259) (xy 124.759214 -274.189652)
			(xy 124.767339 -274.240947) (xy 124.767848 -274.266914) (xy 124.767339 -274.292881) (xy 125.047249 -274.292881)
			(xy 125.047249 -274.240947) (xy 125.055374 -274.189652) (xy 125.071422 -274.140259) (xy 125.095 -274.093985)
			(xy 125.125526 -274.051969) (xy 125.162249 -274.015246) (xy 125.204265 -273.98472) (xy 125.250539 -273.961142)
			(xy 125.299932 -273.945094) (xy 125.351227 -273.936969) (xy 125.403161 -273.936969) (xy 125.454456 -273.945094)
			(xy 125.503849 -273.961142) (xy 125.550123 -273.98472) (xy 125.592139 -274.015246) (xy 125.628862 -274.051969)
			(xy 125.659388 -274.093985) (xy 125.682966 -274.140259) (xy 125.699014 -274.189652) (xy 125.707139 -274.240947)
			(xy 125.707648 -274.266914) (xy 125.707139 -274.292881) (xy 125.987303 -274.292881) (xy 125.987303 -274.240947)
			(xy 125.995428 -274.189652) (xy 126.011476 -274.140259) (xy 126.035054 -274.093985) (xy 126.06558 -274.051969)
			(xy 126.102303 -274.015246) (xy 126.144319 -273.98472) (xy 126.190593 -273.961142) (xy 126.239986 -273.945094)
			(xy 126.291281 -273.936969) (xy 126.343215 -273.936969) (xy 126.39451 -273.945094) (xy 126.443903 -273.961142)
			(xy 126.490177 -273.98472) (xy 126.532193 -274.015246) (xy 126.568916 -274.051969) (xy 126.599442 -274.093985)
			(xy 126.62302 -274.140259) (xy 126.639068 -274.189652) (xy 126.647193 -274.240947) (xy 126.647702 -274.266914)
			(xy 126.647193 -274.292881) (xy 126.926849 -274.292881) (xy 126.926849 -274.240947) (xy 126.934974 -274.189652)
			(xy 126.951022 -274.140259) (xy 126.9746 -274.093985) (xy 127.005126 -274.051969) (xy 127.041849 -274.015246)
			(xy 127.083865 -273.98472) (xy 127.130139 -273.961142) (xy 127.179532 -273.945094) (xy 127.230827 -273.936969)
			(xy 127.282761 -273.936969) (xy 127.334056 -273.945094) (xy 127.383449 -273.961142) (xy 127.429723 -273.98472)
			(xy 127.471739 -274.015246) (xy 127.508462 -274.051969) (xy 127.538988 -274.093985) (xy 127.562566 -274.140259)
			(xy 127.578614 -274.189652) (xy 127.586739 -274.240947) (xy 127.587248 -274.266914) (xy 127.586739 -274.292881)
			(xy 127.866649 -274.292881) (xy 127.866649 -274.240947) (xy 127.874774 -274.189652) (xy 127.890822 -274.140259)
			(xy 127.9144 -274.093985) (xy 127.944926 -274.051969) (xy 127.981649 -274.015246) (xy 128.023665 -273.98472)
			(xy 128.069939 -273.961142) (xy 128.119332 -273.945094) (xy 128.170627 -273.936969) (xy 128.222561 -273.936969)
			(xy 128.273856 -273.945094) (xy 128.323249 -273.961142) (xy 128.369523 -273.98472) (xy 128.411539 -274.015246)
			(xy 128.448262 -274.051969) (xy 128.478788 -274.093985) (xy 128.502366 -274.140259) (xy 128.518414 -274.189652)
			(xy 128.526539 -274.240947) (xy 128.527048 -274.266914) (xy 128.526539 -274.292881) (xy 128.806449 -274.292881)
			(xy 128.806449 -274.240947) (xy 128.814574 -274.189652) (xy 128.830622 -274.140259) (xy 128.8542 -274.093985)
			(xy 128.884726 -274.051969) (xy 128.921449 -274.015246) (xy 128.963465 -273.98472) (xy 129.009739 -273.961142)
			(xy 129.059132 -273.945094) (xy 129.110427 -273.936969) (xy 129.162361 -273.936969) (xy 129.213656 -273.945094)
			(xy 129.263049 -273.961142) (xy 129.309323 -273.98472) (xy 129.351339 -274.015246) (xy 129.388062 -274.051969)
			(xy 129.418588 -274.093985) (xy 129.442166 -274.140259) (xy 129.458214 -274.189652) (xy 129.466339 -274.240947)
			(xy 129.466848 -274.266914) (xy 129.466339 -274.292881) (xy 129.746249 -274.292881) (xy 129.746249 -274.240947)
			(xy 129.754374 -274.189652) (xy 129.770422 -274.140259) (xy 129.794 -274.093985) (xy 129.824526 -274.051969)
			(xy 129.861249 -274.015246) (xy 129.903265 -273.98472) (xy 129.949539 -273.961142) (xy 129.998932 -273.945094)
			(xy 130.050227 -273.936969) (xy 130.102161 -273.936969) (xy 130.153456 -273.945094) (xy 130.202849 -273.961142)
			(xy 130.249123 -273.98472) (xy 130.291139 -274.015246) (xy 130.327862 -274.051969) (xy 130.358388 -274.093985)
			(xy 130.381966 -274.140259) (xy 130.398014 -274.189652) (xy 130.406139 -274.240947) (xy 130.406648 -274.266914)
			(xy 130.406139 -274.292881) (xy 130.686049 -274.292881) (xy 130.686049 -274.240947) (xy 130.694174 -274.189652)
			(xy 130.710222 -274.140259) (xy 130.7338 -274.093985) (xy 130.764326 -274.051969) (xy 130.801049 -274.015246)
			(xy 130.843065 -273.98472) (xy 130.889339 -273.961142) (xy 130.938732 -273.945094) (xy 130.990027 -273.936969)
			(xy 131.041961 -273.936969) (xy 131.093256 -273.945094) (xy 131.142649 -273.961142) (xy 131.188923 -273.98472)
			(xy 131.230939 -274.015246) (xy 131.267662 -274.051969) (xy 131.298188 -274.093985) (xy 131.321766 -274.140259)
			(xy 131.337814 -274.189652) (xy 131.345939 -274.240947) (xy 131.346448 -274.266914) (xy 131.345939 -274.292881)
			(xy 131.337814 -274.344176) (xy 131.321766 -274.393569) (xy 131.298188 -274.439843) (xy 131.267662 -274.481859)
			(xy 131.230939 -274.518582) (xy 131.188923 -274.549108) (xy 131.142649 -274.572686) (xy 131.093256 -274.588734)
			(xy 131.041961 -274.596859) (xy 130.990027 -274.596859) (xy 130.938732 -274.588734) (xy 130.889339 -274.572686)
			(xy 130.843065 -274.549108) (xy 130.801049 -274.518582) (xy 130.764326 -274.481859) (xy 130.7338 -274.439843)
			(xy 130.710222 -274.393569) (xy 130.694174 -274.344176) (xy 130.686049 -274.292881) (xy 130.406139 -274.292881)
			(xy 130.398014 -274.344176) (xy 130.381966 -274.393569) (xy 130.358388 -274.439843) (xy 130.327862 -274.481859)
			(xy 130.291139 -274.518582) (xy 130.249123 -274.549108) (xy 130.202849 -274.572686) (xy 130.153456 -274.588734)
			(xy 130.102161 -274.596859) (xy 130.050227 -274.596859) (xy 129.998932 -274.588734) (xy 129.949539 -274.572686)
			(xy 129.903265 -274.549108) (xy 129.861249 -274.518582) (xy 129.824526 -274.481859) (xy 129.794 -274.439843)
			(xy 129.770422 -274.393569) (xy 129.754374 -274.344176) (xy 129.746249 -274.292881) (xy 129.466339 -274.292881)
			(xy 129.458214 -274.344176) (xy 129.442166 -274.393569) (xy 129.418588 -274.439843) (xy 129.388062 -274.481859)
			(xy 129.351339 -274.518582) (xy 129.309323 -274.549108) (xy 129.263049 -274.572686) (xy 129.213656 -274.588734)
			(xy 129.162361 -274.596859) (xy 129.110427 -274.596859) (xy 129.059132 -274.588734) (xy 129.009739 -274.572686)
			(xy 128.963465 -274.549108) (xy 128.921449 -274.518582) (xy 128.884726 -274.481859) (xy 128.8542 -274.439843)
			(xy 128.830622 -274.393569) (xy 128.814574 -274.344176) (xy 128.806449 -274.292881) (xy 128.526539 -274.292881)
			(xy 128.518414 -274.344176) (xy 128.502366 -274.393569) (xy 128.478788 -274.439843) (xy 128.448262 -274.481859)
			(xy 128.411539 -274.518582) (xy 128.369523 -274.549108) (xy 128.323249 -274.572686) (xy 128.273856 -274.588734)
			(xy 128.222561 -274.596859) (xy 128.170627 -274.596859) (xy 128.119332 -274.588734) (xy 128.069939 -274.572686)
			(xy 128.023665 -274.549108) (xy 127.981649 -274.518582) (xy 127.944926 -274.481859) (xy 127.9144 -274.439843)
			(xy 127.890822 -274.393569) (xy 127.874774 -274.344176) (xy 127.866649 -274.292881) (xy 127.586739 -274.292881)
			(xy 127.578614 -274.344176) (xy 127.562566 -274.393569) (xy 127.538988 -274.439843) (xy 127.508462 -274.481859)
			(xy 127.471739 -274.518582) (xy 127.429723 -274.549108) (xy 127.383449 -274.572686) (xy 127.334056 -274.588734)
			(xy 127.282761 -274.596859) (xy 127.230827 -274.596859) (xy 127.179532 -274.588734) (xy 127.130139 -274.572686)
			(xy 127.083865 -274.549108) (xy 127.041849 -274.518582) (xy 127.005126 -274.481859) (xy 126.9746 -274.439843)
			(xy 126.951022 -274.393569) (xy 126.934974 -274.344176) (xy 126.926849 -274.292881) (xy 126.647193 -274.292881)
			(xy 126.639068 -274.344176) (xy 126.62302 -274.393569) (xy 126.599442 -274.439843) (xy 126.568916 -274.481859)
			(xy 126.532193 -274.518582) (xy 126.490177 -274.549108) (xy 126.443903 -274.572686) (xy 126.39451 -274.588734)
			(xy 126.343215 -274.596859) (xy 126.291281 -274.596859) (xy 126.239986 -274.588734) (xy 126.190593 -274.572686)
			(xy 126.144319 -274.549108) (xy 126.102303 -274.518582) (xy 126.06558 -274.481859) (xy 126.035054 -274.439843)
			(xy 126.011476 -274.393569) (xy 125.995428 -274.344176) (xy 125.987303 -274.292881) (xy 125.707139 -274.292881)
			(xy 125.699014 -274.344176) (xy 125.682966 -274.393569) (xy 125.659388 -274.439843) (xy 125.628862 -274.481859)
			(xy 125.592139 -274.518582) (xy 125.550123 -274.549108) (xy 125.503849 -274.572686) (xy 125.454456 -274.588734)
			(xy 125.403161 -274.596859) (xy 125.351227 -274.596859) (xy 125.299932 -274.588734) (xy 125.250539 -274.572686)
			(xy 125.204265 -274.549108) (xy 125.162249 -274.518582) (xy 125.125526 -274.481859) (xy 125.095 -274.439843)
			(xy 125.071422 -274.393569) (xy 125.055374 -274.344176) (xy 125.047249 -274.292881) (xy 124.767339 -274.292881)
			(xy 124.759214 -274.344176) (xy 124.743166 -274.393569) (xy 124.719588 -274.439843) (xy 124.689062 -274.481859)
			(xy 124.652339 -274.518582) (xy 124.610323 -274.549108) (xy 124.564049 -274.572686) (xy 124.514656 -274.588734)
			(xy 124.463361 -274.596859) (xy 124.411427 -274.596859) (xy 124.360132 -274.588734) (xy 124.310739 -274.572686)
			(xy 124.264465 -274.549108) (xy 124.222449 -274.518582) (xy 124.185726 -274.481859) (xy 124.1552 -274.439843)
			(xy 124.131622 -274.393569) (xy 124.115574 -274.344176) (xy 124.107449 -274.292881) (xy 123.827539 -274.292881)
			(xy 123.819414 -274.344176) (xy 123.803366 -274.393569) (xy 123.779788 -274.439843) (xy 123.749262 -274.481859)
			(xy 123.712539 -274.518582) (xy 123.670523 -274.549108) (xy 123.624249 -274.572686) (xy 123.574856 -274.588734)
			(xy 123.523561 -274.596859) (xy 123.471627 -274.596859) (xy 123.420332 -274.588734) (xy 123.370939 -274.572686)
			(xy 123.324665 -274.549108) (xy 123.282649 -274.518582) (xy 123.245926 -274.481859) (xy 123.2154 -274.439843)
			(xy 123.191822 -274.393569) (xy 123.175774 -274.344176) (xy 123.167649 -274.292881) (xy 122.887739 -274.292881)
			(xy 122.879614 -274.344176) (xy 122.863566 -274.393569) (xy 122.839988 -274.439843) (xy 122.809462 -274.481859)
			(xy 122.772739 -274.518582) (xy 122.730723 -274.549108) (xy 122.684449 -274.572686) (xy 122.635056 -274.588734)
			(xy 122.583761 -274.596859) (xy 122.531827 -274.596859) (xy 122.480532 -274.588734) (xy 122.431139 -274.572686)
			(xy 122.384865 -274.549108) (xy 122.342849 -274.518582) (xy 122.306126 -274.481859) (xy 122.2756 -274.439843)
			(xy 122.252022 -274.393569) (xy 122.235974 -274.344176) (xy 122.227849 -274.292881) (xy 121.948193 -274.292881)
			(xy 121.940068 -274.344176) (xy 121.92402 -274.393569) (xy 121.900442 -274.439843) (xy 121.869916 -274.481859)
			(xy 121.833193 -274.518582) (xy 121.791177 -274.549108) (xy 121.744903 -274.572686) (xy 121.69551 -274.588734)
			(xy 121.644215 -274.596859) (xy 121.592281 -274.596859) (xy 121.540986 -274.588734) (xy 121.491593 -274.572686)
			(xy 121.445319 -274.549108) (xy 121.403303 -274.518582) (xy 121.36658 -274.481859) (xy 121.336054 -274.439843)
			(xy 121.312476 -274.393569) (xy 121.296428 -274.344176) (xy 121.288303 -274.292881) (xy 121.008139 -274.292881)
			(xy 121.000014 -274.344176) (xy 120.983966 -274.393569) (xy 120.960388 -274.439843) (xy 120.929862 -274.481859)
			(xy 120.893139 -274.518582) (xy 120.851123 -274.549108) (xy 120.804849 -274.572686) (xy 120.755456 -274.588734)
			(xy 120.704161 -274.596859) (xy 120.652227 -274.596859) (xy 120.600932 -274.588734) (xy 120.551539 -274.572686)
			(xy 120.505265 -274.549108) (xy 120.463249 -274.518582) (xy 120.426526 -274.481859) (xy 120.396 -274.439843)
			(xy 120.372422 -274.393569) (xy 120.356374 -274.344176) (xy 120.348249 -274.292881) (xy 120.068339 -274.292881)
			(xy 120.060214 -274.344176) (xy 120.044166 -274.393569) (xy 120.020588 -274.439843) (xy 119.990062 -274.481859)
			(xy 119.953339 -274.518582) (xy 119.911323 -274.549108) (xy 119.865049 -274.572686) (xy 119.815656 -274.588734)
			(xy 119.764361 -274.596859) (xy 119.712427 -274.596859) (xy 119.661132 -274.588734) (xy 119.611739 -274.572686)
			(xy 119.565465 -274.549108) (xy 119.523449 -274.518582) (xy 119.486726 -274.481859) (xy 119.4562 -274.439843)
			(xy 119.432622 -274.393569) (xy 119.416574 -274.344176) (xy 119.408449 -274.292881) (xy 119.128539 -274.292881)
			(xy 119.120414 -274.344176) (xy 119.104366 -274.393569) (xy 119.080788 -274.439843) (xy 119.050262 -274.481859)
			(xy 119.013539 -274.518582) (xy 118.971523 -274.549108) (xy 118.925249 -274.572686) (xy 118.875856 -274.588734)
			(xy 118.824561 -274.596859) (xy 118.772627 -274.596859) (xy 118.721332 -274.588734) (xy 118.671939 -274.572686)
			(xy 118.625665 -274.549108) (xy 118.583649 -274.518582) (xy 118.546926 -274.481859) (xy 118.5164 -274.439843)
			(xy 118.492822 -274.393569) (xy 118.476774 -274.344176) (xy 118.468649 -274.292881) (xy 118.188993 -274.292881)
			(xy 118.180868 -274.344176) (xy 118.16482 -274.393569) (xy 118.141242 -274.439843) (xy 118.110716 -274.481859)
			(xy 118.073993 -274.518582) (xy 118.031977 -274.549108) (xy 117.985703 -274.572686) (xy 117.93631 -274.588734)
			(xy 117.885015 -274.596859) (xy 117.833081 -274.596859) (xy 117.781786 -274.588734) (xy 117.732393 -274.572686)
			(xy 117.686119 -274.549108) (xy 117.644103 -274.518582) (xy 117.60738 -274.481859) (xy 117.576854 -274.439843)
			(xy 117.553276 -274.393569) (xy 117.537228 -274.344176) (xy 117.529103 -274.292881) (xy 117.249193 -274.292881)
			(xy 117.241068 -274.344176) (xy 117.22502 -274.393569) (xy 117.201442 -274.439843) (xy 117.170916 -274.481859)
			(xy 117.134193 -274.518582) (xy 117.092177 -274.549108) (xy 117.045903 -274.572686) (xy 116.99651 -274.588734)
			(xy 116.945215 -274.596859) (xy 116.893281 -274.596859) (xy 116.841986 -274.588734) (xy 116.792593 -274.572686)
			(xy 116.746319 -274.549108) (xy 116.704303 -274.518582) (xy 116.66758 -274.481859) (xy 116.637054 -274.439843)
			(xy 116.613476 -274.393569) (xy 116.597428 -274.344176) (xy 116.589303 -274.292881) (xy 116.309393 -274.292881)
			(xy 116.301268 -274.344176) (xy 116.28522 -274.393569) (xy 116.261642 -274.439843) (xy 116.231116 -274.481859)
			(xy 116.194393 -274.518582) (xy 116.152377 -274.549108) (xy 116.106103 -274.572686) (xy 116.05671 -274.588734)
			(xy 116.005415 -274.596859) (xy 115.953481 -274.596859) (xy 115.902186 -274.588734) (xy 115.852793 -274.572686)
			(xy 115.806519 -274.549108) (xy 115.764503 -274.518582) (xy 115.72778 -274.481859) (xy 115.697254 -274.439843)
			(xy 115.673676 -274.393569) (xy 115.657628 -274.344176) (xy 115.649503 -274.292881) (xy 115.369339 -274.292881)
			(xy 115.361214 -274.344176) (xy 115.345166 -274.393569) (xy 115.321588 -274.439843) (xy 115.291062 -274.481859)
			(xy 115.254339 -274.518582) (xy 115.212323 -274.549108) (xy 115.166049 -274.572686) (xy 115.116656 -274.588734)
			(xy 115.065361 -274.596859) (xy 115.013427 -274.596859) (xy 114.962132 -274.588734) (xy 114.912739 -274.572686)
			(xy 114.866465 -274.549108) (xy 114.824449 -274.518582) (xy 114.787726 -274.481859) (xy 114.7572 -274.439843)
			(xy 114.733622 -274.393569) (xy 114.717574 -274.344176) (xy 114.709449 -274.292881) (xy 114.429539 -274.292881)
			(xy 114.421414 -274.344176) (xy 114.405366 -274.393569) (xy 114.381788 -274.439843) (xy 114.351262 -274.481859)
			(xy 114.314539 -274.518582) (xy 114.272523 -274.549108) (xy 114.226249 -274.572686) (xy 114.176856 -274.588734)
			(xy 114.125561 -274.596859) (xy 114.073627 -274.596859) (xy 114.022332 -274.588734) (xy 113.972939 -274.572686)
			(xy 113.926665 -274.549108) (xy 113.884649 -274.518582) (xy 113.847926 -274.481859) (xy 113.8174 -274.439843)
			(xy 113.793822 -274.393569) (xy 113.777774 -274.344176) (xy 113.769649 -274.292881) (xy 113.489313 -274.292881)
			(xy 113.489191 -274.295139) (xy 113.488216 -274.304506) (xy 113.485422 -274.32889) (xy 114.112548 -274.956016)
			(xy 114.122542 -274.965396) (xy 114.146362 -274.978937) (xy 114.172927 -274.985648) (xy 114.20032 -274.985045)
			(xy 114.226563 -274.977172) (xy 114.249765 -274.962597) (xy 114.268249 -274.942372) (xy 114.274854 -274.930362)
			(xy 114.287127 -274.907499) (xy 114.317694 -274.86557) (xy 114.354432 -274.828928) (xy 114.396441 -274.798471)
			(xy 114.442691 -274.774948) (xy 114.492046 -274.758934) (xy 114.543296 -274.750823) (xy 114.56924 -274.750276)
			(xy 114.595204 -274.750788) (xy 114.646493 -274.758918) (xy 114.695878 -274.77497) (xy 114.742144 -274.798551)
			(xy 114.784152 -274.829078) (xy 114.820867 -274.865801) (xy 114.851386 -274.907816) (xy 114.874957 -274.954087)
			(xy 114.890999 -275.003475) (xy 114.899117 -275.054766) (xy 114.899694 -275.08073) (xy 114.899192 -275.106679)
			(xy 114.899189 -275.106697) (xy 115.179095 -275.106697) (xy 115.179095 -275.054763) (xy 115.18722 -275.003468)
			(xy 115.203268 -274.954075) (xy 115.226846 -274.907801) (xy 115.257372 -274.865785) (xy 115.294095 -274.829062)
			(xy 115.336111 -274.798536) (xy 115.382385 -274.774958) (xy 115.431778 -274.75891) (xy 115.483073 -274.750785)
			(xy 115.535007 -274.750785) (xy 115.586302 -274.75891) (xy 115.635695 -274.774958) (xy 115.681969 -274.798536)
			(xy 115.723985 -274.829062) (xy 115.760708 -274.865785) (xy 115.791234 -274.907801) (xy 115.814812 -274.954075)
			(xy 115.83086 -275.003468) (xy 115.838985 -275.054763) (xy 115.839494 -275.08073) (xy 115.838985 -275.106697)
			(xy 116.119149 -275.106697) (xy 116.119149 -275.054763) (xy 116.127274 -275.003468) (xy 116.143322 -274.954075)
			(xy 116.1669 -274.907801) (xy 116.197426 -274.865785) (xy 116.234149 -274.829062) (xy 116.276165 -274.798536)
			(xy 116.322439 -274.774958) (xy 116.371832 -274.75891) (xy 116.423127 -274.750785) (xy 116.475061 -274.750785)
			(xy 116.526356 -274.75891) (xy 116.575749 -274.774958) (xy 116.622023 -274.798536) (xy 116.664039 -274.829062)
			(xy 116.700762 -274.865785) (xy 116.731288 -274.907801) (xy 116.754866 -274.954075) (xy 116.770914 -275.003468)
			(xy 116.779039 -275.054763) (xy 116.779548 -275.08073) (xy 116.779039 -275.106697) (xy 119.878603 -275.106697)
			(xy 119.878603 -275.054763) (xy 119.886728 -275.003468) (xy 119.902776 -274.954075) (xy 119.926354 -274.907801)
			(xy 119.95688 -274.865785) (xy 119.993603 -274.829062) (xy 120.035619 -274.798536) (xy 120.081893 -274.774958)
			(xy 120.131286 -274.75891) (xy 120.182581 -274.750785) (xy 120.234515 -274.750785) (xy 120.28581 -274.75891)
			(xy 120.335203 -274.774958) (xy 120.381477 -274.798536) (xy 120.423493 -274.829062) (xy 120.460216 -274.865785)
			(xy 120.490742 -274.907801) (xy 120.51432 -274.954075) (xy 120.530368 -275.003468) (xy 120.538493 -275.054763)
			(xy 120.539002 -275.08073) (xy 120.538498 -275.106443) (xy 120.818149 -275.106443) (xy 120.818149 -275.054509)
			(xy 120.826274 -275.003214) (xy 120.842322 -274.953821) (xy 120.8659 -274.907547) (xy 120.896426 -274.865531)
			(xy 120.933149 -274.828808) (xy 120.975165 -274.798282) (xy 121.021439 -274.774704) (xy 121.070832 -274.758656)
			(xy 121.122127 -274.750531) (xy 121.174061 -274.750531) (xy 121.225356 -274.758656) (xy 121.274749 -274.774704)
			(xy 121.321023 -274.798282) (xy 121.363039 -274.828808) (xy 121.399762 -274.865531) (xy 121.430288 -274.907547)
			(xy 121.453866 -274.953821) (xy 121.469914 -275.003214) (xy 121.478039 -275.054509) (xy 121.478548 -275.080476)
			(xy 121.478039 -275.106443) (xy 121.477999 -275.106697) (xy 121.758203 -275.106697) (xy 121.758203 -275.054763)
			(xy 121.766328 -275.003468) (xy 121.782376 -274.954075) (xy 121.805954 -274.907801) (xy 121.83648 -274.865785)
			(xy 121.873203 -274.829062) (xy 121.915219 -274.798536) (xy 121.961493 -274.774958) (xy 122.010886 -274.75891)
			(xy 122.062181 -274.750785) (xy 122.114115 -274.750785) (xy 122.16541 -274.75891) (xy 122.214803 -274.774958)
			(xy 122.261077 -274.798536) (xy 122.303093 -274.829062) (xy 122.339816 -274.865785) (xy 122.370342 -274.907801)
			(xy 122.39392 -274.954075) (xy 122.409968 -275.003468) (xy 122.418093 -275.054763) (xy 122.418602 -275.08073)
			(xy 122.418093 -275.106697) (xy 122.698003 -275.106697) (xy 122.698003 -275.054763) (xy 122.706128 -275.003468)
			(xy 122.722176 -274.954075) (xy 122.745754 -274.907801) (xy 122.77628 -274.865785) (xy 122.813003 -274.829062)
			(xy 122.855019 -274.798536) (xy 122.901293 -274.774958) (xy 122.950686 -274.75891) (xy 123.001981 -274.750785)
			(xy 123.053915 -274.750785) (xy 123.10521 -274.75891) (xy 123.154603 -274.774958) (xy 123.200877 -274.798536)
			(xy 123.242893 -274.829062) (xy 123.279616 -274.865785) (xy 123.310142 -274.907801) (xy 123.33372 -274.954075)
			(xy 123.349768 -275.003468) (xy 123.357893 -275.054763) (xy 123.358402 -275.08073) (xy 123.357893 -275.106697)
			(xy 123.637803 -275.106697) (xy 123.637803 -275.054763) (xy 123.645928 -275.003468) (xy 123.661976 -274.954075)
			(xy 123.685554 -274.907801) (xy 123.71608 -274.865785) (xy 123.752803 -274.829062) (xy 123.794819 -274.798536)
			(xy 123.841093 -274.774958) (xy 123.890486 -274.75891) (xy 123.941781 -274.750785) (xy 123.993715 -274.750785)
			(xy 124.04501 -274.75891) (xy 124.094403 -274.774958) (xy 124.140677 -274.798536) (xy 124.182693 -274.829062)
			(xy 124.219416 -274.865785) (xy 124.249942 -274.907801) (xy 124.27352 -274.954075) (xy 124.289568 -275.003468)
			(xy 124.297693 -275.054763) (xy 124.298202 -275.08073) (xy 124.297693 -275.106697) (xy 124.577603 -275.106697)
			(xy 124.577603 -275.054763) (xy 124.585728 -275.003468) (xy 124.601776 -274.954075) (xy 124.625354 -274.907801)
			(xy 124.65588 -274.865785) (xy 124.692603 -274.829062) (xy 124.734619 -274.798536) (xy 124.780893 -274.774958)
			(xy 124.830286 -274.75891) (xy 124.881581 -274.750785) (xy 124.933515 -274.750785) (xy 124.98481 -274.75891)
			(xy 125.034203 -274.774958) (xy 125.080477 -274.798536) (xy 125.122493 -274.829062) (xy 125.159216 -274.865785)
			(xy 125.189742 -274.907801) (xy 125.21332 -274.954075) (xy 125.229368 -275.003468) (xy 125.237493 -275.054763)
			(xy 125.238002 -275.08073) (xy 125.237493 -275.106697) (xy 125.517403 -275.106697) (xy 125.517403 -275.054763)
			(xy 125.525528 -275.003468) (xy 125.541576 -274.954075) (xy 125.565154 -274.907801) (xy 125.59568 -274.865785)
			(xy 125.632403 -274.829062) (xy 125.674419 -274.798536) (xy 125.720693 -274.774958) (xy 125.770086 -274.75891)
			(xy 125.821381 -274.750785) (xy 125.873315 -274.750785) (xy 125.92461 -274.75891) (xy 125.974003 -274.774958)
			(xy 126.020277 -274.798536) (xy 126.062293 -274.829062) (xy 126.099016 -274.865785) (xy 126.129542 -274.907801)
			(xy 126.15312 -274.954075) (xy 126.169168 -275.003468) (xy 126.177293 -275.054763) (xy 126.177802 -275.08073)
			(xy 126.177293 -275.106697) (xy 126.456949 -275.106697) (xy 126.456949 -275.054763) (xy 126.465074 -275.003468)
			(xy 126.481122 -274.954075) (xy 126.5047 -274.907801) (xy 126.535226 -274.865785) (xy 126.571949 -274.829062)
			(xy 126.613965 -274.798536) (xy 126.660239 -274.774958) (xy 126.709632 -274.75891) (xy 126.760927 -274.750785)
			(xy 126.812861 -274.750785) (xy 126.864156 -274.75891) (xy 126.913549 -274.774958) (xy 126.959823 -274.798536)
			(xy 127.001839 -274.829062) (xy 127.038562 -274.865785) (xy 127.069088 -274.907801) (xy 127.092666 -274.954075)
			(xy 127.108714 -275.003468) (xy 127.116839 -275.054763) (xy 127.117348 -275.08073) (xy 127.116839 -275.106697)
			(xy 127.397003 -275.106697) (xy 127.397003 -275.054763) (xy 127.405128 -275.003468) (xy 127.421176 -274.954075)
			(xy 127.444754 -274.907801) (xy 127.47528 -274.865785) (xy 127.512003 -274.829062) (xy 127.554019 -274.798536)
			(xy 127.600293 -274.774958) (xy 127.649686 -274.75891) (xy 127.700981 -274.750785) (xy 127.752915 -274.750785)
			(xy 127.80421 -274.75891) (xy 127.853603 -274.774958) (xy 127.899877 -274.798536) (xy 127.941893 -274.829062)
			(xy 127.978616 -274.865785) (xy 128.009142 -274.907801) (xy 128.03272 -274.954075) (xy 128.048768 -275.003468)
			(xy 128.056893 -275.054763) (xy 128.057402 -275.08073) (xy 128.056893 -275.106697) (xy 128.336803 -275.106697)
			(xy 128.336803 -275.054763) (xy 128.344928 -275.003468) (xy 128.360976 -274.954075) (xy 128.384554 -274.907801)
			(xy 128.41508 -274.865785) (xy 128.451803 -274.829062) (xy 128.493819 -274.798536) (xy 128.540093 -274.774958)
			(xy 128.589486 -274.75891) (xy 128.640781 -274.750785) (xy 128.692715 -274.750785) (xy 128.74401 -274.75891)
			(xy 128.793403 -274.774958) (xy 128.839677 -274.798536) (xy 128.881693 -274.829062) (xy 128.918416 -274.865785)
			(xy 128.948942 -274.907801) (xy 128.97252 -274.954075) (xy 128.988568 -275.003468) (xy 128.996693 -275.054763)
			(xy 128.997202 -275.08073) (xy 128.996693 -275.106697) (xy 129.276603 -275.106697) (xy 129.276603 -275.054763)
			(xy 129.284728 -275.003468) (xy 129.300776 -274.954075) (xy 129.324354 -274.907801) (xy 129.35488 -274.865785)
			(xy 129.391603 -274.829062) (xy 129.433619 -274.798536) (xy 129.479893 -274.774958) (xy 129.529286 -274.75891)
			(xy 129.580581 -274.750785) (xy 129.632515 -274.750785) (xy 129.68381 -274.75891) (xy 129.733203 -274.774958)
			(xy 129.779477 -274.798536) (xy 129.821493 -274.829062) (xy 129.858216 -274.865785) (xy 129.888742 -274.907801)
			(xy 129.91232 -274.954075) (xy 129.928368 -275.003468) (xy 129.936493 -275.054763) (xy 129.937002 -275.08073)
			(xy 129.936493 -275.106697) (xy 130.216403 -275.106697) (xy 130.216403 -275.054763) (xy 130.224528 -275.003468)
			(xy 130.240576 -274.954075) (xy 130.264154 -274.907801) (xy 130.29468 -274.865785) (xy 130.331403 -274.829062)
			(xy 130.373419 -274.798536) (xy 130.419693 -274.774958) (xy 130.469086 -274.75891) (xy 130.520381 -274.750785)
			(xy 130.572315 -274.750785) (xy 130.62361 -274.75891) (xy 130.673003 -274.774958) (xy 130.719277 -274.798536)
			(xy 130.761293 -274.829062) (xy 130.798016 -274.865785) (xy 130.828542 -274.907801) (xy 130.85212 -274.954075)
			(xy 130.868168 -275.003468) (xy 130.876293 -275.054763) (xy 130.876802 -275.08073) (xy 130.876293 -275.106697)
			(xy 130.868168 -275.157992) (xy 130.85212 -275.207385) (xy 130.828542 -275.253659) (xy 130.798016 -275.295675)
			(xy 130.761293 -275.332398) (xy 130.719277 -275.362924) (xy 130.673003 -275.386502) (xy 130.62361 -275.40255)
			(xy 130.572315 -275.410675) (xy 130.520381 -275.410675) (xy 130.469086 -275.40255) (xy 130.419693 -275.386502)
			(xy 130.373419 -275.362924) (xy 130.331403 -275.332398) (xy 130.29468 -275.295675) (xy 130.264154 -275.253659)
			(xy 130.240576 -275.207385) (xy 130.224528 -275.157992) (xy 130.216403 -275.106697) (xy 129.936493 -275.106697)
			(xy 129.928368 -275.157992) (xy 129.91232 -275.207385) (xy 129.888742 -275.253659) (xy 129.858216 -275.295675)
			(xy 129.821493 -275.332398) (xy 129.779477 -275.362924) (xy 129.733203 -275.386502) (xy 129.68381 -275.40255)
			(xy 129.632515 -275.410675) (xy 129.580581 -275.410675) (xy 129.529286 -275.40255) (xy 129.479893 -275.386502)
			(xy 129.433619 -275.362924) (xy 129.391603 -275.332398) (xy 129.35488 -275.295675) (xy 129.324354 -275.253659)
			(xy 129.300776 -275.207385) (xy 129.284728 -275.157992) (xy 129.276603 -275.106697) (xy 128.996693 -275.106697)
			(xy 128.988568 -275.157992) (xy 128.97252 -275.207385) (xy 128.948942 -275.253659) (xy 128.918416 -275.295675)
			(xy 128.881693 -275.332398) (xy 128.839677 -275.362924) (xy 128.793403 -275.386502) (xy 128.74401 -275.40255)
			(xy 128.692715 -275.410675) (xy 128.640781 -275.410675) (xy 128.589486 -275.40255) (xy 128.540093 -275.386502)
			(xy 128.493819 -275.362924) (xy 128.451803 -275.332398) (xy 128.41508 -275.295675) (xy 128.384554 -275.253659)
			(xy 128.360976 -275.207385) (xy 128.344928 -275.157992) (xy 128.336803 -275.106697) (xy 128.056893 -275.106697)
			(xy 128.048768 -275.157992) (xy 128.03272 -275.207385) (xy 128.009142 -275.253659) (xy 127.978616 -275.295675)
			(xy 127.941893 -275.332398) (xy 127.899877 -275.362924) (xy 127.853603 -275.386502) (xy 127.80421 -275.40255)
			(xy 127.752915 -275.410675) (xy 127.700981 -275.410675) (xy 127.649686 -275.40255) (xy 127.600293 -275.386502)
			(xy 127.554019 -275.362924) (xy 127.512003 -275.332398) (xy 127.47528 -275.295675) (xy 127.444754 -275.253659)
			(xy 127.421176 -275.207385) (xy 127.405128 -275.157992) (xy 127.397003 -275.106697) (xy 127.116839 -275.106697)
			(xy 127.108714 -275.157992) (xy 127.092666 -275.207385) (xy 127.069088 -275.253659) (xy 127.038562 -275.295675)
			(xy 127.001839 -275.332398) (xy 126.959823 -275.362924) (xy 126.913549 -275.386502) (xy 126.864156 -275.40255)
			(xy 126.812861 -275.410675) (xy 126.760927 -275.410675) (xy 126.709632 -275.40255) (xy 126.660239 -275.386502)
			(xy 126.613965 -275.362924) (xy 126.571949 -275.332398) (xy 126.535226 -275.295675) (xy 126.5047 -275.253659)
			(xy 126.481122 -275.207385) (xy 126.465074 -275.157992) (xy 126.456949 -275.106697) (xy 126.177293 -275.106697)
			(xy 126.169168 -275.157992) (xy 126.15312 -275.207385) (xy 126.129542 -275.253659) (xy 126.099016 -275.295675)
			(xy 126.062293 -275.332398) (xy 126.020277 -275.362924) (xy 125.974003 -275.386502) (xy 125.92461 -275.40255)
			(xy 125.873315 -275.410675) (xy 125.821381 -275.410675) (xy 125.770086 -275.40255) (xy 125.720693 -275.386502)
			(xy 125.674419 -275.362924) (xy 125.632403 -275.332398) (xy 125.59568 -275.295675) (xy 125.565154 -275.253659)
			(xy 125.541576 -275.207385) (xy 125.525528 -275.157992) (xy 125.517403 -275.106697) (xy 125.237493 -275.106697)
			(xy 125.229368 -275.157992) (xy 125.21332 -275.207385) (xy 125.189742 -275.253659) (xy 125.159216 -275.295675)
			(xy 125.122493 -275.332398) (xy 125.080477 -275.362924) (xy 125.034203 -275.386502) (xy 124.98481 -275.40255)
			(xy 124.933515 -275.410675) (xy 124.881581 -275.410675) (xy 124.830286 -275.40255) (xy 124.780893 -275.386502)
			(xy 124.734619 -275.362924) (xy 124.692603 -275.332398) (xy 124.65588 -275.295675) (xy 124.625354 -275.253659)
			(xy 124.601776 -275.207385) (xy 124.585728 -275.157992) (xy 124.577603 -275.106697) (xy 124.297693 -275.106697)
			(xy 124.289568 -275.157992) (xy 124.27352 -275.207385) (xy 124.249942 -275.253659) (xy 124.219416 -275.295675)
			(xy 124.182693 -275.332398) (xy 124.140677 -275.362924) (xy 124.094403 -275.386502) (xy 124.04501 -275.40255)
			(xy 123.993715 -275.410675) (xy 123.941781 -275.410675) (xy 123.890486 -275.40255) (xy 123.841093 -275.386502)
			(xy 123.794819 -275.362924) (xy 123.752803 -275.332398) (xy 123.71608 -275.295675) (xy 123.685554 -275.253659)
			(xy 123.661976 -275.207385) (xy 123.645928 -275.157992) (xy 123.637803 -275.106697) (xy 123.357893 -275.106697)
			(xy 123.349768 -275.157992) (xy 123.33372 -275.207385) (xy 123.310142 -275.253659) (xy 123.279616 -275.295675)
			(xy 123.242893 -275.332398) (xy 123.200877 -275.362924) (xy 123.154603 -275.386502) (xy 123.10521 -275.40255)
			(xy 123.053915 -275.410675) (xy 123.001981 -275.410675) (xy 122.950686 -275.40255) (xy 122.901293 -275.386502)
			(xy 122.855019 -275.362924) (xy 122.813003 -275.332398) (xy 122.77628 -275.295675) (xy 122.745754 -275.253659)
			(xy 122.722176 -275.207385) (xy 122.706128 -275.157992) (xy 122.698003 -275.106697) (xy 122.418093 -275.106697)
			(xy 122.409968 -275.157992) (xy 122.39392 -275.207385) (xy 122.370342 -275.253659) (xy 122.339816 -275.295675)
			(xy 122.303093 -275.332398) (xy 122.261077 -275.362924) (xy 122.214803 -275.386502) (xy 122.16541 -275.40255)
			(xy 122.114115 -275.410675) (xy 122.062181 -275.410675) (xy 122.010886 -275.40255) (xy 121.961493 -275.386502)
			(xy 121.915219 -275.362924) (xy 121.873203 -275.332398) (xy 121.83648 -275.295675) (xy 121.805954 -275.253659)
			(xy 121.782376 -275.207385) (xy 121.766328 -275.157992) (xy 121.758203 -275.106697) (xy 121.477999 -275.106697)
			(xy 121.469914 -275.157738) (xy 121.453866 -275.207131) (xy 121.430288 -275.253405) (xy 121.399762 -275.295421)
			(xy 121.363039 -275.332144) (xy 121.321023 -275.36267) (xy 121.274749 -275.386248) (xy 121.225356 -275.402296)
			(xy 121.174061 -275.410421) (xy 121.122127 -275.410421) (xy 121.070832 -275.402296) (xy 121.021439 -275.386248)
			(xy 120.975165 -275.36267) (xy 120.933149 -275.332144) (xy 120.896426 -275.295421) (xy 120.8659 -275.253405)
			(xy 120.842322 -275.207131) (xy 120.826274 -275.157738) (xy 120.818149 -275.106443) (xy 120.538498 -275.106443)
			(xy 120.538493 -275.106697) (xy 120.530368 -275.157992) (xy 120.51432 -275.207385) (xy 120.490742 -275.253659)
			(xy 120.460216 -275.295675) (xy 120.423493 -275.332398) (xy 120.381477 -275.362924) (xy 120.335203 -275.386502)
			(xy 120.28581 -275.40255) (xy 120.234515 -275.410675) (xy 120.182581 -275.410675) (xy 120.131286 -275.40255)
			(xy 120.081893 -275.386502) (xy 120.035619 -275.362924) (xy 119.993603 -275.332398) (xy 119.95688 -275.295675)
			(xy 119.926354 -275.253659) (xy 119.902776 -275.207385) (xy 119.886728 -275.157992) (xy 119.878603 -275.106697)
			(xy 116.779039 -275.106697) (xy 116.770914 -275.157992) (xy 116.754866 -275.207385) (xy 116.731288 -275.253659)
			(xy 116.700762 -275.295675) (xy 116.664039 -275.332398) (xy 116.622023 -275.362924) (xy 116.575749 -275.386502)
			(xy 116.526356 -275.40255) (xy 116.475061 -275.410675) (xy 116.423127 -275.410675) (xy 116.371832 -275.40255)
			(xy 116.322439 -275.386502) (xy 116.276165 -275.362924) (xy 116.234149 -275.332398) (xy 116.197426 -275.295675)
			(xy 116.1669 -275.253659) (xy 116.143322 -275.207385) (xy 116.127274 -275.157992) (xy 116.119149 -275.106697)
			(xy 115.838985 -275.106697) (xy 115.83086 -275.157992) (xy 115.814812 -275.207385) (xy 115.791234 -275.253659)
			(xy 115.760708 -275.295675) (xy 115.723985 -275.332398) (xy 115.681969 -275.362924) (xy 115.635695 -275.386502)
			(xy 115.586302 -275.40255) (xy 115.535007 -275.410675) (xy 115.483073 -275.410675) (xy 115.431778 -275.40255)
			(xy 115.382385 -275.386502) (xy 115.336111 -275.362924) (xy 115.294095 -275.332398) (xy 115.257372 -275.295675)
			(xy 115.226846 -275.253659) (xy 115.203268 -275.207385) (xy 115.18722 -275.157992) (xy 115.179095 -275.106697)
			(xy 114.899189 -275.106697) (xy 114.891094 -275.15794) (xy 114.875085 -275.207306) (xy 114.851559 -275.253564)
			(xy 114.821094 -275.295578) (xy 114.784438 -275.332315) (xy 114.742492 -275.362874) (xy 114.719608 -275.375116)
			(xy 114.707623 -275.381746) (xy 114.687438 -275.400243) (xy 114.672894 -275.423439) (xy 114.665035 -275.449665)
			(xy 114.664426 -275.477037) (xy 114.671112 -275.503586) (xy 114.684612 -275.527405) (xy 114.693954 -275.537422)
			(xy 114.809524 -275.652992) (xy 114.844576 -275.627592) (xy 114.865919 -275.612637) (xy 114.912323 -275.58892)
			(xy 114.961871 -275.572769) (xy 115.013337 -275.564584) (xy 115.039394 -275.564092) (xy 115.065384 -275.564575)
			(xy 115.116723 -275.572705) (xy 115.166158 -275.588767) (xy 115.212472 -275.612364) (xy 115.254525 -275.642916)
			(xy 115.29128 -275.679671) (xy 115.321833 -275.721723) (xy 115.345431 -275.768036) (xy 115.361493 -275.817471)
			(xy 115.369625 -275.86881) (xy 115.370102 -275.8948) (xy 115.369614 -275.920767) (xy 115.649249 -275.920767)
			(xy 115.649249 -275.868833) (xy 115.657374 -275.817538) (xy 115.673422 -275.768145) (xy 115.697 -275.721871)
			(xy 115.727526 -275.679855) (xy 115.764249 -275.643132) (xy 115.806265 -275.612606) (xy 115.852539 -275.589028)
			(xy 115.901932 -275.57298) (xy 115.953227 -275.564855) (xy 116.005161 -275.564855) (xy 116.056456 -275.57298)
			(xy 116.105849 -275.589028) (xy 116.152123 -275.612606) (xy 116.194139 -275.643132) (xy 116.230862 -275.679855)
			(xy 116.261388 -275.721871) (xy 116.284966 -275.768145) (xy 116.301014 -275.817538) (xy 116.309139 -275.868833)
			(xy 116.309648 -275.8948) (xy 116.309139 -275.920767) (xy 116.589049 -275.920767) (xy 116.589049 -275.868833)
			(xy 116.597174 -275.817538) (xy 116.613222 -275.768145) (xy 116.6368 -275.721871) (xy 116.667326 -275.679855)
			(xy 116.704049 -275.643132) (xy 116.746065 -275.612606) (xy 116.792339 -275.589028) (xy 116.841732 -275.57298)
			(xy 116.893027 -275.564855) (xy 116.944961 -275.564855) (xy 116.996256 -275.57298) (xy 117.045649 -275.589028)
			(xy 117.091923 -275.612606) (xy 117.133939 -275.643132) (xy 117.170662 -275.679855) (xy 117.201188 -275.721871)
			(xy 117.224766 -275.768145) (xy 117.240814 -275.817538) (xy 117.248939 -275.868833) (xy 117.249448 -275.8948)
			(xy 117.248939 -275.920767) (xy 117.528849 -275.920767) (xy 117.528849 -275.868833) (xy 117.536974 -275.817538)
			(xy 117.553022 -275.768145) (xy 117.5766 -275.721871) (xy 117.607126 -275.679855) (xy 117.643849 -275.643132)
			(xy 117.685865 -275.612606) (xy 117.732139 -275.589028) (xy 117.781532 -275.57298) (xy 117.832827 -275.564855)
			(xy 117.884761 -275.564855) (xy 117.936056 -275.57298) (xy 117.985449 -275.589028) (xy 118.031723 -275.612606)
			(xy 118.073739 -275.643132) (xy 118.110462 -275.679855) (xy 118.140988 -275.721871) (xy 118.164566 -275.768145)
			(xy 118.180614 -275.817538) (xy 118.188739 -275.868833) (xy 118.189248 -275.8948) (xy 118.188739 -275.920767)
			(xy 118.468903 -275.920767) (xy 118.468903 -275.868833) (xy 118.477028 -275.817538) (xy 118.493076 -275.768145)
			(xy 118.516654 -275.721871) (xy 118.54718 -275.679855) (xy 118.583903 -275.643132) (xy 118.625919 -275.612606)
			(xy 118.672193 -275.589028) (xy 118.721586 -275.57298) (xy 118.772881 -275.564855) (xy 118.824815 -275.564855)
			(xy 118.87611 -275.57298) (xy 118.925503 -275.589028) (xy 118.971777 -275.612606) (xy 119.013793 -275.643132)
			(xy 119.050516 -275.679855) (xy 119.081042 -275.721871) (xy 119.10462 -275.768145) (xy 119.120668 -275.817538)
			(xy 119.128793 -275.868833) (xy 119.129302 -275.8948) (xy 119.128798 -275.920513) (xy 119.408703 -275.920513)
			(xy 119.408703 -275.868579) (xy 119.416828 -275.817284) (xy 119.432876 -275.767891) (xy 119.456454 -275.721617)
			(xy 119.48698 -275.679601) (xy 119.523703 -275.642878) (xy 119.565719 -275.612352) (xy 119.611993 -275.588774)
			(xy 119.661386 -275.572726) (xy 119.712681 -275.564601) (xy 119.764615 -275.564601) (xy 119.81591 -275.572726)
			(xy 119.865303 -275.588774) (xy 119.911577 -275.612352) (xy 119.953593 -275.642878) (xy 119.990316 -275.679601)
			(xy 120.020842 -275.721617) (xy 120.04442 -275.767891) (xy 120.060468 -275.817284) (xy 120.068593 -275.868579)
			(xy 120.069102 -275.894546) (xy 120.068593 -275.920513) (xy 120.348503 -275.920513) (xy 120.348503 -275.868579)
			(xy 120.356628 -275.817284) (xy 120.372676 -275.767891) (xy 120.396254 -275.721617) (xy 120.42678 -275.679601)
			(xy 120.463503 -275.642878) (xy 120.505519 -275.612352) (xy 120.551793 -275.588774) (xy 120.601186 -275.572726)
			(xy 120.652481 -275.564601) (xy 120.704415 -275.564601) (xy 120.75571 -275.572726) (xy 120.805103 -275.588774)
			(xy 120.851377 -275.612352) (xy 120.893393 -275.642878) (xy 120.930116 -275.679601) (xy 120.960642 -275.721617)
			(xy 120.98422 -275.767891) (xy 121.000268 -275.817284) (xy 121.008393 -275.868579) (xy 121.008902 -275.894546)
			(xy 121.008393 -275.920513) (xy 121.288303 -275.920513) (xy 121.288303 -275.868579) (xy 121.296428 -275.817284)
			(xy 121.312476 -275.767891) (xy 121.336054 -275.721617) (xy 121.36658 -275.679601) (xy 121.403303 -275.642878)
			(xy 121.445319 -275.612352) (xy 121.491593 -275.588774) (xy 121.540986 -275.572726) (xy 121.592281 -275.564601)
			(xy 121.644215 -275.564601) (xy 121.69551 -275.572726) (xy 121.744903 -275.588774) (xy 121.791177 -275.612352)
			(xy 121.833193 -275.642878) (xy 121.869916 -275.679601) (xy 121.900442 -275.721617) (xy 121.92402 -275.767891)
			(xy 121.940068 -275.817284) (xy 121.948193 -275.868579) (xy 121.948702 -275.894546) (xy 121.948193 -275.920513)
			(xy 121.948153 -275.920767) (xy 122.228103 -275.920767) (xy 122.228103 -275.868833) (xy 122.236228 -275.817538)
			(xy 122.252276 -275.768145) (xy 122.275854 -275.721871) (xy 122.30638 -275.679855) (xy 122.343103 -275.643132)
			(xy 122.385119 -275.612606) (xy 122.431393 -275.589028) (xy 122.480786 -275.57298) (xy 122.532081 -275.564855)
			(xy 122.584015 -275.564855) (xy 122.63531 -275.57298) (xy 122.684703 -275.589028) (xy 122.730977 -275.612606)
			(xy 122.772993 -275.643132) (xy 122.809716 -275.679855) (xy 122.840242 -275.721871) (xy 122.86382 -275.768145)
			(xy 122.879868 -275.817538) (xy 122.887993 -275.868833) (xy 122.888502 -275.8948) (xy 122.887993 -275.920767)
			(xy 123.167649 -275.920767) (xy 123.167649 -275.868833) (xy 123.175774 -275.817538) (xy 123.191822 -275.768145)
			(xy 123.2154 -275.721871) (xy 123.245926 -275.679855) (xy 123.282649 -275.643132) (xy 123.324665 -275.612606)
			(xy 123.370939 -275.589028) (xy 123.420332 -275.57298) (xy 123.471627 -275.564855) (xy 123.523561 -275.564855)
			(xy 123.574856 -275.57298) (xy 123.624249 -275.589028) (xy 123.670523 -275.612606) (xy 123.712539 -275.643132)
			(xy 123.749262 -275.679855) (xy 123.779788 -275.721871) (xy 123.803366 -275.768145) (xy 123.819414 -275.817538)
			(xy 123.827539 -275.868833) (xy 123.828048 -275.8948) (xy 123.827539 -275.920767) (xy 124.107449 -275.920767)
			(xy 124.107449 -275.868833) (xy 124.115574 -275.817538) (xy 124.131622 -275.768145) (xy 124.1552 -275.721871)
			(xy 124.185726 -275.679855) (xy 124.222449 -275.643132) (xy 124.264465 -275.612606) (xy 124.310739 -275.589028)
			(xy 124.360132 -275.57298) (xy 124.411427 -275.564855) (xy 124.463361 -275.564855) (xy 124.514656 -275.57298)
			(xy 124.564049 -275.589028) (xy 124.610323 -275.612606) (xy 124.652339 -275.643132) (xy 124.689062 -275.679855)
			(xy 124.719588 -275.721871) (xy 124.743166 -275.768145) (xy 124.759214 -275.817538) (xy 124.767339 -275.868833)
			(xy 124.767848 -275.8948) (xy 124.767339 -275.920767) (xy 125.047249 -275.920767) (xy 125.047249 -275.868833)
			(xy 125.055374 -275.817538) (xy 125.071422 -275.768145) (xy 125.095 -275.721871) (xy 125.125526 -275.679855)
			(xy 125.162249 -275.643132) (xy 125.204265 -275.612606) (xy 125.250539 -275.589028) (xy 125.299932 -275.57298)
			(xy 125.351227 -275.564855) (xy 125.403161 -275.564855) (xy 125.454456 -275.57298) (xy 125.503849 -275.589028)
			(xy 125.550123 -275.612606) (xy 125.592139 -275.643132) (xy 125.628862 -275.679855) (xy 125.659388 -275.721871)
			(xy 125.682966 -275.768145) (xy 125.699014 -275.817538) (xy 125.707139 -275.868833) (xy 125.707648 -275.8948)
			(xy 125.707139 -275.920767) (xy 125.987049 -275.920767) (xy 125.987049 -275.868833) (xy 125.995174 -275.817538)
			(xy 126.011222 -275.768145) (xy 126.0348 -275.721871) (xy 126.065326 -275.679855) (xy 126.102049 -275.643132)
			(xy 126.144065 -275.612606) (xy 126.190339 -275.589028) (xy 126.239732 -275.57298) (xy 126.291027 -275.564855)
			(xy 126.342961 -275.564855) (xy 126.394256 -275.57298) (xy 126.443649 -275.589028) (xy 126.489923 -275.612606)
			(xy 126.531939 -275.643132) (xy 126.568662 -275.679855) (xy 126.599188 -275.721871) (xy 126.622766 -275.768145)
			(xy 126.638814 -275.817538) (xy 126.646939 -275.868833) (xy 126.647448 -275.8948) (xy 126.646939 -275.920767)
			(xy 126.926849 -275.920767) (xy 126.926849 -275.868833) (xy 126.934974 -275.817538) (xy 126.951022 -275.768145)
			(xy 126.9746 -275.721871) (xy 127.005126 -275.679855) (xy 127.041849 -275.643132) (xy 127.083865 -275.612606)
			(xy 127.130139 -275.589028) (xy 127.179532 -275.57298) (xy 127.230827 -275.564855) (xy 127.282761 -275.564855)
			(xy 127.334056 -275.57298) (xy 127.383449 -275.589028) (xy 127.429723 -275.612606) (xy 127.471739 -275.643132)
			(xy 127.508462 -275.679855) (xy 127.538988 -275.721871) (xy 127.562566 -275.768145) (xy 127.578614 -275.817538)
			(xy 127.586739 -275.868833) (xy 127.587248 -275.8948) (xy 127.586739 -275.920767) (xy 127.866649 -275.920767)
			(xy 127.866649 -275.868833) (xy 127.874774 -275.817538) (xy 127.890822 -275.768145) (xy 127.9144 -275.721871)
			(xy 127.944926 -275.679855) (xy 127.981649 -275.643132) (xy 128.023665 -275.612606) (xy 128.069939 -275.589028)
			(xy 128.119332 -275.57298) (xy 128.170627 -275.564855) (xy 128.222561 -275.564855) (xy 128.273856 -275.57298)
			(xy 128.323249 -275.589028) (xy 128.369523 -275.612606) (xy 128.411539 -275.643132) (xy 128.448262 -275.679855)
			(xy 128.478788 -275.721871) (xy 128.502366 -275.768145) (xy 128.518414 -275.817538) (xy 128.526539 -275.868833)
			(xy 128.527048 -275.8948) (xy 128.526539 -275.920767) (xy 128.806703 -275.920767) (xy 128.806703 -275.868833)
			(xy 128.814828 -275.817538) (xy 128.830876 -275.768145) (xy 128.854454 -275.721871) (xy 128.88498 -275.679855)
			(xy 128.921703 -275.643132) (xy 128.963719 -275.612606) (xy 129.009993 -275.589028) (xy 129.059386 -275.57298)
			(xy 129.110681 -275.564855) (xy 129.162615 -275.564855) (xy 129.21391 -275.57298) (xy 129.263303 -275.589028)
			(xy 129.309577 -275.612606) (xy 129.351593 -275.643132) (xy 129.388316 -275.679855) (xy 129.418842 -275.721871)
			(xy 129.44242 -275.768145) (xy 129.458468 -275.817538) (xy 129.466593 -275.868833) (xy 129.467102 -275.8948)
			(xy 129.466593 -275.920767) (xy 129.746249 -275.920767) (xy 129.746249 -275.868833) (xy 129.754374 -275.817538)
			(xy 129.770422 -275.768145) (xy 129.794 -275.721871) (xy 129.824526 -275.679855) (xy 129.861249 -275.643132)
			(xy 129.903265 -275.612606) (xy 129.949539 -275.589028) (xy 129.998932 -275.57298) (xy 130.050227 -275.564855)
			(xy 130.102161 -275.564855) (xy 130.153456 -275.57298) (xy 130.202849 -275.589028) (xy 130.249123 -275.612606)
			(xy 130.291139 -275.643132) (xy 130.327862 -275.679855) (xy 130.358388 -275.721871) (xy 130.381966 -275.768145)
			(xy 130.398014 -275.817538) (xy 130.406139 -275.868833) (xy 130.406648 -275.8948) (xy 130.406139 -275.920767)
			(xy 130.686049 -275.920767) (xy 130.686049 -275.868833) (xy 130.694174 -275.817538) (xy 130.710222 -275.768145)
			(xy 130.7338 -275.721871) (xy 130.764326 -275.679855) (xy 130.801049 -275.643132) (xy 130.843065 -275.612606)
			(xy 130.889339 -275.589028) (xy 130.938732 -275.57298) (xy 130.990027 -275.564855) (xy 131.041961 -275.564855)
			(xy 131.093256 -275.57298) (xy 131.142649 -275.589028) (xy 131.188923 -275.612606) (xy 131.230939 -275.643132)
			(xy 131.267662 -275.679855) (xy 131.298188 -275.721871) (xy 131.321766 -275.768145) (xy 131.337814 -275.817538)
			(xy 131.345939 -275.868833) (xy 131.346448 -275.8948) (xy 131.345939 -275.920767) (xy 131.337814 -275.972062)
			(xy 131.321766 -276.021455) (xy 131.298188 -276.067729) (xy 131.267662 -276.109745) (xy 131.230939 -276.146468)
			(xy 131.188923 -276.176994) (xy 131.142649 -276.200572) (xy 131.093256 -276.21662) (xy 131.041961 -276.224745)
			(xy 130.990027 -276.224745) (xy 130.938732 -276.21662) (xy 130.889339 -276.200572) (xy 130.843065 -276.176994)
			(xy 130.801049 -276.146468) (xy 130.764326 -276.109745) (xy 130.7338 -276.067729) (xy 130.710222 -276.021455)
			(xy 130.694174 -275.972062) (xy 130.686049 -275.920767) (xy 130.406139 -275.920767) (xy 130.398014 -275.972062)
			(xy 130.381966 -276.021455) (xy 130.358388 -276.067729) (xy 130.327862 -276.109745) (xy 130.291139 -276.146468)
			(xy 130.249123 -276.176994) (xy 130.202849 -276.200572) (xy 130.153456 -276.21662) (xy 130.102161 -276.224745)
			(xy 130.050227 -276.224745) (xy 129.998932 -276.21662) (xy 129.949539 -276.200572) (xy 129.903265 -276.176994)
			(xy 129.861249 -276.146468) (xy 129.824526 -276.109745) (xy 129.794 -276.067729) (xy 129.770422 -276.021455)
			(xy 129.754374 -275.972062) (xy 129.746249 -275.920767) (xy 129.466593 -275.920767) (xy 129.458468 -275.972062)
			(xy 129.44242 -276.021455) (xy 129.418842 -276.067729) (xy 129.388316 -276.109745) (xy 129.351593 -276.146468)
			(xy 129.309577 -276.176994) (xy 129.263303 -276.200572) (xy 129.21391 -276.21662) (xy 129.162615 -276.224745)
			(xy 129.110681 -276.224745) (xy 129.059386 -276.21662) (xy 129.009993 -276.200572) (xy 128.963719 -276.176994)
			(xy 128.921703 -276.146468) (xy 128.88498 -276.109745) (xy 128.854454 -276.067729) (xy 128.830876 -276.021455)
			(xy 128.814828 -275.972062) (xy 128.806703 -275.920767) (xy 128.526539 -275.920767) (xy 128.518414 -275.972062)
			(xy 128.502366 -276.021455) (xy 128.478788 -276.067729) (xy 128.448262 -276.109745) (xy 128.411539 -276.146468)
			(xy 128.369523 -276.176994) (xy 128.323249 -276.200572) (xy 128.273856 -276.21662) (xy 128.222561 -276.224745)
			(xy 128.170627 -276.224745) (xy 128.119332 -276.21662) (xy 128.069939 -276.200572) (xy 128.023665 -276.176994)
			(xy 127.981649 -276.146468) (xy 127.944926 -276.109745) (xy 127.9144 -276.067729) (xy 127.890822 -276.021455)
			(xy 127.874774 -275.972062) (xy 127.866649 -275.920767) (xy 127.586739 -275.920767) (xy 127.578614 -275.972062)
			(xy 127.562566 -276.021455) (xy 127.538988 -276.067729) (xy 127.508462 -276.109745) (xy 127.471739 -276.146468)
			(xy 127.429723 -276.176994) (xy 127.383449 -276.200572) (xy 127.334056 -276.21662) (xy 127.282761 -276.224745)
			(xy 127.230827 -276.224745) (xy 127.179532 -276.21662) (xy 127.130139 -276.200572) (xy 127.083865 -276.176994)
			(xy 127.041849 -276.146468) (xy 127.005126 -276.109745) (xy 126.9746 -276.067729) (xy 126.951022 -276.021455)
			(xy 126.934974 -275.972062) (xy 126.926849 -275.920767) (xy 126.646939 -275.920767) (xy 126.638814 -275.972062)
			(xy 126.622766 -276.021455) (xy 126.599188 -276.067729) (xy 126.568662 -276.109745) (xy 126.531939 -276.146468)
			(xy 126.489923 -276.176994) (xy 126.443649 -276.200572) (xy 126.394256 -276.21662) (xy 126.342961 -276.224745)
			(xy 126.291027 -276.224745) (xy 126.239732 -276.21662) (xy 126.190339 -276.200572) (xy 126.144065 -276.176994)
			(xy 126.102049 -276.146468) (xy 126.065326 -276.109745) (xy 126.0348 -276.067729) (xy 126.011222 -276.021455)
			(xy 125.995174 -275.972062) (xy 125.987049 -275.920767) (xy 125.707139 -275.920767) (xy 125.699014 -275.972062)
			(xy 125.682966 -276.021455) (xy 125.659388 -276.067729) (xy 125.628862 -276.109745) (xy 125.592139 -276.146468)
			(xy 125.550123 -276.176994) (xy 125.503849 -276.200572) (xy 125.454456 -276.21662) (xy 125.403161 -276.224745)
			(xy 125.351227 -276.224745) (xy 125.299932 -276.21662) (xy 125.250539 -276.200572) (xy 125.204265 -276.176994)
			(xy 125.162249 -276.146468) (xy 125.125526 -276.109745) (xy 125.095 -276.067729) (xy 125.071422 -276.021455)
			(xy 125.055374 -275.972062) (xy 125.047249 -275.920767) (xy 124.767339 -275.920767) (xy 124.759214 -275.972062)
			(xy 124.743166 -276.021455) (xy 124.719588 -276.067729) (xy 124.689062 -276.109745) (xy 124.652339 -276.146468)
			(xy 124.610323 -276.176994) (xy 124.564049 -276.200572) (xy 124.514656 -276.21662) (xy 124.463361 -276.224745)
			(xy 124.411427 -276.224745) (xy 124.360132 -276.21662) (xy 124.310739 -276.200572) (xy 124.264465 -276.176994)
			(xy 124.222449 -276.146468) (xy 124.185726 -276.109745) (xy 124.1552 -276.067729) (xy 124.131622 -276.021455)
			(xy 124.115574 -275.972062) (xy 124.107449 -275.920767) (xy 123.827539 -275.920767) (xy 123.819414 -275.972062)
			(xy 123.803366 -276.021455) (xy 123.779788 -276.067729) (xy 123.749262 -276.109745) (xy 123.712539 -276.146468)
			(xy 123.670523 -276.176994) (xy 123.624249 -276.200572) (xy 123.574856 -276.21662) (xy 123.523561 -276.224745)
			(xy 123.471627 -276.224745) (xy 123.420332 -276.21662) (xy 123.370939 -276.200572) (xy 123.324665 -276.176994)
			(xy 123.282649 -276.146468) (xy 123.245926 -276.109745) (xy 123.2154 -276.067729) (xy 123.191822 -276.021455)
			(xy 123.175774 -275.972062) (xy 123.167649 -275.920767) (xy 122.887993 -275.920767) (xy 122.879868 -275.972062)
			(xy 122.86382 -276.021455) (xy 122.840242 -276.067729) (xy 122.809716 -276.109745) (xy 122.772993 -276.146468)
			(xy 122.730977 -276.176994) (xy 122.684703 -276.200572) (xy 122.63531 -276.21662) (xy 122.584015 -276.224745)
			(xy 122.532081 -276.224745) (xy 122.480786 -276.21662) (xy 122.431393 -276.200572) (xy 122.385119 -276.176994)
			(xy 122.343103 -276.146468) (xy 122.30638 -276.109745) (xy 122.275854 -276.067729) (xy 122.252276 -276.021455)
			(xy 122.236228 -275.972062) (xy 122.228103 -275.920767) (xy 121.948153 -275.920767) (xy 121.940068 -275.971808)
			(xy 121.92402 -276.021201) (xy 121.900442 -276.067475) (xy 121.869916 -276.109491) (xy 121.833193 -276.146214)
			(xy 121.791177 -276.17674) (xy 121.744903 -276.200318) (xy 121.69551 -276.216366) (xy 121.644215 -276.224491)
			(xy 121.592281 -276.224491) (xy 121.540986 -276.216366) (xy 121.491593 -276.200318) (xy 121.445319 -276.17674)
			(xy 121.403303 -276.146214) (xy 121.36658 -276.109491) (xy 121.336054 -276.067475) (xy 121.312476 -276.021201)
			(xy 121.296428 -275.971808) (xy 121.288303 -275.920513) (xy 121.008393 -275.920513) (xy 121.000268 -275.971808)
			(xy 120.98422 -276.021201) (xy 120.960642 -276.067475) (xy 120.930116 -276.109491) (xy 120.893393 -276.146214)
			(xy 120.851377 -276.17674) (xy 120.805103 -276.200318) (xy 120.75571 -276.216366) (xy 120.704415 -276.224491)
			(xy 120.652481 -276.224491) (xy 120.601186 -276.216366) (xy 120.551793 -276.200318) (xy 120.505519 -276.17674)
			(xy 120.463503 -276.146214) (xy 120.42678 -276.109491) (xy 120.396254 -276.067475) (xy 120.372676 -276.021201)
			(xy 120.356628 -275.971808) (xy 120.348503 -275.920513) (xy 120.068593 -275.920513) (xy 120.060468 -275.971808)
			(xy 120.04442 -276.021201) (xy 120.020842 -276.067475) (xy 119.990316 -276.109491) (xy 119.953593 -276.146214)
			(xy 119.911577 -276.17674) (xy 119.865303 -276.200318) (xy 119.81591 -276.216366) (xy 119.764615 -276.224491)
			(xy 119.712681 -276.224491) (xy 119.661386 -276.216366) (xy 119.611993 -276.200318) (xy 119.565719 -276.17674)
			(xy 119.523703 -276.146214) (xy 119.48698 -276.109491) (xy 119.456454 -276.067475) (xy 119.432876 -276.021201)
			(xy 119.416828 -275.971808) (xy 119.408703 -275.920513) (xy 119.128798 -275.920513) (xy 119.128793 -275.920767)
			(xy 119.120668 -275.972062) (xy 119.10462 -276.021455) (xy 119.081042 -276.067729) (xy 119.050516 -276.109745)
			(xy 119.013793 -276.146468) (xy 118.971777 -276.176994) (xy 118.925503 -276.200572) (xy 118.87611 -276.21662)
			(xy 118.824815 -276.224745) (xy 118.772881 -276.224745) (xy 118.721586 -276.21662) (xy 118.672193 -276.200572)
			(xy 118.625919 -276.176994) (xy 118.583903 -276.146468) (xy 118.54718 -276.109745) (xy 118.516654 -276.067729)
			(xy 118.493076 -276.021455) (xy 118.477028 -275.972062) (xy 118.468903 -275.920767) (xy 118.188739 -275.920767)
			(xy 118.180614 -275.972062) (xy 118.164566 -276.021455) (xy 118.140988 -276.067729) (xy 118.110462 -276.109745)
			(xy 118.073739 -276.146468) (xy 118.031723 -276.176994) (xy 117.985449 -276.200572) (xy 117.936056 -276.21662)
			(xy 117.884761 -276.224745) (xy 117.832827 -276.224745) (xy 117.781532 -276.21662) (xy 117.732139 -276.200572)
			(xy 117.685865 -276.176994) (xy 117.643849 -276.146468) (xy 117.607126 -276.109745) (xy 117.5766 -276.067729)
			(xy 117.553022 -276.021455) (xy 117.536974 -275.972062) (xy 117.528849 -275.920767) (xy 117.248939 -275.920767)
			(xy 117.240814 -275.972062) (xy 117.224766 -276.021455) (xy 117.201188 -276.067729) (xy 117.170662 -276.109745)
			(xy 117.133939 -276.146468) (xy 117.091923 -276.176994) (xy 117.045649 -276.200572) (xy 116.996256 -276.21662)
			(xy 116.944961 -276.224745) (xy 116.893027 -276.224745) (xy 116.841732 -276.21662) (xy 116.792339 -276.200572)
			(xy 116.746065 -276.176994) (xy 116.704049 -276.146468) (xy 116.667326 -276.109745) (xy 116.6368 -276.067729)
			(xy 116.613222 -276.021455) (xy 116.597174 -275.972062) (xy 116.589049 -275.920767) (xy 116.309139 -275.920767)
			(xy 116.301014 -275.972062) (xy 116.284966 -276.021455) (xy 116.261388 -276.067729) (xy 116.230862 -276.109745)
			(xy 116.194139 -276.146468) (xy 116.152123 -276.176994) (xy 116.105849 -276.200572) (xy 116.056456 -276.21662)
			(xy 116.005161 -276.224745) (xy 115.953227 -276.224745) (xy 115.901932 -276.21662) (xy 115.852539 -276.200572)
			(xy 115.806265 -276.176994) (xy 115.764249 -276.146468) (xy 115.727526 -276.109745) (xy 115.697 -276.067729)
			(xy 115.673422 -276.021455) (xy 115.657374 -275.972062) (xy 115.649249 -275.920767) (xy 115.369614 -275.920767)
			(xy 115.369612 -275.920857) (xy 115.361434 -275.972325) (xy 115.34528 -276.021871) (xy 115.32155 -276.068269)
			(xy 115.306602 -276.089618) (xy 115.281202 -276.12467) (xy 115.534948 -276.378416) (xy 115.55222 -276.380702)
			(xy 115.578999 -276.384757) (xy 115.630834 -276.400451) (xy 115.679416 -276.424387) (xy 115.723446 -276.455923)
			(xy 115.761745 -276.494216) (xy 115.793288 -276.538241) (xy 115.81723 -276.58682) (xy 115.832933 -276.638652)
			(xy 115.836954 -276.665436) (xy 115.83924 -276.682708) (xy 115.945412 -276.78888) (xy 115.956496 -276.799146)
			(xy 115.983185 -276.813269) (xy 116.012837 -276.818973) (xy 116.042861 -276.815761) (xy 116.070635 -276.803912)
			(xy 116.093732 -276.784462) (xy 116.110135 -276.75911) (xy 116.11841 -276.730071) (xy 116.11864 -276.714966)
			(xy 116.11864 -276.708362) (xy 116.119152 -276.682395) (xy 116.127282 -276.631101) (xy 116.143336 -276.58171)
			(xy 116.166919 -276.535439) (xy 116.197449 -276.493426) (xy 116.234176 -276.456707) (xy 116.276195 -276.426185)
			(xy 116.322471 -276.402611) (xy 116.371865 -276.386567) (xy 116.42316 -276.378447) (xy 116.475094 -276.378451)
			(xy 116.526389 -276.38658) (xy 116.57578 -276.402632) (xy 116.622052 -276.426213) (xy 116.664066 -276.456742)
			(xy 116.700786 -276.493468) (xy 116.73131 -276.535486) (xy 116.754885 -276.581761) (xy 116.770931 -276.631154)
			(xy 116.779052 -276.682449) (xy 116.779049 -276.734329) (xy 117.058949 -276.734329) (xy 117.058949 -276.682395)
			(xy 117.067074 -276.6311) (xy 117.083122 -276.581707) (xy 117.1067 -276.535433) (xy 117.137226 -276.493417)
			(xy 117.173949 -276.456694) (xy 117.215965 -276.426168) (xy 117.262239 -276.40259) (xy 117.311632 -276.386542)
			(xy 117.362927 -276.378417) (xy 117.414861 -276.378417) (xy 117.466156 -276.386542) (xy 117.515549 -276.40259)
			(xy 117.561823 -276.426168) (xy 117.603839 -276.456694) (xy 117.640562 -276.493417) (xy 117.671088 -276.535433)
			(xy 117.694666 -276.581707) (xy 117.710714 -276.6311) (xy 117.718839 -276.682395) (xy 117.719348 -276.708362)
			(xy 117.718839 -276.734329) (xy 117.998749 -276.734329) (xy 117.998749 -276.682395) (xy 118.006874 -276.6311)
			(xy 118.022922 -276.581707) (xy 118.0465 -276.535433) (xy 118.077026 -276.493417) (xy 118.113749 -276.456694)
			(xy 118.155765 -276.426168) (xy 118.202039 -276.40259) (xy 118.251432 -276.386542) (xy 118.302727 -276.378417)
			(xy 118.354661 -276.378417) (xy 118.405956 -276.386542) (xy 118.455349 -276.40259) (xy 118.501623 -276.426168)
			(xy 118.543639 -276.456694) (xy 118.580362 -276.493417) (xy 118.610888 -276.535433) (xy 118.634466 -276.581707)
			(xy 118.650514 -276.6311) (xy 118.658639 -276.682395) (xy 118.659148 -276.708362) (xy 118.658639 -276.734329)
			(xy 118.658599 -276.734583) (xy 118.938549 -276.734583) (xy 118.938549 -276.682649) (xy 118.946674 -276.631354)
			(xy 118.962722 -276.581961) (xy 118.9863 -276.535687) (xy 119.016826 -276.493671) (xy 119.053549 -276.456948)
			(xy 119.095565 -276.426422) (xy 119.141839 -276.402844) (xy 119.191232 -276.386796) (xy 119.242527 -276.378671)
			(xy 119.294461 -276.378671) (xy 119.345756 -276.386796) (xy 119.395149 -276.402844) (xy 119.441423 -276.426422)
			(xy 119.483439 -276.456948) (xy 119.520162 -276.493671) (xy 119.550688 -276.535687) (xy 119.574266 -276.581961)
			(xy 119.590314 -276.631354) (xy 119.598439 -276.682649) (xy 119.598948 -276.708616) (xy 119.598444 -276.734329)
			(xy 119.878349 -276.734329) (xy 119.878349 -276.682395) (xy 119.886474 -276.6311) (xy 119.902522 -276.581707)
			(xy 119.9261 -276.535433) (xy 119.956626 -276.493417) (xy 119.993349 -276.456694) (xy 120.035365 -276.426168)
			(xy 120.081639 -276.40259) (xy 120.131032 -276.386542) (xy 120.182327 -276.378417) (xy 120.234261 -276.378417)
			(xy 120.285556 -276.386542) (xy 120.334949 -276.40259) (xy 120.381223 -276.426168) (xy 120.423239 -276.456694)
			(xy 120.459962 -276.493417) (xy 120.490488 -276.535433) (xy 120.514066 -276.581707) (xy 120.530114 -276.6311)
			(xy 120.538239 -276.682395) (xy 120.538748 -276.708362) (xy 120.538239 -276.734329) (xy 120.538199 -276.734583)
			(xy 120.818403 -276.734583) (xy 120.818403 -276.682649) (xy 120.826528 -276.631354) (xy 120.842576 -276.581961)
			(xy 120.866154 -276.535687) (xy 120.89668 -276.493671) (xy 120.933403 -276.456948) (xy 120.975419 -276.426422)
			(xy 121.021693 -276.402844) (xy 121.071086 -276.386796) (xy 121.122381 -276.378671) (xy 121.174315 -276.378671)
			(xy 121.22561 -276.386796) (xy 121.275003 -276.402844) (xy 121.321277 -276.426422) (xy 121.363293 -276.456948)
			(xy 121.400016 -276.493671) (xy 121.430542 -276.535687) (xy 121.45412 -276.581961) (xy 121.470168 -276.631354)
			(xy 121.478293 -276.682649) (xy 121.478802 -276.708616) (xy 121.478293 -276.734583) (xy 122.698003 -276.734583)
			(xy 122.698003 -276.682649) (xy 122.706128 -276.631354) (xy 122.722176 -276.581961) (xy 122.745754 -276.535687)
			(xy 122.77628 -276.493671) (xy 122.813003 -276.456948) (xy 122.855019 -276.426422) (xy 122.901293 -276.402844)
			(xy 122.950686 -276.386796) (xy 123.001981 -276.378671) (xy 123.053915 -276.378671) (xy 123.10521 -276.386796)
			(xy 123.154603 -276.402844) (xy 123.200877 -276.426422) (xy 123.242893 -276.456948) (xy 123.279616 -276.493671)
			(xy 123.310142 -276.535687) (xy 123.33372 -276.581961) (xy 123.349768 -276.631354) (xy 123.357893 -276.682649)
			(xy 123.358402 -276.708616) (xy 123.357893 -276.734583) (xy 123.637803 -276.734583) (xy 123.637803 -276.682649)
			(xy 123.645928 -276.631354) (xy 123.661976 -276.581961) (xy 123.685554 -276.535687) (xy 123.71608 -276.493671)
			(xy 123.752803 -276.456948) (xy 123.794819 -276.426422) (xy 123.841093 -276.402844) (xy 123.890486 -276.386796)
			(xy 123.941781 -276.378671) (xy 123.993715 -276.378671) (xy 124.04501 -276.386796) (xy 124.094403 -276.402844)
			(xy 124.140677 -276.426422) (xy 124.182693 -276.456948) (xy 124.219416 -276.493671) (xy 124.249942 -276.535687)
			(xy 124.27352 -276.581961) (xy 124.289568 -276.631354) (xy 124.297693 -276.682649) (xy 124.298202 -276.708616)
			(xy 124.297693 -276.734583) (xy 124.577603 -276.734583) (xy 124.577603 -276.682649) (xy 124.585728 -276.631354)
			(xy 124.601776 -276.581961) (xy 124.625354 -276.535687) (xy 124.65588 -276.493671) (xy 124.692603 -276.456948)
			(xy 124.734619 -276.426422) (xy 124.780893 -276.402844) (xy 124.830286 -276.386796) (xy 124.881581 -276.378671)
			(xy 124.933515 -276.378671) (xy 124.98481 -276.386796) (xy 125.034203 -276.402844) (xy 125.080477 -276.426422)
			(xy 125.122493 -276.456948) (xy 125.159216 -276.493671) (xy 125.189742 -276.535687) (xy 125.21332 -276.581961)
			(xy 125.229368 -276.631354) (xy 125.237493 -276.682649) (xy 125.238002 -276.708616) (xy 125.237493 -276.734583)
			(xy 125.517149 -276.734583) (xy 125.517149 -276.682649) (xy 125.525274 -276.631354) (xy 125.541322 -276.581961)
			(xy 125.5649 -276.535687) (xy 125.595426 -276.493671) (xy 125.632149 -276.456948) (xy 125.674165 -276.426422)
			(xy 125.720439 -276.402844) (xy 125.769832 -276.386796) (xy 125.821127 -276.378671) (xy 125.873061 -276.378671)
			(xy 125.924356 -276.386796) (xy 125.973749 -276.402844) (xy 126.020023 -276.426422) (xy 126.062039 -276.456948)
			(xy 126.098762 -276.493671) (xy 126.129288 -276.535687) (xy 126.152866 -276.581961) (xy 126.168914 -276.631354)
			(xy 126.177039 -276.682649) (xy 126.177548 -276.708616) (xy 126.177039 -276.734583) (xy 126.457203 -276.734583)
			(xy 126.457203 -276.682649) (xy 126.465328 -276.631354) (xy 126.481376 -276.581961) (xy 126.504954 -276.535687)
			(xy 126.53548 -276.493671) (xy 126.572203 -276.456948) (xy 126.614219 -276.426422) (xy 126.660493 -276.402844)
			(xy 126.709886 -276.386796) (xy 126.761181 -276.378671) (xy 126.813115 -276.378671) (xy 126.86441 -276.386796)
			(xy 126.913803 -276.402844) (xy 126.960077 -276.426422) (xy 127.002093 -276.456948) (xy 127.038816 -276.493671)
			(xy 127.069342 -276.535687) (xy 127.09292 -276.581961) (xy 127.108968 -276.631354) (xy 127.117093 -276.682649)
			(xy 127.117602 -276.708616) (xy 127.117093 -276.734583) (xy 127.397003 -276.734583) (xy 127.397003 -276.682649)
			(xy 127.405128 -276.631354) (xy 127.421176 -276.581961) (xy 127.444754 -276.535687) (xy 127.47528 -276.493671)
			(xy 127.512003 -276.456948) (xy 127.554019 -276.426422) (xy 127.600293 -276.402844) (xy 127.649686 -276.386796)
			(xy 127.700981 -276.378671) (xy 127.752915 -276.378671) (xy 127.80421 -276.386796) (xy 127.853603 -276.402844)
			(xy 127.899877 -276.426422) (xy 127.941893 -276.456948) (xy 127.978616 -276.493671) (xy 128.009142 -276.535687)
			(xy 128.03272 -276.581961) (xy 128.048768 -276.631354) (xy 128.056893 -276.682649) (xy 128.057402 -276.708616)
			(xy 128.056893 -276.734583) (xy 128.336803 -276.734583) (xy 128.336803 -276.682649) (xy 128.344928 -276.631354)
			(xy 128.360976 -276.581961) (xy 128.384554 -276.535687) (xy 128.41508 -276.493671) (xy 128.451803 -276.456948)
			(xy 128.493819 -276.426422) (xy 128.540093 -276.402844) (xy 128.589486 -276.386796) (xy 128.640781 -276.378671)
			(xy 128.692715 -276.378671) (xy 128.74401 -276.386796) (xy 128.793403 -276.402844) (xy 128.839677 -276.426422)
			(xy 128.881693 -276.456948) (xy 128.918416 -276.493671) (xy 128.948942 -276.535687) (xy 128.97252 -276.581961)
			(xy 128.988568 -276.631354) (xy 128.996693 -276.682649) (xy 128.997202 -276.708616) (xy 128.996693 -276.734583)
			(xy 129.276603 -276.734583) (xy 129.276603 -276.682649) (xy 129.284728 -276.631354) (xy 129.300776 -276.581961)
			(xy 129.324354 -276.535687) (xy 129.35488 -276.493671) (xy 129.391603 -276.456948) (xy 129.433619 -276.426422)
			(xy 129.479893 -276.402844) (xy 129.529286 -276.386796) (xy 129.580581 -276.378671) (xy 129.632515 -276.378671)
			(xy 129.68381 -276.386796) (xy 129.733203 -276.402844) (xy 129.779477 -276.426422) (xy 129.821493 -276.456948)
			(xy 129.858216 -276.493671) (xy 129.888742 -276.535687) (xy 129.91232 -276.581961) (xy 129.928368 -276.631354)
			(xy 129.936493 -276.682649) (xy 129.937002 -276.708616) (xy 129.936493 -276.734583) (xy 130.216403 -276.734583)
			(xy 130.216403 -276.682649) (xy 130.224528 -276.631354) (xy 130.240576 -276.581961) (xy 130.264154 -276.535687)
			(xy 130.29468 -276.493671) (xy 130.331403 -276.456948) (xy 130.373419 -276.426422) (xy 130.419693 -276.402844)
			(xy 130.469086 -276.386796) (xy 130.520381 -276.378671) (xy 130.572315 -276.378671) (xy 130.62361 -276.386796)
			(xy 130.673003 -276.402844) (xy 130.719277 -276.426422) (xy 130.761293 -276.456948) (xy 130.798016 -276.493671)
			(xy 130.828542 -276.535687) (xy 130.85212 -276.581961) (xy 130.868168 -276.631354) (xy 130.876293 -276.682649)
			(xy 130.876802 -276.708616) (xy 130.876293 -276.734583) (xy 130.868168 -276.785878) (xy 130.85212 -276.835271)
			(xy 130.828542 -276.881545) (xy 130.798016 -276.923561) (xy 130.761293 -276.960284) (xy 130.719277 -276.99081)
			(xy 130.673003 -277.014388) (xy 130.62361 -277.030436) (xy 130.572315 -277.038561) (xy 130.520381 -277.038561)
			(xy 130.469086 -277.030436) (xy 130.419693 -277.014388) (xy 130.373419 -276.99081) (xy 130.331403 -276.960284)
			(xy 130.29468 -276.923561) (xy 130.264154 -276.881545) (xy 130.240576 -276.835271) (xy 130.224528 -276.785878)
			(xy 130.216403 -276.734583) (xy 129.936493 -276.734583) (xy 129.928368 -276.785878) (xy 129.91232 -276.835271)
			(xy 129.888742 -276.881545) (xy 129.858216 -276.923561) (xy 129.821493 -276.960284) (xy 129.779477 -276.99081)
			(xy 129.733203 -277.014388) (xy 129.68381 -277.030436) (xy 129.632515 -277.038561) (xy 129.580581 -277.038561)
			(xy 129.529286 -277.030436) (xy 129.479893 -277.014388) (xy 129.433619 -276.99081) (xy 129.391603 -276.960284)
			(xy 129.35488 -276.923561) (xy 129.324354 -276.881545) (xy 129.300776 -276.835271) (xy 129.284728 -276.785878)
			(xy 129.276603 -276.734583) (xy 128.996693 -276.734583) (xy 128.988568 -276.785878) (xy 128.97252 -276.835271)
			(xy 128.948942 -276.881545) (xy 128.918416 -276.923561) (xy 128.881693 -276.960284) (xy 128.839677 -276.99081)
			(xy 128.793403 -277.014388) (xy 128.74401 -277.030436) (xy 128.692715 -277.038561) (xy 128.640781 -277.038561)
			(xy 128.589486 -277.030436) (xy 128.540093 -277.014388) (xy 128.493819 -276.99081) (xy 128.451803 -276.960284)
			(xy 128.41508 -276.923561) (xy 128.384554 -276.881545) (xy 128.360976 -276.835271) (xy 128.344928 -276.785878)
			(xy 128.336803 -276.734583) (xy 128.056893 -276.734583) (xy 128.048768 -276.785878) (xy 128.03272 -276.835271)
			(xy 128.009142 -276.881545) (xy 127.978616 -276.923561) (xy 127.941893 -276.960284) (xy 127.899877 -276.99081)
			(xy 127.853603 -277.014388) (xy 127.80421 -277.030436) (xy 127.752915 -277.038561) (xy 127.700981 -277.038561)
			(xy 127.649686 -277.030436) (xy 127.600293 -277.014388) (xy 127.554019 -276.99081) (xy 127.512003 -276.960284)
			(xy 127.47528 -276.923561) (xy 127.444754 -276.881545) (xy 127.421176 -276.835271) (xy 127.405128 -276.785878)
			(xy 127.397003 -276.734583) (xy 127.117093 -276.734583) (xy 127.108968 -276.785878) (xy 127.09292 -276.835271)
			(xy 127.069342 -276.881545) (xy 127.038816 -276.923561) (xy 127.002093 -276.960284) (xy 126.960077 -276.99081)
			(xy 126.913803 -277.014388) (xy 126.86441 -277.030436) (xy 126.813115 -277.038561) (xy 126.761181 -277.038561)
			(xy 126.709886 -277.030436) (xy 126.660493 -277.014388) (xy 126.614219 -276.99081) (xy 126.572203 -276.960284)
			(xy 126.53548 -276.923561) (xy 126.504954 -276.881545) (xy 126.481376 -276.835271) (xy 126.465328 -276.785878)
			(xy 126.457203 -276.734583) (xy 126.177039 -276.734583) (xy 126.168914 -276.785878) (xy 126.152866 -276.835271)
			(xy 126.129288 -276.881545) (xy 126.098762 -276.923561) (xy 126.062039 -276.960284) (xy 126.020023 -276.99081)
			(xy 125.973749 -277.014388) (xy 125.924356 -277.030436) (xy 125.873061 -277.038561) (xy 125.821127 -277.038561)
			(xy 125.769832 -277.030436) (xy 125.720439 -277.014388) (xy 125.674165 -276.99081) (xy 125.632149 -276.960284)
			(xy 125.595426 -276.923561) (xy 125.5649 -276.881545) (xy 125.541322 -276.835271) (xy 125.525274 -276.785878)
			(xy 125.517149 -276.734583) (xy 125.237493 -276.734583) (xy 125.229368 -276.785878) (xy 125.21332 -276.835271)
			(xy 125.189742 -276.881545) (xy 125.159216 -276.923561) (xy 125.122493 -276.960284) (xy 125.080477 -276.99081)
			(xy 125.034203 -277.014388) (xy 124.98481 -277.030436) (xy 124.933515 -277.038561) (xy 124.881581 -277.038561)
			(xy 124.830286 -277.030436) (xy 124.780893 -277.014388) (xy 124.734619 -276.99081) (xy 124.692603 -276.960284)
			(xy 124.65588 -276.923561) (xy 124.625354 -276.881545) (xy 124.601776 -276.835271) (xy 124.585728 -276.785878)
			(xy 124.577603 -276.734583) (xy 124.297693 -276.734583) (xy 124.289568 -276.785878) (xy 124.27352 -276.835271)
			(xy 124.249942 -276.881545) (xy 124.219416 -276.923561) (xy 124.182693 -276.960284) (xy 124.140677 -276.99081)
			(xy 124.094403 -277.014388) (xy 124.04501 -277.030436) (xy 123.993715 -277.038561) (xy 123.941781 -277.038561)
			(xy 123.890486 -277.030436) (xy 123.841093 -277.014388) (xy 123.794819 -276.99081) (xy 123.752803 -276.960284)
			(xy 123.71608 -276.923561) (xy 123.685554 -276.881545) (xy 123.661976 -276.835271) (xy 123.645928 -276.785878)
			(xy 123.637803 -276.734583) (xy 123.357893 -276.734583) (xy 123.349768 -276.785878) (xy 123.33372 -276.835271)
			(xy 123.310142 -276.881545) (xy 123.279616 -276.923561) (xy 123.242893 -276.960284) (xy 123.200877 -276.99081)
			(xy 123.154603 -277.014388) (xy 123.10521 -277.030436) (xy 123.053915 -277.038561) (xy 123.001981 -277.038561)
			(xy 122.950686 -277.030436) (xy 122.901293 -277.014388) (xy 122.855019 -276.99081) (xy 122.813003 -276.960284)
			(xy 122.77628 -276.923561) (xy 122.745754 -276.881545) (xy 122.722176 -276.835271) (xy 122.706128 -276.785878)
			(xy 122.698003 -276.734583) (xy 121.478293 -276.734583) (xy 121.470168 -276.785878) (xy 121.45412 -276.835271)
			(xy 121.430542 -276.881545) (xy 121.400016 -276.923561) (xy 121.363293 -276.960284) (xy 121.321277 -276.99081)
			(xy 121.275003 -277.014388) (xy 121.22561 -277.030436) (xy 121.174315 -277.038561) (xy 121.122381 -277.038561)
			(xy 121.071086 -277.030436) (xy 121.021693 -277.014388) (xy 120.975419 -276.99081) (xy 120.933403 -276.960284)
			(xy 120.89668 -276.923561) (xy 120.866154 -276.881545) (xy 120.842576 -276.835271) (xy 120.826528 -276.785878)
			(xy 120.818403 -276.734583) (xy 120.538199 -276.734583) (xy 120.530114 -276.785624) (xy 120.514066 -276.835017)
			(xy 120.490488 -276.881291) (xy 120.459962 -276.923307) (xy 120.423239 -276.96003) (xy 120.381223 -276.990556)
			(xy 120.334949 -277.014134) (xy 120.285556 -277.030182) (xy 120.234261 -277.038307) (xy 120.182327 -277.038307)
			(xy 120.131032 -277.030182) (xy 120.081639 -277.014134) (xy 120.035365 -276.990556) (xy 119.993349 -276.96003)
			(xy 119.956626 -276.923307) (xy 119.9261 -276.881291) (xy 119.902522 -276.835017) (xy 119.886474 -276.785624)
			(xy 119.878349 -276.734329) (xy 119.598444 -276.734329) (xy 119.598439 -276.734583) (xy 119.590314 -276.785878)
			(xy 119.574266 -276.835271) (xy 119.550688 -276.881545) (xy 119.520162 -276.923561) (xy 119.483439 -276.960284)
			(xy 119.441423 -276.99081) (xy 119.395149 -277.014388) (xy 119.345756 -277.030436) (xy 119.294461 -277.038561)
			(xy 119.242527 -277.038561) (xy 119.191232 -277.030436) (xy 119.141839 -277.014388) (xy 119.095565 -276.99081)
			(xy 119.053549 -276.960284) (xy 119.016826 -276.923561) (xy 118.9863 -276.881545) (xy 118.962722 -276.835271)
			(xy 118.946674 -276.785878) (xy 118.938549 -276.734583) (xy 118.658599 -276.734583) (xy 118.650514 -276.785624)
			(xy 118.634466 -276.835017) (xy 118.610888 -276.881291) (xy 118.580362 -276.923307) (xy 118.543639 -276.96003)
			(xy 118.501623 -276.990556) (xy 118.455349 -277.014134) (xy 118.405956 -277.030182) (xy 118.354661 -277.038307)
			(xy 118.302727 -277.038307) (xy 118.251432 -277.030182) (xy 118.202039 -277.014134) (xy 118.155765 -276.990556)
			(xy 118.113749 -276.96003) (xy 118.077026 -276.923307) (xy 118.0465 -276.881291) (xy 118.022922 -276.835017)
			(xy 118.006874 -276.785624) (xy 117.998749 -276.734329) (xy 117.718839 -276.734329) (xy 117.710714 -276.785624)
			(xy 117.694666 -276.835017) (xy 117.671088 -276.881291) (xy 117.640562 -276.923307) (xy 117.603839 -276.96003)
			(xy 117.561823 -276.990556) (xy 117.515549 -277.014134) (xy 117.466156 -277.030182) (xy 117.414861 -277.038307)
			(xy 117.362927 -277.038307) (xy 117.311632 -277.030182) (xy 117.262239 -277.014134) (xy 117.215965 -276.990556)
			(xy 117.173949 -276.96003) (xy 117.137226 -276.923307) (xy 117.1067 -276.881291) (xy 117.083122 -276.835017)
			(xy 117.067074 -276.785624) (xy 117.058949 -276.734329) (xy 116.779049 -276.734329) (xy 116.779049 -276.734384)
			(xy 116.770923 -276.785678) (xy 116.754872 -276.83507) (xy 116.731292 -276.881343) (xy 116.700765 -276.923358)
			(xy 116.66404 -276.960079) (xy 116.622024 -276.990604) (xy 116.575749 -277.014181) (xy 116.526356 -277.030228)
			(xy 116.475061 -277.038351) (xy 116.449094 -277.038816) (xy 116.44249 -277.038816) (xy 116.427377 -277.039055)
			(xy 116.398315 -277.0473) (xy 116.372939 -277.06369) (xy 116.353471 -277.086789) (xy 116.341616 -277.114575)
			(xy 116.338412 -277.144614) (xy 116.344141 -277.174274) (xy 116.358299 -277.20096) (xy 116.368576 -277.212044)
			(xy 116.497354 -277.340822) (xy 116.508073 -277.35081) (xy 116.533836 -277.364735) (xy 116.562489 -277.370791)
			(xy 116.591683 -277.368481) (xy 116.619027 -277.357995) (xy 116.64228 -277.340191) (xy 116.651278 -277.32863)
			(xy 116.666928 -277.307836) (xy 116.70367 -277.270981) (xy 116.745737 -277.240343) (xy 116.792087 -277.21668)
			(xy 116.841574 -277.200577) (xy 116.892973 -277.192432) (xy 116.918994 -277.191978) (xy 116.944963 -277.19246)
			(xy 116.996261 -277.200585) (xy 117.045656 -277.216635) (xy 117.091932 -277.240214) (xy 117.133949 -277.270744)
			(xy 117.170673 -277.30747) (xy 117.201199 -277.34949) (xy 117.224775 -277.395768) (xy 117.240821 -277.445165)
			(xy 117.248942 -277.496463) (xy 117.249448 -277.522432) (xy 117.248966 -277.548145) (xy 117.529103 -277.548145)
			(xy 117.529103 -277.496211) (xy 117.537228 -277.444916) (xy 117.553276 -277.395523) (xy 117.576854 -277.349249)
			(xy 117.60738 -277.307233) (xy 117.644103 -277.27051) (xy 117.686119 -277.239984) (xy 117.732393 -277.216406)
			(xy 117.781786 -277.200358) (xy 117.833081 -277.192233) (xy 117.885015 -277.192233) (xy 117.93631 -277.200358)
			(xy 117.985703 -277.216406) (xy 118.031977 -277.239984) (xy 118.073993 -277.27051) (xy 118.110716 -277.307233)
			(xy 118.141242 -277.349249) (xy 118.16482 -277.395523) (xy 118.180868 -277.444916) (xy 118.188993 -277.496211)
			(xy 118.189502 -277.522178) (xy 118.188993 -277.548145) (xy 118.188953 -277.548399) (xy 118.468903 -277.548399)
			(xy 118.468903 -277.496465) (xy 118.477028 -277.44517) (xy 118.493076 -277.395777) (xy 118.516654 -277.349503)
			(xy 118.54718 -277.307487) (xy 118.583903 -277.270764) (xy 118.625919 -277.240238) (xy 118.672193 -277.21666)
			(xy 118.721586 -277.200612) (xy 118.772881 -277.192487) (xy 118.824815 -277.192487) (xy 118.87611 -277.200612)
			(xy 118.925503 -277.21666) (xy 118.971777 -277.240238) (xy 119.013793 -277.270764) (xy 119.050516 -277.307487)
			(xy 119.081042 -277.349503) (xy 119.10462 -277.395777) (xy 119.120668 -277.44517) (xy 119.128793 -277.496465)
			(xy 119.129302 -277.522432) (xy 119.128798 -277.548145) (xy 119.408703 -277.548145) (xy 119.408703 -277.496211)
			(xy 119.416828 -277.444916) (xy 119.432876 -277.395523) (xy 119.456454 -277.349249) (xy 119.48698 -277.307233)
			(xy 119.523703 -277.27051) (xy 119.565719 -277.239984) (xy 119.611993 -277.216406) (xy 119.661386 -277.200358)
			(xy 119.712681 -277.192233) (xy 119.764615 -277.192233) (xy 119.81591 -277.200358) (xy 119.865303 -277.216406)
			(xy 119.911577 -277.239984) (xy 119.953593 -277.27051) (xy 119.990316 -277.307233) (xy 120.020842 -277.349249)
			(xy 120.04442 -277.395523) (xy 120.060468 -277.444916) (xy 120.068593 -277.496211) (xy 120.069102 -277.522178)
			(xy 120.068593 -277.548145) (xy 120.348503 -277.548145) (xy 120.348503 -277.496211) (xy 120.356628 -277.444916)
			(xy 120.372676 -277.395523) (xy 120.396254 -277.349249) (xy 120.42678 -277.307233) (xy 120.463503 -277.27051)
			(xy 120.505519 -277.239984) (xy 120.551793 -277.216406) (xy 120.601186 -277.200358) (xy 120.652481 -277.192233)
			(xy 120.704415 -277.192233) (xy 120.75571 -277.200358) (xy 120.805103 -277.216406) (xy 120.851377 -277.239984)
			(xy 120.893393 -277.27051) (xy 120.930116 -277.307233) (xy 120.960642 -277.349249) (xy 120.98422 -277.395523)
			(xy 121.000268 -277.444916) (xy 121.008393 -277.496211) (xy 121.008902 -277.522178) (xy 121.008393 -277.548145)
			(xy 121.288303 -277.548145) (xy 121.288303 -277.496211) (xy 121.296428 -277.444916) (xy 121.312476 -277.395523)
			(xy 121.336054 -277.349249) (xy 121.36658 -277.307233) (xy 121.403303 -277.27051) (xy 121.445319 -277.239984)
			(xy 121.491593 -277.216406) (xy 121.540986 -277.200358) (xy 121.592281 -277.192233) (xy 121.644215 -277.192233)
			(xy 121.69551 -277.200358) (xy 121.744903 -277.216406) (xy 121.791177 -277.239984) (xy 121.833193 -277.27051)
			(xy 121.869916 -277.307233) (xy 121.900442 -277.349249) (xy 121.92402 -277.395523) (xy 121.940068 -277.444916)
			(xy 121.948193 -277.496211) (xy 121.948702 -277.522178) (xy 121.948193 -277.548145) (xy 122.228103 -277.548145)
			(xy 122.228103 -277.496211) (xy 122.236228 -277.444916) (xy 122.252276 -277.395523) (xy 122.275854 -277.349249)
			(xy 122.30638 -277.307233) (xy 122.343103 -277.27051) (xy 122.385119 -277.239984) (xy 122.431393 -277.216406)
			(xy 122.480786 -277.200358) (xy 122.532081 -277.192233) (xy 122.584015 -277.192233) (xy 122.63531 -277.200358)
			(xy 122.684703 -277.216406) (xy 122.730977 -277.239984) (xy 122.772993 -277.27051) (xy 122.809716 -277.307233)
			(xy 122.840242 -277.349249) (xy 122.86382 -277.395523) (xy 122.879868 -277.444916) (xy 122.887993 -277.496211)
			(xy 122.888502 -277.522178) (xy 122.887993 -277.548145) (xy 122.887953 -277.548399) (xy 123.167649 -277.548399)
			(xy 123.167649 -277.496465) (xy 123.175774 -277.44517) (xy 123.191822 -277.395777) (xy 123.2154 -277.349503)
			(xy 123.245926 -277.307487) (xy 123.282649 -277.270764) (xy 123.324665 -277.240238) (xy 123.370939 -277.21666)
			(xy 123.420332 -277.200612) (xy 123.471627 -277.192487) (xy 123.523561 -277.192487) (xy 123.574856 -277.200612)
			(xy 123.624249 -277.21666) (xy 123.670523 -277.240238) (xy 123.712539 -277.270764) (xy 123.749262 -277.307487)
			(xy 123.779788 -277.349503) (xy 123.803366 -277.395777) (xy 123.819414 -277.44517) (xy 123.827539 -277.496465)
			(xy 123.828048 -277.522432) (xy 123.827539 -277.548399) (xy 124.107449 -277.548399) (xy 124.107449 -277.496465)
			(xy 124.115574 -277.44517) (xy 124.131622 -277.395777) (xy 124.1552 -277.349503) (xy 124.185726 -277.307487)
			(xy 124.222449 -277.270764) (xy 124.264465 -277.240238) (xy 124.310739 -277.21666) (xy 124.360132 -277.200612)
			(xy 124.411427 -277.192487) (xy 124.463361 -277.192487) (xy 124.514656 -277.200612) (xy 124.564049 -277.21666)
			(xy 124.610323 -277.240238) (xy 124.652339 -277.270764) (xy 124.689062 -277.307487) (xy 124.719588 -277.349503)
			(xy 124.743166 -277.395777) (xy 124.759214 -277.44517) (xy 124.767339 -277.496465) (xy 124.767848 -277.522432)
			(xy 124.767339 -277.548399) (xy 125.047503 -277.548399) (xy 125.047503 -277.496465) (xy 125.055628 -277.44517)
			(xy 125.071676 -277.395777) (xy 125.095254 -277.349503) (xy 125.12578 -277.307487) (xy 125.162503 -277.270764)
			(xy 125.204519 -277.240238) (xy 125.250793 -277.21666) (xy 125.300186 -277.200612) (xy 125.351481 -277.192487)
			(xy 125.403415 -277.192487) (xy 125.45471 -277.200612) (xy 125.504103 -277.21666) (xy 125.550377 -277.240238)
			(xy 125.592393 -277.270764) (xy 125.629116 -277.307487) (xy 125.659642 -277.349503) (xy 125.68322 -277.395777)
			(xy 125.699268 -277.44517) (xy 125.707393 -277.496465) (xy 125.707902 -277.522432) (xy 125.707393 -277.548399)
			(xy 125.987049 -277.548399) (xy 125.987049 -277.496465) (xy 125.995174 -277.44517) (xy 126.011222 -277.395777)
			(xy 126.0348 -277.349503) (xy 126.065326 -277.307487) (xy 126.102049 -277.270764) (xy 126.144065 -277.240238)
			(xy 126.190339 -277.21666) (xy 126.239732 -277.200612) (xy 126.291027 -277.192487) (xy 126.342961 -277.192487)
			(xy 126.394256 -277.200612) (xy 126.443649 -277.21666) (xy 126.489923 -277.240238) (xy 126.531939 -277.270764)
			(xy 126.568662 -277.307487) (xy 126.599188 -277.349503) (xy 126.622766 -277.395777) (xy 126.638814 -277.44517)
			(xy 126.646939 -277.496465) (xy 126.647448 -277.522432) (xy 126.646939 -277.548399) (xy 126.926849 -277.548399)
			(xy 126.926849 -277.496465) (xy 126.934974 -277.44517) (xy 126.951022 -277.395777) (xy 126.9746 -277.349503)
			(xy 127.005126 -277.307487) (xy 127.041849 -277.270764) (xy 127.083865 -277.240238) (xy 127.130139 -277.21666)
			(xy 127.179532 -277.200612) (xy 127.230827 -277.192487) (xy 127.282761 -277.192487) (xy 127.334056 -277.200612)
			(xy 127.383449 -277.21666) (xy 127.429723 -277.240238) (xy 127.471739 -277.270764) (xy 127.508462 -277.307487)
			(xy 127.538988 -277.349503) (xy 127.562566 -277.395777) (xy 127.578614 -277.44517) (xy 127.586739 -277.496465)
			(xy 127.587248 -277.522432) (xy 127.586739 -277.548399) (xy 127.866649 -277.548399) (xy 127.866649 -277.496465)
			(xy 127.874774 -277.44517) (xy 127.890822 -277.395777) (xy 127.9144 -277.349503) (xy 127.944926 -277.307487)
			(xy 127.981649 -277.270764) (xy 128.023665 -277.240238) (xy 128.069939 -277.21666) (xy 128.119332 -277.200612)
			(xy 128.170627 -277.192487) (xy 128.222561 -277.192487) (xy 128.273856 -277.200612) (xy 128.323249 -277.21666)
			(xy 128.369523 -277.240238) (xy 128.411539 -277.270764) (xy 128.448262 -277.307487) (xy 128.478788 -277.349503)
			(xy 128.502366 -277.395777) (xy 128.518414 -277.44517) (xy 128.526539 -277.496465) (xy 128.527048 -277.522432)
			(xy 128.526539 -277.548399) (xy 128.806449 -277.548399) (xy 128.806449 -277.496465) (xy 128.814574 -277.44517)
			(xy 128.830622 -277.395777) (xy 128.8542 -277.349503) (xy 128.884726 -277.307487) (xy 128.921449 -277.270764)
			(xy 128.963465 -277.240238) (xy 129.009739 -277.21666) (xy 129.059132 -277.200612) (xy 129.110427 -277.192487)
			(xy 129.162361 -277.192487) (xy 129.213656 -277.200612) (xy 129.263049 -277.21666) (xy 129.309323 -277.240238)
			(xy 129.351339 -277.270764) (xy 129.388062 -277.307487) (xy 129.418588 -277.349503) (xy 129.442166 -277.395777)
			(xy 129.458214 -277.44517) (xy 129.466339 -277.496465) (xy 129.466848 -277.522432) (xy 129.466339 -277.548399)
			(xy 129.746503 -277.548399) (xy 129.746503 -277.496465) (xy 129.754628 -277.44517) (xy 129.770676 -277.395777)
			(xy 129.794254 -277.349503) (xy 129.82478 -277.307487) (xy 129.861503 -277.270764) (xy 129.903519 -277.240238)
			(xy 129.949793 -277.21666) (xy 129.999186 -277.200612) (xy 130.050481 -277.192487) (xy 130.102415 -277.192487)
			(xy 130.15371 -277.200612) (xy 130.203103 -277.21666) (xy 130.249377 -277.240238) (xy 130.291393 -277.270764)
			(xy 130.328116 -277.307487) (xy 130.358642 -277.349503) (xy 130.38222 -277.395777) (xy 130.398268 -277.44517)
			(xy 130.406393 -277.496465) (xy 130.406902 -277.522432) (xy 130.406393 -277.548399) (xy 130.686303 -277.548399)
			(xy 130.686303 -277.496465) (xy 130.694428 -277.44517) (xy 130.710476 -277.395777) (xy 130.734054 -277.349503)
			(xy 130.76458 -277.307487) (xy 130.801303 -277.270764) (xy 130.843319 -277.240238) (xy 130.889593 -277.21666)
			(xy 130.938986 -277.200612) (xy 130.990281 -277.192487) (xy 131.042215 -277.192487) (xy 131.09351 -277.200612)
			(xy 131.142903 -277.21666) (xy 131.189177 -277.240238) (xy 131.231193 -277.270764) (xy 131.267916 -277.307487)
			(xy 131.298442 -277.349503) (xy 131.32202 -277.395777) (xy 131.338068 -277.44517) (xy 131.346193 -277.496465)
			(xy 131.346702 -277.522432) (xy 131.346193 -277.548399) (xy 131.338068 -277.599694) (xy 131.32202 -277.649087)
			(xy 131.298442 -277.695361) (xy 131.267916 -277.737377) (xy 131.231193 -277.7741) (xy 131.189177 -277.804626)
			(xy 131.142903 -277.828204) (xy 131.09351 -277.844252) (xy 131.042215 -277.852377) (xy 130.990281 -277.852377)
			(xy 130.938986 -277.844252) (xy 130.889593 -277.828204) (xy 130.843319 -277.804626) (xy 130.801303 -277.7741)
			(xy 130.76458 -277.737377) (xy 130.734054 -277.695361) (xy 130.710476 -277.649087) (xy 130.694428 -277.599694)
			(xy 130.686303 -277.548399) (xy 130.406393 -277.548399) (xy 130.398268 -277.599694) (xy 130.38222 -277.649087)
			(xy 130.358642 -277.695361) (xy 130.328116 -277.737377) (xy 130.291393 -277.7741) (xy 130.249377 -277.804626)
			(xy 130.203103 -277.828204) (xy 130.15371 -277.844252) (xy 130.102415 -277.852377) (xy 130.050481 -277.852377)
			(xy 129.999186 -277.844252) (xy 129.949793 -277.828204) (xy 129.903519 -277.804626) (xy 129.861503 -277.7741)
			(xy 129.82478 -277.737377) (xy 129.794254 -277.695361) (xy 129.770676 -277.649087) (xy 129.754628 -277.599694)
			(xy 129.746503 -277.548399) (xy 129.466339 -277.548399) (xy 129.458214 -277.599694) (xy 129.442166 -277.649087)
			(xy 129.418588 -277.695361) (xy 129.388062 -277.737377) (xy 129.351339 -277.7741) (xy 129.309323 -277.804626)
			(xy 129.263049 -277.828204) (xy 129.213656 -277.844252) (xy 129.162361 -277.852377) (xy 129.110427 -277.852377)
			(xy 129.059132 -277.844252) (xy 129.009739 -277.828204) (xy 128.963465 -277.804626) (xy 128.921449 -277.7741)
			(xy 128.884726 -277.737377) (xy 128.8542 -277.695361) (xy 128.830622 -277.649087) (xy 128.814574 -277.599694)
			(xy 128.806449 -277.548399) (xy 128.526539 -277.548399) (xy 128.518414 -277.599694) (xy 128.502366 -277.649087)
			(xy 128.478788 -277.695361) (xy 128.448262 -277.737377) (xy 128.411539 -277.7741) (xy 128.369523 -277.804626)
			(xy 128.323249 -277.828204) (xy 128.273856 -277.844252) (xy 128.222561 -277.852377) (xy 128.170627 -277.852377)
			(xy 128.119332 -277.844252) (xy 128.069939 -277.828204) (xy 128.023665 -277.804626) (xy 127.981649 -277.7741)
			(xy 127.944926 -277.737377) (xy 127.9144 -277.695361) (xy 127.890822 -277.649087) (xy 127.874774 -277.599694)
			(xy 127.866649 -277.548399) (xy 127.586739 -277.548399) (xy 127.578614 -277.599694) (xy 127.562566 -277.649087)
			(xy 127.538988 -277.695361) (xy 127.508462 -277.737377) (xy 127.471739 -277.7741) (xy 127.429723 -277.804626)
			(xy 127.383449 -277.828204) (xy 127.334056 -277.844252) (xy 127.282761 -277.852377) (xy 127.230827 -277.852377)
			(xy 127.179532 -277.844252) (xy 127.130139 -277.828204) (xy 127.083865 -277.804626) (xy 127.041849 -277.7741)
			(xy 127.005126 -277.737377) (xy 126.9746 -277.695361) (xy 126.951022 -277.649087) (xy 126.934974 -277.599694)
			(xy 126.926849 -277.548399) (xy 126.646939 -277.548399) (xy 126.638814 -277.599694) (xy 126.622766 -277.649087)
			(xy 126.599188 -277.695361) (xy 126.568662 -277.737377) (xy 126.531939 -277.7741) (xy 126.489923 -277.804626)
			(xy 126.443649 -277.828204) (xy 126.394256 -277.844252) (xy 126.342961 -277.852377) (xy 126.291027 -277.852377)
			(xy 126.239732 -277.844252) (xy 126.190339 -277.828204) (xy 126.144065 -277.804626) (xy 126.102049 -277.7741)
			(xy 126.065326 -277.737377) (xy 126.0348 -277.695361) (xy 126.011222 -277.649087) (xy 125.995174 -277.599694)
			(xy 125.987049 -277.548399) (xy 125.707393 -277.548399) (xy 125.699268 -277.599694) (xy 125.68322 -277.649087)
			(xy 125.659642 -277.695361) (xy 125.629116 -277.737377) (xy 125.592393 -277.7741) (xy 125.550377 -277.804626)
			(xy 125.504103 -277.828204) (xy 125.45471 -277.844252) (xy 125.403415 -277.852377) (xy 125.351481 -277.852377)
			(xy 125.300186 -277.844252) (xy 125.250793 -277.828204) (xy 125.204519 -277.804626) (xy 125.162503 -277.7741)
			(xy 125.12578 -277.737377) (xy 125.095254 -277.695361) (xy 125.071676 -277.649087) (xy 125.055628 -277.599694)
			(xy 125.047503 -277.548399) (xy 124.767339 -277.548399) (xy 124.759214 -277.599694) (xy 124.743166 -277.649087)
			(xy 124.719588 -277.695361) (xy 124.689062 -277.737377) (xy 124.652339 -277.7741) (xy 124.610323 -277.804626)
			(xy 124.564049 -277.828204) (xy 124.514656 -277.844252) (xy 124.463361 -277.852377) (xy 124.411427 -277.852377)
			(xy 124.360132 -277.844252) (xy 124.310739 -277.828204) (xy 124.264465 -277.804626) (xy 124.222449 -277.7741)
			(xy 124.185726 -277.737377) (xy 124.1552 -277.695361) (xy 124.131622 -277.649087) (xy 124.115574 -277.599694)
			(xy 124.107449 -277.548399) (xy 123.827539 -277.548399) (xy 123.819414 -277.599694) (xy 123.803366 -277.649087)
			(xy 123.779788 -277.695361) (xy 123.749262 -277.737377) (xy 123.712539 -277.7741) (xy 123.670523 -277.804626)
			(xy 123.624249 -277.828204) (xy 123.574856 -277.844252) (xy 123.523561 -277.852377) (xy 123.471627 -277.852377)
			(xy 123.420332 -277.844252) (xy 123.370939 -277.828204) (xy 123.324665 -277.804626) (xy 123.282649 -277.7741)
			(xy 123.245926 -277.737377) (xy 123.2154 -277.695361) (xy 123.191822 -277.649087) (xy 123.175774 -277.599694)
			(xy 123.167649 -277.548399) (xy 122.887953 -277.548399) (xy 122.879868 -277.59944) (xy 122.86382 -277.648833)
			(xy 122.840242 -277.695107) (xy 122.809716 -277.737123) (xy 122.772993 -277.773846) (xy 122.730977 -277.804372)
			(xy 122.684703 -277.82795) (xy 122.63531 -277.843998) (xy 122.584015 -277.852123) (xy 122.532081 -277.852123)
			(xy 122.480786 -277.843998) (xy 122.431393 -277.82795) (xy 122.385119 -277.804372) (xy 122.343103 -277.773846)
			(xy 122.30638 -277.737123) (xy 122.275854 -277.695107) (xy 122.252276 -277.648833) (xy 122.236228 -277.59944)
			(xy 122.228103 -277.548145) (xy 121.948193 -277.548145) (xy 121.940068 -277.59944) (xy 121.92402 -277.648833)
			(xy 121.900442 -277.695107) (xy 121.869916 -277.737123) (xy 121.833193 -277.773846) (xy 121.791177 -277.804372)
			(xy 121.744903 -277.82795) (xy 121.69551 -277.843998) (xy 121.644215 -277.852123) (xy 121.592281 -277.852123)
			(xy 121.540986 -277.843998) (xy 121.491593 -277.82795) (xy 121.445319 -277.804372) (xy 121.403303 -277.773846)
			(xy 121.36658 -277.737123) (xy 121.336054 -277.695107) (xy 121.312476 -277.648833) (xy 121.296428 -277.59944)
			(xy 121.288303 -277.548145) (xy 121.008393 -277.548145) (xy 121.000268 -277.59944) (xy 120.98422 -277.648833)
			(xy 120.960642 -277.695107) (xy 120.930116 -277.737123) (xy 120.893393 -277.773846) (xy 120.851377 -277.804372)
			(xy 120.805103 -277.82795) (xy 120.75571 -277.843998) (xy 120.704415 -277.852123) (xy 120.652481 -277.852123)
			(xy 120.601186 -277.843998) (xy 120.551793 -277.82795) (xy 120.505519 -277.804372) (xy 120.463503 -277.773846)
			(xy 120.42678 -277.737123) (xy 120.396254 -277.695107) (xy 120.372676 -277.648833) (xy 120.356628 -277.59944)
			(xy 120.348503 -277.548145) (xy 120.068593 -277.548145) (xy 120.060468 -277.59944) (xy 120.04442 -277.648833)
			(xy 120.020842 -277.695107) (xy 119.990316 -277.737123) (xy 119.953593 -277.773846) (xy 119.911577 -277.804372)
			(xy 119.865303 -277.82795) (xy 119.81591 -277.843998) (xy 119.764615 -277.852123) (xy 119.712681 -277.852123)
			(xy 119.661386 -277.843998) (xy 119.611993 -277.82795) (xy 119.565719 -277.804372) (xy 119.523703 -277.773846)
			(xy 119.48698 -277.737123) (xy 119.456454 -277.695107) (xy 119.432876 -277.648833) (xy 119.416828 -277.59944)
			(xy 119.408703 -277.548145) (xy 119.128798 -277.548145) (xy 119.128793 -277.548399) (xy 119.120668 -277.599694)
			(xy 119.10462 -277.649087) (xy 119.081042 -277.695361) (xy 119.050516 -277.737377) (xy 119.013793 -277.7741)
			(xy 118.971777 -277.804626) (xy 118.925503 -277.828204) (xy 118.87611 -277.844252) (xy 118.824815 -277.852377)
			(xy 118.772881 -277.852377) (xy 118.721586 -277.844252) (xy 118.672193 -277.828204) (xy 118.625919 -277.804626)
			(xy 118.583903 -277.7741) (xy 118.54718 -277.737377) (xy 118.516654 -277.695361) (xy 118.493076 -277.649087)
			(xy 118.477028 -277.599694) (xy 118.468903 -277.548399) (xy 118.188953 -277.548399) (xy 118.180868 -277.59944)
			(xy 118.16482 -277.648833) (xy 118.141242 -277.695107) (xy 118.110716 -277.737123) (xy 118.073993 -277.773846)
			(xy 118.031977 -277.804372) (xy 117.985703 -277.82795) (xy 117.93631 -277.843998) (xy 117.885015 -277.852123)
			(xy 117.833081 -277.852123) (xy 117.781786 -277.843998) (xy 117.732393 -277.82795) (xy 117.686119 -277.804372)
			(xy 117.644103 -277.773846) (xy 117.60738 -277.737123) (xy 117.576854 -277.695107) (xy 117.553276 -277.648833)
			(xy 117.537228 -277.59944) (xy 117.529103 -277.548145) (xy 117.248966 -277.548145) (xy 117.24896 -277.54845)
			(xy 117.240804 -277.599842) (xy 117.2247 -277.649323) (xy 117.201043 -277.695671) (xy 117.17042 -277.737741)
			(xy 117.133584 -277.774495) (xy 117.112796 -277.790148) (xy 117.101203 -277.799132) (xy 117.083317 -277.822361)
			(xy 117.07278 -277.849719) (xy 117.070465 -277.878945) (xy 117.076562 -277.907621) (xy 117.090568 -277.933377)
			(xy 117.100604 -277.944072) (xy 117.211602 -278.05507) (xy 117.244114 -278.039068) (xy 117.266704 -278.028583)
			(xy 117.314252 -278.013768) (xy 117.363485 -278.006259) (xy 117.388386 -278.005794) (xy 117.388894 -278.005794)
			(xy 117.414862 -278.006276) (xy 117.466159 -278.014401) (xy 117.515554 -278.030451) (xy 117.561829 -278.054031)
			(xy 117.603845 -278.08456) (xy 117.640567 -278.121287) (xy 117.671091 -278.163307) (xy 117.694665 -278.209585)
			(xy 117.710709 -278.258982) (xy 117.718827 -278.31028) (xy 117.719348 -278.336248) (xy 117.719348 -278.336756)
			(xy 117.718877 -278.361656) (xy 117.718792 -278.362215) (xy 117.998749 -278.362215) (xy 117.998749 -278.310281)
			(xy 118.006874 -278.258986) (xy 118.022922 -278.209593) (xy 118.0465 -278.163319) (xy 118.077026 -278.121303)
			(xy 118.113749 -278.08458) (xy 118.155765 -278.054054) (xy 118.202039 -278.030476) (xy 118.251432 -278.014428)
			(xy 118.302727 -278.006303) (xy 118.354661 -278.006303) (xy 118.405956 -278.014428) (xy 118.455349 -278.030476)
			(xy 118.501623 -278.054054) (xy 118.543639 -278.08458) (xy 118.580362 -278.121303) (xy 118.610888 -278.163319)
			(xy 118.634466 -278.209593) (xy 118.650514 -278.258986) (xy 118.658639 -278.310281) (xy 118.659148 -278.336248)
			(xy 118.658639 -278.362215) (xy 118.658599 -278.362469) (xy 118.938803 -278.362469) (xy 118.938803 -278.310535)
			(xy 118.946928 -278.25924) (xy 118.962976 -278.209847) (xy 118.986554 -278.163573) (xy 119.01708 -278.121557)
			(xy 119.053803 -278.084834) (xy 119.095819 -278.054308) (xy 119.142093 -278.03073) (xy 119.191486 -278.014682)
			(xy 119.242781 -278.006557) (xy 119.294715 -278.006557) (xy 119.34601 -278.014682) (xy 119.395403 -278.03073)
			(xy 119.441677 -278.054308) (xy 119.483693 -278.084834) (xy 119.520416 -278.121557) (xy 119.550942 -278.163573)
			(xy 119.57452 -278.209847) (xy 119.590568 -278.25924) (xy 119.598693 -278.310535) (xy 119.599202 -278.336502)
			(xy 119.598698 -278.362215) (xy 120.818149 -278.362215) (xy 120.818149 -278.310281) (xy 120.826274 -278.258986)
			(xy 120.842322 -278.209593) (xy 120.8659 -278.163319) (xy 120.896426 -278.121303) (xy 120.933149 -278.08458)
			(xy 120.975165 -278.054054) (xy 121.021439 -278.030476) (xy 121.070832 -278.014428) (xy 121.122127 -278.006303)
			(xy 121.174061 -278.006303) (xy 121.225356 -278.014428) (xy 121.274749 -278.030476) (xy 121.321023 -278.054054)
			(xy 121.363039 -278.08458) (xy 121.399762 -278.121303) (xy 121.430288 -278.163319) (xy 121.453866 -278.209593)
			(xy 121.469914 -278.258986) (xy 121.478039 -278.310281) (xy 121.478548 -278.336248) (xy 121.478039 -278.362215)
			(xy 121.477999 -278.362469) (xy 121.757949 -278.362469) (xy 121.757949 -278.310535) (xy 121.766074 -278.25924)
			(xy 121.782122 -278.209847) (xy 121.8057 -278.163573) (xy 121.836226 -278.121557) (xy 121.872949 -278.084834)
			(xy 121.914965 -278.054308) (xy 121.961239 -278.03073) (xy 122.010632 -278.014682) (xy 122.061927 -278.006557)
			(xy 122.113861 -278.006557) (xy 122.165156 -278.014682) (xy 122.214549 -278.03073) (xy 122.260823 -278.054308)
			(xy 122.302839 -278.084834) (xy 122.339562 -278.121557) (xy 122.370088 -278.163573) (xy 122.393666 -278.209847)
			(xy 122.409714 -278.25924) (xy 122.417839 -278.310535) (xy 122.418348 -278.336502) (xy 122.417839 -278.362469)
			(xy 122.698003 -278.362469) (xy 122.698003 -278.310535) (xy 122.706128 -278.25924) (xy 122.722176 -278.209847)
			(xy 122.745754 -278.163573) (xy 122.77628 -278.121557) (xy 122.813003 -278.084834) (xy 122.855019 -278.054308)
			(xy 122.901293 -278.03073) (xy 122.950686 -278.014682) (xy 123.001981 -278.006557) (xy 123.053915 -278.006557)
			(xy 123.10521 -278.014682) (xy 123.154603 -278.03073) (xy 123.200877 -278.054308) (xy 123.242893 -278.084834)
			(xy 123.279616 -278.121557) (xy 123.310142 -278.163573) (xy 123.33372 -278.209847) (xy 123.349768 -278.25924)
			(xy 123.357893 -278.310535) (xy 123.358402 -278.336502) (xy 123.357893 -278.362469) (xy 124.577603 -278.362469)
			(xy 124.577603 -278.310535) (xy 124.585728 -278.25924) (xy 124.601776 -278.209847) (xy 124.625354 -278.163573)
			(xy 124.65588 -278.121557) (xy 124.692603 -278.084834) (xy 124.734619 -278.054308) (xy 124.780893 -278.03073)
			(xy 124.830286 -278.014682) (xy 124.881581 -278.006557) (xy 124.933515 -278.006557) (xy 124.98481 -278.014682)
			(xy 125.034203 -278.03073) (xy 125.080477 -278.054308) (xy 125.122493 -278.084834) (xy 125.159216 -278.121557)
			(xy 125.189742 -278.163573) (xy 125.21332 -278.209847) (xy 125.229368 -278.25924) (xy 125.237493 -278.310535)
			(xy 125.238002 -278.336502) (xy 125.237493 -278.362469) (xy 125.517403 -278.362469) (xy 125.517403 -278.310535)
			(xy 125.525528 -278.25924) (xy 125.541576 -278.209847) (xy 125.565154 -278.163573) (xy 125.59568 -278.121557)
			(xy 125.632403 -278.084834) (xy 125.674419 -278.054308) (xy 125.720693 -278.03073) (xy 125.770086 -278.014682)
			(xy 125.821381 -278.006557) (xy 125.873315 -278.006557) (xy 125.92461 -278.014682) (xy 125.974003 -278.03073)
			(xy 126.020277 -278.054308) (xy 126.062293 -278.084834) (xy 126.099016 -278.121557) (xy 126.129542 -278.163573)
			(xy 126.15312 -278.209847) (xy 126.169168 -278.25924) (xy 126.177293 -278.310535) (xy 126.177802 -278.336502)
			(xy 126.177293 -278.362469) (xy 126.457203 -278.362469) (xy 126.457203 -278.310535) (xy 126.465328 -278.25924)
			(xy 126.481376 -278.209847) (xy 126.504954 -278.163573) (xy 126.53548 -278.121557) (xy 126.572203 -278.084834)
			(xy 126.614219 -278.054308) (xy 126.660493 -278.03073) (xy 126.709886 -278.014682) (xy 126.761181 -278.006557)
			(xy 126.813115 -278.006557) (xy 126.86441 -278.014682) (xy 126.913803 -278.03073) (xy 126.960077 -278.054308)
			(xy 127.002093 -278.084834) (xy 127.038816 -278.121557) (xy 127.069342 -278.163573) (xy 127.09292 -278.209847)
			(xy 127.108968 -278.25924) (xy 127.117093 -278.310535) (xy 127.117602 -278.336502) (xy 127.117093 -278.362469)
			(xy 127.397003 -278.362469) (xy 127.397003 -278.310535) (xy 127.405128 -278.25924) (xy 127.421176 -278.209847)
			(xy 127.444754 -278.163573) (xy 127.47528 -278.121557) (xy 127.512003 -278.084834) (xy 127.554019 -278.054308)
			(xy 127.600293 -278.03073) (xy 127.649686 -278.014682) (xy 127.700981 -278.006557) (xy 127.752915 -278.006557)
			(xy 127.80421 -278.014682) (xy 127.853603 -278.03073) (xy 127.899877 -278.054308) (xy 127.941893 -278.084834)
			(xy 127.978616 -278.121557) (xy 128.009142 -278.163573) (xy 128.03272 -278.209847) (xy 128.048768 -278.25924)
			(xy 128.056893 -278.310535) (xy 128.057402 -278.336502) (xy 128.056893 -278.362469) (xy 128.336549 -278.362469)
			(xy 128.336549 -278.310535) (xy 128.344674 -278.25924) (xy 128.360722 -278.209847) (xy 128.3843 -278.163573)
			(xy 128.414826 -278.121557) (xy 128.451549 -278.084834) (xy 128.493565 -278.054308) (xy 128.539839 -278.03073)
			(xy 128.589232 -278.014682) (xy 128.640527 -278.006557) (xy 128.692461 -278.006557) (xy 128.743756 -278.014682)
			(xy 128.793149 -278.03073) (xy 128.839423 -278.054308) (xy 128.881439 -278.084834) (xy 128.918162 -278.121557)
			(xy 128.948688 -278.163573) (xy 128.972266 -278.209847) (xy 128.988314 -278.25924) (xy 128.996439 -278.310535)
			(xy 128.996948 -278.336502) (xy 128.996439 -278.362469) (xy 129.276603 -278.362469) (xy 129.276603 -278.310535)
			(xy 129.284728 -278.25924) (xy 129.300776 -278.209847) (xy 129.324354 -278.163573) (xy 129.35488 -278.121557)
			(xy 129.391603 -278.084834) (xy 129.433619 -278.054308) (xy 129.479893 -278.03073) (xy 129.529286 -278.014682)
			(xy 129.580581 -278.006557) (xy 129.632515 -278.006557) (xy 129.68381 -278.014682) (xy 129.733203 -278.03073)
			(xy 129.779477 -278.054308) (xy 129.821493 -278.084834) (xy 129.858216 -278.121557) (xy 129.888742 -278.163573)
			(xy 129.91232 -278.209847) (xy 129.928368 -278.25924) (xy 129.936493 -278.310535) (xy 129.937002 -278.336502)
			(xy 129.936493 -278.362469) (xy 130.216149 -278.362469) (xy 130.216149 -278.310535) (xy 130.224274 -278.25924)
			(xy 130.240322 -278.209847) (xy 130.2639 -278.163573) (xy 130.294426 -278.121557) (xy 130.331149 -278.084834)
			(xy 130.373165 -278.054308) (xy 130.419439 -278.03073) (xy 130.468832 -278.014682) (xy 130.520127 -278.006557)
			(xy 130.572061 -278.006557) (xy 130.623356 -278.014682) (xy 130.672749 -278.03073) (xy 130.719023 -278.054308)
			(xy 130.761039 -278.084834) (xy 130.797762 -278.121557) (xy 130.828288 -278.163573) (xy 130.851866 -278.209847)
			(xy 130.867914 -278.25924) (xy 130.876039 -278.310535) (xy 130.876548 -278.336502) (xy 130.876039 -278.362469)
			(xy 130.867914 -278.413764) (xy 130.851866 -278.463157) (xy 130.828288 -278.509431) (xy 130.797762 -278.551447)
			(xy 130.761039 -278.58817) (xy 130.719023 -278.618696) (xy 130.672749 -278.642274) (xy 130.623356 -278.658322)
			(xy 130.572061 -278.666447) (xy 130.520127 -278.666447) (xy 130.468832 -278.658322) (xy 130.419439 -278.642274)
			(xy 130.373165 -278.618696) (xy 130.331149 -278.58817) (xy 130.294426 -278.551447) (xy 130.2639 -278.509431)
			(xy 130.240322 -278.463157) (xy 130.224274 -278.413764) (xy 130.216149 -278.362469) (xy 129.936493 -278.362469)
			(xy 129.928368 -278.413764) (xy 129.91232 -278.463157) (xy 129.888742 -278.509431) (xy 129.858216 -278.551447)
			(xy 129.821493 -278.58817) (xy 129.779477 -278.618696) (xy 129.733203 -278.642274) (xy 129.68381 -278.658322)
			(xy 129.632515 -278.666447) (xy 129.580581 -278.666447) (xy 129.529286 -278.658322) (xy 129.479893 -278.642274)
			(xy 129.433619 -278.618696) (xy 129.391603 -278.58817) (xy 129.35488 -278.551447) (xy 129.324354 -278.509431)
			(xy 129.300776 -278.463157) (xy 129.284728 -278.413764) (xy 129.276603 -278.362469) (xy 128.996439 -278.362469)
			(xy 128.988314 -278.413764) (xy 128.972266 -278.463157) (xy 128.948688 -278.509431) (xy 128.918162 -278.551447)
			(xy 128.881439 -278.58817) (xy 128.839423 -278.618696) (xy 128.793149 -278.642274) (xy 128.743756 -278.658322)
			(xy 128.692461 -278.666447) (xy 128.640527 -278.666447) (xy 128.589232 -278.658322) (xy 128.539839 -278.642274)
			(xy 128.493565 -278.618696) (xy 128.451549 -278.58817) (xy 128.414826 -278.551447) (xy 128.3843 -278.509431)
			(xy 128.360722 -278.463157) (xy 128.344674 -278.413764) (xy 128.336549 -278.362469) (xy 128.056893 -278.362469)
			(xy 128.048768 -278.413764) (xy 128.03272 -278.463157) (xy 128.009142 -278.509431) (xy 127.978616 -278.551447)
			(xy 127.941893 -278.58817) (xy 127.899877 -278.618696) (xy 127.853603 -278.642274) (xy 127.80421 -278.658322)
			(xy 127.752915 -278.666447) (xy 127.700981 -278.666447) (xy 127.649686 -278.658322) (xy 127.600293 -278.642274)
			(xy 127.554019 -278.618696) (xy 127.512003 -278.58817) (xy 127.47528 -278.551447) (xy 127.444754 -278.509431)
			(xy 127.421176 -278.463157) (xy 127.405128 -278.413764) (xy 127.397003 -278.362469) (xy 127.117093 -278.362469)
			(xy 127.108968 -278.413764) (xy 127.09292 -278.463157) (xy 127.069342 -278.509431) (xy 127.038816 -278.551447)
			(xy 127.002093 -278.58817) (xy 126.960077 -278.618696) (xy 126.913803 -278.642274) (xy 126.86441 -278.658322)
			(xy 126.813115 -278.666447) (xy 126.761181 -278.666447) (xy 126.709886 -278.658322) (xy 126.660493 -278.642274)
			(xy 126.614219 -278.618696) (xy 126.572203 -278.58817) (xy 126.53548 -278.551447) (xy 126.504954 -278.509431)
			(xy 126.481376 -278.463157) (xy 126.465328 -278.413764) (xy 126.457203 -278.362469) (xy 126.177293 -278.362469)
			(xy 126.169168 -278.413764) (xy 126.15312 -278.463157) (xy 126.129542 -278.509431) (xy 126.099016 -278.551447)
			(xy 126.062293 -278.58817) (xy 126.020277 -278.618696) (xy 125.974003 -278.642274) (xy 125.92461 -278.658322)
			(xy 125.873315 -278.666447) (xy 125.821381 -278.666447) (xy 125.770086 -278.658322) (xy 125.720693 -278.642274)
			(xy 125.674419 -278.618696) (xy 125.632403 -278.58817) (xy 125.59568 -278.551447) (xy 125.565154 -278.509431)
			(xy 125.541576 -278.463157) (xy 125.525528 -278.413764) (xy 125.517403 -278.362469) (xy 125.237493 -278.362469)
			(xy 125.229368 -278.413764) (xy 125.21332 -278.463157) (xy 125.189742 -278.509431) (xy 125.159216 -278.551447)
			(xy 125.122493 -278.58817) (xy 125.080477 -278.618696) (xy 125.034203 -278.642274) (xy 124.98481 -278.658322)
			(xy 124.933515 -278.666447) (xy 124.881581 -278.666447) (xy 124.830286 -278.658322) (xy 124.780893 -278.642274)
			(xy 124.734619 -278.618696) (xy 124.692603 -278.58817) (xy 124.65588 -278.551447) (xy 124.625354 -278.509431)
			(xy 124.601776 -278.463157) (xy 124.585728 -278.413764) (xy 124.577603 -278.362469) (xy 123.357893 -278.362469)
			(xy 123.349768 -278.413764) (xy 123.33372 -278.463157) (xy 123.310142 -278.509431) (xy 123.279616 -278.551447)
			(xy 123.242893 -278.58817) (xy 123.200877 -278.618696) (xy 123.154603 -278.642274) (xy 123.10521 -278.658322)
			(xy 123.053915 -278.666447) (xy 123.001981 -278.666447) (xy 122.950686 -278.658322) (xy 122.901293 -278.642274)
			(xy 122.855019 -278.618696) (xy 122.813003 -278.58817) (xy 122.77628 -278.551447) (xy 122.745754 -278.509431)
			(xy 122.722176 -278.463157) (xy 122.706128 -278.413764) (xy 122.698003 -278.362469) (xy 122.417839 -278.362469)
			(xy 122.409714 -278.413764) (xy 122.393666 -278.463157) (xy 122.370088 -278.509431) (xy 122.339562 -278.551447)
			(xy 122.302839 -278.58817) (xy 122.260823 -278.618696) (xy 122.214549 -278.642274) (xy 122.165156 -278.658322)
			(xy 122.113861 -278.666447) (xy 122.061927 -278.666447) (xy 122.010632 -278.658322) (xy 121.961239 -278.642274)
			(xy 121.914965 -278.618696) (xy 121.872949 -278.58817) (xy 121.836226 -278.551447) (xy 121.8057 -278.509431)
			(xy 121.782122 -278.463157) (xy 121.766074 -278.413764) (xy 121.757949 -278.362469) (xy 121.477999 -278.362469)
			(xy 121.469914 -278.41351) (xy 121.453866 -278.462903) (xy 121.430288 -278.509177) (xy 121.399762 -278.551193)
			(xy 121.363039 -278.587916) (xy 121.321023 -278.618442) (xy 121.274749 -278.64202) (xy 121.225356 -278.658068)
			(xy 121.174061 -278.666193) (xy 121.122127 -278.666193) (xy 121.070832 -278.658068) (xy 121.021439 -278.64202)
			(xy 120.975165 -278.618442) (xy 120.933149 -278.587916) (xy 120.896426 -278.551193) (xy 120.8659 -278.509177)
			(xy 120.842322 -278.462903) (xy 120.826274 -278.41351) (xy 120.818149 -278.362215) (xy 119.598698 -278.362215)
			(xy 119.598693 -278.362469) (xy 119.590568 -278.413764) (xy 119.57452 -278.463157) (xy 119.550942 -278.509431)
			(xy 119.520416 -278.551447) (xy 119.483693 -278.58817) (xy 119.441677 -278.618696) (xy 119.395403 -278.642274)
			(xy 119.34601 -278.658322) (xy 119.294715 -278.666447) (xy 119.242781 -278.666447) (xy 119.191486 -278.658322)
			(xy 119.142093 -278.642274) (xy 119.095819 -278.618696) (xy 119.053803 -278.58817) (xy 119.01708 -278.551447)
			(xy 118.986554 -278.509431) (xy 118.962976 -278.463157) (xy 118.946928 -278.413764) (xy 118.938803 -278.362469)
			(xy 118.658599 -278.362469) (xy 118.650514 -278.41351) (xy 118.634466 -278.462903) (xy 118.610888 -278.509177)
			(xy 118.580362 -278.551193) (xy 118.543639 -278.587916) (xy 118.501623 -278.618442) (xy 118.455349 -278.64202)
			(xy 118.405956 -278.658068) (xy 118.354661 -278.666193) (xy 118.302727 -278.666193) (xy 118.251432 -278.658068)
			(xy 118.202039 -278.64202) (xy 118.155765 -278.618442) (xy 118.113749 -278.587916) (xy 118.077026 -278.551193)
			(xy 118.0465 -278.509177) (xy 118.022922 -278.462903) (xy 118.006874 -278.41351) (xy 117.998749 -278.362215)
			(xy 117.718792 -278.362215) (xy 117.711368 -278.410889) (xy 117.696558 -278.458437) (xy 117.686074 -278.481028)
			(xy 117.670072 -278.51354) (xy 118.01602 -278.859488) (xy 118.021862 -278.86279) (xy 118.047465 -278.878013)
			(xy 118.0932 -278.916167) (xy 118.13136 -278.961897) (xy 118.146576 -278.987504) (xy 118.149878 -278.993346)
			(xy 118.26748 -279.110948) (xy 118.26748 -279.176285) (xy 119.408449 -279.176285) (xy 119.408449 -279.124351)
			(xy 119.416574 -279.073056) (xy 119.432622 -279.023663) (xy 119.4562 -278.977389) (xy 119.486726 -278.935373)
			(xy 119.523449 -278.89865) (xy 119.565465 -278.868124) (xy 119.611739 -278.844546) (xy 119.661132 -278.828498)
			(xy 119.712427 -278.820373) (xy 119.764361 -278.820373) (xy 119.815656 -278.828498) (xy 119.865049 -278.844546)
			(xy 119.911323 -278.868124) (xy 119.953339 -278.89865) (xy 119.990062 -278.935373) (xy 120.020588 -278.977389)
			(xy 120.044166 -279.023663) (xy 120.060214 -279.073056) (xy 120.068339 -279.124351) (xy 120.068848 -279.150318)
			(xy 120.068339 -279.176285) (xy 120.348503 -279.176285) (xy 120.348503 -279.124351) (xy 120.356628 -279.073056)
			(xy 120.372676 -279.023663) (xy 120.396254 -278.977389) (xy 120.42678 -278.935373) (xy 120.463503 -278.89865)
			(xy 120.505519 -278.868124) (xy 120.551793 -278.844546) (xy 120.601186 -278.828498) (xy 120.652481 -278.820373)
			(xy 120.704415 -278.820373) (xy 120.75571 -278.828498) (xy 120.805103 -278.844546) (xy 120.851377 -278.868124)
			(xy 120.893393 -278.89865) (xy 120.930116 -278.935373) (xy 120.960642 -278.977389) (xy 120.98422 -279.023663)
			(xy 121.000268 -279.073056) (xy 121.008393 -279.124351) (xy 121.008902 -279.150318) (xy 121.008393 -279.176285)
			(xy 121.288049 -279.176285) (xy 121.288049 -279.124351) (xy 121.296174 -279.073056) (xy 121.312222 -279.023663)
			(xy 121.3358 -278.977389) (xy 121.366326 -278.935373) (xy 121.403049 -278.89865) (xy 121.445065 -278.868124)
			(xy 121.491339 -278.844546) (xy 121.540732 -278.828498) (xy 121.592027 -278.820373) (xy 121.643961 -278.820373)
			(xy 121.695256 -278.828498) (xy 121.744649 -278.844546) (xy 121.790923 -278.868124) (xy 121.832939 -278.89865)
			(xy 121.869662 -278.935373) (xy 121.900188 -278.977389) (xy 121.923766 -279.023663) (xy 121.939814 -279.073056)
			(xy 121.947939 -279.124351) (xy 121.948448 -279.150318) (xy 121.947939 -279.176285) (xy 122.227849 -279.176285)
			(xy 122.227849 -279.124351) (xy 122.235974 -279.073056) (xy 122.252022 -279.023663) (xy 122.2756 -278.977389)
			(xy 122.306126 -278.935373) (xy 122.342849 -278.89865) (xy 122.384865 -278.868124) (xy 122.431139 -278.844546)
			(xy 122.480532 -278.828498) (xy 122.531827 -278.820373) (xy 122.583761 -278.820373) (xy 122.635056 -278.828498)
			(xy 122.684449 -278.844546) (xy 122.730723 -278.868124) (xy 122.772739 -278.89865) (xy 122.809462 -278.935373)
			(xy 122.839988 -278.977389) (xy 122.863566 -279.023663) (xy 122.879614 -279.073056) (xy 122.887739 -279.124351)
			(xy 122.888248 -279.150318) (xy 122.887739 -279.176285) (xy 123.167903 -279.176285) (xy 123.167903 -279.124351)
			(xy 123.176028 -279.073056) (xy 123.192076 -279.023663) (xy 123.215654 -278.977389) (xy 123.24618 -278.935373)
			(xy 123.282903 -278.89865) (xy 123.324919 -278.868124) (xy 123.371193 -278.844546) (xy 123.420586 -278.828498)
			(xy 123.471881 -278.820373) (xy 123.523815 -278.820373) (xy 123.57511 -278.828498) (xy 123.624503 -278.844546)
			(xy 123.670777 -278.868124) (xy 123.712793 -278.89865) (xy 123.749516 -278.935373) (xy 123.780042 -278.977389)
			(xy 123.80362 -279.023663) (xy 123.819668 -279.073056) (xy 123.827793 -279.124351) (xy 123.828302 -279.150318)
			(xy 123.827793 -279.176285) (xy 124.107449 -279.176285) (xy 124.107449 -279.124351) (xy 124.115574 -279.073056)
			(xy 124.131622 -279.023663) (xy 124.1552 -278.977389) (xy 124.185726 -278.935373) (xy 124.222449 -278.89865)
			(xy 124.264465 -278.868124) (xy 124.310739 -278.844546) (xy 124.360132 -278.828498) (xy 124.411427 -278.820373)
			(xy 124.463361 -278.820373) (xy 124.514656 -278.828498) (xy 124.564049 -278.844546) (xy 124.610323 -278.868124)
			(xy 124.652339 -278.89865) (xy 124.689062 -278.935373) (xy 124.719588 -278.977389) (xy 124.743166 -279.023663)
			(xy 124.759214 -279.073056) (xy 124.767339 -279.124351) (xy 124.767848 -279.150318) (xy 124.767339 -279.176285)
			(xy 125.047249 -279.176285) (xy 125.047249 -279.124351) (xy 125.055374 -279.073056) (xy 125.071422 -279.023663)
			(xy 125.095 -278.977389) (xy 125.125526 -278.935373) (xy 125.162249 -278.89865) (xy 125.204265 -278.868124)
			(xy 125.250539 -278.844546) (xy 125.299932 -278.828498) (xy 125.351227 -278.820373) (xy 125.403161 -278.820373)
			(xy 125.454456 -278.828498) (xy 125.503849 -278.844546) (xy 125.550123 -278.868124) (xy 125.592139 -278.89865)
			(xy 125.628862 -278.935373) (xy 125.659388 -278.977389) (xy 125.682966 -279.023663) (xy 125.699014 -279.073056)
			(xy 125.707139 -279.124351) (xy 125.707648 -279.150318) (xy 125.707139 -279.176285) (xy 125.987049 -279.176285)
			(xy 125.987049 -279.124351) (xy 125.995174 -279.073056) (xy 126.011222 -279.023663) (xy 126.0348 -278.977389)
			(xy 126.065326 -278.935373) (xy 126.102049 -278.89865) (xy 126.144065 -278.868124) (xy 126.190339 -278.844546)
			(xy 126.239732 -278.828498) (xy 126.291027 -278.820373) (xy 126.342961 -278.820373) (xy 126.394256 -278.828498)
			(xy 126.443649 -278.844546) (xy 126.489923 -278.868124) (xy 126.531939 -278.89865) (xy 126.568662 -278.935373)
			(xy 126.599188 -278.977389) (xy 126.622766 -279.023663) (xy 126.638814 -279.073056) (xy 126.646939 -279.124351)
			(xy 126.647448 -279.150318) (xy 126.646939 -279.176285) (xy 126.926849 -279.176285) (xy 126.926849 -279.124351)
			(xy 126.934974 -279.073056) (xy 126.951022 -279.023663) (xy 126.9746 -278.977389) (xy 127.005126 -278.935373)
			(xy 127.041849 -278.89865) (xy 127.083865 -278.868124) (xy 127.130139 -278.844546) (xy 127.179532 -278.828498)
			(xy 127.230827 -278.820373) (xy 127.282761 -278.820373) (xy 127.334056 -278.828498) (xy 127.383449 -278.844546)
			(xy 127.429723 -278.868124) (xy 127.471739 -278.89865) (xy 127.508462 -278.935373) (xy 127.538988 -278.977389)
			(xy 127.562566 -279.023663) (xy 127.578614 -279.073056) (xy 127.586739 -279.124351) (xy 127.587248 -279.150318)
			(xy 127.586739 -279.176285) (xy 127.866649 -279.176285) (xy 127.866649 -279.124351) (xy 127.874774 -279.073056)
			(xy 127.890822 -279.023663) (xy 127.9144 -278.977389) (xy 127.944926 -278.935373) (xy 127.981649 -278.89865)
			(xy 128.023665 -278.868124) (xy 128.069939 -278.844546) (xy 128.119332 -278.828498) (xy 128.170627 -278.820373)
			(xy 128.222561 -278.820373) (xy 128.273856 -278.828498) (xy 128.323249 -278.844546) (xy 128.369523 -278.868124)
			(xy 128.411539 -278.89865) (xy 128.448262 -278.935373) (xy 128.478788 -278.977389) (xy 128.502366 -279.023663)
			(xy 128.518414 -279.073056) (xy 128.526539 -279.124351) (xy 128.527048 -279.150318) (xy 128.526539 -279.176285)
			(xy 128.806449 -279.176285) (xy 128.806449 -279.124351) (xy 128.814574 -279.073056) (xy 128.830622 -279.023663)
			(xy 128.8542 -278.977389) (xy 128.884726 -278.935373) (xy 128.921449 -278.89865) (xy 128.963465 -278.868124)
			(xy 129.009739 -278.844546) (xy 129.059132 -278.828498) (xy 129.110427 -278.820373) (xy 129.162361 -278.820373)
			(xy 129.213656 -278.828498) (xy 129.263049 -278.844546) (xy 129.309323 -278.868124) (xy 129.351339 -278.89865)
			(xy 129.388062 -278.935373) (xy 129.418588 -278.977389) (xy 129.442166 -279.023663) (xy 129.458214 -279.073056)
			(xy 129.466339 -279.124351) (xy 129.466848 -279.150318) (xy 129.466339 -279.176285) (xy 129.746503 -279.176285)
			(xy 129.746503 -279.124351) (xy 129.754628 -279.073056) (xy 129.770676 -279.023663) (xy 129.794254 -278.977389)
			(xy 129.82478 -278.935373) (xy 129.861503 -278.89865) (xy 129.903519 -278.868124) (xy 129.949793 -278.844546)
			(xy 129.999186 -278.828498) (xy 130.050481 -278.820373) (xy 130.102415 -278.820373) (xy 130.15371 -278.828498)
			(xy 130.203103 -278.844546) (xy 130.249377 -278.868124) (xy 130.291393 -278.89865) (xy 130.328116 -278.935373)
			(xy 130.358642 -278.977389) (xy 130.38222 -279.023663) (xy 130.398268 -279.073056) (xy 130.406393 -279.124351)
			(xy 130.406902 -279.150318) (xy 130.406393 -279.176285) (xy 130.686049 -279.176285) (xy 130.686049 -279.124351)
			(xy 130.694174 -279.073056) (xy 130.710222 -279.023663) (xy 130.7338 -278.977389) (xy 130.764326 -278.935373)
			(xy 130.801049 -278.89865) (xy 130.843065 -278.868124) (xy 130.889339 -278.844546) (xy 130.938732 -278.828498)
			(xy 130.990027 -278.820373) (xy 131.041961 -278.820373) (xy 131.093256 -278.828498) (xy 131.142649 -278.844546)
			(xy 131.188923 -278.868124) (xy 131.230939 -278.89865) (xy 131.267662 -278.935373) (xy 131.298188 -278.977389)
			(xy 131.321766 -279.023663) (xy 131.337814 -279.073056) (xy 131.345939 -279.124351) (xy 131.346448 -279.150318)
			(xy 131.345939 -279.176285) (xy 131.337814 -279.22758) (xy 131.321766 -279.276973) (xy 131.298188 -279.323247)
			(xy 131.267662 -279.365263) (xy 131.230939 -279.401986) (xy 131.188923 -279.432512) (xy 131.142649 -279.45609)
			(xy 131.093256 -279.472138) (xy 131.041961 -279.480263) (xy 130.990027 -279.480263) (xy 130.938732 -279.472138)
			(xy 130.889339 -279.45609) (xy 130.843065 -279.432512) (xy 130.801049 -279.401986) (xy 130.764326 -279.365263)
			(xy 130.7338 -279.323247) (xy 130.710222 -279.276973) (xy 130.694174 -279.22758) (xy 130.686049 -279.176285)
			(xy 130.406393 -279.176285) (xy 130.398268 -279.22758) (xy 130.38222 -279.276973) (xy 130.358642 -279.323247)
			(xy 130.328116 -279.365263) (xy 130.291393 -279.401986) (xy 130.249377 -279.432512) (xy 130.203103 -279.45609)
			(xy 130.15371 -279.472138) (xy 130.102415 -279.480263) (xy 130.050481 -279.480263) (xy 129.999186 -279.472138)
			(xy 129.949793 -279.45609) (xy 129.903519 -279.432512) (xy 129.861503 -279.401986) (xy 129.82478 -279.365263)
			(xy 129.794254 -279.323247) (xy 129.770676 -279.276973) (xy 129.754628 -279.22758) (xy 129.746503 -279.176285)
			(xy 129.466339 -279.176285) (xy 129.458214 -279.22758) (xy 129.442166 -279.276973) (xy 129.418588 -279.323247)
			(xy 129.388062 -279.365263) (xy 129.351339 -279.401986) (xy 129.309323 -279.432512) (xy 129.263049 -279.45609)
			(xy 129.213656 -279.472138) (xy 129.162361 -279.480263) (xy 129.110427 -279.480263) (xy 129.059132 -279.472138)
			(xy 129.009739 -279.45609) (xy 128.963465 -279.432512) (xy 128.921449 -279.401986) (xy 128.884726 -279.365263)
			(xy 128.8542 -279.323247) (xy 128.830622 -279.276973) (xy 128.814574 -279.22758) (xy 128.806449 -279.176285)
			(xy 128.526539 -279.176285) (xy 128.518414 -279.22758) (xy 128.502366 -279.276973) (xy 128.478788 -279.323247)
			(xy 128.448262 -279.365263) (xy 128.411539 -279.401986) (xy 128.369523 -279.432512) (xy 128.323249 -279.45609)
			(xy 128.273856 -279.472138) (xy 128.222561 -279.480263) (xy 128.170627 -279.480263) (xy 128.119332 -279.472138)
			(xy 128.069939 -279.45609) (xy 128.023665 -279.432512) (xy 127.981649 -279.401986) (xy 127.944926 -279.365263)
			(xy 127.9144 -279.323247) (xy 127.890822 -279.276973) (xy 127.874774 -279.22758) (xy 127.866649 -279.176285)
			(xy 127.586739 -279.176285) (xy 127.578614 -279.22758) (xy 127.562566 -279.276973) (xy 127.538988 -279.323247)
			(xy 127.508462 -279.365263) (xy 127.471739 -279.401986) (xy 127.429723 -279.432512) (xy 127.383449 -279.45609)
			(xy 127.334056 -279.472138) (xy 127.282761 -279.480263) (xy 127.230827 -279.480263) (xy 127.179532 -279.472138)
			(xy 127.130139 -279.45609) (xy 127.083865 -279.432512) (xy 127.041849 -279.401986) (xy 127.005126 -279.365263)
			(xy 126.9746 -279.323247) (xy 126.951022 -279.276973) (xy 126.934974 -279.22758) (xy 126.926849 -279.176285)
			(xy 126.646939 -279.176285) (xy 126.638814 -279.22758) (xy 126.622766 -279.276973) (xy 126.599188 -279.323247)
			(xy 126.568662 -279.365263) (xy 126.531939 -279.401986) (xy 126.489923 -279.432512) (xy 126.443649 -279.45609)
			(xy 126.394256 -279.472138) (xy 126.342961 -279.480263) (xy 126.291027 -279.480263) (xy 126.239732 -279.472138)
			(xy 126.190339 -279.45609) (xy 126.144065 -279.432512) (xy 126.102049 -279.401986) (xy 126.065326 -279.365263)
			(xy 126.0348 -279.323247) (xy 126.011222 -279.276973) (xy 125.995174 -279.22758) (xy 125.987049 -279.176285)
			(xy 125.707139 -279.176285) (xy 125.699014 -279.22758) (xy 125.682966 -279.276973) (xy 125.659388 -279.323247)
			(xy 125.628862 -279.365263) (xy 125.592139 -279.401986) (xy 125.550123 -279.432512) (xy 125.503849 -279.45609)
			(xy 125.454456 -279.472138) (xy 125.403161 -279.480263) (xy 125.351227 -279.480263) (xy 125.299932 -279.472138)
			(xy 125.250539 -279.45609) (xy 125.204265 -279.432512) (xy 125.162249 -279.401986) (xy 125.125526 -279.365263)
			(xy 125.095 -279.323247) (xy 125.071422 -279.276973) (xy 125.055374 -279.22758) (xy 125.047249 -279.176285)
			(xy 124.767339 -279.176285) (xy 124.759214 -279.22758) (xy 124.743166 -279.276973) (xy 124.719588 -279.323247)
			(xy 124.689062 -279.365263) (xy 124.652339 -279.401986) (xy 124.610323 -279.432512) (xy 124.564049 -279.45609)
			(xy 124.514656 -279.472138) (xy 124.463361 -279.480263) (xy 124.411427 -279.480263) (xy 124.360132 -279.472138)
			(xy 124.310739 -279.45609) (xy 124.264465 -279.432512) (xy 124.222449 -279.401986) (xy 124.185726 -279.365263)
			(xy 124.1552 -279.323247) (xy 124.131622 -279.276973) (xy 124.115574 -279.22758) (xy 124.107449 -279.176285)
			(xy 123.827793 -279.176285) (xy 123.819668 -279.22758) (xy 123.80362 -279.276973) (xy 123.780042 -279.323247)
			(xy 123.749516 -279.365263) (xy 123.712793 -279.401986) (xy 123.670777 -279.432512) (xy 123.624503 -279.45609)
			(xy 123.57511 -279.472138) (xy 123.523815 -279.480263) (xy 123.471881 -279.480263) (xy 123.420586 -279.472138)
			(xy 123.371193 -279.45609) (xy 123.324919 -279.432512) (xy 123.282903 -279.401986) (xy 123.24618 -279.365263)
			(xy 123.215654 -279.323247) (xy 123.192076 -279.276973) (xy 123.176028 -279.22758) (xy 123.167903 -279.176285)
			(xy 122.887739 -279.176285) (xy 122.879614 -279.22758) (xy 122.863566 -279.276973) (xy 122.839988 -279.323247)
			(xy 122.809462 -279.365263) (xy 122.772739 -279.401986) (xy 122.730723 -279.432512) (xy 122.684449 -279.45609)
			(xy 122.635056 -279.472138) (xy 122.583761 -279.480263) (xy 122.531827 -279.480263) (xy 122.480532 -279.472138)
			(xy 122.431139 -279.45609) (xy 122.384865 -279.432512) (xy 122.342849 -279.401986) (xy 122.306126 -279.365263)
			(xy 122.2756 -279.323247) (xy 122.252022 -279.276973) (xy 122.235974 -279.22758) (xy 122.227849 -279.176285)
			(xy 121.947939 -279.176285) (xy 121.939814 -279.22758) (xy 121.923766 -279.276973) (xy 121.900188 -279.323247)
			(xy 121.869662 -279.365263) (xy 121.832939 -279.401986) (xy 121.790923 -279.432512) (xy 121.744649 -279.45609)
			(xy 121.695256 -279.472138) (xy 121.643961 -279.480263) (xy 121.592027 -279.480263) (xy 121.540732 -279.472138)
			(xy 121.491339 -279.45609) (xy 121.445065 -279.432512) (xy 121.403049 -279.401986) (xy 121.366326 -279.365263)
			(xy 121.3358 -279.323247) (xy 121.312222 -279.276973) (xy 121.296174 -279.22758) (xy 121.288049 -279.176285)
			(xy 121.008393 -279.176285) (xy 121.000268 -279.22758) (xy 120.98422 -279.276973) (xy 120.960642 -279.323247)
			(xy 120.930116 -279.365263) (xy 120.893393 -279.401986) (xy 120.851377 -279.432512) (xy 120.805103 -279.45609)
			(xy 120.75571 -279.472138) (xy 120.704415 -279.480263) (xy 120.652481 -279.480263) (xy 120.601186 -279.472138)
			(xy 120.551793 -279.45609) (xy 120.505519 -279.432512) (xy 120.463503 -279.401986) (xy 120.42678 -279.365263)
			(xy 120.396254 -279.323247) (xy 120.372676 -279.276973) (xy 120.356628 -279.22758) (xy 120.348503 -279.176285)
			(xy 120.068339 -279.176285) (xy 120.060214 -279.22758) (xy 120.044166 -279.276973) (xy 120.020588 -279.323247)
			(xy 119.990062 -279.365263) (xy 119.953339 -279.401986) (xy 119.911323 -279.432512) (xy 119.865049 -279.45609)
			(xy 119.815656 -279.472138) (xy 119.764361 -279.480263) (xy 119.712427 -279.480263) (xy 119.661132 -279.472138)
			(xy 119.611739 -279.45609) (xy 119.565465 -279.432512) (xy 119.523449 -279.401986) (xy 119.486726 -279.365263)
			(xy 119.4562 -279.323247) (xy 119.432622 -279.276973) (xy 119.416574 -279.22758) (xy 119.408449 -279.176285)
			(xy 118.26748 -279.176285) (xy 118.26748 -279.534112) (xy 118.26801 -279.549159) (xy 118.276767 -279.57795)
			(xy 118.293544 -279.602932) (xy 118.316882 -279.621931) (xy 118.344747 -279.633292) (xy 118.359682 -279.635204)
			(xy 118.385215 -279.638099) (xy 118.43501 -279.650782) (xy 118.482241 -279.671021) (xy 118.525769 -279.698329)
			(xy 118.564543 -279.732047) (xy 118.597629 -279.771363) (xy 118.624228 -279.815327) (xy 118.6437 -279.86288)
			(xy 118.655573 -279.912874) (xy 118.659563 -279.964103) (xy 118.657538 -279.990101) (xy 118.938803 -279.990101)
			(xy 118.938803 -279.938167) (xy 118.946928 -279.886872) (xy 118.962976 -279.837479) (xy 118.986554 -279.791205)
			(xy 119.01708 -279.749189) (xy 119.053803 -279.712466) (xy 119.095819 -279.68194) (xy 119.142093 -279.658362)
			(xy 119.191486 -279.642314) (xy 119.242781 -279.634189) (xy 119.294715 -279.634189) (xy 119.34601 -279.642314)
			(xy 119.395403 -279.658362) (xy 119.441677 -279.68194) (xy 119.483693 -279.712466) (xy 119.520416 -279.749189)
			(xy 119.550942 -279.791205) (xy 119.57452 -279.837479) (xy 119.590568 -279.886872) (xy 119.598693 -279.938167)
			(xy 119.599202 -279.964134) (xy 119.598693 -279.990101) (xy 119.878603 -279.990101) (xy 119.878603 -279.938167)
			(xy 119.886728 -279.886872) (xy 119.902776 -279.837479) (xy 119.926354 -279.791205) (xy 119.95688 -279.749189)
			(xy 119.993603 -279.712466) (xy 120.035619 -279.68194) (xy 120.081893 -279.658362) (xy 120.131286 -279.642314)
			(xy 120.182581 -279.634189) (xy 120.234515 -279.634189) (xy 120.28581 -279.642314) (xy 120.335203 -279.658362)
			(xy 120.381477 -279.68194) (xy 120.423493 -279.712466) (xy 120.460216 -279.749189) (xy 120.490742 -279.791205)
			(xy 120.51432 -279.837479) (xy 120.530368 -279.886872) (xy 120.538493 -279.938167) (xy 120.539002 -279.964134)
			(xy 120.538493 -279.990101) (xy 120.818403 -279.990101) (xy 120.818403 -279.938167) (xy 120.826528 -279.886872)
			(xy 120.842576 -279.837479) (xy 120.866154 -279.791205) (xy 120.89668 -279.749189) (xy 120.933403 -279.712466)
			(xy 120.975419 -279.68194) (xy 121.021693 -279.658362) (xy 121.071086 -279.642314) (xy 121.122381 -279.634189)
			(xy 121.174315 -279.634189) (xy 121.22561 -279.642314) (xy 121.275003 -279.658362) (xy 121.321277 -279.68194)
			(xy 121.363293 -279.712466) (xy 121.400016 -279.749189) (xy 121.430542 -279.791205) (xy 121.45412 -279.837479)
			(xy 121.470168 -279.886872) (xy 121.478293 -279.938167) (xy 121.478802 -279.964134) (xy 121.478293 -279.990101)
			(xy 122.698003 -279.990101) (xy 122.698003 -279.938167) (xy 122.706128 -279.886872) (xy 122.722176 -279.837479)
			(xy 122.745754 -279.791205) (xy 122.77628 -279.749189) (xy 122.813003 -279.712466) (xy 122.855019 -279.68194)
			(xy 122.901293 -279.658362) (xy 122.950686 -279.642314) (xy 123.001981 -279.634189) (xy 123.053915 -279.634189)
			(xy 123.10521 -279.642314) (xy 123.154603 -279.658362) (xy 123.200877 -279.68194) (xy 123.242893 -279.712466)
			(xy 123.279616 -279.749189) (xy 123.310142 -279.791205) (xy 123.33372 -279.837479) (xy 123.349768 -279.886872)
			(xy 123.357893 -279.938167) (xy 123.358402 -279.964134) (xy 123.357893 -279.990101) (xy 123.637549 -279.990101)
			(xy 123.637549 -279.938167) (xy 123.645674 -279.886872) (xy 123.661722 -279.837479) (xy 123.6853 -279.791205)
			(xy 123.715826 -279.749189) (xy 123.752549 -279.712466) (xy 123.794565 -279.68194) (xy 123.840839 -279.658362)
			(xy 123.890232 -279.642314) (xy 123.941527 -279.634189) (xy 123.993461 -279.634189) (xy 124.044756 -279.642314)
			(xy 124.094149 -279.658362) (xy 124.140423 -279.68194) (xy 124.182439 -279.712466) (xy 124.219162 -279.749189)
			(xy 124.249688 -279.791205) (xy 124.273266 -279.837479) (xy 124.289314 -279.886872) (xy 124.297439 -279.938167)
			(xy 124.297948 -279.964134) (xy 124.297439 -279.990101) (xy 124.577603 -279.990101) (xy 124.577603 -279.938167)
			(xy 124.585728 -279.886872) (xy 124.601776 -279.837479) (xy 124.625354 -279.791205) (xy 124.65588 -279.749189)
			(xy 124.692603 -279.712466) (xy 124.734619 -279.68194) (xy 124.780893 -279.658362) (xy 124.830286 -279.642314)
			(xy 124.881581 -279.634189) (xy 124.933515 -279.634189) (xy 124.98481 -279.642314) (xy 125.034203 -279.658362)
			(xy 125.080477 -279.68194) (xy 125.122493 -279.712466) (xy 125.159216 -279.749189) (xy 125.189742 -279.791205)
			(xy 125.21332 -279.837479) (xy 125.229368 -279.886872) (xy 125.237493 -279.938167) (xy 125.238002 -279.964134)
			(xy 125.237493 -279.990101) (xy 125.517403 -279.990101) (xy 125.517403 -279.938167) (xy 125.525528 -279.886872)
			(xy 125.541576 -279.837479) (xy 125.565154 -279.791205) (xy 125.59568 -279.749189) (xy 125.632403 -279.712466)
			(xy 125.674419 -279.68194) (xy 125.720693 -279.658362) (xy 125.770086 -279.642314) (xy 125.821381 -279.634189)
			(xy 125.873315 -279.634189) (xy 125.92461 -279.642314) (xy 125.974003 -279.658362) (xy 126.020277 -279.68194)
			(xy 126.062293 -279.712466) (xy 126.099016 -279.749189) (xy 126.129542 -279.791205) (xy 126.15312 -279.837479)
			(xy 126.169168 -279.886872) (xy 126.177293 -279.938167) (xy 126.177802 -279.964134) (xy 126.177293 -279.990101)
			(xy 126.456949 -279.990101) (xy 126.456949 -279.938167) (xy 126.465074 -279.886872) (xy 126.481122 -279.837479)
			(xy 126.5047 -279.791205) (xy 126.535226 -279.749189) (xy 126.571949 -279.712466) (xy 126.613965 -279.68194)
			(xy 126.660239 -279.658362) (xy 126.709632 -279.642314) (xy 126.760927 -279.634189) (xy 126.812861 -279.634189)
			(xy 126.864156 -279.642314) (xy 126.913549 -279.658362) (xy 126.959823 -279.68194) (xy 127.001839 -279.712466)
			(xy 127.038562 -279.749189) (xy 127.069088 -279.791205) (xy 127.092666 -279.837479) (xy 127.108714 -279.886872)
			(xy 127.116839 -279.938167) (xy 127.117348 -279.964134) (xy 127.116839 -279.990101) (xy 127.397003 -279.990101)
			(xy 127.397003 -279.938167) (xy 127.405128 -279.886872) (xy 127.421176 -279.837479) (xy 127.444754 -279.791205)
			(xy 127.47528 -279.749189) (xy 127.512003 -279.712466) (xy 127.554019 -279.68194) (xy 127.600293 -279.658362)
			(xy 127.649686 -279.642314) (xy 127.700981 -279.634189) (xy 127.752915 -279.634189) (xy 127.80421 -279.642314)
			(xy 127.853603 -279.658362) (xy 127.899877 -279.68194) (xy 127.941893 -279.712466) (xy 127.978616 -279.749189)
			(xy 128.009142 -279.791205) (xy 128.03272 -279.837479) (xy 128.048768 -279.886872) (xy 128.056893 -279.938167)
			(xy 128.057402 -279.964134) (xy 128.056898 -279.989847) (xy 128.336549 -279.989847) (xy 128.336549 -279.937913)
			(xy 128.344674 -279.886618) (xy 128.360722 -279.837225) (xy 128.3843 -279.790951) (xy 128.414826 -279.748935)
			(xy 128.451549 -279.712212) (xy 128.493565 -279.681686) (xy 128.539839 -279.658108) (xy 128.589232 -279.64206)
			(xy 128.640527 -279.633935) (xy 128.692461 -279.633935) (xy 128.743756 -279.64206) (xy 128.793149 -279.658108)
			(xy 128.839423 -279.681686) (xy 128.881439 -279.712212) (xy 128.918162 -279.748935) (xy 128.948688 -279.790951)
			(xy 128.972266 -279.837225) (xy 128.988314 -279.886618) (xy 128.996439 -279.937913) (xy 128.996948 -279.96388)
			(xy 128.996439 -279.989847) (xy 128.996399 -279.990101) (xy 130.216403 -279.990101) (xy 130.216403 -279.938167)
			(xy 130.224528 -279.886872) (xy 130.240576 -279.837479) (xy 130.264154 -279.791205) (xy 130.29468 -279.749189)
			(xy 130.331403 -279.712466) (xy 130.373419 -279.68194) (xy 130.419693 -279.658362) (xy 130.469086 -279.642314)
			(xy 130.520381 -279.634189) (xy 130.572315 -279.634189) (xy 130.62361 -279.642314) (xy 130.673003 -279.658362)
			(xy 130.719277 -279.68194) (xy 130.761293 -279.712466) (xy 130.798016 -279.749189) (xy 130.828542 -279.791205)
			(xy 130.85212 -279.837479) (xy 130.868168 -279.886872) (xy 130.876293 -279.938167) (xy 130.876802 -279.964134)
			(xy 130.876293 -279.990101) (xy 131.156203 -279.990101) (xy 131.156203 -279.938167) (xy 131.164328 -279.886872)
			(xy 131.180376 -279.837479) (xy 131.203954 -279.791205) (xy 131.23448 -279.749189) (xy 131.271203 -279.712466)
			(xy 131.313219 -279.68194) (xy 131.359493 -279.658362) (xy 131.408886 -279.642314) (xy 131.460181 -279.634189)
			(xy 131.512115 -279.634189) (xy 131.56341 -279.642314) (xy 131.612803 -279.658362) (xy 131.659077 -279.68194)
			(xy 131.701093 -279.712466) (xy 131.737816 -279.749189) (xy 131.768342 -279.791205) (xy 131.79192 -279.837479)
			(xy 131.807968 -279.886872) (xy 131.816093 -279.938167) (xy 131.816602 -279.964134) (xy 131.816093 -279.990101)
			(xy 131.807968 -280.041396) (xy 131.79192 -280.090789) (xy 131.768342 -280.137063) (xy 131.737816 -280.179079)
			(xy 131.701093 -280.215802) (xy 131.659077 -280.246328) (xy 131.612803 -280.269906) (xy 131.56341 -280.285954)
			(xy 131.512115 -280.294079) (xy 131.460181 -280.294079) (xy 131.408886 -280.285954) (xy 131.359493 -280.269906)
			(xy 131.313219 -280.246328) (xy 131.271203 -280.215802) (xy 131.23448 -280.179079) (xy 131.203954 -280.137063)
			(xy 131.180376 -280.090789) (xy 131.164328 -280.041396) (xy 131.156203 -279.990101) (xy 130.876293 -279.990101)
			(xy 130.868168 -280.041396) (xy 130.85212 -280.090789) (xy 130.828542 -280.137063) (xy 130.798016 -280.179079)
			(xy 130.761293 -280.215802) (xy 130.719277 -280.246328) (xy 130.673003 -280.269906) (xy 130.62361 -280.285954)
			(xy 130.572315 -280.294079) (xy 130.520381 -280.294079) (xy 130.469086 -280.285954) (xy 130.419693 -280.269906)
			(xy 130.373419 -280.246328) (xy 130.331403 -280.215802) (xy 130.29468 -280.179079) (xy 130.264154 -280.137063)
			(xy 130.240576 -280.090789) (xy 130.224528 -280.041396) (xy 130.216403 -279.990101) (xy 128.996399 -279.990101)
			(xy 128.988314 -280.041142) (xy 128.972266 -280.090535) (xy 128.948688 -280.136809) (xy 128.918162 -280.178825)
			(xy 128.881439 -280.215548) (xy 128.839423 -280.246074) (xy 128.793149 -280.269652) (xy 128.743756 -280.2857)
			(xy 128.692461 -280.293825) (xy 128.640527 -280.293825) (xy 128.589232 -280.2857) (xy 128.539839 -280.269652)
			(xy 128.493565 -280.246074) (xy 128.451549 -280.215548) (xy 128.414826 -280.178825) (xy 128.3843 -280.136809)
			(xy 128.360722 -280.090535) (xy 128.344674 -280.041142) (xy 128.336549 -279.989847) (xy 128.056898 -279.989847)
			(xy 128.056893 -279.990101) (xy 128.048768 -280.041396) (xy 128.03272 -280.090789) (xy 128.009142 -280.137063)
			(xy 127.978616 -280.179079) (xy 127.941893 -280.215802) (xy 127.899877 -280.246328) (xy 127.853603 -280.269906)
			(xy 127.80421 -280.285954) (xy 127.752915 -280.294079) (xy 127.700981 -280.294079) (xy 127.649686 -280.285954)
			(xy 127.600293 -280.269906) (xy 127.554019 -280.246328) (xy 127.512003 -280.215802) (xy 127.47528 -280.179079)
			(xy 127.444754 -280.137063) (xy 127.421176 -280.090789) (xy 127.405128 -280.041396) (xy 127.397003 -279.990101)
			(xy 127.116839 -279.990101) (xy 127.108714 -280.041396) (xy 127.092666 -280.090789) (xy 127.069088 -280.137063)
			(xy 127.038562 -280.179079) (xy 127.001839 -280.215802) (xy 126.959823 -280.246328) (xy 126.913549 -280.269906)
			(xy 126.864156 -280.285954) (xy 126.812861 -280.294079) (xy 126.760927 -280.294079) (xy 126.709632 -280.285954)
			(xy 126.660239 -280.269906) (xy 126.613965 -280.246328) (xy 126.571949 -280.215802) (xy 126.535226 -280.179079)
			(xy 126.5047 -280.137063) (xy 126.481122 -280.090789) (xy 126.465074 -280.041396) (xy 126.456949 -279.990101)
			(xy 126.177293 -279.990101) (xy 126.169168 -280.041396) (xy 126.15312 -280.090789) (xy 126.129542 -280.137063)
			(xy 126.099016 -280.179079) (xy 126.062293 -280.215802) (xy 126.020277 -280.246328) (xy 125.974003 -280.269906)
			(xy 125.92461 -280.285954) (xy 125.873315 -280.294079) (xy 125.821381 -280.294079) (xy 125.770086 -280.285954)
			(xy 125.720693 -280.269906) (xy 125.674419 -280.246328) (xy 125.632403 -280.215802) (xy 125.59568 -280.179079)
			(xy 125.565154 -280.137063) (xy 125.541576 -280.090789) (xy 125.525528 -280.041396) (xy 125.517403 -279.990101)
			(xy 125.237493 -279.990101) (xy 125.229368 -280.041396) (xy 125.21332 -280.090789) (xy 125.189742 -280.137063)
			(xy 125.159216 -280.179079) (xy 125.122493 -280.215802) (xy 125.080477 -280.246328) (xy 125.034203 -280.269906)
			(xy 124.98481 -280.285954) (xy 124.933515 -280.294079) (xy 124.881581 -280.294079) (xy 124.830286 -280.285954)
			(xy 124.780893 -280.269906) (xy 124.734619 -280.246328) (xy 124.692603 -280.215802) (xy 124.65588 -280.179079)
			(xy 124.625354 -280.137063) (xy 124.601776 -280.090789) (xy 124.585728 -280.041396) (xy 124.577603 -279.990101)
			(xy 124.297439 -279.990101) (xy 124.289314 -280.041396) (xy 124.273266 -280.090789) (xy 124.249688 -280.137063)
			(xy 124.219162 -280.179079) (xy 124.182439 -280.215802) (xy 124.140423 -280.246328) (xy 124.094149 -280.269906)
			(xy 124.044756 -280.285954) (xy 123.993461 -280.294079) (xy 123.941527 -280.294079) (xy 123.890232 -280.285954)
			(xy 123.840839 -280.269906) (xy 123.794565 -280.246328) (xy 123.752549 -280.215802) (xy 123.715826 -280.179079)
			(xy 123.6853 -280.137063) (xy 123.661722 -280.090789) (xy 123.645674 -280.041396) (xy 123.637549 -279.990101)
			(xy 123.357893 -279.990101) (xy 123.349768 -280.041396) (xy 123.33372 -280.090789) (xy 123.310142 -280.137063)
			(xy 123.279616 -280.179079) (xy 123.242893 -280.215802) (xy 123.200877 -280.246328) (xy 123.154603 -280.269906)
			(xy 123.10521 -280.285954) (xy 123.053915 -280.294079) (xy 123.001981 -280.294079) (xy 122.950686 -280.285954)
			(xy 122.901293 -280.269906) (xy 122.855019 -280.246328) (xy 122.813003 -280.215802) (xy 122.77628 -280.179079)
			(xy 122.745754 -280.137063) (xy 122.722176 -280.090789) (xy 122.706128 -280.041396) (xy 122.698003 -279.990101)
			(xy 121.478293 -279.990101) (xy 121.470168 -280.041396) (xy 121.45412 -280.090789) (xy 121.430542 -280.137063)
			(xy 121.400016 -280.179079) (xy 121.363293 -280.215802) (xy 121.321277 -280.246328) (xy 121.275003 -280.269906)
			(xy 121.22561 -280.285954) (xy 121.174315 -280.294079) (xy 121.122381 -280.294079) (xy 121.071086 -280.285954)
			(xy 121.021693 -280.269906) (xy 120.975419 -280.246328) (xy 120.933403 -280.215802) (xy 120.89668 -280.179079)
			(xy 120.866154 -280.137063) (xy 120.842576 -280.090789) (xy 120.826528 -280.041396) (xy 120.818403 -279.990101)
			(xy 120.538493 -279.990101) (xy 120.530368 -280.041396) (xy 120.51432 -280.090789) (xy 120.490742 -280.137063)
			(xy 120.460216 -280.179079) (xy 120.423493 -280.215802) (xy 120.381477 -280.246328) (xy 120.335203 -280.269906)
			(xy 120.28581 -280.285954) (xy 120.234515 -280.294079) (xy 120.182581 -280.294079) (xy 120.131286 -280.285954)
			(xy 120.081893 -280.269906) (xy 120.035619 -280.246328) (xy 119.993603 -280.215802) (xy 119.95688 -280.179079)
			(xy 119.926354 -280.137063) (xy 119.902776 -280.090789) (xy 119.886728 -280.041396) (xy 119.878603 -279.990101)
			(xy 119.598693 -279.990101) (xy 119.590568 -280.041396) (xy 119.57452 -280.090789) (xy 119.550942 -280.137063)
			(xy 119.520416 -280.179079) (xy 119.483693 -280.215802) (xy 119.441677 -280.246328) (xy 119.395403 -280.269906)
			(xy 119.34601 -280.285954) (xy 119.294715 -280.294079) (xy 119.242781 -280.294079) (xy 119.191486 -280.285954)
			(xy 119.142093 -280.269906) (xy 119.095819 -280.246328) (xy 119.053803 -280.215802) (xy 119.01708 -280.179079)
			(xy 118.986554 -280.137063) (xy 118.962976 -280.090789) (xy 118.946928 -280.041396) (xy 118.938803 -279.990101)
			(xy 118.657538 -279.990101) (xy 118.655572 -280.015333) (xy 118.643698 -280.065326) (xy 118.624225 -280.112879)
			(xy 118.597625 -280.156842) (xy 118.564539 -280.196157) (xy 118.525764 -280.229875) (xy 118.482236 -280.257182)
			(xy 118.435004 -280.277421) (xy 118.385209 -280.290102) (xy 118.359682 -280.293064) (xy 118.344753 -280.294994)
			(xy 118.316904 -280.306379) (xy 118.293575 -280.325377) (xy 118.276784 -280.350342) (xy 118.267987 -280.379114)
			(xy 118.26748 -280.394156) (xy 118.26748 -280.804171) (xy 118.468649 -280.804171) (xy 118.468649 -280.752237)
			(xy 118.476774 -280.700942) (xy 118.492822 -280.651549) (xy 118.5164 -280.605275) (xy 118.546926 -280.563259)
			(xy 118.583649 -280.526536) (xy 118.625665 -280.49601) (xy 118.671939 -280.472432) (xy 118.721332 -280.456384)
			(xy 118.772627 -280.448259) (xy 118.824561 -280.448259) (xy 118.875856 -280.456384) (xy 118.925249 -280.472432)
			(xy 118.971523 -280.49601) (xy 119.013539 -280.526536) (xy 119.050262 -280.563259) (xy 119.080788 -280.605275)
			(xy 119.104366 -280.651549) (xy 119.120414 -280.700942) (xy 119.128539 -280.752237) (xy 119.129048 -280.778204)
			(xy 119.128539 -280.804171) (xy 119.408449 -280.804171) (xy 119.408449 -280.752237) (xy 119.416574 -280.700942)
			(xy 119.432622 -280.651549) (xy 119.4562 -280.605275) (xy 119.486726 -280.563259) (xy 119.523449 -280.526536)
			(xy 119.565465 -280.49601) (xy 119.611739 -280.472432) (xy 119.661132 -280.456384) (xy 119.712427 -280.448259)
			(xy 119.764361 -280.448259) (xy 119.815656 -280.456384) (xy 119.865049 -280.472432) (xy 119.911323 -280.49601)
			(xy 119.953339 -280.526536) (xy 119.990062 -280.563259) (xy 120.020588 -280.605275) (xy 120.044166 -280.651549)
			(xy 120.060214 -280.700942) (xy 120.068339 -280.752237) (xy 120.068848 -280.778204) (xy 120.068339 -280.804171)
			(xy 120.348249 -280.804171) (xy 120.348249 -280.752237) (xy 120.356374 -280.700942) (xy 120.372422 -280.651549)
			(xy 120.396 -280.605275) (xy 120.426526 -280.563259) (xy 120.463249 -280.526536) (xy 120.505265 -280.49601)
			(xy 120.551539 -280.472432) (xy 120.600932 -280.456384) (xy 120.652227 -280.448259) (xy 120.704161 -280.448259)
			(xy 120.755456 -280.456384) (xy 120.804849 -280.472432) (xy 120.851123 -280.49601) (xy 120.893139 -280.526536)
			(xy 120.929862 -280.563259) (xy 120.960388 -280.605275) (xy 120.983966 -280.651549) (xy 121.000014 -280.700942)
			(xy 121.008139 -280.752237) (xy 121.008648 -280.778204) (xy 121.008139 -280.804171) (xy 121.288049 -280.804171)
			(xy 121.288049 -280.752237) (xy 121.296174 -280.700942) (xy 121.312222 -280.651549) (xy 121.3358 -280.605275)
			(xy 121.366326 -280.563259) (xy 121.403049 -280.526536) (xy 121.445065 -280.49601) (xy 121.491339 -280.472432)
			(xy 121.540732 -280.456384) (xy 121.592027 -280.448259) (xy 121.643961 -280.448259) (xy 121.695256 -280.456384)
			(xy 121.744649 -280.472432) (xy 121.790923 -280.49601) (xy 121.832939 -280.526536) (xy 121.869662 -280.563259)
			(xy 121.900188 -280.605275) (xy 121.923766 -280.651549) (xy 121.939814 -280.700942) (xy 121.947939 -280.752237)
			(xy 121.948448 -280.778204) (xy 121.947939 -280.804171) (xy 122.227849 -280.804171) (xy 122.227849 -280.752237)
			(xy 122.235974 -280.700942) (xy 122.252022 -280.651549) (xy 122.2756 -280.605275) (xy 122.306126 -280.563259)
			(xy 122.342849 -280.526536) (xy 122.384865 -280.49601) (xy 122.431139 -280.472432) (xy 122.480532 -280.456384)
			(xy 122.531827 -280.448259) (xy 122.583761 -280.448259) (xy 122.635056 -280.456384) (xy 122.684449 -280.472432)
			(xy 122.730723 -280.49601) (xy 122.772739 -280.526536) (xy 122.809462 -280.563259) (xy 122.839988 -280.605275)
			(xy 122.863566 -280.651549) (xy 122.879614 -280.700942) (xy 122.887739 -280.752237) (xy 122.888248 -280.778204)
			(xy 122.887739 -280.804171) (xy 123.167649 -280.804171) (xy 123.167649 -280.752237) (xy 123.175774 -280.700942)
			(xy 123.191822 -280.651549) (xy 123.2154 -280.605275) (xy 123.245926 -280.563259) (xy 123.282649 -280.526536)
			(xy 123.324665 -280.49601) (xy 123.370939 -280.472432) (xy 123.420332 -280.456384) (xy 123.471627 -280.448259)
			(xy 123.523561 -280.448259) (xy 123.574856 -280.456384) (xy 123.624249 -280.472432) (xy 123.670523 -280.49601)
			(xy 123.712539 -280.526536) (xy 123.749262 -280.563259) (xy 123.779788 -280.605275) (xy 123.803366 -280.651549)
			(xy 123.819414 -280.700942) (xy 123.827539 -280.752237) (xy 123.828048 -280.778204) (xy 123.827539 -280.804171)
			(xy 124.107449 -280.804171) (xy 124.107449 -280.752237) (xy 124.115574 -280.700942) (xy 124.131622 -280.651549)
			(xy 124.1552 -280.605275) (xy 124.185726 -280.563259) (xy 124.222449 -280.526536) (xy 124.264465 -280.49601)
			(xy 124.310739 -280.472432) (xy 124.360132 -280.456384) (xy 124.411427 -280.448259) (xy 124.463361 -280.448259)
			(xy 124.514656 -280.456384) (xy 124.564049 -280.472432) (xy 124.610323 -280.49601) (xy 124.652339 -280.526536)
			(xy 124.689062 -280.563259) (xy 124.719588 -280.605275) (xy 124.743166 -280.651549) (xy 124.759214 -280.700942)
			(xy 124.767339 -280.752237) (xy 124.767848 -280.778204) (xy 124.767339 -280.804171) (xy 125.047249 -280.804171)
			(xy 125.047249 -280.752237) (xy 125.055374 -280.700942) (xy 125.071422 -280.651549) (xy 125.095 -280.605275)
			(xy 125.125526 -280.563259) (xy 125.162249 -280.526536) (xy 125.204265 -280.49601) (xy 125.250539 -280.472432)
			(xy 125.299932 -280.456384) (xy 125.351227 -280.448259) (xy 125.403161 -280.448259) (xy 125.454456 -280.456384)
			(xy 125.503849 -280.472432) (xy 125.550123 -280.49601) (xy 125.592139 -280.526536) (xy 125.628862 -280.563259)
			(xy 125.659388 -280.605275) (xy 125.682966 -280.651549) (xy 125.699014 -280.700942) (xy 125.707139 -280.752237)
			(xy 125.707648 -280.778204) (xy 125.707139 -280.804171) (xy 125.987303 -280.804171) (xy 125.987303 -280.752237)
			(xy 125.995428 -280.700942) (xy 126.011476 -280.651549) (xy 126.035054 -280.605275) (xy 126.06558 -280.563259)
			(xy 126.102303 -280.526536) (xy 126.144319 -280.49601) (xy 126.190593 -280.472432) (xy 126.239986 -280.456384)
			(xy 126.291281 -280.448259) (xy 126.343215 -280.448259) (xy 126.39451 -280.456384) (xy 126.443903 -280.472432)
			(xy 126.490177 -280.49601) (xy 126.532193 -280.526536) (xy 126.568916 -280.563259) (xy 126.599442 -280.605275)
			(xy 126.62302 -280.651549) (xy 126.639068 -280.700942) (xy 126.647193 -280.752237) (xy 126.647702 -280.778204)
			(xy 126.647193 -280.804171) (xy 126.927103 -280.804171) (xy 126.927103 -280.752237) (xy 126.935228 -280.700942)
			(xy 126.951276 -280.651549) (xy 126.974854 -280.605275) (xy 127.00538 -280.563259) (xy 127.042103 -280.526536)
			(xy 127.084119 -280.49601) (xy 127.130393 -280.472432) (xy 127.179786 -280.456384) (xy 127.231081 -280.448259)
			(xy 127.283015 -280.448259) (xy 127.33431 -280.456384) (xy 127.383703 -280.472432) (xy 127.429977 -280.49601)
			(xy 127.471993 -280.526536) (xy 127.508716 -280.563259) (xy 127.539242 -280.605275) (xy 127.56282 -280.651549)
			(xy 127.578868 -280.700942) (xy 127.586993 -280.752237) (xy 127.587502 -280.778204) (xy 127.586993 -280.804171)
			(xy 127.866903 -280.804171) (xy 127.866903 -280.752237) (xy 127.875028 -280.700942) (xy 127.891076 -280.651549)
			(xy 127.914654 -280.605275) (xy 127.94518 -280.563259) (xy 127.981903 -280.526536) (xy 128.023919 -280.49601)
			(xy 128.070193 -280.472432) (xy 128.119586 -280.456384) (xy 128.170881 -280.448259) (xy 128.222815 -280.448259)
			(xy 128.27411 -280.456384) (xy 128.323503 -280.472432) (xy 128.369777 -280.49601) (xy 128.411793 -280.526536)
			(xy 128.448516 -280.563259) (xy 128.479042 -280.605275) (xy 128.50262 -280.651549) (xy 128.518668 -280.700942)
			(xy 128.526793 -280.752237) (xy 128.527302 -280.778204) (xy 128.526793 -280.804171) (xy 128.806703 -280.804171)
			(xy 128.806703 -280.752237) (xy 128.814828 -280.700942) (xy 128.830876 -280.651549) (xy 128.854454 -280.605275)
			(xy 128.88498 -280.563259) (xy 128.921703 -280.526536) (xy 128.963719 -280.49601) (xy 129.009993 -280.472432)
			(xy 129.059386 -280.456384) (xy 129.110681 -280.448259) (xy 129.162615 -280.448259) (xy 129.21391 -280.456384)
			(xy 129.263303 -280.472432) (xy 129.309577 -280.49601) (xy 129.351593 -280.526536) (xy 129.388316 -280.563259)
			(xy 129.418842 -280.605275) (xy 129.44242 -280.651549) (xy 129.458468 -280.700942) (xy 129.466593 -280.752237)
			(xy 129.467102 -280.778204) (xy 129.466593 -280.804171) (xy 129.746503 -280.804171) (xy 129.746503 -280.752237)
			(xy 129.754628 -280.700942) (xy 129.770676 -280.651549) (xy 129.794254 -280.605275) (xy 129.82478 -280.563259)
			(xy 129.861503 -280.526536) (xy 129.903519 -280.49601) (xy 129.949793 -280.472432) (xy 129.999186 -280.456384)
			(xy 130.050481 -280.448259) (xy 130.102415 -280.448259) (xy 130.15371 -280.456384) (xy 130.203103 -280.472432)
			(xy 130.249377 -280.49601) (xy 130.291393 -280.526536) (xy 130.328116 -280.563259) (xy 130.358642 -280.605275)
			(xy 130.38222 -280.651549) (xy 130.398268 -280.700942) (xy 130.406393 -280.752237) (xy 130.406902 -280.778204)
			(xy 130.406393 -280.804171) (xy 130.686049 -280.804171) (xy 130.686049 -280.752237) (xy 130.694174 -280.700942)
			(xy 130.710222 -280.651549) (xy 130.7338 -280.605275) (xy 130.764326 -280.563259) (xy 130.801049 -280.526536)
			(xy 130.843065 -280.49601) (xy 130.889339 -280.472432) (xy 130.938732 -280.456384) (xy 130.990027 -280.448259)
			(xy 131.041961 -280.448259) (xy 131.093256 -280.456384) (xy 131.142649 -280.472432) (xy 131.188923 -280.49601)
			(xy 131.230939 -280.526536) (xy 131.267662 -280.563259) (xy 131.298188 -280.605275) (xy 131.321766 -280.651549)
			(xy 131.337814 -280.700942) (xy 131.345939 -280.752237) (xy 131.346448 -280.778204) (xy 131.345939 -280.804171)
			(xy 131.625849 -280.804171) (xy 131.625849 -280.752237) (xy 131.633974 -280.700942) (xy 131.650022 -280.651549)
			(xy 131.6736 -280.605275) (xy 131.704126 -280.563259) (xy 131.740849 -280.526536) (xy 131.782865 -280.49601)
			(xy 131.829139 -280.472432) (xy 131.878532 -280.456384) (xy 131.929827 -280.448259) (xy 131.981761 -280.448259)
			(xy 132.033056 -280.456384) (xy 132.082449 -280.472432) (xy 132.128723 -280.49601) (xy 132.170739 -280.526536)
			(xy 132.207462 -280.563259) (xy 132.237988 -280.605275) (xy 132.261566 -280.651549) (xy 132.277614 -280.700942)
			(xy 132.285739 -280.752237) (xy 132.286248 -280.778204) (xy 132.285739 -280.804171) (xy 132.277614 -280.855466)
			(xy 132.261566 -280.904859) (xy 132.237988 -280.951133) (xy 132.207462 -280.993149) (xy 132.170739 -281.029872)
			(xy 132.128723 -281.060398) (xy 132.082449 -281.083976) (xy 132.033056 -281.100024) (xy 131.981761 -281.108149)
			(xy 131.929827 -281.108149) (xy 131.878532 -281.100024) (xy 131.829139 -281.083976) (xy 131.782865 -281.060398)
			(xy 131.740849 -281.029872) (xy 131.704126 -280.993149) (xy 131.6736 -280.951133) (xy 131.650022 -280.904859)
			(xy 131.633974 -280.855466) (xy 131.625849 -280.804171) (xy 131.345939 -280.804171) (xy 131.337814 -280.855466)
			(xy 131.321766 -280.904859) (xy 131.298188 -280.951133) (xy 131.267662 -280.993149) (xy 131.230939 -281.029872)
			(xy 131.188923 -281.060398) (xy 131.142649 -281.083976) (xy 131.093256 -281.100024) (xy 131.041961 -281.108149)
			(xy 130.990027 -281.108149) (xy 130.938732 -281.100024) (xy 130.889339 -281.083976) (xy 130.843065 -281.060398)
			(xy 130.801049 -281.029872) (xy 130.764326 -280.993149) (xy 130.7338 -280.951133) (xy 130.710222 -280.904859)
			(xy 130.694174 -280.855466) (xy 130.686049 -280.804171) (xy 130.406393 -280.804171) (xy 130.398268 -280.855466)
			(xy 130.38222 -280.904859) (xy 130.358642 -280.951133) (xy 130.328116 -280.993149) (xy 130.291393 -281.029872)
			(xy 130.249377 -281.060398) (xy 130.203103 -281.083976) (xy 130.15371 -281.100024) (xy 130.102415 -281.108149)
			(xy 130.050481 -281.108149) (xy 129.999186 -281.100024) (xy 129.949793 -281.083976) (xy 129.903519 -281.060398)
			(xy 129.861503 -281.029872) (xy 129.82478 -280.993149) (xy 129.794254 -280.951133) (xy 129.770676 -280.904859)
			(xy 129.754628 -280.855466) (xy 129.746503 -280.804171) (xy 129.466593 -280.804171) (xy 129.458468 -280.855466)
			(xy 129.44242 -280.904859) (xy 129.418842 -280.951133) (xy 129.388316 -280.993149) (xy 129.351593 -281.029872)
			(xy 129.309577 -281.060398) (xy 129.263303 -281.083976) (xy 129.21391 -281.100024) (xy 129.162615 -281.108149)
			(xy 129.110681 -281.108149) (xy 129.059386 -281.100024) (xy 129.009993 -281.083976) (xy 128.963719 -281.060398)
			(xy 128.921703 -281.029872) (xy 128.88498 -280.993149) (xy 128.854454 -280.951133) (xy 128.830876 -280.904859)
			(xy 128.814828 -280.855466) (xy 128.806703 -280.804171) (xy 128.526793 -280.804171) (xy 128.518668 -280.855466)
			(xy 128.50262 -280.904859) (xy 128.479042 -280.951133) (xy 128.448516 -280.993149) (xy 128.411793 -281.029872)
			(xy 128.369777 -281.060398) (xy 128.323503 -281.083976) (xy 128.27411 -281.100024) (xy 128.222815 -281.108149)
			(xy 128.170881 -281.108149) (xy 128.119586 -281.100024) (xy 128.070193 -281.083976) (xy 128.023919 -281.060398)
			(xy 127.981903 -281.029872) (xy 127.94518 -280.993149) (xy 127.914654 -280.951133) (xy 127.891076 -280.904859)
			(xy 127.875028 -280.855466) (xy 127.866903 -280.804171) (xy 127.586993 -280.804171) (xy 127.578868 -280.855466)
			(xy 127.56282 -280.904859) (xy 127.539242 -280.951133) (xy 127.508716 -280.993149) (xy 127.471993 -281.029872)
			(xy 127.429977 -281.060398) (xy 127.383703 -281.083976) (xy 127.33431 -281.100024) (xy 127.283015 -281.108149)
			(xy 127.231081 -281.108149) (xy 127.179786 -281.100024) (xy 127.130393 -281.083976) (xy 127.084119 -281.060398)
			(xy 127.042103 -281.029872) (xy 127.00538 -280.993149) (xy 126.974854 -280.951133) (xy 126.951276 -280.904859)
			(xy 126.935228 -280.855466) (xy 126.927103 -280.804171) (xy 126.647193 -280.804171) (xy 126.639068 -280.855466)
			(xy 126.62302 -280.904859) (xy 126.599442 -280.951133) (xy 126.568916 -280.993149) (xy 126.532193 -281.029872)
			(xy 126.490177 -281.060398) (xy 126.443903 -281.083976) (xy 126.39451 -281.100024) (xy 126.343215 -281.108149)
			(xy 126.291281 -281.108149) (xy 126.239986 -281.100024) (xy 126.190593 -281.083976) (xy 126.144319 -281.060398)
			(xy 126.102303 -281.029872) (xy 126.06558 -280.993149) (xy 126.035054 -280.951133) (xy 126.011476 -280.904859)
			(xy 125.995428 -280.855466) (xy 125.987303 -280.804171) (xy 125.707139 -280.804171) (xy 125.699014 -280.855466)
			(xy 125.682966 -280.904859) (xy 125.659388 -280.951133) (xy 125.628862 -280.993149) (xy 125.592139 -281.029872)
			(xy 125.550123 -281.060398) (xy 125.503849 -281.083976) (xy 125.454456 -281.100024) (xy 125.403161 -281.108149)
			(xy 125.351227 -281.108149) (xy 125.299932 -281.100024) (xy 125.250539 -281.083976) (xy 125.204265 -281.060398)
			(xy 125.162249 -281.029872) (xy 125.125526 -280.993149) (xy 125.095 -280.951133) (xy 125.071422 -280.904859)
			(xy 125.055374 -280.855466) (xy 125.047249 -280.804171) (xy 124.767339 -280.804171) (xy 124.759214 -280.855466)
			(xy 124.743166 -280.904859) (xy 124.719588 -280.951133) (xy 124.689062 -280.993149) (xy 124.652339 -281.029872)
			(xy 124.610323 -281.060398) (xy 124.564049 -281.083976) (xy 124.514656 -281.100024) (xy 124.463361 -281.108149)
			(xy 124.411427 -281.108149) (xy 124.360132 -281.100024) (xy 124.310739 -281.083976) (xy 124.264465 -281.060398)
			(xy 124.222449 -281.029872) (xy 124.185726 -280.993149) (xy 124.1552 -280.951133) (xy 124.131622 -280.904859)
			(xy 124.115574 -280.855466) (xy 124.107449 -280.804171) (xy 123.827539 -280.804171) (xy 123.819414 -280.855466)
			(xy 123.803366 -280.904859) (xy 123.779788 -280.951133) (xy 123.749262 -280.993149) (xy 123.712539 -281.029872)
			(xy 123.670523 -281.060398) (xy 123.624249 -281.083976) (xy 123.574856 -281.100024) (xy 123.523561 -281.108149)
			(xy 123.471627 -281.108149) (xy 123.420332 -281.100024) (xy 123.370939 -281.083976) (xy 123.324665 -281.060398)
			(xy 123.282649 -281.029872) (xy 123.245926 -280.993149) (xy 123.2154 -280.951133) (xy 123.191822 -280.904859)
			(xy 123.175774 -280.855466) (xy 123.167649 -280.804171) (xy 122.887739 -280.804171) (xy 122.879614 -280.855466)
			(xy 122.863566 -280.904859) (xy 122.839988 -280.951133) (xy 122.809462 -280.993149) (xy 122.772739 -281.029872)
			(xy 122.730723 -281.060398) (xy 122.684449 -281.083976) (xy 122.635056 -281.100024) (xy 122.583761 -281.108149)
			(xy 122.531827 -281.108149) (xy 122.480532 -281.100024) (xy 122.431139 -281.083976) (xy 122.384865 -281.060398)
			(xy 122.342849 -281.029872) (xy 122.306126 -280.993149) (xy 122.2756 -280.951133) (xy 122.252022 -280.904859)
			(xy 122.235974 -280.855466) (xy 122.227849 -280.804171) (xy 121.947939 -280.804171) (xy 121.939814 -280.855466)
			(xy 121.923766 -280.904859) (xy 121.900188 -280.951133) (xy 121.869662 -280.993149) (xy 121.832939 -281.029872)
			(xy 121.790923 -281.060398) (xy 121.744649 -281.083976) (xy 121.695256 -281.100024) (xy 121.643961 -281.108149)
			(xy 121.592027 -281.108149) (xy 121.540732 -281.100024) (xy 121.491339 -281.083976) (xy 121.445065 -281.060398)
			(xy 121.403049 -281.029872) (xy 121.366326 -280.993149) (xy 121.3358 -280.951133) (xy 121.312222 -280.904859)
			(xy 121.296174 -280.855466) (xy 121.288049 -280.804171) (xy 121.008139 -280.804171) (xy 121.000014 -280.855466)
			(xy 120.983966 -280.904859) (xy 120.960388 -280.951133) (xy 120.929862 -280.993149) (xy 120.893139 -281.029872)
			(xy 120.851123 -281.060398) (xy 120.804849 -281.083976) (xy 120.755456 -281.100024) (xy 120.704161 -281.108149)
			(xy 120.652227 -281.108149) (xy 120.600932 -281.100024) (xy 120.551539 -281.083976) (xy 120.505265 -281.060398)
			(xy 120.463249 -281.029872) (xy 120.426526 -280.993149) (xy 120.396 -280.951133) (xy 120.372422 -280.904859)
			(xy 120.356374 -280.855466) (xy 120.348249 -280.804171) (xy 120.068339 -280.804171) (xy 120.060214 -280.855466)
			(xy 120.044166 -280.904859) (xy 120.020588 -280.951133) (xy 119.990062 -280.993149) (xy 119.953339 -281.029872)
			(xy 119.911323 -281.060398) (xy 119.865049 -281.083976) (xy 119.815656 -281.100024) (xy 119.764361 -281.108149)
			(xy 119.712427 -281.108149) (xy 119.661132 -281.100024) (xy 119.611739 -281.083976) (xy 119.565465 -281.060398)
			(xy 119.523449 -281.029872) (xy 119.486726 -280.993149) (xy 119.4562 -280.951133) (xy 119.432622 -280.904859)
			(xy 119.416574 -280.855466) (xy 119.408449 -280.804171) (xy 119.128539 -280.804171) (xy 119.120414 -280.855466)
			(xy 119.104366 -280.904859) (xy 119.080788 -280.951133) (xy 119.050262 -280.993149) (xy 119.013539 -281.029872)
			(xy 118.971523 -281.060398) (xy 118.925249 -281.083976) (xy 118.875856 -281.100024) (xy 118.824561 -281.108149)
			(xy 118.772627 -281.108149) (xy 118.721332 -281.100024) (xy 118.671939 -281.083976) (xy 118.625665 -281.060398)
			(xy 118.583649 -281.029872) (xy 118.546926 -280.993149) (xy 118.5164 -280.951133) (xy 118.492822 -280.904859)
			(xy 118.476774 -280.855466) (xy 118.468649 -280.804171) (xy 118.26748 -280.804171) (xy 118.26748 -281.161998)
			(xy 118.268008 -281.177046) (xy 118.276762 -281.20584) (xy 118.293539 -281.230826) (xy 118.316877 -281.249828)
			(xy 118.344745 -281.261191) (xy 118.359682 -281.26309) (xy 118.385216 -281.265985) (xy 118.435014 -281.278668)
			(xy 118.482247 -281.298908) (xy 118.525776 -281.326217) (xy 118.564552 -281.359937) (xy 118.597639 -281.399254)
			(xy 118.62424 -281.44322) (xy 118.643713 -281.490774) (xy 118.655587 -281.54077) (xy 118.659577 -281.592002)
			(xy 118.657553 -281.617987) (xy 118.938803 -281.617987) (xy 118.938803 -281.566053) (xy 118.946928 -281.514758)
			(xy 118.962976 -281.465365) (xy 118.986554 -281.419091) (xy 119.01708 -281.377075) (xy 119.053803 -281.340352)
			(xy 119.095819 -281.309826) (xy 119.142093 -281.286248) (xy 119.191486 -281.2702) (xy 119.242781 -281.262075)
			(xy 119.294715 -281.262075) (xy 119.34601 -281.2702) (xy 119.395403 -281.286248) (xy 119.441677 -281.309826)
			(xy 119.483693 -281.340352) (xy 119.520416 -281.377075) (xy 119.550942 -281.419091) (xy 119.57452 -281.465365)
			(xy 119.590568 -281.514758) (xy 119.598693 -281.566053) (xy 119.599202 -281.59202) (xy 119.598693 -281.617987)
			(xy 119.878603 -281.617987) (xy 119.878603 -281.566053) (xy 119.886728 -281.514758) (xy 119.902776 -281.465365)
			(xy 119.926354 -281.419091) (xy 119.95688 -281.377075) (xy 119.993603 -281.340352) (xy 120.035619 -281.309826)
			(xy 120.081893 -281.286248) (xy 120.131286 -281.2702) (xy 120.182581 -281.262075) (xy 120.234515 -281.262075)
			(xy 120.28581 -281.2702) (xy 120.335203 -281.286248) (xy 120.381477 -281.309826) (xy 120.423493 -281.340352)
			(xy 120.460216 -281.377075) (xy 120.490742 -281.419091) (xy 120.51432 -281.465365) (xy 120.530368 -281.514758)
			(xy 120.538493 -281.566053) (xy 120.539002 -281.59202) (xy 120.538493 -281.617987) (xy 120.818403 -281.617987)
			(xy 120.818403 -281.566053) (xy 120.826528 -281.514758) (xy 120.842576 -281.465365) (xy 120.866154 -281.419091)
			(xy 120.89668 -281.377075) (xy 120.933403 -281.340352) (xy 120.975419 -281.309826) (xy 121.021693 -281.286248)
			(xy 121.071086 -281.2702) (xy 121.122381 -281.262075) (xy 121.174315 -281.262075) (xy 121.22561 -281.2702)
			(xy 121.275003 -281.286248) (xy 121.321277 -281.309826) (xy 121.363293 -281.340352) (xy 121.400016 -281.377075)
			(xy 121.430542 -281.419091) (xy 121.45412 -281.465365) (xy 121.470168 -281.514758) (xy 121.478293 -281.566053)
			(xy 121.478802 -281.59202) (xy 121.478293 -281.617987) (xy 121.758203 -281.617987) (xy 121.758203 -281.566053)
			(xy 121.766328 -281.514758) (xy 121.782376 -281.465365) (xy 121.805954 -281.419091) (xy 121.83648 -281.377075)
			(xy 121.873203 -281.340352) (xy 121.915219 -281.309826) (xy 121.961493 -281.286248) (xy 122.010886 -281.2702)
			(xy 122.062181 -281.262075) (xy 122.114115 -281.262075) (xy 122.16541 -281.2702) (xy 122.214803 -281.286248)
			(xy 122.261077 -281.309826) (xy 122.303093 -281.340352) (xy 122.339816 -281.377075) (xy 122.370342 -281.419091)
			(xy 122.39392 -281.465365) (xy 122.409968 -281.514758) (xy 122.418093 -281.566053) (xy 122.418602 -281.59202)
			(xy 122.418093 -281.617987) (xy 122.698003 -281.617987) (xy 122.698003 -281.566053) (xy 122.706128 -281.514758)
			(xy 122.722176 -281.465365) (xy 122.745754 -281.419091) (xy 122.77628 -281.377075) (xy 122.813003 -281.340352)
			(xy 122.855019 -281.309826) (xy 122.901293 -281.286248) (xy 122.950686 -281.2702) (xy 123.001981 -281.262075)
			(xy 123.053915 -281.262075) (xy 123.10521 -281.2702) (xy 123.154603 -281.286248) (xy 123.200877 -281.309826)
			(xy 123.242893 -281.340352) (xy 123.279616 -281.377075) (xy 123.310142 -281.419091) (xy 123.33372 -281.465365)
			(xy 123.349768 -281.514758) (xy 123.357893 -281.566053) (xy 123.358402 -281.59202) (xy 123.357893 -281.617987)
			(xy 123.637803 -281.617987) (xy 123.637803 -281.566053) (xy 123.645928 -281.514758) (xy 123.661976 -281.465365)
			(xy 123.685554 -281.419091) (xy 123.71608 -281.377075) (xy 123.752803 -281.340352) (xy 123.794819 -281.309826)
			(xy 123.841093 -281.286248) (xy 123.890486 -281.2702) (xy 123.941781 -281.262075) (xy 123.993715 -281.262075)
			(xy 124.04501 -281.2702) (xy 124.094403 -281.286248) (xy 124.140677 -281.309826) (xy 124.182693 -281.340352)
			(xy 124.219416 -281.377075) (xy 124.249942 -281.419091) (xy 124.27352 -281.465365) (xy 124.289568 -281.514758)
			(xy 124.297693 -281.566053) (xy 124.298202 -281.59202) (xy 124.297693 -281.617987) (xy 124.577603 -281.617987)
			(xy 124.577603 -281.566053) (xy 124.585728 -281.514758) (xy 124.601776 -281.465365) (xy 124.625354 -281.419091)
			(xy 124.65588 -281.377075) (xy 124.692603 -281.340352) (xy 124.734619 -281.309826) (xy 124.780893 -281.286248)
			(xy 124.830286 -281.2702) (xy 124.881581 -281.262075) (xy 124.933515 -281.262075) (xy 124.98481 -281.2702)
			(xy 125.034203 -281.286248) (xy 125.080477 -281.309826) (xy 125.122493 -281.340352) (xy 125.159216 -281.377075)
			(xy 125.189742 -281.419091) (xy 125.21332 -281.465365) (xy 125.229368 -281.514758) (xy 125.237493 -281.566053)
			(xy 125.238002 -281.59202) (xy 125.237493 -281.617987) (xy 125.517403 -281.617987) (xy 125.517403 -281.566053)
			(xy 125.525528 -281.514758) (xy 125.541576 -281.465365) (xy 125.565154 -281.419091) (xy 125.59568 -281.377075)
			(xy 125.632403 -281.340352) (xy 125.674419 -281.309826) (xy 125.720693 -281.286248) (xy 125.770086 -281.2702)
			(xy 125.821381 -281.262075) (xy 125.873315 -281.262075) (xy 125.92461 -281.2702) (xy 125.974003 -281.286248)
			(xy 126.020277 -281.309826) (xy 126.062293 -281.340352) (xy 126.099016 -281.377075) (xy 126.129542 -281.419091)
			(xy 126.15312 -281.465365) (xy 126.169168 -281.514758) (xy 126.177293 -281.566053) (xy 126.177802 -281.59202)
			(xy 126.177293 -281.617987) (xy 126.456949 -281.617987) (xy 126.456949 -281.566053) (xy 126.465074 -281.514758)
			(xy 126.481122 -281.465365) (xy 126.5047 -281.419091) (xy 126.535226 -281.377075) (xy 126.571949 -281.340352)
			(xy 126.613965 -281.309826) (xy 126.660239 -281.286248) (xy 126.709632 -281.2702) (xy 126.760927 -281.262075)
			(xy 126.812861 -281.262075) (xy 126.864156 -281.2702) (xy 126.913549 -281.286248) (xy 126.959823 -281.309826)
			(xy 127.001839 -281.340352) (xy 127.038562 -281.377075) (xy 127.069088 -281.419091) (xy 127.092666 -281.465365)
			(xy 127.108714 -281.514758) (xy 127.116839 -281.566053) (xy 127.117348 -281.59202) (xy 127.116844 -281.617733)
			(xy 127.396749 -281.617733) (xy 127.396749 -281.565799) (xy 127.404874 -281.514504) (xy 127.420922 -281.465111)
			(xy 127.4445 -281.418837) (xy 127.475026 -281.376821) (xy 127.511749 -281.340098) (xy 127.553765 -281.309572)
			(xy 127.600039 -281.285994) (xy 127.649432 -281.269946) (xy 127.700727 -281.261821) (xy 127.752661 -281.261821)
			(xy 127.803956 -281.269946) (xy 127.853349 -281.285994) (xy 127.899623 -281.309572) (xy 127.941639 -281.340098)
			(xy 127.978362 -281.376821) (xy 128.008888 -281.418837) (xy 128.032466 -281.465111) (xy 128.048514 -281.514504)
			(xy 128.056639 -281.565799) (xy 128.057148 -281.591766) (xy 128.056639 -281.617733) (xy 128.056599 -281.617987)
			(xy 128.336803 -281.617987) (xy 128.336803 -281.566053) (xy 128.344928 -281.514758) (xy 128.360976 -281.465365)
			(xy 128.384554 -281.419091) (xy 128.41508 -281.377075) (xy 128.451803 -281.340352) (xy 128.493819 -281.309826)
			(xy 128.540093 -281.286248) (xy 128.589486 -281.2702) (xy 128.640781 -281.262075) (xy 128.692715 -281.262075)
			(xy 128.74401 -281.2702) (xy 128.793403 -281.286248) (xy 128.839677 -281.309826) (xy 128.881693 -281.340352)
			(xy 128.918416 -281.377075) (xy 128.948942 -281.419091) (xy 128.97252 -281.465365) (xy 128.988568 -281.514758)
			(xy 128.996693 -281.566053) (xy 128.997202 -281.59202) (xy 128.996693 -281.617987) (xy 129.276349 -281.617987)
			(xy 129.276349 -281.566053) (xy 129.284474 -281.514758) (xy 129.300522 -281.465365) (xy 129.3241 -281.419091)
			(xy 129.354626 -281.377075) (xy 129.391349 -281.340352) (xy 129.433365 -281.309826) (xy 129.479639 -281.286248)
			(xy 129.529032 -281.2702) (xy 129.580327 -281.262075) (xy 129.632261 -281.262075) (xy 129.683556 -281.2702)
			(xy 129.732949 -281.286248) (xy 129.779223 -281.309826) (xy 129.821239 -281.340352) (xy 129.857962 -281.377075)
			(xy 129.888488 -281.419091) (xy 129.912066 -281.465365) (xy 129.928114 -281.514758) (xy 129.936239 -281.566053)
			(xy 129.936748 -281.59202) (xy 129.936239 -281.617987) (xy 130.216403 -281.617987) (xy 130.216403 -281.566053)
			(xy 130.224528 -281.514758) (xy 130.240576 -281.465365) (xy 130.264154 -281.419091) (xy 130.29468 -281.377075)
			(xy 130.331403 -281.340352) (xy 130.373419 -281.309826) (xy 130.419693 -281.286248) (xy 130.469086 -281.2702)
			(xy 130.520381 -281.262075) (xy 130.572315 -281.262075) (xy 130.62361 -281.2702) (xy 130.673003 -281.286248)
			(xy 130.719277 -281.309826) (xy 130.761293 -281.340352) (xy 130.798016 -281.377075) (xy 130.828542 -281.419091)
			(xy 130.85212 -281.465365) (xy 130.868168 -281.514758) (xy 130.876293 -281.566053) (xy 130.876802 -281.59202)
			(xy 130.876293 -281.617987) (xy 131.156203 -281.617987) (xy 131.156203 -281.566053) (xy 131.164328 -281.514758)
			(xy 131.180376 -281.465365) (xy 131.203954 -281.419091) (xy 131.23448 -281.377075) (xy 131.271203 -281.340352)
			(xy 131.313219 -281.309826) (xy 131.359493 -281.286248) (xy 131.408886 -281.2702) (xy 131.460181 -281.262075)
			(xy 131.512115 -281.262075) (xy 131.56341 -281.2702) (xy 131.612803 -281.286248) (xy 131.659077 -281.309826)
			(xy 131.701093 -281.340352) (xy 131.737816 -281.377075) (xy 131.768342 -281.419091) (xy 131.79192 -281.465365)
			(xy 131.807968 -281.514758) (xy 131.816093 -281.566053) (xy 131.816602 -281.59202) (xy 131.816093 -281.617987)
			(xy 132.096003 -281.617987) (xy 132.096003 -281.566053) (xy 132.104128 -281.514758) (xy 132.120176 -281.465365)
			(xy 132.143754 -281.419091) (xy 132.17428 -281.377075) (xy 132.211003 -281.340352) (xy 132.253019 -281.309826)
			(xy 132.299293 -281.286248) (xy 132.348686 -281.2702) (xy 132.399981 -281.262075) (xy 132.451915 -281.262075)
			(xy 132.50321 -281.2702) (xy 132.552603 -281.286248) (xy 132.598877 -281.309826) (xy 132.640893 -281.340352)
			(xy 132.677616 -281.377075) (xy 132.708142 -281.419091) (xy 132.73172 -281.465365) (xy 132.747768 -281.514758)
			(xy 132.755893 -281.566053) (xy 132.756402 -281.59202) (xy 132.755893 -281.617987) (xy 132.747768 -281.669282)
			(xy 132.73172 -281.718675) (xy 132.708142 -281.764949) (xy 132.677616 -281.806965) (xy 132.640893 -281.843688)
			(xy 132.598877 -281.874214) (xy 132.552603 -281.897792) (xy 132.50321 -281.91384) (xy 132.451915 -281.921965)
			(xy 132.399981 -281.921965) (xy 132.348686 -281.91384) (xy 132.299293 -281.897792) (xy 132.253019 -281.874214)
			(xy 132.211003 -281.843688) (xy 132.17428 -281.806965) (xy 132.143754 -281.764949) (xy 132.120176 -281.718675)
			(xy 132.104128 -281.669282) (xy 132.096003 -281.617987) (xy 131.816093 -281.617987) (xy 131.807968 -281.669282)
			(xy 131.79192 -281.718675) (xy 131.768342 -281.764949) (xy 131.737816 -281.806965) (xy 131.701093 -281.843688)
			(xy 131.659077 -281.874214) (xy 131.612803 -281.897792) (xy 131.56341 -281.91384) (xy 131.512115 -281.921965)
			(xy 131.460181 -281.921965) (xy 131.408886 -281.91384) (xy 131.359493 -281.897792) (xy 131.313219 -281.874214)
			(xy 131.271203 -281.843688) (xy 131.23448 -281.806965) (xy 131.203954 -281.764949) (xy 131.180376 -281.718675)
			(xy 131.164328 -281.669282) (xy 131.156203 -281.617987) (xy 130.876293 -281.617987) (xy 130.868168 -281.669282)
			(xy 130.85212 -281.718675) (xy 130.828542 -281.764949) (xy 130.798016 -281.806965) (xy 130.761293 -281.843688)
			(xy 130.719277 -281.874214) (xy 130.673003 -281.897792) (xy 130.62361 -281.91384) (xy 130.572315 -281.921965)
			(xy 130.520381 -281.921965) (xy 130.469086 -281.91384) (xy 130.419693 -281.897792) (xy 130.373419 -281.874214)
			(xy 130.331403 -281.843688) (xy 130.29468 -281.806965) (xy 130.264154 -281.764949) (xy 130.240576 -281.718675)
			(xy 130.224528 -281.669282) (xy 130.216403 -281.617987) (xy 129.936239 -281.617987) (xy 129.928114 -281.669282)
			(xy 129.912066 -281.718675) (xy 129.888488 -281.764949) (xy 129.857962 -281.806965) (xy 129.821239 -281.843688)
			(xy 129.779223 -281.874214) (xy 129.732949 -281.897792) (xy 129.683556 -281.91384) (xy 129.632261 -281.921965)
			(xy 129.580327 -281.921965) (xy 129.529032 -281.91384) (xy 129.479639 -281.897792) (xy 129.433365 -281.874214)
			(xy 129.391349 -281.843688) (xy 129.354626 -281.806965) (xy 129.3241 -281.764949) (xy 129.300522 -281.718675)
			(xy 129.284474 -281.669282) (xy 129.276349 -281.617987) (xy 128.996693 -281.617987) (xy 128.988568 -281.669282)
			(xy 128.97252 -281.718675) (xy 128.948942 -281.764949) (xy 128.918416 -281.806965) (xy 128.881693 -281.843688)
			(xy 128.839677 -281.874214) (xy 128.793403 -281.897792) (xy 128.74401 -281.91384) (xy 128.692715 -281.921965)
			(xy 128.640781 -281.921965) (xy 128.589486 -281.91384) (xy 128.540093 -281.897792) (xy 128.493819 -281.874214)
			(xy 128.451803 -281.843688) (xy 128.41508 -281.806965) (xy 128.384554 -281.764949) (xy 128.360976 -281.718675)
			(xy 128.344928 -281.669282) (xy 128.336803 -281.617987) (xy 128.056599 -281.617987) (xy 128.048514 -281.669028)
			(xy 128.032466 -281.718421) (xy 128.008888 -281.764695) (xy 127.978362 -281.806711) (xy 127.941639 -281.843434)
			(xy 127.899623 -281.87396) (xy 127.853349 -281.897538) (xy 127.803956 -281.913586) (xy 127.752661 -281.921711)
			(xy 127.700727 -281.921711) (xy 127.649432 -281.913586) (xy 127.600039 -281.897538) (xy 127.553765 -281.87396)
			(xy 127.511749 -281.843434) (xy 127.475026 -281.806711) (xy 127.4445 -281.764695) (xy 127.420922 -281.718421)
			(xy 127.404874 -281.669028) (xy 127.396749 -281.617733) (xy 127.116844 -281.617733) (xy 127.116839 -281.617987)
			(xy 127.108714 -281.669282) (xy 127.092666 -281.718675) (xy 127.069088 -281.764949) (xy 127.038562 -281.806965)
			(xy 127.001839 -281.843688) (xy 126.959823 -281.874214) (xy 126.913549 -281.897792) (xy 126.864156 -281.91384)
			(xy 126.812861 -281.921965) (xy 126.760927 -281.921965) (xy 126.709632 -281.91384) (xy 126.660239 -281.897792)
			(xy 126.613965 -281.874214) (xy 126.571949 -281.843688) (xy 126.535226 -281.806965) (xy 126.5047 -281.764949)
			(xy 126.481122 -281.718675) (xy 126.465074 -281.669282) (xy 126.456949 -281.617987) (xy 126.177293 -281.617987)
			(xy 126.169168 -281.669282) (xy 126.15312 -281.718675) (xy 126.129542 -281.764949) (xy 126.099016 -281.806965)
			(xy 126.062293 -281.843688) (xy 126.020277 -281.874214) (xy 125.974003 -281.897792) (xy 125.92461 -281.91384)
			(xy 125.873315 -281.921965) (xy 125.821381 -281.921965) (xy 125.770086 -281.91384) (xy 125.720693 -281.897792)
			(xy 125.674419 -281.874214) (xy 125.632403 -281.843688) (xy 125.59568 -281.806965) (xy 125.565154 -281.764949)
			(xy 125.541576 -281.718675) (xy 125.525528 -281.669282) (xy 125.517403 -281.617987) (xy 125.237493 -281.617987)
			(xy 125.229368 -281.669282) (xy 125.21332 -281.718675) (xy 125.189742 -281.764949) (xy 125.159216 -281.806965)
			(xy 125.122493 -281.843688) (xy 125.080477 -281.874214) (xy 125.034203 -281.897792) (xy 124.98481 -281.91384)
			(xy 124.933515 -281.921965) (xy 124.881581 -281.921965) (xy 124.830286 -281.91384) (xy 124.780893 -281.897792)
			(xy 124.734619 -281.874214) (xy 124.692603 -281.843688) (xy 124.65588 -281.806965) (xy 124.625354 -281.764949)
			(xy 124.601776 -281.718675) (xy 124.585728 -281.669282) (xy 124.577603 -281.617987) (xy 124.297693 -281.617987)
			(xy 124.289568 -281.669282) (xy 124.27352 -281.718675) (xy 124.249942 -281.764949) (xy 124.219416 -281.806965)
			(xy 124.182693 -281.843688) (xy 124.140677 -281.874214) (xy 124.094403 -281.897792) (xy 124.04501 -281.91384)
			(xy 123.993715 -281.921965) (xy 123.941781 -281.921965) (xy 123.890486 -281.91384) (xy 123.841093 -281.897792)
			(xy 123.794819 -281.874214) (xy 123.752803 -281.843688) (xy 123.71608 -281.806965) (xy 123.685554 -281.764949)
			(xy 123.661976 -281.718675) (xy 123.645928 -281.669282) (xy 123.637803 -281.617987) (xy 123.357893 -281.617987)
			(xy 123.349768 -281.669282) (xy 123.33372 -281.718675) (xy 123.310142 -281.764949) (xy 123.279616 -281.806965)
			(xy 123.242893 -281.843688) (xy 123.200877 -281.874214) (xy 123.154603 -281.897792) (xy 123.10521 -281.91384)
			(xy 123.053915 -281.921965) (xy 123.001981 -281.921965) (xy 122.950686 -281.91384) (xy 122.901293 -281.897792)
			(xy 122.855019 -281.874214) (xy 122.813003 -281.843688) (xy 122.77628 -281.806965) (xy 122.745754 -281.764949)
			(xy 122.722176 -281.718675) (xy 122.706128 -281.669282) (xy 122.698003 -281.617987) (xy 122.418093 -281.617987)
			(xy 122.409968 -281.669282) (xy 122.39392 -281.718675) (xy 122.370342 -281.764949) (xy 122.339816 -281.806965)
			(xy 122.303093 -281.843688) (xy 122.261077 -281.874214) (xy 122.214803 -281.897792) (xy 122.16541 -281.91384)
			(xy 122.114115 -281.921965) (xy 122.062181 -281.921965) (xy 122.010886 -281.91384) (xy 121.961493 -281.897792)
			(xy 121.915219 -281.874214) (xy 121.873203 -281.843688) (xy 121.83648 -281.806965) (xy 121.805954 -281.764949)
			(xy 121.782376 -281.718675) (xy 121.766328 -281.669282) (xy 121.758203 -281.617987) (xy 121.478293 -281.617987)
			(xy 121.470168 -281.669282) (xy 121.45412 -281.718675) (xy 121.430542 -281.764949) (xy 121.400016 -281.806965)
			(xy 121.363293 -281.843688) (xy 121.321277 -281.874214) (xy 121.275003 -281.897792) (xy 121.22561 -281.91384)
			(xy 121.174315 -281.921965) (xy 121.122381 -281.921965) (xy 121.071086 -281.91384) (xy 121.021693 -281.897792)
			(xy 120.975419 -281.874214) (xy 120.933403 -281.843688) (xy 120.89668 -281.806965) (xy 120.866154 -281.764949)
			(xy 120.842576 -281.718675) (xy 120.826528 -281.669282) (xy 120.818403 -281.617987) (xy 120.538493 -281.617987)
			(xy 120.530368 -281.669282) (xy 120.51432 -281.718675) (xy 120.490742 -281.764949) (xy 120.460216 -281.806965)
			(xy 120.423493 -281.843688) (xy 120.381477 -281.874214) (xy 120.335203 -281.897792) (xy 120.28581 -281.91384)
			(xy 120.234515 -281.921965) (xy 120.182581 -281.921965) (xy 120.131286 -281.91384) (xy 120.081893 -281.897792)
			(xy 120.035619 -281.874214) (xy 119.993603 -281.843688) (xy 119.95688 -281.806965) (xy 119.926354 -281.764949)
			(xy 119.902776 -281.718675) (xy 119.886728 -281.669282) (xy 119.878603 -281.617987) (xy 119.598693 -281.617987)
			(xy 119.590568 -281.669282) (xy 119.57452 -281.718675) (xy 119.550942 -281.764949) (xy 119.520416 -281.806965)
			(xy 119.483693 -281.843688) (xy 119.441677 -281.874214) (xy 119.395403 -281.897792) (xy 119.34601 -281.91384)
			(xy 119.294715 -281.921965) (xy 119.242781 -281.921965) (xy 119.191486 -281.91384) (xy 119.142093 -281.897792)
			(xy 119.095819 -281.874214) (xy 119.053803 -281.843688) (xy 119.01708 -281.806965) (xy 118.986554 -281.764949)
			(xy 118.962976 -281.718675) (xy 118.946928 -281.669282) (xy 118.938803 -281.617987) (xy 118.657553 -281.617987)
			(xy 118.655586 -281.643234) (xy 118.643711 -281.693229) (xy 118.624238 -281.740784) (xy 118.597637 -281.784749)
			(xy 118.564549 -281.824066) (xy 118.525773 -281.857785) (xy 118.482243 -281.885094) (xy 118.43501 -281.905333)
			(xy 118.385213 -281.918015) (xy 118.359682 -281.92095) (xy 118.344752 -281.922879) (xy 118.316901 -281.934264)
			(xy 118.293569 -281.953261) (xy 118.276776 -281.978227) (xy 118.267975 -282.006999) (xy 118.26748 -282.022042)
			(xy 118.26748 -282.431803) (xy 118.468649 -282.431803) (xy 118.468649 -282.379869) (xy 118.476774 -282.328574)
			(xy 118.492822 -282.279181) (xy 118.5164 -282.232907) (xy 118.546926 -282.190891) (xy 118.583649 -282.154168)
			(xy 118.625665 -282.123642) (xy 118.671939 -282.100064) (xy 118.721332 -282.084016) (xy 118.772627 -282.075891)
			(xy 118.824561 -282.075891) (xy 118.875856 -282.084016) (xy 118.925249 -282.100064) (xy 118.971523 -282.123642)
			(xy 119.013539 -282.154168) (xy 119.050262 -282.190891) (xy 119.080788 -282.232907) (xy 119.104366 -282.279181)
			(xy 119.120414 -282.328574) (xy 119.128539 -282.379869) (xy 119.129048 -282.405836) (xy 119.128539 -282.431803)
			(xy 119.408449 -282.431803) (xy 119.408449 -282.379869) (xy 119.416574 -282.328574) (xy 119.432622 -282.279181)
			(xy 119.4562 -282.232907) (xy 119.486726 -282.190891) (xy 119.523449 -282.154168) (xy 119.565465 -282.123642)
			(xy 119.611739 -282.100064) (xy 119.661132 -282.084016) (xy 119.712427 -282.075891) (xy 119.764361 -282.075891)
			(xy 119.815656 -282.084016) (xy 119.865049 -282.100064) (xy 119.911323 -282.123642) (xy 119.953339 -282.154168)
			(xy 119.990062 -282.190891) (xy 120.020588 -282.232907) (xy 120.044166 -282.279181) (xy 120.060214 -282.328574)
			(xy 120.068339 -282.379869) (xy 120.068848 -282.405836) (xy 120.068339 -282.431803) (xy 120.348249 -282.431803)
			(xy 120.348249 -282.379869) (xy 120.356374 -282.328574) (xy 120.372422 -282.279181) (xy 120.396 -282.232907)
			(xy 120.426526 -282.190891) (xy 120.463249 -282.154168) (xy 120.505265 -282.123642) (xy 120.551539 -282.100064)
			(xy 120.600932 -282.084016) (xy 120.652227 -282.075891) (xy 120.704161 -282.075891) (xy 120.755456 -282.084016)
			(xy 120.804849 -282.100064) (xy 120.851123 -282.123642) (xy 120.893139 -282.154168) (xy 120.929862 -282.190891)
			(xy 120.960388 -282.232907) (xy 120.983966 -282.279181) (xy 121.000014 -282.328574) (xy 121.008139 -282.379869)
			(xy 121.008648 -282.405836) (xy 121.008139 -282.431803) (xy 121.288049 -282.431803) (xy 121.288049 -282.379869)
			(xy 121.296174 -282.328574) (xy 121.312222 -282.279181) (xy 121.3358 -282.232907) (xy 121.366326 -282.190891)
			(xy 121.403049 -282.154168) (xy 121.445065 -282.123642) (xy 121.491339 -282.100064) (xy 121.540732 -282.084016)
			(xy 121.592027 -282.075891) (xy 121.643961 -282.075891) (xy 121.695256 -282.084016) (xy 121.744649 -282.100064)
			(xy 121.790923 -282.123642) (xy 121.832939 -282.154168) (xy 121.869662 -282.190891) (xy 121.900188 -282.232907)
			(xy 121.923766 -282.279181) (xy 121.939814 -282.328574) (xy 121.947939 -282.379869) (xy 121.948448 -282.405836)
			(xy 121.947939 -282.431803) (xy 122.227849 -282.431803) (xy 122.227849 -282.379869) (xy 122.235974 -282.328574)
			(xy 122.252022 -282.279181) (xy 122.2756 -282.232907) (xy 122.306126 -282.190891) (xy 122.342849 -282.154168)
			(xy 122.384865 -282.123642) (xy 122.431139 -282.100064) (xy 122.480532 -282.084016) (xy 122.531827 -282.075891)
			(xy 122.583761 -282.075891) (xy 122.635056 -282.084016) (xy 122.684449 -282.100064) (xy 122.730723 -282.123642)
			(xy 122.772739 -282.154168) (xy 122.809462 -282.190891) (xy 122.839988 -282.232907) (xy 122.863566 -282.279181)
			(xy 122.879614 -282.328574) (xy 122.887739 -282.379869) (xy 122.888248 -282.405836) (xy 122.887739 -282.431803)
			(xy 123.167649 -282.431803) (xy 123.167649 -282.379869) (xy 123.175774 -282.328574) (xy 123.191822 -282.279181)
			(xy 123.2154 -282.232907) (xy 123.245926 -282.190891) (xy 123.282649 -282.154168) (xy 123.324665 -282.123642)
			(xy 123.370939 -282.100064) (xy 123.420332 -282.084016) (xy 123.471627 -282.075891) (xy 123.523561 -282.075891)
			(xy 123.574856 -282.084016) (xy 123.624249 -282.100064) (xy 123.670523 -282.123642) (xy 123.712539 -282.154168)
			(xy 123.749262 -282.190891) (xy 123.779788 -282.232907) (xy 123.803366 -282.279181) (xy 123.819414 -282.328574)
			(xy 123.827539 -282.379869) (xy 123.828048 -282.405836) (xy 123.827539 -282.431803) (xy 124.107449 -282.431803)
			(xy 124.107449 -282.379869) (xy 124.115574 -282.328574) (xy 124.131622 -282.279181) (xy 124.1552 -282.232907)
			(xy 124.185726 -282.190891) (xy 124.222449 -282.154168) (xy 124.264465 -282.123642) (xy 124.310739 -282.100064)
			(xy 124.360132 -282.084016) (xy 124.411427 -282.075891) (xy 124.463361 -282.075891) (xy 124.514656 -282.084016)
			(xy 124.564049 -282.100064) (xy 124.610323 -282.123642) (xy 124.652339 -282.154168) (xy 124.689062 -282.190891)
			(xy 124.719588 -282.232907) (xy 124.743166 -282.279181) (xy 124.759214 -282.328574) (xy 124.767339 -282.379869)
			(xy 124.767848 -282.405836) (xy 124.767339 -282.431803) (xy 125.047249 -282.431803) (xy 125.047249 -282.379869)
			(xy 125.055374 -282.328574) (xy 125.071422 -282.279181) (xy 125.095 -282.232907) (xy 125.125526 -282.190891)
			(xy 125.162249 -282.154168) (xy 125.204265 -282.123642) (xy 125.250539 -282.100064) (xy 125.299932 -282.084016)
			(xy 125.351227 -282.075891) (xy 125.403161 -282.075891) (xy 125.454456 -282.084016) (xy 125.503849 -282.100064)
			(xy 125.550123 -282.123642) (xy 125.592139 -282.154168) (xy 125.628862 -282.190891) (xy 125.659388 -282.232907)
			(xy 125.682966 -282.279181) (xy 125.699014 -282.328574) (xy 125.707139 -282.379869) (xy 125.707648 -282.405836)
			(xy 125.707139 -282.431803) (xy 125.987303 -282.431803) (xy 125.987303 -282.379869) (xy 125.995428 -282.328574)
			(xy 126.011476 -282.279181) (xy 126.035054 -282.232907) (xy 126.06558 -282.190891) (xy 126.102303 -282.154168)
			(xy 126.144319 -282.123642) (xy 126.190593 -282.100064) (xy 126.239986 -282.084016) (xy 126.291281 -282.075891)
			(xy 126.343215 -282.075891) (xy 126.39451 -282.084016) (xy 126.443903 -282.100064) (xy 126.490177 -282.123642)
			(xy 126.532193 -282.154168) (xy 126.568916 -282.190891) (xy 126.599442 -282.232907) (xy 126.62302 -282.279181)
			(xy 126.639068 -282.328574) (xy 126.647193 -282.379869) (xy 126.647702 -282.405836) (xy 126.647198 -282.431549)
			(xy 126.927103 -282.431549) (xy 126.927103 -282.379615) (xy 126.935228 -282.32832) (xy 126.951276 -282.278927)
			(xy 126.974854 -282.232653) (xy 127.00538 -282.190637) (xy 127.042103 -282.153914) (xy 127.084119 -282.123388)
			(xy 127.130393 -282.09981) (xy 127.179786 -282.083762) (xy 127.231081 -282.075637) (xy 127.283015 -282.075637)
			(xy 127.33431 -282.083762) (xy 127.383703 -282.09981) (xy 127.429977 -282.123388) (xy 127.471993 -282.153914)
			(xy 127.508716 -282.190637) (xy 127.539242 -282.232653) (xy 127.56282 -282.278927) (xy 127.578868 -282.32832)
			(xy 127.586993 -282.379615) (xy 127.587502 -282.405582) (xy 127.586993 -282.431549) (xy 127.866903 -282.431549)
			(xy 127.866903 -282.379615) (xy 127.875028 -282.32832) (xy 127.891076 -282.278927) (xy 127.914654 -282.232653)
			(xy 127.94518 -282.190637) (xy 127.981903 -282.153914) (xy 128.023919 -282.123388) (xy 128.070193 -282.09981)
			(xy 128.119586 -282.083762) (xy 128.170881 -282.075637) (xy 128.222815 -282.075637) (xy 128.27411 -282.083762)
			(xy 128.323503 -282.09981) (xy 128.369777 -282.123388) (xy 128.411793 -282.153914) (xy 128.448516 -282.190637)
			(xy 128.479042 -282.232653) (xy 128.50262 -282.278927) (xy 128.518668 -282.32832) (xy 128.526793 -282.379615)
			(xy 128.527302 -282.405582) (xy 128.526793 -282.431549) (xy 128.806703 -282.431549) (xy 128.806703 -282.379615)
			(xy 128.814828 -282.32832) (xy 128.830876 -282.278927) (xy 128.854454 -282.232653) (xy 128.88498 -282.190637)
			(xy 128.921703 -282.153914) (xy 128.963719 -282.123388) (xy 129.009993 -282.09981) (xy 129.059386 -282.083762)
			(xy 129.110681 -282.075637) (xy 129.162615 -282.075637) (xy 129.21391 -282.083762) (xy 129.263303 -282.09981)
			(xy 129.309577 -282.123388) (xy 129.351593 -282.153914) (xy 129.388316 -282.190637) (xy 129.418842 -282.232653)
			(xy 129.44242 -282.278927) (xy 129.458468 -282.32832) (xy 129.466593 -282.379615) (xy 129.467102 -282.405582)
			(xy 129.466593 -282.431549) (xy 129.746503 -282.431549) (xy 129.746503 -282.379615) (xy 129.754628 -282.32832)
			(xy 129.770676 -282.278927) (xy 129.794254 -282.232653) (xy 129.82478 -282.190637) (xy 129.861503 -282.153914)
			(xy 129.903519 -282.123388) (xy 129.949793 -282.09981) (xy 129.999186 -282.083762) (xy 130.050481 -282.075637)
			(xy 130.102415 -282.075637) (xy 130.15371 -282.083762) (xy 130.203103 -282.09981) (xy 130.249377 -282.123388)
			(xy 130.291393 -282.153914) (xy 130.328116 -282.190637) (xy 130.358642 -282.232653) (xy 130.38222 -282.278927)
			(xy 130.398268 -282.32832) (xy 130.406393 -282.379615) (xy 130.406902 -282.405582) (xy 130.406393 -282.431549)
			(xy 130.406353 -282.431803) (xy 130.686049 -282.431803) (xy 130.686049 -282.379869) (xy 130.694174 -282.328574)
			(xy 130.710222 -282.279181) (xy 130.7338 -282.232907) (xy 130.764326 -282.190891) (xy 130.801049 -282.154168)
			(xy 130.843065 -282.123642) (xy 130.889339 -282.100064) (xy 130.938732 -282.084016) (xy 130.990027 -282.075891)
			(xy 131.041961 -282.075891) (xy 131.093256 -282.084016) (xy 131.142649 -282.100064) (xy 131.188923 -282.123642)
			(xy 131.230939 -282.154168) (xy 131.267662 -282.190891) (xy 131.298188 -282.232907) (xy 131.321766 -282.279181)
			(xy 131.337814 -282.328574) (xy 131.345939 -282.379869) (xy 131.346448 -282.405836) (xy 131.345939 -282.431803)
			(xy 131.625849 -282.431803) (xy 131.625849 -282.379869) (xy 131.633974 -282.328574) (xy 131.650022 -282.279181)
			(xy 131.6736 -282.232907) (xy 131.704126 -282.190891) (xy 131.740849 -282.154168) (xy 131.782865 -282.123642)
			(xy 131.829139 -282.100064) (xy 131.878532 -282.084016) (xy 131.929827 -282.075891) (xy 131.981761 -282.075891)
			(xy 132.033056 -282.084016) (xy 132.082449 -282.100064) (xy 132.128723 -282.123642) (xy 132.170739 -282.154168)
			(xy 132.207462 -282.190891) (xy 132.237988 -282.232907) (xy 132.261566 -282.279181) (xy 132.277614 -282.328574)
			(xy 132.285739 -282.379869) (xy 132.286248 -282.405836) (xy 132.285739 -282.431803) (xy 132.565649 -282.431803)
			(xy 132.565649 -282.379869) (xy 132.573774 -282.328574) (xy 132.589822 -282.279181) (xy 132.6134 -282.232907)
			(xy 132.643926 -282.190891) (xy 132.680649 -282.154168) (xy 132.722665 -282.123642) (xy 132.768939 -282.100064)
			(xy 132.818332 -282.084016) (xy 132.869627 -282.075891) (xy 132.921561 -282.075891) (xy 132.972856 -282.084016)
			(xy 133.022249 -282.100064) (xy 133.068523 -282.123642) (xy 133.110539 -282.154168) (xy 133.147262 -282.190891)
			(xy 133.177788 -282.232907) (xy 133.201366 -282.279181) (xy 133.217414 -282.328574) (xy 133.225539 -282.379869)
			(xy 133.226048 -282.405836) (xy 133.225539 -282.431803) (xy 133.505449 -282.431803) (xy 133.505449 -282.379869)
			(xy 133.513574 -282.328574) (xy 133.529622 -282.279181) (xy 133.5532 -282.232907) (xy 133.583726 -282.190891)
			(xy 133.620449 -282.154168) (xy 133.662465 -282.123642) (xy 133.708739 -282.100064) (xy 133.758132 -282.084016)
			(xy 133.809427 -282.075891) (xy 133.861361 -282.075891) (xy 133.912656 -282.084016) (xy 133.962049 -282.100064)
			(xy 134.008323 -282.123642) (xy 134.050339 -282.154168) (xy 134.087062 -282.190891) (xy 134.117588 -282.232907)
			(xy 134.141166 -282.279181) (xy 134.157214 -282.328574) (xy 134.165339 -282.379869) (xy 134.165848 -282.405836)
			(xy 134.165339 -282.431803) (xy 134.445503 -282.431803) (xy 134.445503 -282.379869) (xy 134.453628 -282.328574)
			(xy 134.469676 -282.279181) (xy 134.493254 -282.232907) (xy 134.52378 -282.190891) (xy 134.560503 -282.154168)
			(xy 134.602519 -282.123642) (xy 134.648793 -282.100064) (xy 134.698186 -282.084016) (xy 134.749481 -282.075891)
			(xy 134.801415 -282.075891) (xy 134.85271 -282.084016) (xy 134.902103 -282.100064) (xy 134.948377 -282.123642)
			(xy 134.990393 -282.154168) (xy 135.027116 -282.190891) (xy 135.057642 -282.232907) (xy 135.08122 -282.279181)
			(xy 135.097268 -282.328574) (xy 135.105393 -282.379869) (xy 135.105902 -282.405836) (xy 135.105393 -282.431803)
			(xy 135.385049 -282.431803) (xy 135.385049 -282.379869) (xy 135.393174 -282.328574) (xy 135.409222 -282.279181)
			(xy 135.4328 -282.232907) (xy 135.463326 -282.190891) (xy 135.500049 -282.154168) (xy 135.542065 -282.123642)
			(xy 135.588339 -282.100064) (xy 135.637732 -282.084016) (xy 135.689027 -282.075891) (xy 135.740961 -282.075891)
			(xy 135.792256 -282.084016) (xy 135.841649 -282.100064) (xy 135.887923 -282.123642) (xy 135.929939 -282.154168)
			(xy 135.966662 -282.190891) (xy 135.997188 -282.232907) (xy 136.020766 -282.279181) (xy 136.036814 -282.328574)
			(xy 136.044939 -282.379869) (xy 136.045448 -282.405836) (xy 136.044939 -282.431803) (xy 136.324849 -282.431803)
			(xy 136.324849 -282.379869) (xy 136.332974 -282.328574) (xy 136.349022 -282.279181) (xy 136.3726 -282.232907)
			(xy 136.403126 -282.190891) (xy 136.439849 -282.154168) (xy 136.481865 -282.123642) (xy 136.528139 -282.100064)
			(xy 136.577532 -282.084016) (xy 136.628827 -282.075891) (xy 136.680761 -282.075891) (xy 136.732056 -282.084016)
			(xy 136.781449 -282.100064) (xy 136.827723 -282.123642) (xy 136.869739 -282.154168) (xy 136.906462 -282.190891)
			(xy 136.936988 -282.232907) (xy 136.960566 -282.279181) (xy 136.976614 -282.328574) (xy 136.984739 -282.379869)
			(xy 136.985248 -282.405836) (xy 136.984739 -282.431803) (xy 137.264649 -282.431803) (xy 137.264649 -282.379869)
			(xy 137.272774 -282.328574) (xy 137.288822 -282.279181) (xy 137.3124 -282.232907) (xy 137.342926 -282.190891)
			(xy 137.379649 -282.154168) (xy 137.421665 -282.123642) (xy 137.467939 -282.100064) (xy 137.517332 -282.084016)
			(xy 137.568627 -282.075891) (xy 137.620561 -282.075891) (xy 137.671856 -282.084016) (xy 137.721249 -282.100064)
			(xy 137.767523 -282.123642) (xy 137.809539 -282.154168) (xy 137.846262 -282.190891) (xy 137.876788 -282.232907)
			(xy 137.900366 -282.279181) (xy 137.916414 -282.328574) (xy 137.924539 -282.379869) (xy 137.925048 -282.405836)
			(xy 137.924539 -282.431803) (xy 137.916414 -282.483098) (xy 137.900366 -282.532491) (xy 137.876788 -282.578765)
			(xy 137.846262 -282.620781) (xy 137.809539 -282.657504) (xy 137.767523 -282.68803) (xy 137.721249 -282.711608)
			(xy 137.671856 -282.727656) (xy 137.620561 -282.735781) (xy 137.568627 -282.735781) (xy 137.517332 -282.727656)
			(xy 137.467939 -282.711608) (xy 137.421665 -282.68803) (xy 137.379649 -282.657504) (xy 137.342926 -282.620781)
			(xy 137.3124 -282.578765) (xy 137.288822 -282.532491) (xy 137.272774 -282.483098) (xy 137.264649 -282.431803)
			(xy 136.984739 -282.431803) (xy 136.976614 -282.483098) (xy 136.960566 -282.532491) (xy 136.936988 -282.578765)
			(xy 136.906462 -282.620781) (xy 136.869739 -282.657504) (xy 136.827723 -282.68803) (xy 136.781449 -282.711608)
			(xy 136.732056 -282.727656) (xy 136.680761 -282.735781) (xy 136.628827 -282.735781) (xy 136.577532 -282.727656)
			(xy 136.528139 -282.711608) (xy 136.481865 -282.68803) (xy 136.439849 -282.657504) (xy 136.403126 -282.620781)
			(xy 136.3726 -282.578765) (xy 136.349022 -282.532491) (xy 136.332974 -282.483098) (xy 136.324849 -282.431803)
			(xy 136.044939 -282.431803) (xy 136.036814 -282.483098) (xy 136.020766 -282.532491) (xy 135.997188 -282.578765)
			(xy 135.966662 -282.620781) (xy 135.929939 -282.657504) (xy 135.887923 -282.68803) (xy 135.841649 -282.711608)
			(xy 135.792256 -282.727656) (xy 135.740961 -282.735781) (xy 135.689027 -282.735781) (xy 135.637732 -282.727656)
			(xy 135.588339 -282.711608) (xy 135.542065 -282.68803) (xy 135.500049 -282.657504) (xy 135.463326 -282.620781)
			(xy 135.4328 -282.578765) (xy 135.409222 -282.532491) (xy 135.393174 -282.483098) (xy 135.385049 -282.431803)
			(xy 135.105393 -282.431803) (xy 135.097268 -282.483098) (xy 135.08122 -282.532491) (xy 135.057642 -282.578765)
			(xy 135.027116 -282.620781) (xy 134.990393 -282.657504) (xy 134.948377 -282.68803) (xy 134.902103 -282.711608)
			(xy 134.85271 -282.727656) (xy 134.801415 -282.735781) (xy 134.749481 -282.735781) (xy 134.698186 -282.727656)
			(xy 134.648793 -282.711608) (xy 134.602519 -282.68803) (xy 134.560503 -282.657504) (xy 134.52378 -282.620781)
			(xy 134.493254 -282.578765) (xy 134.469676 -282.532491) (xy 134.453628 -282.483098) (xy 134.445503 -282.431803)
			(xy 134.165339 -282.431803) (xy 134.157214 -282.483098) (xy 134.141166 -282.532491) (xy 134.117588 -282.578765)
			(xy 134.087062 -282.620781) (xy 134.050339 -282.657504) (xy 134.008323 -282.68803) (xy 133.962049 -282.711608)
			(xy 133.912656 -282.727656) (xy 133.861361 -282.735781) (xy 133.809427 -282.735781) (xy 133.758132 -282.727656)
			(xy 133.708739 -282.711608) (xy 133.662465 -282.68803) (xy 133.620449 -282.657504) (xy 133.583726 -282.620781)
			(xy 133.5532 -282.578765) (xy 133.529622 -282.532491) (xy 133.513574 -282.483098) (xy 133.505449 -282.431803)
			(xy 133.225539 -282.431803) (xy 133.217414 -282.483098) (xy 133.201366 -282.532491) (xy 133.177788 -282.578765)
			(xy 133.147262 -282.620781) (xy 133.110539 -282.657504) (xy 133.068523 -282.68803) (xy 133.022249 -282.711608)
			(xy 132.972856 -282.727656) (xy 132.921561 -282.735781) (xy 132.869627 -282.735781) (xy 132.818332 -282.727656)
			(xy 132.768939 -282.711608) (xy 132.722665 -282.68803) (xy 132.680649 -282.657504) (xy 132.643926 -282.620781)
			(xy 132.6134 -282.578765) (xy 132.589822 -282.532491) (xy 132.573774 -282.483098) (xy 132.565649 -282.431803)
			(xy 132.285739 -282.431803) (xy 132.277614 -282.483098) (xy 132.261566 -282.532491) (xy 132.237988 -282.578765)
			(xy 132.207462 -282.620781) (xy 132.170739 -282.657504) (xy 132.128723 -282.68803) (xy 132.082449 -282.711608)
			(xy 132.033056 -282.727656) (xy 131.981761 -282.735781) (xy 131.929827 -282.735781) (xy 131.878532 -282.727656)
			(xy 131.829139 -282.711608) (xy 131.782865 -282.68803) (xy 131.740849 -282.657504) (xy 131.704126 -282.620781)
			(xy 131.6736 -282.578765) (xy 131.650022 -282.532491) (xy 131.633974 -282.483098) (xy 131.625849 -282.431803)
			(xy 131.345939 -282.431803) (xy 131.337814 -282.483098) (xy 131.321766 -282.532491) (xy 131.298188 -282.578765)
			(xy 131.267662 -282.620781) (xy 131.230939 -282.657504) (xy 131.188923 -282.68803) (xy 131.142649 -282.711608)
			(xy 131.093256 -282.727656) (xy 131.041961 -282.735781) (xy 130.990027 -282.735781) (xy 130.938732 -282.727656)
			(xy 130.889339 -282.711608) (xy 130.843065 -282.68803) (xy 130.801049 -282.657504) (xy 130.764326 -282.620781)
			(xy 130.7338 -282.578765) (xy 130.710222 -282.532491) (xy 130.694174 -282.483098) (xy 130.686049 -282.431803)
			(xy 130.406353 -282.431803) (xy 130.398268 -282.482844) (xy 130.38222 -282.532237) (xy 130.358642 -282.578511)
			(xy 130.328116 -282.620527) (xy 130.291393 -282.65725) (xy 130.249377 -282.687776) (xy 130.203103 -282.711354)
			(xy 130.15371 -282.727402) (xy 130.102415 -282.735527) (xy 130.050481 -282.735527) (xy 129.999186 -282.727402)
			(xy 129.949793 -282.711354) (xy 129.903519 -282.687776) (xy 129.861503 -282.65725) (xy 129.82478 -282.620527)
			(xy 129.794254 -282.578511) (xy 129.770676 -282.532237) (xy 129.754628 -282.482844) (xy 129.746503 -282.431549)
			(xy 129.466593 -282.431549) (xy 129.458468 -282.482844) (xy 129.44242 -282.532237) (xy 129.418842 -282.578511)
			(xy 129.388316 -282.620527) (xy 129.351593 -282.65725) (xy 129.309577 -282.687776) (xy 129.263303 -282.711354)
			(xy 129.21391 -282.727402) (xy 129.162615 -282.735527) (xy 129.110681 -282.735527) (xy 129.059386 -282.727402)
			(xy 129.009993 -282.711354) (xy 128.963719 -282.687776) (xy 128.921703 -282.65725) (xy 128.88498 -282.620527)
			(xy 128.854454 -282.578511) (xy 128.830876 -282.532237) (xy 128.814828 -282.482844) (xy 128.806703 -282.431549)
			(xy 128.526793 -282.431549) (xy 128.518668 -282.482844) (xy 128.50262 -282.532237) (xy 128.479042 -282.578511)
			(xy 128.448516 -282.620527) (xy 128.411793 -282.65725) (xy 128.369777 -282.687776) (xy 128.323503 -282.711354)
			(xy 128.27411 -282.727402) (xy 128.222815 -282.735527) (xy 128.170881 -282.735527) (xy 128.119586 -282.727402)
			(xy 128.070193 -282.711354) (xy 128.023919 -282.687776) (xy 127.981903 -282.65725) (xy 127.94518 -282.620527)
			(xy 127.914654 -282.578511) (xy 127.891076 -282.532237) (xy 127.875028 -282.482844) (xy 127.866903 -282.431549)
			(xy 127.586993 -282.431549) (xy 127.578868 -282.482844) (xy 127.56282 -282.532237) (xy 127.539242 -282.578511)
			(xy 127.508716 -282.620527) (xy 127.471993 -282.65725) (xy 127.429977 -282.687776) (xy 127.383703 -282.711354)
			(xy 127.33431 -282.727402) (xy 127.283015 -282.735527) (xy 127.231081 -282.735527) (xy 127.179786 -282.727402)
			(xy 127.130393 -282.711354) (xy 127.084119 -282.687776) (xy 127.042103 -282.65725) (xy 127.00538 -282.620527)
			(xy 126.974854 -282.578511) (xy 126.951276 -282.532237) (xy 126.935228 -282.482844) (xy 126.927103 -282.431549)
			(xy 126.647198 -282.431549) (xy 126.647193 -282.431803) (xy 126.639068 -282.483098) (xy 126.62302 -282.532491)
			(xy 126.599442 -282.578765) (xy 126.568916 -282.620781) (xy 126.532193 -282.657504) (xy 126.490177 -282.68803)
			(xy 126.443903 -282.711608) (xy 126.39451 -282.727656) (xy 126.343215 -282.735781) (xy 126.291281 -282.735781)
			(xy 126.239986 -282.727656) (xy 126.190593 -282.711608) (xy 126.144319 -282.68803) (xy 126.102303 -282.657504)
			(xy 126.06558 -282.620781) (xy 126.035054 -282.578765) (xy 126.011476 -282.532491) (xy 125.995428 -282.483098)
			(xy 125.987303 -282.431803) (xy 125.707139 -282.431803) (xy 125.699014 -282.483098) (xy 125.682966 -282.532491)
			(xy 125.659388 -282.578765) (xy 125.628862 -282.620781) (xy 125.592139 -282.657504) (xy 125.550123 -282.68803)
			(xy 125.503849 -282.711608) (xy 125.454456 -282.727656) (xy 125.403161 -282.735781) (xy 125.351227 -282.735781)
			(xy 125.299932 -282.727656) (xy 125.250539 -282.711608) (xy 125.204265 -282.68803) (xy 125.162249 -282.657504)
			(xy 125.125526 -282.620781) (xy 125.095 -282.578765) (xy 125.071422 -282.532491) (xy 125.055374 -282.483098)
			(xy 125.047249 -282.431803) (xy 124.767339 -282.431803) (xy 124.759214 -282.483098) (xy 124.743166 -282.532491)
			(xy 124.719588 -282.578765) (xy 124.689062 -282.620781) (xy 124.652339 -282.657504) (xy 124.610323 -282.68803)
			(xy 124.564049 -282.711608) (xy 124.514656 -282.727656) (xy 124.463361 -282.735781) (xy 124.411427 -282.735781)
			(xy 124.360132 -282.727656) (xy 124.310739 -282.711608) (xy 124.264465 -282.68803) (xy 124.222449 -282.657504)
			(xy 124.185726 -282.620781) (xy 124.1552 -282.578765) (xy 124.131622 -282.532491) (xy 124.115574 -282.483098)
			(xy 124.107449 -282.431803) (xy 123.827539 -282.431803) (xy 123.819414 -282.483098) (xy 123.803366 -282.532491)
			(xy 123.779788 -282.578765) (xy 123.749262 -282.620781) (xy 123.712539 -282.657504) (xy 123.670523 -282.68803)
			(xy 123.624249 -282.711608) (xy 123.574856 -282.727656) (xy 123.523561 -282.735781) (xy 123.471627 -282.735781)
			(xy 123.420332 -282.727656) (xy 123.370939 -282.711608) (xy 123.324665 -282.68803) (xy 123.282649 -282.657504)
			(xy 123.245926 -282.620781) (xy 123.2154 -282.578765) (xy 123.191822 -282.532491) (xy 123.175774 -282.483098)
			(xy 123.167649 -282.431803) (xy 122.887739 -282.431803) (xy 122.879614 -282.483098) (xy 122.863566 -282.532491)
			(xy 122.839988 -282.578765) (xy 122.809462 -282.620781) (xy 122.772739 -282.657504) (xy 122.730723 -282.68803)
			(xy 122.684449 -282.711608) (xy 122.635056 -282.727656) (xy 122.583761 -282.735781) (xy 122.531827 -282.735781)
			(xy 122.480532 -282.727656) (xy 122.431139 -282.711608) (xy 122.384865 -282.68803) (xy 122.342849 -282.657504)
			(xy 122.306126 -282.620781) (xy 122.2756 -282.578765) (xy 122.252022 -282.532491) (xy 122.235974 -282.483098)
			(xy 122.227849 -282.431803) (xy 121.947939 -282.431803) (xy 121.939814 -282.483098) (xy 121.923766 -282.532491)
			(xy 121.900188 -282.578765) (xy 121.869662 -282.620781) (xy 121.832939 -282.657504) (xy 121.790923 -282.68803)
			(xy 121.744649 -282.711608) (xy 121.695256 -282.727656) (xy 121.643961 -282.735781) (xy 121.592027 -282.735781)
			(xy 121.540732 -282.727656) (xy 121.491339 -282.711608) (xy 121.445065 -282.68803) (xy 121.403049 -282.657504)
			(xy 121.366326 -282.620781) (xy 121.3358 -282.578765) (xy 121.312222 -282.532491) (xy 121.296174 -282.483098)
			(xy 121.288049 -282.431803) (xy 121.008139 -282.431803) (xy 121.000014 -282.483098) (xy 120.983966 -282.532491)
			(xy 120.960388 -282.578765) (xy 120.929862 -282.620781) (xy 120.893139 -282.657504) (xy 120.851123 -282.68803)
			(xy 120.804849 -282.711608) (xy 120.755456 -282.727656) (xy 120.704161 -282.735781) (xy 120.652227 -282.735781)
			(xy 120.600932 -282.727656) (xy 120.551539 -282.711608) (xy 120.505265 -282.68803) (xy 120.463249 -282.657504)
			(xy 120.426526 -282.620781) (xy 120.396 -282.578765) (xy 120.372422 -282.532491) (xy 120.356374 -282.483098)
			(xy 120.348249 -282.431803) (xy 120.068339 -282.431803) (xy 120.060214 -282.483098) (xy 120.044166 -282.532491)
			(xy 120.020588 -282.578765) (xy 119.990062 -282.620781) (xy 119.953339 -282.657504) (xy 119.911323 -282.68803)
			(xy 119.865049 -282.711608) (xy 119.815656 -282.727656) (xy 119.764361 -282.735781) (xy 119.712427 -282.735781)
			(xy 119.661132 -282.727656) (xy 119.611739 -282.711608) (xy 119.565465 -282.68803) (xy 119.523449 -282.657504)
			(xy 119.486726 -282.620781) (xy 119.4562 -282.578765) (xy 119.432622 -282.532491) (xy 119.416574 -282.483098)
			(xy 119.408449 -282.431803) (xy 119.128539 -282.431803) (xy 119.120414 -282.483098) (xy 119.104366 -282.532491)
			(xy 119.080788 -282.578765) (xy 119.050262 -282.620781) (xy 119.013539 -282.657504) (xy 118.971523 -282.68803)
			(xy 118.925249 -282.711608) (xy 118.875856 -282.727656) (xy 118.824561 -282.735781) (xy 118.772627 -282.735781)
			(xy 118.721332 -282.727656) (xy 118.671939 -282.711608) (xy 118.625665 -282.68803) (xy 118.583649 -282.657504)
			(xy 118.546926 -282.620781) (xy 118.5164 -282.578765) (xy 118.492822 -282.532491) (xy 118.476774 -282.483098)
			(xy 118.468649 -282.431803) (xy 118.26748 -282.431803) (xy 118.26748 -282.789884) (xy 118.26802 -282.804924)
			(xy 118.276789 -282.833697) (xy 118.293571 -282.858661) (xy 118.316904 -282.877644) (xy 118.34476 -282.888995)
			(xy 118.359682 -282.890976) (xy 118.386653 -282.894048) (xy 118.439144 -282.907864) (xy 118.488673 -282.93007)
			(xy 118.533909 -282.960068) (xy 118.573636 -282.997054) (xy 118.606787 -283.040033) (xy 118.632471 -283.087851)
			(xy 118.649998 -283.139222) (xy 118.658897 -283.192767) (xy 118.659402 -283.219906) (xy 118.658958 -283.244395)
			(xy 118.658737 -283.245873) (xy 118.938549 -283.245873) (xy 118.938549 -283.193939) (xy 118.946674 -283.142644)
			(xy 118.962722 -283.093251) (xy 118.9863 -283.046977) (xy 119.016826 -283.004961) (xy 119.053549 -282.968238)
			(xy 119.095565 -282.937712) (xy 119.141839 -282.914134) (xy 119.191232 -282.898086) (xy 119.242527 -282.889961)
			(xy 119.294461 -282.889961) (xy 119.345756 -282.898086) (xy 119.395149 -282.914134) (xy 119.441423 -282.937712)
			(xy 119.483439 -282.968238) (xy 119.520162 -283.004961) (xy 119.550688 -283.046977) (xy 119.574266 -283.093251)
			(xy 119.590314 -283.142644) (xy 119.598439 -283.193939) (xy 119.598948 -283.219906) (xy 119.598439 -283.245873)
			(xy 119.878603 -283.245873) (xy 119.878603 -283.193939) (xy 119.886728 -283.142644) (xy 119.902776 -283.093251)
			(xy 119.926354 -283.046977) (xy 119.95688 -283.004961) (xy 119.993603 -282.968238) (xy 120.035619 -282.937712)
			(xy 120.081893 -282.914134) (xy 120.131286 -282.898086) (xy 120.182581 -282.889961) (xy 120.234515 -282.889961)
			(xy 120.28581 -282.898086) (xy 120.335203 -282.914134) (xy 120.381477 -282.937712) (xy 120.423493 -282.968238)
			(xy 120.460216 -283.004961) (xy 120.490742 -283.046977) (xy 120.51432 -283.093251) (xy 120.530368 -283.142644)
			(xy 120.538493 -283.193939) (xy 120.539002 -283.219906) (xy 120.538493 -283.245873) (xy 120.818149 -283.245873)
			(xy 120.818149 -283.193939) (xy 120.826274 -283.142644) (xy 120.842322 -283.093251) (xy 120.8659 -283.046977)
			(xy 120.896426 -283.004961) (xy 120.933149 -282.968238) (xy 120.975165 -282.937712) (xy 121.021439 -282.914134)
			(xy 121.070832 -282.898086) (xy 121.122127 -282.889961) (xy 121.174061 -282.889961) (xy 121.225356 -282.898086)
			(xy 121.274749 -282.914134) (xy 121.321023 -282.937712) (xy 121.363039 -282.968238) (xy 121.399762 -283.004961)
			(xy 121.430288 -283.046977) (xy 121.453866 -283.093251) (xy 121.469914 -283.142644) (xy 121.478039 -283.193939)
			(xy 121.478548 -283.219906) (xy 121.478039 -283.245873) (xy 121.757949 -283.245873) (xy 121.757949 -283.193939)
			(xy 121.766074 -283.142644) (xy 121.782122 -283.093251) (xy 121.8057 -283.046977) (xy 121.836226 -283.004961)
			(xy 121.872949 -282.968238) (xy 121.914965 -282.937712) (xy 121.961239 -282.914134) (xy 122.010632 -282.898086)
			(xy 122.061927 -282.889961) (xy 122.113861 -282.889961) (xy 122.165156 -282.898086) (xy 122.214549 -282.914134)
			(xy 122.260823 -282.937712) (xy 122.302839 -282.968238) (xy 122.339562 -283.004961) (xy 122.370088 -283.046977)
			(xy 122.393666 -283.093251) (xy 122.409714 -283.142644) (xy 122.417839 -283.193939) (xy 122.418348 -283.219906)
			(xy 122.417839 -283.245873) (xy 122.698003 -283.245873) (xy 122.698003 -283.193939) (xy 122.706128 -283.142644)
			(xy 122.722176 -283.093251) (xy 122.745754 -283.046977) (xy 122.77628 -283.004961) (xy 122.813003 -282.968238)
			(xy 122.855019 -282.937712) (xy 122.901293 -282.914134) (xy 122.950686 -282.898086) (xy 123.001981 -282.889961)
			(xy 123.053915 -282.889961) (xy 123.10521 -282.898086) (xy 123.154603 -282.914134) (xy 123.200877 -282.937712)
			(xy 123.242893 -282.968238) (xy 123.279616 -283.004961) (xy 123.310142 -283.046977) (xy 123.33372 -283.093251)
			(xy 123.349768 -283.142644) (xy 123.357893 -283.193939) (xy 123.358402 -283.219906) (xy 123.357893 -283.245873)
			(xy 124.577603 -283.245873) (xy 124.577603 -283.193939) (xy 124.585728 -283.142644) (xy 124.601776 -283.093251)
			(xy 124.625354 -283.046977) (xy 124.65588 -283.004961) (xy 124.692603 -282.968238) (xy 124.734619 -282.937712)
			(xy 124.780893 -282.914134) (xy 124.830286 -282.898086) (xy 124.881581 -282.889961) (xy 124.933515 -282.889961)
			(xy 124.98481 -282.898086) (xy 125.034203 -282.914134) (xy 125.080477 -282.937712) (xy 125.122493 -282.968238)
			(xy 125.159216 -283.004961) (xy 125.189742 -283.046977) (xy 125.21332 -283.093251) (xy 125.229368 -283.142644)
			(xy 125.237493 -283.193939) (xy 125.238002 -283.219906) (xy 125.237493 -283.245873) (xy 125.517403 -283.245873)
			(xy 125.517403 -283.193939) (xy 125.525528 -283.142644) (xy 125.541576 -283.093251) (xy 125.565154 -283.046977)
			(xy 125.59568 -283.004961) (xy 125.632403 -282.968238) (xy 125.674419 -282.937712) (xy 125.720693 -282.914134)
			(xy 125.770086 -282.898086) (xy 125.821381 -282.889961) (xy 125.873315 -282.889961) (xy 125.92461 -282.898086)
			(xy 125.974003 -282.914134) (xy 126.020277 -282.937712) (xy 126.062293 -282.968238) (xy 126.099016 -283.004961)
			(xy 126.129542 -283.046977) (xy 126.15312 -283.093251) (xy 126.169168 -283.142644) (xy 126.177293 -283.193939)
			(xy 126.177802 -283.219906) (xy 126.177293 -283.245873) (xy 126.456949 -283.245873) (xy 126.456949 -283.193939)
			(xy 126.465074 -283.142644) (xy 126.481122 -283.093251) (xy 126.5047 -283.046977) (xy 126.535226 -283.004961)
			(xy 126.571949 -282.968238) (xy 126.613965 -282.937712) (xy 126.660239 -282.914134) (xy 126.709632 -282.898086)
			(xy 126.760927 -282.889961) (xy 126.812861 -282.889961) (xy 126.864156 -282.898086) (xy 126.913549 -282.914134)
			(xy 126.959823 -282.937712) (xy 127.001839 -282.968238) (xy 127.038562 -283.004961) (xy 127.069088 -283.046977)
			(xy 127.092666 -283.093251) (xy 127.108714 -283.142644) (xy 127.116839 -283.193939) (xy 127.117348 -283.219906)
			(xy 127.116844 -283.245619) (xy 128.336549 -283.245619) (xy 128.336549 -283.193685) (xy 128.344674 -283.14239)
			(xy 128.360722 -283.092997) (xy 128.3843 -283.046723) (xy 128.414826 -283.004707) (xy 128.451549 -282.967984)
			(xy 128.493565 -282.937458) (xy 128.539839 -282.91388) (xy 128.589232 -282.897832) (xy 128.640527 -282.889707)
			(xy 128.692461 -282.889707) (xy 128.743756 -282.897832) (xy 128.793149 -282.91388) (xy 128.839423 -282.937458)
			(xy 128.881439 -282.967984) (xy 128.918162 -283.004707) (xy 128.948688 -283.046723) (xy 128.972266 -283.092997)
			(xy 128.988314 -283.14239) (xy 128.996439 -283.193685) (xy 128.996948 -283.219652) (xy 128.996439 -283.245619)
			(xy 128.996399 -283.245873) (xy 129.276349 -283.245873) (xy 129.276349 -283.193939) (xy 129.284474 -283.142644)
			(xy 129.300522 -283.093251) (xy 129.3241 -283.046977) (xy 129.354626 -283.004961) (xy 129.391349 -282.968238)
			(xy 129.433365 -282.937712) (xy 129.479639 -282.914134) (xy 129.529032 -282.898086) (xy 129.580327 -282.889961)
			(xy 129.632261 -282.889961) (xy 129.683556 -282.898086) (xy 129.732949 -282.914134) (xy 129.779223 -282.937712)
			(xy 129.821239 -282.968238) (xy 129.857962 -283.004961) (xy 129.888488 -283.046977) (xy 129.912066 -283.093251)
			(xy 129.928114 -283.142644) (xy 129.936239 -283.193939) (xy 129.936748 -283.219906) (xy 129.936239 -283.245873)
			(xy 130.216149 -283.245873) (xy 130.216149 -283.193939) (xy 130.224274 -283.142644) (xy 130.240322 -283.093251)
			(xy 130.2639 -283.046977) (xy 130.294426 -283.004961) (xy 130.331149 -282.968238) (xy 130.373165 -282.937712)
			(xy 130.419439 -282.914134) (xy 130.468832 -282.898086) (xy 130.520127 -282.889961) (xy 130.572061 -282.889961)
			(xy 130.623356 -282.898086) (xy 130.672749 -282.914134) (xy 130.719023 -282.937712) (xy 130.761039 -282.968238)
			(xy 130.797762 -283.004961) (xy 130.828288 -283.046977) (xy 130.851866 -283.093251) (xy 130.867914 -283.142644)
			(xy 130.876039 -283.193939) (xy 130.876548 -283.219906) (xy 130.876039 -283.245873) (xy 131.156203 -283.245873)
			(xy 131.156203 -283.193939) (xy 131.164328 -283.142644) (xy 131.180376 -283.093251) (xy 131.203954 -283.046977)
			(xy 131.23448 -283.004961) (xy 131.271203 -282.968238) (xy 131.313219 -282.937712) (xy 131.359493 -282.914134)
			(xy 131.408886 -282.898086) (xy 131.460181 -282.889961) (xy 131.512115 -282.889961) (xy 131.56341 -282.898086)
			(xy 131.612803 -282.914134) (xy 131.659077 -282.937712) (xy 131.701093 -282.968238) (xy 131.737816 -283.004961)
			(xy 131.768342 -283.046977) (xy 131.79192 -283.093251) (xy 131.807968 -283.142644) (xy 131.816093 -283.193939)
			(xy 131.816602 -283.219906) (xy 131.816093 -283.245873) (xy 132.095749 -283.245873) (xy 132.095749 -283.193939)
			(xy 132.103874 -283.142644) (xy 132.119922 -283.093251) (xy 132.1435 -283.046977) (xy 132.174026 -283.004961)
			(xy 132.210749 -282.968238) (xy 132.252765 -282.937712) (xy 132.299039 -282.914134) (xy 132.348432 -282.898086)
			(xy 132.399727 -282.889961) (xy 132.451661 -282.889961) (xy 132.502956 -282.898086) (xy 132.552349 -282.914134)
			(xy 132.598623 -282.937712) (xy 132.640639 -282.968238) (xy 132.677362 -283.004961) (xy 132.707888 -283.046977)
			(xy 132.731466 -283.093251) (xy 132.747514 -283.142644) (xy 132.755639 -283.193939) (xy 132.756148 -283.219906)
			(xy 132.755639 -283.245873) (xy 133.035803 -283.245873) (xy 133.035803 -283.193939) (xy 133.043928 -283.142644)
			(xy 133.059976 -283.093251) (xy 133.083554 -283.046977) (xy 133.11408 -283.004961) (xy 133.150803 -282.968238)
			(xy 133.192819 -282.937712) (xy 133.239093 -282.914134) (xy 133.288486 -282.898086) (xy 133.339781 -282.889961)
			(xy 133.391715 -282.889961) (xy 133.44301 -282.898086) (xy 133.492403 -282.914134) (xy 133.538677 -282.937712)
			(xy 133.580693 -282.968238) (xy 133.617416 -283.004961) (xy 133.647942 -283.046977) (xy 133.67152 -283.093251)
			(xy 133.687568 -283.142644) (xy 133.695693 -283.193939) (xy 133.696202 -283.219906) (xy 133.695693 -283.245873)
			(xy 133.975603 -283.245873) (xy 133.975603 -283.193939) (xy 133.983728 -283.142644) (xy 133.999776 -283.093251)
			(xy 134.023354 -283.046977) (xy 134.05388 -283.004961) (xy 134.090603 -282.968238) (xy 134.132619 -282.937712)
			(xy 134.178893 -282.914134) (xy 134.228286 -282.898086) (xy 134.279581 -282.889961) (xy 134.331515 -282.889961)
			(xy 134.38281 -282.898086) (xy 134.432203 -282.914134) (xy 134.478477 -282.937712) (xy 134.520493 -282.968238)
			(xy 134.557216 -283.004961) (xy 134.587742 -283.046977) (xy 134.61132 -283.093251) (xy 134.627368 -283.142644)
			(xy 134.635493 -283.193939) (xy 134.636002 -283.219906) (xy 134.635493 -283.245873) (xy 134.915149 -283.245873)
			(xy 134.915149 -283.193939) (xy 134.923274 -283.142644) (xy 134.939322 -283.093251) (xy 134.9629 -283.046977)
			(xy 134.993426 -283.004961) (xy 135.030149 -282.968238) (xy 135.072165 -282.937712) (xy 135.118439 -282.914134)
			(xy 135.167832 -282.898086) (xy 135.219127 -282.889961) (xy 135.271061 -282.889961) (xy 135.322356 -282.898086)
			(xy 135.371749 -282.914134) (xy 135.418023 -282.937712) (xy 135.460039 -282.968238) (xy 135.496762 -283.004961)
			(xy 135.527288 -283.046977) (xy 135.550866 -283.093251) (xy 135.566914 -283.142644) (xy 135.575039 -283.193939)
			(xy 135.575548 -283.219906) (xy 135.575039 -283.245873) (xy 135.854949 -283.245873) (xy 135.854949 -283.193939)
			(xy 135.863074 -283.142644) (xy 135.879122 -283.093251) (xy 135.9027 -283.046977) (xy 135.933226 -283.004961)
			(xy 135.969949 -282.968238) (xy 136.011965 -282.937712) (xy 136.058239 -282.914134) (xy 136.107632 -282.898086)
			(xy 136.158927 -282.889961) (xy 136.210861 -282.889961) (xy 136.262156 -282.898086) (xy 136.311549 -282.914134)
			(xy 136.357823 -282.937712) (xy 136.399839 -282.968238) (xy 136.436562 -283.004961) (xy 136.467088 -283.046977)
			(xy 136.490666 -283.093251) (xy 136.506714 -283.142644) (xy 136.514839 -283.193939) (xy 136.515348 -283.219906)
			(xy 136.514839 -283.245873) (xy 136.795003 -283.245873) (xy 136.795003 -283.193939) (xy 136.803128 -283.142644)
			(xy 136.819176 -283.093251) (xy 136.842754 -283.046977) (xy 136.87328 -283.004961) (xy 136.910003 -282.968238)
			(xy 136.952019 -282.937712) (xy 136.998293 -282.914134) (xy 137.047686 -282.898086) (xy 137.098981 -282.889961)
			(xy 137.150915 -282.889961) (xy 137.20221 -282.898086) (xy 137.251603 -282.914134) (xy 137.297877 -282.937712)
			(xy 137.339893 -282.968238) (xy 137.376616 -283.004961) (xy 137.407142 -283.046977) (xy 137.43072 -283.093251)
			(xy 137.446768 -283.142644) (xy 137.454893 -283.193939) (xy 137.455402 -283.219906) (xy 137.454893 -283.245873)
			(xy 137.446768 -283.297168) (xy 137.43072 -283.346561) (xy 137.407142 -283.392835) (xy 137.376616 -283.434851)
			(xy 137.339893 -283.471574) (xy 137.297877 -283.5021) (xy 137.251603 -283.525678) (xy 137.20221 -283.541726)
			(xy 137.150915 -283.549851) (xy 137.098981 -283.549851) (xy 137.047686 -283.541726) (xy 136.998293 -283.525678)
			(xy 136.952019 -283.5021) (xy 136.910003 -283.471574) (xy 136.87328 -283.434851) (xy 136.842754 -283.392835)
			(xy 136.819176 -283.346561) (xy 136.803128 -283.297168) (xy 136.795003 -283.245873) (xy 136.514839 -283.245873)
			(xy 136.506714 -283.297168) (xy 136.490666 -283.346561) (xy 136.467088 -283.392835) (xy 136.436562 -283.434851)
			(xy 136.399839 -283.471574) (xy 136.357823 -283.5021) (xy 136.311549 -283.525678) (xy 136.262156 -283.541726)
			(xy 136.210861 -283.549851) (xy 136.158927 -283.549851) (xy 136.107632 -283.541726) (xy 136.058239 -283.525678)
			(xy 136.011965 -283.5021) (xy 135.969949 -283.471574) (xy 135.933226 -283.434851) (xy 135.9027 -283.392835)
			(xy 135.879122 -283.346561) (xy 135.863074 -283.297168) (xy 135.854949 -283.245873) (xy 135.575039 -283.245873)
			(xy 135.566914 -283.297168) (xy 135.550866 -283.346561) (xy 135.527288 -283.392835) (xy 135.496762 -283.434851)
			(xy 135.460039 -283.471574) (xy 135.418023 -283.5021) (xy 135.371749 -283.525678) (xy 135.322356 -283.541726)
			(xy 135.271061 -283.549851) (xy 135.219127 -283.549851) (xy 135.167832 -283.541726) (xy 135.118439 -283.525678)
			(xy 135.072165 -283.5021) (xy 135.030149 -283.471574) (xy 134.993426 -283.434851) (xy 134.9629 -283.392835)
			(xy 134.939322 -283.346561) (xy 134.923274 -283.297168) (xy 134.915149 -283.245873) (xy 134.635493 -283.245873)
			(xy 134.627368 -283.297168) (xy 134.61132 -283.346561) (xy 134.587742 -283.392835) (xy 134.557216 -283.434851)
			(xy 134.520493 -283.471574) (xy 134.478477 -283.5021) (xy 134.432203 -283.525678) (xy 134.38281 -283.541726)
			(xy 134.331515 -283.549851) (xy 134.279581 -283.549851) (xy 134.228286 -283.541726) (xy 134.178893 -283.525678)
			(xy 134.132619 -283.5021) (xy 134.090603 -283.471574) (xy 134.05388 -283.434851) (xy 134.023354 -283.392835)
			(xy 133.999776 -283.346561) (xy 133.983728 -283.297168) (xy 133.975603 -283.245873) (xy 133.695693 -283.245873)
			(xy 133.687568 -283.297168) (xy 133.67152 -283.346561) (xy 133.647942 -283.392835) (xy 133.617416 -283.434851)
			(xy 133.580693 -283.471574) (xy 133.538677 -283.5021) (xy 133.492403 -283.525678) (xy 133.44301 -283.541726)
			(xy 133.391715 -283.549851) (xy 133.339781 -283.549851) (xy 133.288486 -283.541726) (xy 133.239093 -283.525678)
			(xy 133.192819 -283.5021) (xy 133.150803 -283.471574) (xy 133.11408 -283.434851) (xy 133.083554 -283.392835)
			(xy 133.059976 -283.346561) (xy 133.043928 -283.297168) (xy 133.035803 -283.245873) (xy 132.755639 -283.245873)
			(xy 132.747514 -283.297168) (xy 132.731466 -283.346561) (xy 132.707888 -283.392835) (xy 132.677362 -283.434851)
			(xy 132.640639 -283.471574) (xy 132.598623 -283.5021) (xy 132.552349 -283.525678) (xy 132.502956 -283.541726)
			(xy 132.451661 -283.549851) (xy 132.399727 -283.549851) (xy 132.348432 -283.541726) (xy 132.299039 -283.525678)
			(xy 132.252765 -283.5021) (xy 132.210749 -283.471574) (xy 132.174026 -283.434851) (xy 132.1435 -283.392835)
			(xy 132.119922 -283.346561) (xy 132.103874 -283.297168) (xy 132.095749 -283.245873) (xy 131.816093 -283.245873)
			(xy 131.807968 -283.297168) (xy 131.79192 -283.346561) (xy 131.768342 -283.392835) (xy 131.737816 -283.434851)
			(xy 131.701093 -283.471574) (xy 131.659077 -283.5021) (xy 131.612803 -283.525678) (xy 131.56341 -283.541726)
			(xy 131.512115 -283.549851) (xy 131.460181 -283.549851) (xy 131.408886 -283.541726) (xy 131.359493 -283.525678)
			(xy 131.313219 -283.5021) (xy 131.271203 -283.471574) (xy 131.23448 -283.434851) (xy 131.203954 -283.392835)
			(xy 131.180376 -283.346561) (xy 131.164328 -283.297168) (xy 131.156203 -283.245873) (xy 130.876039 -283.245873)
			(xy 130.867914 -283.297168) (xy 130.851866 -283.346561) (xy 130.828288 -283.392835) (xy 130.797762 -283.434851)
			(xy 130.761039 -283.471574) (xy 130.719023 -283.5021) (xy 130.672749 -283.525678) (xy 130.623356 -283.541726)
			(xy 130.572061 -283.549851) (xy 130.520127 -283.549851) (xy 130.468832 -283.541726) (xy 130.419439 -283.525678)
			(xy 130.373165 -283.5021) (xy 130.331149 -283.471574) (xy 130.294426 -283.434851) (xy 130.2639 -283.392835)
			(xy 130.240322 -283.346561) (xy 130.224274 -283.297168) (xy 130.216149 -283.245873) (xy 129.936239 -283.245873)
			(xy 129.928114 -283.297168) (xy 129.912066 -283.346561) (xy 129.888488 -283.392835) (xy 129.857962 -283.434851)
			(xy 129.821239 -283.471574) (xy 129.779223 -283.5021) (xy 129.732949 -283.525678) (xy 129.683556 -283.541726)
			(xy 129.632261 -283.549851) (xy 129.580327 -283.549851) (xy 129.529032 -283.541726) (xy 129.479639 -283.525678)
			(xy 129.433365 -283.5021) (xy 129.391349 -283.471574) (xy 129.354626 -283.434851) (xy 129.3241 -283.392835)
			(xy 129.300522 -283.346561) (xy 129.284474 -283.297168) (xy 129.276349 -283.245873) (xy 128.996399 -283.245873)
			(xy 128.988314 -283.296914) (xy 128.972266 -283.346307) (xy 128.948688 -283.392581) (xy 128.918162 -283.434597)
			(xy 128.881439 -283.47132) (xy 128.839423 -283.501846) (xy 128.793149 -283.525424) (xy 128.743756 -283.541472)
			(xy 128.692461 -283.549597) (xy 128.640527 -283.549597) (xy 128.589232 -283.541472) (xy 128.539839 -283.525424)
			(xy 128.493565 -283.501846) (xy 128.451549 -283.47132) (xy 128.414826 -283.434597) (xy 128.3843 -283.392581)
			(xy 128.360722 -283.346307) (xy 128.344674 -283.296914) (xy 128.336549 -283.245619) (xy 127.116844 -283.245619)
			(xy 127.116839 -283.245873) (xy 127.108714 -283.297168) (xy 127.092666 -283.346561) (xy 127.069088 -283.392835)
			(xy 127.038562 -283.434851) (xy 127.001839 -283.471574) (xy 126.959823 -283.5021) (xy 126.913549 -283.525678)
			(xy 126.864156 -283.541726) (xy 126.812861 -283.549851) (xy 126.760927 -283.549851) (xy 126.709632 -283.541726)
			(xy 126.660239 -283.525678) (xy 126.613965 -283.5021) (xy 126.571949 -283.471574) (xy 126.535226 -283.434851)
			(xy 126.5047 -283.392835) (xy 126.481122 -283.346561) (xy 126.465074 -283.297168) (xy 126.456949 -283.245873)
			(xy 126.177293 -283.245873) (xy 126.169168 -283.297168) (xy 126.15312 -283.346561) (xy 126.129542 -283.392835)
			(xy 126.099016 -283.434851) (xy 126.062293 -283.471574) (xy 126.020277 -283.5021) (xy 125.974003 -283.525678)
			(xy 125.92461 -283.541726) (xy 125.873315 -283.549851) (xy 125.821381 -283.549851) (xy 125.770086 -283.541726)
			(xy 125.720693 -283.525678) (xy 125.674419 -283.5021) (xy 125.632403 -283.471574) (xy 125.59568 -283.434851)
			(xy 125.565154 -283.392835) (xy 125.541576 -283.346561) (xy 125.525528 -283.297168) (xy 125.517403 -283.245873)
			(xy 125.237493 -283.245873) (xy 125.229368 -283.297168) (xy 125.21332 -283.346561) (xy 125.189742 -283.392835)
			(xy 125.159216 -283.434851) (xy 125.122493 -283.471574) (xy 125.080477 -283.5021) (xy 125.034203 -283.525678)
			(xy 124.98481 -283.541726) (xy 124.933515 -283.549851) (xy 124.881581 -283.549851) (xy 124.830286 -283.541726)
			(xy 124.780893 -283.525678) (xy 124.734619 -283.5021) (xy 124.692603 -283.471574) (xy 124.65588 -283.434851)
			(xy 124.625354 -283.392835) (xy 124.601776 -283.346561) (xy 124.585728 -283.297168) (xy 124.577603 -283.245873)
			(xy 123.357893 -283.245873) (xy 123.349768 -283.297168) (xy 123.33372 -283.346561) (xy 123.310142 -283.392835)
			(xy 123.279616 -283.434851) (xy 123.242893 -283.471574) (xy 123.200877 -283.5021) (xy 123.154603 -283.525678)
			(xy 123.10521 -283.541726) (xy 123.053915 -283.549851) (xy 123.001981 -283.549851) (xy 122.950686 -283.541726)
			(xy 122.901293 -283.525678) (xy 122.855019 -283.5021) (xy 122.813003 -283.471574) (xy 122.77628 -283.434851)
			(xy 122.745754 -283.392835) (xy 122.722176 -283.346561) (xy 122.706128 -283.297168) (xy 122.698003 -283.245873)
			(xy 122.417839 -283.245873) (xy 122.409714 -283.297168) (xy 122.393666 -283.346561) (xy 122.370088 -283.392835)
			(xy 122.339562 -283.434851) (xy 122.302839 -283.471574) (xy 122.260823 -283.5021) (xy 122.214549 -283.525678)
			(xy 122.165156 -283.541726) (xy 122.113861 -283.549851) (xy 122.061927 -283.549851) (xy 122.010632 -283.541726)
			(xy 121.961239 -283.525678) (xy 121.914965 -283.5021) (xy 121.872949 -283.471574) (xy 121.836226 -283.434851)
			(xy 121.8057 -283.392835) (xy 121.782122 -283.346561) (xy 121.766074 -283.297168) (xy 121.757949 -283.245873)
			(xy 121.478039 -283.245873) (xy 121.469914 -283.297168) (xy 121.453866 -283.346561) (xy 121.430288 -283.392835)
			(xy 121.399762 -283.434851) (xy 121.363039 -283.471574) (xy 121.321023 -283.5021) (xy 121.274749 -283.525678)
			(xy 121.225356 -283.541726) (xy 121.174061 -283.549851) (xy 121.122127 -283.549851) (xy 121.070832 -283.541726)
			(xy 121.021439 -283.525678) (xy 120.975165 -283.5021) (xy 120.933149 -283.471574) (xy 120.896426 -283.434851)
			(xy 120.8659 -283.392835) (xy 120.842322 -283.346561) (xy 120.826274 -283.297168) (xy 120.818149 -283.245873)
			(xy 120.538493 -283.245873) (xy 120.530368 -283.297168) (xy 120.51432 -283.346561) (xy 120.490742 -283.392835)
			(xy 120.460216 -283.434851) (xy 120.423493 -283.471574) (xy 120.381477 -283.5021) (xy 120.335203 -283.525678)
			(xy 120.28581 -283.541726) (xy 120.234515 -283.549851) (xy 120.182581 -283.549851) (xy 120.131286 -283.541726)
			(xy 120.081893 -283.525678) (xy 120.035619 -283.5021) (xy 119.993603 -283.471574) (xy 119.95688 -283.434851)
			(xy 119.926354 -283.392835) (xy 119.902776 -283.346561) (xy 119.886728 -283.297168) (xy 119.878603 -283.245873)
			(xy 119.598439 -283.245873) (xy 119.590314 -283.297168) (xy 119.574266 -283.346561) (xy 119.550688 -283.392835)
			(xy 119.520162 -283.434851) (xy 119.483439 -283.471574) (xy 119.441423 -283.5021) (xy 119.395149 -283.525678)
			(xy 119.345756 -283.541726) (xy 119.294461 -283.549851) (xy 119.242527 -283.549851) (xy 119.191232 -283.541726)
			(xy 119.141839 -283.525678) (xy 119.095565 -283.5021) (xy 119.053549 -283.471574) (xy 119.016826 -283.434851)
			(xy 118.9863 -283.392835) (xy 118.962722 -283.346561) (xy 118.946674 -283.297168) (xy 118.938549 -283.245873)
			(xy 118.658737 -283.245873) (xy 118.651729 -283.292836) (xy 118.63743 -283.33968) (xy 118.616375 -283.383901)
			(xy 118.589025 -283.42453) (xy 118.555977 -283.460678) (xy 118.517957 -283.491553) (xy 118.497096 -283.504386)
			(xy 118.48402 -283.512688) (xy 118.463234 -283.535631) (xy 118.450283 -283.56375) (xy 118.446356 -283.594459)
			(xy 118.451817 -283.624932) (xy 118.466161 -283.652367) (xy 118.476776 -283.663644) (xy 118.588536 -283.775404)
			(xy 118.622826 -283.753814) (xy 118.64263 -283.741829) (xy 118.68488 -283.72292) (xy 118.72936 -283.710105)
			(xy 118.775195 -283.703637) (xy 118.79834 -283.703268) (xy 118.798594 -283.703268) (xy 118.826083 -283.703821)
			(xy 118.880302 -283.71293) (xy 118.932267 -283.730883) (xy 118.980546 -283.757183) (xy 119.02381 -283.791107)
			(xy 119.060867 -283.831721) (xy 119.090696 -283.877904) (xy 119.102124 -283.902912) (xy 119.14344 -283.896057)
			(xy 119.22687 -283.888681) (xy 119.268748 -283.88818) (xy 119.310499 -283.888685) (xy 119.393676 -283.896059)
			(xy 119.434864 -283.902912) (xy 119.446245 -283.877879) (xy 119.476064 -283.831681) (xy 119.513121 -283.791058)
			(xy 119.556394 -283.757134) (xy 119.604688 -283.730844) (xy 119.656669 -283.712914) (xy 119.710901 -283.70384)
			(xy 119.738394 -283.703268) (xy 119.764363 -283.70375) (xy 119.815662 -283.711875) (xy 119.865057 -283.727924)
			(xy 119.911334 -283.751504) (xy 119.953353 -283.782033) (xy 119.990077 -283.81876) (xy 120.020604 -283.860779)
			(xy 120.044182 -283.907057) (xy 120.060229 -283.956454) (xy 120.068351 -284.007753) (xy 120.068848 -284.033722)
			(xy 120.068327 -284.060138) (xy 120.059912 -284.112296) (xy 120.0433 -284.162449) (xy 120.018916 -284.209318)
			(xy 120.00357 -284.230826) (xy 120.030177 -284.263219) (xy 120.078254 -284.331898) (xy 120.099582 -284.367986)
			(xy 120.121172 -284.405324) (xy 120.128331 -284.416854) (xy 120.147617 -284.435934) (xy 120.171249 -284.449257)
			(xy 120.197556 -284.455882) (xy 120.22468 -284.455341) (xy 120.250702 -284.447671) (xy 120.273784 -284.433416)
			(xy 120.292293 -284.413581) (xy 120.298972 -284.401768) (xy 120.323479 -284.356565) (xy 120.380754 -284.271164)
			(xy 120.413272 -284.231334) (xy 120.397859 -284.209783) (xy 120.373373 -284.1628) (xy 120.356691 -284.112514)
			(xy 120.348241 -284.060212) (xy 120.34774 -284.033722) (xy 120.348221 -284.007751) (xy 120.356343 -283.956449)
			(xy 120.372391 -283.907049) (xy 120.39597 -283.860768) (xy 120.426498 -283.818746) (xy 120.463224 -283.782016)
			(xy 120.505244 -283.751484) (xy 120.551523 -283.727902) (xy 120.600922 -283.71185) (xy 120.652223 -283.703723)
			(xy 120.678194 -283.703268) (xy 120.705683 -283.703821) (xy 120.759902 -283.71293) (xy 120.811867 -283.730883)
			(xy 120.860146 -283.757183) (xy 120.90341 -283.791107) (xy 120.940467 -283.831721) (xy 120.970296 -283.877904)
			(xy 120.981724 -283.902912) (xy 121.02304 -283.896057) (xy 121.10647 -283.888681) (xy 121.148348 -283.88818)
			(xy 121.190099 -283.888685) (xy 121.273276 -283.896059) (xy 121.314464 -283.902912) (xy 121.325845 -283.877879)
			(xy 121.355664 -283.831681) (xy 121.392721 -283.791058) (xy 121.435994 -283.757134) (xy 121.484288 -283.730844)
			(xy 121.536269 -283.712914) (xy 121.590501 -283.70384) (xy 121.617994 -283.703268) (xy 121.643963 -283.70375)
			(xy 121.695262 -283.711875) (xy 121.744657 -283.727924) (xy 121.790934 -283.751504) (xy 121.832953 -283.782033)
			(xy 121.869677 -283.81876) (xy 121.900204 -283.860779) (xy 121.923782 -283.907057) (xy 121.939829 -283.956454)
			(xy 121.947951 -284.007753) (xy 121.948448 -284.033722) (xy 121.947927 -284.060138) (xy 121.939512 -284.112296)
			(xy 121.9229 -284.162449) (xy 121.898516 -284.209318) (xy 121.88317 -284.230826) (xy 121.909777 -284.263219)
			(xy 121.957854 -284.331898) (xy 121.979182 -284.367986) (xy 122.000772 -284.405324) (xy 122.007931 -284.416854)
			(xy 122.027217 -284.435934) (xy 122.050849 -284.449257) (xy 122.077156 -284.455882) (xy 122.10428 -284.455341)
			(xy 122.130302 -284.447671) (xy 122.153384 -284.433416) (xy 122.171893 -284.413581) (xy 122.178572 -284.401768)
			(xy 122.203079 -284.356565) (xy 122.260354 -284.271164) (xy 122.292872 -284.231334) (xy 122.277459 -284.209783)
			(xy 122.252973 -284.1628) (xy 122.236291 -284.112514) (xy 122.227841 -284.060212) (xy 122.22734 -284.033722)
			(xy 122.227821 -284.007751) (xy 122.235943 -283.956449) (xy 122.251991 -283.907049) (xy 122.27557 -283.860768)
			(xy 122.306098 -283.818746) (xy 122.342824 -283.782016) (xy 122.384844 -283.751484) (xy 122.431123 -283.727902)
			(xy 122.480522 -283.71185) (xy 122.531823 -283.703723) (xy 122.557794 -283.703268) (xy 122.585283 -283.703821)
			(xy 122.639502 -283.71293) (xy 122.691467 -283.730883) (xy 122.739746 -283.757183) (xy 122.78301 -283.791107)
			(xy 122.820067 -283.831721) (xy 122.849896 -283.877904) (xy 122.861324 -283.902912) (xy 122.90264 -283.896057)
			(xy 122.98607 -283.888681) (xy 123.027948 -283.88818) (xy 123.069699 -283.888685) (xy 123.152876 -283.896059)
			(xy 123.194064 -283.902912) (xy 123.205445 -283.877879) (xy 123.235264 -283.831681) (xy 123.272321 -283.791058)
			(xy 123.315594 -283.757134) (xy 123.363888 -283.730844) (xy 123.415869 -283.712914) (xy 123.470101 -283.70384)
			(xy 123.497594 -283.703268) (xy 123.523563 -283.70375) (xy 123.574862 -283.711875) (xy 123.624257 -283.727924)
			(xy 123.670534 -283.751504) (xy 123.712553 -283.782033) (xy 123.749277 -283.81876) (xy 123.779804 -283.860779)
			(xy 123.803382 -283.907057) (xy 123.819429 -283.956454) (xy 123.827551 -284.007753) (xy 123.828048 -284.033722)
			(xy 123.827527 -284.060138) (xy 123.819112 -284.112296) (xy 123.8025 -284.162449) (xy 123.778116 -284.209318)
			(xy 123.76277 -284.230826) (xy 123.789377 -284.263219) (xy 123.837454 -284.331898) (xy 123.858782 -284.367986)
			(xy 123.880372 -284.405324) (xy 123.887531 -284.416854) (xy 123.906817 -284.435934) (xy 123.930449 -284.449257)
			(xy 123.956756 -284.455882) (xy 123.98388 -284.455341) (xy 124.009902 -284.447671) (xy 124.032984 -284.433416)
			(xy 124.051493 -284.413581) (xy 124.058172 -284.401768) (xy 124.082679 -284.356565) (xy 124.139954 -284.271164)
			(xy 124.172472 -284.231334) (xy 124.157059 -284.209783) (xy 124.132573 -284.1628) (xy 124.115891 -284.112514)
			(xy 124.107441 -284.060212) (xy 124.10694 -284.033722) (xy 124.107421 -284.007751) (xy 124.115543 -283.956449)
			(xy 124.131591 -283.907049) (xy 124.15517 -283.860768) (xy 124.185698 -283.818746) (xy 124.222424 -283.782016)
			(xy 124.264444 -283.751484) (xy 124.310723 -283.727902) (xy 124.360122 -283.71185) (xy 124.411423 -283.703723)
			(xy 124.437394 -283.703268) (xy 124.464883 -283.703821) (xy 124.519102 -283.71293) (xy 124.571067 -283.730883)
			(xy 124.619346 -283.757183) (xy 124.66261 -283.791107) (xy 124.699667 -283.831721) (xy 124.729496 -283.877904)
			(xy 124.740924 -283.902912) (xy 124.78224 -283.896057) (xy 124.86567 -283.888681) (xy 124.907548 -283.88818)
			(xy 124.949363 -283.888666) (xy 125.032668 -283.896045) (xy 125.073918 -283.902912) (xy 125.085298 -283.877877)
			(xy 125.115115 -283.831674) (xy 125.152172 -283.791047) (xy 125.195444 -283.757116) (xy 125.243738 -283.73082)
			(xy 125.295719 -283.712883) (xy 125.349953 -283.703802) (xy 125.377448 -283.703268) (xy 125.403412 -283.703781)
			(xy 125.4547 -283.711911) (xy 125.504085 -283.727964) (xy 125.55035 -283.751545) (xy 125.592358 -283.782073)
			(xy 125.629073 -283.818795) (xy 125.659592 -283.860809) (xy 125.683162 -283.90708) (xy 125.699205 -283.956468)
			(xy 125.707325 -284.007758) (xy 125.707902 -284.033722) (xy 125.707357 -284.060179) (xy 125.698888 -284.112411)
			(xy 125.682217 -284.162631) (xy 125.657768 -284.209559) (xy 125.64237 -284.23108) (xy 125.668968 -284.263413)
			(xy 125.717043 -284.331965) (xy 125.738382 -284.367986) (xy 125.759972 -284.405324) (xy 125.767131 -284.416854)
			(xy 125.786417 -284.435934) (xy 125.810049 -284.449257) (xy 125.836356 -284.455882) (xy 125.86348 -284.455341)
			(xy 125.889502 -284.447671) (xy 125.912584 -284.433416) (xy 125.931093 -284.413581) (xy 125.937772 -284.401768)
			(xy 125.962279 -284.356565) (xy 126.019554 -284.271164) (xy 126.052072 -284.231334) (xy 126.036659 -284.209783)
			(xy 126.012173 -284.1628) (xy 125.995491 -284.112514) (xy 125.987041 -284.060212) (xy 125.98654 -284.033722)
			(xy 125.987021 -284.007751) (xy 125.995143 -283.956449) (xy 126.011191 -283.907049) (xy 126.03477 -283.860768)
			(xy 126.065298 -283.818746) (xy 126.102024 -283.782016) (xy 126.144044 -283.751484) (xy 126.190323 -283.727902)
			(xy 126.239722 -283.71185) (xy 126.291023 -283.703723) (xy 126.316994 -283.703268) (xy 126.344483 -283.703821)
			(xy 126.398702 -283.71293) (xy 126.450667 -283.730883) (xy 126.498946 -283.757183) (xy 126.54221 -283.791107)
			(xy 126.579267 -283.831721) (xy 126.609096 -283.877904) (xy 126.620524 -283.902912) (xy 126.66184 -283.896057)
			(xy 126.74527 -283.888681) (xy 126.787148 -283.88818) (xy 126.828899 -283.888685) (xy 126.912076 -283.896059)
			(xy 126.953264 -283.902912) (xy 126.964645 -283.877879) (xy 126.994464 -283.831681) (xy 127.031521 -283.791058)
			(xy 127.074794 -283.757134) (xy 127.123088 -283.730844) (xy 127.175069 -283.712914) (xy 127.229301 -283.70384)
			(xy 127.256794 -283.703268) (xy 127.282763 -283.70375) (xy 127.334062 -283.711875) (xy 127.383457 -283.727924)
			(xy 127.429734 -283.751504) (xy 127.471753 -283.782033) (xy 127.508477 -283.81876) (xy 127.539004 -283.860779)
			(xy 127.562582 -283.907057) (xy 127.578629 -283.956454) (xy 127.586751 -284.007753) (xy 127.587248 -284.033722)
			(xy 127.586727 -284.060138) (xy 127.578312 -284.112296) (xy 127.5617 -284.162449) (xy 127.537316 -284.209318)
			(xy 127.52197 -284.230826) (xy 127.548577 -284.263219) (xy 127.596654 -284.331898) (xy 127.617982 -284.367986)
			(xy 127.639572 -284.405324) (xy 127.646731 -284.416854) (xy 127.666017 -284.435934) (xy 127.689649 -284.449257)
			(xy 127.715956 -284.455882) (xy 127.74308 -284.455341) (xy 127.769102 -284.447671) (xy 127.792184 -284.433416)
			(xy 127.810693 -284.413581) (xy 127.817372 -284.401768) (xy 127.841879 -284.356565) (xy 127.899154 -284.271164)
			(xy 127.931672 -284.231334) (xy 127.916259 -284.209783) (xy 127.891773 -284.1628) (xy 127.875091 -284.112514)
			(xy 127.866641 -284.060212) (xy 127.86614 -284.033722) (xy 127.866621 -284.007751) (xy 127.874743 -283.956449)
			(xy 127.890791 -283.907049) (xy 127.91437 -283.860768) (xy 127.944898 -283.818746) (xy 127.981624 -283.782016)
			(xy 128.023644 -283.751484) (xy 128.069923 -283.727902) (xy 128.119322 -283.71185) (xy 128.170623 -283.703723)
			(xy 128.196594 -283.703268) (xy 128.224083 -283.703821) (xy 128.278302 -283.71293) (xy 128.330267 -283.730883)
			(xy 128.378546 -283.757183) (xy 128.42181 -283.791107) (xy 128.458867 -283.831721) (xy 128.488696 -283.877904)
			(xy 128.500124 -283.902912) (xy 128.54144 -283.896057) (xy 128.62487 -283.888681) (xy 128.666748 -283.88818)
			(xy 128.708499 -283.888685) (xy 128.791676 -283.896059) (xy 128.832864 -283.902912) (xy 128.844245 -283.877879)
			(xy 128.874064 -283.831681) (xy 128.911121 -283.791058) (xy 128.954394 -283.757134) (xy 129.002688 -283.730844)
			(xy 129.054669 -283.712914) (xy 129.108901 -283.70384) (xy 129.136394 -283.703268) (xy 129.162363 -283.70375)
			(xy 129.213662 -283.711875) (xy 129.263057 -283.727924) (xy 129.309334 -283.751504) (xy 129.351353 -283.782033)
			(xy 129.388077 -283.81876) (xy 129.418604 -283.860779) (xy 129.442182 -283.907057) (xy 129.458229 -283.956454)
			(xy 129.466351 -284.007753) (xy 129.466848 -284.033722) (xy 129.466327 -284.060138) (xy 129.457912 -284.112296)
			(xy 129.4413 -284.162449) (xy 129.416916 -284.209318) (xy 129.40157 -284.230826) (xy 129.428177 -284.263219)
			(xy 129.476254 -284.331898) (xy 129.497582 -284.367986) (xy 129.519172 -284.405324) (xy 129.526331 -284.416854)
			(xy 129.545617 -284.435934) (xy 129.569249 -284.449257) (xy 129.595556 -284.455882) (xy 129.62268 -284.455341)
			(xy 129.648702 -284.447671) (xy 129.671784 -284.433416) (xy 129.690293 -284.413581) (xy 129.696972 -284.401768)
			(xy 129.721479 -284.356565) (xy 129.778754 -284.271164) (xy 129.811272 -284.231334) (xy 129.795859 -284.209783)
			(xy 129.771373 -284.1628) (xy 129.754691 -284.112514) (xy 129.746241 -284.060212) (xy 129.74574 -284.033722)
			(xy 129.746221 -284.007751) (xy 129.754343 -283.956449) (xy 129.770391 -283.907049) (xy 129.79397 -283.860768)
			(xy 129.824498 -283.818746) (xy 129.861224 -283.782016) (xy 129.903244 -283.751484) (xy 129.949523 -283.727902)
			(xy 129.998922 -283.71185) (xy 130.050223 -283.703723) (xy 130.076194 -283.703268) (xy 130.103683 -283.703821)
			(xy 130.157902 -283.71293) (xy 130.209867 -283.730883) (xy 130.258146 -283.757183) (xy 130.30141 -283.791107)
			(xy 130.338467 -283.831721) (xy 130.368296 -283.877904) (xy 130.379724 -283.902912) (xy 130.42104 -283.896057)
			(xy 130.50447 -283.888681) (xy 130.546348 -283.88818) (xy 130.588099 -283.888685) (xy 130.671276 -283.896059)
			(xy 130.712464 -283.902912) (xy 130.723845 -283.877879) (xy 130.753664 -283.831681) (xy 130.790721 -283.791058)
			(xy 130.833994 -283.757134) (xy 130.882288 -283.730844) (xy 130.934269 -283.712914) (xy 130.988501 -283.70384)
			(xy 131.015994 -283.703268) (xy 131.041963 -283.70375) (xy 131.093262 -283.711875) (xy 131.142657 -283.727924)
			(xy 131.188934 -283.751504) (xy 131.230953 -283.782033) (xy 131.267677 -283.81876) (xy 131.298204 -283.860779)
			(xy 131.321782 -283.907057) (xy 131.337829 -283.956454) (xy 131.345951 -284.007753) (xy 131.346448 -284.033722)
			(xy 131.345927 -284.060138) (xy 131.337512 -284.112296) (xy 131.3209 -284.162449) (xy 131.296516 -284.209318)
			(xy 131.28117 -284.230826) (xy 131.307777 -284.263219) (xy 131.355854 -284.331898) (xy 131.377182 -284.367986)
			(xy 131.398772 -284.405324) (xy 131.405931 -284.416854) (xy 131.425217 -284.435934) (xy 131.448849 -284.449257)
			(xy 131.475156 -284.455882) (xy 131.50228 -284.455341) (xy 131.528302 -284.447671) (xy 131.551384 -284.433416)
			(xy 131.569893 -284.413581) (xy 131.576572 -284.401768) (xy 131.601079 -284.356565) (xy 131.658354 -284.271164)
			(xy 131.690872 -284.231334) (xy 131.675459 -284.209783) (xy 131.650973 -284.1628) (xy 131.634291 -284.112514)
			(xy 131.625841 -284.060212) (xy 131.62534 -284.033722) (xy 131.625821 -284.007751) (xy 131.633943 -283.956449)
			(xy 131.649991 -283.907049) (xy 131.67357 -283.860768) (xy 131.704098 -283.818746) (xy 131.740824 -283.782016)
			(xy 131.782844 -283.751484) (xy 131.829123 -283.727902) (xy 131.878522 -283.71185) (xy 131.929823 -283.703723)
			(xy 131.955794 -283.703268) (xy 131.983283 -283.703821) (xy 132.037502 -283.71293) (xy 132.089467 -283.730883)
			(xy 132.137746 -283.757183) (xy 132.18101 -283.791107) (xy 132.218067 -283.831721) (xy 132.247896 -283.877904)
			(xy 132.259324 -283.902912) (xy 132.30064 -283.896057) (xy 132.38407 -283.888681) (xy 132.425948 -283.88818)
			(xy 132.467699 -283.888685) (xy 132.550876 -283.896059) (xy 132.592064 -283.902912) (xy 132.603445 -283.877879)
			(xy 132.633264 -283.831681) (xy 132.670321 -283.791058) (xy 132.713594 -283.757134) (xy 132.761888 -283.730844)
			(xy 132.813869 -283.712914) (xy 132.868101 -283.70384) (xy 132.895594 -283.703268) (xy 132.921563 -283.70375)
			(xy 132.972862 -283.711875) (xy 133.022257 -283.727924) (xy 133.068534 -283.751504) (xy 133.110553 -283.782033)
			(xy 133.147277 -283.81876) (xy 133.177804 -283.860779) (xy 133.201382 -283.907057) (xy 133.217429 -283.956454)
			(xy 133.225551 -284.007753) (xy 133.226048 -284.033722) (xy 133.225536 -284.059689) (xy 134.445249 -284.059689)
			(xy 134.445249 -284.007755) (xy 134.453374 -283.95646) (xy 134.469422 -283.907067) (xy 134.493 -283.860793)
			(xy 134.523526 -283.818777) (xy 134.560249 -283.782054) (xy 134.602265 -283.751528) (xy 134.648539 -283.72795)
			(xy 134.697932 -283.711902) (xy 134.749227 -283.703777) (xy 134.801161 -283.703777) (xy 134.852456 -283.711902)
			(xy 134.901849 -283.72795) (xy 134.948123 -283.751528) (xy 134.990139 -283.782054) (xy 135.026862 -283.818777)
			(xy 135.057388 -283.860793) (xy 135.080966 -283.907067) (xy 135.097014 -283.95646) (xy 135.105139 -284.007755)
			(xy 135.105648 -284.033722) (xy 135.105144 -284.059435) (xy 136.324595 -284.059435) (xy 136.324595 -284.007501)
			(xy 136.33272 -283.956206) (xy 136.348768 -283.906813) (xy 136.372346 -283.860539) (xy 136.402872 -283.818523)
			(xy 136.439595 -283.7818) (xy 136.481611 -283.751274) (xy 136.527885 -283.727696) (xy 136.577278 -283.711648)
			(xy 136.628573 -283.703523) (xy 136.680507 -283.703523) (xy 136.731802 -283.711648) (xy 136.781195 -283.727696)
			(xy 136.827469 -283.751274) (xy 136.869485 -283.7818) (xy 136.906208 -283.818523) (xy 136.936734 -283.860539)
			(xy 136.960312 -283.906813) (xy 136.97636 -283.956206) (xy 136.984485 -284.007501) (xy 136.984994 -284.033468)
			(xy 136.984485 -284.059435) (xy 136.97636 -284.11073) (xy 136.960312 -284.160123) (xy 136.936734 -284.206397)
			(xy 136.906208 -284.248413) (xy 136.869485 -284.285136) (xy 136.827469 -284.315662) (xy 136.781195 -284.33924)
			(xy 136.731802 -284.355288) (xy 136.680507 -284.363413) (xy 136.628573 -284.363413) (xy 136.577278 -284.355288)
			(xy 136.527885 -284.33924) (xy 136.481611 -284.315662) (xy 136.439595 -284.285136) (xy 136.402872 -284.248413)
			(xy 136.372346 -284.206397) (xy 136.348768 -284.160123) (xy 136.33272 -284.11073) (xy 136.324595 -284.059435)
			(xy 135.105144 -284.059435) (xy 135.105139 -284.059689) (xy 135.097014 -284.110984) (xy 135.080966 -284.160377)
			(xy 135.057388 -284.206651) (xy 135.026862 -284.248667) (xy 134.990139 -284.28539) (xy 134.948123 -284.315916)
			(xy 134.901849 -284.339494) (xy 134.852456 -284.355542) (xy 134.801161 -284.363667) (xy 134.749227 -284.363667)
			(xy 134.697932 -284.355542) (xy 134.648539 -284.339494) (xy 134.602265 -284.315916) (xy 134.560249 -284.28539)
			(xy 134.523526 -284.248667) (xy 134.493 -284.206651) (xy 134.469422 -284.160377) (xy 134.453374 -284.110984)
			(xy 134.445249 -284.059689) (xy 133.225536 -284.059689) (xy 133.225527 -284.060138) (xy 133.217112 -284.112296)
			(xy 133.2005 -284.162449) (xy 133.176116 -284.209318) (xy 133.16077 -284.230826) (xy 133.187377 -284.263219)
			(xy 133.235454 -284.331898) (xy 133.256782 -284.367986) (xy 133.34238 -284.516322) (xy 133.371082 -284.51683)
			(xy 133.396248 -284.517706) (xy 133.445889 -284.52614) (xy 133.493676 -284.542009) (xy 133.538502 -284.564945)
			(xy 133.579329 -284.594417) (xy 133.615211 -284.629742) (xy 133.645318 -284.670103) (xy 133.657594 -284.69209)
			(xy 134.013956 -284.69209) (xy 134.026385 -284.669786) (xy 134.057049 -284.628961) (xy 134.093627 -284.593338)
			(xy 134.13525 -284.563766) (xy 134.180926 -284.540948) (xy 134.229568 -284.525428) (xy 134.280019 -284.517574)
			(xy 134.331077 -284.517574) (xy 134.381528 -284.525428) (xy 134.43017 -284.540948) (xy 134.475846 -284.563766)
			(xy 134.517469 -284.593338) (xy 134.554047 -284.628961) (xy 134.584711 -284.669786) (xy 134.59714 -284.69209)
			(xy 134.953248 -284.69209) (xy 134.965682 -284.669759) (xy 134.996364 -284.628883) (xy 135.032971 -284.593215)
			(xy 135.074629 -284.563605) (xy 135.120348 -284.540757) (xy 135.169038 -284.525215) (xy 135.219539 -284.517351)
			(xy 135.270649 -284.517351) (xy 135.32115 -284.525215) (xy 135.36984 -284.540757) (xy 135.415559 -284.563605)
			(xy 135.457217 -284.593215) (xy 135.493824 -284.628883) (xy 135.524506 -284.669759) (xy 135.53694 -284.69209)
			(xy 135.893048 -284.69209) (xy 135.905482 -284.669759) (xy 135.936164 -284.628883) (xy 135.972771 -284.593215)
			(xy 136.014429 -284.563605) (xy 136.060148 -284.540757) (xy 136.108838 -284.525215) (xy 136.159339 -284.517351)
			(xy 136.210449 -284.517351) (xy 136.26095 -284.525215) (xy 136.30964 -284.540757) (xy 136.355359 -284.563605)
			(xy 136.397017 -284.593215) (xy 136.433624 -284.628883) (xy 136.464306 -284.669759) (xy 136.47674 -284.69209)
			(xy 136.832848 -284.69209) (xy 136.845282 -284.669759) (xy 136.875964 -284.628883) (xy 136.912571 -284.593215)
			(xy 136.954229 -284.563605) (xy 136.999948 -284.540757) (xy 137.048638 -284.525215) (xy 137.099139 -284.517351)
			(xy 137.150249 -284.517351) (xy 137.20075 -284.525215) (xy 137.24944 -284.540757) (xy 137.295159 -284.563605)
			(xy 137.336817 -284.593215) (xy 137.373424 -284.628883) (xy 137.404106 -284.669759) (xy 137.41654 -284.69209)
			(xy 137.772648 -284.69209) (xy 137.785997 -284.668135) (xy 137.819376 -284.624627) (xy 137.859473 -284.58722)
			(xy 137.90519 -284.556938) (xy 137.955275 -284.53461) (xy 137.98169 -284.527244) (xy 137.995152 -284.523942)
			(xy 138.164062 -284.355032) (xy 138.164062 -283.65196) (xy 138.163628 -283.638689) (xy 138.156769 -283.613047)
			(xy 138.143527 -283.590044) (xy 138.124798 -283.571236) (xy 138.101851 -283.557896) (xy 138.076239 -283.55093)
			(xy 138.06297 -283.55036) (xy 138.037091 -283.549722) (xy 137.986004 -283.541384) (xy 137.936842 -283.525182)
			(xy 137.890806 -283.501513) (xy 137.849025 -283.470956) (xy 137.812519 -283.434258) (xy 137.782181 -283.392317)
			(xy 137.758753 -283.346159) (xy 137.742809 -283.296912) (xy 137.734738 -283.245782) (xy 137.734738 -283.194018)
			(xy 137.742809 -283.142888) (xy 137.758753 -283.093641) (xy 137.782181 -283.047483) (xy 137.812519 -283.005542)
			(xy 137.849025 -282.968844) (xy 137.890806 -282.938287) (xy 137.936841 -282.914618) (xy 137.986004 -282.898416)
			(xy 138.037091 -282.890078) (xy 138.06297 -282.889452) (xy 138.076245 -282.888961) (xy 138.101868 -282.881987)
			(xy 138.124822 -282.868635) (xy 138.143552 -282.84981) (xy 138.156786 -282.826788) (xy 138.163629 -282.80113)
			(xy 138.164062 -282.787852) (xy 138.164062 -282.024074) (xy 138.163629 -282.010802) (xy 138.156773 -281.985157)
			(xy 138.143532 -281.96215) (xy 138.124803 -281.943339) (xy 138.101854 -281.929998) (xy 138.07624 -281.92303)
			(xy 138.06297 -281.922474) (xy 138.037081 -281.921851) (xy 137.985969 -281.913537) (xy 137.93678 -281.897354)
			(xy 137.890716 -281.873696) (xy 137.848907 -281.843143) (xy 137.812374 -281.806443) (xy 137.782013 -281.764495)
			(xy 137.758566 -281.718324) (xy 137.742607 -281.669061) (xy 137.734527 -281.617912) (xy 137.73404 -281.59202)
			(xy 137.734587 -281.564487) (xy 137.743709 -281.51018) (xy 137.761704 -281.458137) (xy 137.788074 -281.409794)
			(xy 137.804652 -281.387804) (xy 137.813058 -281.376334) (xy 137.823766 -281.350004) (xy 137.826796 -281.321741)
			(xy 137.821913 -281.293739) (xy 137.809496 -281.26817) (xy 137.790508 -281.247017) (xy 137.766422 -281.231923)
			(xy 137.739108 -281.224057) (xy 137.724896 -281.223466) (xy 137.464292 -281.223466) (xy 137.450055 -281.223929)
			(xy 137.422682 -281.231771) (xy 137.398541 -281.246869) (xy 137.379512 -281.26805) (xy 137.367074 -281.293664)
			(xy 137.362197 -281.321716) (xy 137.36526 -281.350025) (xy 137.376024 -281.376385) (xy 137.384536 -281.387804)
			(xy 137.401106 -281.409798) (xy 137.427469 -281.458143) (xy 137.445463 -281.510185) (xy 137.454593 -281.564488)
			(xy 137.455148 -281.59202) (xy 137.454639 -281.617987) (xy 137.446514 -281.669282) (xy 137.430466 -281.718675)
			(xy 137.406888 -281.764949) (xy 137.376362 -281.806965) (xy 137.339639 -281.843688) (xy 137.297623 -281.874214)
			(xy 137.251349 -281.897792) (xy 137.201956 -281.91384) (xy 137.150661 -281.921965) (xy 137.098727 -281.921965)
			(xy 137.047432 -281.91384) (xy 136.998039 -281.897792) (xy 136.951765 -281.874214) (xy 136.909749 -281.843688)
			(xy 136.873026 -281.806965) (xy 136.8425 -281.764949) (xy 136.818922 -281.718675) (xy 136.802874 -281.669282)
			(xy 136.794749 -281.617987) (xy 136.79424 -281.59202) (xy 136.794787 -281.564487) (xy 136.803909 -281.51018)
			(xy 136.821904 -281.458137) (xy 136.848274 -281.409794) (xy 136.864852 -281.387804) (xy 136.873258 -281.376334)
			(xy 136.883966 -281.350004) (xy 136.886996 -281.321741) (xy 136.882113 -281.293739) (xy 136.869696 -281.26817)
			(xy 136.850708 -281.247017) (xy 136.826622 -281.231923) (xy 136.799308 -281.224057) (xy 136.785096 -281.223466)
			(xy 136.524492 -281.223466) (xy 136.510255 -281.223929) (xy 136.482882 -281.231771) (xy 136.458741 -281.246869)
			(xy 136.439712 -281.26805) (xy 136.427274 -281.293664) (xy 136.422397 -281.321716) (xy 136.42546 -281.350025)
			(xy 136.436224 -281.376385) (xy 136.444736 -281.387804) (xy 136.461306 -281.409798) (xy 136.487669 -281.458143)
			(xy 136.505663 -281.510185) (xy 136.514793 -281.564488) (xy 136.515348 -281.59202) (xy 136.514839 -281.617987)
			(xy 136.506714 -281.669282) (xy 136.490666 -281.718675) (xy 136.467088 -281.764949) (xy 136.436562 -281.806965)
			(xy 136.399839 -281.843688) (xy 136.357823 -281.874214) (xy 136.311549 -281.897792) (xy 136.262156 -281.91384)
			(xy 136.210861 -281.921965) (xy 136.158927 -281.921965) (xy 136.107632 -281.91384) (xy 136.058239 -281.897792)
			(xy 136.011965 -281.874214) (xy 135.969949 -281.843688) (xy 135.933226 -281.806965) (xy 135.9027 -281.764949)
			(xy 135.879122 -281.718675) (xy 135.863074 -281.669282) (xy 135.854949 -281.617987) (xy 135.85444 -281.59202)
			(xy 135.854987 -281.564487) (xy 135.864109 -281.51018) (xy 135.882104 -281.458137) (xy 135.908474 -281.409794)
			(xy 135.925052 -281.387804) (xy 135.933458 -281.376334) (xy 135.944166 -281.350004) (xy 135.947196 -281.321741)
			(xy 135.942313 -281.293739) (xy 135.929896 -281.26817) (xy 135.910908 -281.247017) (xy 135.886822 -281.231923)
			(xy 135.859508 -281.224057) (xy 135.845296 -281.223466) (xy 135.584692 -281.223466) (xy 135.570455 -281.223929)
			(xy 135.543082 -281.231771) (xy 135.518941 -281.246869) (xy 135.499912 -281.26805) (xy 135.487474 -281.293664)
			(xy 135.482597 -281.321716) (xy 135.48566 -281.350025) (xy 135.496424 -281.376385) (xy 135.504936 -281.387804)
			(xy 135.521506 -281.409798) (xy 135.547869 -281.458143) (xy 135.565863 -281.510185) (xy 135.574993 -281.564488)
			(xy 135.575548 -281.59202) (xy 135.575039 -281.617987) (xy 135.566914 -281.669282) (xy 135.550866 -281.718675)
			(xy 135.527288 -281.764949) (xy 135.496762 -281.806965) (xy 135.460039 -281.843688) (xy 135.418023 -281.874214)
			(xy 135.371749 -281.897792) (xy 135.322356 -281.91384) (xy 135.271061 -281.921965) (xy 135.219127 -281.921965)
			(xy 135.167832 -281.91384) (xy 135.118439 -281.897792) (xy 135.072165 -281.874214) (xy 135.030149 -281.843688)
			(xy 134.993426 -281.806965) (xy 134.9629 -281.764949) (xy 134.939322 -281.718675) (xy 134.923274 -281.669282)
			(xy 134.915149 -281.617987) (xy 134.91464 -281.59202) (xy 134.915187 -281.564487) (xy 134.924309 -281.51018)
			(xy 134.942304 -281.458137) (xy 134.968674 -281.409794) (xy 134.985252 -281.387804) (xy 134.993658 -281.376334)
			(xy 135.004366 -281.350004) (xy 135.007396 -281.321741) (xy 135.002513 -281.293739) (xy 134.990096 -281.26817)
			(xy 134.971108 -281.247017) (xy 134.947022 -281.231923) (xy 134.919708 -281.224057) (xy 134.905496 -281.223466)
			(xy 134.645146 -281.223466) (xy 134.630914 -281.223935) (xy 134.603553 -281.231784) (xy 134.579424 -281.246884)
			(xy 134.560404 -281.268061) (xy 134.547973 -281.293668) (xy 134.543097 -281.321711) (xy 134.546156 -281.350011)
			(xy 134.556912 -281.376365) (xy 134.56539 -281.387804) (xy 134.581958 -281.4098) (xy 134.608316 -281.458145)
			(xy 134.626307 -281.510186) (xy 134.635435 -281.564488) (xy 134.636002 -281.59202) (xy 134.635493 -281.617987)
			(xy 134.627368 -281.669282) (xy 134.61132 -281.718675) (xy 134.587742 -281.764949) (xy 134.557216 -281.806965)
			(xy 134.520493 -281.843688) (xy 134.478477 -281.874214) (xy 134.432203 -281.897792) (xy 134.38281 -281.91384)
			(xy 134.331515 -281.921965) (xy 134.279581 -281.921965) (xy 134.228286 -281.91384) (xy 134.178893 -281.897792)
			(xy 134.132619 -281.874214) (xy 134.090603 -281.843688) (xy 134.05388 -281.806965) (xy 134.023354 -281.764949)
			(xy 133.999776 -281.718675) (xy 133.983728 -281.669282) (xy 133.975603 -281.617987) (xy 133.975094 -281.59202)
			(xy 133.975642 -281.564487) (xy 133.984765 -281.510182) (xy 134.002762 -281.458139) (xy 134.029136 -281.4098)
			(xy 134.045706 -281.387804) (xy 134.054109 -281.376331) (xy 134.064811 -281.349997) (xy 134.067838 -281.321733)
			(xy 134.062955 -281.29373) (xy 134.05054 -281.268159) (xy 134.031556 -281.247002) (xy 134.007474 -281.231899)
			(xy 133.980162 -281.224022) (xy 133.96595 -281.223466) (xy 133.705346 -281.223466) (xy 133.691114 -281.223935)
			(xy 133.663753 -281.231784) (xy 133.639624 -281.246884) (xy 133.620604 -281.268061) (xy 133.608173 -281.293668)
			(xy 133.603297 -281.321711) (xy 133.606356 -281.350011) (xy 133.617112 -281.376365) (xy 133.62559 -281.387804)
			(xy 133.642158 -281.4098) (xy 133.668516 -281.458145) (xy 133.686507 -281.510186) (xy 133.695635 -281.564488)
			(xy 133.696202 -281.59202) (xy 133.695693 -281.617987) (xy 133.687568 -281.669282) (xy 133.67152 -281.718675)
			(xy 133.647942 -281.764949) (xy 133.617416 -281.806965) (xy 133.580693 -281.843688) (xy 133.538677 -281.874214)
			(xy 133.492403 -281.897792) (xy 133.44301 -281.91384) (xy 133.391715 -281.921965) (xy 133.339781 -281.921965)
			(xy 133.288486 -281.91384) (xy 133.239093 -281.897792) (xy 133.192819 -281.874214) (xy 133.150803 -281.843688)
			(xy 133.11408 -281.806965) (xy 133.083554 -281.764949) (xy 133.059976 -281.718675) (xy 133.043928 -281.669282)
			(xy 133.035803 -281.617987) (xy 133.035294 -281.59202) (xy 133.035759 -281.567019) (xy 133.043301 -281.517588)
			(xy 133.058201 -281.469857) (xy 133.080118 -281.424914) (xy 133.108554 -281.383784) (xy 133.14286 -281.347406)
			(xy 133.182252 -281.316608) (xy 133.225833 -281.292094) (xy 133.272609 -281.274422) (xy 133.321513 -281.263996)
			(xy 133.346444 -281.262074) (xy 133.36101 -281.260743) (xy 133.38852 -281.250841) (xy 133.412102 -281.233555)
			(xy 133.429826 -281.210302) (xy 133.440242 -281.182982) (xy 133.442498 -281.153831) (xy 133.436409 -281.125233)
			(xy 133.422474 -281.09953) (xy 133.412484 -281.088846) (xy 133.302502 -280.978864) (xy 133.292137 -280.969144)
			(xy 133.267305 -280.955351) (xy 133.239633 -280.948945) (xy 133.211267 -280.950422) (xy 133.184409 -280.959668)
			(xy 133.161145 -280.975965) (xy 133.15188 -280.986738) (xy 133.1361 -281.005429) (xy 133.099972 -281.038405)
			(xy 133.059381 -281.065699) (xy 133.015211 -281.086716) (xy 132.968428 -281.100997) (xy 132.920051 -281.108231)
			(xy 132.895594 -281.108658) (xy 132.869627 -281.108148) (xy 132.818332 -281.100023) (xy 132.76894 -281.083974)
			(xy 132.722667 -281.060396) (xy 132.680652 -281.02987) (xy 132.643929 -280.993147) (xy 132.613403 -280.951131)
			(xy 132.589825 -280.904858) (xy 132.573776 -280.855466) (xy 132.565652 -280.804171) (xy 132.56514 -280.778204)
			(xy 132.565575 -280.753743) (xy 132.572777 -280.705355) (xy 132.587037 -280.658558) (xy 132.608045 -280.614378)
			(xy 132.635341 -280.573779) (xy 132.668327 -280.537651) (xy 132.68706 -280.521918) (xy 132.697769 -280.512598)
			(xy 132.714005 -280.489324) (xy 132.723222 -280.462486) (xy 132.724711 -280.434148) (xy 132.718358 -280.406491)
			(xy 132.704651 -280.381643) (xy 132.694934 -280.371296) (xy 132.581142 -280.257504) (xy 132.550154 -280.270204)
			(xy 132.520295 -280.281543) (xy 132.457624 -280.293827) (xy 132.425694 -280.294588) (xy 132.399726 -280.294078)
			(xy 132.34843 -280.285953) (xy 132.299036 -280.269905) (xy 132.25276 -280.246327) (xy 132.210742 -280.215801)
			(xy 132.174017 -280.179079) (xy 132.143487 -280.137064) (xy 132.119906 -280.09079) (xy 132.103853 -280.041397)
			(xy 132.095724 -279.990102) (xy 132.09524 -279.964134) (xy 132.095979 -279.9322) (xy 132.108258 -279.869525)
			(xy 132.119624 -279.839674) (xy 132.132324 -279.808686) (xy 131.728972 -279.405334) (xy 131.728972 -279.39111)
			(xy 131.715256 -279.376632) (xy 131.698506 -279.358145) (xy 131.670196 -279.317071) (xy 131.648379 -279.272209)
			(xy 131.633553 -279.224579) (xy 131.626053 -279.175261) (xy 131.625594 -279.150318) (xy 131.626121 -279.123433)
			(xy 131.63483 -279.070374) (xy 131.65202 -279.019426) (xy 131.677238 -278.971937) (xy 131.709817 -278.929161)
			(xy 131.728972 -278.910288) (xy 131.728972 -278.910034) (xy 131.73456 -278.904954) (xy 131.737862 -278.901652)
			(xy 131.754823 -278.887247) (xy 131.791905 -278.862647) (xy 131.811776 -278.85263) (xy 131.816094 -278.850598)
			(xy 131.823318 -278.845866) (xy 131.834284 -278.832541) (xy 131.840121 -278.8163) (xy 131.840478 -278.807672)
			(xy 131.840478 -278.684482) (xy 131.840054 -278.675456) (xy 131.833605 -278.65859) (xy 131.821617 -278.645088)
			(xy 131.813808 -278.64054) (xy 131.741672 -278.60371) (xy 131.681474 -278.60371) (xy 131.674362 -278.608282)
			(xy 131.653525 -278.622193) (xy 131.608531 -278.644229) (xy 131.560722 -278.659205) (xy 131.511198 -278.666777)
			(xy 131.486148 -278.66721) (xy 131.460156 -278.66673) (xy 131.408811 -278.658605) (xy 131.35937 -278.642547)
			(xy 131.31305 -278.618952) (xy 131.270992 -278.5884) (xy 131.234231 -278.551645) (xy 131.203673 -278.509591)
			(xy 131.180071 -278.463274) (xy 131.164006 -278.413835) (xy 131.155873 -278.362492) (xy 131.155873 -278.310508)
			(xy 131.164006 -278.259165) (xy 131.180071 -278.209726) (xy 131.203673 -278.163409) (xy 131.234231 -278.121355)
			(xy 131.270992 -278.0846) (xy 131.31305 -278.054048) (xy 131.35937 -278.030453) (xy 131.408811 -278.014395)
			(xy 131.460156 -278.00627) (xy 131.486148 -278.005794) (xy 131.512206 -278.00628) (xy 131.563678 -278.014451)
			(xy 131.613229 -278.030599) (xy 131.659632 -278.054323) (xy 131.680966 -278.069294) (xy 131.68122 -278.069294)
			(xy 131.688885 -278.074368) (xy 131.706614 -278.079171) (xy 131.724891 -278.077349) (xy 131.73329 -278.073612)
			(xy 131.813046 -278.032972) (xy 131.821069 -278.028468) (xy 131.833425 -278.014855) (xy 131.840068 -277.997713)
			(xy 131.840478 -277.988522) (xy 131.840478 -277.865332) (xy 131.840122 -277.856703) (xy 131.834295 -277.840459)
			(xy 131.823316 -277.827143) (xy 131.816094 -277.822406) (xy 131.811776 -277.820374) (xy 131.788153 -277.80836)
			(xy 131.744739 -277.777967) (xy 131.706721 -277.741046) (xy 131.675072 -277.69854) (xy 131.650598 -277.651534)
			(xy 131.633926 -277.60123) (xy 131.625481 -277.548912) (xy 131.625478 -277.495916) (xy 131.633919 -277.443598)
			(xy 131.650587 -277.393292) (xy 131.675057 -277.346284) (xy 131.706703 -277.303775) (xy 131.744717 -277.266851)
			(xy 131.788129 -277.236454) (xy 131.811776 -277.22449) (xy 131.816094 -277.222458) (xy 131.823325 -277.217729)
			(xy 131.834307 -277.204406) (xy 131.840163 -277.188164) (xy 131.840478 -277.179532) (xy 131.840478 -277.056596)
			(xy 131.840056 -277.047568) (xy 131.83361 -277.030699) (xy 131.821623 -277.017193) (xy 131.813808 -277.012654)
			(xy 131.741672 -276.975824) (xy 131.681474 -276.975824) (xy 131.674362 -276.980396) (xy 131.653525 -276.994307)
			(xy 131.608531 -277.016342) (xy 131.560722 -277.031317) (xy 131.511198 -277.038888) (xy 131.486148 -277.039324)
			(xy 131.460155 -277.038844) (xy 131.408808 -277.030719) (xy 131.359365 -277.01466) (xy 131.313043 -276.991064)
			(xy 131.270983 -276.960511) (xy 131.23422 -276.923754) (xy 131.203662 -276.881698) (xy 131.180058 -276.83538)
			(xy 131.163992 -276.785939) (xy 131.155859 -276.734593) (xy 131.155859 -276.682607) (xy 131.163992 -276.631261)
			(xy 131.180058 -276.58182) (xy 131.203662 -276.535502) (xy 131.23422 -276.493446) (xy 131.270983 -276.456689)
			(xy 131.313043 -276.426136) (xy 131.359365 -276.40254) (xy 131.408808 -276.386481) (xy 131.460155 -276.378356)
			(xy 131.486148 -276.377908) (xy 131.512206 -276.378394) (xy 131.563678 -276.386565) (xy 131.613229 -276.402713)
			(xy 131.659631 -276.426439) (xy 131.680966 -276.441408) (xy 131.68122 -276.441408) (xy 131.688885 -276.446481)
			(xy 131.706614 -276.451283) (xy 131.72489 -276.449461) (xy 131.73329 -276.445726) (xy 131.813046 -276.405086)
			(xy 131.821071 -276.400583) (xy 131.83343 -276.38697) (xy 131.840078 -276.369828) (xy 131.840478 -276.360636)
			(xy 131.840478 -276.2377) (xy 131.840117 -276.229074) (xy 131.834283 -276.212838) (xy 131.823302 -276.199531)
			(xy 131.816094 -276.194774) (xy 131.811776 -276.192742) (xy 131.788155 -276.180728) (xy 131.744746 -276.150336)
			(xy 131.706734 -276.113417) (xy 131.675089 -276.070913) (xy 131.650619 -276.02391) (xy 131.63395 -275.973609)
			(xy 131.625508 -275.921295) (xy 131.625508 -275.868305) (xy 131.63395 -275.815991) (xy 131.650619 -275.76569)
			(xy 131.675089 -275.718687) (xy 131.706734 -275.676183) (xy 131.744746 -275.639264) (xy 131.788155 -275.608872)
			(xy 131.811776 -275.596858) (xy 131.816094 -275.594826) (xy 131.823321 -275.590095) (xy 131.834295 -275.576771)
			(xy 131.84014 -275.56053) (xy 131.840478 -275.5519) (xy 131.840478 -275.42871) (xy 131.840058 -275.419681)
			(xy 131.833616 -275.402808) (xy 131.821629 -275.389298) (xy 131.813808 -275.384768) (xy 131.741672 -275.347938)
			(xy 131.681474 -275.347938) (xy 131.674362 -275.35251) (xy 131.653524 -275.36642) (xy 131.608531 -275.388454)
			(xy 131.560722 -275.403429) (xy 131.511198 -275.411) (xy 131.486148 -275.411438) (xy 131.460154 -275.410958)
			(xy 131.408805 -275.402832) (xy 131.359359 -275.386773) (xy 131.313035 -275.363176) (xy 131.270974 -275.332621)
			(xy 131.23421 -275.295863) (xy 131.20365 -275.253806) (xy 131.180045 -275.207485) (xy 131.163979 -275.158042)
			(xy 131.155845 -275.106694) (xy 131.155845 -275.054706) (xy 131.163979 -275.003358) (xy 131.180045 -274.953915)
			(xy 131.20365 -274.907594) (xy 131.23421 -274.865537) (xy 131.270974 -274.828779) (xy 131.313035 -274.798224)
			(xy 131.359359 -274.774627) (xy 131.408805 -274.758568) (xy 131.460154 -274.750442) (xy 131.486148 -274.750022)
			(xy 131.512206 -274.750508) (xy 131.563677 -274.758679) (xy 131.613228 -274.774828) (xy 131.65963 -274.798554)
			(xy 131.680966 -274.813522) (xy 131.68122 -274.813522) (xy 131.688886 -274.818594) (xy 131.706614 -274.823395)
			(xy 131.72489 -274.821573) (xy 131.73329 -274.81784) (xy 131.813046 -274.7772) (xy 131.821073 -274.772697)
			(xy 131.833436 -274.759085) (xy 131.840088 -274.741943) (xy 131.840478 -274.73275) (xy 131.840478 -274.609814)
			(xy 131.840119 -274.601186) (xy 131.834288 -274.584947) (xy 131.823308 -274.571636) (xy 131.816094 -274.566888)
			(xy 131.811776 -274.564856) (xy 131.788154 -274.552842) (xy 131.744743 -274.52245) (xy 131.706728 -274.485529)
			(xy 131.675081 -274.443024) (xy 131.65061 -274.39602) (xy 131.63394 -274.345718) (xy 131.625496 -274.293402)
			(xy 131.625495 -274.24041) (xy 131.633937 -274.188094) (xy 131.650605 -274.137791) (xy 131.675075 -274.090786)
			(xy 131.70672 -274.04828) (xy 131.744734 -274.011358) (xy 131.788144 -273.980964) (xy 131.811776 -273.968972)
			(xy 131.816094 -273.96694) (xy 131.823323 -273.96221) (xy 131.8343 -273.948886) (xy 131.84015 -273.932645)
			(xy 131.840478 -273.924014) (xy 131.840478 -273.801078) (xy 131.840053 -273.792052) (xy 131.833603 -273.775188)
			(xy 131.821615 -273.761687) (xy 131.813808 -273.757136) (xy 131.741672 -273.720306) (xy 131.681474 -273.720306)
			(xy 131.674362 -273.724878) (xy 131.653524 -273.738786) (xy 131.608529 -273.760816) (xy 131.56072 -273.775787)
			(xy 131.511197 -273.783356) (xy 131.486148 -273.783806) (xy 131.460156 -273.783326) (xy 131.408812 -273.775201)
			(xy 131.359372 -273.759143) (xy 131.313052 -273.735548) (xy 131.270994 -273.704997) (xy 131.234234 -273.668242)
			(xy 131.203677 -273.626189) (xy 131.180075 -273.579873) (xy 131.16401 -273.530434) (xy 131.155877 -273.479092)
			(xy 131.155877 -273.427108) (xy 131.16401 -273.375766) (xy 131.180075 -273.326327) (xy 131.203677 -273.280011)
			(xy 131.234234 -273.237958) (xy 131.270994 -273.201203) (xy 131.313052 -273.170652) (xy 131.359372 -273.147057)
			(xy 131.408812 -273.130999) (xy 131.460156 -273.122874) (xy 131.486148 -273.12239) (xy 131.512206 -273.122876)
			(xy 131.563678 -273.131047) (xy 131.613229 -273.147194) (xy 131.659633 -273.170919) (xy 131.680966 -273.18589)
			(xy 131.68122 -273.18589) (xy 131.688885 -273.190965) (xy 131.706614 -273.195768) (xy 131.724891 -273.193945)
			(xy 131.73329 -273.190208) (xy 131.813046 -273.149568) (xy 131.821069 -273.145063) (xy 131.833423 -273.13145)
			(xy 131.840065 -273.114309) (xy 131.840478 -273.105118) (xy 131.840478 -272.981928) (xy 131.840121 -272.973299)
			(xy 131.834293 -272.957056) (xy 131.823315 -272.943741) (xy 131.816094 -272.939002) (xy 131.811776 -272.93697)
			(xy 131.788184 -272.924961) (xy 131.744829 -272.894587) (xy 131.706866 -272.857695) (xy 131.675263 -272.815229)
			(xy 131.650827 -272.768271) (xy 131.634181 -272.71802) (xy 131.625752 -272.66576) (xy 131.625753 -272.612824)
			(xy 131.634185 -272.560565) (xy 131.650833 -272.510315) (xy 131.675271 -272.463358) (xy 131.706876 -272.420893)
			(xy 131.744842 -272.384003) (xy 131.788197 -272.353632) (xy 131.811776 -272.341594) (xy 131.816094 -272.339562)
			(xy 131.823314 -272.334828) (xy 131.834271 -272.321501) (xy 131.840096 -272.305262) (xy 131.840478 -272.296636)
			(xy 131.840478 -272.173192) (xy 131.840056 -272.164165) (xy 131.833609 -272.147297) (xy 131.821621 -272.133792)
			(xy 131.813808 -272.12925) (xy 131.741672 -272.09242) (xy 131.681474 -272.09242) (xy 131.674362 -272.096992)
			(xy 131.653525 -272.110903) (xy 131.608531 -272.132938) (xy 131.560722 -272.147914) (xy 131.511198 -272.155485)
			(xy 131.486148 -272.15592) (xy 131.460155 -272.15544) (xy 131.408809 -272.147315) (xy 131.359366 -272.131256)
			(xy 131.313045 -272.10766) (xy 131.270985 -272.077108) (xy 131.234223 -272.040351) (xy 131.203665 -271.998296)
			(xy 131.180062 -271.951978) (xy 131.163996 -271.902538) (xy 131.155863 -271.851193) (xy 131.155863 -271.799207)
			(xy 131.163996 -271.747862) (xy 131.180062 -271.698422) (xy 131.203665 -271.652104) (xy 131.234223 -271.610049)
			(xy 131.270985 -271.573292) (xy 131.313045 -271.54274) (xy 131.359366 -271.519144) (xy 131.408809 -271.503085)
			(xy 131.460155 -271.49496) (xy 131.486148 -271.494504) (xy 131.512206 -271.49499) (xy 131.563678 -271.503161)
			(xy 131.613229 -271.519309) (xy 131.659632 -271.543034) (xy 131.680966 -271.558004) (xy 131.68122 -271.558004)
			(xy 131.688885 -271.563078) (xy 131.706614 -271.56788) (xy 131.72489 -271.566058) (xy 131.73329 -271.562322)
			(xy 131.813046 -271.521682) (xy 131.821071 -271.517178) (xy 131.833429 -271.503566) (xy 131.840075 -271.486424)
			(xy 131.840478 -271.477232) (xy 131.840478 -271.354296) (xy 131.840116 -271.34567) (xy 131.834281 -271.329435)
			(xy 131.8233 -271.316129) (xy 131.816094 -271.31137) (xy 131.811776 -271.309338) (xy 131.788156 -271.297324)
			(xy 131.744747 -271.266932) (xy 131.706735 -271.230013) (xy 131.675091 -271.187509) (xy 131.650622 -271.140507)
			(xy 131.633954 -271.090207) (xy 131.625512 -271.037893) (xy 131.625512 -270.984903) (xy 131.633954 -270.93259)
			(xy 131.650623 -270.88229) (xy 131.675093 -270.835288) (xy 131.706738 -270.792785) (xy 131.74475 -270.755866)
			(xy 131.788159 -270.725474) (xy 131.811776 -270.713454) (xy 131.816094 -270.711422) (xy 131.823321 -270.706691)
			(xy 131.834293 -270.693367) (xy 131.840138 -270.677126) (xy 131.840478 -270.668496) (xy 131.840478 -270.54556)
			(xy 131.84005 -270.536536) (xy 131.833597 -270.519676) (xy 131.821607 -270.50618) (xy 131.813808 -270.501618)
			(xy 131.741672 -270.464788) (xy 131.681474 -270.464788) (xy 131.674362 -270.46936) (xy 131.653524 -270.483269)
			(xy 131.608529 -270.5053) (xy 131.560721 -270.520272) (xy 131.511197 -270.527841) (xy 131.486148 -270.528288)
			(xy 131.460158 -270.527809) (xy 131.408817 -270.519684) (xy 131.359379 -270.503627) (xy 131.313062 -270.480033)
			(xy 131.271006 -270.449483) (xy 131.234248 -270.412731) (xy 131.203692 -270.370679) (xy 131.180092 -270.324366)
			(xy 131.164027 -270.27493) (xy 131.155895 -270.22359) (xy 131.155895 -270.17161) (xy 131.164027 -270.12027)
			(xy 131.180092 -270.070834) (xy 131.203692 -270.024521) (xy 131.234248 -269.982469) (xy 131.271006 -269.945717)
			(xy 131.313062 -269.915167) (xy 131.359379 -269.891573) (xy 131.408817 -269.875516) (xy 131.460158 -269.867391)
			(xy 131.486148 -269.866872) (xy 131.512206 -269.867358) (xy 131.563678 -269.875528) (xy 131.61323 -269.891675)
			(xy 131.659634 -269.915398) (xy 131.680966 -269.930372) (xy 131.68122 -269.930372) (xy 131.688887 -269.93544)
			(xy 131.706614 -269.940236) (xy 131.724888 -269.938416) (xy 131.73329 -269.93469) (xy 131.813046 -269.89405)
			(xy 131.821067 -269.889545) (xy 131.833416 -269.875931) (xy 131.840052 -269.85879) (xy 131.840478 -269.8496)
			(xy 131.840478 -269.72641) (xy 131.840118 -269.717783) (xy 131.834286 -269.701544) (xy 131.823306 -269.688234)
			(xy 131.816094 -269.683484) (xy 131.811776 -269.681452) (xy 131.788154 -269.669438) (xy 131.744744 -269.639046)
			(xy 131.70673 -269.602126) (xy 131.675083 -269.559621) (xy 131.650613 -269.512617) (xy 131.633943 -269.462316)
			(xy 131.6255 -269.41) (xy 131.625499 -269.357008) (xy 131.633941 -269.304693) (xy 131.650609 -269.254391)
			(xy 131.675079 -269.207386) (xy 131.706724 -269.164881) (xy 131.744737 -269.12796) (xy 131.788147 -269.097566)
			(xy 131.811776 -269.085568) (xy 131.816094 -269.083536) (xy 131.823322 -269.078805) (xy 131.834298 -269.065482)
			(xy 131.840147 -269.049241) (xy 131.840478 -269.04061) (xy 131.840478 -268.917674) (xy 131.840053 -268.908648)
			(xy 131.833602 -268.891785) (xy 131.821613 -268.878285) (xy 131.813808 -268.873732) (xy 131.741672 -268.836902)
			(xy 131.681474 -268.836902) (xy 131.674362 -268.841474) (xy 131.653524 -268.855382) (xy 131.608529 -268.877412)
			(xy 131.56072 -268.892384) (xy 131.511197 -268.899953) (xy 131.486148 -268.900402) (xy 131.460157 -268.899922)
			(xy 131.408813 -268.891797) (xy 131.359373 -268.87574) (xy 131.313054 -268.852145) (xy 131.270997 -268.821594)
			(xy 131.234237 -268.78484) (xy 131.20368 -268.742787) (xy 131.180079 -268.696471) (xy 131.164014 -268.647033)
			(xy 131.155881 -268.595691) (xy 131.155881 -268.543709) (xy 131.164014 -268.492367) (xy 131.180079 -268.442929)
			(xy 131.20368 -268.396613) (xy 131.234237 -268.35456) (xy 131.270997 -268.317806) (xy 131.313054 -268.287255)
			(xy 131.359373 -268.26366) (xy 131.408813 -268.247603) (xy 131.460157 -268.239478) (xy 131.486148 -268.238986)
			(xy 131.512206 -268.239472) (xy 131.563678 -268.247642) (xy 131.61323 -268.26379) (xy 131.659633 -268.287514)
			(xy 131.680966 -268.302486) (xy 131.68122 -268.302486) (xy 131.688885 -268.307561) (xy 131.706614 -268.312365)
			(xy 131.724891 -268.310542) (xy 131.73329 -268.306804) (xy 131.813046 -268.266164) (xy 131.821068 -268.261659)
			(xy 131.833422 -268.248046) (xy 131.840062 -268.230904) (xy 131.840478 -268.221714) (xy 131.840478 -268.098524)
			(xy 131.840121 -268.089896) (xy 131.834292 -268.073653) (xy 131.823313 -268.06034) (xy 131.816094 -268.055598)
			(xy 131.811776 -268.053566) (xy 131.788184 -268.041557) (xy 131.74483 -268.011183) (xy 131.706868 -267.974292)
			(xy 131.675265 -267.931825) (xy 131.650829 -267.884868) (xy 131.634184 -267.834618) (xy 131.625755 -267.782358)
			(xy 131.625757 -267.729423) (xy 131.634189 -267.677164) (xy 131.650837 -267.626915) (xy 131.675275 -267.579959)
			(xy 131.70688 -267.537494) (xy 131.744845 -267.500605) (xy 131.788201 -267.470234) (xy 131.811776 -267.45819)
			(xy 131.816094 -267.456158) (xy 131.823325 -267.451429) (xy 131.834307 -267.438106) (xy 131.840163 -267.421864)
			(xy 131.840478 -267.413232) (xy 131.840478 -267.289788) (xy 131.840055 -267.280761) (xy 131.833607 -267.263894)
			(xy 131.821619 -267.25039) (xy 131.813808 -267.245846) (xy 131.741672 -267.209016) (xy 131.681474 -267.209016)
			(xy 131.674362 -267.213588) (xy 131.653525 -267.227499) (xy 131.608531 -267.249535) (xy 131.560722 -267.26451)
			(xy 131.511198 -267.272081) (xy 131.486148 -267.272516) (xy 131.460156 -267.272036) (xy 131.40881 -267.263911)
			(xy 131.359368 -267.247853) (xy 131.313047 -267.224257) (xy 131.270988 -267.193705) (xy 131.234227 -267.156949)
			(xy 131.203668 -267.114894) (xy 131.180066 -267.068577) (xy 131.164 -267.019137) (xy 131.155867 -266.967792)
			(xy 131.155867 -266.915808) (xy 131.164 -266.864463) (xy 131.180066 -266.815023) (xy 131.203668 -266.768706)
			(xy 131.234227 -266.726651) (xy 131.270988 -266.689895) (xy 131.313047 -266.659343) (xy 131.359368 -266.635747)
			(xy 131.40881 -266.619689) (xy 131.460156 -266.611564) (xy 131.486148 -266.6111) (xy 131.512206 -266.611586)
			(xy 131.563678 -266.619757) (xy 131.613229 -266.635905) (xy 131.659632 -266.65963) (xy 131.680966 -266.6746)
			(xy 131.68122 -266.6746) (xy 131.688885 -266.679674) (xy 131.706614 -266.684477) (xy 131.724891 -266.682654)
			(xy 131.73329 -266.678918) (xy 131.813046 -266.638278) (xy 131.82107 -266.633774) (xy 131.833427 -266.620161)
			(xy 131.840072 -266.603019) (xy 131.840478 -266.593828) (xy 131.840478 -266.471146) (xy 131.840124 -266.462516)
			(xy 131.8343 -266.446268) (xy 131.823323 -266.432948) (xy 131.816094 -266.42822) (xy 131.811776 -266.426188)
			(xy 131.788152 -266.414174) (xy 131.744735 -266.383781) (xy 131.706716 -266.346859) (xy 131.675064 -266.304352)
			(xy 131.650589 -266.257344) (xy 131.633915 -266.207038) (xy 131.625469 -266.154719) (xy 131.625465 -266.101721)
			(xy 131.633905 -266.049401) (xy 131.650573 -265.999093) (xy 131.675043 -265.952083) (xy 131.706689 -265.909571)
			(xy 131.744705 -265.872645) (xy 131.788117 -265.842246) (xy 131.811776 -265.830304) (xy 131.816094 -265.828272)
			(xy 131.823315 -265.823538) (xy 131.834274 -265.810212) (xy 131.840103 -265.793973) (xy 131.840478 -265.785346)
			(xy 131.840478 -265.662156) (xy 131.84005 -265.653132) (xy 131.833595 -265.636274) (xy 131.821605 -265.622779)
			(xy 131.813808 -265.618214) (xy 131.741672 -265.581384) (xy 131.681474 -265.581384) (xy 131.674362 -265.585956)
			(xy 131.653524 -265.599865) (xy 131.60853 -265.621896) (xy 131.560721 -265.636869) (xy 131.511197 -265.644438)
			(xy 131.486148 -265.644884) (xy 131.460158 -265.644405) (xy 131.408817 -265.63628) (xy 131.35938 -265.620223)
			(xy 131.313064 -265.59663) (xy 131.271009 -265.56608) (xy 131.234251 -265.529328) (xy 131.203696 -265.487277)
			(xy 131.180095 -265.440964) (xy 131.164031 -265.391529) (xy 131.155899 -265.34019) (xy 131.155899 -265.28821)
			(xy 131.164031 -265.236871) (xy 131.180095 -265.187436) (xy 131.203696 -265.141123) (xy 131.234251 -265.099072)
			(xy 131.271009 -265.06232) (xy 131.313064 -265.03177) (xy 131.35938 -265.008177) (xy 131.408817 -264.99212)
			(xy 131.460158 -264.983995) (xy 131.486148 -264.983468) (xy 131.512206 -264.983954) (xy 131.563678 -264.992124)
			(xy 131.61323 -265.008271) (xy 131.659635 -265.031994) (xy 131.680966 -265.046968) (xy 131.68122 -265.046968)
			(xy 131.688887 -265.052036) (xy 131.706614 -265.056832) (xy 131.724888 -265.055012) (xy 131.73329 -265.051286)
			(xy 131.813046 -265.010646) (xy 131.821067 -265.006141) (xy 131.833415 -264.992526) (xy 131.840049 -264.975385)
			(xy 131.840478 -264.966196) (xy 131.840478 -264.84326) (xy 131.840126 -264.834628) (xy 131.834305 -264.818377)
			(xy 131.823329 -264.805054) (xy 131.816094 -264.800334) (xy 131.811776 -264.798302) (xy 131.788158 -264.786288)
			(xy 131.744756 -264.755897) (xy 131.706749 -264.71898) (xy 131.67511 -264.676479) (xy 131.650646 -264.62948)
			(xy 131.633981 -264.579184) (xy 131.625543 -264.526875) (xy 131.625546 -264.47389) (xy 131.63399 -264.421582)
			(xy 131.650659 -264.371288) (xy 131.675128 -264.324292) (xy 131.706772 -264.281794) (xy 131.744783 -264.244881)
			(xy 131.788188 -264.214494) (xy 131.811776 -264.202418) (xy 131.816094 -264.200386) (xy 131.823317 -264.195653)
			(xy 131.83428 -264.182328) (xy 131.840113 -264.166087) (xy 131.840478 -264.15746) (xy 131.840478 -264.034524)
			(xy 131.840061 -264.025494) (xy 131.833621 -264.008617) (xy 131.821635 -263.995103) (xy 131.813808 -263.990582)
			(xy 131.741672 -263.953752) (xy 131.681474 -263.953752) (xy 131.674362 -263.958324) (xy 131.653524 -263.972234)
			(xy 131.60853 -263.994267) (xy 131.560721 -264.009241) (xy 131.511198 -264.016811) (xy 131.486148 -264.017252)
			(xy 131.460153 -264.016772) (xy 131.408802 -264.008646) (xy 131.359354 -263.992586) (xy 131.313028 -263.968987)
			(xy 131.270964 -263.938432) (xy 131.234199 -263.901672) (xy 131.203638 -263.859613) (xy 131.180033 -263.81329)
			(xy 131.163965 -263.763845) (xy 131.155831 -263.712495) (xy 131.155831 -263.660505) (xy 131.163965 -263.609155)
			(xy 131.180033 -263.55971) (xy 131.203638 -263.513387) (xy 131.234199 -263.471328) (xy 131.270964 -263.434568)
			(xy 131.313028 -263.404013) (xy 131.359354 -263.380414) (xy 131.408802 -263.364354) (xy 131.460153 -263.356228)
			(xy 131.486148 -263.355836) (xy 131.512206 -263.356322) (xy 131.563677 -263.364494) (xy 131.613227 -263.380643)
			(xy 131.659629 -263.40437) (xy 131.680966 -263.419336) (xy 131.68122 -263.419336) (xy 131.688886 -263.424407)
			(xy 131.706614 -263.429206) (xy 131.724889 -263.427385) (xy 131.73329 -263.423654) (xy 131.813046 -263.383014)
			(xy 131.821063 -263.378507) (xy 131.833403 -263.364891) (xy 131.840027 -263.347751) (xy 131.840478 -263.338564)
			(xy 131.840478 -263.21512) (xy 131.84012 -263.206492) (xy 131.83429 -263.190251) (xy 131.823311 -263.176938)
			(xy 131.816094 -263.172194) (xy 131.811776 -263.170162) (xy 131.788184 -263.158153) (xy 131.744831 -263.127779)
			(xy 131.706869 -263.090888) (xy 131.675267 -263.048422) (xy 131.650832 -263.001465) (xy 131.634187 -262.951215)
			(xy 131.625758 -262.898956) (xy 131.62576 -262.846021) (xy 131.634193 -262.793763) (xy 131.650841 -262.743514)
			(xy 131.675279 -262.696559) (xy 131.706884 -262.654095) (xy 131.744849 -262.617207) (xy 131.788204 -262.586836)
			(xy 131.811776 -262.574786) (xy 131.816094 -262.572754) (xy 131.823324 -262.568024) (xy 131.834305 -262.554702)
			(xy 131.840159 -262.53846) (xy 131.840478 -262.529828) (xy 131.840478 -262.406638) (xy 131.840063 -262.397606)
			(xy 131.833626 -262.380726) (xy 131.821641 -262.367208) (xy 131.813808 -262.362696) (xy 131.741672 -262.325866)
			(xy 131.681474 -262.325866) (xy 131.674362 -262.330438) (xy 131.653524 -262.344348) (xy 131.60853 -262.36638)
			(xy 131.560721 -262.381353) (xy 131.511197 -262.388923) (xy 131.486148 -262.389366) (xy 131.46016 -262.388887)
			(xy 131.408822 -262.380762) (xy 131.359387 -262.364706) (xy 131.313073 -262.341114) (xy 131.27102 -262.310567)
			(xy 131.234265 -262.273816) (xy 131.203711 -262.231768) (xy 131.180112 -262.185457) (xy 131.164049 -262.136025)
			(xy 131.155917 -262.084688) (xy 131.155917 -262.032712) (xy 131.164049 -261.981375) (xy 131.180112 -261.931943)
			(xy 131.203711 -261.885632) (xy 131.234265 -261.843584) (xy 131.27102 -261.806833) (xy 131.313073 -261.776286)
			(xy 131.359387 -261.752694) (xy 131.408822 -261.736638) (xy 131.46016 -261.728513) (xy 131.486148 -261.72795)
			(xy 131.512206 -261.728436) (xy 131.563677 -261.736608) (xy 131.613227 -261.752758) (xy 131.659628 -261.776486)
			(xy 131.680966 -261.79145) (xy 131.68122 -261.79145) (xy 131.688887 -261.79652) (xy 131.706614 -261.801317)
			(xy 131.724889 -261.799497) (xy 131.73329 -261.795768) (xy 131.813046 -261.755128) (xy 131.821065 -261.750622)
			(xy 131.833408 -261.737007) (xy 131.840037 -261.719866) (xy 131.840478 -261.710678) (xy 131.840478 -261.587742)
			(xy 131.840123 -261.579112) (xy 131.834298 -261.562865) (xy 131.823321 -261.549547) (xy 131.816094 -261.544816)
			(xy 131.811776 -261.542784) (xy 131.789348 -261.531431) (xy 131.747918 -261.502968) (xy 131.711276 -261.468559)
			(xy 131.680267 -261.428997) (xy 131.655607 -261.385196) (xy 131.637865 -261.338166) (xy 131.632198 -261.313676)
			(xy 131.63169 -261.310882) (xy 131.630928 -261.307072) (xy 131.630928 -261.306564) (xy 131.617212 -261.281164)
			(xy 131.517644 -261.181596) (xy 131.510422 -261.175054) (xy 131.492453 -261.167567) (xy 131.472987 -261.167441)
			(xy 131.463796 -261.170674) (xy 131.377944 -261.205472) (xy 131.346956 -261.25043) (xy 131.346194 -261.264654)
			(xy 131.344243 -261.289584) (xy 131.333775 -261.33848) (xy 131.316064 -261.385242) (xy 131.291515 -261.428805)
			(xy 131.260687 -261.468175) (xy 131.224283 -261.502454) (xy 131.183132 -261.530862) (xy 131.138174 -261.552751)
			(xy 131.090432 -261.567621) (xy 131.040996 -261.575134) (xy 131.015994 -261.57555) (xy 130.990006 -261.57504)
			(xy 130.93867 -261.566909) (xy 130.889237 -261.550848) (xy 130.842926 -261.527253) (xy 130.800875 -261.496703)
			(xy 130.76412 -261.459953) (xy 130.733566 -261.417905) (xy 130.709966 -261.371596) (xy 130.693899 -261.322165)
			(xy 130.685763 -261.27083) (xy 130.685286 -261.244842) (xy 130.685748 -261.219844) (xy 130.693277 -261.170417)
			(xy 130.708157 -261.122686) (xy 130.730048 -261.077736) (xy 130.758452 -261.036592) (xy 130.792722 -261.000188)
			(xy 130.832078 -260.969354) (xy 130.875625 -260.944791) (xy 130.922372 -260.927059) (xy 130.971254 -260.916561)
			(xy 130.996182 -260.914642) (xy 131.010406 -260.91388) (xy 131.055364 -260.882892) (xy 131.090162 -260.79704)
			(xy 131.093335 -260.78784) (xy 131.093186 -260.768399) (xy 131.085732 -260.750443) (xy 131.07924 -260.743192)
			(xy 130.95859 -260.622542) (xy 130.950721 -260.6154) (xy 130.93086 -260.607895) (xy 130.920236 -260.608064)
			(xy 130.844798 -260.613144) (xy 130.80873 -260.632194) (xy 130.807206 -260.633972) (xy 130.791438 -260.653457)
			(xy 130.755019 -260.687896) (xy 130.713823 -260.716448) (xy 130.668792 -260.73846) (xy 130.620956 -260.753429)
			(xy 130.571409 -260.761011) (xy 130.546348 -260.76148) (xy 130.520357 -260.761) (xy 130.469014 -260.752875)
			(xy 130.419575 -260.736817) (xy 130.373257 -260.713221) (xy 130.331202 -260.682669) (xy 130.294444 -260.645914)
			(xy 130.263889 -260.60386) (xy 130.240291 -260.557543) (xy 130.22423 -260.508105) (xy 130.216101 -260.456763)
			(xy 130.21564 -260.430772) (xy 130.216099 -260.405708) (xy 130.223659 -260.356153) (xy 130.238617 -260.308308)
			(xy 130.26063 -260.263272) (xy 130.289192 -260.222077) (xy 130.323649 -260.185668) (xy 130.343148 -260.169914)
			(xy 130.344926 -260.16839) (xy 130.363976 -260.132322) (xy 130.369056 -260.056884) (xy 130.36923 -260.046256)
			(xy 130.361741 -260.026383) (xy 130.354578 -260.01853) (xy 130.265678 -259.92963) (xy 130.258693 -259.923232)
			(xy 130.241317 -259.915727) (xy 130.222399 -259.915133) (xy 130.213354 -259.917946) (xy 130.210052 -259.91947)
			(xy 130.188956 -259.928362) (xy 130.144928 -259.940904) (xy 130.099591 -259.947257) (xy 130.076702 -259.947664)
			(xy 130.076194 -259.947664) (xy 130.050206 -259.94718) (xy 129.998871 -259.939048) (xy 129.94944 -259.922985)
			(xy 129.903131 -259.899386) (xy 129.861084 -259.868833) (xy 129.824335 -259.832078) (xy 129.793788 -259.790026)
			(xy 129.770196 -259.743714) (xy 129.75414 -259.69428) (xy 129.746016 -259.642944) (xy 129.745486 -259.616956)
			(xy 129.745486 -259.616448) (xy 129.745892 -259.593558) (xy 129.752243 -259.548221) (xy 129.764788 -259.504194)
			(xy 129.77368 -259.483098) (xy 129.775204 -259.479796) (xy 129.778049 -259.470755) (xy 129.77747 -259.451826)
			(xy 129.769931 -259.434454) (xy 129.76352 -259.427472) (xy 129.386076 -259.050028) (xy 129.383536 -259.047742)
			(xy 129.361692 -259.025898) (xy 129.360168 -259.02412) (xy 129.159 -258.822952) (xy 129.152652 -258.817123)
			(xy 129.137084 -258.809756) (xy 129.119948 -258.808027) (xy 129.111502 -258.809744) (xy 129.024888 -258.835398)
			(xy 128.990344 -258.872482) (xy 128.987296 -258.884928) (xy 128.979976 -258.911255) (xy 128.957913 -258.961242)
			(xy 128.927941 -259.006927) (xy 128.890874 -259.04707) (xy 128.847719 -259.080582) (xy 128.799646 -259.106553)
			(xy 128.747961 -259.124277) (xy 128.694067 -259.133273) (xy 128.666748 -259.133848) (xy 128.640755 -259.133368)
			(xy 128.589408 -259.125243) (xy 128.539965 -259.109186) (xy 128.493642 -259.085591) (xy 128.451581 -259.055041)
			(xy 128.414817 -259.018286) (xy 128.384255 -258.976233) (xy 128.360648 -258.929917) (xy 128.344577 -258.880477)
			(xy 128.336438 -258.829133) (xy 128.33604 -258.80314) (xy 128.336598 -258.775818) (xy 128.345573 -258.721915)
			(xy 128.363286 -258.670221) (xy 128.389255 -258.622141) (xy 128.422773 -258.578983) (xy 128.462929 -258.541922)
			(xy 128.50863 -258.511965) (xy 128.558634 -258.489926) (xy 128.58496 -258.482592) (xy 128.597406 -258.479544)
			(xy 128.63449 -258.445) (xy 128.660144 -258.358386) (xy 128.661905 -258.34994) (xy 128.660213 -258.332783)
			(xy 128.652799 -258.317218) (xy 128.646936 -258.310888) (xy 128.565402 -258.229354) (xy 128.558526 -258.223045)
			(xy 128.541431 -258.215594) (xy 128.532128 -258.214876) (xy 128.495552 -258.214368) (xy 128.4605 -258.214114)
			(xy 128.451693 -258.214283) (xy 128.435052 -258.220024) (xy 128.427988 -258.22529) (xy 128.425194 -258.228084)
			(xy 128.406616 -258.245193) (xy 128.365235 -258.274143) (xy 128.319933 -258.296463) (xy 128.271763 -258.311632)
			(xy 128.221845 -258.319298) (xy 128.196594 -258.319778) (xy 128.170606 -258.319294) (xy 128.11927 -258.311162)
			(xy 128.069838 -258.295099) (xy 128.023528 -258.271501) (xy 127.98148 -258.240948) (xy 127.944729 -258.204193)
			(xy 127.914181 -258.162141) (xy 127.890587 -258.115829) (xy 127.874529 -258.066395) (xy 127.866403 -258.015058)
			(xy 127.865886 -257.98907) (xy 127.866365 -257.963819) (xy 127.874043 -257.913905) (xy 127.889216 -257.865737)
			(xy 127.911531 -257.820434) (xy 127.940471 -257.779047) (xy 127.95758 -257.76047) (xy 127.960374 -257.757676)
			(xy 127.965645 -257.75062) (xy 127.971358 -257.73397) (xy 127.97155 -257.725164) (xy 127.971296 -257.690112)
			(xy 127.970788 -257.653536) (xy 127.969982 -257.644251) (xy 127.962561 -257.627173) (xy 127.95631 -257.620262)
			(xy 127.84709 -257.511042) (xy 127.841921 -257.506214) (xy 127.829548 -257.499372) (xy 127.822706 -257.49758)
			(xy 127.800608 -257.49758) (xy 127.799084 -257.497834) (xy 127.781226 -257.501618) (xy 127.744947 -257.505688)
			(xy 127.726694 -257.505962) (xy 127.700706 -257.505478) (xy 127.649371 -257.497346) (xy 127.59994 -257.481283)
			(xy 127.553631 -257.457684) (xy 127.511585 -257.427131) (xy 127.474835 -257.390376) (xy 127.444289 -257.348324)
			(xy 127.420697 -257.302011) (xy 127.404642 -257.252578) (xy 127.396518 -257.201242) (xy 127.395986 -257.175254)
			(xy 127.396249 -257.156675) (xy 127.400445 -257.119756) (xy 127.404368 -257.101594) (xy 127.404368 -257.10134)
			(xy 127.405937 -257.093035) (xy 127.404033 -257.076252) (xy 127.396651 -257.061059) (xy 127.390906 -257.054858)
			(xy 127.030226 -256.694178) (xy 127.02351 -256.686941) (xy 127.015914 -256.668736) (xy 127.015494 -256.658872)
			(xy 127.015494 -256.606294) (xy 127.00381 -256.574544) (xy 127.00127 -256.571242) (xy 126.983695 -256.548887)
			(xy 126.955668 -256.499414) (xy 126.936494 -256.445884) (xy 126.926734 -256.389868) (xy 126.926086 -256.361438)
			(xy 126.926669 -256.333001) (xy 126.936392 -256.276964) (xy 126.955574 -256.223423) (xy 126.983649 -256.173961)
			(xy 127.00127 -256.151634) (xy 127.00381 -256.148332) (xy 127.015494 -256.116582) (xy 127.015494 -255.958848)
			(xy 127.014888 -255.947393) (xy 127.004708 -255.926866) (xy 126.995936 -255.919478) (xy 126.982728 -255.909572)
			(xy 126.929896 -255.87071) (xy 126.926504 -255.868335) (xy 126.919099 -255.864633) (xy 126.915164 -255.863344)
			(xy 126.885446 -255.863344) (xy 126.878588 -255.865376) (xy 126.856152 -255.871442) (xy 126.810132 -255.877946)
			(xy 126.786894 -255.87833) (xy 126.760905 -255.87782) (xy 126.709568 -255.869688) (xy 126.660135 -255.853626)
			(xy 126.613823 -255.830028) (xy 126.571773 -255.799476) (xy 126.53502 -255.762722) (xy 126.504469 -255.720671)
			(xy 126.480872 -255.674359) (xy 126.464811 -255.624926) (xy 126.45668 -255.573589) (xy 126.45668 -255.521611)
			(xy 126.464811 -255.470274) (xy 126.480872 -255.420841) (xy 126.504469 -255.374529) (xy 126.53502 -255.332478)
			(xy 126.571773 -255.295724) (xy 126.613823 -255.265172) (xy 126.660135 -255.241574) (xy 126.709568 -255.225512)
			(xy 126.760905 -255.21738) (xy 126.786894 -255.216914) (xy 126.811861 -255.217369) (xy 126.861223 -255.224897)
			(xy 126.885192 -255.2319) (xy 126.885446 -255.2319) (xy 126.89685 -255.234818) (xy 126.92004 -255.230971)
			(xy 126.929896 -255.224534) (xy 126.962408 -255.200404) (xy 126.99619 -255.175766) (xy 127.004886 -255.168336)
			(xy 127.014944 -255.147821) (xy 127.015494 -255.136396) (xy 127.015494 -254.978408) (xy 127.00381 -254.946658)
			(xy 127.00127 -254.943356) (xy 126.983694 -254.921002) (xy 126.955665 -254.871529) (xy 126.936488 -254.817999)
			(xy 126.926727 -254.761982) (xy 126.926086 -254.733552) (xy 126.926599 -254.707567) (xy 126.934736 -254.656238)
			(xy 126.950801 -254.606814) (xy 126.974399 -254.56051) (xy 127.00495 -254.518468) (xy 127.0417 -254.481722)
			(xy 127.083746 -254.451177) (xy 127.130052 -254.427585) (xy 127.179479 -254.411526) (xy 127.230809 -254.403396)
			(xy 127.256794 -254.402844) (xy 127.265938 -254.402844) (xy 127.27543 -254.402192) (xy 127.292927 -254.394757)
			(xy 127.299974 -254.388366) (xy 127.479044 -254.209296) (xy 127.480822 -254.207518) (xy 127.480822 -254.141224)
			(xy 127.47244 -254.13081) (xy 127.454633 -254.108376) (xy 127.426215 -254.058652) (xy 127.406771 -254.004782)
			(xy 127.396882 -253.948371) (xy 127.39624 -253.919736) (xy 127.39672 -253.893746) (xy 127.404848 -253.842406)
			(xy 127.420907 -253.79297) (xy 127.444504 -253.746655) (xy 127.475056 -253.704603) (xy 127.511812 -253.667848)
			(xy 127.553865 -253.637298) (xy 127.600181 -253.613703) (xy 127.649618 -253.597645) (xy 127.700958 -253.58952)
			(xy 127.726948 -253.589028) (xy 127.750289 -253.589421) (xy 127.796507 -253.595977) (xy 127.841341 -253.608979)
			(xy 127.883895 -253.628168) (xy 127.923321 -253.653162) (xy 127.941324 -253.668022) (xy 127.947928 -253.67361)
			(xy 127.980948 -253.68631) (xy 127.990767 -253.685841) (xy 128.008944 -253.678403) (xy 128.016254 -253.671832)
			(xy 131.670806 -250.01728) (xy 131.677519 -250.010042) (xy 131.685111 -249.991837) (xy 131.685538 -249.981974)
			(xy 131.685538 -249.93727) (xy 131.66344 -249.896122) (xy 131.657598 -249.891804) (xy 131.636045 -249.87621)
			(xy 131.597749 -249.83929) (xy 131.565854 -249.796717) (xy 131.541185 -249.749589) (xy 131.524375 -249.69912)
			(xy 131.51586 -249.646611) (xy 131.515858 -249.593416) (xy 131.524369 -249.540907) (xy 131.541174 -249.490436)
			(xy 131.56584 -249.443306) (xy 131.59773 -249.40073) (xy 131.636024 -249.363807) (xy 131.657598 -249.348244)
			(xy 131.66344 -249.343926) (xy 131.685538 -249.302778) (xy 131.685538 -249.18289) (xy 131.685128 -249.174244)
			(xy 131.679205 -249.157993) (xy 131.668156 -249.144684) (xy 131.6609 -249.139964) (xy 131.623562 -249.11812)
			(xy 131.585208 -249.095514) (xy 131.577656 -249.091682) (xy 131.560983 -249.088772) (xy 131.544279 -249.091496)
			(xy 131.536694 -249.09526) (xy 131.53644 -249.095514) (xy 131.511749 -249.108524) (xy 131.459084 -249.126985)
			(xy 131.404069 -249.136354) (xy 131.376166 -249.136916) (xy 131.35018 -249.136404) (xy 131.298848 -249.128269)
			(xy 131.249421 -249.112205) (xy 131.203115 -249.088606) (xy 131.161071 -249.058055) (xy 131.124323 -249.021303)
			(xy 131.093776 -248.979256) (xy 131.070182 -248.932947) (xy 131.054123 -248.883519) (xy 131.045993 -248.832186)
			(xy 131.045993 -248.780214) (xy 131.054123 -248.728881) (xy 131.070182 -248.679453) (xy 131.093776 -248.633144)
			(xy 131.124323 -248.591097) (xy 131.161071 -248.554345) (xy 131.203115 -248.523794) (xy 131.249421 -248.500195)
			(xy 131.298848 -248.484131) (xy 131.35018 -248.475996) (xy 131.376166 -248.4755) (xy 131.404069 -248.476076)
			(xy 131.459086 -248.485431) (xy 131.511753 -248.503884) (xy 131.53644 -248.516902) (xy 131.536694 -248.517156)
			(xy 131.544274 -248.520948) (xy 131.560983 -248.523716) (xy 131.57766 -248.52076) (xy 131.585208 -248.516902)
			(xy 131.623562 -248.49455) (xy 131.6609 -248.472452) (xy 131.668188 -248.467762) (xy 131.679278 -248.45446)
			(xy 131.685197 -248.438184) (xy 131.685538 -248.429526) (xy 131.685538 -248.309384) (xy 131.66344 -248.268236)
			(xy 131.657852 -248.264172) (xy 131.636209 -248.24862) (xy 131.597769 -248.211707) (xy 131.565749 -248.169106)
			(xy 131.540978 -248.121919) (xy 131.524098 -248.07137) (xy 131.515545 -248.018768) (xy 131.515542 -247.965475)
			(xy 131.524088 -247.912872) (xy 131.540962 -247.86232) (xy 131.565726 -247.815131) (xy 131.597741 -247.772525)
			(xy 131.636175 -247.735607) (xy 131.657852 -247.720104) (xy 131.66344 -247.71604) (xy 131.685538 -247.674892)
			(xy 131.685538 -247.555004) (xy 131.685158 -247.546318) (xy 131.679252 -247.529978) (xy 131.66817 -247.516597)
			(xy 131.6609 -247.511824) (xy 131.62534 -247.490742) (xy 131.585462 -247.467374) (xy 131.579741 -247.464406)
			(xy 131.567267 -247.461184) (xy 131.560824 -247.461024) (xy 131.536694 -247.467374) (xy 131.53136 -247.470168)
			(xy 131.507287 -247.482383) (xy 131.456159 -247.499694) (xy 131.402901 -247.508491) (xy 131.375912 -247.50903)
			(xy 131.34992 -247.508548) (xy 131.298577 -247.500417) (xy 131.249138 -247.484355) (xy 131.20282 -247.460756)
			(xy 131.160764 -247.430202) (xy 131.124005 -247.393445) (xy 131.09345 -247.351391) (xy 131.069849 -247.305074)
			(xy 131.053785 -247.255635) (xy 131.045653 -247.204292) (xy 131.045653 -247.152308) (xy 131.053785 -247.100965)
			(xy 131.069849 -247.051526) (xy 131.09345 -247.005209) (xy 131.124005 -246.963155) (xy 131.160764 -246.926398)
			(xy 131.20282 -246.895844) (xy 131.249138 -246.872245) (xy 131.298577 -246.856183) (xy 131.34992 -246.848052)
			(xy 131.375912 -246.847614) (xy 131.402903 -246.848145) (xy 131.456168 -246.856917) (xy 131.507295 -246.874242)
			(xy 131.53136 -246.886476) (xy 131.536694 -246.88927) (xy 131.560824 -246.89562) (xy 131.567267 -246.895456)
			(xy 131.579743 -246.892241) (xy 131.585462 -246.88927) (xy 131.62534 -246.865902) (xy 131.6609 -246.84482)
			(xy 131.668217 -246.8401) (xy 131.67933 -246.826714) (xy 131.685211 -246.81034) (xy 131.685538 -246.80164)
			(xy 131.685538 -246.681752) (xy 131.66344 -246.640604) (xy 131.657852 -246.63654) (xy 131.636211 -246.620988)
			(xy 131.597777 -246.584076) (xy 131.565762 -246.541476) (xy 131.540996 -246.494292) (xy 131.524119 -246.443746)
			(xy 131.51557 -246.391148) (xy 131.515569 -246.337859) (xy 131.524118 -246.28526) (xy 131.540993 -246.234714)
			(xy 131.565758 -246.18753) (xy 131.597772 -246.144929) (xy 131.636206 -246.108016) (xy 131.657852 -246.092472)
			(xy 131.66344 -246.088408) (xy 131.685538 -246.04726) (xy 131.685538 -245.927372) (xy 131.685125 -245.918727)
			(xy 131.679198 -245.902481) (xy 131.668148 -245.889177) (xy 131.6609 -245.884446) (xy 131.623562 -245.862348)
			(xy 131.585208 -245.839996) (xy 131.577656 -245.836166) (xy 131.560983 -245.833256) (xy 131.54428 -245.835979)
			(xy 131.536694 -245.839742) (xy 131.53644 -245.839996) (xy 131.511749 -245.853007) (xy 131.459084 -245.871469)
			(xy 131.404069 -245.880838) (xy 131.376166 -245.881398) (xy 131.350181 -245.880886) (xy 131.298853 -245.872751)
			(xy 131.249428 -245.856688) (xy 131.203125 -245.833091) (xy 131.161082 -245.802542) (xy 131.124336 -245.765792)
			(xy 131.093791 -245.723746) (xy 131.070199 -245.677441) (xy 131.054141 -245.628014) (xy 131.046011 -245.576685)
			(xy 131.046011 -245.524715) (xy 131.054141 -245.473386) (xy 131.070199 -245.423959) (xy 131.093791 -245.377654)
			(xy 131.124336 -245.335608) (xy 131.161082 -245.298858) (xy 131.203125 -245.268309) (xy 131.249428 -245.244712)
			(xy 131.298853 -245.228649) (xy 131.350181 -245.220514) (xy 131.376166 -245.219982) (xy 131.404069 -245.220558)
			(xy 131.459086 -245.229913) (xy 131.511754 -245.248364) (xy 131.53644 -245.261384) (xy 131.536694 -245.261638)
			(xy 131.544273 -245.265432) (xy 131.560983 -245.2682) (xy 131.577661 -245.265243) (xy 131.585208 -245.261384)
			(xy 131.623562 -245.239032) (xy 131.6609 -245.216934) (xy 131.668186 -245.212242) (xy 131.679271 -245.19894)
			(xy 131.685184 -245.182665) (xy 131.685538 -245.174008) (xy 131.685538 -245.053866) (xy 131.66344 -245.012718)
			(xy 131.657598 -245.0084) (xy 131.636045 -244.992806) (xy 131.59775 -244.955886) (xy 131.565856 -244.913314)
			(xy 131.541187 -244.866186) (xy 131.524378 -244.815717) (xy 131.515863 -244.763209) (xy 131.515861 -244.710014)
			(xy 131.524373 -244.657505) (xy 131.541178 -244.607035) (xy 131.565844 -244.559906) (xy 131.597734 -244.517331)
			(xy 131.636028 -244.480409) (xy 131.657598 -244.46484) (xy 131.66344 -244.460522) (xy 131.685538 -244.419374)
			(xy 131.685538 -244.299486) (xy 131.685127 -244.29084) (xy 131.679203 -244.27459) (xy 131.668155 -244.261282)
			(xy 131.6609 -244.25656) (xy 131.623562 -244.234716) (xy 131.585208 -244.21211) (xy 131.577656 -244.208279)
			(xy 131.560983 -244.205368) (xy 131.544279 -244.208093) (xy 131.536694 -244.211856) (xy 131.53644 -244.21211)
			(xy 131.511749 -244.22512) (xy 131.459084 -244.243581) (xy 131.404069 -244.25295) (xy 131.376166 -244.253512)
			(xy 131.35018 -244.253) (xy 131.298849 -244.244865) (xy 131.249423 -244.228801) (xy 131.203117 -244.205203)
			(xy 131.161073 -244.174652) (xy 131.124326 -244.137901) (xy 131.093779 -244.095854) (xy 131.070186 -244.049546)
			(xy 131.054127 -244.000118) (xy 131.045997 -243.948786) (xy 131.045997 -243.896814) (xy 131.054127 -243.845482)
			(xy 131.070186 -243.796054) (xy 131.093779 -243.749746) (xy 131.124326 -243.707699) (xy 131.161073 -243.670948)
			(xy 131.203117 -243.640397) (xy 131.249423 -243.616799) (xy 131.298849 -243.600735) (xy 131.35018 -243.5926)
			(xy 131.376166 -243.592096) (xy 131.404069 -243.592672) (xy 131.459086 -243.602027) (xy 131.511754 -243.620479)
			(xy 131.53644 -243.633498) (xy 131.536694 -243.633752) (xy 131.544273 -243.637545) (xy 131.560983 -243.640313)
			(xy 131.577661 -243.637356) (xy 131.585208 -243.633498) (xy 131.623562 -243.611146) (xy 131.6609 -243.589048)
			(xy 131.668187 -243.584357) (xy 131.679276 -243.571055) (xy 131.685193 -243.55478) (xy 131.685538 -243.546122)
			(xy 131.685538 -243.426234) (xy 131.66344 -243.385086) (xy 131.657852 -243.381022) (xy 131.636213 -243.36547)
			(xy 131.597781 -243.328559) (xy 131.565769 -243.28596) (xy 131.541005 -243.238777) (xy 131.524131 -243.188233)
			(xy 131.515584 -243.135636) (xy 131.515585 -243.08235) (xy 131.524134 -243.029754) (xy 131.541011 -242.97921)
			(xy 131.565776 -242.932029) (xy 131.59779 -242.889431) (xy 131.636223 -242.852521) (xy 131.657852 -242.836954)
			(xy 131.66344 -242.83289) (xy 131.685538 -242.791742) (xy 131.685538 -242.6716) (xy 131.68513 -242.662953)
			(xy 131.679208 -242.646699) (xy 131.668161 -242.633388) (xy 131.6609 -242.628674) (xy 131.623562 -242.606576)
			(xy 131.585208 -242.584224) (xy 131.577656 -242.580392) (xy 131.560983 -242.57748) (xy 131.544279 -242.580206)
			(xy 131.536694 -242.58397) (xy 131.53644 -242.584224) (xy 131.511748 -242.597234) (xy 131.459084 -242.615694)
			(xy 131.404069 -242.625062) (xy 131.376166 -242.625626) (xy 131.350179 -242.625114) (xy 131.298846 -242.616979)
			(xy 131.249417 -242.600914) (xy 131.20311 -242.577315) (xy 131.161064 -242.546763) (xy 131.124315 -242.51001)
			(xy 131.093767 -242.467961) (xy 131.070173 -242.421651) (xy 131.054113 -242.372221) (xy 131.045983 -242.320887)
			(xy 131.045983 -242.268913) (xy 131.054113 -242.217579) (xy 131.070173 -242.168149) (xy 131.093767 -242.121839)
			(xy 131.124315 -242.07979) (xy 131.161064 -242.043037) (xy 131.20311 -242.012485) (xy 131.249417 -241.988886)
			(xy 131.298846 -241.972821) (xy 131.350179 -241.964686) (xy 131.376166 -241.96421) (xy 131.404069 -241.964786)
			(xy 131.459086 -241.974142) (xy 131.511753 -241.992594) (xy 131.53644 -242.005612) (xy 131.536694 -242.005866)
			(xy 131.544274 -242.009658) (xy 131.560983 -242.012425) (xy 131.57766 -242.009469) (xy 131.585208 -242.005612)
			(xy 131.623562 -241.98326) (xy 131.6609 -241.961162) (xy 131.668189 -241.956472) (xy 131.679282 -241.943171)
			(xy 131.685203 -241.926895) (xy 131.685538 -241.918236) (xy 131.685538 -241.798348) (xy 131.66344 -241.7572)
			(xy 131.657852 -241.753136) (xy 131.636212 -241.737584) (xy 131.597778 -241.700672) (xy 131.565764 -241.658073)
			(xy 131.540998 -241.610889) (xy 131.524122 -241.560343) (xy 131.515573 -241.507745) (xy 131.515573 -241.454457)
			(xy 131.524121 -241.401859) (xy 131.540997 -241.351313) (xy 131.565762 -241.304129) (xy 131.597776 -241.26153)
			(xy 131.63621 -241.224617) (xy 131.657852 -241.209068) (xy 131.66344 -241.205004) (xy 131.685538 -241.163856)
			(xy 131.685538 -241.043968) (xy 131.685124 -241.035324) (xy 131.679196 -241.019078) (xy 131.668146 -241.005775)
			(xy 131.6609 -241.001042) (xy 131.623562 -240.978944) (xy 131.585208 -240.956592) (xy 131.577656 -240.952762)
			(xy 131.560983 -240.949852) (xy 131.54428 -240.952576) (xy 131.536694 -240.956338) (xy 131.53644 -240.956592)
			(xy 131.511749 -240.969603) (xy 131.459084 -240.988065) (xy 131.404069 -240.997434) (xy 131.376166 -240.997994)
			(xy 131.350182 -240.997482) (xy 131.298853 -240.989348) (xy 131.24943 -240.973284) (xy 131.203127 -240.949688)
			(xy 131.161085 -240.919138) (xy 131.124339 -240.882389) (xy 131.093795 -240.840344) (xy 131.070203 -240.794039)
			(xy 131.054145 -240.744613) (xy 131.046015 -240.693284) (xy 131.046015 -240.641316) (xy 131.054145 -240.589987)
			(xy 131.070203 -240.540561) (xy 131.093795 -240.494256) (xy 131.124339 -240.452211) (xy 131.161085 -240.415462)
			(xy 131.203127 -240.384912) (xy 131.24943 -240.361316) (xy 131.298853 -240.345252) (xy 131.350182 -240.337118)
			(xy 131.376166 -240.336578) (xy 131.404069 -240.337153) (xy 131.459086 -240.346509) (xy 131.511754 -240.36496)
			(xy 131.53644 -240.37798) (xy 131.536694 -240.378234) (xy 131.544273 -240.382028) (xy 131.560983 -240.384797)
			(xy 131.577661 -240.381839) (xy 131.585208 -240.37798) (xy 131.623562 -240.355628) (xy 131.6609 -240.33353)
			(xy 131.668185 -240.328838) (xy 131.67927 -240.315536) (xy 131.685181 -240.299261) (xy 131.685538 -240.290604)
			(xy 131.685538 -240.170462) (xy 131.66344 -240.129314) (xy 131.657598 -240.124996) (xy 131.636046 -240.109402)
			(xy 131.597751 -240.072482) (xy 131.565858 -240.02991) (xy 131.541189 -239.982782) (xy 131.524381 -239.932314)
			(xy 131.515866 -239.879806) (xy 131.515865 -239.826612) (xy 131.524376 -239.774104) (xy 131.541182 -239.723635)
			(xy 131.565848 -239.676505) (xy 131.597738 -239.633931) (xy 131.636032 -239.59701) (xy 131.657598 -239.581436)
			(xy 131.66344 -239.577118) (xy 131.685538 -239.53597) (xy 131.685538 -239.416082) (xy 131.685127 -239.407437)
			(xy 131.679202 -239.391187) (xy 131.668153 -239.377881) (xy 131.6609 -239.373156) (xy 131.623562 -239.351312)
			(xy 131.585208 -239.328706) (xy 131.577656 -239.324875) (xy 131.560983 -239.321965) (xy 131.544279 -239.324689)
			(xy 131.536694 -239.328452) (xy 131.53644 -239.328706) (xy 131.511749 -239.341716) (xy 131.459084 -239.360178)
			(xy 131.404069 -239.369546) (xy 131.376166 -239.370108) (xy 131.350181 -239.369596) (xy 131.29885 -239.361461)
			(xy 131.249424 -239.345397) (xy 131.203119 -239.321799) (xy 131.161076 -239.291249) (xy 131.124329 -239.254498)
			(xy 131.093783 -239.212452) (xy 131.07019 -239.166144) (xy 131.054131 -239.116717) (xy 131.046001 -239.065385)
			(xy 131.046001 -239.013415) (xy 131.054131 -238.962083) (xy 131.07019 -238.912656) (xy 131.093783 -238.866348)
			(xy 131.124329 -238.824302) (xy 131.161076 -238.787551) (xy 131.203119 -238.757001) (xy 131.249424 -238.733403)
			(xy 131.29885 -238.717339) (xy 131.350181 -238.709204) (xy 131.376166 -238.708692) (xy 131.404069 -238.709268)
			(xy 131.459086 -238.718623) (xy 131.511754 -238.737075) (xy 131.53644 -238.750094) (xy 131.536694 -238.750348)
			(xy 131.544273 -238.754141) (xy 131.560983 -238.756909) (xy 131.577661 -238.753952) (xy 131.585208 -238.750094)
			(xy 131.623562 -238.727488) (xy 131.6609 -238.705644) (xy 131.668187 -238.700953) (xy 131.679275 -238.687651)
			(xy 131.685191 -238.671376) (xy 131.685538 -238.662718) (xy 131.685538 -238.54283) (xy 131.66344 -238.501682)
			(xy 131.657852 -238.497618) (xy 131.636213 -238.482066) (xy 131.597782 -238.445155) (xy 131.565771 -238.402556)
			(xy 131.541007 -238.355374) (xy 131.524134 -238.30483) (xy 131.515587 -238.252234) (xy 131.515589 -238.198948)
			(xy 131.524138 -238.146352) (xy 131.541014 -238.09581) (xy 131.56578 -238.048629) (xy 131.597794 -238.006032)
			(xy 131.636227 -237.969122) (xy 131.657852 -237.95355) (xy 131.66344 -237.949486) (xy 131.685538 -237.908338)
			(xy 131.685538 -237.788196) (xy 131.685129 -237.779549) (xy 131.679207 -237.763296) (xy 131.668159 -237.749986)
			(xy 131.6609 -237.74527) (xy 131.623562 -237.723172) (xy 131.585208 -237.70082) (xy 131.577656 -237.696988)
			(xy 131.560983 -237.694077) (xy 131.544279 -237.696802) (xy 131.536694 -237.700566) (xy 131.53644 -237.70082)
			(xy 131.511748 -237.71383) (xy 131.459084 -237.73229) (xy 131.404069 -237.741659) (xy 131.376166 -237.742222)
			(xy 131.350179 -237.74171) (xy 131.298847 -237.733575) (xy 131.249419 -237.71751) (xy 131.203112 -237.693911)
			(xy 131.161067 -237.66336) (xy 131.124318 -237.626607) (xy 131.093771 -237.584559) (xy 131.070177 -237.53825)
			(xy 131.054117 -237.48882) (xy 131.045987 -237.437487) (xy 131.045987 -237.385513) (xy 131.054117 -237.33418)
			(xy 131.070177 -237.28475) (xy 131.093771 -237.238441) (xy 131.124318 -237.196393) (xy 131.161067 -237.15964)
			(xy 131.203112 -237.129089) (xy 131.249419 -237.10549) (xy 131.298847 -237.089425) (xy 131.350179 -237.08129)
			(xy 131.376166 -237.080806) (xy 131.404069 -237.081382) (xy 131.459086 -237.090738) (xy 131.511753 -237.10919)
			(xy 131.53644 -237.122208) (xy 131.536694 -237.122462) (xy 131.544274 -237.126254) (xy 131.560983 -237.129021)
			(xy 131.57766 -237.126065) (xy 131.585208 -237.122208) (xy 131.623562 -237.099856) (xy 131.6609 -237.077758)
			(xy 131.668189 -237.073068) (xy 131.679281 -237.059767) (xy 131.685201 -237.043491) (xy 131.685538 -237.034832)
			(xy 131.685538 -236.915198) (xy 131.66344 -236.87405) (xy 131.657852 -236.869986) (xy 131.636215 -236.854434)
			(xy 131.59779 -236.817524) (xy 131.565783 -236.774927) (xy 131.541024 -236.727747) (xy 131.524155 -236.677206)
			(xy 131.515612 -236.624614) (xy 131.515616 -236.571332) (xy 131.524168 -236.518741) (xy 131.541046 -236.468203)
			(xy 131.565812 -236.421027) (xy 131.597826 -236.378436) (xy 131.636258 -236.341531) (xy 131.657852 -236.325918)
			(xy 131.66344 -236.321854) (xy 131.685538 -236.280706) (xy 131.685538 -236.160564) (xy 131.685124 -236.15192)
			(xy 131.679195 -236.135675) (xy 131.668145 -236.122374) (xy 131.6609 -236.117638) (xy 131.623562 -236.09554)
			(xy 131.585208 -236.073188) (xy 131.577656 -236.069358) (xy 131.560983 -236.066449) (xy 131.54428 -236.069172)
			(xy 131.536694 -236.072934) (xy 131.53644 -236.073188) (xy 131.511749 -236.086199) (xy 131.459084 -236.104661)
			(xy 131.404069 -236.114031) (xy 131.376166 -236.11459) (xy 131.350182 -236.114078) (xy 131.298854 -236.105944)
			(xy 131.249431 -236.089881) (xy 131.203129 -236.066284) (xy 131.161088 -236.035735) (xy 131.124342 -235.998987)
			(xy 131.093798 -235.956942) (xy 131.070206 -235.910637) (xy 131.054148 -235.861212) (xy 131.046019 -235.809884)
			(xy 131.046019 -235.757916) (xy 131.054148 -235.706588) (xy 131.070206 -235.657163) (xy 131.093798 -235.610858)
			(xy 131.124342 -235.568813) (xy 131.161088 -235.532065) (xy 131.203129 -235.501516) (xy 131.249431 -235.477919)
			(xy 131.298854 -235.461856) (xy 131.350182 -235.453722) (xy 131.376166 -235.453174) (xy 131.404069 -235.453749)
			(xy 131.459086 -235.463105) (xy 131.511754 -235.481556) (xy 131.53644 -235.494576) (xy 131.536694 -235.49483)
			(xy 131.544273 -235.498624) (xy 131.560983 -235.501393) (xy 131.577661 -235.498435) (xy 131.585208 -235.494576)
			(xy 131.623562 -235.472224) (xy 131.6609 -235.450126) (xy 131.668185 -235.445434) (xy 131.679268 -235.432132)
			(xy 131.685178 -235.415857) (xy 131.685538 -235.4072) (xy 131.685538 -235.287312) (xy 131.66344 -235.246164)
			(xy 131.657598 -235.241846) (xy 131.636043 -235.226255) (xy 131.597744 -235.18934) (xy 131.565848 -235.146769)
			(xy 131.541178 -235.099641) (xy 131.524371 -235.049172) (xy 131.515861 -234.996663) (xy 131.515358 -234.970066)
			(xy 131.515845 -234.94408) (xy 131.523986 -234.89275) (xy 131.540062 -234.843327) (xy 131.563676 -234.797029)
			(xy 131.594246 -234.754999) (xy 131.631019 -234.718273) (xy 131.651756 -234.702604) (xy 131.653534 -234.701334)
			(xy 131.65963 -234.696) (xy 132.005324 -234.350306) (xy 132.011533 -234.343515) (xy 132.019015 -234.326723)
			(xy 132.019994 -234.308365) (xy 132.017516 -234.299506) (xy 132.014976 -234.293918) (xy 132.005571 -234.272335)
			(xy 131.992329 -234.227156) (xy 131.985654 -234.180552) (xy 131.985258 -234.157012) (xy 131.985258 -234.15625)
			(xy 131.985737 -234.130257) (xy 131.993862 -234.078911) (xy 132.00992 -234.029467) (xy 132.033514 -233.983145)
			(xy 132.064065 -233.941083) (xy 132.100819 -233.90432) (xy 132.142873 -233.873758) (xy 132.189189 -233.850152)
			(xy 132.238629 -233.834082) (xy 132.289973 -233.825944) (xy 132.315966 -233.825542) (xy 132.316728 -233.825542)
			(xy 132.340263 -233.825982) (xy 132.386854 -233.83269) (xy 132.432031 -233.84591) (xy 132.453634 -233.85526)
			(xy 132.459222 -233.8578) (xy 132.468088 -233.860259) (xy 132.486445 -233.859305) (xy 132.503233 -233.851818)
			(xy 132.510022 -233.845608) (xy 132.597906 -233.757724) (xy 132.604703 -233.750248) (xy 132.612192 -233.731503)
			(xy 132.612384 -233.721402) (xy 132.60705 -233.64317) (xy 132.587492 -233.606848) (xy 132.584698 -233.604816)
			(xy 132.579872 -233.600752) (xy 132.579364 -233.600498) (xy 132.560343 -233.584707) (xy 132.526752 -233.548439)
			(xy 132.498935 -233.507575) (xy 132.477511 -233.463024) (xy 132.462959 -233.415781) (xy 132.455602 -233.366897)
			(xy 132.455158 -233.34218) (xy 132.455672 -233.315451) (xy 132.464271 -233.262689) (xy 132.48124 -233.211995)
			(xy 132.506139 -233.16469) (xy 132.538321 -233.122003) (xy 132.576946 -233.085045) (xy 132.621012 -233.054779)
			(xy 132.66937 -233.031992) (xy 132.694934 -233.024172) (xy 132.708904 -233.020108) (xy 132.74675 -232.972102)
			(xy 132.74675 -232.80497) (xy 132.74627 -232.794726) (xy 132.738144 -232.77592) (xy 132.723206 -232.761901)
			(xy 132.71373 -232.75798) (xy 132.625084 -232.725722) (xy 132.620974 -232.7243) (xy 132.612414 -232.722761)
			(xy 132.608066 -232.722674) (xy 132.569712 -232.740454) (xy 132.568442 -232.741724) (xy 132.552671 -232.759768)
			(xy 132.51681 -232.791555) (xy 132.476728 -232.817822) (xy 132.43327 -232.838016) (xy 132.387347 -232.851713)
			(xy 132.339927 -232.858624) (xy 132.315966 -232.859072) (xy 132.289983 -232.85856) (xy 132.238659 -232.850426)
			(xy 132.189238 -232.834364) (xy 132.142938 -232.810769) (xy 132.100899 -232.780222) (xy 132.064156 -232.743475)
			(xy 132.033613 -232.701433) (xy 132.010023 -232.655131) (xy 131.993966 -232.605708) (xy 131.985837 -232.554383)
			(xy 131.985837 -232.502417) (xy 131.993966 -232.451092) (xy 132.010023 -232.401669) (xy 132.033613 -232.355367)
			(xy 132.064156 -232.313325) (xy 132.100899 -232.276578) (xy 132.142938 -232.246031) (xy 132.189238 -232.222436)
			(xy 132.238659 -232.206374) (xy 132.289983 -232.19824) (xy 132.315966 -232.197656) (xy 132.339925 -232.198088)
			(xy 132.38734 -232.205021) (xy 132.433255 -232.218731) (xy 132.476708 -232.238932) (xy 132.516786 -232.265199)
			(xy 132.552648 -232.296981) (xy 132.568442 -232.315004) (xy 132.569712 -232.316274) (xy 132.608066 -232.334054)
			(xy 132.612411 -232.333934) (xy 132.620965 -232.332395) (xy 132.625084 -232.331006) (xy 132.71373 -232.298748)
			(xy 132.723186 -232.294799) (xy 132.738096 -232.280771) (xy 132.746248 -232.261992) (xy 132.74675 -232.251758)
			(xy 132.74675 -232.084626) (xy 132.708904 -232.03662) (xy 132.696712 -232.033064) (xy 132.672493 -232.025809)
			(xy 132.626433 -232.004969) (xy 132.584081 -231.977362) (xy 132.546424 -231.943631) (xy 132.514339 -231.904562)
			(xy 132.488573 -231.861065) (xy 132.469728 -231.814154) (xy 132.458241 -231.764921) (xy 132.454381 -231.714513)
			(xy 132.458237 -231.664105) (xy 132.46972 -231.614871) (xy 132.488562 -231.567958) (xy 132.514324 -231.524459)
			(xy 132.546406 -231.485388) (xy 132.584061 -231.451654) (xy 132.62641 -231.424044) (xy 132.672469 -231.4032)
			(xy 132.696712 -231.396032) (xy 132.708904 -231.392476) (xy 132.74675 -231.34447) (xy 132.74675 -231.116124)
			(xy 132.745226 -231.112314) (xy 132.74294 -231.106726) (xy 132.737009 -231.091698) (xy 132.726712 -231.061072)
			(xy 132.722366 -231.045512) (xy 132.718048 -231.029256) (xy 132.669534 -230.991156) (xy 132.62356 -231.022398)
			(xy 132.617718 -231.035606) (xy 132.606094 -231.060189) (xy 132.576039 -231.105502) (xy 132.538982 -231.145293)
			(xy 132.49592 -231.178492) (xy 132.44801 -231.204206) (xy 132.396542 -231.221743) (xy 132.342899 -231.230632)
			(xy 132.315712 -231.231186) (xy 132.289723 -231.230704) (xy 132.238384 -231.222574) (xy 132.188949 -231.206512)
			(xy 132.142636 -231.182915) (xy 132.100585 -231.152363) (xy 132.063831 -231.115608) (xy 132.03328 -231.073555)
			(xy 132.009684 -231.027241) (xy 131.993624 -230.977806) (xy 131.985495 -230.926467) (xy 131.985004 -230.900478)
			(xy 131.985532 -230.874038) (xy 131.993961 -230.821835) (xy 132.010586 -230.771636) (xy 132.034982 -230.72472)
			(xy 132.066529 -230.682282) (xy 132.104425 -230.645401) (xy 132.147703 -230.615016) (xy 132.195263 -230.591901)
			(xy 132.245894 -230.576644) (xy 132.272024 -230.572564) (xy 132.275072 -230.572056) (xy 132.287111 -230.56915)
			(xy 132.306429 -230.553701) (xy 132.311902 -230.542592) (xy 132.323586 -230.515414) (xy 132.346446 -230.46182)
			(xy 132.348069 -230.457487) (xy 132.349861 -230.448411) (xy 132.350002 -230.443786) (xy 132.340096 -230.414068)
			(xy 132.337302 -230.410004) (xy 132.321115 -230.38699) (xy 132.292988 -230.338255) (xy 132.281168 -230.312722)
			(xy 132.27939 -230.308658) (xy 132.239766 -230.279448) (xy 132.150866 -230.26878) (xy 132.13946 -230.268618)
			(xy 132.118415 -230.27735) (xy 132.11048 -230.285544) (xy 132.108194 -230.288338) (xy 132.092435 -230.308051)
			(xy 132.05595 -230.342917) (xy 132.01459 -230.371833) (xy 131.969316 -230.394128) (xy 131.92118 -230.409284)
			(xy 131.871299 -230.416948) (xy 131.846066 -230.41737) (xy 131.820084 -230.416858) (xy 131.768759 -230.408724)
			(xy 131.719339 -230.392662) (xy 131.67304 -230.369067) (xy 131.631001 -230.33852) (xy 131.594258 -230.301773)
			(xy 131.563716 -230.259731) (xy 131.540125 -230.21343) (xy 131.524068 -230.164008) (xy 131.51594 -230.112682)
			(xy 131.51594 -230.060718) (xy 131.524068 -230.009392) (xy 131.540125 -229.95997) (xy 131.563716 -229.913669)
			(xy 131.594258 -229.871627) (xy 131.631001 -229.83488) (xy 131.67304 -229.804333) (xy 131.719339 -229.780738)
			(xy 131.768759 -229.764676) (xy 131.820084 -229.756542) (xy 131.846066 -229.755954) (xy 131.871295 -229.756434)
			(xy 131.921165 -229.764105) (xy 131.969293 -229.779261) (xy 132.014561 -229.801548) (xy 132.05592 -229.83045)
			(xy 132.092411 -229.865298) (xy 132.108194 -229.884986) (xy 132.11048 -229.88778) (xy 132.11852 -229.895825)
			(xy 132.139494 -229.904541) (xy 132.150866 -229.904544) (xy 132.239766 -229.893876) (xy 132.27939 -229.864666)
			(xy 132.281168 -229.860602) (xy 132.293004 -229.835077) (xy 132.321128 -229.786342) (xy 132.337302 -229.76332)
			(xy 132.340096 -229.759256) (xy 132.350002 -229.729538) (xy 132.349844 -229.724915) (xy 132.348046 -229.715844)
			(xy 132.346446 -229.711504) (xy 132.311902 -229.630732) (xy 132.272786 -229.601014) (xy 132.260594 -229.598982)
			(xy 132.235251 -229.594181) (xy 132.186356 -229.577762) (xy 132.140604 -229.553949) (xy 132.099104 -229.523321)
			(xy 132.062864 -229.486621) (xy 132.032762 -229.444738) (xy 132.009529 -229.398689) (xy 131.993728 -229.349591)
			(xy 131.985742 -229.298635) (xy 131.985258 -229.272846) (xy 131.985738 -229.246853) (xy 131.993863 -229.195507)
			(xy 132.009921 -229.146064) (xy 132.033515 -229.099742) (xy 132.064066 -229.057682) (xy 132.100821 -229.020918)
			(xy 132.142874 -228.990357) (xy 132.18919 -228.966751) (xy 132.238629 -228.950682) (xy 132.289974 -228.942544)
			(xy 132.315966 -228.942138) (xy 132.340337 -228.942576) (xy 132.38855 -228.949732) (xy 132.435193 -228.96388)
			(xy 132.479257 -228.984714) (xy 132.51979 -229.011784) (xy 132.555916 -229.044505) (xy 132.571744 -229.063042)
			(xy 132.574538 -229.066598) (xy 132.575554 -229.068122) (xy 132.578602 -229.071678) (xy 132.617972 -229.090982)
			(xy 132.624068 -229.090728) (xy 132.681218 -229.08387) (xy 132.711952 -229.08006) (xy 132.724183 -229.077269)
			(xy 132.743893 -229.061799) (xy 132.749544 -229.050596) (xy 132.749798 -229.050596) (xy 132.749798 -229.050342)
			(xy 132.75669 -229.035087) (xy 132.772065 -229.005347) (xy 132.780532 -228.990906) (xy 132.786852 -228.980294)
			(xy 132.80032 -228.959585) (xy 132.807456 -228.949504) (xy 132.81025 -228.94544) (xy 132.820156 -228.915722)
			(xy 132.820006 -228.911098) (xy 132.818224 -228.90202) (xy 132.8166 -228.897688) (xy 132.79374 -228.844094)
			(xy 132.782056 -228.816916) (xy 132.776622 -228.805771) (xy 132.757293 -228.790296) (xy 132.745226 -228.787452)
			(xy 132.742178 -228.786944) (xy 132.716031 -228.78294) (xy 132.665379 -228.767703) (xy 132.617799 -228.744596)
			(xy 132.574505 -228.714208) (xy 132.5366 -228.677316) (xy 132.505053 -228.63486) (xy 132.480668 -228.587922)
			(xy 132.464066 -228.537701) (xy 132.455672 -228.485477) (xy 132.455158 -228.45903) (xy 132.455665 -228.43304)
			(xy 132.463792 -228.3817) (xy 132.47985 -228.332263) (xy 132.503444 -228.285947) (xy 132.533992 -228.243892)
			(xy 132.570744 -228.207134) (xy 132.612793 -228.176577) (xy 132.659104 -228.152974) (xy 132.708538 -228.136907)
			(xy 132.759876 -228.12877) (xy 132.785866 -228.128322) (xy 132.810237 -228.12876) (xy 132.85845 -228.135916)
			(xy 132.905094 -228.150063) (xy 132.949159 -228.170897) (xy 132.989693 -228.197966) (xy 133.02582 -228.230685)
			(xy 133.041644 -228.249226) (xy 133.044438 -228.252782) (xy 133.045454 -228.254306) (xy 133.048502 -228.257862)
			(xy 133.087872 -228.277166) (xy 133.093968 -228.276912) (xy 133.151118 -228.270054) (xy 133.181852 -228.266244)
			(xy 133.194082 -228.263453) (xy 133.213788 -228.24798) (xy 133.219444 -228.23678) (xy 133.219698 -228.23678)
			(xy 133.219698 -228.236526) (xy 133.231476 -228.210608) (xy 133.259597 -228.161106) (xy 133.275832 -228.13772)
			(xy 133.280404 -228.13137) (xy 133.290056 -228.101906) (xy 133.289918 -228.097625) (xy 133.288385 -228.089198)
			(xy 133.287008 -228.085142) (xy 133.25221 -228.002846) (xy 133.21284 -227.973128) (xy 133.200648 -227.971096)
			(xy 133.175291 -227.966311) (xy 133.126364 -227.949919) (xy 133.080578 -227.926124) (xy 133.039044 -227.895505)
			(xy 133.002772 -227.858805) (xy 132.972642 -227.816915) (xy 132.949386 -227.770853) (xy 132.933568 -227.721737)
			(xy 132.925573 -227.67076) (xy 132.925058 -227.64496) (xy 132.925568 -227.618973) (xy 132.933698 -227.567638)
			(xy 132.949759 -227.518208) (xy 132.973355 -227.471898) (xy 133.003905 -227.42985) (xy 133.040656 -227.393099)
			(xy 133.082704 -227.362549) (xy 133.129014 -227.338953) (xy 133.178444 -227.322892) (xy 133.229779 -227.314762)
			(xy 133.281753 -227.314762) (xy 133.333088 -227.322892) (xy 133.382518 -227.338953) (xy 133.428828 -227.362549)
			(xy 133.470876 -227.393099) (xy 133.507627 -227.42985) (xy 133.538177 -227.471898) (xy 133.561773 -227.518208)
			(xy 133.577834 -227.567638) (xy 133.585964 -227.618973) (xy 133.586474 -227.64496) (xy 133.586124 -227.666602)
			(xy 133.580483 -227.709515) (xy 133.569294 -227.751327) (xy 133.561328 -227.771452) (xy 133.561328 -227.771706)
			(xy 133.55838 -227.779824) (xy 133.557566 -227.797063) (xy 133.56258 -227.813578) (xy 133.567424 -227.820728)
			(xy 133.621526 -227.89261) (xy 133.628923 -227.900381) (xy 133.648403 -227.909324) (xy 133.659118 -227.909882)
			(xy 133.66496 -227.909628) (xy 133.66623 -227.909374) (xy 133.680855 -227.907932) (xy 133.710208 -227.906408)
			(xy 133.724904 -227.906326) (xy 133.79577 -227.906326) (xy 133.808085 -227.90571) (xy 133.829813 -227.894121)
			(xy 133.837172 -227.884228) (xy 133.87959 -227.821744) (xy 133.883908 -227.81514) (xy 133.888734 -227.80625)
			(xy 133.888734 -227.768658) (xy 133.885432 -227.760276) (xy 133.875826 -227.732421) (xy 133.865485 -227.674419)
			(xy 133.864858 -227.64496) (xy 133.86537 -227.618974) (xy 133.873506 -227.567642) (xy 133.88957 -227.518215)
			(xy 133.913167 -227.471908) (xy 133.943717 -227.429863) (xy 133.980468 -227.393113) (xy 134.022514 -227.362564)
			(xy 134.06882 -227.338968) (xy 134.118248 -227.322904) (xy 134.16958 -227.31477) (xy 134.195566 -227.314252)
			(xy 134.222575 -227.314794) (xy 134.275874 -227.323585) (xy 134.327034 -227.340923) (xy 134.374696 -227.366347)
			(xy 134.39648 -227.382324) (xy 134.400036 -227.384864) (xy 134.431024 -227.395532) (xy 134.440777 -227.395023)
			(xy 134.458815 -227.387584) (xy 134.466076 -227.381054) (xy 134.535164 -227.311966) (xy 134.542578 -227.303728)
			(xy 134.550098 -227.282907) (xy 134.549642 -227.271834) (xy 134.535926 -227.18776) (xy 134.508748 -227.151184)
			(xy 134.503668 -227.148644) (xy 134.478969 -227.135441) (xy 134.433665 -227.102521) (xy 134.394066 -227.06292)
			(xy 134.361149 -227.017614) (xy 134.335723 -226.967717) (xy 134.318414 -226.914457) (xy 134.309648 -226.859145)
			(xy 134.309104 -226.831144) (xy 134.309621 -226.803157) (xy 134.318372 -226.747871) (xy 134.335664 -226.694634)
			(xy 134.361072 -226.644759) (xy 134.39397 -226.599472) (xy 134.433548 -226.559891) (xy 134.478831 -226.526989)
			(xy 134.528705 -226.501576) (xy 134.581939 -226.484279) (xy 134.637225 -226.475524) (xy 134.665212 -226.475036)
			(xy 134.693213 -226.475586) (xy 134.748526 -226.484348) (xy 134.801787 -226.501654) (xy 134.851685 -226.527079)
			(xy 134.896992 -226.559995) (xy 134.936593 -226.599594) (xy 134.969512 -226.644899) (xy 134.982712 -226.6696)
			(xy 134.985252 -226.67468) (xy 135.021828 -226.701858) (xy 135.105902 -226.715574) (xy 135.116983 -226.716071)
			(xy 135.137821 -226.708552) (xy 135.146034 -226.701096) (xy 135.297418 -226.549712) (xy 135.304655 -226.542997)
			(xy 135.322861 -226.535402) (xy 135.332724 -226.53498) (xy 135.457692 -226.53498) (xy 135.467598 -226.530408)
			(xy 135.489292 -226.520918) (xy 135.534719 -226.507552) (xy 135.58159 -226.500819) (xy 135.605266 -226.500436)
			(xy 135.628939 -226.500862) (xy 135.675802 -226.507607) (xy 135.721229 -226.520949) (xy 135.742934 -226.530408)
			(xy 135.75284 -226.53498) (xy 135.94207 -226.53498) (xy 135.944864 -226.534726) (xy 135.988155 -226.530065)
			(xy 136.075166 -226.526674) (xy 136.162177 -226.530065) (xy 136.205468 -226.534726) (xy 136.208262 -226.53498)
			(xy 136.407652 -226.53498) (xy 136.41749 -226.534447) (xy 136.435654 -226.526862) (xy 136.442958 -226.520248)
			(xy 136.591294 -226.371912) (xy 136.598013 -226.364676) (xy 136.605618 -226.346471) (xy 136.606026 -226.336606)
			(xy 136.606026 -225.818954) (xy 136.605513 -225.809203) (xy 136.598068 -225.791171) (xy 136.591548 -225.783902)
			(xy 135.400288 -224.592642) (xy 135.364474 -224.62744) (xy 135.345885 -224.644697) (xy 135.304404 -224.673885)
			(xy 135.258953 -224.696397) (xy 135.210598 -224.711705) (xy 135.160472 -224.719451) (xy 135.135112 -224.719896)
			(xy 135.109143 -224.719388) (xy 135.057844 -224.711265) (xy 135.008447 -224.695218) (xy 134.962169 -224.671642)
			(xy 134.920148 -224.641116) (xy 134.883419 -224.604394) (xy 134.852887 -224.562378) (xy 134.829303 -224.516103)
			(xy 134.813248 -224.466709) (xy 134.805117 -224.415411) (xy 134.804658 -224.389442) (xy 134.805116 -224.364081)
			(xy 134.812853 -224.313953) (xy 134.828153 -224.265594) (xy 134.850656 -224.220137) (xy 134.879836 -224.178649)
			(xy 134.897114 -224.16008) (xy 134.911338 -224.124774) (xy 134.91086 -224.114808) (xy 134.903287 -224.096369)
			(xy 134.896606 -224.08896) (xy 134.71144 -223.903794) (xy 134.688326 -223.905318) (xy 134.665466 -223.90608)
			(xy 134.639822 -223.905593) (xy 134.58915 -223.897665) (xy 134.540312 -223.882003) (xy 134.494479 -223.858985)
			(xy 134.452753 -223.829162) (xy 134.416135 -223.793252) (xy 134.385504 -223.752115) (xy 134.361596 -223.70674)
			(xy 134.344985 -223.658216) (xy 134.33607 -223.607709) (xy 134.335065 -223.556431) (xy 134.341993 -223.505613)
			(xy 134.356689 -223.456475) (xy 134.3788 -223.410198) (xy 134.407794 -223.367892) (xy 134.442976 -223.330573)
			(xy 134.483501 -223.299138) (xy 134.528396 -223.27434) (xy 134.576583 -223.256776) (xy 134.626905 -223.246867)
			(xy 134.652512 -223.245426) (xy 134.70128 -223.194626) (xy 134.70128 -222.32874) (xy 134.652512 -222.27794)
			(xy 134.627217 -222.276483) (xy 134.577481 -222.266834) (xy 134.529799 -222.249706) (xy 134.485291 -222.225502)
			(xy 134.444998 -222.194788) (xy 134.409866 -222.158284) (xy 134.380716 -222.116845) (xy 134.358233 -222.071443)
			(xy 134.342943 -222.023142) (xy 134.335204 -221.973072) (xy 134.334758 -221.94774) (xy 134.335231 -221.922292)
			(xy 134.343039 -221.871999) (xy 134.358462 -221.823496) (xy 134.381135 -221.77793) (xy 134.410523 -221.736376)
			(xy 134.445932 -221.699816) (xy 134.486525 -221.669114) (xy 134.531343 -221.644995) (xy 134.579327 -221.628028)
			(xy 134.604252 -221.622874) (xy 134.627366 -221.618556) (xy 134.70128 -221.490286) (xy 134.70128 -220.700854)
			(xy 134.652512 -220.650054) (xy 134.627222 -220.648597) (xy 134.577495 -220.638948) (xy 134.529823 -220.621822)
			(xy 134.485324 -220.59762) (xy 134.44504 -220.56691) (xy 134.409917 -220.53041) (xy 134.380776 -220.488977)
			(xy 134.358301 -220.443581) (xy 134.343019 -220.395287) (xy 134.335287 -220.345226) (xy 134.335287 -220.294571)
			(xy 134.343019 -220.24451) (xy 134.358302 -220.196216) (xy 134.380778 -220.15082) (xy 134.409919 -220.109387)
			(xy 134.445043 -220.072888) (xy 134.485327 -220.042178) (xy 134.529826 -220.017976) (xy 134.577498 -220.000851)
			(xy 134.627225 -219.991203) (xy 134.652512 -219.989654) (xy 134.70128 -219.938854) (xy 134.70128 -219.073222)
			(xy 134.652512 -219.022422) (xy 134.627232 -219.020944) (xy 134.57753 -219.011258) (xy 134.529887 -218.994104)
			(xy 134.485419 -218.969883) (xy 134.445166 -218.939161) (xy 134.410071 -218.902659) (xy 134.380955 -218.86123)
			(xy 134.3585 -218.815844) (xy 134.343231 -218.767564) (xy 134.335506 -218.717519) (xy 134.335506 -218.666882)
			(xy 134.343231 -218.616838) (xy 134.358499 -218.568558) (xy 134.380954 -218.523172) (xy 134.41007 -218.481743)
			(xy 134.445165 -218.44524) (xy 134.485417 -218.414518) (xy 134.529886 -218.390296) (xy 134.577528 -218.373142)
			(xy 134.62723 -218.363456) (xy 134.652512 -218.362022) (xy 134.70128 -218.311222) (xy 134.70128 -217.445336)
			(xy 134.652512 -217.394536) (xy 134.627231 -217.393058) (xy 134.577527 -217.383372) (xy 134.529882 -217.366217)
			(xy 134.485412 -217.341995) (xy 134.445157 -217.311272) (xy 134.41006 -217.274768) (xy 134.380943 -217.233337)
			(xy 134.358487 -217.18795) (xy 134.343217 -217.139667) (xy 134.335492 -217.089621) (xy 134.335492 -217.038982)
			(xy 134.343217 -216.988935) (xy 134.358486 -216.940653) (xy 134.380942 -216.895265) (xy 134.410058 -216.853834)
			(xy 134.445155 -216.81733) (xy 134.485409 -216.786607) (xy 134.529879 -216.762384) (xy 134.577524 -216.745229)
			(xy 134.627228 -216.735542) (xy 134.652512 -216.734136) (xy 134.70128 -216.683336) (xy 134.70128 -215.966548)
			(xy 134.368794 -215.634316) (xy 133.990334 -215.634316) (xy 133.974614 -215.654553) (xy 133.937983 -215.690383)
			(xy 133.896265 -215.720137) (xy 133.850458 -215.743102) (xy 133.801658 -215.758731) (xy 133.751032 -215.766648)
			(xy 133.725412 -215.767158) (xy 133.699442 -215.766676) (xy 133.648141 -215.758553) (xy 133.598743 -215.742504)
			(xy 133.552463 -215.718925) (xy 133.510442 -215.688396) (xy 133.473714 -215.65167) (xy 133.443184 -215.60965)
			(xy 133.419602 -215.563372) (xy 133.403551 -215.513974) (xy 133.395425 -215.462674) (xy 133.394958 -215.436704)
			(xy 133.395496 -215.409771) (xy 133.404243 -215.356621) (xy 133.421489 -215.305591) (xy 133.446779 -215.258032)
			(xy 133.479444 -215.215201) (xy 133.518619 -215.178231) (xy 133.563269 -215.1481) (xy 133.612213 -215.125605)
			(xy 133.638036 -215.117934) (xy 133.652524 -215.113392) (xy 133.678147 -215.097134) (xy 133.697853 -215.074057)
			(xy 133.709897 -215.046204) (xy 133.713214 -215.01604) (xy 133.707508 -214.986235) (xy 133.693287 -214.959428)
			(xy 133.682994 -214.948262) (xy 133.611112 -214.87638) (xy 133.599918 -214.865931) (xy 133.572835 -214.851671)
			(xy 133.542747 -214.846052) (xy 133.512342 -214.849575) (xy 133.484336 -214.861926) (xy 133.472428 -214.871554)
			(xy 133.449942 -214.89037) (xy 133.399691 -214.920566) (xy 133.344903 -214.941429) (xy 133.316218 -214.9475)
			(xy 133.293358 -214.951818) (xy 133.08965 -215.304878) (xy 133.09727 -215.326976) (xy 133.106064 -215.35355)
			(xy 133.115514 -215.408718) (xy 133.116066 -215.436704) (xy 133.115557 -215.462671) (xy 133.107432 -215.513966)
			(xy 133.091384 -215.563359) (xy 133.067806 -215.609633) (xy 133.03728 -215.651649) (xy 133.000557 -215.688372)
			(xy 132.958541 -215.718898) (xy 132.912267 -215.742476) (xy 132.862874 -215.758524) (xy 132.811579 -215.766649)
			(xy 132.759645 -215.766649) (xy 132.70835 -215.758524) (xy 132.658957 -215.742476) (xy 132.612683 -215.718898)
			(xy 132.570667 -215.688372) (xy 132.533944 -215.651649) (xy 132.503418 -215.609633) (xy 132.47984 -215.563359)
			(xy 132.463792 -215.513966) (xy 132.455667 -215.462671) (xy 132.455158 -215.436704) (xy 132.455634 -215.411258)
			(xy 132.463446 -215.360969) (xy 132.478873 -215.31247) (xy 132.501548 -215.266908) (xy 132.530937 -215.225359)
			(xy 132.566346 -215.188804) (xy 132.606937 -215.158106) (xy 132.651753 -215.13399) (xy 132.699735 -215.117026)
			(xy 132.724652 -215.111838) (xy 132.747512 -215.10752) (xy 132.95122 -214.75446) (xy 132.9436 -214.732362)
			(xy 132.934804 -214.705788) (xy 132.925348 -214.65062) (xy 132.924804 -214.622634) (xy 132.925237 -214.598923)
			(xy 132.932059 -214.551994) (xy 132.94551 -214.506519) (xy 132.965316 -214.46343) (xy 132.99107 -214.42361)
			(xy 133.006338 -214.405464) (xy 133.016004 -214.393578) (xy 133.028382 -214.365567) (xy 133.031912 -214.335147)
			(xy 133.026278 -214.305046) (xy 133.011985 -214.277962) (xy 133.001512 -214.26678) (xy 132.798312 -214.06358)
			(xy 132.777992 -214.063072) (xy 132.751103 -214.061912) (xy 132.698218 -214.051944) (xy 132.64765 -214.033528)
			(xy 132.60074 -214.007152) (xy 132.558731 -213.973515) (xy 132.522734 -213.933509) (xy 132.493705 -213.888193)
			(xy 132.48259 -213.863682) (xy 132.469128 -213.832948) (xy 132.162804 -213.832948) (xy 132.149342 -213.863682)
			(xy 132.147818 -213.867238) (xy 132.137658 -213.889844) (xy 132.35051 -214.293196) (xy 132.374894 -214.297514)
			(xy 132.399926 -214.302572) (xy 132.448151 -214.319374) (xy 132.493216 -214.343397) (xy 132.534047 -214.374068)
			(xy 132.569673 -214.410657) (xy 132.599244 -214.452292) (xy 132.622056 -214.497981) (xy 132.637566 -214.546637)
			(xy 132.645403 -214.5971) (xy 132.645912 -214.622634) (xy 132.645403 -214.648601) (xy 132.637278 -214.699896)
			(xy 132.62123 -214.749289) (xy 132.597652 -214.795563) (xy 132.567126 -214.837579) (xy 132.530403 -214.874302)
			(xy 132.488387 -214.904828) (xy 132.442113 -214.928406) (xy 132.39272 -214.944454) (xy 132.341425 -214.952579)
			(xy 132.289491 -214.952579) (xy 132.238196 -214.944454) (xy 132.188803 -214.928406) (xy 132.142529 -214.904828)
			(xy 132.100513 -214.874302) (xy 132.06379 -214.837579) (xy 132.033264 -214.795563) (xy 132.009686 -214.749289)
			(xy 131.993638 -214.699896) (xy 131.985513 -214.648601) (xy 131.985004 -214.622634) (xy 131.985391 -214.599513)
			(xy 131.991848 -214.553724) (xy 132.00464 -214.509287) (xy 132.013706 -214.488014) (xy 132.023866 -214.465408)
			(xy 131.811014 -214.062056) (xy 131.78663 -214.057738) (xy 131.760102 -214.05235) (xy 131.709149 -214.034083)
			(xy 131.66186 -214.007746) (xy 131.619503 -213.974044) (xy 131.583215 -213.933882) (xy 131.553967 -213.888336)
			(xy 131.54279 -213.863682) (xy 131.529328 -213.832948) (xy 131.223004 -213.832948) (xy 131.209542 -213.863682)
			(xy 131.198932 -213.887015) (xy 131.171578 -213.930359) (xy 131.137858 -213.968959) (xy 131.098582 -214.001888)
			(xy 131.054692 -214.028357) (xy 131.00724 -214.047731) (xy 130.957366 -214.059544) (xy 130.906266 -214.063514)
			(xy 130.855166 -214.059544) (xy 130.805292 -214.047731) (xy 130.75784 -214.028357) (xy 130.71395 -214.001888)
			(xy 130.674674 -213.968959) (xy 130.640954 -213.930359) (xy 130.6136 -213.887015) (xy 130.60299 -213.863682)
			(xy 130.589528 -213.832948) (xy 130.283204 -213.832948) (xy 130.269742 -213.863682) (xy 130.268218 -213.867238)
			(xy 130.258058 -213.889844) (xy 130.47091 -214.293196) (xy 130.495294 -214.297514) (xy 130.520326 -214.302572)
			(xy 130.568551 -214.319374) (xy 130.613616 -214.343397) (xy 130.654447 -214.374068) (xy 130.690073 -214.410657)
			(xy 130.719644 -214.452292) (xy 130.742456 -214.497981) (xy 130.757966 -214.546637) (xy 130.765803 -214.5971)
			(xy 130.766312 -214.622634) (xy 130.765803 -214.648601) (xy 130.757678 -214.699896) (xy 130.74163 -214.749289)
			(xy 130.718052 -214.795563) (xy 130.687526 -214.837579) (xy 130.650803 -214.874302) (xy 130.608787 -214.904828)
			(xy 130.562513 -214.928406) (xy 130.51312 -214.944454) (xy 130.461825 -214.952579) (xy 130.409891 -214.952579)
			(xy 130.358596 -214.944454) (xy 130.309203 -214.928406) (xy 130.262929 -214.904828) (xy 130.220913 -214.874302)
			(xy 130.18419 -214.837579) (xy 130.153664 -214.795563) (xy 130.130086 -214.749289) (xy 130.114038 -214.699896)
			(xy 130.105913 -214.648601) (xy 130.105404 -214.622634) (xy 130.105791 -214.599513) (xy 130.112248 -214.553724)
			(xy 130.12504 -214.509287) (xy 130.134106 -214.488014) (xy 130.144266 -214.465408) (xy 129.931414 -214.062056)
			(xy 129.90703 -214.057738) (xy 129.880502 -214.05235) (xy 129.829549 -214.034083) (xy 129.78226 -214.007746)
			(xy 129.739903 -213.974044) (xy 129.703615 -213.933882) (xy 129.674367 -213.888336) (xy 129.66319 -213.863682)
			(xy 129.649728 -213.832948) (xy 129.343404 -213.832948) (xy 129.329942 -213.863682) (xy 129.319332 -213.887015)
			(xy 129.291978 -213.930359) (xy 129.258258 -213.968959) (xy 129.218982 -214.001888) (xy 129.175092 -214.028357)
			(xy 129.12764 -214.047731) (xy 129.077766 -214.059544) (xy 129.026666 -214.063514) (xy 128.975566 -214.059544)
			(xy 128.925692 -214.047731) (xy 128.87824 -214.028357) (xy 128.83435 -214.001888) (xy 128.795074 -213.968959)
			(xy 128.761354 -213.930359) (xy 128.734 -213.887015) (xy 128.72339 -213.863682) (xy 128.709928 -213.832948)
			(xy 128.403604 -213.832948) (xy 128.390142 -213.863682) (xy 128.388618 -213.867238) (xy 128.378458 -213.889844)
			(xy 128.59131 -214.293196) (xy 128.615694 -214.297514) (xy 128.640726 -214.302572) (xy 128.688951 -214.319374)
			(xy 128.734016 -214.343397) (xy 128.774847 -214.374068) (xy 128.810473 -214.410657) (xy 128.840044 -214.452292)
			(xy 128.862856 -214.497981) (xy 128.878366 -214.546637) (xy 128.886203 -214.5971) (xy 128.886712 -214.622634)
			(xy 128.886203 -214.648601) (xy 128.878078 -214.699896) (xy 128.86203 -214.749289) (xy 128.838452 -214.795563)
			(xy 128.807926 -214.837579) (xy 128.771203 -214.874302) (xy 128.729187 -214.904828) (xy 128.682913 -214.928406)
			(xy 128.63352 -214.944454) (xy 128.582225 -214.952579) (xy 128.530291 -214.952579) (xy 128.478996 -214.944454)
			(xy 128.429603 -214.928406) (xy 128.383329 -214.904828) (xy 128.341313 -214.874302) (xy 128.30459 -214.837579)
			(xy 128.274064 -214.795563) (xy 128.250486 -214.749289) (xy 128.234438 -214.699896) (xy 128.226313 -214.648601)
			(xy 128.225804 -214.622634) (xy 128.226191 -214.599513) (xy 128.232648 -214.553724) (xy 128.24544 -214.509287)
			(xy 128.254506 -214.488014) (xy 128.264666 -214.465408) (xy 128.051814 -214.062056) (xy 128.02743 -214.057738)
			(xy 128.000902 -214.05235) (xy 127.949949 -214.034083) (xy 127.90266 -214.007746) (xy 127.860303 -213.974044)
			(xy 127.824015 -213.933882) (xy 127.794767 -213.888336) (xy 127.78359 -213.863682) (xy 127.770128 -213.832948)
			(xy 127.463804 -213.832948) (xy 127.450342 -213.863682) (xy 127.439732 -213.887015) (xy 127.412378 -213.930359)
			(xy 127.378658 -213.968959) (xy 127.339382 -214.001888) (xy 127.295492 -214.028357) (xy 127.24804 -214.047731)
			(xy 127.198166 -214.059544) (xy 127.147066 -214.063514) (xy 127.095966 -214.059544) (xy 127.046092 -214.047731)
			(xy 126.99864 -214.028357) (xy 126.95475 -214.001888) (xy 126.915474 -213.968959) (xy 126.881754 -213.930359)
			(xy 126.8544 -213.887015) (xy 126.84379 -213.863682) (xy 126.830328 -213.832948) (xy 126.52375 -213.832948)
			(xy 126.510288 -213.863682) (xy 126.508764 -213.866984) (xy 126.498858 -213.88959) (xy 126.71171 -214.293196)
			(xy 126.736094 -214.297514) (xy 126.761126 -214.302572) (xy 126.809351 -214.319374) (xy 126.854416 -214.343397)
			(xy 126.895247 -214.374068) (xy 126.930873 -214.410657) (xy 126.960444 -214.452292) (xy 126.983256 -214.497981)
			(xy 126.998766 -214.546637) (xy 127.006603 -214.5971) (xy 127.007112 -214.622634) (xy 127.006603 -214.648601)
			(xy 126.998478 -214.699896) (xy 126.98243 -214.749289) (xy 126.958852 -214.795563) (xy 126.928326 -214.837579)
			(xy 126.891603 -214.874302) (xy 126.849587 -214.904828) (xy 126.803313 -214.928406) (xy 126.75392 -214.944454)
			(xy 126.702625 -214.952579) (xy 126.650691 -214.952579) (xy 126.599396 -214.944454) (xy 126.550003 -214.928406)
			(xy 126.503729 -214.904828) (xy 126.461713 -214.874302) (xy 126.42499 -214.837579) (xy 126.394464 -214.795563)
			(xy 126.370886 -214.749289) (xy 126.354838 -214.699896) (xy 126.346713 -214.648601) (xy 126.346204 -214.622634)
			(xy 126.346591 -214.599513) (xy 126.353048 -214.553724) (xy 126.36584 -214.509287) (xy 126.374906 -214.488014)
			(xy 126.385066 -214.465408) (xy 126.172214 -214.062056) (xy 126.14783 -214.057738) (xy 126.121284 -214.052357)
			(xy 126.070295 -214.034101) (xy 126.022968 -214.007767) (xy 125.980574 -213.974063) (xy 125.944249 -213.933891)
			(xy 125.914967 -213.888329) (xy 125.903736 -213.863682) (xy 125.890274 -213.832948) (xy 125.584204 -213.832948)
			(xy 125.570742 -213.863682) (xy 125.560132 -213.887015) (xy 125.532778 -213.930359) (xy 125.499058 -213.968959)
			(xy 125.459782 -214.001888) (xy 125.415892 -214.028357) (xy 125.36844 -214.047731) (xy 125.318566 -214.059544)
			(xy 125.267466 -214.063514) (xy 125.216366 -214.059544) (xy 125.166492 -214.047731) (xy 125.11904 -214.028357)
			(xy 125.07515 -214.001888) (xy 125.035874 -213.968959) (xy 125.002154 -213.930359) (xy 124.9748 -213.887015)
			(xy 124.96419 -213.863682) (xy 124.950728 -213.832948) (xy 124.64415 -213.832948) (xy 124.630688 -213.863682)
			(xy 124.625862 -213.874604) (xy 124.61494 -213.897464) (xy 124.819664 -214.291926) (xy 124.845318 -214.295736)
			(xy 124.871125 -214.300053) (xy 124.921032 -214.315761) (xy 124.967841 -214.339135) (xy 125.010383 -214.369593)
			(xy 125.047595 -214.406372) (xy 125.078548 -214.448555) (xy 125.102468 -214.495088) (xy 125.118758 -214.544808)
			(xy 125.127012 -214.596474) (xy 125.127512 -214.622634) (xy 125.127003 -214.648601) (xy 125.118878 -214.699896)
			(xy 125.10283 -214.749289) (xy 125.079252 -214.795563) (xy 125.048726 -214.837579) (xy 125.012003 -214.874302)
			(xy 124.969987 -214.904828) (xy 124.923713 -214.928406) (xy 124.87432 -214.944454) (xy 124.823025 -214.952579)
			(xy 124.771091 -214.952579) (xy 124.719796 -214.944454) (xy 124.670403 -214.928406) (xy 124.624129 -214.904828)
			(xy 124.582113 -214.874302) (xy 124.54539 -214.837579) (xy 124.514864 -214.795563) (xy 124.491286 -214.749289)
			(xy 124.475238 -214.699896) (xy 124.467113 -214.648601) (xy 124.466604 -214.622634) (xy 124.466604 -214.622126)
			(xy 124.467112 -214.596469) (xy 124.475092 -214.545778) (xy 124.490819 -214.496932) (xy 124.50191 -214.47379)
			(xy 124.513594 -214.450676) (xy 124.312934 -214.063834) (xy 124.286518 -214.060532) (xy 124.262231 -214.057057)
			(xy 124.214978 -214.043859) (xy 124.170198 -214.023814) (xy 124.128878 -213.997363) (xy 124.091927 -213.965088)
			(xy 124.060159 -213.927701) (xy 124.034273 -213.886025) (xy 124.024136 -213.863682) (xy 124.010674 -213.832948)
			(xy 123.704604 -213.832948) (xy 123.691142 -213.863682) (xy 123.680532 -213.887015) (xy 123.653178 -213.930359)
			(xy 123.619458 -213.968959) (xy 123.580182 -214.001888) (xy 123.536292 -214.028357) (xy 123.48884 -214.047731)
			(xy 123.438966 -214.059544) (xy 123.387866 -214.063514) (xy 123.336766 -214.059544) (xy 123.286892 -214.047731)
			(xy 123.23944 -214.028357) (xy 123.19555 -214.001888) (xy 123.156274 -213.968959) (xy 123.122554 -213.930359)
			(xy 123.0952 -213.887015) (xy 123.08459 -213.863682) (xy 123.071128 -213.832948) (xy 122.764804 -213.832948)
			(xy 122.751342 -213.863682) (xy 122.749818 -213.867238) (xy 122.739658 -213.889844) (xy 122.95251 -214.293196)
			(xy 122.976894 -214.297514) (xy 123.001926 -214.302572) (xy 123.050151 -214.319374) (xy 123.095216 -214.343397)
			(xy 123.136047 -214.374068) (xy 123.171673 -214.410657) (xy 123.201244 -214.452292) (xy 123.224056 -214.497981)
			(xy 123.239566 -214.546637) (xy 123.247403 -214.5971) (xy 123.247912 -214.622634) (xy 123.247403 -214.648601)
			(xy 123.239278 -214.699896) (xy 123.22323 -214.749289) (xy 123.199652 -214.795563) (xy 123.169126 -214.837579)
			(xy 123.132403 -214.874302) (xy 123.090387 -214.904828) (xy 123.044113 -214.928406) (xy 122.99472 -214.944454)
			(xy 122.943425 -214.952579) (xy 122.891491 -214.952579) (xy 122.840196 -214.944454) (xy 122.790803 -214.928406)
			(xy 122.744529 -214.904828) (xy 122.702513 -214.874302) (xy 122.66579 -214.837579) (xy 122.635264 -214.795563)
			(xy 122.611686 -214.749289) (xy 122.595638 -214.699896) (xy 122.587513 -214.648601) (xy 122.587004 -214.622634)
			(xy 122.587391 -214.599513) (xy 122.593848 -214.553724) (xy 122.60664 -214.509287) (xy 122.615706 -214.488014)
			(xy 122.625866 -214.465408) (xy 122.413014 -214.062056) (xy 122.38863 -214.057738) (xy 122.362102 -214.05235)
			(xy 122.311149 -214.034083) (xy 122.26386 -214.007746) (xy 122.221503 -213.974044) (xy 122.185215 -213.933882)
			(xy 122.155967 -213.888336) (xy 122.14479 -213.863682) (xy 122.131328 -213.832948) (xy 121.825004 -213.832948)
			(xy 121.811542 -213.863682) (xy 121.800146 -213.888674) (xy 121.770318 -213.934794) (xy 121.733278 -213.975349)
			(xy 121.690045 -214.009226) (xy 121.641808 -214.035491) (xy 121.589893 -214.053422) (xy 121.535728 -214.062527)
			(xy 121.508266 -214.063072) (xy 121.484347 -214.062653) (xy 121.437006 -214.055767) (xy 121.391153 -214.042129)
			(xy 121.347744 -214.022024) (xy 121.307686 -213.995872) (xy 121.271817 -213.964218) (xy 121.256044 -213.946232)
			(xy 121.246626 -213.935843) (xy 121.223347 -213.920229) (xy 121.196702 -213.911527) (xy 121.168694 -213.910392)
			(xy 121.141432 -213.91691) (xy 121.116966 -213.93059) (xy 121.106692 -213.940136) (xy 121.01068 -214.036148)
			(xy 121.01068 -214.175086) (xy 121.07291 -214.293196) (xy 121.097294 -214.297514) (xy 121.122326 -214.302572)
			(xy 121.170551 -214.319374) (xy 121.215616 -214.343397) (xy 121.256447 -214.374068) (xy 121.292073 -214.410657)
			(xy 121.321644 -214.452292) (xy 121.344456 -214.497981) (xy 121.359966 -214.546637) (xy 121.367803 -214.5971)
			(xy 121.368312 -214.622634) (xy 121.367862 -214.647577) (xy 121.360375 -214.696896) (xy 121.345562 -214.744531)
			(xy 121.323757 -214.789398) (xy 121.295458 -214.830479) (xy 121.261307 -214.866841) (xy 121.222078 -214.897657)
			(xy 121.178664 -214.922228) (xy 121.132051 -214.939996) (xy 121.083297 -214.950557) (xy 121.058432 -214.95258)
			(xy 121.01068 -215.003126) (xy 121.01068 -215.436704) (xy 121.177558 -215.436704) (xy 121.178039 -215.411253)
			(xy 121.185817 -215.360948) (xy 121.20122 -215.312433) (xy 121.223883 -215.266854) (xy 121.25327 -215.225292)
			(xy 121.288685 -215.18873) (xy 121.32929 -215.158033) (xy 121.374123 -215.133929) (xy 121.422123 -215.116988)
			(xy 121.447052 -215.111838) (xy 121.469912 -215.10752) (xy 121.67362 -214.75446) (xy 121.666 -214.732362)
			(xy 121.657253 -214.705776) (xy 121.647812 -214.650615) (xy 121.647204 -214.622634) (xy 121.647713 -214.596667)
			(xy 121.655838 -214.545372) (xy 121.671886 -214.495979) (xy 121.695464 -214.449705) (xy 121.72599 -214.407689)
			(xy 121.762713 -214.370966) (xy 121.804729 -214.34044) (xy 121.851003 -214.316862) (xy 121.900396 -214.300814)
			(xy 121.951691 -214.292689) (xy 122.003625 -214.292689) (xy 122.05492 -214.300814) (xy 122.104313 -214.316862)
			(xy 122.150587 -214.34044) (xy 122.192603 -214.370966) (xy 122.229326 -214.407689) (xy 122.259852 -214.449705)
			(xy 122.28343 -214.495979) (xy 122.299478 -214.545372) (xy 122.307603 -214.596667) (xy 122.308112 -214.622634)
			(xy 122.307689 -214.648088) (xy 122.299905 -214.698396) (xy 122.284496 -214.746914) (xy 122.261825 -214.792494)
			(xy 122.232431 -214.834057) (xy 122.197008 -214.870619) (xy 122.156396 -214.901314) (xy 122.111556 -214.925415)
			(xy 122.06355 -214.942352) (xy 122.038618 -214.9475) (xy 122.015758 -214.951818) (xy 121.81205 -215.304878)
			(xy 121.81967 -215.326976) (xy 121.828401 -215.353566) (xy 121.837853 -215.408724) (xy 121.838466 -215.436704)
			(xy 121.837957 -215.462671) (xy 122.117867 -215.462671) (xy 122.117867 -215.410737) (xy 122.125992 -215.359442)
			(xy 122.14204 -215.310049) (xy 122.165618 -215.263775) (xy 122.196144 -215.221759) (xy 122.232867 -215.185036)
			(xy 122.274883 -215.15451) (xy 122.321157 -215.130932) (xy 122.37055 -215.114884) (xy 122.421845 -215.106759)
			(xy 122.473779 -215.106759) (xy 122.525074 -215.114884) (xy 122.574467 -215.130932) (xy 122.620741 -215.15451)
			(xy 122.662757 -215.185036) (xy 122.69948 -215.221759) (xy 122.730006 -215.263775) (xy 122.753584 -215.310049)
			(xy 122.769632 -215.359442) (xy 122.777757 -215.410737) (xy 122.778266 -215.436704) (xy 123.057158 -215.436704)
			(xy 123.057639 -215.411253) (xy 123.065417 -215.360948) (xy 123.08082 -215.312433) (xy 123.103483 -215.266854)
			(xy 123.13287 -215.225292) (xy 123.168285 -215.18873) (xy 123.20889 -215.158033) (xy 123.253723 -215.133929)
			(xy 123.301723 -215.116988) (xy 123.326652 -215.111838) (xy 123.349512 -215.10752) (xy 123.55322 -214.75446)
			(xy 123.5456 -214.732362) (xy 123.536853 -214.705776) (xy 123.527412 -214.650615) (xy 123.526804 -214.622634)
			(xy 123.527313 -214.596667) (xy 123.535438 -214.545372) (xy 123.551486 -214.495979) (xy 123.575064 -214.449705)
			(xy 123.60559 -214.407689) (xy 123.642313 -214.370966) (xy 123.684329 -214.34044) (xy 123.730603 -214.316862)
			(xy 123.779996 -214.300814) (xy 123.831291 -214.292689) (xy 123.883225 -214.292689) (xy 123.93452 -214.300814)
			(xy 123.983913 -214.316862) (xy 124.030187 -214.34044) (xy 124.072203 -214.370966) (xy 124.108926 -214.407689)
			(xy 124.139452 -214.449705) (xy 124.16303 -214.495979) (xy 124.179078 -214.545372) (xy 124.187203 -214.596667)
			(xy 124.187712 -214.622634) (xy 124.187289 -214.648088) (xy 124.179505 -214.698396) (xy 124.164096 -214.746914)
			(xy 124.141425 -214.792494) (xy 124.112031 -214.834057) (xy 124.076608 -214.870619) (xy 124.035996 -214.901314)
			(xy 123.991156 -214.925415) (xy 123.94315 -214.942352) (xy 123.918218 -214.9475) (xy 123.895358 -214.951818)
			(xy 123.69165 -215.304878) (xy 123.69927 -215.326976) (xy 123.708001 -215.353566) (xy 123.717453 -215.408724)
			(xy 123.718066 -215.436704) (xy 123.717557 -215.462671) (xy 123.997467 -215.462671) (xy 123.997467 -215.410737)
			(xy 124.005592 -215.359442) (xy 124.02164 -215.310049) (xy 124.045218 -215.263775) (xy 124.075744 -215.221759)
			(xy 124.112467 -215.185036) (xy 124.154483 -215.15451) (xy 124.200757 -215.130932) (xy 124.25015 -215.114884)
			(xy 124.301445 -215.106759) (xy 124.353379 -215.106759) (xy 124.404674 -215.114884) (xy 124.454067 -215.130932)
			(xy 124.500341 -215.15451) (xy 124.542357 -215.185036) (xy 124.57908 -215.221759) (xy 124.609606 -215.263775)
			(xy 124.633184 -215.310049) (xy 124.649232 -215.359442) (xy 124.657357 -215.410737) (xy 124.657866 -215.436704)
			(xy 124.936758 -215.436704) (xy 124.937239 -215.411253) (xy 124.945017 -215.360948) (xy 124.96042 -215.312433)
			(xy 124.983083 -215.266854) (xy 125.01247 -215.225292) (xy 125.047885 -215.18873) (xy 125.08849 -215.158033)
			(xy 125.133323 -215.133929) (xy 125.181323 -215.116988) (xy 125.206252 -215.111838) (xy 125.229112 -215.10752)
			(xy 125.43282 -214.75446) (xy 125.4252 -214.732362) (xy 125.416453 -214.705776) (xy 125.407012 -214.650615)
			(xy 125.406404 -214.622634) (xy 125.406913 -214.596667) (xy 125.415038 -214.545372) (xy 125.431086 -214.495979)
			(xy 125.454664 -214.449705) (xy 125.48519 -214.407689) (xy 125.521913 -214.370966) (xy 125.563929 -214.34044)
			(xy 125.610203 -214.316862) (xy 125.659596 -214.300814) (xy 125.710891 -214.292689) (xy 125.762825 -214.292689)
			(xy 125.81412 -214.300814) (xy 125.863513 -214.316862) (xy 125.909787 -214.34044) (xy 125.951803 -214.370966)
			(xy 125.988526 -214.407689) (xy 126.019052 -214.449705) (xy 126.04263 -214.495979) (xy 126.058678 -214.545372)
			(xy 126.066803 -214.596667) (xy 126.067312 -214.622634) (xy 126.066889 -214.648088) (xy 126.059105 -214.698396)
			(xy 126.043696 -214.746914) (xy 126.021025 -214.792494) (xy 125.991631 -214.834057) (xy 125.956208 -214.870619)
			(xy 125.915596 -214.901314) (xy 125.870756 -214.925415) (xy 125.82275 -214.942352) (xy 125.797818 -214.9475)
			(xy 125.774958 -214.951818) (xy 125.57125 -215.304878) (xy 125.57887 -215.326976) (xy 125.587601 -215.353566)
			(xy 125.597053 -215.408724) (xy 125.597666 -215.436704) (xy 125.597157 -215.462671) (xy 125.877067 -215.462671)
			(xy 125.877067 -215.410737) (xy 125.885192 -215.359442) (xy 125.90124 -215.310049) (xy 125.924818 -215.263775)
			(xy 125.955344 -215.221759) (xy 125.992067 -215.185036) (xy 126.034083 -215.15451) (xy 126.080357 -215.130932)
			(xy 126.12975 -215.114884) (xy 126.181045 -215.106759) (xy 126.232979 -215.106759) (xy 126.284274 -215.114884)
			(xy 126.333667 -215.130932) (xy 126.379941 -215.15451) (xy 126.421957 -215.185036) (xy 126.45868 -215.221759)
			(xy 126.489206 -215.263775) (xy 126.512784 -215.310049) (xy 126.528832 -215.359442) (xy 126.536957 -215.410737)
			(xy 126.537466 -215.436704) (xy 126.816358 -215.436704) (xy 126.816839 -215.411253) (xy 126.824617 -215.360948)
			(xy 126.84002 -215.312433) (xy 126.862683 -215.266854) (xy 126.89207 -215.225292) (xy 126.927485 -215.18873)
			(xy 126.96809 -215.158033) (xy 127.012923 -215.133929) (xy 127.060923 -215.116988) (xy 127.085852 -215.111838)
			(xy 127.108712 -215.10752) (xy 127.31242 -214.75446) (xy 127.3048 -214.732362) (xy 127.296053 -214.705776)
			(xy 127.286612 -214.650615) (xy 127.286004 -214.622634) (xy 127.286513 -214.596667) (xy 127.294638 -214.545372)
			(xy 127.310686 -214.495979) (xy 127.334264 -214.449705) (xy 127.36479 -214.407689) (xy 127.401513 -214.370966)
			(xy 127.443529 -214.34044) (xy 127.489803 -214.316862) (xy 127.539196 -214.300814) (xy 127.590491 -214.292689)
			(xy 127.642425 -214.292689) (xy 127.69372 -214.300814) (xy 127.743113 -214.316862) (xy 127.789387 -214.34044)
			(xy 127.831403 -214.370966) (xy 127.868126 -214.407689) (xy 127.898652 -214.449705) (xy 127.92223 -214.495979)
			(xy 127.938278 -214.545372) (xy 127.946403 -214.596667) (xy 127.946912 -214.622634) (xy 127.946489 -214.648088)
			(xy 127.938705 -214.698396) (xy 127.923296 -214.746914) (xy 127.900625 -214.792494) (xy 127.871231 -214.834057)
			(xy 127.835808 -214.870619) (xy 127.795196 -214.901314) (xy 127.750356 -214.925415) (xy 127.70235 -214.942352)
			(xy 127.677418 -214.9475) (xy 127.654558 -214.951818) (xy 127.45085 -215.304878) (xy 127.45847 -215.326976)
			(xy 127.467201 -215.353566) (xy 127.476653 -215.408724) (xy 127.477266 -215.436704) (xy 128.695958 -215.436704)
			(xy 128.696439 -215.411253) (xy 128.704217 -215.360948) (xy 128.71962 -215.312433) (xy 128.742283 -215.266854)
			(xy 128.77167 -215.225292) (xy 128.807085 -215.18873) (xy 128.84769 -215.158033) (xy 128.892523 -215.133929)
			(xy 128.940523 -215.116988) (xy 128.965452 -215.111838) (xy 128.988312 -215.10752) (xy 129.19202 -214.75446)
			(xy 129.1844 -214.732362) (xy 129.175653 -214.705776) (xy 129.166212 -214.650615) (xy 129.165604 -214.622634)
			(xy 129.166113 -214.596667) (xy 129.174238 -214.545372) (xy 129.190286 -214.495979) (xy 129.213864 -214.449705)
			(xy 129.24439 -214.407689) (xy 129.281113 -214.370966) (xy 129.323129 -214.34044) (xy 129.369403 -214.316862)
			(xy 129.418796 -214.300814) (xy 129.470091 -214.292689) (xy 129.522025 -214.292689) (xy 129.57332 -214.300814)
			(xy 129.622713 -214.316862) (xy 129.668987 -214.34044) (xy 129.711003 -214.370966) (xy 129.747726 -214.407689)
			(xy 129.778252 -214.449705) (xy 129.80183 -214.495979) (xy 129.817878 -214.545372) (xy 129.826003 -214.596667)
			(xy 129.826512 -214.622634) (xy 129.826089 -214.648088) (xy 129.818305 -214.698396) (xy 129.802896 -214.746914)
			(xy 129.780225 -214.792494) (xy 129.750831 -214.834057) (xy 129.715408 -214.870619) (xy 129.674796 -214.901314)
			(xy 129.629956 -214.925415) (xy 129.58195 -214.942352) (xy 129.557018 -214.9475) (xy 129.534158 -214.951818)
			(xy 129.33045 -215.304878) (xy 129.33807 -215.326976) (xy 129.346801 -215.353566) (xy 129.356253 -215.408724)
			(xy 129.356866 -215.436704) (xy 130.575558 -215.436704) (xy 130.576039 -215.411253) (xy 130.583817 -215.360948)
			(xy 130.59922 -215.312433) (xy 130.621883 -215.266854) (xy 130.65127 -215.225292) (xy 130.686685 -215.18873)
			(xy 130.72729 -215.158033) (xy 130.772123 -215.133929) (xy 130.820123 -215.116988) (xy 130.845052 -215.111838)
			(xy 130.867912 -215.10752) (xy 131.07162 -214.75446) (xy 131.064 -214.732362) (xy 131.055253 -214.705776)
			(xy 131.045812 -214.650615) (xy 131.045204 -214.622634) (xy 131.045713 -214.596667) (xy 131.053838 -214.545372)
			(xy 131.069886 -214.495979) (xy 131.093464 -214.449705) (xy 131.12399 -214.407689) (xy 131.160713 -214.370966)
			(xy 131.202729 -214.34044) (xy 131.249003 -214.316862) (xy 131.298396 -214.300814) (xy 131.349691 -214.292689)
			(xy 131.401625 -214.292689) (xy 131.45292 -214.300814) (xy 131.502313 -214.316862) (xy 131.548587 -214.34044)
			(xy 131.590603 -214.370966) (xy 131.627326 -214.407689) (xy 131.657852 -214.449705) (xy 131.68143 -214.495979)
			(xy 131.697478 -214.545372) (xy 131.705603 -214.596667) (xy 131.706112 -214.622634) (xy 131.705689 -214.648088)
			(xy 131.697905 -214.698396) (xy 131.682496 -214.746914) (xy 131.659825 -214.792494) (xy 131.630431 -214.834057)
			(xy 131.595008 -214.870619) (xy 131.554396 -214.901314) (xy 131.509556 -214.925415) (xy 131.46155 -214.942352)
			(xy 131.436618 -214.9475) (xy 131.413758 -214.951818) (xy 131.21005 -215.304878) (xy 131.21767 -215.326976)
			(xy 131.226401 -215.353566) (xy 131.235853 -215.408724) (xy 131.236466 -215.436704) (xy 131.235957 -215.462671)
			(xy 131.227832 -215.513966) (xy 131.211784 -215.563359) (xy 131.188206 -215.609633) (xy 131.15768 -215.651649)
			(xy 131.120957 -215.688372) (xy 131.078941 -215.718898) (xy 131.032667 -215.742476) (xy 130.983274 -215.758524)
			(xy 130.931979 -215.766649) (xy 130.880045 -215.766649) (xy 130.82875 -215.758524) (xy 130.779357 -215.742476)
			(xy 130.733083 -215.718898) (xy 130.691067 -215.688372) (xy 130.654344 -215.651649) (xy 130.623818 -215.609633)
			(xy 130.60024 -215.563359) (xy 130.584192 -215.513966) (xy 130.576067 -215.462671) (xy 130.575558 -215.436704)
			(xy 129.356866 -215.436704) (xy 129.356357 -215.462671) (xy 129.348232 -215.513966) (xy 129.332184 -215.563359)
			(xy 129.308606 -215.609633) (xy 129.27808 -215.651649) (xy 129.241357 -215.688372) (xy 129.199341 -215.718898)
			(xy 129.153067 -215.742476) (xy 129.103674 -215.758524) (xy 129.052379 -215.766649) (xy 129.000445 -215.766649)
			(xy 128.94915 -215.758524) (xy 128.899757 -215.742476) (xy 128.853483 -215.718898) (xy 128.811467 -215.688372)
			(xy 128.774744 -215.651649) (xy 128.744218 -215.609633) (xy 128.72064 -215.563359) (xy 128.704592 -215.513966)
			(xy 128.696467 -215.462671) (xy 128.695958 -215.436704) (xy 127.477266 -215.436704) (xy 127.476757 -215.462671)
			(xy 127.468632 -215.513966) (xy 127.452584 -215.563359) (xy 127.429006 -215.609633) (xy 127.39848 -215.651649)
			(xy 127.361757 -215.688372) (xy 127.319741 -215.718898) (xy 127.273467 -215.742476) (xy 127.224074 -215.758524)
			(xy 127.172779 -215.766649) (xy 127.120845 -215.766649) (xy 127.06955 -215.758524) (xy 127.020157 -215.742476)
			(xy 126.973883 -215.718898) (xy 126.931867 -215.688372) (xy 126.895144 -215.651649) (xy 126.864618 -215.609633)
			(xy 126.84104 -215.563359) (xy 126.824992 -215.513966) (xy 126.816867 -215.462671) (xy 126.816358 -215.436704)
			(xy 126.537466 -215.436704) (xy 126.536957 -215.462671) (xy 126.528832 -215.513966) (xy 126.512784 -215.563359)
			(xy 126.489206 -215.609633) (xy 126.45868 -215.651649) (xy 126.421957 -215.688372) (xy 126.379941 -215.718898)
			(xy 126.333667 -215.742476) (xy 126.284274 -215.758524) (xy 126.232979 -215.766649) (xy 126.181045 -215.766649)
			(xy 126.12975 -215.758524) (xy 126.080357 -215.742476) (xy 126.034083 -215.718898) (xy 125.992067 -215.688372)
			(xy 125.955344 -215.651649) (xy 125.924818 -215.609633) (xy 125.90124 -215.563359) (xy 125.885192 -215.513966)
			(xy 125.877067 -215.462671) (xy 125.597157 -215.462671) (xy 125.589032 -215.513966) (xy 125.572984 -215.563359)
			(xy 125.549406 -215.609633) (xy 125.51888 -215.651649) (xy 125.482157 -215.688372) (xy 125.440141 -215.718898)
			(xy 125.393867 -215.742476) (xy 125.344474 -215.758524) (xy 125.293179 -215.766649) (xy 125.241245 -215.766649)
			(xy 125.18995 -215.758524) (xy 125.140557 -215.742476) (xy 125.094283 -215.718898) (xy 125.052267 -215.688372)
			(xy 125.015544 -215.651649) (xy 124.985018 -215.609633) (xy 124.96144 -215.563359) (xy 124.945392 -215.513966)
			(xy 124.937267 -215.462671) (xy 124.936758 -215.436704) (xy 124.657866 -215.436704) (xy 124.657357 -215.462671)
			(xy 124.649232 -215.513966) (xy 124.633184 -215.563359) (xy 124.609606 -215.609633) (xy 124.57908 -215.651649)
			(xy 124.542357 -215.688372) (xy 124.500341 -215.718898) (xy 124.454067 -215.742476) (xy 124.404674 -215.758524)
			(xy 124.353379 -215.766649) (xy 124.301445 -215.766649) (xy 124.25015 -215.758524) (xy 124.200757 -215.742476)
			(xy 124.154483 -215.718898) (xy 124.112467 -215.688372) (xy 124.075744 -215.651649) (xy 124.045218 -215.609633)
			(xy 124.02164 -215.563359) (xy 124.005592 -215.513966) (xy 123.997467 -215.462671) (xy 123.717557 -215.462671)
			(xy 123.709432 -215.513966) (xy 123.693384 -215.563359) (xy 123.669806 -215.609633) (xy 123.63928 -215.651649)
			(xy 123.602557 -215.688372) (xy 123.560541 -215.718898) (xy 123.514267 -215.742476) (xy 123.464874 -215.758524)
			(xy 123.413579 -215.766649) (xy 123.361645 -215.766649) (xy 123.31035 -215.758524) (xy 123.260957 -215.742476)
			(xy 123.214683 -215.718898) (xy 123.172667 -215.688372) (xy 123.135944 -215.651649) (xy 123.105418 -215.609633)
			(xy 123.08184 -215.563359) (xy 123.065792 -215.513966) (xy 123.057667 -215.462671) (xy 123.057158 -215.436704)
			(xy 122.778266 -215.436704) (xy 122.777757 -215.462671) (xy 122.769632 -215.513966) (xy 122.753584 -215.563359)
			(xy 122.730006 -215.609633) (xy 122.69948 -215.651649) (xy 122.662757 -215.688372) (xy 122.620741 -215.718898)
			(xy 122.574467 -215.742476) (xy 122.525074 -215.758524) (xy 122.473779 -215.766649) (xy 122.421845 -215.766649)
			(xy 122.37055 -215.758524) (xy 122.321157 -215.742476) (xy 122.274883 -215.718898) (xy 122.232867 -215.688372)
			(xy 122.196144 -215.651649) (xy 122.165618 -215.609633) (xy 122.14204 -215.563359) (xy 122.125992 -215.513966)
			(xy 122.117867 -215.462671) (xy 121.837957 -215.462671) (xy 121.829832 -215.513966) (xy 121.813784 -215.563359)
			(xy 121.790206 -215.609633) (xy 121.75968 -215.651649) (xy 121.722957 -215.688372) (xy 121.680941 -215.718898)
			(xy 121.634667 -215.742476) (xy 121.585274 -215.758524) (xy 121.533979 -215.766649) (xy 121.482045 -215.766649)
			(xy 121.43075 -215.758524) (xy 121.381357 -215.742476) (xy 121.335083 -215.718898) (xy 121.293067 -215.688372)
			(xy 121.256344 -215.651649) (xy 121.225818 -215.609633) (xy 121.20224 -215.563359) (xy 121.186192 -215.513966)
			(xy 121.178067 -215.462671) (xy 121.177558 -215.436704) (xy 121.01068 -215.436704) (xy 121.01068 -215.870028)
			(xy 121.058432 -215.920574) (xy 121.084639 -215.922674) (xy 121.13595 -215.934127) (xy 121.1848 -215.953557)
			(xy 121.229959 -215.980476) (xy 121.270287 -216.014203) (xy 121.304768 -216.053889) (xy 121.332533 -216.098533)
			(xy 121.35288 -216.147009) (xy 121.365297 -216.198094) (xy 121.369471 -216.250501) (xy 121.367401 -216.276487)
			(xy 121.648221 -216.276487) (xy 121.648221 -216.224553) (xy 121.656346 -216.173258) (xy 121.672394 -216.123865)
			(xy 121.695972 -216.077591) (xy 121.726498 -216.035575) (xy 121.763221 -215.998852) (xy 121.805237 -215.968326)
			(xy 121.851511 -215.944748) (xy 121.900904 -215.9287) (xy 121.952199 -215.920575) (xy 122.004133 -215.920575)
			(xy 122.055428 -215.9287) (xy 122.104821 -215.944748) (xy 122.151095 -215.968326) (xy 122.193111 -215.998852)
			(xy 122.229834 -216.035575) (xy 122.26036 -216.077591) (xy 122.283938 -216.123865) (xy 122.299986 -216.173258)
			(xy 122.308111 -216.224553) (xy 122.30862 -216.25052) (xy 122.308111 -216.276487) (xy 122.588021 -216.276487)
			(xy 122.588021 -216.224553) (xy 122.596146 -216.173258) (xy 122.612194 -216.123865) (xy 122.635772 -216.077591)
			(xy 122.666298 -216.035575) (xy 122.703021 -215.998852) (xy 122.745037 -215.968326) (xy 122.791311 -215.944748)
			(xy 122.840704 -215.9287) (xy 122.891999 -215.920575) (xy 122.943933 -215.920575) (xy 122.995228 -215.9287)
			(xy 123.044621 -215.944748) (xy 123.090895 -215.968326) (xy 123.132911 -215.998852) (xy 123.169634 -216.035575)
			(xy 123.20016 -216.077591) (xy 123.223738 -216.123865) (xy 123.239786 -216.173258) (xy 123.247911 -216.224553)
			(xy 123.24842 -216.25052) (xy 123.247911 -216.276487) (xy 123.527821 -216.276487) (xy 123.527821 -216.224553)
			(xy 123.535946 -216.173258) (xy 123.551994 -216.123865) (xy 123.575572 -216.077591) (xy 123.606098 -216.035575)
			(xy 123.642821 -215.998852) (xy 123.684837 -215.968326) (xy 123.731111 -215.944748) (xy 123.780504 -215.9287)
			(xy 123.831799 -215.920575) (xy 123.883733 -215.920575) (xy 123.935028 -215.9287) (xy 123.984421 -215.944748)
			(xy 124.030695 -215.968326) (xy 124.072711 -215.998852) (xy 124.109434 -216.035575) (xy 124.13996 -216.077591)
			(xy 124.163538 -216.123865) (xy 124.179586 -216.173258) (xy 124.187711 -216.224553) (xy 124.18822 -216.25052)
			(xy 124.187711 -216.276487) (xy 124.467621 -216.276487) (xy 124.467621 -216.224553) (xy 124.475746 -216.173258)
			(xy 124.491794 -216.123865) (xy 124.515372 -216.077591) (xy 124.545898 -216.035575) (xy 124.582621 -215.998852)
			(xy 124.624637 -215.968326) (xy 124.670911 -215.944748) (xy 124.720304 -215.9287) (xy 124.771599 -215.920575)
			(xy 124.823533 -215.920575) (xy 124.874828 -215.9287) (xy 124.924221 -215.944748) (xy 124.970495 -215.968326)
			(xy 125.012511 -215.998852) (xy 125.049234 -216.035575) (xy 125.07976 -216.077591) (xy 125.103338 -216.123865)
			(xy 125.119386 -216.173258) (xy 125.127511 -216.224553) (xy 125.12802 -216.25052) (xy 125.127511 -216.276487)
			(xy 125.407421 -216.276487) (xy 125.407421 -216.224553) (xy 125.415546 -216.173258) (xy 125.431594 -216.123865)
			(xy 125.455172 -216.077591) (xy 125.485698 -216.035575) (xy 125.522421 -215.998852) (xy 125.564437 -215.968326)
			(xy 125.610711 -215.944748) (xy 125.660104 -215.9287) (xy 125.711399 -215.920575) (xy 125.763333 -215.920575)
			(xy 125.814628 -215.9287) (xy 125.864021 -215.944748) (xy 125.910295 -215.968326) (xy 125.952311 -215.998852)
			(xy 125.989034 -216.035575) (xy 126.01956 -216.077591) (xy 126.043138 -216.123865) (xy 126.059186 -216.173258)
			(xy 126.067311 -216.224553) (xy 126.06782 -216.25052) (xy 126.067311 -216.276487) (xy 126.347221 -216.276487)
			(xy 126.347221 -216.224553) (xy 126.355346 -216.173258) (xy 126.371394 -216.123865) (xy 126.394972 -216.077591)
			(xy 126.425498 -216.035575) (xy 126.462221 -215.998852) (xy 126.504237 -215.968326) (xy 126.550511 -215.944748)
			(xy 126.599904 -215.9287) (xy 126.651199 -215.920575) (xy 126.703133 -215.920575) (xy 126.754428 -215.9287)
			(xy 126.803821 -215.944748) (xy 126.850095 -215.968326) (xy 126.892111 -215.998852) (xy 126.928834 -216.035575)
			(xy 126.95936 -216.077591) (xy 126.982938 -216.123865) (xy 126.998986 -216.173258) (xy 127.007111 -216.224553)
			(xy 127.00762 -216.25052) (xy 127.007111 -216.276487) (xy 127.287021 -216.276487) (xy 127.287021 -216.224553)
			(xy 127.295146 -216.173258) (xy 127.311194 -216.123865) (xy 127.334772 -216.077591) (xy 127.365298 -216.035575)
			(xy 127.402021 -215.998852) (xy 127.444037 -215.968326) (xy 127.490311 -215.944748) (xy 127.539704 -215.9287)
			(xy 127.590999 -215.920575) (xy 127.642933 -215.920575) (xy 127.694228 -215.9287) (xy 127.743621 -215.944748)
			(xy 127.789895 -215.968326) (xy 127.831911 -215.998852) (xy 127.868634 -216.035575) (xy 127.89916 -216.077591)
			(xy 127.922738 -216.123865) (xy 127.938786 -216.173258) (xy 127.946911 -216.224553) (xy 127.94742 -216.25052)
			(xy 127.946911 -216.276487) (xy 128.226821 -216.276487) (xy 128.226821 -216.224553) (xy 128.234946 -216.173258)
			(xy 128.250994 -216.123865) (xy 128.274572 -216.077591) (xy 128.305098 -216.035575) (xy 128.341821 -215.998852)
			(xy 128.383837 -215.968326) (xy 128.430111 -215.944748) (xy 128.479504 -215.9287) (xy 128.530799 -215.920575)
			(xy 128.582733 -215.920575) (xy 128.634028 -215.9287) (xy 128.683421 -215.944748) (xy 128.729695 -215.968326)
			(xy 128.771711 -215.998852) (xy 128.808434 -216.035575) (xy 128.83896 -216.077591) (xy 128.862538 -216.123865)
			(xy 128.878586 -216.173258) (xy 128.886711 -216.224553) (xy 128.88722 -216.25052) (xy 128.886711 -216.276487)
			(xy 129.166621 -216.276487) (xy 129.166621 -216.224553) (xy 129.174746 -216.173258) (xy 129.190794 -216.123865)
			(xy 129.214372 -216.077591) (xy 129.244898 -216.035575) (xy 129.281621 -215.998852) (xy 129.323637 -215.968326)
			(xy 129.369911 -215.944748) (xy 129.419304 -215.9287) (xy 129.470599 -215.920575) (xy 129.522533 -215.920575)
			(xy 129.573828 -215.9287) (xy 129.623221 -215.944748) (xy 129.669495 -215.968326) (xy 129.711511 -215.998852)
			(xy 129.748234 -216.035575) (xy 129.77876 -216.077591) (xy 129.802338 -216.123865) (xy 129.818386 -216.173258)
			(xy 129.826511 -216.224553) (xy 129.82702 -216.25052) (xy 129.826511 -216.276487) (xy 130.106421 -216.276487)
			(xy 130.106421 -216.224553) (xy 130.114546 -216.173258) (xy 130.130594 -216.123865) (xy 130.154172 -216.077591)
			(xy 130.184698 -216.035575) (xy 130.221421 -215.998852) (xy 130.263437 -215.968326) (xy 130.309711 -215.944748)
			(xy 130.359104 -215.9287) (xy 130.410399 -215.920575) (xy 130.462333 -215.920575) (xy 130.513628 -215.9287)
			(xy 130.563021 -215.944748) (xy 130.609295 -215.968326) (xy 130.651311 -215.998852) (xy 130.688034 -216.035575)
			(xy 130.71856 -216.077591) (xy 130.742138 -216.123865) (xy 130.758186 -216.173258) (xy 130.766311 -216.224553)
			(xy 130.76682 -216.25052) (xy 130.766311 -216.276487) (xy 131.046221 -216.276487) (xy 131.046221 -216.224553)
			(xy 131.054346 -216.173258) (xy 131.070394 -216.123865) (xy 131.093972 -216.077591) (xy 131.124498 -216.035575)
			(xy 131.161221 -215.998852) (xy 131.203237 -215.968326) (xy 131.249511 -215.944748) (xy 131.298904 -215.9287)
			(xy 131.350199 -215.920575) (xy 131.402133 -215.920575) (xy 131.453428 -215.9287) (xy 131.502821 -215.944748)
			(xy 131.549095 -215.968326) (xy 131.591111 -215.998852) (xy 131.627834 -216.035575) (xy 131.65836 -216.077591)
			(xy 131.681938 -216.123865) (xy 131.697986 -216.173258) (xy 131.706111 -216.224553) (xy 131.70662 -216.25052)
			(xy 131.706111 -216.276487) (xy 131.986021 -216.276487) (xy 131.986021 -216.224553) (xy 131.994146 -216.173258)
			(xy 132.010194 -216.123865) (xy 132.033772 -216.077591) (xy 132.064298 -216.035575) (xy 132.101021 -215.998852)
			(xy 132.143037 -215.968326) (xy 132.189311 -215.944748) (xy 132.238704 -215.9287) (xy 132.289999 -215.920575)
			(xy 132.341933 -215.920575) (xy 132.393228 -215.9287) (xy 132.442621 -215.944748) (xy 132.488895 -215.968326)
			(xy 132.530911 -215.998852) (xy 132.567634 -216.035575) (xy 132.59816 -216.077591) (xy 132.621738 -216.123865)
			(xy 132.637786 -216.173258) (xy 132.645911 -216.224553) (xy 132.64642 -216.25052) (xy 132.645911 -216.276487)
			(xy 132.925821 -216.276487) (xy 132.925821 -216.224553) (xy 132.933946 -216.173258) (xy 132.949994 -216.123865)
			(xy 132.973572 -216.077591) (xy 133.004098 -216.035575) (xy 133.040821 -215.998852) (xy 133.082837 -215.968326)
			(xy 133.129111 -215.944748) (xy 133.178504 -215.9287) (xy 133.229799 -215.920575) (xy 133.281733 -215.920575)
			(xy 133.333028 -215.9287) (xy 133.382421 -215.944748) (xy 133.428695 -215.968326) (xy 133.470711 -215.998852)
			(xy 133.507434 -216.035575) (xy 133.53796 -216.077591) (xy 133.561538 -216.123865) (xy 133.577586 -216.173258)
			(xy 133.585711 -216.224553) (xy 133.58622 -216.25052) (xy 133.585711 -216.276487) (xy 133.865621 -216.276487)
			(xy 133.865621 -216.224553) (xy 133.873746 -216.173258) (xy 133.889794 -216.123865) (xy 133.913372 -216.077591)
			(xy 133.943898 -216.035575) (xy 133.980621 -215.998852) (xy 134.022637 -215.968326) (xy 134.068911 -215.944748)
			(xy 134.118304 -215.9287) (xy 134.169599 -215.920575) (xy 134.221533 -215.920575) (xy 134.272828 -215.9287)
			(xy 134.322221 -215.944748) (xy 134.368495 -215.968326) (xy 134.410511 -215.998852) (xy 134.447234 -216.035575)
			(xy 134.47776 -216.077591) (xy 134.501338 -216.123865) (xy 134.517386 -216.173258) (xy 134.525511 -216.224553)
			(xy 134.52602 -216.25052) (xy 134.525511 -216.276487) (xy 134.517386 -216.327782) (xy 134.501338 -216.377175)
			(xy 134.47776 -216.423449) (xy 134.447234 -216.465465) (xy 134.410511 -216.502188) (xy 134.368495 -216.532714)
			(xy 134.322221 -216.556292) (xy 134.272828 -216.57234) (xy 134.221533 -216.580465) (xy 134.169599 -216.580465)
			(xy 134.118304 -216.57234) (xy 134.068911 -216.556292) (xy 134.022637 -216.532714) (xy 133.980621 -216.502188)
			(xy 133.943898 -216.465465) (xy 133.913372 -216.423449) (xy 133.889794 -216.377175) (xy 133.873746 -216.327782)
			(xy 133.865621 -216.276487) (xy 133.585711 -216.276487) (xy 133.577586 -216.327782) (xy 133.561538 -216.377175)
			(xy 133.53796 -216.423449) (xy 133.507434 -216.465465) (xy 133.470711 -216.502188) (xy 133.428695 -216.532714)
			(xy 133.382421 -216.556292) (xy 133.333028 -216.57234) (xy 133.281733 -216.580465) (xy 133.229799 -216.580465)
			(xy 133.178504 -216.57234) (xy 133.129111 -216.556292) (xy 133.082837 -216.532714) (xy 133.040821 -216.502188)
			(xy 133.004098 -216.465465) (xy 132.973572 -216.423449) (xy 132.949994 -216.377175) (xy 132.933946 -216.327782)
			(xy 132.925821 -216.276487) (xy 132.645911 -216.276487) (xy 132.637786 -216.327782) (xy 132.621738 -216.377175)
			(xy 132.59816 -216.423449) (xy 132.567634 -216.465465) (xy 132.530911 -216.502188) (xy 132.488895 -216.532714)
			(xy 132.442621 -216.556292) (xy 132.393228 -216.57234) (xy 132.341933 -216.580465) (xy 132.289999 -216.580465)
			(xy 132.238704 -216.57234) (xy 132.189311 -216.556292) (xy 132.143037 -216.532714) (xy 132.101021 -216.502188)
			(xy 132.064298 -216.465465) (xy 132.033772 -216.423449) (xy 132.010194 -216.377175) (xy 131.994146 -216.327782)
			(xy 131.986021 -216.276487) (xy 131.706111 -216.276487) (xy 131.697986 -216.327782) (xy 131.681938 -216.377175)
			(xy 131.65836 -216.423449) (xy 131.627834 -216.465465) (xy 131.591111 -216.502188) (xy 131.549095 -216.532714)
			(xy 131.502821 -216.556292) (xy 131.453428 -216.57234) (xy 131.402133 -216.580465) (xy 131.350199 -216.580465)
			(xy 131.298904 -216.57234) (xy 131.249511 -216.556292) (xy 131.203237 -216.532714) (xy 131.161221 -216.502188)
			(xy 131.124498 -216.465465) (xy 131.093972 -216.423449) (xy 131.070394 -216.377175) (xy 131.054346 -216.327782)
			(xy 131.046221 -216.276487) (xy 130.766311 -216.276487) (xy 130.758186 -216.327782) (xy 130.742138 -216.377175)
			(xy 130.71856 -216.423449) (xy 130.688034 -216.465465) (xy 130.651311 -216.502188) (xy 130.609295 -216.532714)
			(xy 130.563021 -216.556292) (xy 130.513628 -216.57234) (xy 130.462333 -216.580465) (xy 130.410399 -216.580465)
			(xy 130.359104 -216.57234) (xy 130.309711 -216.556292) (xy 130.263437 -216.532714) (xy 130.221421 -216.502188)
			(xy 130.184698 -216.465465) (xy 130.154172 -216.423449) (xy 130.130594 -216.377175) (xy 130.114546 -216.327782)
			(xy 130.106421 -216.276487) (xy 129.826511 -216.276487) (xy 129.818386 -216.327782) (xy 129.802338 -216.377175)
			(xy 129.77876 -216.423449) (xy 129.748234 -216.465465) (xy 129.711511 -216.502188) (xy 129.669495 -216.532714)
			(xy 129.623221 -216.556292) (xy 129.573828 -216.57234) (xy 129.522533 -216.580465) (xy 129.470599 -216.580465)
			(xy 129.419304 -216.57234) (xy 129.369911 -216.556292) (xy 129.323637 -216.532714) (xy 129.281621 -216.502188)
			(xy 129.244898 -216.465465) (xy 129.214372 -216.423449) (xy 129.190794 -216.377175) (xy 129.174746 -216.327782)
			(xy 129.166621 -216.276487) (xy 128.886711 -216.276487) (xy 128.878586 -216.327782) (xy 128.862538 -216.377175)
			(xy 128.83896 -216.423449) (xy 128.808434 -216.465465) (xy 128.771711 -216.502188) (xy 128.729695 -216.532714)
			(xy 128.683421 -216.556292) (xy 128.634028 -216.57234) (xy 128.582733 -216.580465) (xy 128.530799 -216.580465)
			(xy 128.479504 -216.57234) (xy 128.430111 -216.556292) (xy 128.383837 -216.532714) (xy 128.341821 -216.502188)
			(xy 128.305098 -216.465465) (xy 128.274572 -216.423449) (xy 128.250994 -216.377175) (xy 128.234946 -216.327782)
			(xy 128.226821 -216.276487) (xy 127.946911 -216.276487) (xy 127.938786 -216.327782) (xy 127.922738 -216.377175)
			(xy 127.89916 -216.423449) (xy 127.868634 -216.465465) (xy 127.831911 -216.502188) (xy 127.789895 -216.532714)
			(xy 127.743621 -216.556292) (xy 127.694228 -216.57234) (xy 127.642933 -216.580465) (xy 127.590999 -216.580465)
			(xy 127.539704 -216.57234) (xy 127.490311 -216.556292) (xy 127.444037 -216.532714) (xy 127.402021 -216.502188)
			(xy 127.365298 -216.465465) (xy 127.334772 -216.423449) (xy 127.311194 -216.377175) (xy 127.295146 -216.327782)
			(xy 127.287021 -216.276487) (xy 127.007111 -216.276487) (xy 126.998986 -216.327782) (xy 126.982938 -216.377175)
			(xy 126.95936 -216.423449) (xy 126.928834 -216.465465) (xy 126.892111 -216.502188) (xy 126.850095 -216.532714)
			(xy 126.803821 -216.556292) (xy 126.754428 -216.57234) (xy 126.703133 -216.580465) (xy 126.651199 -216.580465)
			(xy 126.599904 -216.57234) (xy 126.550511 -216.556292) (xy 126.504237 -216.532714) (xy 126.462221 -216.502188)
			(xy 126.425498 -216.465465) (xy 126.394972 -216.423449) (xy 126.371394 -216.377175) (xy 126.355346 -216.327782)
			(xy 126.347221 -216.276487) (xy 126.067311 -216.276487) (xy 126.059186 -216.327782) (xy 126.043138 -216.377175)
			(xy 126.01956 -216.423449) (xy 125.989034 -216.465465) (xy 125.952311 -216.502188) (xy 125.910295 -216.532714)
			(xy 125.864021 -216.556292) (xy 125.814628 -216.57234) (xy 125.763333 -216.580465) (xy 125.711399 -216.580465)
			(xy 125.660104 -216.57234) (xy 125.610711 -216.556292) (xy 125.564437 -216.532714) (xy 125.522421 -216.502188)
			(xy 125.485698 -216.465465) (xy 125.455172 -216.423449) (xy 125.431594 -216.377175) (xy 125.415546 -216.327782)
			(xy 125.407421 -216.276487) (xy 125.127511 -216.276487) (xy 125.119386 -216.327782) (xy 125.103338 -216.377175)
			(xy 125.07976 -216.423449) (xy 125.049234 -216.465465) (xy 125.012511 -216.502188) (xy 124.970495 -216.532714)
			(xy 124.924221 -216.556292) (xy 124.874828 -216.57234) (xy 124.823533 -216.580465) (xy 124.771599 -216.580465)
			(xy 124.720304 -216.57234) (xy 124.670911 -216.556292) (xy 124.624637 -216.532714) (xy 124.582621 -216.502188)
			(xy 124.545898 -216.465465) (xy 124.515372 -216.423449) (xy 124.491794 -216.377175) (xy 124.475746 -216.327782)
			(xy 124.467621 -216.276487) (xy 124.187711 -216.276487) (xy 124.179586 -216.327782) (xy 124.163538 -216.377175)
			(xy 124.13996 -216.423449) (xy 124.109434 -216.465465) (xy 124.072711 -216.502188) (xy 124.030695 -216.532714)
			(xy 123.984421 -216.556292) (xy 123.935028 -216.57234) (xy 123.883733 -216.580465) (xy 123.831799 -216.580465)
			(xy 123.780504 -216.57234) (xy 123.731111 -216.556292) (xy 123.684837 -216.532714) (xy 123.642821 -216.502188)
			(xy 123.606098 -216.465465) (xy 123.575572 -216.423449) (xy 123.551994 -216.377175) (xy 123.535946 -216.327782)
			(xy 123.527821 -216.276487) (xy 123.247911 -216.276487) (xy 123.239786 -216.327782) (xy 123.223738 -216.377175)
			(xy 123.20016 -216.423449) (xy 123.169634 -216.465465) (xy 123.132911 -216.502188) (xy 123.090895 -216.532714)
			(xy 123.044621 -216.556292) (xy 122.995228 -216.57234) (xy 122.943933 -216.580465) (xy 122.891999 -216.580465)
			(xy 122.840704 -216.57234) (xy 122.791311 -216.556292) (xy 122.745037 -216.532714) (xy 122.703021 -216.502188)
			(xy 122.666298 -216.465465) (xy 122.635772 -216.423449) (xy 122.612194 -216.377175) (xy 122.596146 -216.327782)
			(xy 122.588021 -216.276487) (xy 122.308111 -216.276487) (xy 122.299986 -216.327782) (xy 122.283938 -216.377175)
			(xy 122.26036 -216.423449) (xy 122.229834 -216.465465) (xy 122.193111 -216.502188) (xy 122.151095 -216.532714)
			(xy 122.104821 -216.556292) (xy 122.055428 -216.57234) (xy 122.004133 -216.580465) (xy 121.952199 -216.580465)
			(xy 121.900904 -216.57234) (xy 121.851511 -216.556292) (xy 121.805237 -216.532714) (xy 121.763221 -216.502188)
			(xy 121.726498 -216.465465) (xy 121.695972 -216.423449) (xy 121.672394 -216.377175) (xy 121.656346 -216.327782)
			(xy 121.648221 -216.276487) (xy 121.367401 -216.276487) (xy 121.365297 -216.302908) (xy 121.352879 -216.353994)
			(xy 121.332532 -216.402469) (xy 121.304767 -216.447113) (xy 121.270286 -216.486799) (xy 121.229957 -216.520526)
			(xy 121.184798 -216.547444) (xy 121.135947 -216.566874) (xy 121.084637 -216.578326) (xy 121.058432 -216.580466)
			(xy 121.01068 -216.631012) (xy 121.01068 -217.090303) (xy 121.178321 -217.090303) (xy 121.178321 -217.038369)
			(xy 121.186446 -216.987074) (xy 121.202494 -216.937681) (xy 121.226072 -216.891407) (xy 121.256598 -216.849391)
			(xy 121.293321 -216.812668) (xy 121.335337 -216.782142) (xy 121.381611 -216.758564) (xy 121.431004 -216.742516)
			(xy 121.482299 -216.734391) (xy 121.534233 -216.734391) (xy 121.585528 -216.742516) (xy 121.634921 -216.758564)
			(xy 121.681195 -216.782142) (xy 121.723211 -216.812668) (xy 121.759934 -216.849391) (xy 121.79046 -216.891407)
			(xy 121.814038 -216.937681) (xy 121.830086 -216.987074) (xy 121.838211 -217.038369) (xy 121.83872 -217.064336)
			(xy 122.117358 -217.064336) (xy 122.117867 -217.038369) (xy 122.125992 -216.987074) (xy 122.14204 -216.937681)
			(xy 122.165618 -216.891407) (xy 122.196144 -216.849391) (xy 122.232867 -216.812668) (xy 122.274883 -216.782142)
			(xy 122.321157 -216.758564) (xy 122.37055 -216.742516) (xy 122.421845 -216.734391) (xy 122.473779 -216.734391)
			(xy 122.525074 -216.742516) (xy 122.574467 -216.758564) (xy 122.620741 -216.782142) (xy 122.662757 -216.812668)
			(xy 122.69948 -216.849391) (xy 122.730006 -216.891407) (xy 122.753584 -216.937681) (xy 122.769632 -216.987074)
			(xy 122.777757 -217.038369) (xy 122.778266 -217.064336) (xy 122.778266 -217.065098) (xy 122.777732 -217.090303)
			(xy 123.057921 -217.090303) (xy 123.057921 -217.038369) (xy 123.066046 -216.987074) (xy 123.082094 -216.937681)
			(xy 123.105672 -216.891407) (xy 123.136198 -216.849391) (xy 123.172921 -216.812668) (xy 123.214937 -216.782142)
			(xy 123.261211 -216.758564) (xy 123.310604 -216.742516) (xy 123.361899 -216.734391) (xy 123.413833 -216.734391)
			(xy 123.465128 -216.742516) (xy 123.514521 -216.758564) (xy 123.560795 -216.782142) (xy 123.602811 -216.812668)
			(xy 123.639534 -216.849391) (xy 123.67006 -216.891407) (xy 123.693638 -216.937681) (xy 123.709686 -216.987074)
			(xy 123.717811 -217.038369) (xy 123.71832 -217.064336) (xy 123.996958 -217.064336) (xy 123.997467 -217.038369)
			(xy 124.005592 -216.987074) (xy 124.02164 -216.937681) (xy 124.045218 -216.891407) (xy 124.075744 -216.849391)
			(xy 124.112467 -216.812668) (xy 124.154483 -216.782142) (xy 124.200757 -216.758564) (xy 124.25015 -216.742516)
			(xy 124.301445 -216.734391) (xy 124.353379 -216.734391) (xy 124.404674 -216.742516) (xy 124.454067 -216.758564)
			(xy 124.500341 -216.782142) (xy 124.542357 -216.812668) (xy 124.57908 -216.849391) (xy 124.609606 -216.891407)
			(xy 124.633184 -216.937681) (xy 124.649232 -216.987074) (xy 124.657357 -217.038369) (xy 124.657866 -217.064336)
			(xy 124.657866 -217.065098) (xy 124.657332 -217.090303) (xy 124.937521 -217.090303) (xy 124.937521 -217.038369)
			(xy 124.945646 -216.987074) (xy 124.961694 -216.937681) (xy 124.985272 -216.891407) (xy 125.015798 -216.849391)
			(xy 125.052521 -216.812668) (xy 125.094537 -216.782142) (xy 125.140811 -216.758564) (xy 125.190204 -216.742516)
			(xy 125.241499 -216.734391) (xy 125.293433 -216.734391) (xy 125.344728 -216.742516) (xy 125.394121 -216.758564)
			(xy 125.440395 -216.782142) (xy 125.482411 -216.812668) (xy 125.519134 -216.849391) (xy 125.54966 -216.891407)
			(xy 125.573238 -216.937681) (xy 125.589286 -216.987074) (xy 125.597411 -217.038369) (xy 125.59792 -217.064336)
			(xy 125.876558 -217.064336) (xy 125.877067 -217.038369) (xy 125.885192 -216.987074) (xy 125.90124 -216.937681)
			(xy 125.924818 -216.891407) (xy 125.955344 -216.849391) (xy 125.992067 -216.812668) (xy 126.034083 -216.782142)
			(xy 126.080357 -216.758564) (xy 126.12975 -216.742516) (xy 126.181045 -216.734391) (xy 126.232979 -216.734391)
			(xy 126.284274 -216.742516) (xy 126.333667 -216.758564) (xy 126.379941 -216.782142) (xy 126.421957 -216.812668)
			(xy 126.45868 -216.849391) (xy 126.489206 -216.891407) (xy 126.512784 -216.937681) (xy 126.528832 -216.987074)
			(xy 126.536957 -217.038369) (xy 126.537466 -217.064336) (xy 126.537466 -217.065098) (xy 126.536932 -217.090303)
			(xy 126.817121 -217.090303) (xy 126.817121 -217.038369) (xy 126.825246 -216.987074) (xy 126.841294 -216.937681)
			(xy 126.864872 -216.891407) (xy 126.895398 -216.849391) (xy 126.932121 -216.812668) (xy 126.974137 -216.782142)
			(xy 127.020411 -216.758564) (xy 127.069804 -216.742516) (xy 127.121099 -216.734391) (xy 127.173033 -216.734391)
			(xy 127.224328 -216.742516) (xy 127.273721 -216.758564) (xy 127.319995 -216.782142) (xy 127.362011 -216.812668)
			(xy 127.398734 -216.849391) (xy 127.42926 -216.891407) (xy 127.452838 -216.937681) (xy 127.468886 -216.987074)
			(xy 127.477011 -217.038369) (xy 127.47752 -217.064336) (xy 127.756158 -217.064336) (xy 127.756667 -217.038369)
			(xy 127.764792 -216.987074) (xy 127.78084 -216.937681) (xy 127.804418 -216.891407) (xy 127.834944 -216.849391)
			(xy 127.871667 -216.812668) (xy 127.913683 -216.782142) (xy 127.959957 -216.758564) (xy 128.00935 -216.742516)
			(xy 128.060645 -216.734391) (xy 128.112579 -216.734391) (xy 128.163874 -216.742516) (xy 128.213267 -216.758564)
			(xy 128.259541 -216.782142) (xy 128.301557 -216.812668) (xy 128.33828 -216.849391) (xy 128.368806 -216.891407)
			(xy 128.392384 -216.937681) (xy 128.408432 -216.987074) (xy 128.416557 -217.038369) (xy 128.417066 -217.064336)
			(xy 128.417066 -217.065098) (xy 128.416532 -217.090303) (xy 128.696721 -217.090303) (xy 128.696721 -217.038369)
			(xy 128.704846 -216.987074) (xy 128.720894 -216.937681) (xy 128.744472 -216.891407) (xy 128.774998 -216.849391)
			(xy 128.811721 -216.812668) (xy 128.853737 -216.782142) (xy 128.900011 -216.758564) (xy 128.949404 -216.742516)
			(xy 129.000699 -216.734391) (xy 129.052633 -216.734391) (xy 129.103928 -216.742516) (xy 129.153321 -216.758564)
			(xy 129.199595 -216.782142) (xy 129.241611 -216.812668) (xy 129.278334 -216.849391) (xy 129.30886 -216.891407)
			(xy 129.332438 -216.937681) (xy 129.348486 -216.987074) (xy 129.356611 -217.038369) (xy 129.35712 -217.064336)
			(xy 129.635758 -217.064336) (xy 129.636267 -217.038369) (xy 129.644392 -216.987074) (xy 129.66044 -216.937681)
			(xy 129.684018 -216.891407) (xy 129.714544 -216.849391) (xy 129.751267 -216.812668) (xy 129.793283 -216.782142)
			(xy 129.839557 -216.758564) (xy 129.88895 -216.742516) (xy 129.940245 -216.734391) (xy 129.992179 -216.734391)
			(xy 130.043474 -216.742516) (xy 130.092867 -216.758564) (xy 130.139141 -216.782142) (xy 130.181157 -216.812668)
			(xy 130.21788 -216.849391) (xy 130.248406 -216.891407) (xy 130.271984 -216.937681) (xy 130.288032 -216.987074)
			(xy 130.296157 -217.038369) (xy 130.296666 -217.064336) (xy 130.296666 -217.065098) (xy 130.296132 -217.090303)
			(xy 130.576321 -217.090303) (xy 130.576321 -217.038369) (xy 130.584446 -216.987074) (xy 130.600494 -216.937681)
			(xy 130.624072 -216.891407) (xy 130.654598 -216.849391) (xy 130.691321 -216.812668) (xy 130.733337 -216.782142)
			(xy 130.779611 -216.758564) (xy 130.829004 -216.742516) (xy 130.880299 -216.734391) (xy 130.932233 -216.734391)
			(xy 130.983528 -216.742516) (xy 131.032921 -216.758564) (xy 131.079195 -216.782142) (xy 131.121211 -216.812668)
			(xy 131.157934 -216.849391) (xy 131.18846 -216.891407) (xy 131.212038 -216.937681) (xy 131.228086 -216.987074)
			(xy 131.236211 -217.038369) (xy 131.23672 -217.064336) (xy 131.515358 -217.064336) (xy 131.515867 -217.038369)
			(xy 131.523992 -216.987074) (xy 131.54004 -216.937681) (xy 131.563618 -216.891407) (xy 131.594144 -216.849391)
			(xy 131.630867 -216.812668) (xy 131.672883 -216.782142) (xy 131.719157 -216.758564) (xy 131.76855 -216.742516)
			(xy 131.819845 -216.734391) (xy 131.871779 -216.734391) (xy 131.923074 -216.742516) (xy 131.972467 -216.758564)
			(xy 132.018741 -216.782142) (xy 132.060757 -216.812668) (xy 132.09748 -216.849391) (xy 132.128006 -216.891407)
			(xy 132.151584 -216.937681) (xy 132.167632 -216.987074) (xy 132.175757 -217.038369) (xy 132.176266 -217.064336)
			(xy 132.176266 -217.065098) (xy 132.175732 -217.090303) (xy 132.455921 -217.090303) (xy 132.455921 -217.038369)
			(xy 132.464046 -216.987074) (xy 132.480094 -216.937681) (xy 132.503672 -216.891407) (xy 132.534198 -216.849391)
			(xy 132.570921 -216.812668) (xy 132.612937 -216.782142) (xy 132.659211 -216.758564) (xy 132.708604 -216.742516)
			(xy 132.759899 -216.734391) (xy 132.811833 -216.734391) (xy 132.863128 -216.742516) (xy 132.912521 -216.758564)
			(xy 132.958795 -216.782142) (xy 133.000811 -216.812668) (xy 133.037534 -216.849391) (xy 133.06806 -216.891407)
			(xy 133.091638 -216.937681) (xy 133.107686 -216.987074) (xy 133.115811 -217.038369) (xy 133.11632 -217.064336)
			(xy 133.394958 -217.064336) (xy 133.395467 -217.038369) (xy 133.403592 -216.987074) (xy 133.41964 -216.937681)
			(xy 133.443218 -216.891407) (xy 133.473744 -216.849391) (xy 133.510467 -216.812668) (xy 133.552483 -216.782142)
			(xy 133.598757 -216.758564) (xy 133.64815 -216.742516) (xy 133.699445 -216.734391) (xy 133.751379 -216.734391)
			(xy 133.802674 -216.742516) (xy 133.852067 -216.758564) (xy 133.898341 -216.782142) (xy 133.940357 -216.812668)
			(xy 133.97708 -216.849391) (xy 134.007606 -216.891407) (xy 134.031184 -216.937681) (xy 134.047232 -216.987074)
			(xy 134.055357 -217.038369) (xy 134.055866 -217.064336) (xy 134.055866 -217.065098) (xy 134.055279 -217.092816)
			(xy 134.045955 -217.147463) (xy 134.037324 -217.17381) (xy 134.02945 -217.195654) (xy 134.233666 -217.549222)
			(xy 134.256526 -217.55354) (xy 134.28144 -217.558742) (xy 134.329422 -217.575703) (xy 134.374238 -217.599816)
			(xy 134.414831 -217.630512) (xy 134.45024 -217.667066) (xy 134.479629 -217.708614) (xy 134.502305 -217.754174)
			(xy 134.517732 -217.802672) (xy 134.525545 -217.85296) (xy 134.52602 -217.878406) (xy 134.525511 -217.904373)
			(xy 134.517386 -217.955668) (xy 134.501338 -218.005061) (xy 134.47776 -218.051335) (xy 134.447234 -218.093351)
			(xy 134.410511 -218.130074) (xy 134.368495 -218.1606) (xy 134.322221 -218.184178) (xy 134.272828 -218.200226)
			(xy 134.221533 -218.208351) (xy 134.169599 -218.208351) (xy 134.118304 -218.200226) (xy 134.068911 -218.184178)
			(xy 134.022637 -218.1606) (xy 133.980621 -218.130074) (xy 133.943898 -218.093351) (xy 133.913372 -218.051335)
			(xy 133.889794 -218.005061) (xy 133.873746 -217.955668) (xy 133.865621 -217.904373) (xy 133.865112 -217.878406)
			(xy 133.865666 -217.85042) (xy 133.875115 -217.795252) (xy 133.883908 -217.768678) (xy 133.891528 -217.74658)
			(xy 133.68782 -217.39352) (xy 133.664706 -217.389202) (xy 133.639766 -217.384059) (xy 133.591742 -217.367128)
			(xy 133.546882 -217.343032) (xy 133.506249 -217.312342) (xy 133.470803 -217.275784) (xy 133.441382 -217.234221)
			(xy 133.418684 -217.188639) (xy 133.403245 -217.140115) (xy 133.39543 -217.089797) (xy 133.394958 -217.064336)
			(xy 133.11632 -217.064336) (xy 133.115811 -217.090303) (xy 133.107686 -217.141598) (xy 133.091638 -217.190991)
			(xy 133.06806 -217.237265) (xy 133.037534 -217.279281) (xy 133.000811 -217.316004) (xy 132.958795 -217.34653)
			(xy 132.912521 -217.370108) (xy 132.863128 -217.386156) (xy 132.811833 -217.394281) (xy 132.759899 -217.394281)
			(xy 132.708604 -217.386156) (xy 132.659211 -217.370108) (xy 132.612937 -217.34653) (xy 132.570921 -217.316004)
			(xy 132.534198 -217.279281) (xy 132.503672 -217.237265) (xy 132.480094 -217.190991) (xy 132.464046 -217.141598)
			(xy 132.455921 -217.090303) (xy 132.175732 -217.090303) (xy 132.175679 -217.092816) (xy 132.166355 -217.147463)
			(xy 132.157724 -217.17381) (xy 132.14985 -217.195654) (xy 132.354066 -217.549222) (xy 132.376926 -217.55354)
			(xy 132.40184 -217.558742) (xy 132.449822 -217.575703) (xy 132.494638 -217.599816) (xy 132.535231 -217.630512)
			(xy 132.57064 -217.667066) (xy 132.600029 -217.708614) (xy 132.622705 -217.754174) (xy 132.638132 -217.802672)
			(xy 132.645945 -217.85296) (xy 132.64642 -217.878406) (xy 132.645911 -217.904373) (xy 132.637786 -217.955668)
			(xy 132.621738 -218.005061) (xy 132.59816 -218.051335) (xy 132.567634 -218.093351) (xy 132.530911 -218.130074)
			(xy 132.488895 -218.1606) (xy 132.442621 -218.184178) (xy 132.393228 -218.200226) (xy 132.341933 -218.208351)
			(xy 132.289999 -218.208351) (xy 132.238704 -218.200226) (xy 132.189311 -218.184178) (xy 132.143037 -218.1606)
			(xy 132.101021 -218.130074) (xy 132.064298 -218.093351) (xy 132.033772 -218.051335) (xy 132.010194 -218.005061)
			(xy 131.994146 -217.955668) (xy 131.986021 -217.904373) (xy 131.985512 -217.878406) (xy 131.986066 -217.85042)
			(xy 131.995515 -217.795252) (xy 132.004308 -217.768678) (xy 132.011928 -217.74658) (xy 131.80822 -217.39352)
			(xy 131.785106 -217.389202) (xy 131.760166 -217.384059) (xy 131.712142 -217.367128) (xy 131.667282 -217.343032)
			(xy 131.626649 -217.312342) (xy 131.591203 -217.275784) (xy 131.561782 -217.234221) (xy 131.539084 -217.188639)
			(xy 131.523645 -217.140115) (xy 131.51583 -217.089797) (xy 131.515358 -217.064336) (xy 131.23672 -217.064336)
			(xy 131.236211 -217.090303) (xy 131.228086 -217.141598) (xy 131.212038 -217.190991) (xy 131.18846 -217.237265)
			(xy 131.157934 -217.279281) (xy 131.121211 -217.316004) (xy 131.079195 -217.34653) (xy 131.032921 -217.370108)
			(xy 130.983528 -217.386156) (xy 130.932233 -217.394281) (xy 130.880299 -217.394281) (xy 130.829004 -217.386156)
			(xy 130.779611 -217.370108) (xy 130.733337 -217.34653) (xy 130.691321 -217.316004) (xy 130.654598 -217.279281)
			(xy 130.624072 -217.237265) (xy 130.600494 -217.190991) (xy 130.584446 -217.141598) (xy 130.576321 -217.090303)
			(xy 130.296132 -217.090303) (xy 130.296079 -217.092816) (xy 130.286755 -217.147463) (xy 130.278124 -217.17381)
			(xy 130.27025 -217.195654) (xy 130.474466 -217.549222) (xy 130.497326 -217.55354) (xy 130.52224 -217.558742)
			(xy 130.570222 -217.575703) (xy 130.615038 -217.599816) (xy 130.655631 -217.630512) (xy 130.69104 -217.667066)
			(xy 130.720429 -217.708614) (xy 130.743105 -217.754174) (xy 130.758532 -217.802672) (xy 130.766345 -217.85296)
			(xy 130.76682 -217.878406) (xy 130.766311 -217.904373) (xy 130.758186 -217.955668) (xy 130.742138 -218.005061)
			(xy 130.71856 -218.051335) (xy 130.688034 -218.093351) (xy 130.651311 -218.130074) (xy 130.609295 -218.1606)
			(xy 130.563021 -218.184178) (xy 130.513628 -218.200226) (xy 130.462333 -218.208351) (xy 130.410399 -218.208351)
			(xy 130.359104 -218.200226) (xy 130.309711 -218.184178) (xy 130.263437 -218.1606) (xy 130.221421 -218.130074)
			(xy 130.184698 -218.093351) (xy 130.154172 -218.051335) (xy 130.130594 -218.005061) (xy 130.114546 -217.955668)
			(xy 130.106421 -217.904373) (xy 130.105912 -217.878406) (xy 130.106466 -217.85042) (xy 130.115915 -217.795252)
			(xy 130.124708 -217.768678) (xy 130.132328 -217.74658) (xy 129.92862 -217.39352) (xy 129.905506 -217.389202)
			(xy 129.880566 -217.384059) (xy 129.832542 -217.367128) (xy 129.787682 -217.343032) (xy 129.747049 -217.312342)
			(xy 129.711603 -217.275784) (xy 129.682182 -217.234221) (xy 129.659484 -217.188639) (xy 129.644045 -217.140115)
			(xy 129.63623 -217.089797) (xy 129.635758 -217.064336) (xy 129.35712 -217.064336) (xy 129.356611 -217.090303)
			(xy 129.348486 -217.141598) (xy 129.332438 -217.190991) (xy 129.30886 -217.237265) (xy 129.278334 -217.279281)
			(xy 129.241611 -217.316004) (xy 129.199595 -217.34653) (xy 129.153321 -217.370108) (xy 129.103928 -217.386156)
			(xy 129.052633 -217.394281) (xy 129.000699 -217.394281) (xy 128.949404 -217.386156) (xy 128.900011 -217.370108)
			(xy 128.853737 -217.34653) (xy 128.811721 -217.316004) (xy 128.774998 -217.279281) (xy 128.744472 -217.237265)
			(xy 128.720894 -217.190991) (xy 128.704846 -217.141598) (xy 128.696721 -217.090303) (xy 128.416532 -217.090303)
			(xy 128.416479 -217.092816) (xy 128.407155 -217.147463) (xy 128.398524 -217.17381) (xy 128.39065 -217.195654)
			(xy 128.594866 -217.549222) (xy 128.617726 -217.55354) (xy 128.64264 -217.558742) (xy 128.690622 -217.575703)
			(xy 128.735438 -217.599816) (xy 128.776031 -217.630512) (xy 128.81144 -217.667066) (xy 128.840829 -217.708614)
			(xy 128.863505 -217.754174) (xy 128.878932 -217.802672) (xy 128.886745 -217.85296) (xy 128.88722 -217.878406)
			(xy 128.886711 -217.904373) (xy 128.878586 -217.955668) (xy 128.862538 -218.005061) (xy 128.83896 -218.051335)
			(xy 128.808434 -218.093351) (xy 128.771711 -218.130074) (xy 128.729695 -218.1606) (xy 128.683421 -218.184178)
			(xy 128.634028 -218.200226) (xy 128.582733 -218.208351) (xy 128.530799 -218.208351) (xy 128.479504 -218.200226)
			(xy 128.430111 -218.184178) (xy 128.383837 -218.1606) (xy 128.341821 -218.130074) (xy 128.305098 -218.093351)
			(xy 128.274572 -218.051335) (xy 128.250994 -218.005061) (xy 128.234946 -217.955668) (xy 128.226821 -217.904373)
			(xy 128.226312 -217.878406) (xy 128.226866 -217.85042) (xy 128.236315 -217.795252) (xy 128.245108 -217.768678)
			(xy 128.252728 -217.74658) (xy 128.04902 -217.39352) (xy 128.025906 -217.389202) (xy 128.000966 -217.384059)
			(xy 127.952942 -217.367128) (xy 127.908082 -217.343032) (xy 127.867449 -217.312342) (xy 127.832003 -217.275784)
			(xy 127.802582 -217.234221) (xy 127.779884 -217.188639) (xy 127.764445 -217.140115) (xy 127.75663 -217.089797)
			(xy 127.756158 -217.064336) (xy 127.47752 -217.064336) (xy 127.477011 -217.090303) (xy 127.468886 -217.141598)
			(xy 127.452838 -217.190991) (xy 127.42926 -217.237265) (xy 127.398734 -217.279281) (xy 127.362011 -217.316004)
			(xy 127.319995 -217.34653) (xy 127.273721 -217.370108) (xy 127.224328 -217.386156) (xy 127.173033 -217.394281)
			(xy 127.121099 -217.394281) (xy 127.069804 -217.386156) (xy 127.020411 -217.370108) (xy 126.974137 -217.34653)
			(xy 126.932121 -217.316004) (xy 126.895398 -217.279281) (xy 126.864872 -217.237265) (xy 126.841294 -217.190991)
			(xy 126.825246 -217.141598) (xy 126.817121 -217.090303) (xy 126.536932 -217.090303) (xy 126.536879 -217.092816)
			(xy 126.527555 -217.147463) (xy 126.518924 -217.17381) (xy 126.51105 -217.195654) (xy 126.715266 -217.549222)
			(xy 126.738126 -217.55354) (xy 126.76304 -217.558742) (xy 126.811022 -217.575703) (xy 126.855838 -217.599816)
			(xy 126.896431 -217.630512) (xy 126.93184 -217.667066) (xy 126.961229 -217.708614) (xy 126.983905 -217.754174)
			(xy 126.999332 -217.802672) (xy 127.007145 -217.85296) (xy 127.00762 -217.878406) (xy 127.007111 -217.904373)
			(xy 126.998986 -217.955668) (xy 126.982938 -218.005061) (xy 126.95936 -218.051335) (xy 126.928834 -218.093351)
			(xy 126.892111 -218.130074) (xy 126.850095 -218.1606) (xy 126.803821 -218.184178) (xy 126.754428 -218.200226)
			(xy 126.703133 -218.208351) (xy 126.651199 -218.208351) (xy 126.599904 -218.200226) (xy 126.550511 -218.184178)
			(xy 126.504237 -218.1606) (xy 126.462221 -218.130074) (xy 126.425498 -218.093351) (xy 126.394972 -218.051335)
			(xy 126.371394 -218.005061) (xy 126.355346 -217.955668) (xy 126.347221 -217.904373) (xy 126.346712 -217.878406)
			(xy 126.347266 -217.85042) (xy 126.356715 -217.795252) (xy 126.365508 -217.768678) (xy 126.373128 -217.74658)
			(xy 126.16942 -217.39352) (xy 126.146306 -217.389202) (xy 126.121366 -217.384059) (xy 126.073342 -217.367128)
			(xy 126.028482 -217.343032) (xy 125.987849 -217.312342) (xy 125.952403 -217.275784) (xy 125.922982 -217.234221)
			(xy 125.900284 -217.188639) (xy 125.884845 -217.140115) (xy 125.87703 -217.089797) (xy 125.876558 -217.064336)
			(xy 125.59792 -217.064336) (xy 125.597411 -217.090303) (xy 125.589286 -217.141598) (xy 125.573238 -217.190991)
			(xy 125.54966 -217.237265) (xy 125.519134 -217.279281) (xy 125.482411 -217.316004) (xy 125.440395 -217.34653)
			(xy 125.394121 -217.370108) (xy 125.344728 -217.386156) (xy 125.293433 -217.394281) (xy 125.241499 -217.394281)
			(xy 125.190204 -217.386156) (xy 125.140811 -217.370108) (xy 125.094537 -217.34653) (xy 125.052521 -217.316004)
			(xy 125.015798 -217.279281) (xy 124.985272 -217.237265) (xy 124.961694 -217.190991) (xy 124.945646 -217.141598)
			(xy 124.937521 -217.090303) (xy 124.657332 -217.090303) (xy 124.657279 -217.092816) (xy 124.647955 -217.147463)
			(xy 124.639324 -217.17381) (xy 124.63145 -217.195654) (xy 124.835666 -217.549222) (xy 124.858526 -217.55354)
			(xy 124.88344 -217.558742) (xy 124.931422 -217.575703) (xy 124.976238 -217.599816) (xy 125.016831 -217.630512)
			(xy 125.05224 -217.667066) (xy 125.081629 -217.708614) (xy 125.104305 -217.754174) (xy 125.119732 -217.802672)
			(xy 125.127545 -217.85296) (xy 125.12802 -217.878406) (xy 125.127511 -217.904373) (xy 125.119386 -217.955668)
			(xy 125.103338 -218.005061) (xy 125.07976 -218.051335) (xy 125.049234 -218.093351) (xy 125.012511 -218.130074)
			(xy 124.970495 -218.1606) (xy 124.924221 -218.184178) (xy 124.874828 -218.200226) (xy 124.823533 -218.208351)
			(xy 124.771599 -218.208351) (xy 124.720304 -218.200226) (xy 124.670911 -218.184178) (xy 124.624637 -218.1606)
			(xy 124.582621 -218.130074) (xy 124.545898 -218.093351) (xy 124.515372 -218.051335) (xy 124.491794 -218.005061)
			(xy 124.475746 -217.955668) (xy 124.467621 -217.904373) (xy 124.467112 -217.878406) (xy 124.467666 -217.85042)
			(xy 124.477115 -217.795252) (xy 124.485908 -217.768678) (xy 124.493528 -217.74658) (xy 124.28982 -217.39352)
			(xy 124.266706 -217.389202) (xy 124.241766 -217.384059) (xy 124.193742 -217.367128) (xy 124.148882 -217.343032)
			(xy 124.108249 -217.312342) (xy 124.072803 -217.275784) (xy 124.043382 -217.234221) (xy 124.020684 -217.188639)
			(xy 124.005245 -217.140115) (xy 123.99743 -217.089797) (xy 123.996958 -217.064336) (xy 123.71832 -217.064336)
			(xy 123.717811 -217.090303) (xy 123.709686 -217.141598) (xy 123.693638 -217.190991) (xy 123.67006 -217.237265)
			(xy 123.639534 -217.279281) (xy 123.602811 -217.316004) (xy 123.560795 -217.34653) (xy 123.514521 -217.370108)
			(xy 123.465128 -217.386156) (xy 123.413833 -217.394281) (xy 123.361899 -217.394281) (xy 123.310604 -217.386156)
			(xy 123.261211 -217.370108) (xy 123.214937 -217.34653) (xy 123.172921 -217.316004) (xy 123.136198 -217.279281)
			(xy 123.105672 -217.237265) (xy 123.082094 -217.190991) (xy 123.066046 -217.141598) (xy 123.057921 -217.090303)
			(xy 122.777732 -217.090303) (xy 122.777679 -217.092816) (xy 122.768355 -217.147463) (xy 122.759724 -217.17381)
			(xy 122.75185 -217.195654) (xy 122.956066 -217.549222) (xy 122.978926 -217.55354) (xy 123.00384 -217.558742)
			(xy 123.051822 -217.575703) (xy 123.096638 -217.599816) (xy 123.137231 -217.630512) (xy 123.17264 -217.667066)
			(xy 123.202029 -217.708614) (xy 123.224705 -217.754174) (xy 123.240132 -217.802672) (xy 123.247945 -217.85296)
			(xy 123.24842 -217.878406) (xy 123.247911 -217.904373) (xy 123.239786 -217.955668) (xy 123.223738 -218.005061)
			(xy 123.20016 -218.051335) (xy 123.169634 -218.093351) (xy 123.132911 -218.130074) (xy 123.090895 -218.1606)
			(xy 123.044621 -218.184178) (xy 122.995228 -218.200226) (xy 122.943933 -218.208351) (xy 122.891999 -218.208351)
			(xy 122.840704 -218.200226) (xy 122.791311 -218.184178) (xy 122.745037 -218.1606) (xy 122.703021 -218.130074)
			(xy 122.666298 -218.093351) (xy 122.635772 -218.051335) (xy 122.612194 -218.005061) (xy 122.596146 -217.955668)
			(xy 122.588021 -217.904373) (xy 122.587512 -217.878406) (xy 122.588066 -217.85042) (xy 122.597515 -217.795252)
			(xy 122.606308 -217.768678) (xy 122.613928 -217.74658) (xy 122.41022 -217.39352) (xy 122.387106 -217.389202)
			(xy 122.362166 -217.384059) (xy 122.314142 -217.367128) (xy 122.269282 -217.343032) (xy 122.228649 -217.312342)
			(xy 122.193203 -217.275784) (xy 122.163782 -217.234221) (xy 122.141084 -217.188639) (xy 122.125645 -217.140115)
			(xy 122.11783 -217.089797) (xy 122.117358 -217.064336) (xy 121.83872 -217.064336) (xy 121.838211 -217.090303)
			(xy 121.830086 -217.141598) (xy 121.814038 -217.190991) (xy 121.79046 -217.237265) (xy 121.759934 -217.279281)
			(xy 121.723211 -217.316004) (xy 121.681195 -217.34653) (xy 121.634921 -217.370108) (xy 121.585528 -217.386156)
			(xy 121.534233 -217.394281) (xy 121.482299 -217.394281) (xy 121.431004 -217.386156) (xy 121.381611 -217.370108)
			(xy 121.335337 -217.34653) (xy 121.293321 -217.316004) (xy 121.256598 -217.279281) (xy 121.226072 -217.237265)
			(xy 121.202494 -217.190991) (xy 121.186446 -217.141598) (xy 121.178321 -217.090303) (xy 121.01068 -217.090303)
			(xy 121.01068 -217.43543) (xy 121.076466 -217.549222) (xy 121.099326 -217.55354) (xy 121.124256 -217.558689)
			(xy 121.172259 -217.575628) (xy 121.217095 -217.59973) (xy 121.257702 -217.630426) (xy 121.293119 -217.666988)
			(xy 121.322508 -217.708551) (xy 121.345173 -217.754131) (xy 121.360577 -217.802648) (xy 121.368355 -217.852954)
			(xy 121.36882 -217.878406) (xy 121.368356 -217.903368) (xy 121.360834 -217.952723) (xy 121.345977 -218.000386)
			(xy 121.324122 -218.045274) (xy 121.295767 -218.086365) (xy 121.261556 -218.122725) (xy 121.222267 -218.153529)
			(xy 121.178793 -218.178075) (xy 121.132122 -218.195806) (xy 121.083317 -218.206318) (xy 121.058432 -218.208352)
			(xy 121.01068 -218.258898) (xy 121.01068 -218.692222) (xy 121.177558 -218.692222) (xy 121.177965 -218.666768)
			(xy 121.185754 -218.616461) (xy 121.201169 -218.567943) (xy 121.223842 -218.522364) (xy 121.253239 -218.480803)
			(xy 121.288662 -218.444242) (xy 121.329274 -218.413547) (xy 121.374114 -218.389444) (xy 121.42212 -218.372505)
			(xy 121.447052 -218.367356) (xy 121.469912 -218.363038) (xy 121.673874 -218.00947) (xy 121.666254 -217.987626)
			(xy 121.657633 -217.961211) (xy 121.648308 -217.906439) (xy 121.647712 -217.87866) (xy 121.647712 -217.878406)
			(xy 121.648221 -217.852439) (xy 121.656346 -217.801144) (xy 121.672394 -217.751751) (xy 121.695972 -217.705477)
			(xy 121.726498 -217.663461) (xy 121.763221 -217.626738) (xy 121.805237 -217.596212) (xy 121.851511 -217.572634)
			(xy 121.900904 -217.556586) (xy 121.952199 -217.548461) (xy 122.004133 -217.548461) (xy 122.055428 -217.556586)
			(xy 122.104821 -217.572634) (xy 122.151095 -217.596212) (xy 122.193111 -217.626738) (xy 122.229834 -217.663461)
			(xy 122.26036 -217.705477) (xy 122.283938 -217.751751) (xy 122.299986 -217.801144) (xy 122.308111 -217.852439)
			(xy 122.30862 -217.878406) (xy 122.308171 -217.903881) (xy 122.30035 -217.954227) (xy 122.284894 -218.002775)
			(xy 122.262169 -218.048376) (xy 122.232714 -218.089949) (xy 122.197227 -218.126507) (xy 122.156549 -218.157186)
			(xy 122.111645 -218.181258) (xy 122.063577 -218.198151) (xy 122.038618 -218.203272) (xy 122.015504 -218.20759)
			(xy 121.81205 -218.560396) (xy 121.81967 -218.582494) (xy 121.828405 -218.609083) (xy 121.837855 -218.664242)
			(xy 121.838466 -218.692222) (xy 121.837957 -218.718189) (xy 122.117867 -218.718189) (xy 122.117867 -218.666255)
			(xy 122.125992 -218.61496) (xy 122.14204 -218.565567) (xy 122.165618 -218.519293) (xy 122.196144 -218.477277)
			(xy 122.232867 -218.440554) (xy 122.274883 -218.410028) (xy 122.321157 -218.38645) (xy 122.37055 -218.370402)
			(xy 122.421845 -218.362277) (xy 122.473779 -218.362277) (xy 122.525074 -218.370402) (xy 122.574467 -218.38645)
			(xy 122.620741 -218.410028) (xy 122.662757 -218.440554) (xy 122.69948 -218.477277) (xy 122.730006 -218.519293)
			(xy 122.753584 -218.565567) (xy 122.769632 -218.61496) (xy 122.777757 -218.666255) (xy 122.778266 -218.692222)
			(xy 123.057158 -218.692222) (xy 123.057565 -218.666768) (xy 123.065354 -218.616461) (xy 123.080769 -218.567943)
			(xy 123.103442 -218.522364) (xy 123.132839 -218.480803) (xy 123.168262 -218.444242) (xy 123.208874 -218.413547)
			(xy 123.253714 -218.389444) (xy 123.30172 -218.372505) (xy 123.326652 -218.367356) (xy 123.349512 -218.363038)
			(xy 123.553474 -218.00947) (xy 123.545854 -217.987626) (xy 123.537233 -217.961211) (xy 123.527908 -217.906439)
			(xy 123.527312 -217.87866) (xy 123.527312 -217.878406) (xy 123.527821 -217.852439) (xy 123.535946 -217.801144)
			(xy 123.551994 -217.751751) (xy 123.575572 -217.705477) (xy 123.606098 -217.663461) (xy 123.642821 -217.626738)
			(xy 123.684837 -217.596212) (xy 123.731111 -217.572634) (xy 123.780504 -217.556586) (xy 123.831799 -217.548461)
			(xy 123.883733 -217.548461) (xy 123.935028 -217.556586) (xy 123.984421 -217.572634) (xy 124.030695 -217.596212)
			(xy 124.072711 -217.626738) (xy 124.109434 -217.663461) (xy 124.13996 -217.705477) (xy 124.163538 -217.751751)
			(xy 124.179586 -217.801144) (xy 124.187711 -217.852439) (xy 124.18822 -217.878406) (xy 124.187771 -217.903881)
			(xy 124.17995 -217.954227) (xy 124.164494 -218.002775) (xy 124.141769 -218.048376) (xy 124.112314 -218.089949)
			(xy 124.076827 -218.126507) (xy 124.036149 -218.157186) (xy 123.991245 -218.181258) (xy 123.943177 -218.198151)
			(xy 123.918218 -218.203272) (xy 123.895104 -218.20759) (xy 123.69165 -218.560396) (xy 123.69927 -218.582494)
			(xy 123.708005 -218.609083) (xy 123.717455 -218.664242) (xy 123.718066 -218.692222) (xy 123.717557 -218.718189)
			(xy 123.997467 -218.718189) (xy 123.997467 -218.666255) (xy 124.005592 -218.61496) (xy 124.02164 -218.565567)
			(xy 124.045218 -218.519293) (xy 124.075744 -218.477277) (xy 124.112467 -218.440554) (xy 124.154483 -218.410028)
			(xy 124.200757 -218.38645) (xy 124.25015 -218.370402) (xy 124.301445 -218.362277) (xy 124.353379 -218.362277)
			(xy 124.404674 -218.370402) (xy 124.454067 -218.38645) (xy 124.500341 -218.410028) (xy 124.542357 -218.440554)
			(xy 124.57908 -218.477277) (xy 124.609606 -218.519293) (xy 124.633184 -218.565567) (xy 124.649232 -218.61496)
			(xy 124.657357 -218.666255) (xy 124.657866 -218.692222) (xy 124.936758 -218.692222) (xy 124.937165 -218.666768)
			(xy 124.944954 -218.616461) (xy 124.960369 -218.567943) (xy 124.983042 -218.522364) (xy 125.012439 -218.480803)
			(xy 125.047862 -218.444242) (xy 125.088474 -218.413547) (xy 125.133314 -218.389444) (xy 125.18132 -218.372505)
			(xy 125.206252 -218.367356) (xy 125.229112 -218.363038) (xy 125.433074 -218.00947) (xy 125.425454 -217.987626)
			(xy 125.416833 -217.961211) (xy 125.407508 -217.906439) (xy 125.406912 -217.87866) (xy 125.406912 -217.878406)
			(xy 125.407421 -217.852439) (xy 125.415546 -217.801144) (xy 125.431594 -217.751751) (xy 125.455172 -217.705477)
			(xy 125.485698 -217.663461) (xy 125.522421 -217.626738) (xy 125.564437 -217.596212) (xy 125.610711 -217.572634)
			(xy 125.660104 -217.556586) (xy 125.711399 -217.548461) (xy 125.763333 -217.548461) (xy 125.814628 -217.556586)
			(xy 125.864021 -217.572634) (xy 125.910295 -217.596212) (xy 125.952311 -217.626738) (xy 125.989034 -217.663461)
			(xy 126.01956 -217.705477) (xy 126.043138 -217.751751) (xy 126.059186 -217.801144) (xy 126.067311 -217.852439)
			(xy 126.06782 -217.878406) (xy 126.067371 -217.903881) (xy 126.05955 -217.954227) (xy 126.044094 -218.002775)
			(xy 126.021369 -218.048376) (xy 125.991914 -218.089949) (xy 125.956427 -218.126507) (xy 125.915749 -218.157186)
			(xy 125.870845 -218.181258) (xy 125.822777 -218.198151) (xy 125.797818 -218.203272) (xy 125.774704 -218.20759)
			(xy 125.57125 -218.560396) (xy 125.57887 -218.582494) (xy 125.587605 -218.609083) (xy 125.597055 -218.664242)
			(xy 125.597666 -218.692222) (xy 125.597157 -218.718189) (xy 125.877067 -218.718189) (xy 125.877067 -218.666255)
			(xy 125.885192 -218.61496) (xy 125.90124 -218.565567) (xy 125.924818 -218.519293) (xy 125.955344 -218.477277)
			(xy 125.992067 -218.440554) (xy 126.034083 -218.410028) (xy 126.080357 -218.38645) (xy 126.12975 -218.370402)
			(xy 126.181045 -218.362277) (xy 126.232979 -218.362277) (xy 126.284274 -218.370402) (xy 126.333667 -218.38645)
			(xy 126.379941 -218.410028) (xy 126.421957 -218.440554) (xy 126.45868 -218.477277) (xy 126.489206 -218.519293)
			(xy 126.512784 -218.565567) (xy 126.528832 -218.61496) (xy 126.536957 -218.666255) (xy 126.537466 -218.692222)
			(xy 126.816358 -218.692222) (xy 126.816765 -218.666768) (xy 126.824554 -218.616461) (xy 126.839969 -218.567943)
			(xy 126.862642 -218.522364) (xy 126.892039 -218.480803) (xy 126.927462 -218.444242) (xy 126.968074 -218.413547)
			(xy 127.012914 -218.389444) (xy 127.06092 -218.372505) (xy 127.085852 -218.367356) (xy 127.108712 -218.363038)
			(xy 127.312674 -218.00947) (xy 127.305054 -217.987626) (xy 127.296433 -217.961211) (xy 127.287108 -217.906439)
			(xy 127.286512 -217.87866) (xy 127.286512 -217.878406) (xy 127.287021 -217.852439) (xy 127.295146 -217.801144)
			(xy 127.311194 -217.751751) (xy 127.334772 -217.705477) (xy 127.365298 -217.663461) (xy 127.402021 -217.626738)
			(xy 127.444037 -217.596212) (xy 127.490311 -217.572634) (xy 127.539704 -217.556586) (xy 127.590999 -217.548461)
			(xy 127.642933 -217.548461) (xy 127.694228 -217.556586) (xy 127.743621 -217.572634) (xy 127.789895 -217.596212)
			(xy 127.831911 -217.626738) (xy 127.868634 -217.663461) (xy 127.89916 -217.705477) (xy 127.922738 -217.751751)
			(xy 127.938786 -217.801144) (xy 127.946911 -217.852439) (xy 127.94742 -217.878406) (xy 127.946971 -217.903881)
			(xy 127.93915 -217.954227) (xy 127.923694 -218.002775) (xy 127.900969 -218.048376) (xy 127.871514 -218.089949)
			(xy 127.836027 -218.126507) (xy 127.795349 -218.157186) (xy 127.750445 -218.181258) (xy 127.702377 -218.198151)
			(xy 127.677418 -218.203272) (xy 127.654304 -218.20759) (xy 127.45085 -218.560396) (xy 127.45847 -218.582494)
			(xy 127.467205 -218.609083) (xy 127.476655 -218.664242) (xy 127.477266 -218.692222) (xy 128.695958 -218.692222)
			(xy 128.696365 -218.666768) (xy 128.704154 -218.616461) (xy 128.719569 -218.567943) (xy 128.742242 -218.522364)
			(xy 128.771639 -218.480803) (xy 128.807062 -218.444242) (xy 128.847674 -218.413547) (xy 128.892514 -218.389444)
			(xy 128.94052 -218.372505) (xy 128.965452 -218.367356) (xy 128.988312 -218.363038) (xy 129.192274 -218.00947)
			(xy 129.184654 -217.987626) (xy 129.176033 -217.961211) (xy 129.166708 -217.906439) (xy 129.166112 -217.87866)
			(xy 129.166112 -217.878406) (xy 129.166621 -217.852439) (xy 129.174746 -217.801144) (xy 129.190794 -217.751751)
			(xy 129.214372 -217.705477) (xy 129.244898 -217.663461) (xy 129.281621 -217.626738) (xy 129.323637 -217.596212)
			(xy 129.369911 -217.572634) (xy 129.419304 -217.556586) (xy 129.470599 -217.548461) (xy 129.522533 -217.548461)
			(xy 129.573828 -217.556586) (xy 129.623221 -217.572634) (xy 129.669495 -217.596212) (xy 129.711511 -217.626738)
			(xy 129.748234 -217.663461) (xy 129.77876 -217.705477) (xy 129.802338 -217.751751) (xy 129.818386 -217.801144)
			(xy 129.826511 -217.852439) (xy 129.82702 -217.878406) (xy 129.826571 -217.903881) (xy 129.81875 -217.954227)
			(xy 129.803294 -218.002775) (xy 129.780569 -218.048376) (xy 129.751114 -218.089949) (xy 129.715627 -218.126507)
			(xy 129.674949 -218.157186) (xy 129.630045 -218.181258) (xy 129.581977 -218.198151) (xy 129.557018 -218.203272)
			(xy 129.533904 -218.20759) (xy 129.33045 -218.560396) (xy 129.33807 -218.582494) (xy 129.346805 -218.609083)
			(xy 129.356255 -218.664242) (xy 129.356866 -218.692222) (xy 130.575558 -218.692222) (xy 130.575965 -218.666768)
			(xy 130.583754 -218.616461) (xy 130.599169 -218.567943) (xy 130.621842 -218.522364) (xy 130.651239 -218.480803)
			(xy 130.686662 -218.444242) (xy 130.727274 -218.413547) (xy 130.772114 -218.389444) (xy 130.82012 -218.372505)
			(xy 130.845052 -218.367356) (xy 130.867912 -218.363038) (xy 131.071874 -218.00947) (xy 131.064254 -217.987626)
			(xy 131.055633 -217.961211) (xy 131.046308 -217.906439) (xy 131.045712 -217.87866) (xy 131.045712 -217.878406)
			(xy 131.046221 -217.852439) (xy 131.054346 -217.801144) (xy 131.070394 -217.751751) (xy 131.093972 -217.705477)
			(xy 131.124498 -217.663461) (xy 131.161221 -217.626738) (xy 131.203237 -217.596212) (xy 131.249511 -217.572634)
			(xy 131.298904 -217.556586) (xy 131.350199 -217.548461) (xy 131.402133 -217.548461) (xy 131.453428 -217.556586)
			(xy 131.502821 -217.572634) (xy 131.549095 -217.596212) (xy 131.591111 -217.626738) (xy 131.627834 -217.663461)
			(xy 131.65836 -217.705477) (xy 131.681938 -217.751751) (xy 131.697986 -217.801144) (xy 131.706111 -217.852439)
			(xy 131.70662 -217.878406) (xy 131.706171 -217.903881) (xy 131.69835 -217.954227) (xy 131.682894 -218.002775)
			(xy 131.660169 -218.048376) (xy 131.630714 -218.089949) (xy 131.595227 -218.126507) (xy 131.554549 -218.157186)
			(xy 131.509645 -218.181258) (xy 131.461577 -218.198151) (xy 131.436618 -218.203272) (xy 131.413504 -218.20759)
			(xy 131.21005 -218.560396) (xy 131.21767 -218.582494) (xy 131.226405 -218.609083) (xy 131.235855 -218.664242)
			(xy 131.236466 -218.692222) (xy 132.455158 -218.692222) (xy 132.455565 -218.666768) (xy 132.463354 -218.616461)
			(xy 132.478769 -218.567943) (xy 132.501442 -218.522364) (xy 132.530839 -218.480803) (xy 132.566262 -218.444242)
			(xy 132.606874 -218.413547) (xy 132.651714 -218.389444) (xy 132.69972 -218.372505) (xy 132.724652 -218.367356)
			(xy 132.747512 -218.363038) (xy 132.951474 -218.00947) (xy 132.943854 -217.987626) (xy 132.935233 -217.961211)
			(xy 132.925908 -217.906439) (xy 132.925312 -217.87866) (xy 132.925312 -217.878406) (xy 132.925821 -217.852439)
			(xy 132.933946 -217.801144) (xy 132.949994 -217.751751) (xy 132.973572 -217.705477) (xy 133.004098 -217.663461)
			(xy 133.040821 -217.626738) (xy 133.082837 -217.596212) (xy 133.129111 -217.572634) (xy 133.178504 -217.556586)
			(xy 133.229799 -217.548461) (xy 133.281733 -217.548461) (xy 133.333028 -217.556586) (xy 133.382421 -217.572634)
			(xy 133.428695 -217.596212) (xy 133.470711 -217.626738) (xy 133.507434 -217.663461) (xy 133.53796 -217.705477)
			(xy 133.561538 -217.751751) (xy 133.577586 -217.801144) (xy 133.585711 -217.852439) (xy 133.58622 -217.878406)
			(xy 133.585771 -217.903881) (xy 133.57795 -217.954227) (xy 133.562494 -218.002775) (xy 133.539769 -218.048376)
			(xy 133.510314 -218.089949) (xy 133.474827 -218.126507) (xy 133.434149 -218.157186) (xy 133.389245 -218.181258)
			(xy 133.341177 -218.198151) (xy 133.316218 -218.203272) (xy 133.293104 -218.20759) (xy 133.08965 -218.560396)
			(xy 133.09727 -218.582494) (xy 133.106005 -218.609083) (xy 133.115455 -218.664242) (xy 133.116066 -218.692222)
			(xy 133.115557 -218.718189) (xy 133.107432 -218.769484) (xy 133.091384 -218.818877) (xy 133.067806 -218.865151)
			(xy 133.03728 -218.907167) (xy 133.000557 -218.94389) (xy 132.958541 -218.974416) (xy 132.912267 -218.997994)
			(xy 132.862874 -219.014042) (xy 132.811579 -219.022167) (xy 132.759645 -219.022167) (xy 132.70835 -219.014042)
			(xy 132.658957 -218.997994) (xy 132.612683 -218.974416) (xy 132.570667 -218.94389) (xy 132.533944 -218.907167)
			(xy 132.503418 -218.865151) (xy 132.47984 -218.818877) (xy 132.463792 -218.769484) (xy 132.455667 -218.718189)
			(xy 132.455158 -218.692222) (xy 131.236466 -218.692222) (xy 131.235957 -218.718189) (xy 131.227832 -218.769484)
			(xy 131.211784 -218.818877) (xy 131.188206 -218.865151) (xy 131.15768 -218.907167) (xy 131.120957 -218.94389)
			(xy 131.078941 -218.974416) (xy 131.032667 -218.997994) (xy 130.983274 -219.014042) (xy 130.931979 -219.022167)
			(xy 130.880045 -219.022167) (xy 130.82875 -219.014042) (xy 130.779357 -218.997994) (xy 130.733083 -218.974416)
			(xy 130.691067 -218.94389) (xy 130.654344 -218.907167) (xy 130.623818 -218.865151) (xy 130.60024 -218.818877)
			(xy 130.584192 -218.769484) (xy 130.576067 -218.718189) (xy 130.575558 -218.692222) (xy 129.356866 -218.692222)
			(xy 129.356357 -218.718189) (xy 129.348232 -218.769484) (xy 129.332184 -218.818877) (xy 129.308606 -218.865151)
			(xy 129.27808 -218.907167) (xy 129.241357 -218.94389) (xy 129.199341 -218.974416) (xy 129.153067 -218.997994)
			(xy 129.103674 -219.014042) (xy 129.052379 -219.022167) (xy 129.000445 -219.022167) (xy 128.94915 -219.014042)
			(xy 128.899757 -218.997994) (xy 128.853483 -218.974416) (xy 128.811467 -218.94389) (xy 128.774744 -218.907167)
			(xy 128.744218 -218.865151) (xy 128.72064 -218.818877) (xy 128.704592 -218.769484) (xy 128.696467 -218.718189)
			(xy 128.695958 -218.692222) (xy 127.477266 -218.692222) (xy 127.476757 -218.718189) (xy 127.468632 -218.769484)
			(xy 127.452584 -218.818877) (xy 127.429006 -218.865151) (xy 127.39848 -218.907167) (xy 127.361757 -218.94389)
			(xy 127.319741 -218.974416) (xy 127.273467 -218.997994) (xy 127.224074 -219.014042) (xy 127.172779 -219.022167)
			(xy 127.120845 -219.022167) (xy 127.06955 -219.014042) (xy 127.020157 -218.997994) (xy 126.973883 -218.974416)
			(xy 126.931867 -218.94389) (xy 126.895144 -218.907167) (xy 126.864618 -218.865151) (xy 126.84104 -218.818877)
			(xy 126.824992 -218.769484) (xy 126.816867 -218.718189) (xy 126.816358 -218.692222) (xy 126.537466 -218.692222)
			(xy 126.536957 -218.718189) (xy 126.528832 -218.769484) (xy 126.512784 -218.818877) (xy 126.489206 -218.865151)
			(xy 126.45868 -218.907167) (xy 126.421957 -218.94389) (xy 126.379941 -218.974416) (xy 126.333667 -218.997994)
			(xy 126.284274 -219.014042) (xy 126.232979 -219.022167) (xy 126.181045 -219.022167) (xy 126.12975 -219.014042)
			(xy 126.080357 -218.997994) (xy 126.034083 -218.974416) (xy 125.992067 -218.94389) (xy 125.955344 -218.907167)
			(xy 125.924818 -218.865151) (xy 125.90124 -218.818877) (xy 125.885192 -218.769484) (xy 125.877067 -218.718189)
			(xy 125.597157 -218.718189) (xy 125.589032 -218.769484) (xy 125.572984 -218.818877) (xy 125.549406 -218.865151)
			(xy 125.51888 -218.907167) (xy 125.482157 -218.94389) (xy 125.440141 -218.974416) (xy 125.393867 -218.997994)
			(xy 125.344474 -219.014042) (xy 125.293179 -219.022167) (xy 125.241245 -219.022167) (xy 125.18995 -219.014042)
			(xy 125.140557 -218.997994) (xy 125.094283 -218.974416) (xy 125.052267 -218.94389) (xy 125.015544 -218.907167)
			(xy 124.985018 -218.865151) (xy 124.96144 -218.818877) (xy 124.945392 -218.769484) (xy 124.937267 -218.718189)
			(xy 124.936758 -218.692222) (xy 124.657866 -218.692222) (xy 124.657357 -218.718189) (xy 124.649232 -218.769484)
			(xy 124.633184 -218.818877) (xy 124.609606 -218.865151) (xy 124.57908 -218.907167) (xy 124.542357 -218.94389)
			(xy 124.500341 -218.974416) (xy 124.454067 -218.997994) (xy 124.404674 -219.014042) (xy 124.353379 -219.022167)
			(xy 124.301445 -219.022167) (xy 124.25015 -219.014042) (xy 124.200757 -218.997994) (xy 124.154483 -218.974416)
			(xy 124.112467 -218.94389) (xy 124.075744 -218.907167) (xy 124.045218 -218.865151) (xy 124.02164 -218.818877)
			(xy 124.005592 -218.769484) (xy 123.997467 -218.718189) (xy 123.717557 -218.718189) (xy 123.709432 -218.769484)
			(xy 123.693384 -218.818877) (xy 123.669806 -218.865151) (xy 123.63928 -218.907167) (xy 123.602557 -218.94389)
			(xy 123.560541 -218.974416) (xy 123.514267 -218.997994) (xy 123.464874 -219.014042) (xy 123.413579 -219.022167)
			(xy 123.361645 -219.022167) (xy 123.31035 -219.014042) (xy 123.260957 -218.997994) (xy 123.214683 -218.974416)
			(xy 123.172667 -218.94389) (xy 123.135944 -218.907167) (xy 123.105418 -218.865151) (xy 123.08184 -218.818877)
			(xy 123.065792 -218.769484) (xy 123.057667 -218.718189) (xy 123.057158 -218.692222) (xy 122.778266 -218.692222)
			(xy 122.777757 -218.718189) (xy 122.769632 -218.769484) (xy 122.753584 -218.818877) (xy 122.730006 -218.865151)
			(xy 122.69948 -218.907167) (xy 122.662757 -218.94389) (xy 122.620741 -218.974416) (xy 122.574467 -218.997994)
			(xy 122.525074 -219.014042) (xy 122.473779 -219.022167) (xy 122.421845 -219.022167) (xy 122.37055 -219.014042)
			(xy 122.321157 -218.997994) (xy 122.274883 -218.974416) (xy 122.232867 -218.94389) (xy 122.196144 -218.907167)
			(xy 122.165618 -218.865151) (xy 122.14204 -218.818877) (xy 122.125992 -218.769484) (xy 122.117867 -218.718189)
			(xy 121.837957 -218.718189) (xy 121.829832 -218.769484) (xy 121.813784 -218.818877) (xy 121.790206 -218.865151)
			(xy 121.75968 -218.907167) (xy 121.722957 -218.94389) (xy 121.680941 -218.974416) (xy 121.634667 -218.997994)
			(xy 121.585274 -219.014042) (xy 121.533979 -219.022167) (xy 121.482045 -219.022167) (xy 121.43075 -219.014042)
			(xy 121.381357 -218.997994) (xy 121.335083 -218.974416) (xy 121.293067 -218.94389) (xy 121.256344 -218.907167)
			(xy 121.225818 -218.865151) (xy 121.20224 -218.818877) (xy 121.186192 -218.769484) (xy 121.178067 -218.718189)
			(xy 121.177558 -218.692222) (xy 121.01068 -218.692222) (xy 121.01068 -219.125546) (xy 121.058432 -219.176092)
			(xy 121.084638 -219.178192) (xy 121.135946 -219.189644) (xy 121.184793 -219.209074) (xy 121.22995 -219.235991)
			(xy 121.270276 -219.269717) (xy 121.304755 -219.309401) (xy 121.332517 -219.354042) (xy 121.352863 -219.402515)
			(xy 121.365279 -219.453598) (xy 121.369453 -219.506002) (xy 121.367382 -219.532005) (xy 121.648221 -219.532005)
			(xy 121.648221 -219.480071) (xy 121.656346 -219.428776) (xy 121.672394 -219.379383) (xy 121.695972 -219.333109)
			(xy 121.726498 -219.291093) (xy 121.763221 -219.25437) (xy 121.805237 -219.223844) (xy 121.851511 -219.200266)
			(xy 121.900904 -219.184218) (xy 121.952199 -219.176093) (xy 122.004133 -219.176093) (xy 122.055428 -219.184218)
			(xy 122.104821 -219.200266) (xy 122.151095 -219.223844) (xy 122.193111 -219.25437) (xy 122.229834 -219.291093)
			(xy 122.26036 -219.333109) (xy 122.283938 -219.379383) (xy 122.299986 -219.428776) (xy 122.308111 -219.480071)
			(xy 122.30862 -219.506038) (xy 122.308111 -219.532005) (xy 122.588021 -219.532005) (xy 122.588021 -219.480071)
			(xy 122.596146 -219.428776) (xy 122.612194 -219.379383) (xy 122.635772 -219.333109) (xy 122.666298 -219.291093)
			(xy 122.703021 -219.25437) (xy 122.745037 -219.223844) (xy 122.791311 -219.200266) (xy 122.840704 -219.184218)
			(xy 122.891999 -219.176093) (xy 122.943933 -219.176093) (xy 122.995228 -219.184218) (xy 123.044621 -219.200266)
			(xy 123.090895 -219.223844) (xy 123.132911 -219.25437) (xy 123.169634 -219.291093) (xy 123.20016 -219.333109)
			(xy 123.223738 -219.379383) (xy 123.239786 -219.428776) (xy 123.247911 -219.480071) (xy 123.24842 -219.506038)
			(xy 123.247911 -219.532005) (xy 123.527821 -219.532005) (xy 123.527821 -219.480071) (xy 123.535946 -219.428776)
			(xy 123.551994 -219.379383) (xy 123.575572 -219.333109) (xy 123.606098 -219.291093) (xy 123.642821 -219.25437)
			(xy 123.684837 -219.223844) (xy 123.731111 -219.200266) (xy 123.780504 -219.184218) (xy 123.831799 -219.176093)
			(xy 123.883733 -219.176093) (xy 123.935028 -219.184218) (xy 123.984421 -219.200266) (xy 124.030695 -219.223844)
			(xy 124.072711 -219.25437) (xy 124.109434 -219.291093) (xy 124.13996 -219.333109) (xy 124.163538 -219.379383)
			(xy 124.179586 -219.428776) (xy 124.187711 -219.480071) (xy 124.18822 -219.506038) (xy 124.187711 -219.532005)
			(xy 124.467621 -219.532005) (xy 124.467621 -219.480071) (xy 124.475746 -219.428776) (xy 124.491794 -219.379383)
			(xy 124.515372 -219.333109) (xy 124.545898 -219.291093) (xy 124.582621 -219.25437) (xy 124.624637 -219.223844)
			(xy 124.670911 -219.200266) (xy 124.720304 -219.184218) (xy 124.771599 -219.176093) (xy 124.823533 -219.176093)
			(xy 124.874828 -219.184218) (xy 124.924221 -219.200266) (xy 124.970495 -219.223844) (xy 125.012511 -219.25437)
			(xy 125.049234 -219.291093) (xy 125.07976 -219.333109) (xy 125.103338 -219.379383) (xy 125.119386 -219.428776)
			(xy 125.127511 -219.480071) (xy 125.12802 -219.506038) (xy 125.127511 -219.532005) (xy 125.407421 -219.532005)
			(xy 125.407421 -219.480071) (xy 125.415546 -219.428776) (xy 125.431594 -219.379383) (xy 125.455172 -219.333109)
			(xy 125.485698 -219.291093) (xy 125.522421 -219.25437) (xy 125.564437 -219.223844) (xy 125.610711 -219.200266)
			(xy 125.660104 -219.184218) (xy 125.711399 -219.176093) (xy 125.763333 -219.176093) (xy 125.814628 -219.184218)
			(xy 125.864021 -219.200266) (xy 125.910295 -219.223844) (xy 125.952311 -219.25437) (xy 125.989034 -219.291093)
			(xy 126.01956 -219.333109) (xy 126.043138 -219.379383) (xy 126.059186 -219.428776) (xy 126.067311 -219.480071)
			(xy 126.06782 -219.506038) (xy 126.067311 -219.532005) (xy 126.347221 -219.532005) (xy 126.347221 -219.480071)
			(xy 126.355346 -219.428776) (xy 126.371394 -219.379383) (xy 126.394972 -219.333109) (xy 126.425498 -219.291093)
			(xy 126.462221 -219.25437) (xy 126.504237 -219.223844) (xy 126.550511 -219.200266) (xy 126.599904 -219.184218)
			(xy 126.651199 -219.176093) (xy 126.703133 -219.176093) (xy 126.754428 -219.184218) (xy 126.803821 -219.200266)
			(xy 126.850095 -219.223844) (xy 126.892111 -219.25437) (xy 126.928834 -219.291093) (xy 126.95936 -219.333109)
			(xy 126.982938 -219.379383) (xy 126.998986 -219.428776) (xy 127.007111 -219.480071) (xy 127.00762 -219.506038)
			(xy 127.007111 -219.532005) (xy 127.287021 -219.532005) (xy 127.287021 -219.480071) (xy 127.295146 -219.428776)
			(xy 127.311194 -219.379383) (xy 127.334772 -219.333109) (xy 127.365298 -219.291093) (xy 127.402021 -219.25437)
			(xy 127.444037 -219.223844) (xy 127.490311 -219.200266) (xy 127.539704 -219.184218) (xy 127.590999 -219.176093)
			(xy 127.642933 -219.176093) (xy 127.694228 -219.184218) (xy 127.743621 -219.200266) (xy 127.789895 -219.223844)
			(xy 127.831911 -219.25437) (xy 127.868634 -219.291093) (xy 127.89916 -219.333109) (xy 127.922738 -219.379383)
			(xy 127.938786 -219.428776) (xy 127.946911 -219.480071) (xy 127.94742 -219.506038) (xy 127.946911 -219.532005)
			(xy 128.226821 -219.532005) (xy 128.226821 -219.480071) (xy 128.234946 -219.428776) (xy 128.250994 -219.379383)
			(xy 128.274572 -219.333109) (xy 128.305098 -219.291093) (xy 128.341821 -219.25437) (xy 128.383837 -219.223844)
			(xy 128.430111 -219.200266) (xy 128.479504 -219.184218) (xy 128.530799 -219.176093) (xy 128.582733 -219.176093)
			(xy 128.634028 -219.184218) (xy 128.683421 -219.200266) (xy 128.729695 -219.223844) (xy 128.771711 -219.25437)
			(xy 128.808434 -219.291093) (xy 128.83896 -219.333109) (xy 128.862538 -219.379383) (xy 128.878586 -219.428776)
			(xy 128.886711 -219.480071) (xy 128.88722 -219.506038) (xy 128.886711 -219.532005) (xy 129.166621 -219.532005)
			(xy 129.166621 -219.480071) (xy 129.174746 -219.428776) (xy 129.190794 -219.379383) (xy 129.214372 -219.333109)
			(xy 129.244898 -219.291093) (xy 129.281621 -219.25437) (xy 129.323637 -219.223844) (xy 129.369911 -219.200266)
			(xy 129.419304 -219.184218) (xy 129.470599 -219.176093) (xy 129.522533 -219.176093) (xy 129.573828 -219.184218)
			(xy 129.623221 -219.200266) (xy 129.669495 -219.223844) (xy 129.711511 -219.25437) (xy 129.748234 -219.291093)
			(xy 129.77876 -219.333109) (xy 129.802338 -219.379383) (xy 129.818386 -219.428776) (xy 129.826511 -219.480071)
			(xy 129.82702 -219.506038) (xy 129.826511 -219.532005) (xy 130.106421 -219.532005) (xy 130.106421 -219.480071)
			(xy 130.114546 -219.428776) (xy 130.130594 -219.379383) (xy 130.154172 -219.333109) (xy 130.184698 -219.291093)
			(xy 130.221421 -219.25437) (xy 130.263437 -219.223844) (xy 130.309711 -219.200266) (xy 130.359104 -219.184218)
			(xy 130.410399 -219.176093) (xy 130.462333 -219.176093) (xy 130.513628 -219.184218) (xy 130.563021 -219.200266)
			(xy 130.609295 -219.223844) (xy 130.651311 -219.25437) (xy 130.688034 -219.291093) (xy 130.71856 -219.333109)
			(xy 130.742138 -219.379383) (xy 130.758186 -219.428776) (xy 130.766311 -219.480071) (xy 130.76682 -219.506038)
			(xy 130.766311 -219.532005) (xy 131.046221 -219.532005) (xy 131.046221 -219.480071) (xy 131.054346 -219.428776)
			(xy 131.070394 -219.379383) (xy 131.093972 -219.333109) (xy 131.124498 -219.291093) (xy 131.161221 -219.25437)
			(xy 131.203237 -219.223844) (xy 131.249511 -219.200266) (xy 131.298904 -219.184218) (xy 131.350199 -219.176093)
			(xy 131.402133 -219.176093) (xy 131.453428 -219.184218) (xy 131.502821 -219.200266) (xy 131.549095 -219.223844)
			(xy 131.591111 -219.25437) (xy 131.627834 -219.291093) (xy 131.65836 -219.333109) (xy 131.681938 -219.379383)
			(xy 131.697986 -219.428776) (xy 131.706111 -219.480071) (xy 131.70662 -219.506038) (xy 131.706111 -219.532005)
			(xy 131.986021 -219.532005) (xy 131.986021 -219.480071) (xy 131.994146 -219.428776) (xy 132.010194 -219.379383)
			(xy 132.033772 -219.333109) (xy 132.064298 -219.291093) (xy 132.101021 -219.25437) (xy 132.143037 -219.223844)
			(xy 132.189311 -219.200266) (xy 132.238704 -219.184218) (xy 132.289999 -219.176093) (xy 132.341933 -219.176093)
			(xy 132.393228 -219.184218) (xy 132.442621 -219.200266) (xy 132.488895 -219.223844) (xy 132.530911 -219.25437)
			(xy 132.567634 -219.291093) (xy 132.59816 -219.333109) (xy 132.621738 -219.379383) (xy 132.637786 -219.428776)
			(xy 132.645911 -219.480071) (xy 132.64642 -219.506038) (xy 132.645911 -219.532005) (xy 132.925821 -219.532005)
			(xy 132.925821 -219.480071) (xy 132.933946 -219.428776) (xy 132.949994 -219.379383) (xy 132.973572 -219.333109)
			(xy 133.004098 -219.291093) (xy 133.040821 -219.25437) (xy 133.082837 -219.223844) (xy 133.129111 -219.200266)
			(xy 133.178504 -219.184218) (xy 133.229799 -219.176093) (xy 133.281733 -219.176093) (xy 133.333028 -219.184218)
			(xy 133.382421 -219.200266) (xy 133.428695 -219.223844) (xy 133.470711 -219.25437) (xy 133.507434 -219.291093)
			(xy 133.53796 -219.333109) (xy 133.561538 -219.379383) (xy 133.577586 -219.428776) (xy 133.585711 -219.480071)
			(xy 133.58622 -219.506038) (xy 133.585711 -219.532005) (xy 133.865621 -219.532005) (xy 133.865621 -219.480071)
			(xy 133.873746 -219.428776) (xy 133.889794 -219.379383) (xy 133.913372 -219.333109) (xy 133.943898 -219.291093)
			(xy 133.980621 -219.25437) (xy 134.022637 -219.223844) (xy 134.068911 -219.200266) (xy 134.118304 -219.184218)
			(xy 134.169599 -219.176093) (xy 134.221533 -219.176093) (xy 134.272828 -219.184218) (xy 134.322221 -219.200266)
			(xy 134.368495 -219.223844) (xy 134.410511 -219.25437) (xy 134.447234 -219.291093) (xy 134.47776 -219.333109)
			(xy 134.501338 -219.379383) (xy 134.517386 -219.428776) (xy 134.525511 -219.480071) (xy 134.52602 -219.506038)
			(xy 134.525511 -219.532005) (xy 134.517386 -219.5833) (xy 134.501338 -219.632693) (xy 134.47776 -219.678967)
			(xy 134.447234 -219.720983) (xy 134.410511 -219.757706) (xy 134.368495 -219.788232) (xy 134.322221 -219.81181)
			(xy 134.272828 -219.827858) (xy 134.221533 -219.835983) (xy 134.169599 -219.835983) (xy 134.118304 -219.827858)
			(xy 134.068911 -219.81181) (xy 134.022637 -219.788232) (xy 133.980621 -219.757706) (xy 133.943898 -219.720983)
			(xy 133.913372 -219.678967) (xy 133.889794 -219.632693) (xy 133.873746 -219.5833) (xy 133.865621 -219.532005)
			(xy 133.585711 -219.532005) (xy 133.577586 -219.5833) (xy 133.561538 -219.632693) (xy 133.53796 -219.678967)
			(xy 133.507434 -219.720983) (xy 133.470711 -219.757706) (xy 133.428695 -219.788232) (xy 133.382421 -219.81181)
			(xy 133.333028 -219.827858) (xy 133.281733 -219.835983) (xy 133.229799 -219.835983) (xy 133.178504 -219.827858)
			(xy 133.129111 -219.81181) (xy 133.082837 -219.788232) (xy 133.040821 -219.757706) (xy 133.004098 -219.720983)
			(xy 132.973572 -219.678967) (xy 132.949994 -219.632693) (xy 132.933946 -219.5833) (xy 132.925821 -219.532005)
			(xy 132.645911 -219.532005) (xy 132.637786 -219.5833) (xy 132.621738 -219.632693) (xy 132.59816 -219.678967)
			(xy 132.567634 -219.720983) (xy 132.530911 -219.757706) (xy 132.488895 -219.788232) (xy 132.442621 -219.81181)
			(xy 132.393228 -219.827858) (xy 132.341933 -219.835983) (xy 132.289999 -219.835983) (xy 132.238704 -219.827858)
			(xy 132.189311 -219.81181) (xy 132.143037 -219.788232) (xy 132.101021 -219.757706) (xy 132.064298 -219.720983)
			(xy 132.033772 -219.678967) (xy 132.010194 -219.632693) (xy 131.994146 -219.5833) (xy 131.986021 -219.532005)
			(xy 131.706111 -219.532005) (xy 131.697986 -219.5833) (xy 131.681938 -219.632693) (xy 131.65836 -219.678967)
			(xy 131.627834 -219.720983) (xy 131.591111 -219.757706) (xy 131.549095 -219.788232) (xy 131.502821 -219.81181)
			(xy 131.453428 -219.827858) (xy 131.402133 -219.835983) (xy 131.350199 -219.835983) (xy 131.298904 -219.827858)
			(xy 131.249511 -219.81181) (xy 131.203237 -219.788232) (xy 131.161221 -219.757706) (xy 131.124498 -219.720983)
			(xy 131.093972 -219.678967) (xy 131.070394 -219.632693) (xy 131.054346 -219.5833) (xy 131.046221 -219.532005)
			(xy 130.766311 -219.532005) (xy 130.758186 -219.5833) (xy 130.742138 -219.632693) (xy 130.71856 -219.678967)
			(xy 130.688034 -219.720983) (xy 130.651311 -219.757706) (xy 130.609295 -219.788232) (xy 130.563021 -219.81181)
			(xy 130.513628 -219.827858) (xy 130.462333 -219.835983) (xy 130.410399 -219.835983) (xy 130.359104 -219.827858)
			(xy 130.309711 -219.81181) (xy 130.263437 -219.788232) (xy 130.221421 -219.757706) (xy 130.184698 -219.720983)
			(xy 130.154172 -219.678967) (xy 130.130594 -219.632693) (xy 130.114546 -219.5833) (xy 130.106421 -219.532005)
			(xy 129.826511 -219.532005) (xy 129.818386 -219.5833) (xy 129.802338 -219.632693) (xy 129.77876 -219.678967)
			(xy 129.748234 -219.720983) (xy 129.711511 -219.757706) (xy 129.669495 -219.788232) (xy 129.623221 -219.81181)
			(xy 129.573828 -219.827858) (xy 129.522533 -219.835983) (xy 129.470599 -219.835983) (xy 129.419304 -219.827858)
			(xy 129.369911 -219.81181) (xy 129.323637 -219.788232) (xy 129.281621 -219.757706) (xy 129.244898 -219.720983)
			(xy 129.214372 -219.678967) (xy 129.190794 -219.632693) (xy 129.174746 -219.5833) (xy 129.166621 -219.532005)
			(xy 128.886711 -219.532005) (xy 128.878586 -219.5833) (xy 128.862538 -219.632693) (xy 128.83896 -219.678967)
			(xy 128.808434 -219.720983) (xy 128.771711 -219.757706) (xy 128.729695 -219.788232) (xy 128.683421 -219.81181)
			(xy 128.634028 -219.827858) (xy 128.582733 -219.835983) (xy 128.530799 -219.835983) (xy 128.479504 -219.827858)
			(xy 128.430111 -219.81181) (xy 128.383837 -219.788232) (xy 128.341821 -219.757706) (xy 128.305098 -219.720983)
			(xy 128.274572 -219.678967) (xy 128.250994 -219.632693) (xy 128.234946 -219.5833) (xy 128.226821 -219.532005)
			(xy 127.946911 -219.532005) (xy 127.938786 -219.5833) (xy 127.922738 -219.632693) (xy 127.89916 -219.678967)
			(xy 127.868634 -219.720983) (xy 127.831911 -219.757706) (xy 127.789895 -219.788232) (xy 127.743621 -219.81181)
			(xy 127.694228 -219.827858) (xy 127.642933 -219.835983) (xy 127.590999 -219.835983) (xy 127.539704 -219.827858)
			(xy 127.490311 -219.81181) (xy 127.444037 -219.788232) (xy 127.402021 -219.757706) (xy 127.365298 -219.720983)
			(xy 127.334772 -219.678967) (xy 127.311194 -219.632693) (xy 127.295146 -219.5833) (xy 127.287021 -219.532005)
			(xy 127.007111 -219.532005) (xy 126.998986 -219.5833) (xy 126.982938 -219.632693) (xy 126.95936 -219.678967)
			(xy 126.928834 -219.720983) (xy 126.892111 -219.757706) (xy 126.850095 -219.788232) (xy 126.803821 -219.81181)
			(xy 126.754428 -219.827858) (xy 126.703133 -219.835983) (xy 126.651199 -219.835983) (xy 126.599904 -219.827858)
			(xy 126.550511 -219.81181) (xy 126.504237 -219.788232) (xy 126.462221 -219.757706) (xy 126.425498 -219.720983)
			(xy 126.394972 -219.678967) (xy 126.371394 -219.632693) (xy 126.355346 -219.5833) (xy 126.347221 -219.532005)
			(xy 126.067311 -219.532005) (xy 126.059186 -219.5833) (xy 126.043138 -219.632693) (xy 126.01956 -219.678967)
			(xy 125.989034 -219.720983) (xy 125.952311 -219.757706) (xy 125.910295 -219.788232) (xy 125.864021 -219.81181)
			(xy 125.814628 -219.827858) (xy 125.763333 -219.835983) (xy 125.711399 -219.835983) (xy 125.660104 -219.827858)
			(xy 125.610711 -219.81181) (xy 125.564437 -219.788232) (xy 125.522421 -219.757706) (xy 125.485698 -219.720983)
			(xy 125.455172 -219.678967) (xy 125.431594 -219.632693) (xy 125.415546 -219.5833) (xy 125.407421 -219.532005)
			(xy 125.127511 -219.532005) (xy 125.119386 -219.5833) (xy 125.103338 -219.632693) (xy 125.07976 -219.678967)
			(xy 125.049234 -219.720983) (xy 125.012511 -219.757706) (xy 124.970495 -219.788232) (xy 124.924221 -219.81181)
			(xy 124.874828 -219.827858) (xy 124.823533 -219.835983) (xy 124.771599 -219.835983) (xy 124.720304 -219.827858)
			(xy 124.670911 -219.81181) (xy 124.624637 -219.788232) (xy 124.582621 -219.757706) (xy 124.545898 -219.720983)
			(xy 124.515372 -219.678967) (xy 124.491794 -219.632693) (xy 124.475746 -219.5833) (xy 124.467621 -219.532005)
			(xy 124.187711 -219.532005) (xy 124.179586 -219.5833) (xy 124.163538 -219.632693) (xy 124.13996 -219.678967)
			(xy 124.109434 -219.720983) (xy 124.072711 -219.757706) (xy 124.030695 -219.788232) (xy 123.984421 -219.81181)
			(xy 123.935028 -219.827858) (xy 123.883733 -219.835983) (xy 123.831799 -219.835983) (xy 123.780504 -219.827858)
			(xy 123.731111 -219.81181) (xy 123.684837 -219.788232) (xy 123.642821 -219.757706) (xy 123.606098 -219.720983)
			(xy 123.575572 -219.678967) (xy 123.551994 -219.632693) (xy 123.535946 -219.5833) (xy 123.527821 -219.532005)
			(xy 123.247911 -219.532005) (xy 123.239786 -219.5833) (xy 123.223738 -219.632693) (xy 123.20016 -219.678967)
			(xy 123.169634 -219.720983) (xy 123.132911 -219.757706) (xy 123.090895 -219.788232) (xy 123.044621 -219.81181)
			(xy 122.995228 -219.827858) (xy 122.943933 -219.835983) (xy 122.891999 -219.835983) (xy 122.840704 -219.827858)
			(xy 122.791311 -219.81181) (xy 122.745037 -219.788232) (xy 122.703021 -219.757706) (xy 122.666298 -219.720983)
			(xy 122.635772 -219.678967) (xy 122.612194 -219.632693) (xy 122.596146 -219.5833) (xy 122.588021 -219.532005)
			(xy 122.308111 -219.532005) (xy 122.299986 -219.5833) (xy 122.283938 -219.632693) (xy 122.26036 -219.678967)
			(xy 122.229834 -219.720983) (xy 122.193111 -219.757706) (xy 122.151095 -219.788232) (xy 122.104821 -219.81181)
			(xy 122.055428 -219.827858) (xy 122.004133 -219.835983) (xy 121.952199 -219.835983) (xy 121.900904 -219.827858)
			(xy 121.851511 -219.81181) (xy 121.805237 -219.788232) (xy 121.763221 -219.757706) (xy 121.726498 -219.720983)
			(xy 121.695972 -219.678967) (xy 121.672394 -219.632693) (xy 121.656346 -219.5833) (xy 121.648221 -219.532005)
			(xy 121.367382 -219.532005) (xy 121.365279 -219.558406) (xy 121.352862 -219.609489) (xy 121.332515 -219.657962)
			(xy 121.304752 -219.702603) (xy 121.270272 -219.742287) (xy 121.229946 -219.776012) (xy 121.184789 -219.802928)
			(xy 121.135941 -219.822357) (xy 121.084633 -219.833809) (xy 121.058432 -219.835984) (xy 121.01068 -219.88653)
			(xy 121.01068 -220.345821) (xy 121.178321 -220.345821) (xy 121.178321 -220.293887) (xy 121.186446 -220.242592)
			(xy 121.202494 -220.193199) (xy 121.226072 -220.146925) (xy 121.256598 -220.104909) (xy 121.293321 -220.068186)
			(xy 121.335337 -220.03766) (xy 121.381611 -220.014082) (xy 121.431004 -219.998034) (xy 121.482299 -219.989909)
			(xy 121.534233 -219.989909) (xy 121.585528 -219.998034) (xy 121.634921 -220.014082) (xy 121.681195 -220.03766)
			(xy 121.723211 -220.068186) (xy 121.759934 -220.104909) (xy 121.79046 -220.146925) (xy 121.814038 -220.193199)
			(xy 121.830086 -220.242592) (xy 121.838211 -220.293887) (xy 121.83872 -220.319854) (xy 122.117358 -220.319854)
			(xy 122.117867 -220.293887) (xy 122.125992 -220.242592) (xy 122.14204 -220.193199) (xy 122.165618 -220.146925)
			(xy 122.196144 -220.104909) (xy 122.232867 -220.068186) (xy 122.274883 -220.03766) (xy 122.321157 -220.014082)
			(xy 122.37055 -219.998034) (xy 122.421845 -219.989909) (xy 122.473779 -219.989909) (xy 122.525074 -219.998034)
			(xy 122.574467 -220.014082) (xy 122.620741 -220.03766) (xy 122.662757 -220.068186) (xy 122.69948 -220.104909)
			(xy 122.730006 -220.146925) (xy 122.753584 -220.193199) (xy 122.769632 -220.242592) (xy 122.777757 -220.293887)
			(xy 122.778266 -220.319854) (xy 122.778266 -220.320616) (xy 122.777737 -220.345821) (xy 123.057921 -220.345821)
			(xy 123.057921 -220.293887) (xy 123.066046 -220.242592) (xy 123.082094 -220.193199) (xy 123.105672 -220.146925)
			(xy 123.136198 -220.104909) (xy 123.172921 -220.068186) (xy 123.214937 -220.03766) (xy 123.261211 -220.014082)
			(xy 123.310604 -219.998034) (xy 123.361899 -219.989909) (xy 123.413833 -219.989909) (xy 123.465128 -219.998034)
			(xy 123.514521 -220.014082) (xy 123.560795 -220.03766) (xy 123.602811 -220.068186) (xy 123.639534 -220.104909)
			(xy 123.67006 -220.146925) (xy 123.693638 -220.193199) (xy 123.709686 -220.242592) (xy 123.717811 -220.293887)
			(xy 123.71832 -220.319854) (xy 123.996958 -220.319854) (xy 123.997467 -220.293887) (xy 124.005592 -220.242592)
			(xy 124.02164 -220.193199) (xy 124.045218 -220.146925) (xy 124.075744 -220.104909) (xy 124.112467 -220.068186)
			(xy 124.154483 -220.03766) (xy 124.200757 -220.014082) (xy 124.25015 -219.998034) (xy 124.301445 -219.989909)
			(xy 124.353379 -219.989909) (xy 124.404674 -219.998034) (xy 124.454067 -220.014082) (xy 124.500341 -220.03766)
			(xy 124.542357 -220.068186) (xy 124.57908 -220.104909) (xy 124.609606 -220.146925) (xy 124.633184 -220.193199)
			(xy 124.649232 -220.242592) (xy 124.657357 -220.293887) (xy 124.657866 -220.319854) (xy 124.657866 -220.320616)
			(xy 124.657337 -220.345821) (xy 124.937521 -220.345821) (xy 124.937521 -220.293887) (xy 124.945646 -220.242592)
			(xy 124.961694 -220.193199) (xy 124.985272 -220.146925) (xy 125.015798 -220.104909) (xy 125.052521 -220.068186)
			(xy 125.094537 -220.03766) (xy 125.140811 -220.014082) (xy 125.190204 -219.998034) (xy 125.241499 -219.989909)
			(xy 125.293433 -219.989909) (xy 125.344728 -219.998034) (xy 125.394121 -220.014082) (xy 125.440395 -220.03766)
			(xy 125.482411 -220.068186) (xy 125.519134 -220.104909) (xy 125.54966 -220.146925) (xy 125.573238 -220.193199)
			(xy 125.589286 -220.242592) (xy 125.597411 -220.293887) (xy 125.59792 -220.319854) (xy 125.876558 -220.319854)
			(xy 125.877067 -220.293887) (xy 125.885192 -220.242592) (xy 125.90124 -220.193199) (xy 125.924818 -220.146925)
			(xy 125.955344 -220.104909) (xy 125.992067 -220.068186) (xy 126.034083 -220.03766) (xy 126.080357 -220.014082)
			(xy 126.12975 -219.998034) (xy 126.181045 -219.989909) (xy 126.232979 -219.989909) (xy 126.284274 -219.998034)
			(xy 126.333667 -220.014082) (xy 126.379941 -220.03766) (xy 126.421957 -220.068186) (xy 126.45868 -220.104909)
			(xy 126.489206 -220.146925) (xy 126.512784 -220.193199) (xy 126.528832 -220.242592) (xy 126.536957 -220.293887)
			(xy 126.537466 -220.319854) (xy 126.537466 -220.320616) (xy 126.536937 -220.345821) (xy 126.817121 -220.345821)
			(xy 126.817121 -220.293887) (xy 126.825246 -220.242592) (xy 126.841294 -220.193199) (xy 126.864872 -220.146925)
			(xy 126.895398 -220.104909) (xy 126.932121 -220.068186) (xy 126.974137 -220.03766) (xy 127.020411 -220.014082)
			(xy 127.069804 -219.998034) (xy 127.121099 -219.989909) (xy 127.173033 -219.989909) (xy 127.224328 -219.998034)
			(xy 127.273721 -220.014082) (xy 127.319995 -220.03766) (xy 127.362011 -220.068186) (xy 127.398734 -220.104909)
			(xy 127.42926 -220.146925) (xy 127.452838 -220.193199) (xy 127.468886 -220.242592) (xy 127.477011 -220.293887)
			(xy 127.47752 -220.319854) (xy 127.756158 -220.319854) (xy 127.756667 -220.293887) (xy 127.764792 -220.242592)
			(xy 127.78084 -220.193199) (xy 127.804418 -220.146925) (xy 127.834944 -220.104909) (xy 127.871667 -220.068186)
			(xy 127.913683 -220.03766) (xy 127.959957 -220.014082) (xy 128.00935 -219.998034) (xy 128.060645 -219.989909)
			(xy 128.112579 -219.989909) (xy 128.163874 -219.998034) (xy 128.213267 -220.014082) (xy 128.259541 -220.03766)
			(xy 128.301557 -220.068186) (xy 128.33828 -220.104909) (xy 128.368806 -220.146925) (xy 128.392384 -220.193199)
			(xy 128.408432 -220.242592) (xy 128.416557 -220.293887) (xy 128.417066 -220.319854) (xy 128.417066 -220.320616)
			(xy 128.416537 -220.345821) (xy 128.696721 -220.345821) (xy 128.696721 -220.293887) (xy 128.704846 -220.242592)
			(xy 128.720894 -220.193199) (xy 128.744472 -220.146925) (xy 128.774998 -220.104909) (xy 128.811721 -220.068186)
			(xy 128.853737 -220.03766) (xy 128.900011 -220.014082) (xy 128.949404 -219.998034) (xy 129.000699 -219.989909)
			(xy 129.052633 -219.989909) (xy 129.103928 -219.998034) (xy 129.153321 -220.014082) (xy 129.199595 -220.03766)
			(xy 129.241611 -220.068186) (xy 129.278334 -220.104909) (xy 129.30886 -220.146925) (xy 129.332438 -220.193199)
			(xy 129.348486 -220.242592) (xy 129.356611 -220.293887) (xy 129.35712 -220.319854) (xy 129.635758 -220.319854)
			(xy 129.636267 -220.293887) (xy 129.644392 -220.242592) (xy 129.66044 -220.193199) (xy 129.684018 -220.146925)
			(xy 129.714544 -220.104909) (xy 129.751267 -220.068186) (xy 129.793283 -220.03766) (xy 129.839557 -220.014082)
			(xy 129.88895 -219.998034) (xy 129.940245 -219.989909) (xy 129.992179 -219.989909) (xy 130.043474 -219.998034)
			(xy 130.092867 -220.014082) (xy 130.139141 -220.03766) (xy 130.181157 -220.068186) (xy 130.21788 -220.104909)
			(xy 130.248406 -220.146925) (xy 130.271984 -220.193199) (xy 130.288032 -220.242592) (xy 130.296157 -220.293887)
			(xy 130.296666 -220.319854) (xy 130.296666 -220.320616) (xy 130.296137 -220.345821) (xy 130.576321 -220.345821)
			(xy 130.576321 -220.293887) (xy 130.584446 -220.242592) (xy 130.600494 -220.193199) (xy 130.624072 -220.146925)
			(xy 130.654598 -220.104909) (xy 130.691321 -220.068186) (xy 130.733337 -220.03766) (xy 130.779611 -220.014082)
			(xy 130.829004 -219.998034) (xy 130.880299 -219.989909) (xy 130.932233 -219.989909) (xy 130.983528 -219.998034)
			(xy 131.032921 -220.014082) (xy 131.079195 -220.03766) (xy 131.121211 -220.068186) (xy 131.157934 -220.104909)
			(xy 131.18846 -220.146925) (xy 131.212038 -220.193199) (xy 131.228086 -220.242592) (xy 131.236211 -220.293887)
			(xy 131.23672 -220.319854) (xy 131.515358 -220.319854) (xy 131.515867 -220.293887) (xy 131.523992 -220.242592)
			(xy 131.54004 -220.193199) (xy 131.563618 -220.146925) (xy 131.594144 -220.104909) (xy 131.630867 -220.068186)
			(xy 131.672883 -220.03766) (xy 131.719157 -220.014082) (xy 131.76855 -219.998034) (xy 131.819845 -219.989909)
			(xy 131.871779 -219.989909) (xy 131.923074 -219.998034) (xy 131.972467 -220.014082) (xy 132.018741 -220.03766)
			(xy 132.060757 -220.068186) (xy 132.09748 -220.104909) (xy 132.128006 -220.146925) (xy 132.151584 -220.193199)
			(xy 132.167632 -220.242592) (xy 132.175757 -220.293887) (xy 132.176266 -220.319854) (xy 132.176266 -220.320616)
			(xy 132.175737 -220.345821) (xy 132.455921 -220.345821) (xy 132.455921 -220.293887) (xy 132.464046 -220.242592)
			(xy 132.480094 -220.193199) (xy 132.503672 -220.146925) (xy 132.534198 -220.104909) (xy 132.570921 -220.068186)
			(xy 132.612937 -220.03766) (xy 132.659211 -220.014082) (xy 132.708604 -219.998034) (xy 132.759899 -219.989909)
			(xy 132.811833 -219.989909) (xy 132.863128 -219.998034) (xy 132.912521 -220.014082) (xy 132.958795 -220.03766)
			(xy 133.000811 -220.068186) (xy 133.037534 -220.104909) (xy 133.06806 -220.146925) (xy 133.091638 -220.193199)
			(xy 133.107686 -220.242592) (xy 133.115811 -220.293887) (xy 133.11632 -220.319854) (xy 133.395212 -220.319854)
			(xy 133.395721 -220.293887) (xy 133.403846 -220.242592) (xy 133.419894 -220.193199) (xy 133.443472 -220.146925)
			(xy 133.473998 -220.104909) (xy 133.510721 -220.068186) (xy 133.552737 -220.03766) (xy 133.599011 -220.014082)
			(xy 133.648404 -219.998034) (xy 133.699699 -219.989909) (xy 133.751633 -219.989909) (xy 133.802928 -219.998034)
			(xy 133.852321 -220.014082) (xy 133.898595 -220.03766) (xy 133.940611 -220.068186) (xy 133.977334 -220.104909)
			(xy 134.00786 -220.146925) (xy 134.031438 -220.193199) (xy 134.047486 -220.242592) (xy 134.055611 -220.293887)
			(xy 134.05612 -220.319854) (xy 134.055555 -220.347839) (xy 134.046113 -220.403007) (xy 134.037324 -220.429582)
			(xy 134.029704 -220.451426) (xy 134.233666 -220.80474) (xy 134.256526 -220.809058) (xy 134.281444 -220.814243)
			(xy 134.329427 -220.831206) (xy 134.374245 -220.85532) (xy 134.414838 -220.886018) (xy 134.450247 -220.922574)
			(xy 134.479636 -220.964124) (xy 134.502311 -221.009687) (xy 134.517735 -221.058187) (xy 134.525546 -221.108477)
			(xy 134.52602 -221.133924) (xy 134.525511 -221.159891) (xy 134.517386 -221.211186) (xy 134.501338 -221.260579)
			(xy 134.47776 -221.306853) (xy 134.447234 -221.348869) (xy 134.410511 -221.385592) (xy 134.368495 -221.416118)
			(xy 134.322221 -221.439696) (xy 134.272828 -221.455744) (xy 134.221533 -221.463869) (xy 134.169599 -221.463869)
			(xy 134.118304 -221.455744) (xy 134.068911 -221.439696) (xy 134.022637 -221.416118) (xy 133.980621 -221.385592)
			(xy 133.943898 -221.348869) (xy 133.913372 -221.306853) (xy 133.889794 -221.260579) (xy 133.873746 -221.211186)
			(xy 133.865621 -221.159891) (xy 133.865112 -221.133924) (xy 133.86567 -221.105938) (xy 133.875116 -221.050771)
			(xy 133.883908 -221.024196) (xy 133.891528 -221.002098) (xy 133.68782 -220.649038) (xy 133.66496 -220.64472)
			(xy 133.640032 -220.639521) (xy 133.592009 -220.622599) (xy 133.54715 -220.598512) (xy 133.506516 -220.567829)
			(xy 133.471068 -220.531278) (xy 133.441646 -220.489722) (xy 133.418945 -220.444145) (xy 133.403503 -220.395626)
			(xy 133.395686 -220.345313) (xy 133.395212 -220.319854) (xy 133.11632 -220.319854) (xy 133.115811 -220.345821)
			(xy 133.107686 -220.397116) (xy 133.091638 -220.446509) (xy 133.06806 -220.492783) (xy 133.037534 -220.534799)
			(xy 133.000811 -220.571522) (xy 132.958795 -220.602048) (xy 132.912521 -220.625626) (xy 132.863128 -220.641674)
			(xy 132.811833 -220.649799) (xy 132.759899 -220.649799) (xy 132.708604 -220.641674) (xy 132.659211 -220.625626)
			(xy 132.612937 -220.602048) (xy 132.570921 -220.571522) (xy 132.534198 -220.534799) (xy 132.503672 -220.492783)
			(xy 132.480094 -220.446509) (xy 132.464046 -220.397116) (xy 132.455921 -220.345821) (xy 132.175737 -220.345821)
			(xy 132.175684 -220.348334) (xy 132.166356 -220.402981) (xy 132.157724 -220.429328) (xy 132.14985 -220.451172)
			(xy 132.354066 -220.80474) (xy 132.376926 -220.809058) (xy 132.401844 -220.814243) (xy 132.449827 -220.831206)
			(xy 132.494645 -220.85532) (xy 132.535238 -220.886018) (xy 132.570647 -220.922574) (xy 132.600036 -220.964124)
			(xy 132.622711 -221.009687) (xy 132.638135 -221.058187) (xy 132.645946 -221.108477) (xy 132.64642 -221.133924)
			(xy 132.645911 -221.159891) (xy 132.637786 -221.211186) (xy 132.621738 -221.260579) (xy 132.59816 -221.306853)
			(xy 132.567634 -221.348869) (xy 132.530911 -221.385592) (xy 132.488895 -221.416118) (xy 132.442621 -221.439696)
			(xy 132.393228 -221.455744) (xy 132.341933 -221.463869) (xy 132.289999 -221.463869) (xy 132.238704 -221.455744)
			(xy 132.189311 -221.439696) (xy 132.143037 -221.416118) (xy 132.101021 -221.385592) (xy 132.064298 -221.348869)
			(xy 132.033772 -221.306853) (xy 132.010194 -221.260579) (xy 131.994146 -221.211186) (xy 131.986021 -221.159891)
			(xy 131.985512 -221.133924) (xy 131.98607 -221.105938) (xy 131.995516 -221.050771) (xy 132.004308 -221.024196)
			(xy 132.011928 -221.002098) (xy 131.80822 -220.649038) (xy 131.785106 -220.64472) (xy 131.76017 -220.63956)
			(xy 131.712147 -220.62263) (xy 131.667288 -220.598536) (xy 131.626655 -220.567848) (xy 131.591209 -220.531292)
			(xy 131.561789 -220.489732) (xy 131.539089 -220.444152) (xy 131.523649 -220.39563) (xy 131.515832 -220.345314)
			(xy 131.515358 -220.319854) (xy 131.23672 -220.319854) (xy 131.236211 -220.345821) (xy 131.228086 -220.397116)
			(xy 131.212038 -220.446509) (xy 131.18846 -220.492783) (xy 131.157934 -220.534799) (xy 131.121211 -220.571522)
			(xy 131.079195 -220.602048) (xy 131.032921 -220.625626) (xy 130.983528 -220.641674) (xy 130.932233 -220.649799)
			(xy 130.880299 -220.649799) (xy 130.829004 -220.641674) (xy 130.779611 -220.625626) (xy 130.733337 -220.602048)
			(xy 130.691321 -220.571522) (xy 130.654598 -220.534799) (xy 130.624072 -220.492783) (xy 130.600494 -220.446509)
			(xy 130.584446 -220.397116) (xy 130.576321 -220.345821) (xy 130.296137 -220.345821) (xy 130.296084 -220.348334)
			(xy 130.286756 -220.402981) (xy 130.278124 -220.429328) (xy 130.27025 -220.451172) (xy 130.474466 -220.80474)
			(xy 130.497326 -220.809058) (xy 130.522244 -220.814243) (xy 130.570227 -220.831206) (xy 130.615045 -220.85532)
			(xy 130.655638 -220.886018) (xy 130.691047 -220.922574) (xy 130.720436 -220.964124) (xy 130.743111 -221.009687)
			(xy 130.758535 -221.058187) (xy 130.766346 -221.108477) (xy 130.76682 -221.133924) (xy 130.766311 -221.159891)
			(xy 130.758186 -221.211186) (xy 130.742138 -221.260579) (xy 130.71856 -221.306853) (xy 130.688034 -221.348869)
			(xy 130.651311 -221.385592) (xy 130.609295 -221.416118) (xy 130.563021 -221.439696) (xy 130.513628 -221.455744)
			(xy 130.462333 -221.463869) (xy 130.410399 -221.463869) (xy 130.359104 -221.455744) (xy 130.309711 -221.439696)
			(xy 130.263437 -221.416118) (xy 130.221421 -221.385592) (xy 130.184698 -221.348869) (xy 130.154172 -221.306853)
			(xy 130.130594 -221.260579) (xy 130.114546 -221.211186) (xy 130.106421 -221.159891) (xy 130.105912 -221.133924)
			(xy 130.10647 -221.105938) (xy 130.115916 -221.050771) (xy 130.124708 -221.024196) (xy 130.132328 -221.002098)
			(xy 129.92862 -220.649038) (xy 129.905506 -220.64472) (xy 129.88057 -220.63956) (xy 129.832547 -220.62263)
			(xy 129.787688 -220.598536) (xy 129.747055 -220.567848) (xy 129.711609 -220.531292) (xy 129.682189 -220.489732)
			(xy 129.659489 -220.444152) (xy 129.644049 -220.39563) (xy 129.636232 -220.345314) (xy 129.635758 -220.319854)
			(xy 129.35712 -220.319854) (xy 129.356611 -220.345821) (xy 129.348486 -220.397116) (xy 129.332438 -220.446509)
			(xy 129.30886 -220.492783) (xy 129.278334 -220.534799) (xy 129.241611 -220.571522) (xy 129.199595 -220.602048)
			(xy 129.153321 -220.625626) (xy 129.103928 -220.641674) (xy 129.052633 -220.649799) (xy 129.000699 -220.649799)
			(xy 128.949404 -220.641674) (xy 128.900011 -220.625626) (xy 128.853737 -220.602048) (xy 128.811721 -220.571522)
			(xy 128.774998 -220.534799) (xy 128.744472 -220.492783) (xy 128.720894 -220.446509) (xy 128.704846 -220.397116)
			(xy 128.696721 -220.345821) (xy 128.416537 -220.345821) (xy 128.416484 -220.348334) (xy 128.407156 -220.402981)
			(xy 128.398524 -220.429328) (xy 128.39065 -220.451172) (xy 128.594866 -220.80474) (xy 128.617726 -220.809058)
			(xy 128.642644 -220.814243) (xy 128.690627 -220.831206) (xy 128.735445 -220.85532) (xy 128.776038 -220.886018)
			(xy 128.811447 -220.922574) (xy 128.840836 -220.964124) (xy 128.863511 -221.009687) (xy 128.878935 -221.058187)
			(xy 128.886746 -221.108477) (xy 128.88722 -221.133924) (xy 128.886711 -221.159891) (xy 128.878586 -221.211186)
			(xy 128.862538 -221.260579) (xy 128.83896 -221.306853) (xy 128.808434 -221.348869) (xy 128.771711 -221.385592)
			(xy 128.729695 -221.416118) (xy 128.683421 -221.439696) (xy 128.634028 -221.455744) (xy 128.582733 -221.463869)
			(xy 128.530799 -221.463869) (xy 128.479504 -221.455744) (xy 128.430111 -221.439696) (xy 128.383837 -221.416118)
			(xy 128.341821 -221.385592) (xy 128.305098 -221.348869) (xy 128.274572 -221.306853) (xy 128.250994 -221.260579)
			(xy 128.234946 -221.211186) (xy 128.226821 -221.159891) (xy 128.226312 -221.133924) (xy 128.22687 -221.105938)
			(xy 128.236316 -221.050771) (xy 128.245108 -221.024196) (xy 128.252728 -221.002098) (xy 128.04902 -220.649038)
			(xy 128.025906 -220.64472) (xy 128.00097 -220.63956) (xy 127.952947 -220.62263) (xy 127.908088 -220.598536)
			(xy 127.867455 -220.567848) (xy 127.832009 -220.531292) (xy 127.802589 -220.489732) (xy 127.779889 -220.444152)
			(xy 127.764449 -220.39563) (xy 127.756632 -220.345314) (xy 127.756158 -220.319854) (xy 127.47752 -220.319854)
			(xy 127.477011 -220.345821) (xy 127.468886 -220.397116) (xy 127.452838 -220.446509) (xy 127.42926 -220.492783)
			(xy 127.398734 -220.534799) (xy 127.362011 -220.571522) (xy 127.319995 -220.602048) (xy 127.273721 -220.625626)
			(xy 127.224328 -220.641674) (xy 127.173033 -220.649799) (xy 127.121099 -220.649799) (xy 127.069804 -220.641674)
			(xy 127.020411 -220.625626) (xy 126.974137 -220.602048) (xy 126.932121 -220.571522) (xy 126.895398 -220.534799)
			(xy 126.864872 -220.492783) (xy 126.841294 -220.446509) (xy 126.825246 -220.397116) (xy 126.817121 -220.345821)
			(xy 126.536937 -220.345821) (xy 126.536884 -220.348334) (xy 126.527556 -220.402981) (xy 126.518924 -220.429328)
			(xy 126.51105 -220.451172) (xy 126.715266 -220.80474) (xy 126.738126 -220.809058) (xy 126.763044 -220.814243)
			(xy 126.811027 -220.831206) (xy 126.855845 -220.85532) (xy 126.896438 -220.886018) (xy 126.931847 -220.922574)
			(xy 126.961236 -220.964124) (xy 126.983911 -221.009687) (xy 126.999335 -221.058187) (xy 127.007146 -221.108477)
			(xy 127.00762 -221.133924) (xy 127.007111 -221.159891) (xy 126.998986 -221.211186) (xy 126.982938 -221.260579)
			(xy 126.95936 -221.306853) (xy 126.928834 -221.348869) (xy 126.892111 -221.385592) (xy 126.850095 -221.416118)
			(xy 126.803821 -221.439696) (xy 126.754428 -221.455744) (xy 126.703133 -221.463869) (xy 126.651199 -221.463869)
			(xy 126.599904 -221.455744) (xy 126.550511 -221.439696) (xy 126.504237 -221.416118) (xy 126.462221 -221.385592)
			(xy 126.425498 -221.348869) (xy 126.394972 -221.306853) (xy 126.371394 -221.260579) (xy 126.355346 -221.211186)
			(xy 126.347221 -221.159891) (xy 126.346712 -221.133924) (xy 126.34727 -221.105938) (xy 126.356716 -221.050771)
			(xy 126.365508 -221.024196) (xy 126.373128 -221.002098) (xy 126.16942 -220.649038) (xy 126.146306 -220.64472)
			(xy 126.12137 -220.63956) (xy 126.073347 -220.62263) (xy 126.028488 -220.598536) (xy 125.987855 -220.567848)
			(xy 125.952409 -220.531292) (xy 125.922989 -220.489732) (xy 125.900289 -220.444152) (xy 125.884849 -220.39563)
			(xy 125.877032 -220.345314) (xy 125.876558 -220.319854) (xy 125.59792 -220.319854) (xy 125.597411 -220.345821)
			(xy 125.589286 -220.397116) (xy 125.573238 -220.446509) (xy 125.54966 -220.492783) (xy 125.519134 -220.534799)
			(xy 125.482411 -220.571522) (xy 125.440395 -220.602048) (xy 125.394121 -220.625626) (xy 125.344728 -220.641674)
			(xy 125.293433 -220.649799) (xy 125.241499 -220.649799) (xy 125.190204 -220.641674) (xy 125.140811 -220.625626)
			(xy 125.094537 -220.602048) (xy 125.052521 -220.571522) (xy 125.015798 -220.534799) (xy 124.985272 -220.492783)
			(xy 124.961694 -220.446509) (xy 124.945646 -220.397116) (xy 124.937521 -220.345821) (xy 124.657337 -220.345821)
			(xy 124.657284 -220.348334) (xy 124.647956 -220.402981) (xy 124.639324 -220.429328) (xy 124.63145 -220.451172)
			(xy 124.835666 -220.80474) (xy 124.858526 -220.809058) (xy 124.883444 -220.814243) (xy 124.931427 -220.831206)
			(xy 124.976245 -220.85532) (xy 125.016838 -220.886018) (xy 125.052247 -220.922574) (xy 125.081636 -220.964124)
			(xy 125.104311 -221.009687) (xy 125.119735 -221.058187) (xy 125.127546 -221.108477) (xy 125.12802 -221.133924)
			(xy 125.127511 -221.159891) (xy 125.119386 -221.211186) (xy 125.103338 -221.260579) (xy 125.07976 -221.306853)
			(xy 125.049234 -221.348869) (xy 125.012511 -221.385592) (xy 124.970495 -221.416118) (xy 124.924221 -221.439696)
			(xy 124.874828 -221.455744) (xy 124.823533 -221.463869) (xy 124.771599 -221.463869) (xy 124.720304 -221.455744)
			(xy 124.670911 -221.439696) (xy 124.624637 -221.416118) (xy 124.582621 -221.385592) (xy 124.545898 -221.348869)
			(xy 124.515372 -221.306853) (xy 124.491794 -221.260579) (xy 124.475746 -221.211186) (xy 124.467621 -221.159891)
			(xy 124.467112 -221.133924) (xy 124.46767 -221.105938) (xy 124.477116 -221.050771) (xy 124.485908 -221.024196)
			(xy 124.493528 -221.002098) (xy 124.28982 -220.649038) (xy 124.266706 -220.64472) (xy 124.24177 -220.63956)
			(xy 124.193747 -220.62263) (xy 124.148888 -220.598536) (xy 124.108255 -220.567848) (xy 124.072809 -220.531292)
			(xy 124.043389 -220.489732) (xy 124.020689 -220.444152) (xy 124.005249 -220.39563) (xy 123.997432 -220.345314)
			(xy 123.996958 -220.319854) (xy 123.71832 -220.319854) (xy 123.717811 -220.345821) (xy 123.709686 -220.397116)
			(xy 123.693638 -220.446509) (xy 123.67006 -220.492783) (xy 123.639534 -220.534799) (xy 123.602811 -220.571522)
			(xy 123.560795 -220.602048) (xy 123.514521 -220.625626) (xy 123.465128 -220.641674) (xy 123.413833 -220.649799)
			(xy 123.361899 -220.649799) (xy 123.310604 -220.641674) (xy 123.261211 -220.625626) (xy 123.214937 -220.602048)
			(xy 123.172921 -220.571522) (xy 123.136198 -220.534799) (xy 123.105672 -220.492783) (xy 123.082094 -220.446509)
			(xy 123.066046 -220.397116) (xy 123.057921 -220.345821) (xy 122.777737 -220.345821) (xy 122.777684 -220.348334)
			(xy 122.768356 -220.402981) (xy 122.759724 -220.429328) (xy 122.75185 -220.451172) (xy 122.956066 -220.80474)
			(xy 122.978926 -220.809058) (xy 123.003844 -220.814243) (xy 123.051827 -220.831206) (xy 123.096645 -220.85532)
			(xy 123.137238 -220.886018) (xy 123.172647 -220.922574) (xy 123.202036 -220.964124) (xy 123.224711 -221.009687)
			(xy 123.240135 -221.058187) (xy 123.247946 -221.108477) (xy 123.24842 -221.133924) (xy 123.247911 -221.159891)
			(xy 123.239786 -221.211186) (xy 123.223738 -221.260579) (xy 123.20016 -221.306853) (xy 123.169634 -221.348869)
			(xy 123.132911 -221.385592) (xy 123.090895 -221.416118) (xy 123.044621 -221.439696) (xy 122.995228 -221.455744)
			(xy 122.943933 -221.463869) (xy 122.891999 -221.463869) (xy 122.840704 -221.455744) (xy 122.791311 -221.439696)
			(xy 122.745037 -221.416118) (xy 122.703021 -221.385592) (xy 122.666298 -221.348869) (xy 122.635772 -221.306853)
			(xy 122.612194 -221.260579) (xy 122.596146 -221.211186) (xy 122.588021 -221.159891) (xy 122.587512 -221.133924)
			(xy 122.58807 -221.105938) (xy 122.597516 -221.050771) (xy 122.606308 -221.024196) (xy 122.613928 -221.002098)
			(xy 122.41022 -220.649038) (xy 122.387106 -220.64472) (xy 122.36217 -220.63956) (xy 122.314147 -220.62263)
			(xy 122.269288 -220.598536) (xy 122.228655 -220.567848) (xy 122.193209 -220.531292) (xy 122.163789 -220.489732)
			(xy 122.141089 -220.444152) (xy 122.125649 -220.39563) (xy 122.117832 -220.345314) (xy 122.117358 -220.319854)
			(xy 121.83872 -220.319854) (xy 121.838211 -220.345821) (xy 121.830086 -220.397116) (xy 121.814038 -220.446509)
			(xy 121.79046 -220.492783) (xy 121.759934 -220.534799) (xy 121.723211 -220.571522) (xy 121.681195 -220.602048)
			(xy 121.634921 -220.625626) (xy 121.585528 -220.641674) (xy 121.534233 -220.649799) (xy 121.482299 -220.649799)
			(xy 121.431004 -220.641674) (xy 121.381611 -220.625626) (xy 121.335337 -220.602048) (xy 121.293321 -220.571522)
			(xy 121.256598 -220.534799) (xy 121.226072 -220.492783) (xy 121.202494 -220.446509) (xy 121.186446 -220.397116)
			(xy 121.178321 -220.345821) (xy 121.01068 -220.345821) (xy 121.01068 -220.690948) (xy 121.076466 -220.80474)
			(xy 121.099326 -220.809058) (xy 121.124259 -220.814206) (xy 121.172268 -220.831143) (xy 121.21711 -220.855244)
			(xy 121.257725 -220.885938) (xy 121.293151 -220.922499) (xy 121.322549 -220.964061) (xy 121.345224 -221.009641)
			(xy 121.360639 -221.05816) (xy 121.368429 -221.108469) (xy 121.36882 -221.133924) (xy 121.368355 -221.158885)
			(xy 121.360831 -221.208238) (xy 121.345972 -221.255899) (xy 121.324116 -221.300784) (xy 121.29576 -221.341873)
			(xy 121.261549 -221.378231) (xy 121.222261 -221.409033) (xy 121.178788 -221.433578) (xy 121.132119 -221.451307)
			(xy 121.083315 -221.461819) (xy 121.058432 -221.46387) (xy 121.01068 -221.514416) (xy 121.01068 -221.94774)
			(xy 121.177558 -221.94774) (xy 121.177981 -221.922287) (xy 121.185768 -221.87198) (xy 121.20118 -221.823463)
			(xy 121.223851 -221.777884) (xy 121.253245 -221.736322) (xy 121.288667 -221.699761) (xy 121.329278 -221.669066)
			(xy 121.374116 -221.644963) (xy 121.422121 -221.628023) (xy 121.447052 -221.622874) (xy 121.469912 -221.618556)
			(xy 121.673874 -221.264988) (xy 121.666254 -221.243144) (xy 121.657637 -221.216728) (xy 121.648309 -221.161957)
			(xy 121.647712 -221.134178) (xy 121.647712 -221.133924) (xy 121.648221 -221.107957) (xy 121.656346 -221.056662)
			(xy 121.672394 -221.007269) (xy 121.695972 -220.960995) (xy 121.726498 -220.918979) (xy 121.763221 -220.882256)
			(xy 121.805237 -220.85173) (xy 121.851511 -220.828152) (xy 121.900904 -220.812104) (xy 121.952199 -220.803979)
			(xy 122.004133 -220.803979) (xy 122.055428 -220.812104) (xy 122.104821 -220.828152) (xy 122.151095 -220.85173)
			(xy 122.193111 -220.882256) (xy 122.229834 -220.918979) (xy 122.26036 -220.960995) (xy 122.283938 -221.007269)
			(xy 122.299986 -221.056662) (xy 122.308111 -221.107957) (xy 122.30862 -221.133924) (xy 122.308187 -221.159399)
			(xy 122.300363 -221.209746) (xy 122.284905 -221.258295) (xy 122.262178 -221.303896) (xy 122.232721 -221.345468)
			(xy 122.197232 -221.382027) (xy 122.156553 -221.412705) (xy 122.111646 -221.436776) (xy 122.063578 -221.453669)
			(xy 122.038618 -221.45879) (xy 122.015504 -221.463108) (xy 121.81205 -221.815914) (xy 121.81967 -221.838012)
			(xy 121.82841 -221.8646) (xy 121.837856 -221.919759) (xy 121.838466 -221.94774) (xy 121.837957 -221.973707)
			(xy 122.117867 -221.973707) (xy 122.117867 -221.921773) (xy 122.125992 -221.870478) (xy 122.14204 -221.821085)
			(xy 122.165618 -221.774811) (xy 122.196144 -221.732795) (xy 122.232867 -221.696072) (xy 122.274883 -221.665546)
			(xy 122.321157 -221.641968) (xy 122.37055 -221.62592) (xy 122.421845 -221.617795) (xy 122.473779 -221.617795)
			(xy 122.525074 -221.62592) (xy 122.574467 -221.641968) (xy 122.620741 -221.665546) (xy 122.662757 -221.696072)
			(xy 122.69948 -221.732795) (xy 122.730006 -221.774811) (xy 122.753584 -221.821085) (xy 122.769632 -221.870478)
			(xy 122.777757 -221.921773) (xy 122.778266 -221.94774) (xy 123.057158 -221.94774) (xy 123.057581 -221.922287)
			(xy 123.065368 -221.87198) (xy 123.08078 -221.823463) (xy 123.103451 -221.777884) (xy 123.132845 -221.736322)
			(xy 123.168267 -221.699761) (xy 123.208878 -221.669066) (xy 123.253716 -221.644963) (xy 123.301721 -221.628023)
			(xy 123.326652 -221.622874) (xy 123.349512 -221.618556) (xy 123.553474 -221.264988) (xy 123.545854 -221.243144)
			(xy 123.537237 -221.216728) (xy 123.527909 -221.161957) (xy 123.527312 -221.134178) (xy 123.527312 -221.133924)
			(xy 123.527821 -221.107957) (xy 123.535946 -221.056662) (xy 123.551994 -221.007269) (xy 123.575572 -220.960995)
			(xy 123.606098 -220.918979) (xy 123.642821 -220.882256) (xy 123.684837 -220.85173) (xy 123.731111 -220.828152)
			(xy 123.780504 -220.812104) (xy 123.831799 -220.803979) (xy 123.883733 -220.803979) (xy 123.935028 -220.812104)
			(xy 123.984421 -220.828152) (xy 124.030695 -220.85173) (xy 124.072711 -220.882256) (xy 124.109434 -220.918979)
			(xy 124.13996 -220.960995) (xy 124.163538 -221.007269) (xy 124.179586 -221.056662) (xy 124.187711 -221.107957)
			(xy 124.18822 -221.133924) (xy 124.187787 -221.159399) (xy 124.179963 -221.209746) (xy 124.164505 -221.258295)
			(xy 124.141778 -221.303896) (xy 124.112321 -221.345468) (xy 124.076832 -221.382027) (xy 124.036153 -221.412705)
			(xy 123.991246 -221.436776) (xy 123.943178 -221.453669) (xy 123.918218 -221.45879) (xy 123.895104 -221.463108)
			(xy 123.69165 -221.815914) (xy 123.69927 -221.838012) (xy 123.70801 -221.8646) (xy 123.717456 -221.919759)
			(xy 123.718066 -221.94774) (xy 123.717557 -221.973707) (xy 123.997467 -221.973707) (xy 123.997467 -221.921773)
			(xy 124.005592 -221.870478) (xy 124.02164 -221.821085) (xy 124.045218 -221.774811) (xy 124.075744 -221.732795)
			(xy 124.112467 -221.696072) (xy 124.154483 -221.665546) (xy 124.200757 -221.641968) (xy 124.25015 -221.62592)
			(xy 124.301445 -221.617795) (xy 124.353379 -221.617795) (xy 124.404674 -221.62592) (xy 124.454067 -221.641968)
			(xy 124.500341 -221.665546) (xy 124.542357 -221.696072) (xy 124.57908 -221.732795) (xy 124.609606 -221.774811)
			(xy 124.633184 -221.821085) (xy 124.649232 -221.870478) (xy 124.657357 -221.921773) (xy 124.657866 -221.94774)
			(xy 124.936758 -221.94774) (xy 124.937181 -221.922287) (xy 124.944968 -221.87198) (xy 124.96038 -221.823463)
			(xy 124.983051 -221.777884) (xy 125.012445 -221.736322) (xy 125.047867 -221.699761) (xy 125.088478 -221.669066)
			(xy 125.133316 -221.644963) (xy 125.181321 -221.628023) (xy 125.206252 -221.622874) (xy 125.229112 -221.618556)
			(xy 125.433074 -221.264988) (xy 125.425454 -221.243144) (xy 125.416837 -221.216728) (xy 125.407509 -221.161957)
			(xy 125.406912 -221.134178) (xy 125.406912 -221.133924) (xy 125.407421 -221.107957) (xy 125.415546 -221.056662)
			(xy 125.431594 -221.007269) (xy 125.455172 -220.960995) (xy 125.485698 -220.918979) (xy 125.522421 -220.882256)
			(xy 125.564437 -220.85173) (xy 125.610711 -220.828152) (xy 125.660104 -220.812104) (xy 125.711399 -220.803979)
			(xy 125.763333 -220.803979) (xy 125.814628 -220.812104) (xy 125.864021 -220.828152) (xy 125.910295 -220.85173)
			(xy 125.952311 -220.882256) (xy 125.989034 -220.918979) (xy 126.01956 -220.960995) (xy 126.043138 -221.007269)
			(xy 126.059186 -221.056662) (xy 126.067311 -221.107957) (xy 126.06782 -221.133924) (xy 126.067387 -221.159399)
			(xy 126.059563 -221.209746) (xy 126.044105 -221.258295) (xy 126.021378 -221.303896) (xy 125.991921 -221.345468)
			(xy 125.956432 -221.382027) (xy 125.915753 -221.412705) (xy 125.870846 -221.436776) (xy 125.822778 -221.453669)
			(xy 125.797818 -221.45879) (xy 125.774704 -221.463108) (xy 125.57125 -221.815914) (xy 125.57887 -221.838012)
			(xy 125.58761 -221.8646) (xy 125.597056 -221.919759) (xy 125.597666 -221.94774) (xy 125.597157 -221.973707)
			(xy 125.877067 -221.973707) (xy 125.877067 -221.921773) (xy 125.885192 -221.870478) (xy 125.90124 -221.821085)
			(xy 125.924818 -221.774811) (xy 125.955344 -221.732795) (xy 125.992067 -221.696072) (xy 126.034083 -221.665546)
			(xy 126.080357 -221.641968) (xy 126.12975 -221.62592) (xy 126.181045 -221.617795) (xy 126.232979 -221.617795)
			(xy 126.284274 -221.62592) (xy 126.333667 -221.641968) (xy 126.379941 -221.665546) (xy 126.421957 -221.696072)
			(xy 126.45868 -221.732795) (xy 126.489206 -221.774811) (xy 126.512784 -221.821085) (xy 126.528832 -221.870478)
			(xy 126.536957 -221.921773) (xy 126.537466 -221.94774) (xy 126.816358 -221.94774) (xy 126.816781 -221.922287)
			(xy 126.824568 -221.87198) (xy 126.83998 -221.823463) (xy 126.862651 -221.777884) (xy 126.892045 -221.736322)
			(xy 126.927467 -221.699761) (xy 126.968078 -221.669066) (xy 127.012916 -221.644963) (xy 127.060921 -221.628023)
			(xy 127.085852 -221.622874) (xy 127.108712 -221.618556) (xy 127.312674 -221.264988) (xy 127.305054 -221.243144)
			(xy 127.296437 -221.216728) (xy 127.287109 -221.161957) (xy 127.286512 -221.134178) (xy 127.286512 -221.133924)
			(xy 127.287021 -221.107957) (xy 127.295146 -221.056662) (xy 127.311194 -221.007269) (xy 127.334772 -220.960995)
			(xy 127.365298 -220.918979) (xy 127.402021 -220.882256) (xy 127.444037 -220.85173) (xy 127.490311 -220.828152)
			(xy 127.539704 -220.812104) (xy 127.590999 -220.803979) (xy 127.642933 -220.803979) (xy 127.694228 -220.812104)
			(xy 127.743621 -220.828152) (xy 127.789895 -220.85173) (xy 127.831911 -220.882256) (xy 127.868634 -220.918979)
			(xy 127.89916 -220.960995) (xy 127.922738 -221.007269) (xy 127.938786 -221.056662) (xy 127.946911 -221.107957)
			(xy 127.94742 -221.133924) (xy 127.946987 -221.159399) (xy 127.939163 -221.209746) (xy 127.923705 -221.258295)
			(xy 127.900978 -221.303896) (xy 127.871521 -221.345468) (xy 127.836032 -221.382027) (xy 127.795353 -221.412705)
			(xy 127.750446 -221.436776) (xy 127.702378 -221.453669) (xy 127.677418 -221.45879) (xy 127.654304 -221.463108)
			(xy 127.45085 -221.815914) (xy 127.45847 -221.838012) (xy 127.46721 -221.8646) (xy 127.476656 -221.919759)
			(xy 127.477266 -221.94774) (xy 128.695958 -221.94774) (xy 128.696381 -221.922287) (xy 128.704168 -221.87198)
			(xy 128.71958 -221.823463) (xy 128.742251 -221.777884) (xy 128.771645 -221.736322) (xy 128.807067 -221.699761)
			(xy 128.847678 -221.669066) (xy 128.892516 -221.644963) (xy 128.940521 -221.628023) (xy 128.965452 -221.622874)
			(xy 128.988312 -221.618556) (xy 129.192274 -221.264988) (xy 129.184654 -221.243144) (xy 129.176037 -221.216728)
			(xy 129.166709 -221.161957) (xy 129.166112 -221.134178) (xy 129.166112 -221.133924) (xy 129.166621 -221.107957)
			(xy 129.174746 -221.056662) (xy 129.190794 -221.007269) (xy 129.214372 -220.960995) (xy 129.244898 -220.918979)
			(xy 129.281621 -220.882256) (xy 129.323637 -220.85173) (xy 129.369911 -220.828152) (xy 129.419304 -220.812104)
			(xy 129.470599 -220.803979) (xy 129.522533 -220.803979) (xy 129.573828 -220.812104) (xy 129.623221 -220.828152)
			(xy 129.669495 -220.85173) (xy 129.711511 -220.882256) (xy 129.748234 -220.918979) (xy 129.77876 -220.960995)
			(xy 129.802338 -221.007269) (xy 129.818386 -221.056662) (xy 129.826511 -221.107957) (xy 129.82702 -221.133924)
			(xy 129.826587 -221.159399) (xy 129.818763 -221.209746) (xy 129.803305 -221.258295) (xy 129.780578 -221.303896)
			(xy 129.751121 -221.345468) (xy 129.715632 -221.382027) (xy 129.674953 -221.412705) (xy 129.630046 -221.436776)
			(xy 129.581978 -221.453669) (xy 129.557018 -221.45879) (xy 129.533904 -221.463108) (xy 129.33045 -221.815914)
			(xy 129.33807 -221.838012) (xy 129.34681 -221.8646) (xy 129.356256 -221.919759) (xy 129.356866 -221.94774)
			(xy 130.575558 -221.94774) (xy 130.575981 -221.922287) (xy 130.583768 -221.87198) (xy 130.59918 -221.823463)
			(xy 130.621851 -221.777884) (xy 130.651245 -221.736322) (xy 130.686667 -221.699761) (xy 130.727278 -221.669066)
			(xy 130.772116 -221.644963) (xy 130.820121 -221.628023) (xy 130.845052 -221.622874) (xy 130.867912 -221.618556)
			(xy 131.071874 -221.264988) (xy 131.064254 -221.243144) (xy 131.055637 -221.216728) (xy 131.046309 -221.161957)
			(xy 131.045712 -221.134178) (xy 131.045712 -221.133924) (xy 131.046221 -221.107957) (xy 131.054346 -221.056662)
			(xy 131.070394 -221.007269) (xy 131.093972 -220.960995) (xy 131.124498 -220.918979) (xy 131.161221 -220.882256)
			(xy 131.203237 -220.85173) (xy 131.249511 -220.828152) (xy 131.298904 -220.812104) (xy 131.350199 -220.803979)
			(xy 131.402133 -220.803979) (xy 131.453428 -220.812104) (xy 131.502821 -220.828152) (xy 131.549095 -220.85173)
			(xy 131.591111 -220.882256) (xy 131.627834 -220.918979) (xy 131.65836 -220.960995) (xy 131.681938 -221.007269)
			(xy 131.697986 -221.056662) (xy 131.706111 -221.107957) (xy 131.70662 -221.133924) (xy 131.706187 -221.159399)
			(xy 131.698363 -221.209746) (xy 131.682905 -221.258295) (xy 131.660178 -221.303896) (xy 131.630721 -221.345468)
			(xy 131.595232 -221.382027) (xy 131.554553 -221.412705) (xy 131.509646 -221.436776) (xy 131.461578 -221.453669)
			(xy 131.436618 -221.45879) (xy 131.413504 -221.463108) (xy 131.21005 -221.815914) (xy 131.21767 -221.838012)
			(xy 131.22641 -221.8646) (xy 131.235856 -221.919759) (xy 131.236466 -221.94774) (xy 132.454904 -221.94774)
			(xy 132.45537 -221.922256) (xy 132.463184 -221.87189) (xy 132.478633 -221.82332) (xy 132.501351 -221.777695)
			(xy 132.5308 -221.736096) (xy 132.566283 -221.699507) (xy 132.60696 -221.668797) (xy 132.651867 -221.64469)
			(xy 132.699941 -221.62776) (xy 132.724906 -221.62262) (xy 132.747766 -221.618302) (xy 132.951474 -221.264988)
			(xy 132.943854 -221.24289) (xy 132.935224 -221.216478) (xy 132.925905 -221.161704) (xy 132.925312 -221.133924)
			(xy 132.925821 -221.107957) (xy 132.933946 -221.056662) (xy 132.949994 -221.007269) (xy 132.973572 -220.960995)
			(xy 133.004098 -220.918979) (xy 133.040821 -220.882256) (xy 133.082837 -220.85173) (xy 133.129111 -220.828152)
			(xy 133.178504 -220.812104) (xy 133.229799 -220.803979) (xy 133.281733 -220.803979) (xy 133.333028 -220.812104)
			(xy 133.382421 -220.828152) (xy 133.428695 -220.85173) (xy 133.470711 -220.882256) (xy 133.507434 -220.918979)
			(xy 133.53796 -220.960995) (xy 133.561538 -221.007269) (xy 133.577586 -221.056662) (xy 133.585711 -221.107957)
			(xy 133.58622 -221.133924) (xy 133.585787 -221.159399) (xy 133.577963 -221.209746) (xy 133.562505 -221.258295)
			(xy 133.539778 -221.303896) (xy 133.510321 -221.345468) (xy 133.474832 -221.382027) (xy 133.434153 -221.412705)
			(xy 133.389246 -221.436776) (xy 133.341178 -221.453669) (xy 133.316218 -221.45879) (xy 133.293104 -221.463108)
			(xy 133.08965 -221.81566) (xy 133.097524 -221.837758) (xy 133.106267 -221.864345) (xy 133.115713 -221.919505)
			(xy 133.11632 -221.947486) (xy 133.11632 -221.94774) (xy 133.11581 -221.973727) (xy 133.10768 -222.025062)
			(xy 133.091619 -222.074492) (xy 133.068023 -222.120802) (xy 133.037473 -222.16285) (xy 133.000722 -222.199601)
			(xy 132.958674 -222.230151) (xy 132.912364 -222.253747) (xy 132.862934 -222.269808) (xy 132.811599 -222.277938)
			(xy 132.759625 -222.277938) (xy 132.70829 -222.269808) (xy 132.65886 -222.253747) (xy 132.61255 -222.230151)
			(xy 132.570502 -222.199601) (xy 132.533751 -222.16285) (xy 132.503201 -222.120802) (xy 132.479605 -222.074492)
			(xy 132.463544 -222.025062) (xy 132.455414 -221.973727) (xy 132.454904 -221.94774) (xy 131.236466 -221.94774)
			(xy 131.235957 -221.973707) (xy 131.227832 -222.025002) (xy 131.211784 -222.074395) (xy 131.188206 -222.120669)
			(xy 131.15768 -222.162685) (xy 131.120957 -222.199408) (xy 131.078941 -222.229934) (xy 131.032667 -222.253512)
			(xy 130.983274 -222.26956) (xy 130.931979 -222.277685) (xy 130.880045 -222.277685) (xy 130.82875 -222.26956)
			(xy 130.779357 -222.253512) (xy 130.733083 -222.229934) (xy 130.691067 -222.199408) (xy 130.654344 -222.162685)
			(xy 130.623818 -222.120669) (xy 130.60024 -222.074395) (xy 130.584192 -222.025002) (xy 130.576067 -221.973707)
			(xy 130.575558 -221.94774) (xy 129.356866 -221.94774) (xy 129.356357 -221.973707) (xy 129.348232 -222.025002)
			(xy 129.332184 -222.074395) (xy 129.308606 -222.120669) (xy 129.27808 -222.162685) (xy 129.241357 -222.199408)
			(xy 129.199341 -222.229934) (xy 129.153067 -222.253512) (xy 129.103674 -222.26956) (xy 129.052379 -222.277685)
			(xy 129.000445 -222.277685) (xy 128.94915 -222.26956) (xy 128.899757 -222.253512) (xy 128.853483 -222.229934)
			(xy 128.811467 -222.199408) (xy 128.774744 -222.162685) (xy 128.744218 -222.120669) (xy 128.72064 -222.074395)
			(xy 128.704592 -222.025002) (xy 128.696467 -221.973707) (xy 128.695958 -221.94774) (xy 127.477266 -221.94774)
			(xy 127.476757 -221.973707) (xy 127.468632 -222.025002) (xy 127.452584 -222.074395) (xy 127.429006 -222.120669)
			(xy 127.39848 -222.162685) (xy 127.361757 -222.199408) (xy 127.319741 -222.229934) (xy 127.273467 -222.253512)
			(xy 127.224074 -222.26956) (xy 127.172779 -222.277685) (xy 127.120845 -222.277685) (xy 127.06955 -222.26956)
			(xy 127.020157 -222.253512) (xy 126.973883 -222.229934) (xy 126.931867 -222.199408) (xy 126.895144 -222.162685)
			(xy 126.864618 -222.120669) (xy 126.84104 -222.074395) (xy 126.824992 -222.025002) (xy 126.816867 -221.973707)
			(xy 126.816358 -221.94774) (xy 126.537466 -221.94774) (xy 126.536957 -221.973707) (xy 126.528832 -222.025002)
			(xy 126.512784 -222.074395) (xy 126.489206 -222.120669) (xy 126.45868 -222.162685) (xy 126.421957 -222.199408)
			(xy 126.379941 -222.229934) (xy 126.333667 -222.253512) (xy 126.284274 -222.26956) (xy 126.232979 -222.277685)
			(xy 126.181045 -222.277685) (xy 126.12975 -222.26956) (xy 126.080357 -222.253512) (xy 126.034083 -222.229934)
			(xy 125.992067 -222.199408) (xy 125.955344 -222.162685) (xy 125.924818 -222.120669) (xy 125.90124 -222.074395)
			(xy 125.885192 -222.025002) (xy 125.877067 -221.973707) (xy 125.597157 -221.973707) (xy 125.589032 -222.025002)
			(xy 125.572984 -222.074395) (xy 125.549406 -222.120669) (xy 125.51888 -222.162685) (xy 125.482157 -222.199408)
			(xy 125.440141 -222.229934) (xy 125.393867 -222.253512) (xy 125.344474 -222.26956) (xy 125.293179 -222.277685)
			(xy 125.241245 -222.277685) (xy 125.18995 -222.26956) (xy 125.140557 -222.253512) (xy 125.094283 -222.229934)
			(xy 125.052267 -222.199408) (xy 125.015544 -222.162685) (xy 124.985018 -222.120669) (xy 124.96144 -222.074395)
			(xy 124.945392 -222.025002) (xy 124.937267 -221.973707) (xy 124.936758 -221.94774) (xy 124.657866 -221.94774)
			(xy 124.657357 -221.973707) (xy 124.649232 -222.025002) (xy 124.633184 -222.074395) (xy 124.609606 -222.120669)
			(xy 124.57908 -222.162685) (xy 124.542357 -222.199408) (xy 124.500341 -222.229934) (xy 124.454067 -222.253512)
			(xy 124.404674 -222.26956) (xy 124.353379 -222.277685) (xy 124.301445 -222.277685) (xy 124.25015 -222.26956)
			(xy 124.200757 -222.253512) (xy 124.154483 -222.229934) (xy 124.112467 -222.199408) (xy 124.075744 -222.162685)
			(xy 124.045218 -222.120669) (xy 124.02164 -222.074395) (xy 124.005592 -222.025002) (xy 123.997467 -221.973707)
			(xy 123.717557 -221.973707) (xy 123.709432 -222.025002) (xy 123.693384 -222.074395) (xy 123.669806 -222.120669)
			(xy 123.63928 -222.162685) (xy 123.602557 -222.199408) (xy 123.560541 -222.229934) (xy 123.514267 -222.253512)
			(xy 123.464874 -222.26956) (xy 123.413579 -222.277685) (xy 123.361645 -222.277685) (xy 123.31035 -222.26956)
			(xy 123.260957 -222.253512) (xy 123.214683 -222.229934) (xy 123.172667 -222.199408) (xy 123.135944 -222.162685)
			(xy 123.105418 -222.120669) (xy 123.08184 -222.074395) (xy 123.065792 -222.025002) (xy 123.057667 -221.973707)
			(xy 123.057158 -221.94774) (xy 122.778266 -221.94774) (xy 122.777757 -221.973707) (xy 122.769632 -222.025002)
			(xy 122.753584 -222.074395) (xy 122.730006 -222.120669) (xy 122.69948 -222.162685) (xy 122.662757 -222.199408)
			(xy 122.620741 -222.229934) (xy 122.574467 -222.253512) (xy 122.525074 -222.26956) (xy 122.473779 -222.277685)
			(xy 122.421845 -222.277685) (xy 122.37055 -222.26956) (xy 122.321157 -222.253512) (xy 122.274883 -222.229934)
			(xy 122.232867 -222.199408) (xy 122.196144 -222.162685) (xy 122.165618 -222.120669) (xy 122.14204 -222.074395)
			(xy 122.125992 -222.025002) (xy 122.117867 -221.973707) (xy 121.837957 -221.973707) (xy 121.829832 -222.025002)
			(xy 121.813784 -222.074395) (xy 121.790206 -222.120669) (xy 121.75968 -222.162685) (xy 121.722957 -222.199408)
			(xy 121.680941 -222.229934) (xy 121.634667 -222.253512) (xy 121.585274 -222.26956) (xy 121.533979 -222.277685)
			(xy 121.482045 -222.277685) (xy 121.43075 -222.26956) (xy 121.381357 -222.253512) (xy 121.335083 -222.229934)
			(xy 121.293067 -222.199408) (xy 121.256344 -222.162685) (xy 121.225818 -222.120669) (xy 121.20224 -222.074395)
			(xy 121.186192 -222.025002) (xy 121.178067 -221.973707) (xy 121.177558 -221.94774) (xy 121.01068 -221.94774)
			(xy 121.01068 -222.381064) (xy 121.058432 -222.43161) (xy 121.084645 -222.43371) (xy 121.135965 -222.445164)
			(xy 121.184825 -222.464598) (xy 121.229993 -222.491521) (xy 121.27033 -222.525254) (xy 121.304818 -222.564948)
			(xy 121.332588 -222.6096) (xy 121.35294 -222.658085) (xy 121.36536 -222.70918) (xy 121.369535 -222.761597)
			(xy 121.367471 -222.787523) (xy 121.648221 -222.787523) (xy 121.648221 -222.735589) (xy 121.656346 -222.684294)
			(xy 121.672394 -222.634901) (xy 121.695972 -222.588627) (xy 121.726498 -222.546611) (xy 121.763221 -222.509888)
			(xy 121.805237 -222.479362) (xy 121.851511 -222.455784) (xy 121.900904 -222.439736) (xy 121.952199 -222.431611)
			(xy 122.004133 -222.431611) (xy 122.055428 -222.439736) (xy 122.104821 -222.455784) (xy 122.151095 -222.479362)
			(xy 122.193111 -222.509888) (xy 122.229834 -222.546611) (xy 122.26036 -222.588627) (xy 122.283938 -222.634901)
			(xy 122.299986 -222.684294) (xy 122.308111 -222.735589) (xy 122.30862 -222.761556) (xy 122.308111 -222.787523)
			(xy 122.588021 -222.787523) (xy 122.588021 -222.735589) (xy 122.596146 -222.684294) (xy 122.612194 -222.634901)
			(xy 122.635772 -222.588627) (xy 122.666298 -222.546611) (xy 122.703021 -222.509888) (xy 122.745037 -222.479362)
			(xy 122.791311 -222.455784) (xy 122.840704 -222.439736) (xy 122.891999 -222.431611) (xy 122.943933 -222.431611)
			(xy 122.995228 -222.439736) (xy 123.044621 -222.455784) (xy 123.090895 -222.479362) (xy 123.132911 -222.509888)
			(xy 123.169634 -222.546611) (xy 123.20016 -222.588627) (xy 123.223738 -222.634901) (xy 123.239786 -222.684294)
			(xy 123.247911 -222.735589) (xy 123.24842 -222.761556) (xy 123.247911 -222.787523) (xy 123.527821 -222.787523)
			(xy 123.527821 -222.735589) (xy 123.535946 -222.684294) (xy 123.551994 -222.634901) (xy 123.575572 -222.588627)
			(xy 123.606098 -222.546611) (xy 123.642821 -222.509888) (xy 123.684837 -222.479362) (xy 123.731111 -222.455784)
			(xy 123.780504 -222.439736) (xy 123.831799 -222.431611) (xy 123.883733 -222.431611) (xy 123.935028 -222.439736)
			(xy 123.984421 -222.455784) (xy 124.030695 -222.479362) (xy 124.072711 -222.509888) (xy 124.109434 -222.546611)
			(xy 124.13996 -222.588627) (xy 124.163538 -222.634901) (xy 124.179586 -222.684294) (xy 124.187711 -222.735589)
			(xy 124.18822 -222.761556) (xy 124.187711 -222.787523) (xy 124.467621 -222.787523) (xy 124.467621 -222.735589)
			(xy 124.475746 -222.684294) (xy 124.491794 -222.634901) (xy 124.515372 -222.588627) (xy 124.545898 -222.546611)
			(xy 124.582621 -222.509888) (xy 124.624637 -222.479362) (xy 124.670911 -222.455784) (xy 124.720304 -222.439736)
			(xy 124.771599 -222.431611) (xy 124.823533 -222.431611) (xy 124.874828 -222.439736) (xy 124.924221 -222.455784)
			(xy 124.970495 -222.479362) (xy 125.012511 -222.509888) (xy 125.049234 -222.546611) (xy 125.07976 -222.588627)
			(xy 125.103338 -222.634901) (xy 125.119386 -222.684294) (xy 125.127511 -222.735589) (xy 125.12802 -222.761556)
			(xy 125.127511 -222.787523) (xy 125.407421 -222.787523) (xy 125.407421 -222.735589) (xy 125.415546 -222.684294)
			(xy 125.431594 -222.634901) (xy 125.455172 -222.588627) (xy 125.485698 -222.546611) (xy 125.522421 -222.509888)
			(xy 125.564437 -222.479362) (xy 125.610711 -222.455784) (xy 125.660104 -222.439736) (xy 125.711399 -222.431611)
			(xy 125.763333 -222.431611) (xy 125.814628 -222.439736) (xy 125.864021 -222.455784) (xy 125.910295 -222.479362)
			(xy 125.952311 -222.509888) (xy 125.989034 -222.546611) (xy 126.01956 -222.588627) (xy 126.043138 -222.634901)
			(xy 126.059186 -222.684294) (xy 126.067311 -222.735589) (xy 126.06782 -222.761556) (xy 126.067311 -222.787523)
			(xy 126.347221 -222.787523) (xy 126.347221 -222.735589) (xy 126.355346 -222.684294) (xy 126.371394 -222.634901)
			(xy 126.394972 -222.588627) (xy 126.425498 -222.546611) (xy 126.462221 -222.509888) (xy 126.504237 -222.479362)
			(xy 126.550511 -222.455784) (xy 126.599904 -222.439736) (xy 126.651199 -222.431611) (xy 126.703133 -222.431611)
			(xy 126.754428 -222.439736) (xy 126.803821 -222.455784) (xy 126.850095 -222.479362) (xy 126.892111 -222.509888)
			(xy 126.928834 -222.546611) (xy 126.95936 -222.588627) (xy 126.982938 -222.634901) (xy 126.998986 -222.684294)
			(xy 127.007111 -222.735589) (xy 127.00762 -222.761556) (xy 127.007111 -222.787523) (xy 127.287021 -222.787523)
			(xy 127.287021 -222.735589) (xy 127.295146 -222.684294) (xy 127.311194 -222.634901) (xy 127.334772 -222.588627)
			(xy 127.365298 -222.546611) (xy 127.402021 -222.509888) (xy 127.444037 -222.479362) (xy 127.490311 -222.455784)
			(xy 127.539704 -222.439736) (xy 127.590999 -222.431611) (xy 127.642933 -222.431611) (xy 127.694228 -222.439736)
			(xy 127.743621 -222.455784) (xy 127.789895 -222.479362) (xy 127.831911 -222.509888) (xy 127.868634 -222.546611)
			(xy 127.89916 -222.588627) (xy 127.922738 -222.634901) (xy 127.938786 -222.684294) (xy 127.946911 -222.735589)
			(xy 127.94742 -222.761556) (xy 127.946911 -222.787523) (xy 128.226821 -222.787523) (xy 128.226821 -222.735589)
			(xy 128.234946 -222.684294) (xy 128.250994 -222.634901) (xy 128.274572 -222.588627) (xy 128.305098 -222.546611)
			(xy 128.341821 -222.509888) (xy 128.383837 -222.479362) (xy 128.430111 -222.455784) (xy 128.479504 -222.439736)
			(xy 128.530799 -222.431611) (xy 128.582733 -222.431611) (xy 128.634028 -222.439736) (xy 128.683421 -222.455784)
			(xy 128.729695 -222.479362) (xy 128.771711 -222.509888) (xy 128.808434 -222.546611) (xy 128.83896 -222.588627)
			(xy 128.862538 -222.634901) (xy 128.878586 -222.684294) (xy 128.886711 -222.735589) (xy 128.88722 -222.761556)
			(xy 128.886711 -222.787523) (xy 129.166621 -222.787523) (xy 129.166621 -222.735589) (xy 129.174746 -222.684294)
			(xy 129.190794 -222.634901) (xy 129.214372 -222.588627) (xy 129.244898 -222.546611) (xy 129.281621 -222.509888)
			(xy 129.323637 -222.479362) (xy 129.369911 -222.455784) (xy 129.419304 -222.439736) (xy 129.470599 -222.431611)
			(xy 129.522533 -222.431611) (xy 129.573828 -222.439736) (xy 129.623221 -222.455784) (xy 129.669495 -222.479362)
			(xy 129.711511 -222.509888) (xy 129.748234 -222.546611) (xy 129.77876 -222.588627) (xy 129.802338 -222.634901)
			(xy 129.818386 -222.684294) (xy 129.826511 -222.735589) (xy 129.82702 -222.761556) (xy 129.826511 -222.787523)
			(xy 130.106421 -222.787523) (xy 130.106421 -222.735589) (xy 130.114546 -222.684294) (xy 130.130594 -222.634901)
			(xy 130.154172 -222.588627) (xy 130.184698 -222.546611) (xy 130.221421 -222.509888) (xy 130.263437 -222.479362)
			(xy 130.309711 -222.455784) (xy 130.359104 -222.439736) (xy 130.410399 -222.431611) (xy 130.462333 -222.431611)
			(xy 130.513628 -222.439736) (xy 130.563021 -222.455784) (xy 130.609295 -222.479362) (xy 130.651311 -222.509888)
			(xy 130.688034 -222.546611) (xy 130.71856 -222.588627) (xy 130.742138 -222.634901) (xy 130.758186 -222.684294)
			(xy 130.766311 -222.735589) (xy 130.76682 -222.761556) (xy 130.766311 -222.787523) (xy 131.046221 -222.787523)
			(xy 131.046221 -222.735589) (xy 131.054346 -222.684294) (xy 131.070394 -222.634901) (xy 131.093972 -222.588627)
			(xy 131.124498 -222.546611) (xy 131.161221 -222.509888) (xy 131.203237 -222.479362) (xy 131.249511 -222.455784)
			(xy 131.298904 -222.439736) (xy 131.350199 -222.431611) (xy 131.402133 -222.431611) (xy 131.453428 -222.439736)
			(xy 131.502821 -222.455784) (xy 131.549095 -222.479362) (xy 131.591111 -222.509888) (xy 131.627834 -222.546611)
			(xy 131.65836 -222.588627) (xy 131.681938 -222.634901) (xy 131.697986 -222.684294) (xy 131.706111 -222.735589)
			(xy 131.70662 -222.761556) (xy 131.706111 -222.787523) (xy 131.706108 -222.787543) (xy 131.985768 -222.787543)
			(xy 131.985768 -222.735569) (xy 131.993898 -222.684234) (xy 132.009959 -222.634804) (xy 132.033555 -222.588494)
			(xy 132.064105 -222.546446) (xy 132.100856 -222.509695) (xy 132.142904 -222.479145) (xy 132.189214 -222.455549)
			(xy 132.238644 -222.439488) (xy 132.289979 -222.431358) (xy 132.341953 -222.431358) (xy 132.393288 -222.439488)
			(xy 132.442718 -222.455549) (xy 132.489028 -222.479145) (xy 132.531076 -222.509695) (xy 132.567827 -222.546446)
			(xy 132.598377 -222.588494) (xy 132.621973 -222.634804) (xy 132.638034 -222.684234) (xy 132.646164 -222.735569)
			(xy 132.646674 -222.761556) (xy 132.646164 -222.787543) (xy 132.925568 -222.787543) (xy 132.925568 -222.735569)
			(xy 132.933698 -222.684234) (xy 132.949759 -222.634804) (xy 132.973355 -222.588494) (xy 133.003905 -222.546446)
			(xy 133.040656 -222.509695) (xy 133.082704 -222.479145) (xy 133.129014 -222.455549) (xy 133.178444 -222.439488)
			(xy 133.229779 -222.431358) (xy 133.281753 -222.431358) (xy 133.333088 -222.439488) (xy 133.382518 -222.455549)
			(xy 133.428828 -222.479145) (xy 133.470876 -222.509695) (xy 133.507627 -222.546446) (xy 133.538177 -222.588494)
			(xy 133.561773 -222.634804) (xy 133.577834 -222.684234) (xy 133.585964 -222.735569) (xy 133.586474 -222.761556)
			(xy 133.585964 -222.787523) (xy 133.865621 -222.787523) (xy 133.865621 -222.735589) (xy 133.873746 -222.684294)
			(xy 133.889794 -222.634901) (xy 133.913372 -222.588627) (xy 133.943898 -222.546611) (xy 133.980621 -222.509888)
			(xy 134.022637 -222.479362) (xy 134.068911 -222.455784) (xy 134.118304 -222.439736) (xy 134.169599 -222.431611)
			(xy 134.221533 -222.431611) (xy 134.272828 -222.439736) (xy 134.322221 -222.455784) (xy 134.368495 -222.479362)
			(xy 134.410511 -222.509888) (xy 134.447234 -222.546611) (xy 134.47776 -222.588627) (xy 134.501338 -222.634901)
			(xy 134.517386 -222.684294) (xy 134.525511 -222.735589) (xy 134.52602 -222.761556) (xy 134.525511 -222.787523)
			(xy 134.517386 -222.838818) (xy 134.501338 -222.888211) (xy 134.47776 -222.934485) (xy 134.447234 -222.976501)
			(xy 134.410511 -223.013224) (xy 134.368495 -223.04375) (xy 134.322221 -223.067328) (xy 134.272828 -223.083376)
			(xy 134.221533 -223.091501) (xy 134.169599 -223.091501) (xy 134.118304 -223.083376) (xy 134.068911 -223.067328)
			(xy 134.022637 -223.04375) (xy 133.980621 -223.013224) (xy 133.943898 -222.976501) (xy 133.913372 -222.934485)
			(xy 133.889794 -222.888211) (xy 133.873746 -222.838818) (xy 133.865621 -222.787523) (xy 133.585964 -222.787523)
			(xy 133.585964 -222.787543) (xy 133.577834 -222.838878) (xy 133.561773 -222.888308) (xy 133.538177 -222.934618)
			(xy 133.507627 -222.976666) (xy 133.470876 -223.013417) (xy 133.428828 -223.043967) (xy 133.382518 -223.067563)
			(xy 133.333088 -223.083624) (xy 133.281753 -223.091754) (xy 133.229779 -223.091754) (xy 133.178444 -223.083624)
			(xy 133.129014 -223.067563) (xy 133.082704 -223.043967) (xy 133.040656 -223.013417) (xy 133.003905 -222.976666)
			(xy 132.973355 -222.934618) (xy 132.949759 -222.888308) (xy 132.933698 -222.838878) (xy 132.925568 -222.787543)
			(xy 132.646164 -222.787543) (xy 132.638034 -222.838878) (xy 132.621973 -222.888308) (xy 132.598377 -222.934618)
			(xy 132.567827 -222.976666) (xy 132.531076 -223.013417) (xy 132.489028 -223.043967) (xy 132.442718 -223.067563)
			(xy 132.393288 -223.083624) (xy 132.341953 -223.091754) (xy 132.289979 -223.091754) (xy 132.238644 -223.083624)
			(xy 132.189214 -223.067563) (xy 132.142904 -223.043967) (xy 132.100856 -223.013417) (xy 132.064105 -222.976666)
			(xy 132.033555 -222.934618) (xy 132.009959 -222.888308) (xy 131.993898 -222.838878) (xy 131.985768 -222.787543)
			(xy 131.706108 -222.787543) (xy 131.697986 -222.838818) (xy 131.681938 -222.888211) (xy 131.65836 -222.934485)
			(xy 131.627834 -222.976501) (xy 131.591111 -223.013224) (xy 131.549095 -223.04375) (xy 131.502821 -223.067328)
			(xy 131.453428 -223.083376) (xy 131.402133 -223.091501) (xy 131.350199 -223.091501) (xy 131.298904 -223.083376)
			(xy 131.249511 -223.067328) (xy 131.203237 -223.04375) (xy 131.161221 -223.013224) (xy 131.124498 -222.976501)
			(xy 131.093972 -222.934485) (xy 131.070394 -222.888211) (xy 131.054346 -222.838818) (xy 131.046221 -222.787523)
			(xy 130.766311 -222.787523) (xy 130.758186 -222.838818) (xy 130.742138 -222.888211) (xy 130.71856 -222.934485)
			(xy 130.688034 -222.976501) (xy 130.651311 -223.013224) (xy 130.609295 -223.04375) (xy 130.563021 -223.067328)
			(xy 130.513628 -223.083376) (xy 130.462333 -223.091501) (xy 130.410399 -223.091501) (xy 130.359104 -223.083376)
			(xy 130.309711 -223.067328) (xy 130.263437 -223.04375) (xy 130.221421 -223.013224) (xy 130.184698 -222.976501)
			(xy 130.154172 -222.934485) (xy 130.130594 -222.888211) (xy 130.114546 -222.838818) (xy 130.106421 -222.787523)
			(xy 129.826511 -222.787523) (xy 129.818386 -222.838818) (xy 129.802338 -222.888211) (xy 129.77876 -222.934485)
			(xy 129.748234 -222.976501) (xy 129.711511 -223.013224) (xy 129.669495 -223.04375) (xy 129.623221 -223.067328)
			(xy 129.573828 -223.083376) (xy 129.522533 -223.091501) (xy 129.470599 -223.091501) (xy 129.419304 -223.083376)
			(xy 129.369911 -223.067328) (xy 129.323637 -223.04375) (xy 129.281621 -223.013224) (xy 129.244898 -222.976501)
			(xy 129.214372 -222.934485) (xy 129.190794 -222.888211) (xy 129.174746 -222.838818) (xy 129.166621 -222.787523)
			(xy 128.886711 -222.787523) (xy 128.878586 -222.838818) (xy 128.862538 -222.888211) (xy 128.83896 -222.934485)
			(xy 128.808434 -222.976501) (xy 128.771711 -223.013224) (xy 128.729695 -223.04375) (xy 128.683421 -223.067328)
			(xy 128.634028 -223.083376) (xy 128.582733 -223.091501) (xy 128.530799 -223.091501) (xy 128.479504 -223.083376)
			(xy 128.430111 -223.067328) (xy 128.383837 -223.04375) (xy 128.341821 -223.013224) (xy 128.305098 -222.976501)
			(xy 128.274572 -222.934485) (xy 128.250994 -222.888211) (xy 128.234946 -222.838818) (xy 128.226821 -222.787523)
			(xy 127.946911 -222.787523) (xy 127.938786 -222.838818) (xy 127.922738 -222.888211) (xy 127.89916 -222.934485)
			(xy 127.868634 -222.976501) (xy 127.831911 -223.013224) (xy 127.789895 -223.04375) (xy 127.743621 -223.067328)
			(xy 127.694228 -223.083376) (xy 127.642933 -223.091501) (xy 127.590999 -223.091501) (xy 127.539704 -223.083376)
			(xy 127.490311 -223.067328) (xy 127.444037 -223.04375) (xy 127.402021 -223.013224) (xy 127.365298 -222.976501)
			(xy 127.334772 -222.934485) (xy 127.311194 -222.888211) (xy 127.295146 -222.838818) (xy 127.287021 -222.787523)
			(xy 127.007111 -222.787523) (xy 126.998986 -222.838818) (xy 126.982938 -222.888211) (xy 126.95936 -222.934485)
			(xy 126.928834 -222.976501) (xy 126.892111 -223.013224) (xy 126.850095 -223.04375) (xy 126.803821 -223.067328)
			(xy 126.754428 -223.083376) (xy 126.703133 -223.091501) (xy 126.651199 -223.091501) (xy 126.599904 -223.083376)
			(xy 126.550511 -223.067328) (xy 126.504237 -223.04375) (xy 126.462221 -223.013224) (xy 126.425498 -222.976501)
			(xy 126.394972 -222.934485) (xy 126.371394 -222.888211) (xy 126.355346 -222.838818) (xy 126.347221 -222.787523)
			(xy 126.067311 -222.787523) (xy 126.059186 -222.838818) (xy 126.043138 -222.888211) (xy 126.01956 -222.934485)
			(xy 125.989034 -222.976501) (xy 125.952311 -223.013224) (xy 125.910295 -223.04375) (xy 125.864021 -223.067328)
			(xy 125.814628 -223.083376) (xy 125.763333 -223.091501) (xy 125.711399 -223.091501) (xy 125.660104 -223.083376)
			(xy 125.610711 -223.067328) (xy 125.564437 -223.04375) (xy 125.522421 -223.013224) (xy 125.485698 -222.976501)
			(xy 125.455172 -222.934485) (xy 125.431594 -222.888211) (xy 125.415546 -222.838818) (xy 125.407421 -222.787523)
			(xy 125.127511 -222.787523) (xy 125.119386 -222.838818) (xy 125.103338 -222.888211) (xy 125.07976 -222.934485)
			(xy 125.049234 -222.976501) (xy 125.012511 -223.013224) (xy 124.970495 -223.04375) (xy 124.924221 -223.067328)
			(xy 124.874828 -223.083376) (xy 124.823533 -223.091501) (xy 124.771599 -223.091501) (xy 124.720304 -223.083376)
			(xy 124.670911 -223.067328) (xy 124.624637 -223.04375) (xy 124.582621 -223.013224) (xy 124.545898 -222.976501)
			(xy 124.515372 -222.934485) (xy 124.491794 -222.888211) (xy 124.475746 -222.838818) (xy 124.467621 -222.787523)
			(xy 124.187711 -222.787523) (xy 124.179586 -222.838818) (xy 124.163538 -222.888211) (xy 124.13996 -222.934485)
			(xy 124.109434 -222.976501) (xy 124.072711 -223.013224) (xy 124.030695 -223.04375) (xy 123.984421 -223.067328)
			(xy 123.935028 -223.083376) (xy 123.883733 -223.091501) (xy 123.831799 -223.091501) (xy 123.780504 -223.083376)
			(xy 123.731111 -223.067328) (xy 123.684837 -223.04375) (xy 123.642821 -223.013224) (xy 123.606098 -222.976501)
			(xy 123.575572 -222.934485) (xy 123.551994 -222.888211) (xy 123.535946 -222.838818) (xy 123.527821 -222.787523)
			(xy 123.247911 -222.787523) (xy 123.239786 -222.838818) (xy 123.223738 -222.888211) (xy 123.20016 -222.934485)
			(xy 123.169634 -222.976501) (xy 123.132911 -223.013224) (xy 123.090895 -223.04375) (xy 123.044621 -223.067328)
			(xy 122.995228 -223.083376) (xy 122.943933 -223.091501) (xy 122.891999 -223.091501) (xy 122.840704 -223.083376)
			(xy 122.791311 -223.067328) (xy 122.745037 -223.04375) (xy 122.703021 -223.013224) (xy 122.666298 -222.976501)
			(xy 122.635772 -222.934485) (xy 122.612194 -222.888211) (xy 122.596146 -222.838818) (xy 122.588021 -222.787523)
			(xy 122.308111 -222.787523) (xy 122.299986 -222.838818) (xy 122.283938 -222.888211) (xy 122.26036 -222.934485)
			(xy 122.229834 -222.976501) (xy 122.193111 -223.013224) (xy 122.151095 -223.04375) (xy 122.104821 -223.067328)
			(xy 122.055428 -223.083376) (xy 122.004133 -223.091501) (xy 121.952199 -223.091501) (xy 121.900904 -223.083376)
			(xy 121.851511 -223.067328) (xy 121.805237 -223.04375) (xy 121.763221 -223.013224) (xy 121.726498 -222.976501)
			(xy 121.695972 -222.934485) (xy 121.672394 -222.888211) (xy 121.656346 -222.838818) (xy 121.648221 -222.787523)
			(xy 121.367471 -222.787523) (xy 121.365361 -222.814015) (xy 121.352942 -222.86511) (xy 121.332591 -222.913595)
			(xy 121.304821 -222.958248) (xy 121.270334 -222.997942) (xy 121.229998 -223.031676) (xy 121.18483 -223.0586)
			(xy 121.13597 -223.078034) (xy 121.08465 -223.08949) (xy 121.058432 -223.091502) (xy 121.01068 -223.142048)
			(xy 121.01068 -223.601593) (xy 121.178321 -223.601593) (xy 121.178321 -223.549659) (xy 121.186446 -223.498364)
			(xy 121.202494 -223.448971) (xy 121.226072 -223.402697) (xy 121.256598 -223.360681) (xy 121.293321 -223.323958)
			(xy 121.335337 -223.293432) (xy 121.381611 -223.269854) (xy 121.431004 -223.253806) (xy 121.482299 -223.245681)
			(xy 121.534233 -223.245681) (xy 121.585528 -223.253806) (xy 121.634921 -223.269854) (xy 121.681195 -223.293432)
			(xy 121.723211 -223.323958) (xy 121.759934 -223.360681) (xy 121.79046 -223.402697) (xy 121.814038 -223.448971)
			(xy 121.830086 -223.498364) (xy 121.838211 -223.549659) (xy 121.83872 -223.575626) (xy 121.838211 -223.601593)
			(xy 121.830086 -223.652888) (xy 121.814038 -223.702281) (xy 121.79046 -223.748555) (xy 121.759934 -223.790571)
			(xy 121.723211 -223.827294) (xy 121.681195 -223.85782) (xy 121.634921 -223.881398) (xy 121.585528 -223.897446)
			(xy 121.534233 -223.905571) (xy 121.482299 -223.905571) (xy 121.431004 -223.897446) (xy 121.381611 -223.881398)
			(xy 121.335337 -223.85782) (xy 121.293321 -223.827294) (xy 121.256598 -223.790571) (xy 121.226072 -223.748555)
			(xy 121.202494 -223.702281) (xy 121.186446 -223.652888) (xy 121.178321 -223.601593) (xy 121.01068 -223.601593)
			(xy 121.01068 -224.00895) (xy 121.058432 -224.059496) (xy 121.083332 -224.061459) (xy 121.132165 -224.071942)
			(xy 121.178864 -224.089655) (xy 121.222366 -224.114195) (xy 121.261678 -224.145003) (xy 121.295905 -224.181377)
			(xy 121.324268 -224.222488) (xy 121.346119 -224.2674) (xy 121.360963 -224.315089) (xy 121.368459 -224.364469)
			(xy 121.36882 -224.389442) (xy 121.647712 -224.389442) (xy 121.648174 -224.363991) (xy 121.65596 -224.313687)
			(xy 121.671368 -224.265174) (xy 121.694036 -224.219597) (xy 121.723425 -224.178036) (xy 121.758841 -224.141475)
			(xy 121.799446 -224.110778) (xy 121.844278 -224.086672) (xy 121.892277 -224.069728) (xy 121.917206 -224.064576)
			(xy 121.940066 -224.060258) (xy 122.143774 -223.707198) (xy 122.136154 -223.685354) (xy 122.127431 -223.658761)
			(xy 122.117974 -223.603606) (xy 122.117358 -223.575626) (xy 122.117867 -223.549659) (xy 122.125992 -223.498364)
			(xy 122.14204 -223.448971) (xy 122.165618 -223.402697) (xy 122.196144 -223.360681) (xy 122.232867 -223.323958)
			(xy 122.274883 -223.293432) (xy 122.321157 -223.269854) (xy 122.37055 -223.253806) (xy 122.421845 -223.245681)
			(xy 122.473779 -223.245681) (xy 122.525074 -223.253806) (xy 122.574467 -223.269854) (xy 122.620741 -223.293432)
			(xy 122.662757 -223.323958) (xy 122.69948 -223.360681) (xy 122.730006 -223.402697) (xy 122.753584 -223.448971)
			(xy 122.769632 -223.498364) (xy 122.777757 -223.549659) (xy 122.778266 -223.575626) (xy 122.777793 -223.601077)
			(xy 122.777713 -223.601593) (xy 123.057921 -223.601593) (xy 123.057921 -223.549659) (xy 123.066046 -223.498364)
			(xy 123.082094 -223.448971) (xy 123.105672 -223.402697) (xy 123.136198 -223.360681) (xy 123.172921 -223.323958)
			(xy 123.214937 -223.293432) (xy 123.261211 -223.269854) (xy 123.310604 -223.253806) (xy 123.361899 -223.245681)
			(xy 123.413833 -223.245681) (xy 123.465128 -223.253806) (xy 123.514521 -223.269854) (xy 123.560795 -223.293432)
			(xy 123.602811 -223.323958) (xy 123.639534 -223.360681) (xy 123.67006 -223.402697) (xy 123.693638 -223.448971)
			(xy 123.709686 -223.498364) (xy 123.717811 -223.549659) (xy 123.71832 -223.575626) (xy 123.717811 -223.601593)
			(xy 123.709686 -223.652888) (xy 123.693638 -223.702281) (xy 123.67006 -223.748555) (xy 123.639534 -223.790571)
			(xy 123.602811 -223.827294) (xy 123.560795 -223.85782) (xy 123.514521 -223.881398) (xy 123.465128 -223.897446)
			(xy 123.413833 -223.905571) (xy 123.361899 -223.905571) (xy 123.310604 -223.897446) (xy 123.261211 -223.881398)
			(xy 123.214937 -223.85782) (xy 123.172921 -223.827294) (xy 123.136198 -223.790571) (xy 123.105672 -223.748555)
			(xy 123.082094 -223.702281) (xy 123.066046 -223.652888) (xy 123.057921 -223.601593) (xy 122.777713 -223.601593)
			(xy 122.770011 -223.651381) (xy 122.754606 -223.699896) (xy 122.731941 -223.745473) (xy 122.702553 -223.787035)
			(xy 122.667137 -223.823597) (xy 122.626533 -223.854293) (xy 122.5817 -223.878398) (xy 122.533701 -223.895341)
			(xy 122.508772 -223.900492) (xy 122.485658 -223.90481) (xy 122.282204 -224.257616) (xy 122.289824 -224.279714)
			(xy 122.298566 -224.306301) (xy 122.30801 -224.361461) (xy 122.30862 -224.389442) (xy 122.587512 -224.389442)
			(xy 122.588021 -224.363475) (xy 122.596146 -224.31218) (xy 122.612194 -224.262787) (xy 122.635772 -224.216513)
			(xy 122.666298 -224.174497) (xy 122.703021 -224.137774) (xy 122.745037 -224.107248) (xy 122.791311 -224.08367)
			(xy 122.840704 -224.067622) (xy 122.891999 -224.059497) (xy 122.943933 -224.059497) (xy 122.995228 -224.067622)
			(xy 123.044621 -224.08367) (xy 123.090895 -224.107248) (xy 123.132911 -224.137774) (xy 123.169634 -224.174497)
			(xy 123.20016 -224.216513) (xy 123.223738 -224.262787) (xy 123.239786 -224.31218) (xy 123.247911 -224.363475)
			(xy 123.24842 -224.389442) (xy 123.527312 -224.389442) (xy 123.527774 -224.363991) (xy 123.53556 -224.313687)
			(xy 123.550968 -224.265174) (xy 123.573636 -224.219597) (xy 123.603025 -224.178036) (xy 123.638441 -224.141475)
			(xy 123.679046 -224.110778) (xy 123.723878 -224.086672) (xy 123.771877 -224.069728) (xy 123.796806 -224.064576)
			(xy 123.819666 -224.060258) (xy 124.023374 -223.707198) (xy 124.015754 -223.685354) (xy 124.007031 -223.658761)
			(xy 123.997574 -223.603606) (xy 123.996958 -223.575626) (xy 123.997467 -223.549659) (xy 124.005592 -223.498364)
			(xy 124.02164 -223.448971) (xy 124.045218 -223.402697) (xy 124.075744 -223.360681) (xy 124.112467 -223.323958)
			(xy 124.154483 -223.293432) (xy 124.200757 -223.269854) (xy 124.25015 -223.253806) (xy 124.301445 -223.245681)
			(xy 124.353379 -223.245681) (xy 124.404674 -223.253806) (xy 124.454067 -223.269854) (xy 124.500341 -223.293432)
			(xy 124.542357 -223.323958) (xy 124.57908 -223.360681) (xy 124.609606 -223.402697) (xy 124.633184 -223.448971)
			(xy 124.649232 -223.498364) (xy 124.657357 -223.549659) (xy 124.657866 -223.575626) (xy 124.657393 -223.601077)
			(xy 124.657313 -223.601593) (xy 124.937521 -223.601593) (xy 124.937521 -223.549659) (xy 124.945646 -223.498364)
			(xy 124.961694 -223.448971) (xy 124.985272 -223.402697) (xy 125.015798 -223.360681) (xy 125.052521 -223.323958)
			(xy 125.094537 -223.293432) (xy 125.140811 -223.269854) (xy 125.190204 -223.253806) (xy 125.241499 -223.245681)
			(xy 125.293433 -223.245681) (xy 125.344728 -223.253806) (xy 125.394121 -223.269854) (xy 125.440395 -223.293432)
			(xy 125.482411 -223.323958) (xy 125.519134 -223.360681) (xy 125.54966 -223.402697) (xy 125.573238 -223.448971)
			(xy 125.589286 -223.498364) (xy 125.597411 -223.549659) (xy 125.59792 -223.575626) (xy 125.597411 -223.601593)
			(xy 125.589286 -223.652888) (xy 125.573238 -223.702281) (xy 125.54966 -223.748555) (xy 125.519134 -223.790571)
			(xy 125.482411 -223.827294) (xy 125.440395 -223.85782) (xy 125.394121 -223.881398) (xy 125.344728 -223.897446)
			(xy 125.293433 -223.905571) (xy 125.241499 -223.905571) (xy 125.190204 -223.897446) (xy 125.140811 -223.881398)
			(xy 125.094537 -223.85782) (xy 125.052521 -223.827294) (xy 125.015798 -223.790571) (xy 124.985272 -223.748555)
			(xy 124.961694 -223.702281) (xy 124.945646 -223.652888) (xy 124.937521 -223.601593) (xy 124.657313 -223.601593)
			(xy 124.649611 -223.651381) (xy 124.634206 -223.699896) (xy 124.611541 -223.745473) (xy 124.582153 -223.787035)
			(xy 124.546737 -223.823597) (xy 124.506133 -223.854293) (xy 124.4613 -223.878398) (xy 124.413301 -223.895341)
			(xy 124.388372 -223.900492) (xy 124.365258 -223.90481) (xy 124.161804 -224.257616) (xy 124.169424 -224.279714)
			(xy 124.178166 -224.306301) (xy 124.18761 -224.361461) (xy 124.18822 -224.389442) (xy 124.467112 -224.389442)
			(xy 124.467621 -224.363475) (xy 124.475746 -224.31218) (xy 124.491794 -224.262787) (xy 124.515372 -224.216513)
			(xy 124.545898 -224.174497) (xy 124.582621 -224.137774) (xy 124.624637 -224.107248) (xy 124.670911 -224.08367)
			(xy 124.720304 -224.067622) (xy 124.771599 -224.059497) (xy 124.823533 -224.059497) (xy 124.874828 -224.067622)
			(xy 124.924221 -224.08367) (xy 124.970495 -224.107248) (xy 125.012511 -224.137774) (xy 125.049234 -224.174497)
			(xy 125.07976 -224.216513) (xy 125.103338 -224.262787) (xy 125.119386 -224.31218) (xy 125.127511 -224.363475)
			(xy 125.12802 -224.389442) (xy 125.406912 -224.389442) (xy 125.407374 -224.363991) (xy 125.41516 -224.313687)
			(xy 125.430568 -224.265174) (xy 125.453236 -224.219597) (xy 125.482625 -224.178036) (xy 125.518041 -224.141475)
			(xy 125.558646 -224.110778) (xy 125.603478 -224.086672) (xy 125.651477 -224.069728) (xy 125.676406 -224.064576)
			(xy 125.699266 -224.060258) (xy 125.902974 -223.707198) (xy 125.895354 -223.685354) (xy 125.886631 -223.658761)
			(xy 125.877174 -223.603606) (xy 125.876558 -223.575626) (xy 125.877067 -223.549659) (xy 125.885192 -223.498364)
			(xy 125.90124 -223.448971) (xy 125.924818 -223.402697) (xy 125.955344 -223.360681) (xy 125.992067 -223.323958)
			(xy 126.034083 -223.293432) (xy 126.080357 -223.269854) (xy 126.12975 -223.253806) (xy 126.181045 -223.245681)
			(xy 126.232979 -223.245681) (xy 126.284274 -223.253806) (xy 126.333667 -223.269854) (xy 126.379941 -223.293432)
			(xy 126.421957 -223.323958) (xy 126.45868 -223.360681) (xy 126.489206 -223.402697) (xy 126.512784 -223.448971)
			(xy 126.528832 -223.498364) (xy 126.536957 -223.549659) (xy 126.537466 -223.575626) (xy 126.536993 -223.601077)
			(xy 126.536913 -223.601593) (xy 126.817121 -223.601593) (xy 126.817121 -223.549659) (xy 126.825246 -223.498364)
			(xy 126.841294 -223.448971) (xy 126.864872 -223.402697) (xy 126.895398 -223.360681) (xy 126.932121 -223.323958)
			(xy 126.974137 -223.293432) (xy 127.020411 -223.269854) (xy 127.069804 -223.253806) (xy 127.121099 -223.245681)
			(xy 127.173033 -223.245681) (xy 127.224328 -223.253806) (xy 127.273721 -223.269854) (xy 127.319995 -223.293432)
			(xy 127.362011 -223.323958) (xy 127.398734 -223.360681) (xy 127.42926 -223.402697) (xy 127.452838 -223.448971)
			(xy 127.468886 -223.498364) (xy 127.477011 -223.549659) (xy 127.47752 -223.575626) (xy 127.477011 -223.601593)
			(xy 127.468886 -223.652888) (xy 127.452838 -223.702281) (xy 127.42926 -223.748555) (xy 127.398734 -223.790571)
			(xy 127.362011 -223.827294) (xy 127.319995 -223.85782) (xy 127.273721 -223.881398) (xy 127.224328 -223.897446)
			(xy 127.173033 -223.905571) (xy 127.121099 -223.905571) (xy 127.069804 -223.897446) (xy 127.020411 -223.881398)
			(xy 126.974137 -223.85782) (xy 126.932121 -223.827294) (xy 126.895398 -223.790571) (xy 126.864872 -223.748555)
			(xy 126.841294 -223.702281) (xy 126.825246 -223.652888) (xy 126.817121 -223.601593) (xy 126.536913 -223.601593)
			(xy 126.529211 -223.651381) (xy 126.513806 -223.699896) (xy 126.491141 -223.745473) (xy 126.461753 -223.787035)
			(xy 126.426337 -223.823597) (xy 126.385733 -223.854293) (xy 126.3409 -223.878398) (xy 126.292901 -223.895341)
			(xy 126.267972 -223.900492) (xy 126.244858 -223.90481) (xy 126.041404 -224.257616) (xy 126.049024 -224.279714)
			(xy 126.057766 -224.306301) (xy 126.06721 -224.361461) (xy 126.06782 -224.389442) (xy 126.346712 -224.389442)
			(xy 126.347221 -224.363475) (xy 126.355346 -224.31218) (xy 126.371394 -224.262787) (xy 126.394972 -224.216513)
			(xy 126.425498 -224.174497) (xy 126.462221 -224.137774) (xy 126.504237 -224.107248) (xy 126.550511 -224.08367)
			(xy 126.599904 -224.067622) (xy 126.651199 -224.059497) (xy 126.703133 -224.059497) (xy 126.754428 -224.067622)
			(xy 126.803821 -224.08367) (xy 126.850095 -224.107248) (xy 126.892111 -224.137774) (xy 126.928834 -224.174497)
			(xy 126.95936 -224.216513) (xy 126.982938 -224.262787) (xy 126.998986 -224.31218) (xy 127.007111 -224.363475)
			(xy 127.00762 -224.389442) (xy 127.286512 -224.389442) (xy 127.286974 -224.363991) (xy 127.29476 -224.313687)
			(xy 127.310168 -224.265174) (xy 127.332836 -224.219597) (xy 127.362225 -224.178036) (xy 127.397641 -224.141475)
			(xy 127.438246 -224.110778) (xy 127.483078 -224.086672) (xy 127.531077 -224.069728) (xy 127.556006 -224.064576)
			(xy 127.578866 -224.060258) (xy 127.782574 -223.707198) (xy 127.774954 -223.685354) (xy 127.766231 -223.658761)
			(xy 127.756774 -223.603606) (xy 127.756158 -223.575626) (xy 127.756667 -223.549659) (xy 127.764792 -223.498364)
			(xy 127.78084 -223.448971) (xy 127.804418 -223.402697) (xy 127.834944 -223.360681) (xy 127.871667 -223.323958)
			(xy 127.913683 -223.293432) (xy 127.959957 -223.269854) (xy 128.00935 -223.253806) (xy 128.060645 -223.245681)
			(xy 128.112579 -223.245681) (xy 128.163874 -223.253806) (xy 128.213267 -223.269854) (xy 128.259541 -223.293432)
			(xy 128.301557 -223.323958) (xy 128.33828 -223.360681) (xy 128.368806 -223.402697) (xy 128.392384 -223.448971)
			(xy 128.408432 -223.498364) (xy 128.416557 -223.549659) (xy 128.417066 -223.575626) (xy 128.416593 -223.601077)
			(xy 128.416513 -223.601593) (xy 128.696721 -223.601593) (xy 128.696721 -223.549659) (xy 128.704846 -223.498364)
			(xy 128.720894 -223.448971) (xy 128.744472 -223.402697) (xy 128.774998 -223.360681) (xy 128.811721 -223.323958)
			(xy 128.853737 -223.293432) (xy 128.900011 -223.269854) (xy 128.949404 -223.253806) (xy 129.000699 -223.245681)
			(xy 129.052633 -223.245681) (xy 129.103928 -223.253806) (xy 129.153321 -223.269854) (xy 129.199595 -223.293432)
			(xy 129.241611 -223.323958) (xy 129.278334 -223.360681) (xy 129.30886 -223.402697) (xy 129.332438 -223.448971)
			(xy 129.348486 -223.498364) (xy 129.356611 -223.549659) (xy 129.35712 -223.575626) (xy 129.356611 -223.601593)
			(xy 129.348486 -223.652888) (xy 129.332438 -223.702281) (xy 129.30886 -223.748555) (xy 129.278334 -223.790571)
			(xy 129.241611 -223.827294) (xy 129.199595 -223.85782) (xy 129.153321 -223.881398) (xy 129.103928 -223.897446)
			(xy 129.052633 -223.905571) (xy 129.000699 -223.905571) (xy 128.949404 -223.897446) (xy 128.900011 -223.881398)
			(xy 128.853737 -223.85782) (xy 128.811721 -223.827294) (xy 128.774998 -223.790571) (xy 128.744472 -223.748555)
			(xy 128.720894 -223.702281) (xy 128.704846 -223.652888) (xy 128.696721 -223.601593) (xy 128.416513 -223.601593)
			(xy 128.408811 -223.651381) (xy 128.393406 -223.699896) (xy 128.370741 -223.745473) (xy 128.341353 -223.787035)
			(xy 128.305937 -223.823597) (xy 128.265333 -223.854293) (xy 128.2205 -223.878398) (xy 128.172501 -223.895341)
			(xy 128.147572 -223.900492) (xy 128.124458 -223.90481) (xy 127.921004 -224.257616) (xy 127.928624 -224.279714)
			(xy 127.937366 -224.306301) (xy 127.94681 -224.361461) (xy 127.94742 -224.389442) (xy 128.226312 -224.389442)
			(xy 128.226821 -224.363475) (xy 128.234946 -224.31218) (xy 128.250994 -224.262787) (xy 128.274572 -224.216513)
			(xy 128.305098 -224.174497) (xy 128.341821 -224.137774) (xy 128.383837 -224.107248) (xy 128.430111 -224.08367)
			(xy 128.479504 -224.067622) (xy 128.530799 -224.059497) (xy 128.582733 -224.059497) (xy 128.634028 -224.067622)
			(xy 128.683421 -224.08367) (xy 128.729695 -224.107248) (xy 128.771711 -224.137774) (xy 128.808434 -224.174497)
			(xy 128.83896 -224.216513) (xy 128.862538 -224.262787) (xy 128.878586 -224.31218) (xy 128.886711 -224.363475)
			(xy 128.88722 -224.389442) (xy 129.166112 -224.389442) (xy 129.166574 -224.363991) (xy 129.17436 -224.313687)
			(xy 129.189768 -224.265174) (xy 129.212436 -224.219597) (xy 129.241825 -224.178036) (xy 129.277241 -224.141475)
			(xy 129.317846 -224.110778) (xy 129.362678 -224.086672) (xy 129.410677 -224.069728) (xy 129.435606 -224.064576)
			(xy 129.458466 -224.060258) (xy 129.662174 -223.707198) (xy 129.654554 -223.685354) (xy 129.645831 -223.658761)
			(xy 129.636374 -223.603606) (xy 129.635758 -223.575626) (xy 129.636267 -223.549659) (xy 129.644392 -223.498364)
			(xy 129.66044 -223.448971) (xy 129.684018 -223.402697) (xy 129.714544 -223.360681) (xy 129.751267 -223.323958)
			(xy 129.793283 -223.293432) (xy 129.839557 -223.269854) (xy 129.88895 -223.253806) (xy 129.940245 -223.245681)
			(xy 129.992179 -223.245681) (xy 130.043474 -223.253806) (xy 130.092867 -223.269854) (xy 130.139141 -223.293432)
			(xy 130.181157 -223.323958) (xy 130.21788 -223.360681) (xy 130.248406 -223.402697) (xy 130.271984 -223.448971)
			(xy 130.288032 -223.498364) (xy 130.296157 -223.549659) (xy 130.296666 -223.575626) (xy 130.296193 -223.601077)
			(xy 130.296113 -223.601593) (xy 130.576321 -223.601593) (xy 130.576321 -223.549659) (xy 130.584446 -223.498364)
			(xy 130.600494 -223.448971) (xy 130.624072 -223.402697) (xy 130.654598 -223.360681) (xy 130.691321 -223.323958)
			(xy 130.733337 -223.293432) (xy 130.779611 -223.269854) (xy 130.829004 -223.253806) (xy 130.880299 -223.245681)
			(xy 130.932233 -223.245681) (xy 130.983528 -223.253806) (xy 131.032921 -223.269854) (xy 131.079195 -223.293432)
			(xy 131.121211 -223.323958) (xy 131.157934 -223.360681) (xy 131.18846 -223.402697) (xy 131.212038 -223.448971)
			(xy 131.228086 -223.498364) (xy 131.236211 -223.549659) (xy 131.23672 -223.575626) (xy 131.236211 -223.601593)
			(xy 131.228086 -223.652888) (xy 131.212038 -223.702281) (xy 131.18846 -223.748555) (xy 131.157934 -223.790571)
			(xy 131.121211 -223.827294) (xy 131.079195 -223.85782) (xy 131.032921 -223.881398) (xy 130.983528 -223.897446)
			(xy 130.932233 -223.905571) (xy 130.880299 -223.905571) (xy 130.829004 -223.897446) (xy 130.779611 -223.881398)
			(xy 130.733337 -223.85782) (xy 130.691321 -223.827294) (xy 130.654598 -223.790571) (xy 130.624072 -223.748555)
			(xy 130.600494 -223.702281) (xy 130.584446 -223.652888) (xy 130.576321 -223.601593) (xy 130.296113 -223.601593)
			(xy 130.288411 -223.651381) (xy 130.273006 -223.699896) (xy 130.250341 -223.745473) (xy 130.220953 -223.787035)
			(xy 130.185537 -223.823597) (xy 130.144933 -223.854293) (xy 130.1001 -223.878398) (xy 130.052101 -223.895341)
			(xy 130.027172 -223.900492) (xy 130.004058 -223.90481) (xy 129.800604 -224.257616) (xy 129.808224 -224.279714)
			(xy 129.816966 -224.306301) (xy 129.82641 -224.361461) (xy 129.82702 -224.389442) (xy 130.105912 -224.389442)
			(xy 130.106421 -224.363475) (xy 130.114546 -224.31218) (xy 130.130594 -224.262787) (xy 130.154172 -224.216513)
			(xy 130.184698 -224.174497) (xy 130.221421 -224.137774) (xy 130.263437 -224.107248) (xy 130.309711 -224.08367)
			(xy 130.359104 -224.067622) (xy 130.410399 -224.059497) (xy 130.462333 -224.059497) (xy 130.513628 -224.067622)
			(xy 130.563021 -224.08367) (xy 130.609295 -224.107248) (xy 130.651311 -224.137774) (xy 130.688034 -224.174497)
			(xy 130.71856 -224.216513) (xy 130.742138 -224.262787) (xy 130.758186 -224.31218) (xy 130.766311 -224.363475)
			(xy 130.76682 -224.389442) (xy 131.045712 -224.389442) (xy 131.046174 -224.363991) (xy 131.05396 -224.313687)
			(xy 131.069368 -224.265174) (xy 131.092036 -224.219597) (xy 131.121425 -224.178036) (xy 131.156841 -224.141475)
			(xy 131.197446 -224.110778) (xy 131.242278 -224.086672) (xy 131.290277 -224.069728) (xy 131.315206 -224.064576)
			(xy 131.33832 -224.060258) (xy 131.541774 -223.707198) (xy 131.534154 -223.6851) (xy 131.525408 -223.658579)
			(xy 131.515959 -223.603545) (xy 131.515358 -223.575626) (xy 131.515867 -223.549659) (xy 131.523992 -223.498364)
			(xy 131.54004 -223.448971) (xy 131.563618 -223.402697) (xy 131.594144 -223.360681) (xy 131.630867 -223.323958)
			(xy 131.672883 -223.293432) (xy 131.719157 -223.269854) (xy 131.76855 -223.253806) (xy 131.819845 -223.245681)
			(xy 131.871779 -223.245681) (xy 131.923074 -223.253806) (xy 131.972467 -223.269854) (xy 132.018741 -223.293432)
			(xy 132.060757 -223.323958) (xy 132.09748 -223.360681) (xy 132.128006 -223.402697) (xy 132.151584 -223.448971)
			(xy 132.167632 -223.498364) (xy 132.175757 -223.549659) (xy 132.176266 -223.575626) (xy 132.175793 -223.601077)
			(xy 132.175713 -223.601593) (xy 132.455921 -223.601593) (xy 132.455921 -223.549659) (xy 132.464046 -223.498364)
			(xy 132.480094 -223.448971) (xy 132.503672 -223.402697) (xy 132.534198 -223.360681) (xy 132.570921 -223.323958)
			(xy 132.612937 -223.293432) (xy 132.659211 -223.269854) (xy 132.708604 -223.253806) (xy 132.759899 -223.245681)
			(xy 132.811833 -223.245681) (xy 132.863128 -223.253806) (xy 132.912521 -223.269854) (xy 132.958795 -223.293432)
			(xy 133.000811 -223.323958) (xy 133.037534 -223.360681) (xy 133.06806 -223.402697) (xy 133.091638 -223.448971)
			(xy 133.107686 -223.498364) (xy 133.115811 -223.549659) (xy 133.11632 -223.575626) (xy 133.115811 -223.601593)
			(xy 133.107686 -223.652888) (xy 133.091638 -223.702281) (xy 133.06806 -223.748555) (xy 133.037534 -223.790571)
			(xy 133.000811 -223.827294) (xy 132.958795 -223.85782) (xy 132.912521 -223.881398) (xy 132.863128 -223.897446)
			(xy 132.811833 -223.905571) (xy 132.759899 -223.905571) (xy 132.708604 -223.897446) (xy 132.659211 -223.881398)
			(xy 132.612937 -223.85782) (xy 132.570921 -223.827294) (xy 132.534198 -223.790571) (xy 132.503672 -223.748555)
			(xy 132.480094 -223.702281) (xy 132.464046 -223.652888) (xy 132.455921 -223.601593) (xy 132.175713 -223.601593)
			(xy 132.168011 -223.651381) (xy 132.152606 -223.699896) (xy 132.129941 -223.745473) (xy 132.100553 -223.787035)
			(xy 132.065137 -223.823597) (xy 132.024533 -223.854293) (xy 131.9797 -223.878398) (xy 131.931701 -223.895341)
			(xy 131.906772 -223.900492) (xy 131.883658 -223.90481) (xy 131.680204 -224.257616) (xy 131.687824 -224.279714)
			(xy 131.696566 -224.306301) (xy 131.70601 -224.361461) (xy 131.70662 -224.389442) (xy 131.985512 -224.389442)
			(xy 131.986021 -224.363475) (xy 131.994146 -224.31218) (xy 132.010194 -224.262787) (xy 132.033772 -224.216513)
			(xy 132.064298 -224.174497) (xy 132.101021 -224.137774) (xy 132.143037 -224.107248) (xy 132.189311 -224.08367)
			(xy 132.238704 -224.067622) (xy 132.289999 -224.059497) (xy 132.341933 -224.059497) (xy 132.393228 -224.067622)
			(xy 132.442621 -224.08367) (xy 132.488895 -224.107248) (xy 132.530911 -224.137774) (xy 132.567634 -224.174497)
			(xy 132.59816 -224.216513) (xy 132.621738 -224.262787) (xy 132.637786 -224.31218) (xy 132.645911 -224.363475)
			(xy 132.64642 -224.389442) (xy 132.925312 -224.389442) (xy 132.925774 -224.363991) (xy 132.93356 -224.313687)
			(xy 132.948968 -224.265174) (xy 132.971636 -224.219597) (xy 133.001025 -224.178036) (xy 133.036441 -224.141475)
			(xy 133.077046 -224.110778) (xy 133.121878 -224.086672) (xy 133.169877 -224.069728) (xy 133.194806 -224.064576)
			(xy 133.21792 -224.060258) (xy 133.421628 -223.706944) (xy 133.413754 -223.6851) (xy 133.405142 -223.658749)
			(xy 133.395821 -223.604104) (xy 133.395212 -223.576388) (xy 133.395212 -223.575626) (xy 133.395721 -223.549659)
			(xy 133.403846 -223.498364) (xy 133.419894 -223.448971) (xy 133.443472 -223.402697) (xy 133.473998 -223.360681)
			(xy 133.510721 -223.323958) (xy 133.552737 -223.293432) (xy 133.599011 -223.269854) (xy 133.648404 -223.253806)
			(xy 133.699699 -223.245681) (xy 133.751633 -223.245681) (xy 133.802928 -223.253806) (xy 133.852321 -223.269854)
			(xy 133.898595 -223.293432) (xy 133.940611 -223.323958) (xy 133.977334 -223.360681) (xy 134.00786 -223.402697)
			(xy 134.031438 -223.448971) (xy 134.047486 -223.498364) (xy 134.055611 -223.549659) (xy 134.05612 -223.575626)
			(xy 134.055646 -223.601088) (xy 134.047844 -223.651411) (xy 134.032413 -223.699941) (xy 134.009719 -223.745529)
			(xy 133.980299 -223.787095) (xy 133.94485 -223.823656) (xy 133.904212 -223.854344) (xy 133.859346 -223.878434)
			(xy 133.811315 -223.895354) (xy 133.786372 -223.900492) (xy 133.763258 -223.90481) (xy 133.559804 -224.257616)
			(xy 133.567424 -224.279714) (xy 133.576166 -224.306301) (xy 133.58561 -224.361461) (xy 133.58622 -224.389442)
			(xy 133.865112 -224.389442) (xy 133.865621 -224.363475) (xy 133.873746 -224.31218) (xy 133.889794 -224.262787)
			(xy 133.913372 -224.216513) (xy 133.943898 -224.174497) (xy 133.980621 -224.137774) (xy 134.022637 -224.107248)
			(xy 134.068911 -224.08367) (xy 134.118304 -224.067622) (xy 134.169599 -224.059497) (xy 134.221533 -224.059497)
			(xy 134.272828 -224.067622) (xy 134.322221 -224.08367) (xy 134.368495 -224.107248) (xy 134.410511 -224.137774)
			(xy 134.447234 -224.174497) (xy 134.47776 -224.216513) (xy 134.501338 -224.262787) (xy 134.517386 -224.31218)
			(xy 134.525511 -224.363475) (xy 134.52602 -224.389442) (xy 134.525393 -224.417359) (xy 134.515944 -224.472389)
			(xy 134.507224 -224.498916) (xy 134.499604 -224.521014) (xy 134.703312 -224.874074) (xy 134.726426 -224.878392)
			(xy 134.751351 -224.883545) (xy 134.799337 -224.90051) (xy 134.844156 -224.924628) (xy 134.88475 -224.95533)
			(xy 134.92016 -224.99189) (xy 134.949548 -225.033444) (xy 134.97222 -225.079012) (xy 134.987642 -225.127516)
			(xy 134.995448 -225.17781) (xy 134.99592 -225.203258) (xy 134.995411 -225.229225) (xy 134.987286 -225.28052)
			(xy 134.971238 -225.329913) (xy 134.94766 -225.376187) (xy 134.917134 -225.418203) (xy 134.880411 -225.454926)
			(xy 134.838395 -225.485452) (xy 134.792121 -225.50903) (xy 134.742728 -225.525078) (xy 134.691433 -225.533203)
			(xy 134.639499 -225.533203) (xy 134.588204 -225.525078) (xy 134.538811 -225.50903) (xy 134.492537 -225.485452)
			(xy 134.450521 -225.454926) (xy 134.413798 -225.418203) (xy 134.383272 -225.376187) (xy 134.359694 -225.329913)
			(xy 134.343646 -225.28052) (xy 134.335521 -225.229225) (xy 134.335012 -225.203258) (xy 134.335554 -225.175272)
			(xy 134.345011 -225.120104) (xy 134.353808 -225.09353) (xy 134.361428 -225.071432) (xy 134.157974 -224.718626)
			(xy 134.13486 -224.714308) (xy 134.10993 -224.70912) (xy 134.061906 -224.692197) (xy 134.017046 -224.668109)
			(xy 133.976411 -224.637425) (xy 133.940963 -224.600872) (xy 133.911541 -224.559315) (xy 133.888842 -224.513737)
			(xy 133.873401 -224.465216) (xy 133.865585 -224.414901) (xy 133.865112 -224.389442) (xy 133.58622 -224.389442)
			(xy 133.585711 -224.415409) (xy 133.577586 -224.466704) (xy 133.561538 -224.516097) (xy 133.53796 -224.562371)
			(xy 133.507434 -224.604387) (xy 133.470711 -224.64111) (xy 133.428695 -224.671636) (xy 133.382421 -224.695214)
			(xy 133.333028 -224.711262) (xy 133.281733 -224.719387) (xy 133.229799 -224.719387) (xy 133.178504 -224.711262)
			(xy 133.129111 -224.695214) (xy 133.082837 -224.671636) (xy 133.040821 -224.64111) (xy 133.004098 -224.604387)
			(xy 132.973572 -224.562371) (xy 132.949994 -224.516097) (xy 132.933946 -224.466704) (xy 132.925821 -224.415409)
			(xy 132.925312 -224.389442) (xy 132.64642 -224.389442) (xy 132.645877 -224.417428) (xy 132.63642 -224.472596)
			(xy 132.627624 -224.49917) (xy 132.620004 -224.521268) (xy 132.823712 -224.874074) (xy 132.846572 -224.878392)
			(xy 132.871504 -224.883512) (xy 132.91949 -224.900483) (xy 132.964309 -224.924607) (xy 133.004902 -224.955314)
			(xy 133.040309 -224.991878) (xy 133.069696 -225.033436) (xy 133.092368 -225.079006) (xy 133.107789 -225.127512)
			(xy 133.115594 -225.177809) (xy 133.116066 -225.203258) (xy 133.115557 -225.229225) (xy 133.107432 -225.28052)
			(xy 133.091384 -225.329913) (xy 133.067806 -225.376187) (xy 133.03728 -225.418203) (xy 133.000557 -225.454926)
			(xy 132.958541 -225.485452) (xy 132.912267 -225.50903) (xy 132.862874 -225.525078) (xy 132.811579 -225.533203)
			(xy 132.759645 -225.533203) (xy 132.70835 -225.525078) (xy 132.658957 -225.50903) (xy 132.612683 -225.485452)
			(xy 132.570667 -225.454926) (xy 132.533944 -225.418203) (xy 132.503418 -225.376187) (xy 132.47984 -225.329913)
			(xy 132.463792 -225.28052) (xy 132.455667 -225.229225) (xy 132.455158 -225.203258) (xy 132.455697 -225.175271)
			(xy 132.465156 -225.120104) (xy 132.473954 -225.09353) (xy 132.481574 -225.071432) (xy 132.277866 -224.718626)
			(xy 132.255006 -224.714308) (xy 132.230086 -224.709131) (xy 132.1821 -224.692171) (xy 132.13728 -224.668057)
			(xy 132.096685 -224.637359) (xy 132.061275 -224.600802) (xy 132.031886 -224.55925) (xy 132.009212 -224.513684)
			(xy 131.99379 -224.465182) (xy 131.985984 -224.414889) (xy 131.985512 -224.389442) (xy 131.70662 -224.389442)
			(xy 131.706111 -224.415409) (xy 131.697986 -224.466704) (xy 131.681938 -224.516097) (xy 131.65836 -224.562371)
			(xy 131.627834 -224.604387) (xy 131.591111 -224.64111) (xy 131.549095 -224.671636) (xy 131.502821 -224.695214)
			(xy 131.453428 -224.711262) (xy 131.402133 -224.719387) (xy 131.350199 -224.719387) (xy 131.298904 -224.711262)
			(xy 131.249511 -224.695214) (xy 131.203237 -224.671636) (xy 131.161221 -224.64111) (xy 131.124498 -224.604387)
			(xy 131.093972 -224.562371) (xy 131.070394 -224.516097) (xy 131.054346 -224.466704) (xy 131.046221 -224.415409)
			(xy 131.045712 -224.389442) (xy 130.76682 -224.389442) (xy 130.766277 -224.417428) (xy 130.75682 -224.472596)
			(xy 130.748024 -224.49917) (xy 130.740404 -224.521268) (xy 130.944112 -224.874074) (xy 130.966972 -224.878392)
			(xy 130.991904 -224.883512) (xy 131.03989 -224.900483) (xy 131.084709 -224.924607) (xy 131.125302 -224.955314)
			(xy 131.160709 -224.991878) (xy 131.190096 -225.033436) (xy 131.212768 -225.079006) (xy 131.228189 -225.127512)
			(xy 131.235994 -225.177809) (xy 131.236466 -225.203258) (xy 131.235957 -225.229225) (xy 131.227832 -225.28052)
			(xy 131.211784 -225.329913) (xy 131.188206 -225.376187) (xy 131.15768 -225.418203) (xy 131.120957 -225.454926)
			(xy 131.078941 -225.485452) (xy 131.032667 -225.50903) (xy 130.983274 -225.525078) (xy 130.931979 -225.533203)
			(xy 130.880045 -225.533203) (xy 130.82875 -225.525078) (xy 130.779357 -225.50903) (xy 130.733083 -225.485452)
			(xy 130.691067 -225.454926) (xy 130.654344 -225.418203) (xy 130.623818 -225.376187) (xy 130.60024 -225.329913)
			(xy 130.584192 -225.28052) (xy 130.576067 -225.229225) (xy 130.575558 -225.203258) (xy 130.576097 -225.175271)
			(xy 130.585556 -225.120104) (xy 130.594354 -225.09353) (xy 130.601974 -225.071432) (xy 130.398266 -224.718626)
			(xy 130.375406 -224.714308) (xy 130.350486 -224.709131) (xy 130.3025 -224.692171) (xy 130.25768 -224.668057)
			(xy 130.217085 -224.637359) (xy 130.181675 -224.600802) (xy 130.152286 -224.55925) (xy 130.129612 -224.513684)
			(xy 130.11419 -224.465182) (xy 130.106384 -224.414889) (xy 130.105912 -224.389442) (xy 129.82702 -224.389442)
			(xy 129.826511 -224.415409) (xy 129.818386 -224.466704) (xy 129.802338 -224.516097) (xy 129.77876 -224.562371)
			(xy 129.748234 -224.604387) (xy 129.711511 -224.64111) (xy 129.669495 -224.671636) (xy 129.623221 -224.695214)
			(xy 129.573828 -224.711262) (xy 129.522533 -224.719387) (xy 129.470599 -224.719387) (xy 129.419304 -224.711262)
			(xy 129.369911 -224.695214) (xy 129.323637 -224.671636) (xy 129.281621 -224.64111) (xy 129.244898 -224.604387)
			(xy 129.214372 -224.562371) (xy 129.190794 -224.516097) (xy 129.174746 -224.466704) (xy 129.166621 -224.415409)
			(xy 129.166112 -224.389442) (xy 128.88722 -224.389442) (xy 128.886677 -224.417428) (xy 128.87722 -224.472596)
			(xy 128.868424 -224.49917) (xy 128.860804 -224.521268) (xy 129.064512 -224.874074) (xy 129.087372 -224.878392)
			(xy 129.112304 -224.883512) (xy 129.16029 -224.900483) (xy 129.205109 -224.924607) (xy 129.245702 -224.955314)
			(xy 129.281109 -224.991878) (xy 129.310496 -225.033436) (xy 129.333168 -225.079006) (xy 129.348589 -225.127512)
			(xy 129.356394 -225.177809) (xy 129.356866 -225.203258) (xy 129.356357 -225.229225) (xy 129.348232 -225.28052)
			(xy 129.332184 -225.329913) (xy 129.308606 -225.376187) (xy 129.27808 -225.418203) (xy 129.241357 -225.454926)
			(xy 129.199341 -225.485452) (xy 129.153067 -225.50903) (xy 129.103674 -225.525078) (xy 129.052379 -225.533203)
			(xy 129.000445 -225.533203) (xy 128.94915 -225.525078) (xy 128.899757 -225.50903) (xy 128.853483 -225.485452)
			(xy 128.811467 -225.454926) (xy 128.774744 -225.418203) (xy 128.744218 -225.376187) (xy 128.72064 -225.329913)
			(xy 128.704592 -225.28052) (xy 128.696467 -225.229225) (xy 128.695958 -225.203258) (xy 128.696497 -225.175271)
			(xy 128.705956 -225.120104) (xy 128.714754 -225.09353) (xy 128.722374 -225.071432) (xy 128.518666 -224.718626)
			(xy 128.495806 -224.714308) (xy 128.470886 -224.709131) (xy 128.4229 -224.692171) (xy 128.37808 -224.668057)
			(xy 128.337485 -224.637359) (xy 128.302075 -224.600802) (xy 128.272686 -224.55925) (xy 128.250012 -224.513684)
			(xy 128.23459 -224.465182) (xy 128.226784 -224.414889) (xy 128.226312 -224.389442) (xy 127.94742 -224.389442)
			(xy 127.946911 -224.415409) (xy 127.938786 -224.466704) (xy 127.922738 -224.516097) (xy 127.89916 -224.562371)
			(xy 127.868634 -224.604387) (xy 127.831911 -224.64111) (xy 127.789895 -224.671636) (xy 127.743621 -224.695214)
			(xy 127.694228 -224.711262) (xy 127.642933 -224.719387) (xy 127.590999 -224.719387) (xy 127.539704 -224.711262)
			(xy 127.490311 -224.695214) (xy 127.444037 -224.671636) (xy 127.402021 -224.64111) (xy 127.365298 -224.604387)
			(xy 127.334772 -224.562371) (xy 127.311194 -224.516097) (xy 127.295146 -224.466704) (xy 127.287021 -224.415409)
			(xy 127.286512 -224.389442) (xy 127.00762 -224.389442) (xy 127.007077 -224.417428) (xy 126.99762 -224.472596)
			(xy 126.988824 -224.49917) (xy 126.981204 -224.521268) (xy 127.184912 -224.874074) (xy 127.207772 -224.878392)
			(xy 127.232704 -224.883512) (xy 127.28069 -224.900483) (xy 127.325509 -224.924607) (xy 127.366102 -224.955314)
			(xy 127.401509 -224.991878) (xy 127.430896 -225.033436) (xy 127.453568 -225.079006) (xy 127.468989 -225.127512)
			(xy 127.476794 -225.177809) (xy 127.477266 -225.203258) (xy 127.476757 -225.229225) (xy 127.468632 -225.28052)
			(xy 127.452584 -225.329913) (xy 127.429006 -225.376187) (xy 127.39848 -225.418203) (xy 127.361757 -225.454926)
			(xy 127.319741 -225.485452) (xy 127.273467 -225.50903) (xy 127.224074 -225.525078) (xy 127.172779 -225.533203)
			(xy 127.120845 -225.533203) (xy 127.06955 -225.525078) (xy 127.020157 -225.50903) (xy 126.973883 -225.485452)
			(xy 126.931867 -225.454926) (xy 126.895144 -225.418203) (xy 126.864618 -225.376187) (xy 126.84104 -225.329913)
			(xy 126.824992 -225.28052) (xy 126.816867 -225.229225) (xy 126.816358 -225.203258) (xy 126.816897 -225.175271)
			(xy 126.826356 -225.120104) (xy 126.835154 -225.09353) (xy 126.842774 -225.071432) (xy 126.639066 -224.718626)
			(xy 126.616206 -224.714308) (xy 126.591286 -224.709131) (xy 126.5433 -224.692171) (xy 126.49848 -224.668057)
			(xy 126.457885 -224.637359) (xy 126.422475 -224.600802) (xy 126.393086 -224.55925) (xy 126.370412 -224.513684)
			(xy 126.35499 -224.465182) (xy 126.347184 -224.414889) (xy 126.346712 -224.389442) (xy 126.06782 -224.389442)
			(xy 126.067311 -224.415409) (xy 126.059186 -224.466704) (xy 126.043138 -224.516097) (xy 126.01956 -224.562371)
			(xy 125.989034 -224.604387) (xy 125.952311 -224.64111) (xy 125.910295 -224.671636) (xy 125.864021 -224.695214)
			(xy 125.814628 -224.711262) (xy 125.763333 -224.719387) (xy 125.711399 -224.719387) (xy 125.660104 -224.711262)
			(xy 125.610711 -224.695214) (xy 125.564437 -224.671636) (xy 125.522421 -224.64111) (xy 125.485698 -224.604387)
			(xy 125.455172 -224.562371) (xy 125.431594 -224.516097) (xy 125.415546 -224.466704) (xy 125.407421 -224.415409)
			(xy 125.406912 -224.389442) (xy 125.12802 -224.389442) (xy 125.127477 -224.417428) (xy 125.11802 -224.472596)
			(xy 125.109224 -224.49917) (xy 125.101604 -224.521268) (xy 125.305312 -224.874074) (xy 125.328172 -224.878392)
			(xy 125.353104 -224.883512) (xy 125.40109 -224.900483) (xy 125.445909 -224.924607) (xy 125.486502 -224.955314)
			(xy 125.521909 -224.991878) (xy 125.551296 -225.033436) (xy 125.573968 -225.079006) (xy 125.589389 -225.127512)
			(xy 125.597194 -225.177809) (xy 125.597666 -225.203258) (xy 125.597157 -225.229225) (xy 125.877067 -225.229225)
			(xy 125.877067 -225.177291) (xy 125.885192 -225.125996) (xy 125.90124 -225.076603) (xy 125.924818 -225.030329)
			(xy 125.955344 -224.988313) (xy 125.992067 -224.95159) (xy 126.034083 -224.921064) (xy 126.080357 -224.897486)
			(xy 126.12975 -224.881438) (xy 126.181045 -224.873313) (xy 126.232979 -224.873313) (xy 126.284274 -224.881438)
			(xy 126.333667 -224.897486) (xy 126.379941 -224.921064) (xy 126.421957 -224.95159) (xy 126.45868 -224.988313)
			(xy 126.489206 -225.030329) (xy 126.512784 -225.076603) (xy 126.528832 -225.125996) (xy 126.536957 -225.177291)
			(xy 126.537466 -225.203258) (xy 126.536957 -225.229225) (xy 126.528832 -225.28052) (xy 126.512784 -225.329913)
			(xy 126.489206 -225.376187) (xy 126.45868 -225.418203) (xy 126.421957 -225.454926) (xy 126.379941 -225.485452)
			(xy 126.333667 -225.50903) (xy 126.284274 -225.525078) (xy 126.232979 -225.533203) (xy 126.181045 -225.533203)
			(xy 126.12975 -225.525078) (xy 126.080357 -225.50903) (xy 126.034083 -225.485452) (xy 125.992067 -225.454926)
			(xy 125.955344 -225.418203) (xy 125.924818 -225.376187) (xy 125.90124 -225.329913) (xy 125.885192 -225.28052)
			(xy 125.877067 -225.229225) (xy 125.597157 -225.229225) (xy 125.589032 -225.28052) (xy 125.572984 -225.329913)
			(xy 125.549406 -225.376187) (xy 125.51888 -225.418203) (xy 125.482157 -225.454926) (xy 125.440141 -225.485452)
			(xy 125.393867 -225.50903) (xy 125.344474 -225.525078) (xy 125.293179 -225.533203) (xy 125.241245 -225.533203)
			(xy 125.18995 -225.525078) (xy 125.140557 -225.50903) (xy 125.094283 -225.485452) (xy 125.052267 -225.454926)
			(xy 125.015544 -225.418203) (xy 124.985018 -225.376187) (xy 124.96144 -225.329913) (xy 124.945392 -225.28052)
			(xy 124.937267 -225.229225) (xy 124.936758 -225.203258) (xy 124.937297 -225.175271) (xy 124.946756 -225.120104)
			(xy 124.955554 -225.09353) (xy 124.963174 -225.071432) (xy 124.759466 -224.718626) (xy 124.736606 -224.714308)
			(xy 124.711686 -224.709131) (xy 124.6637 -224.692171) (xy 124.61888 -224.668057) (xy 124.578285 -224.637359)
			(xy 124.542875 -224.600802) (xy 124.513486 -224.55925) (xy 124.490812 -224.513684) (xy 124.47539 -224.465182)
			(xy 124.467584 -224.414889) (xy 124.467112 -224.389442) (xy 124.18822 -224.389442) (xy 124.187711 -224.415409)
			(xy 124.179586 -224.466704) (xy 124.163538 -224.516097) (xy 124.13996 -224.562371) (xy 124.109434 -224.604387)
			(xy 124.072711 -224.64111) (xy 124.030695 -224.671636) (xy 123.984421 -224.695214) (xy 123.935028 -224.711262)
			(xy 123.883733 -224.719387) (xy 123.831799 -224.719387) (xy 123.780504 -224.711262) (xy 123.731111 -224.695214)
			(xy 123.684837 -224.671636) (xy 123.642821 -224.64111) (xy 123.606098 -224.604387) (xy 123.575572 -224.562371)
			(xy 123.551994 -224.516097) (xy 123.535946 -224.466704) (xy 123.527821 -224.415409) (xy 123.527312 -224.389442)
			(xy 123.24842 -224.389442) (xy 123.247877 -224.417428) (xy 123.23842 -224.472596) (xy 123.229624 -224.49917)
			(xy 123.222004 -224.521268) (xy 123.425712 -224.874074) (xy 123.448572 -224.878392) (xy 123.473504 -224.883512)
			(xy 123.52149 -224.900483) (xy 123.566309 -224.924607) (xy 123.606902 -224.955314) (xy 123.642309 -224.991878)
			(xy 123.671696 -225.033436) (xy 123.694368 -225.079006) (xy 123.709789 -225.127512) (xy 123.717594 -225.177809)
			(xy 123.718066 -225.203258) (xy 123.717557 -225.229225) (xy 123.997467 -225.229225) (xy 123.997467 -225.177291)
			(xy 124.005592 -225.125996) (xy 124.02164 -225.076603) (xy 124.045218 -225.030329) (xy 124.075744 -224.988313)
			(xy 124.112467 -224.95159) (xy 124.154483 -224.921064) (xy 124.200757 -224.897486) (xy 124.25015 -224.881438)
			(xy 124.301445 -224.873313) (xy 124.353379 -224.873313) (xy 124.404674 -224.881438) (xy 124.454067 -224.897486)
			(xy 124.500341 -224.921064) (xy 124.542357 -224.95159) (xy 124.57908 -224.988313) (xy 124.609606 -225.030329)
			(xy 124.633184 -225.076603) (xy 124.649232 -225.125996) (xy 124.657357 -225.177291) (xy 124.657866 -225.203258)
			(xy 124.657357 -225.229225) (xy 124.649232 -225.28052) (xy 124.633184 -225.329913) (xy 124.609606 -225.376187)
			(xy 124.57908 -225.418203) (xy 124.542357 -225.454926) (xy 124.500341 -225.485452) (xy 124.454067 -225.50903)
			(xy 124.404674 -225.525078) (xy 124.353379 -225.533203) (xy 124.301445 -225.533203) (xy 124.25015 -225.525078)
			(xy 124.200757 -225.50903) (xy 124.154483 -225.485452) (xy 124.112467 -225.454926) (xy 124.075744 -225.418203)
			(xy 124.045218 -225.376187) (xy 124.02164 -225.329913) (xy 124.005592 -225.28052) (xy 123.997467 -225.229225)
			(xy 123.717557 -225.229225) (xy 123.709432 -225.28052) (xy 123.693384 -225.329913) (xy 123.669806 -225.376187)
			(xy 123.63928 -225.418203) (xy 123.602557 -225.454926) (xy 123.560541 -225.485452) (xy 123.514267 -225.50903)
			(xy 123.464874 -225.525078) (xy 123.413579 -225.533203) (xy 123.361645 -225.533203) (xy 123.31035 -225.525078)
			(xy 123.260957 -225.50903) (xy 123.214683 -225.485452) (xy 123.172667 -225.454926) (xy 123.135944 -225.418203)
			(xy 123.105418 -225.376187) (xy 123.08184 -225.329913) (xy 123.065792 -225.28052) (xy 123.057667 -225.229225)
			(xy 123.057158 -225.203258) (xy 123.057697 -225.175271) (xy 123.067156 -225.120104) (xy 123.075954 -225.09353)
			(xy 123.083574 -225.071432) (xy 122.879866 -224.718626) (xy 122.857006 -224.714308) (xy 122.832086 -224.709131)
			(xy 122.7841 -224.692171) (xy 122.73928 -224.668057) (xy 122.698685 -224.637359) (xy 122.663275 -224.600802)
			(xy 122.633886 -224.55925) (xy 122.611212 -224.513684) (xy 122.59579 -224.465182) (xy 122.587984 -224.414889)
			(xy 122.587512 -224.389442) (xy 122.30862 -224.389442) (xy 122.308111 -224.415409) (xy 122.299986 -224.466704)
			(xy 122.283938 -224.516097) (xy 122.26036 -224.562371) (xy 122.229834 -224.604387) (xy 122.193111 -224.64111)
			(xy 122.151095 -224.671636) (xy 122.104821 -224.695214) (xy 122.055428 -224.711262) (xy 122.004133 -224.719387)
			(xy 121.952199 -224.719387) (xy 121.900904 -224.711262) (xy 121.851511 -224.695214) (xy 121.805237 -224.671636)
			(xy 121.763221 -224.64111) (xy 121.726498 -224.604387) (xy 121.695972 -224.562371) (xy 121.672394 -224.516097)
			(xy 121.656346 -224.466704) (xy 121.648221 -224.415409) (xy 121.647712 -224.389442) (xy 121.36882 -224.389442)
			(xy 121.368212 -224.417423) (xy 121.35877 -224.472584) (xy 121.350024 -224.49917) (xy 121.342404 -224.521268)
			(xy 121.546112 -224.874074) (xy 121.568972 -224.878392) (xy 121.593901 -224.883543) (xy 121.641902 -224.900485)
			(xy 121.686736 -224.92459) (xy 121.727342 -224.955286) (xy 121.762759 -224.991848) (xy 121.792149 -225.033409)
			(xy 121.814816 -225.078987) (xy 121.830223 -225.127502) (xy 121.838007 -225.177806) (xy 121.838466 -225.203258)
			(xy 121.837957 -225.229225) (xy 122.117867 -225.229225) (xy 122.117867 -225.177291) (xy 122.125992 -225.125996)
			(xy 122.14204 -225.076603) (xy 122.165618 -225.030329) (xy 122.196144 -224.988313) (xy 122.232867 -224.95159)
			(xy 122.274883 -224.921064) (xy 122.321157 -224.897486) (xy 122.37055 -224.881438) (xy 122.421845 -224.873313)
			(xy 122.473779 -224.873313) (xy 122.525074 -224.881438) (xy 122.574467 -224.897486) (xy 122.620741 -224.921064)
			(xy 122.662757 -224.95159) (xy 122.69948 -224.988313) (xy 122.730006 -225.030329) (xy 122.753584 -225.076603)
			(xy 122.769632 -225.125996) (xy 122.777757 -225.177291) (xy 122.778266 -225.203258) (xy 122.777757 -225.229225)
			(xy 122.769632 -225.28052) (xy 122.753584 -225.329913) (xy 122.730006 -225.376187) (xy 122.69948 -225.418203)
			(xy 122.662757 -225.454926) (xy 122.620741 -225.485452) (xy 122.574467 -225.50903) (xy 122.525074 -225.525078)
			(xy 122.473779 -225.533203) (xy 122.421845 -225.533203) (xy 122.37055 -225.525078) (xy 122.321157 -225.50903)
			(xy 122.274883 -225.485452) (xy 122.232867 -225.454926) (xy 122.196144 -225.418203) (xy 122.165618 -225.376187)
			(xy 122.14204 -225.329913) (xy 122.125992 -225.28052) (xy 122.117867 -225.229225) (xy 121.837957 -225.229225)
			(xy 121.829832 -225.28052) (xy 121.813784 -225.329913) (xy 121.790206 -225.376187) (xy 121.75968 -225.418203)
			(xy 121.722957 -225.454926) (xy 121.680941 -225.485452) (xy 121.634667 -225.50903) (xy 121.585274 -225.525078)
			(xy 121.533979 -225.533203) (xy 121.482045 -225.533203) (xy 121.43075 -225.525078) (xy 121.381357 -225.50903)
			(xy 121.335083 -225.485452) (xy 121.293067 -225.454926) (xy 121.256344 -225.418203) (xy 121.225818 -225.376187)
			(xy 121.20224 -225.329913) (xy 121.186192 -225.28052) (xy 121.178067 -225.229225) (xy 121.177558 -225.203258)
			(xy 121.178167 -225.175277) (xy 121.187611 -225.120117) (xy 121.196354 -225.09353) (xy 121.203974 -225.071432)
			(xy 121.105422 -224.900744) (xy 121.100319 -224.892719) (xy 121.085454 -224.880877) (xy 121.067296 -224.875266)
			(xy 121.048342 -224.876654) (xy 121.031196 -224.884853) (xy 121.018216 -224.898734) (xy 121.011184 -224.91639)
			(xy 121.01068 -224.92589) (xy 121.01068 -225.561398) (xy 120.934734 -225.637344) (xy 120.987312 -225.689922)
			(xy 121.01068 -225.688144) (xy 121.038366 -225.686874) (xy 121.064335 -225.687354) (xy 121.115634 -225.695474)
			(xy 121.165031 -225.71152) (xy 121.211309 -225.735096) (xy 121.253329 -225.765621) (xy 121.290057 -225.802345)
			(xy 121.320587 -225.844362) (xy 121.344167 -225.890638) (xy 121.360218 -225.940033) (xy 121.368343 -225.991331)
			(xy 121.368343 -226.043269) (xy 121.368339 -226.043295) (xy 121.648221 -226.043295) (xy 121.648221 -225.991361)
			(xy 121.656346 -225.940066) (xy 121.672394 -225.890673) (xy 121.695972 -225.844399) (xy 121.726498 -225.802383)
			(xy 121.763221 -225.76566) (xy 121.805237 -225.735134) (xy 121.851511 -225.711556) (xy 121.900904 -225.695508)
			(xy 121.952199 -225.687383) (xy 122.004133 -225.687383) (xy 122.055428 -225.695508) (xy 122.104821 -225.711556)
			(xy 122.151095 -225.735134) (xy 122.193111 -225.76566) (xy 122.229834 -225.802383) (xy 122.26036 -225.844399)
			(xy 122.283938 -225.890673) (xy 122.299986 -225.940066) (xy 122.308111 -225.991361) (xy 122.30862 -226.017328)
			(xy 122.308111 -226.043295) (xy 122.588021 -226.043295) (xy 122.588021 -225.991361) (xy 122.596146 -225.940066)
			(xy 122.612194 -225.890673) (xy 122.635772 -225.844399) (xy 122.666298 -225.802383) (xy 122.703021 -225.76566)
			(xy 122.745037 -225.735134) (xy 122.791311 -225.711556) (xy 122.840704 -225.695508) (xy 122.891999 -225.687383)
			(xy 122.943933 -225.687383) (xy 122.995228 -225.695508) (xy 123.044621 -225.711556) (xy 123.090895 -225.735134)
			(xy 123.132911 -225.76566) (xy 123.169634 -225.802383) (xy 123.20016 -225.844399) (xy 123.223738 -225.890673)
			(xy 123.239786 -225.940066) (xy 123.247911 -225.991361) (xy 123.24842 -226.017328) (xy 123.247911 -226.043295)
			(xy 123.527821 -226.043295) (xy 123.527821 -225.991361) (xy 123.535946 -225.940066) (xy 123.551994 -225.890673)
			(xy 123.575572 -225.844399) (xy 123.606098 -225.802383) (xy 123.642821 -225.76566) (xy 123.684837 -225.735134)
			(xy 123.731111 -225.711556) (xy 123.780504 -225.695508) (xy 123.831799 -225.687383) (xy 123.883733 -225.687383)
			(xy 123.935028 -225.695508) (xy 123.984421 -225.711556) (xy 124.030695 -225.735134) (xy 124.072711 -225.76566)
			(xy 124.109434 -225.802383) (xy 124.13996 -225.844399) (xy 124.163538 -225.890673) (xy 124.179586 -225.940066)
			(xy 124.187711 -225.991361) (xy 124.18822 -226.017328) (xy 124.187711 -226.043295) (xy 124.467621 -226.043295)
			(xy 124.467621 -225.991361) (xy 124.475746 -225.940066) (xy 124.491794 -225.890673) (xy 124.515372 -225.844399)
			(xy 124.545898 -225.802383) (xy 124.582621 -225.76566) (xy 124.624637 -225.735134) (xy 124.670911 -225.711556)
			(xy 124.720304 -225.695508) (xy 124.771599 -225.687383) (xy 124.823533 -225.687383) (xy 124.874828 -225.695508)
			(xy 124.924221 -225.711556) (xy 124.970495 -225.735134) (xy 125.012511 -225.76566) (xy 125.049234 -225.802383)
			(xy 125.07976 -225.844399) (xy 125.103338 -225.890673) (xy 125.119386 -225.940066) (xy 125.127511 -225.991361)
			(xy 125.12802 -226.017328) (xy 125.127511 -226.043295) (xy 125.407421 -226.043295) (xy 125.407421 -225.991361)
			(xy 125.415546 -225.940066) (xy 125.431594 -225.890673) (xy 125.455172 -225.844399) (xy 125.485698 -225.802383)
			(xy 125.522421 -225.76566) (xy 125.564437 -225.735134) (xy 125.610711 -225.711556) (xy 125.660104 -225.695508)
			(xy 125.711399 -225.687383) (xy 125.763333 -225.687383) (xy 125.814628 -225.695508) (xy 125.864021 -225.711556)
			(xy 125.910295 -225.735134) (xy 125.952311 -225.76566) (xy 125.989034 -225.802383) (xy 126.01956 -225.844399)
			(xy 126.043138 -225.890673) (xy 126.059186 -225.940066) (xy 126.067311 -225.991361) (xy 126.06782 -226.017328)
			(xy 126.067311 -226.043295) (xy 126.347221 -226.043295) (xy 126.347221 -225.991361) (xy 126.355346 -225.940066)
			(xy 126.371394 -225.890673) (xy 126.394972 -225.844399) (xy 126.425498 -225.802383) (xy 126.462221 -225.76566)
			(xy 126.504237 -225.735134) (xy 126.550511 -225.711556) (xy 126.599904 -225.695508) (xy 126.651199 -225.687383)
			(xy 126.703133 -225.687383) (xy 126.754428 -225.695508) (xy 126.803821 -225.711556) (xy 126.850095 -225.735134)
			(xy 126.892111 -225.76566) (xy 126.928834 -225.802383) (xy 126.95936 -225.844399) (xy 126.982938 -225.890673)
			(xy 126.998986 -225.940066) (xy 127.007111 -225.991361) (xy 127.00762 -226.017328) (xy 127.007111 -226.043295)
			(xy 127.287021 -226.043295) (xy 127.287021 -225.991361) (xy 127.295146 -225.940066) (xy 127.311194 -225.890673)
			(xy 127.334772 -225.844399) (xy 127.365298 -225.802383) (xy 127.402021 -225.76566) (xy 127.444037 -225.735134)
			(xy 127.490311 -225.711556) (xy 127.539704 -225.695508) (xy 127.590999 -225.687383) (xy 127.642933 -225.687383)
			(xy 127.694228 -225.695508) (xy 127.743621 -225.711556) (xy 127.789895 -225.735134) (xy 127.831911 -225.76566)
			(xy 127.868634 -225.802383) (xy 127.89916 -225.844399) (xy 127.922738 -225.890673) (xy 127.938786 -225.940066)
			(xy 127.946911 -225.991361) (xy 127.94742 -226.017328) (xy 127.946911 -226.043295) (xy 128.226821 -226.043295)
			(xy 128.226821 -225.991361) (xy 128.234946 -225.940066) (xy 128.250994 -225.890673) (xy 128.274572 -225.844399)
			(xy 128.305098 -225.802383) (xy 128.341821 -225.76566) (xy 128.383837 -225.735134) (xy 128.430111 -225.711556)
			(xy 128.479504 -225.695508) (xy 128.530799 -225.687383) (xy 128.582733 -225.687383) (xy 128.634028 -225.695508)
			(xy 128.683421 -225.711556) (xy 128.729695 -225.735134) (xy 128.771711 -225.76566) (xy 128.808434 -225.802383)
			(xy 128.83896 -225.844399) (xy 128.862538 -225.890673) (xy 128.878586 -225.940066) (xy 128.886711 -225.991361)
			(xy 128.88722 -226.017328) (xy 128.886711 -226.043295) (xy 129.166621 -226.043295) (xy 129.166621 -225.991361)
			(xy 129.174746 -225.940066) (xy 129.190794 -225.890673) (xy 129.214372 -225.844399) (xy 129.244898 -225.802383)
			(xy 129.281621 -225.76566) (xy 129.323637 -225.735134) (xy 129.369911 -225.711556) (xy 129.419304 -225.695508)
			(xy 129.470599 -225.687383) (xy 129.522533 -225.687383) (xy 129.573828 -225.695508) (xy 129.623221 -225.711556)
			(xy 129.669495 -225.735134) (xy 129.711511 -225.76566) (xy 129.748234 -225.802383) (xy 129.77876 -225.844399)
			(xy 129.802338 -225.890673) (xy 129.818386 -225.940066) (xy 129.826511 -225.991361) (xy 129.82702 -226.017328)
			(xy 129.826511 -226.043295) (xy 130.106421 -226.043295) (xy 130.106421 -225.991361) (xy 130.114546 -225.940066)
			(xy 130.130594 -225.890673) (xy 130.154172 -225.844399) (xy 130.184698 -225.802383) (xy 130.221421 -225.76566)
			(xy 130.263437 -225.735134) (xy 130.309711 -225.711556) (xy 130.359104 -225.695508) (xy 130.410399 -225.687383)
			(xy 130.462333 -225.687383) (xy 130.513628 -225.695508) (xy 130.563021 -225.711556) (xy 130.609295 -225.735134)
			(xy 130.651311 -225.76566) (xy 130.688034 -225.802383) (xy 130.71856 -225.844399) (xy 130.742138 -225.890673)
			(xy 130.758186 -225.940066) (xy 130.766311 -225.991361) (xy 130.76682 -226.017328) (xy 130.766311 -226.043295)
			(xy 131.046221 -226.043295) (xy 131.046221 -225.991361) (xy 131.054346 -225.940066) (xy 131.070394 -225.890673)
			(xy 131.093972 -225.844399) (xy 131.124498 -225.802383) (xy 131.161221 -225.76566) (xy 131.203237 -225.735134)
			(xy 131.249511 -225.711556) (xy 131.298904 -225.695508) (xy 131.350199 -225.687383) (xy 131.402133 -225.687383)
			(xy 131.453428 -225.695508) (xy 131.502821 -225.711556) (xy 131.549095 -225.735134) (xy 131.591111 -225.76566)
			(xy 131.627834 -225.802383) (xy 131.65836 -225.844399) (xy 131.681938 -225.890673) (xy 131.697986 -225.940066)
			(xy 131.706111 -225.991361) (xy 131.70662 -226.017328) (xy 131.706111 -226.043295) (xy 131.986021 -226.043295)
			(xy 131.986021 -225.991361) (xy 131.994146 -225.940066) (xy 132.010194 -225.890673) (xy 132.033772 -225.844399)
			(xy 132.064298 -225.802383) (xy 132.101021 -225.76566) (xy 132.143037 -225.735134) (xy 132.189311 -225.711556)
			(xy 132.238704 -225.695508) (xy 132.289999 -225.687383) (xy 132.341933 -225.687383) (xy 132.393228 -225.695508)
			(xy 132.442621 -225.711556) (xy 132.488895 -225.735134) (xy 132.530911 -225.76566) (xy 132.567634 -225.802383)
			(xy 132.59816 -225.844399) (xy 132.621738 -225.890673) (xy 132.637786 -225.940066) (xy 132.645911 -225.991361)
			(xy 132.64642 -226.017328) (xy 132.645911 -226.043295) (xy 132.925821 -226.043295) (xy 132.925821 -225.991361)
			(xy 132.933946 -225.940066) (xy 132.949994 -225.890673) (xy 132.973572 -225.844399) (xy 133.004098 -225.802383)
			(xy 133.040821 -225.76566) (xy 133.082837 -225.735134) (xy 133.129111 -225.711556) (xy 133.178504 -225.695508)
			(xy 133.229799 -225.687383) (xy 133.281733 -225.687383) (xy 133.333028 -225.695508) (xy 133.382421 -225.711556)
			(xy 133.428695 -225.735134) (xy 133.470711 -225.76566) (xy 133.507434 -225.802383) (xy 133.53796 -225.844399)
			(xy 133.561538 -225.890673) (xy 133.577586 -225.940066) (xy 133.585711 -225.991361) (xy 133.58622 -226.017328)
			(xy 133.585711 -226.043295) (xy 133.865621 -226.043295) (xy 133.865621 -225.991361) (xy 133.873746 -225.940066)
			(xy 133.889794 -225.890673) (xy 133.913372 -225.844399) (xy 133.943898 -225.802383) (xy 133.980621 -225.76566)
			(xy 134.022637 -225.735134) (xy 134.068911 -225.711556) (xy 134.118304 -225.695508) (xy 134.169599 -225.687383)
			(xy 134.221533 -225.687383) (xy 134.272828 -225.695508) (xy 134.322221 -225.711556) (xy 134.368495 -225.735134)
			(xy 134.410511 -225.76566) (xy 134.447234 -225.802383) (xy 134.47776 -225.844399) (xy 134.501338 -225.890673)
			(xy 134.517386 -225.940066) (xy 134.525511 -225.991361) (xy 134.52602 -226.017328) (xy 134.525511 -226.043295)
			(xy 134.805421 -226.043295) (xy 134.805421 -225.991361) (xy 134.813546 -225.940066) (xy 134.829594 -225.890673)
			(xy 134.853172 -225.844399) (xy 134.883698 -225.802383) (xy 134.920421 -225.76566) (xy 134.962437 -225.735134)
			(xy 135.008711 -225.711556) (xy 135.058104 -225.695508) (xy 135.109399 -225.687383) (xy 135.161333 -225.687383)
			(xy 135.212628 -225.695508) (xy 135.262021 -225.711556) (xy 135.308295 -225.735134) (xy 135.350311 -225.76566)
			(xy 135.387034 -225.802383) (xy 135.41756 -225.844399) (xy 135.441138 -225.890673) (xy 135.457186 -225.940066)
			(xy 135.465311 -225.991361) (xy 135.46582 -226.017328) (xy 135.465311 -226.043295) (xy 135.745221 -226.043295)
			(xy 135.745221 -225.991361) (xy 135.753346 -225.940066) (xy 135.769394 -225.890673) (xy 135.792972 -225.844399)
			(xy 135.823498 -225.802383) (xy 135.860221 -225.76566) (xy 135.902237 -225.735134) (xy 135.948511 -225.711556)
			(xy 135.997904 -225.695508) (xy 136.049199 -225.687383) (xy 136.101133 -225.687383) (xy 136.152428 -225.695508)
			(xy 136.201821 -225.711556) (xy 136.248095 -225.735134) (xy 136.290111 -225.76566) (xy 136.326834 -225.802383)
			(xy 136.35736 -225.844399) (xy 136.380938 -225.890673) (xy 136.396986 -225.940066) (xy 136.405111 -225.991361)
			(xy 136.40562 -226.017328) (xy 136.405111 -226.043295) (xy 136.396986 -226.09459) (xy 136.380938 -226.143983)
			(xy 136.35736 -226.190257) (xy 136.326834 -226.232273) (xy 136.290111 -226.268996) (xy 136.248095 -226.299522)
			(xy 136.201821 -226.3231) (xy 136.152428 -226.339148) (xy 136.101133 -226.347273) (xy 136.049199 -226.347273)
			(xy 135.997904 -226.339148) (xy 135.948511 -226.3231) (xy 135.902237 -226.299522) (xy 135.860221 -226.268996)
			(xy 135.823498 -226.232273) (xy 135.792972 -226.190257) (xy 135.769394 -226.143983) (xy 135.753346 -226.09459)
			(xy 135.745221 -226.043295) (xy 135.465311 -226.043295) (xy 135.457186 -226.09459) (xy 135.441138 -226.143983)
			(xy 135.41756 -226.190257) (xy 135.387034 -226.232273) (xy 135.350311 -226.268996) (xy 135.308295 -226.299522)
			(xy 135.262021 -226.3231) (xy 135.212628 -226.339148) (xy 135.161333 -226.347273) (xy 135.109399 -226.347273)
			(xy 135.058104 -226.339148) (xy 135.008711 -226.3231) (xy 134.962437 -226.299522) (xy 134.920421 -226.268996)
			(xy 134.883698 -226.232273) (xy 134.853172 -226.190257) (xy 134.829594 -226.143983) (xy 134.813546 -226.09459)
			(xy 134.805421 -226.043295) (xy 134.525511 -226.043295) (xy 134.517386 -226.09459) (xy 134.501338 -226.143983)
			(xy 134.47776 -226.190257) (xy 134.447234 -226.232273) (xy 134.410511 -226.268996) (xy 134.368495 -226.299522)
			(xy 134.322221 -226.3231) (xy 134.272828 -226.339148) (xy 134.221533 -226.347273) (xy 134.169599 -226.347273)
			(xy 134.118304 -226.339148) (xy 134.068911 -226.3231) (xy 134.022637 -226.299522) (xy 133.980621 -226.268996)
			(xy 133.943898 -226.232273) (xy 133.913372 -226.190257) (xy 133.889794 -226.143983) (xy 133.873746 -226.09459)
			(xy 133.865621 -226.043295) (xy 133.585711 -226.043295) (xy 133.577586 -226.09459) (xy 133.561538 -226.143983)
			(xy 133.53796 -226.190257) (xy 133.507434 -226.232273) (xy 133.470711 -226.268996) (xy 133.428695 -226.299522)
			(xy 133.382421 -226.3231) (xy 133.333028 -226.339148) (xy 133.281733 -226.347273) (xy 133.229799 -226.347273)
			(xy 133.178504 -226.339148) (xy 133.129111 -226.3231) (xy 133.082837 -226.299522) (xy 133.040821 -226.268996)
			(xy 133.004098 -226.232273) (xy 132.973572 -226.190257) (xy 132.949994 -226.143983) (xy 132.933946 -226.09459)
			(xy 132.925821 -226.043295) (xy 132.645911 -226.043295) (xy 132.637786 -226.09459) (xy 132.621738 -226.143983)
			(xy 132.59816 -226.190257) (xy 132.567634 -226.232273) (xy 132.530911 -226.268996) (xy 132.488895 -226.299522)
			(xy 132.442621 -226.3231) (xy 132.393228 -226.339148) (xy 132.341933 -226.347273) (xy 132.289999 -226.347273)
			(xy 132.238704 -226.339148) (xy 132.189311 -226.3231) (xy 132.143037 -226.299522) (xy 132.101021 -226.268996)
			(xy 132.064298 -226.232273) (xy 132.033772 -226.190257) (xy 132.010194 -226.143983) (xy 131.994146 -226.09459)
			(xy 131.986021 -226.043295) (xy 131.706111 -226.043295) (xy 131.697986 -226.09459) (xy 131.681938 -226.143983)
			(xy 131.65836 -226.190257) (xy 131.627834 -226.232273) (xy 131.591111 -226.268996) (xy 131.549095 -226.299522)
			(xy 131.502821 -226.3231) (xy 131.453428 -226.339148) (xy 131.402133 -226.347273) (xy 131.350199 -226.347273)
			(xy 131.298904 -226.339148) (xy 131.249511 -226.3231) (xy 131.203237 -226.299522) (xy 131.161221 -226.268996)
			(xy 131.124498 -226.232273) (xy 131.093972 -226.190257) (xy 131.070394 -226.143983) (xy 131.054346 -226.09459)
			(xy 131.046221 -226.043295) (xy 130.766311 -226.043295) (xy 130.758186 -226.09459) (xy 130.742138 -226.143983)
			(xy 130.71856 -226.190257) (xy 130.688034 -226.232273) (xy 130.651311 -226.268996) (xy 130.609295 -226.299522)
			(xy 130.563021 -226.3231) (xy 130.513628 -226.339148) (xy 130.462333 -226.347273) (xy 130.410399 -226.347273)
			(xy 130.359104 -226.339148) (xy 130.309711 -226.3231) (xy 130.263437 -226.299522) (xy 130.221421 -226.268996)
			(xy 130.184698 -226.232273) (xy 130.154172 -226.190257) (xy 130.130594 -226.143983) (xy 130.114546 -226.09459)
			(xy 130.106421 -226.043295) (xy 129.826511 -226.043295) (xy 129.818386 -226.09459) (xy 129.802338 -226.143983)
			(xy 129.77876 -226.190257) (xy 129.748234 -226.232273) (xy 129.711511 -226.268996) (xy 129.669495 -226.299522)
			(xy 129.623221 -226.3231) (xy 129.573828 -226.339148) (xy 129.522533 -226.347273) (xy 129.470599 -226.347273)
			(xy 129.419304 -226.339148) (xy 129.369911 -226.3231) (xy 129.323637 -226.299522) (xy 129.281621 -226.268996)
			(xy 129.244898 -226.232273) (xy 129.214372 -226.190257) (xy 129.190794 -226.143983) (xy 129.174746 -226.09459)
			(xy 129.166621 -226.043295) (xy 128.886711 -226.043295) (xy 128.878586 -226.09459) (xy 128.862538 -226.143983)
			(xy 128.83896 -226.190257) (xy 128.808434 -226.232273) (xy 128.771711 -226.268996) (xy 128.729695 -226.299522)
			(xy 128.683421 -226.3231) (xy 128.634028 -226.339148) (xy 128.582733 -226.347273) (xy 128.530799 -226.347273)
			(xy 128.479504 -226.339148) (xy 128.430111 -226.3231) (xy 128.383837 -226.299522) (xy 128.341821 -226.268996)
			(xy 128.305098 -226.232273) (xy 128.274572 -226.190257) (xy 128.250994 -226.143983) (xy 128.234946 -226.09459)
			(xy 128.226821 -226.043295) (xy 127.946911 -226.043295) (xy 127.938786 -226.09459) (xy 127.922738 -226.143983)
			(xy 127.89916 -226.190257) (xy 127.868634 -226.232273) (xy 127.831911 -226.268996) (xy 127.789895 -226.299522)
			(xy 127.743621 -226.3231) (xy 127.694228 -226.339148) (xy 127.642933 -226.347273) (xy 127.590999 -226.347273)
			(xy 127.539704 -226.339148) (xy 127.490311 -226.3231) (xy 127.444037 -226.299522) (xy 127.402021 -226.268996)
			(xy 127.365298 -226.232273) (xy 127.334772 -226.190257) (xy 127.311194 -226.143983) (xy 127.295146 -226.09459)
			(xy 127.287021 -226.043295) (xy 127.007111 -226.043295) (xy 126.998986 -226.09459) (xy 126.982938 -226.143983)
			(xy 126.95936 -226.190257) (xy 126.928834 -226.232273) (xy 126.892111 -226.268996) (xy 126.850095 -226.299522)
			(xy 126.803821 -226.3231) (xy 126.754428 -226.339148) (xy 126.703133 -226.347273) (xy 126.651199 -226.347273)
			(xy 126.599904 -226.339148) (xy 126.550511 -226.3231) (xy 126.504237 -226.299522) (xy 126.462221 -226.268996)
			(xy 126.425498 -226.232273) (xy 126.394972 -226.190257) (xy 126.371394 -226.143983) (xy 126.355346 -226.09459)
			(xy 126.347221 -226.043295) (xy 126.067311 -226.043295) (xy 126.059186 -226.09459) (xy 126.043138 -226.143983)
			(xy 126.01956 -226.190257) (xy 125.989034 -226.232273) (xy 125.952311 -226.268996) (xy 125.910295 -226.299522)
			(xy 125.864021 -226.3231) (xy 125.814628 -226.339148) (xy 125.763333 -226.347273) (xy 125.711399 -226.347273)
			(xy 125.660104 -226.339148) (xy 125.610711 -226.3231) (xy 125.564437 -226.299522) (xy 125.522421 -226.268996)
			(xy 125.485698 -226.232273) (xy 125.455172 -226.190257) (xy 125.431594 -226.143983) (xy 125.415546 -226.09459)
			(xy 125.407421 -226.043295) (xy 125.127511 -226.043295) (xy 125.119386 -226.09459) (xy 125.103338 -226.143983)
			(xy 125.07976 -226.190257) (xy 125.049234 -226.232273) (xy 125.012511 -226.268996) (xy 124.970495 -226.299522)
			(xy 124.924221 -226.3231) (xy 124.874828 -226.339148) (xy 124.823533 -226.347273) (xy 124.771599 -226.347273)
			(xy 124.720304 -226.339148) (xy 124.670911 -226.3231) (xy 124.624637 -226.299522) (xy 124.582621 -226.268996)
			(xy 124.545898 -226.232273) (xy 124.515372 -226.190257) (xy 124.491794 -226.143983) (xy 124.475746 -226.09459)
			(xy 124.467621 -226.043295) (xy 124.187711 -226.043295) (xy 124.179586 -226.09459) (xy 124.163538 -226.143983)
			(xy 124.13996 -226.190257) (xy 124.109434 -226.232273) (xy 124.072711 -226.268996) (xy 124.030695 -226.299522)
			(xy 123.984421 -226.3231) (xy 123.935028 -226.339148) (xy 123.883733 -226.347273) (xy 123.831799 -226.347273)
			(xy 123.780504 -226.339148) (xy 123.731111 -226.3231) (xy 123.684837 -226.299522) (xy 123.642821 -226.268996)
			(xy 123.606098 -226.232273) (xy 123.575572 -226.190257) (xy 123.551994 -226.143983) (xy 123.535946 -226.09459)
			(xy 123.527821 -226.043295) (xy 123.247911 -226.043295) (xy 123.239786 -226.09459) (xy 123.223738 -226.143983)
			(xy 123.20016 -226.190257) (xy 123.169634 -226.232273) (xy 123.132911 -226.268996) (xy 123.090895 -226.299522)
			(xy 123.044621 -226.3231) (xy 122.995228 -226.339148) (xy 122.943933 -226.347273) (xy 122.891999 -226.347273)
			(xy 122.840704 -226.339148) (xy 122.791311 -226.3231) (xy 122.745037 -226.299522) (xy 122.703021 -226.268996)
			(xy 122.666298 -226.232273) (xy 122.635772 -226.190257) (xy 122.612194 -226.143983) (xy 122.596146 -226.09459)
			(xy 122.588021 -226.043295) (xy 122.308111 -226.043295) (xy 122.299986 -226.09459) (xy 122.283938 -226.143983)
			(xy 122.26036 -226.190257) (xy 122.229834 -226.232273) (xy 122.193111 -226.268996) (xy 122.151095 -226.299522)
			(xy 122.104821 -226.3231) (xy 122.055428 -226.339148) (xy 122.004133 -226.347273) (xy 121.952199 -226.347273)
			(xy 121.900904 -226.339148) (xy 121.851511 -226.3231) (xy 121.805237 -226.299522) (xy 121.763221 -226.268996)
			(xy 121.726498 -226.232273) (xy 121.695972 -226.190257) (xy 121.672394 -226.143983) (xy 121.656346 -226.09459)
			(xy 121.648221 -226.043295) (xy 121.368339 -226.043295) (xy 121.360218 -226.094567) (xy 121.344167 -226.143962)
			(xy 121.320587 -226.190238) (xy 121.290057 -226.232255) (xy 121.253329 -226.268979) (xy 121.211309 -226.299504)
			(xy 121.165031 -226.32308) (xy 121.115634 -226.339126) (xy 121.064335 -226.347246) (xy 121.038366 -226.347782)
			(xy 121.013108 -226.347308) (xy 120.963179 -226.339627) (xy 120.915001 -226.324436) (xy 120.869698 -226.302087)
			(xy 120.828324 -226.273103) (xy 120.791846 -226.238158) (xy 120.761112 -226.198066) (xy 120.736839 -226.153764)
			(xy 120.719594 -226.106283) (xy 120.714262 -226.08159) (xy 120.711156 -226.068195) (xy 120.698834 -226.043627)
			(xy 120.680407 -226.023232) (xy 120.657211 -226.008488) (xy 120.630924 -226.00046) (xy 120.603448 -225.999731)
			(xy 120.576772 -226.006353) (xy 120.552826 -226.019846) (xy 120.542812 -226.029266) (xy 120.443498 -226.12858)
			(xy 120.39854 -226.157282) (xy 120.39219 -226.169474) (xy 120.379867 -226.192177) (xy 120.349264 -226.233788)
			(xy 120.312564 -226.270136) (xy 120.27066 -226.300338) (xy 120.224571 -226.323659) (xy 120.175417 -226.339532)
			(xy 120.124393 -226.347571) (xy 120.098566 -226.348036) (xy 120.074011 -226.347585) (xy 120.025443 -226.340316)
			(xy 119.978484 -226.325943) (xy 119.934167 -226.304783) (xy 119.893468 -226.2773) (xy 119.857282 -226.244099)
			(xy 119.826404 -226.205911) (xy 119.813578 -226.184968) (xy 119.80926 -226.178364) (xy 119.76608 -226.152964)
			(xy 119.761762 -226.153218) (xy 119.748554 -226.154996) (xy 119.718645 -226.158551) (xy 119.65853 -226.162366)
			(xy 119.628412 -226.162616) (xy 119.598357 -226.16236) (xy 119.538369 -226.15855) (xy 119.508524 -226.154996)
			(xy 119.4943 -226.153218) (xy 119.490744 -226.152964) (xy 119.447818 -226.178364) (xy 119.443754 -226.184968)
			(xy 119.430932 -226.205916) (xy 119.400066 -226.244118) (xy 119.363885 -226.27733) (xy 119.323185 -226.304818)
			(xy 119.278863 -226.325978) (xy 119.231898 -226.340342) (xy 119.183323 -226.347594) (xy 119.158766 -226.348036)
			(xy 119.132943 -226.347536) (xy 119.081924 -226.3395) (xy 119.032776 -226.323629) (xy 118.986694 -226.300309)
			(xy 118.944797 -226.270108) (xy 118.908107 -226.233759) (xy 118.877514 -226.192148) (xy 118.865142 -226.169474)
			(xy 118.858792 -226.157282) (xy 118.814088 -226.12858) (xy 118.563644 -226.12858) (xy 118.51894 -226.157282)
			(xy 118.51259 -226.169474) (xy 118.500267 -226.192177) (xy 118.469664 -226.233788) (xy 118.432964 -226.270136)
			(xy 118.39106 -226.300338) (xy 118.344971 -226.323659) (xy 118.295817 -226.339532) (xy 118.244793 -226.347571)
			(xy 118.218966 -226.348036) (xy 118.194411 -226.347585) (xy 118.145843 -226.340316) (xy 118.098884 -226.325943)
			(xy 118.054567 -226.304783) (xy 118.013868 -226.2773) (xy 117.977682 -226.244099) (xy 117.946804 -226.205911)
			(xy 117.933978 -226.184968) (xy 117.92966 -226.178364) (xy 117.88648 -226.152964) (xy 117.882162 -226.153218)
			(xy 117.868954 -226.154996) (xy 117.839045 -226.158551) (xy 117.77893 -226.162366) (xy 117.748812 -226.162616)
			(xy 117.718757 -226.16236) (xy 117.658769 -226.15855) (xy 117.628924 -226.154996) (xy 117.6147 -226.153218)
			(xy 117.611144 -226.152964) (xy 117.568218 -226.178364) (xy 117.564154 -226.184968) (xy 117.551332 -226.205916)
			(xy 117.520466 -226.244118) (xy 117.484285 -226.27733) (xy 117.443585 -226.304818) (xy 117.399263 -226.325978)
			(xy 117.352298 -226.340342) (xy 117.303723 -226.347594) (xy 117.279166 -226.348036) (xy 117.253343 -226.347536)
			(xy 117.202324 -226.3395) (xy 117.153176 -226.323629) (xy 117.107094 -226.300309) (xy 117.065197 -226.270108)
			(xy 117.028507 -226.233759) (xy 116.997914 -226.192148) (xy 116.985542 -226.169474) (xy 116.979192 -226.157282)
			(xy 116.934488 -226.12858) (xy 116.684044 -226.12858) (xy 116.63934 -226.157282) (xy 116.63299 -226.169474)
			(xy 116.620667 -226.192177) (xy 116.590064 -226.233788) (xy 116.553364 -226.270136) (xy 116.51146 -226.300338)
			(xy 116.465371 -226.323659) (xy 116.416217 -226.339532) (xy 116.365193 -226.347571) (xy 116.339366 -226.348036)
			(xy 116.314811 -226.347585) (xy 116.266243 -226.340316) (xy 116.219284 -226.325943) (xy 116.174967 -226.304783)
			(xy 116.134268 -226.2773) (xy 116.098082 -226.244099) (xy 116.067204 -226.205911) (xy 116.054378 -226.184968)
			(xy 116.05006 -226.178364) (xy 116.00688 -226.152964) (xy 116.002562 -226.153218) (xy 115.989354 -226.154996)
			(xy 115.959445 -226.158551) (xy 115.89933 -226.162366) (xy 115.869212 -226.162616) (xy 115.839157 -226.16236)
			(xy 115.779169 -226.15855) (xy 115.749324 -226.154996) (xy 115.7351 -226.153218) (xy 115.731544 -226.152964)
			(xy 115.688618 -226.178364) (xy 115.684554 -226.184968) (xy 115.671732 -226.205916) (xy 115.640866 -226.244118)
			(xy 115.604685 -226.27733) (xy 115.563985 -226.304818) (xy 115.519663 -226.325978) (xy 115.472698 -226.340342)
			(xy 115.424123 -226.347594) (xy 115.399566 -226.348036) (xy 115.373743 -226.347536) (xy 115.322724 -226.3395)
			(xy 115.273576 -226.323629) (xy 115.227494 -226.300309) (xy 115.185597 -226.270108) (xy 115.148907 -226.233759)
			(xy 115.118314 -226.192148) (xy 115.105942 -226.169474) (xy 115.099592 -226.157282) (xy 115.054888 -226.12858)
			(xy 114.804444 -226.12858) (xy 114.75974 -226.157282) (xy 114.75339 -226.169474) (xy 114.741067 -226.192177)
			(xy 114.710464 -226.233788) (xy 114.673764 -226.270136) (xy 114.63186 -226.300338) (xy 114.585771 -226.323659)
			(xy 114.536617 -226.339532) (xy 114.485593 -226.347571) (xy 114.459766 -226.348036) (xy 114.435211 -226.347585)
			(xy 114.386643 -226.340316) (xy 114.339684 -226.325943) (xy 114.295367 -226.304783) (xy 114.254668 -226.2773)
			(xy 114.218482 -226.244099) (xy 114.187604 -226.205911) (xy 114.174778 -226.184968) (xy 114.17046 -226.178364)
			(xy 114.12728 -226.152964) (xy 114.122962 -226.153218) (xy 114.109754 -226.154996) (xy 114.079845 -226.158551)
			(xy 114.01973 -226.162366) (xy 113.989612 -226.162616) (xy 113.959557 -226.16236) (xy 113.899569 -226.15855)
			(xy 113.869724 -226.154996) (xy 113.8555 -226.153218) (xy 113.851944 -226.152964) (xy 113.809018 -226.178364)
			(xy 113.804954 -226.184968) (xy 113.792132 -226.205916) (xy 113.761266 -226.244118) (xy 113.725085 -226.27733)
			(xy 113.684385 -226.304818) (xy 113.640063 -226.325978) (xy 113.593098 -226.340342) (xy 113.544523 -226.347594)
			(xy 113.519966 -226.348036) (xy 113.494143 -226.347536) (xy 113.443124 -226.3395) (xy 113.393976 -226.323629)
			(xy 113.347894 -226.300309) (xy 113.305997 -226.270108) (xy 113.269307 -226.233759) (xy 113.238714 -226.192148)
			(xy 113.226342 -226.169474) (xy 113.219992 -226.157282) (xy 113.175288 -226.12858) (xy 112.924844 -226.12858)
			(xy 112.88014 -226.157282) (xy 112.87379 -226.169474) (xy 112.861467 -226.192177) (xy 112.830864 -226.233788)
			(xy 112.794164 -226.270136) (xy 112.75226 -226.300338) (xy 112.706171 -226.323659) (xy 112.657017 -226.339532)
			(xy 112.605993 -226.347571) (xy 112.580166 -226.348036) (xy 112.555611 -226.347585) (xy 112.507043 -226.340316)
			(xy 112.460084 -226.325943) (xy 112.415767 -226.304783) (xy 112.375068 -226.2773) (xy 112.338882 -226.244099)
			(xy 112.308004 -226.205911) (xy 112.295178 -226.184968) (xy 112.29086 -226.178364) (xy 112.24768 -226.152964)
			(xy 112.243362 -226.153218) (xy 112.230154 -226.154996) (xy 112.200245 -226.158551) (xy 112.14013 -226.162366)
			(xy 112.110012 -226.162616) (xy 112.079957 -226.16236) (xy 112.019969 -226.15855) (xy 111.990124 -226.154996)
			(xy 111.9759 -226.153218) (xy 111.972344 -226.152964) (xy 111.929418 -226.178364) (xy 111.925354 -226.184968)
			(xy 111.912532 -226.205916) (xy 111.881666 -226.244118) (xy 111.845485 -226.27733) (xy 111.804785 -226.304818)
			(xy 111.760463 -226.325978) (xy 111.713498 -226.340342) (xy 111.664923 -226.347594) (xy 111.640366 -226.348036)
			(xy 111.614543 -226.347536) (xy 111.563524 -226.3395) (xy 111.514376 -226.323629) (xy 111.468294 -226.300309)
			(xy 111.426397 -226.270108) (xy 111.389707 -226.233759) (xy 111.359114 -226.192148) (xy 111.346742 -226.169474)
			(xy 111.340392 -226.157282) (xy 111.295688 -226.12858) (xy 111.045244 -226.12858) (xy 111.00054 -226.157282)
			(xy 110.99419 -226.169474) (xy 110.981867 -226.192177) (xy 110.951264 -226.233788) (xy 110.914564 -226.270136)
			(xy 110.87266 -226.300338) (xy 110.826571 -226.323659) (xy 110.777417 -226.339532) (xy 110.726393 -226.347571)
			(xy 110.700566 -226.348036) (xy 110.676011 -226.347585) (xy 110.627443 -226.340316) (xy 110.580484 -226.325943)
			(xy 110.536167 -226.304783) (xy 110.495468 -226.2773) (xy 110.459282 -226.244099) (xy 110.428404 -226.205911)
			(xy 110.415578 -226.184968) (xy 110.41126 -226.178364) (xy 110.36808 -226.152964) (xy 110.363762 -226.153218)
			(xy 110.350554 -226.154996) (xy 110.320645 -226.158551) (xy 110.26053 -226.162366) (xy 110.230412 -226.162616)
			(xy 110.200357 -226.16236) (xy 110.140369 -226.15855) (xy 110.110524 -226.154996) (xy 110.0963 -226.153218)
			(xy 110.092744 -226.152964) (xy 110.049818 -226.178364) (xy 110.045754 -226.184968) (xy 110.032932 -226.205916)
			(xy 110.002066 -226.244118) (xy 109.965885 -226.27733) (xy 109.925185 -226.304818) (xy 109.880863 -226.325978)
			(xy 109.833898 -226.340342) (xy 109.785323 -226.347594) (xy 109.760766 -226.348036) (xy 109.734943 -226.347536)
			(xy 109.683924 -226.3395) (xy 109.634776 -226.323629) (xy 109.588694 -226.300309) (xy 109.546797 -226.270108)
			(xy 109.510107 -226.233759) (xy 109.479514 -226.192148) (xy 109.467142 -226.169474) (xy 109.460792 -226.157282)
			(xy 109.416088 -226.12858) (xy 109.165644 -226.12858) (xy 109.12094 -226.157282) (xy 109.11459 -226.169474)
			(xy 109.102267 -226.192177) (xy 109.071664 -226.233788) (xy 109.034964 -226.270136) (xy 108.99306 -226.300338)
			(xy 108.946971 -226.323659) (xy 108.897817 -226.339532) (xy 108.846793 -226.347571) (xy 108.820966 -226.348036)
			(xy 108.796411 -226.347585) (xy 108.747843 -226.340316) (xy 108.700884 -226.325943) (xy 108.656567 -226.304783)
			(xy 108.615868 -226.2773) (xy 108.579682 -226.244099) (xy 108.548804 -226.205911) (xy 108.535978 -226.184968)
			(xy 108.53166 -226.178364) (xy 108.48848 -226.152964) (xy 108.484162 -226.153218) (xy 108.470954 -226.154996)
			(xy 108.441045 -226.158551) (xy 108.38093 -226.162366) (xy 108.350812 -226.162616) (xy 108.320757 -226.16236)
			(xy 108.260769 -226.15855) (xy 108.230924 -226.154996) (xy 108.2167 -226.153218) (xy 108.213144 -226.152964)
			(xy 108.170218 -226.178364) (xy 108.166154 -226.184968) (xy 108.153332 -226.205916) (xy 108.122466 -226.244118)
			(xy 108.086285 -226.27733) (xy 108.045585 -226.304818) (xy 108.001263 -226.325978) (xy 107.954298 -226.340342)
			(xy 107.905723 -226.347594) (xy 107.881166 -226.348036) (xy 107.855343 -226.347536) (xy 107.804324 -226.3395)
			(xy 107.755176 -226.323629) (xy 107.709094 -226.300309) (xy 107.667197 -226.270108) (xy 107.630507 -226.233759)
			(xy 107.599914 -226.192148) (xy 107.587542 -226.169474) (xy 107.581192 -226.157282) (xy 107.536488 -226.12858)
			(xy 107.286044 -226.12858) (xy 107.24134 -226.157282) (xy 107.23499 -226.169474) (xy 107.222667 -226.192177)
			(xy 107.192064 -226.233788) (xy 107.155364 -226.270136) (xy 107.11346 -226.300338) (xy 107.067371 -226.323659)
			(xy 107.018217 -226.339532) (xy 106.967193 -226.347571) (xy 106.941366 -226.348036) (xy 106.916811 -226.347585)
			(xy 106.868243 -226.340316) (xy 106.821284 -226.325943) (xy 106.776967 -226.304783) (xy 106.736268 -226.2773)
			(xy 106.700082 -226.244099) (xy 106.669204 -226.205911) (xy 106.656378 -226.184968) (xy 106.65206 -226.178364)
			(xy 106.60888 -226.152964) (xy 106.604562 -226.153218) (xy 106.591354 -226.154996) (xy 106.561445 -226.158551)
			(xy 106.50133 -226.162366) (xy 106.471212 -226.162616) (xy 106.441157 -226.16236) (xy 106.381169 -226.15855)
			(xy 106.351324 -226.154996) (xy 106.3371 -226.153218) (xy 106.333544 -226.152964) (xy 106.290618 -226.178364)
			(xy 106.286554 -226.184968) (xy 106.273732 -226.205916) (xy 106.242866 -226.244118) (xy 106.206685 -226.27733)
			(xy 106.165985 -226.304818) (xy 106.121663 -226.325978) (xy 106.074698 -226.340342) (xy 106.026123 -226.347594)
			(xy 106.001566 -226.348036) (xy 105.976047 -226.347567) (xy 105.925612 -226.339734) (xy 105.876981 -226.324244)
			(xy 105.831308 -226.301465) (xy 105.789677 -226.271938) (xy 105.753078 -226.236364) (xy 105.722381 -226.195588)
			(xy 105.709974 -226.173284) (xy 105.706418 -226.16668) (xy 105.557574 -226.017836) (xy 105.55081 -226.01167)
			(xy 105.534106 -226.004225) (xy 105.515847 -226.003205) (xy 105.507028 -226.005644) (xy 105.421938 -226.032822)
			(xy 105.388156 -226.071684) (xy 105.385616 -226.084638) (xy 105.380052 -226.109129) (xy 105.362519 -226.156192)
			(xy 105.33807 -226.200061) (xy 105.307268 -226.239728) (xy 105.27082 -226.27428) (xy 105.229566 -226.302922)
			(xy 105.184455 -226.324996) (xy 105.136525 -226.339993) (xy 105.086877 -226.347568) (xy 105.061766 -226.348036)
			(xy 105.03578 -226.347524) (xy 104.984448 -226.339389) (xy 104.93502 -226.323326) (xy 104.888713 -226.299728)
			(xy 104.846667 -226.269179) (xy 104.809917 -226.232428) (xy 104.779368 -226.190382) (xy 104.755772 -226.144074)
			(xy 104.739709 -226.094646) (xy 104.731576 -226.043314) (xy 104.731058 -226.017328) (xy 104.731529 -225.992221)
			(xy 104.739128 -225.942585) (xy 104.754141 -225.894667) (xy 104.776223 -225.849568) (xy 104.804866 -225.808325)
			(xy 104.839413 -225.771883) (xy 104.879071 -225.741081) (xy 104.922927 -225.716625) (xy 104.969976 -225.699078)
			(xy 104.994456 -225.693478) (xy 105.00741 -225.690938) (xy 105.046272 -225.657156) (xy 105.07345 -225.572066)
			(xy 105.075854 -225.563236) (xy 105.074863 -225.544976) (xy 105.067443 -225.528263) (xy 105.061258 -225.52152)
			(xy 104.989884 -225.450146) (xy 104.98257 -225.443455) (xy 104.964231 -225.435973) (xy 104.954324 -225.435668)
			(xy 104.882696 -225.436176) (xy 104.84739 -225.451162) (xy 104.840786 -225.45802) (xy 104.820713 -225.476892)
			(xy 104.775833 -225.508845) (xy 104.72657 -225.533509) (xy 104.674097 -225.550298) (xy 104.619666 -225.558811)
			(xy 104.59212 -225.559366) (xy 104.591612 -225.559366) (xy 104.563627 -225.558846) (xy 104.508347 -225.550092)
			(xy 104.455116 -225.532796) (xy 104.405248 -225.507386) (xy 104.359968 -225.474487) (xy 104.320394 -225.434909)
			(xy 104.287498 -225.389627) (xy 104.262092 -225.339756) (xy 104.244801 -225.286524) (xy 104.236051 -225.231243)
			(xy 104.235504 -225.203258) (xy 104.235902 -225.179463) (xy 104.242239 -225.132296) (xy 104.254796 -225.086391)
			(xy 104.263698 -225.06432) (xy 104.27208 -225.044254) (xy 104.099614 -224.745804) (xy 104.074976 -224.742502)
			(xy 104.049631 -224.738682) (xy 104.000316 -224.724709) (xy 103.953515 -224.703809) (xy 103.910196 -224.676414)
			(xy 103.871252 -224.643089) (xy 103.837491 -224.604523) (xy 103.809608 -224.561515) (xy 103.788182 -224.514953)
			(xy 103.773655 -224.465799) (xy 103.766327 -224.41507) (xy 103.765858 -224.389442) (xy 103.765858 -224.38868)
			(xy 103.766396 -224.361373) (xy 103.774822 -224.307413) (xy 103.782622 -224.281238) (xy 103.784908 -224.265744)
			(xy 103.784393 -224.255994) (xy 103.776943 -224.237966) (xy 103.77043 -224.230692) (xy 103.693468 -224.15373)
			(xy 103.683724 -224.144651) (xy 103.660634 -224.131398) (xy 103.634902 -224.124567) (xy 103.608279 -224.124622)
			(xy 103.582576 -224.13156) (xy 103.559541 -224.144908) (xy 103.540741 -224.163759) (xy 103.533702 -224.175066)
			(xy 103.486204 -224.257616) (xy 103.493824 -224.279714) (xy 103.502613 -224.306289) (xy 103.512056 -224.361457)
			(xy 103.51262 -224.389442) (xy 103.512111 -224.415409) (xy 103.503986 -224.466704) (xy 103.487938 -224.516097)
			(xy 103.46436 -224.562371) (xy 103.433834 -224.604387) (xy 103.397111 -224.64111) (xy 103.355095 -224.671636)
			(xy 103.308821 -224.695214) (xy 103.259428 -224.711262) (xy 103.208133 -224.719387) (xy 103.156199 -224.719387)
			(xy 103.104904 -224.711262) (xy 103.055511 -224.695214) (xy 103.009237 -224.671636) (xy 102.967221 -224.64111)
			(xy 102.930498 -224.604387) (xy 102.899972 -224.562371) (xy 102.876394 -224.516097) (xy 102.860346 -224.466704)
			(xy 102.852221 -224.415409) (xy 102.851712 -224.389442) (xy 102.852185 -224.363995) (xy 102.859993 -224.313704)
			(xy 102.875417 -224.265204) (xy 102.898092 -224.219641) (xy 102.927481 -224.178091) (xy 102.962891 -224.141535)
			(xy 103.003486 -224.110839) (xy 103.048305 -224.086727) (xy 103.096289 -224.069768) (xy 103.121206 -224.064576)
			(xy 103.144066 -224.060258) (xy 103.310944 -223.771206) (xy 103.189024 -223.64954) (xy 103.189024 -223.095058)
			(xy 103.144066 -223.089724) (xy 103.11898 -223.086322) (xy 103.070177 -223.072874) (xy 103.023997 -223.052139)
			(xy 102.981521 -223.0246) (xy 102.943744 -222.990903) (xy 102.911551 -222.951837) (xy 102.885695 -222.908316)
			(xy 102.866782 -222.86136) (xy 102.855254 -222.812068) (xy 102.851381 -222.761595) (xy 102.855255 -222.711121)
			(xy 102.866785 -222.66183) (xy 102.885699 -222.614875) (xy 102.911557 -222.571355) (xy 102.943751 -222.53229)
			(xy 102.981529 -222.498594) (xy 103.024006 -222.471057) (xy 103.070187 -222.450322) (xy 103.11899 -222.436876)
			(xy 103.144066 -222.433388) (xy 103.189024 -222.428054) (xy 103.189024 -221.467426) (xy 103.144066 -221.462092)
			(xy 103.117576 -221.458497) (xy 103.066162 -221.443864) (xy 103.017773 -221.421147) (xy 102.973671 -221.390938)
			(xy 102.935005 -221.354026) (xy 102.902785 -221.311372) (xy 102.877849 -221.264088) (xy 102.860848 -221.213408)
			(xy 102.852225 -221.160652) (xy 102.851712 -221.133924) (xy 102.852186 -221.108478) (xy 102.859997 -221.058189)
			(xy 102.875422 -221.009691) (xy 102.898098 -220.96413) (xy 102.927488 -220.922582) (xy 102.962898 -220.886029)
			(xy 103.003492 -220.855335) (xy 103.04831 -220.831224) (xy 103.096293 -220.814267) (xy 103.121206 -220.809058)
			(xy 103.144066 -220.80474) (xy 103.189024 -220.727016) (xy 103.189024 -219.83954) (xy 103.144066 -219.834206)
			(xy 103.118974 -219.830803) (xy 103.070158 -219.817354) (xy 103.023966 -219.796615) (xy 102.981479 -219.76907)
			(xy 102.943692 -219.735366) (xy 102.91149 -219.696291) (xy 102.885626 -219.652761) (xy 102.866707 -219.605794)
			(xy 102.855175 -219.55649) (xy 102.8513 -219.506004) (xy 102.855173 -219.455518) (xy 102.866704 -219.406215)
			(xy 102.885622 -219.359247) (xy 102.911485 -219.315716) (xy 102.943686 -219.27664) (xy 102.981472 -219.242935)
			(xy 103.023959 -219.21539) (xy 103.07015 -219.194649) (xy 103.118965 -219.181198) (xy 103.144066 -219.17787)
			(xy 103.189024 -219.172536) (xy 103.189024 -218.998292) (xy 103.102664 -218.911932) (xy 103.092663 -218.90255)
			(xy 103.06883 -218.889011) (xy 103.042252 -218.882304) (xy 103.014849 -218.882914) (xy 102.988596 -218.890796)
			(xy 102.965388 -218.905383) (xy 102.955852 -218.915234) (xy 102.93693 -218.935119) (xy 102.893703 -218.968944)
			(xy 102.845481 -218.995162) (xy 102.79359 -219.013053) (xy 102.739456 -219.022123) (xy 102.712012 -219.022676)
			(xy 102.686044 -219.022168) (xy 102.634746 -219.014045) (xy 102.58535 -218.997998) (xy 102.539073 -218.974421)
			(xy 102.497054 -218.943895) (xy 102.460327 -218.907172) (xy 102.429797 -218.865156) (xy 102.406215 -218.818881)
			(xy 102.390163 -218.769487) (xy 102.382035 -218.71819) (xy 102.381558 -218.692222) (xy 102.38217 -218.664242)
			(xy 102.391619 -218.609083) (xy 102.400354 -218.582494) (xy 102.407974 -218.560396) (xy 102.204266 -218.20759)
			(xy 102.181406 -218.203272) (xy 102.157253 -218.198279) (xy 102.110668 -218.182086) (xy 102.067007 -218.159149)
			(xy 102.02724 -218.129977) (xy 101.992251 -218.095219) (xy 101.962817 -218.055646) (xy 101.939591 -218.012138)
			(xy 101.923091 -217.965661) (xy 101.913682 -217.917247) (xy 101.912166 -217.89263) (xy 101.910956 -217.877118)
			(xy 101.900363 -217.847879) (xy 101.881467 -217.82318) (xy 101.856016 -217.805308) (xy 101.826369 -217.79592)
			(xy 101.81082 -217.795348) (xy 101.734112 -217.795348) (xy 101.71857 -217.795945) (xy 101.688943 -217.805358)
			(xy 101.663506 -217.823229) (xy 101.644604 -217.847909) (xy 101.633981 -217.877125) (xy 101.632766 -217.89263)
			(xy 101.631201 -217.917845) (xy 101.621371 -217.967398) (xy 101.604115 -218.014877) (xy 101.579834 -218.059178)
			(xy 101.549095 -218.099267) (xy 101.512613 -218.134212) (xy 101.471237 -218.163197) (xy 101.425933 -218.185549)
			(xy 101.377755 -218.200746) (xy 101.327825 -218.208434) (xy 101.277307 -218.208434) (xy 101.227377 -218.200746)
			(xy 101.179199 -218.185549) (xy 101.133895 -218.163197) (xy 101.092519 -218.134212) (xy 101.056037 -218.099267)
			(xy 101.025298 -218.059178) (xy 101.001017 -218.014877) (xy 100.983761 -217.967398) (xy 100.973931 -217.917845)
			(xy 100.972366 -217.89263) (xy 100.971156 -217.877118) (xy 100.960563 -217.847879) (xy 100.941667 -217.82318)
			(xy 100.916216 -217.805308) (xy 100.886569 -217.79592) (xy 100.87102 -217.795348) (xy 100.794312 -217.795348)
			(xy 100.77877 -217.795945) (xy 100.749143 -217.805358) (xy 100.723706 -217.823229) (xy 100.704804 -217.847909)
			(xy 100.694181 -217.877125) (xy 100.692966 -217.89263) (xy 100.691461 -217.917011) (xy 100.682155 -217.964963)
			(xy 100.674424 -217.988134) (xy 100.666804 -218.010232) (xy 100.870512 -218.363038) (xy 100.893372 -218.367356)
			(xy 100.918302 -218.372507) (xy 100.966306 -218.389448) (xy 101.011142 -218.413552) (xy 101.051752 -218.444248)
			(xy 101.087172 -218.480809) (xy 101.116566 -218.52237) (xy 101.139238 -218.567948) (xy 101.154651 -218.616464)
			(xy 101.16244 -218.666769) (xy 101.162866 -218.692222) (xy 101.162357 -218.718189) (xy 101.442267 -218.718189)
			(xy 101.442267 -218.666255) (xy 101.450392 -218.61496) (xy 101.46644 -218.565567) (xy 101.490018 -218.519293)
			(xy 101.520544 -218.477277) (xy 101.557267 -218.440554) (xy 101.599283 -218.410028) (xy 101.645557 -218.38645)
			(xy 101.69495 -218.370402) (xy 101.746245 -218.362277) (xy 101.798179 -218.362277) (xy 101.849474 -218.370402)
			(xy 101.898867 -218.38645) (xy 101.945141 -218.410028) (xy 101.987157 -218.440554) (xy 102.02388 -218.477277)
			(xy 102.054406 -218.519293) (xy 102.077984 -218.565567) (xy 102.094032 -218.61496) (xy 102.102157 -218.666255)
			(xy 102.102666 -218.692222) (xy 102.102157 -218.718189) (xy 102.094032 -218.769484) (xy 102.077984 -218.818877)
			(xy 102.054406 -218.865151) (xy 102.02388 -218.907167) (xy 101.987157 -218.94389) (xy 101.945141 -218.974416)
			(xy 101.898867 -218.997994) (xy 101.849474 -219.014042) (xy 101.798179 -219.022167) (xy 101.746245 -219.022167)
			(xy 101.69495 -219.014042) (xy 101.645557 -218.997994) (xy 101.599283 -218.974416) (xy 101.557267 -218.94389)
			(xy 101.520544 -218.907167) (xy 101.490018 -218.865151) (xy 101.46644 -218.818877) (xy 101.450392 -218.769484)
			(xy 101.442267 -218.718189) (xy 101.162357 -218.718189) (xy 101.154232 -218.769484) (xy 101.138184 -218.818877)
			(xy 101.114606 -218.865151) (xy 101.08408 -218.907167) (xy 101.047357 -218.94389) (xy 101.005341 -218.974416)
			(xy 100.959067 -218.997994) (xy 100.909674 -219.014042) (xy 100.858379 -219.022167) (xy 100.806445 -219.022167)
			(xy 100.75515 -219.014042) (xy 100.705757 -218.997994) (xy 100.659483 -218.974416) (xy 100.617467 -218.94389)
			(xy 100.580744 -218.907167) (xy 100.550218 -218.865151) (xy 100.52664 -218.818877) (xy 100.510592 -218.769484)
			(xy 100.502467 -218.718189) (xy 100.501958 -218.692222) (xy 100.50257 -218.664242) (xy 100.512019 -218.609083)
			(xy 100.520754 -218.582494) (xy 100.528374 -218.560396) (xy 100.324666 -218.20759) (xy 100.301806 -218.203272)
			(xy 100.277653 -218.198279) (xy 100.231068 -218.182086) (xy 100.187407 -218.159149) (xy 100.14764 -218.129977)
			(xy 100.112651 -218.095219) (xy 100.083217 -218.055646) (xy 100.059991 -218.012138) (xy 100.043491 -217.965661)
			(xy 100.034082 -217.917247) (xy 100.032566 -217.89263) (xy 100.031356 -217.877118) (xy 100.020763 -217.847879)
			(xy 100.001867 -217.82318) (xy 99.976416 -217.805308) (xy 99.946769 -217.79592) (xy 99.93122 -217.795348)
			(xy 99.854512 -217.795348) (xy 99.83897 -217.795945) (xy 99.809343 -217.805358) (xy 99.783906 -217.823229)
			(xy 99.765004 -217.847909) (xy 99.754381 -217.877125) (xy 99.753166 -217.89263) (xy 99.751601 -217.917845)
			(xy 99.741771 -217.967398) (xy 99.724515 -218.014877) (xy 99.700234 -218.059178) (xy 99.669495 -218.099267)
			(xy 99.633013 -218.134212) (xy 99.591637 -218.163197) (xy 99.546333 -218.185549) (xy 99.498155 -218.200746)
			(xy 99.448225 -218.208434) (xy 99.397707 -218.208434) (xy 99.347777 -218.200746) (xy 99.299599 -218.185549)
			(xy 99.254295 -218.163197) (xy 99.212919 -218.134212) (xy 99.176437 -218.099267) (xy 99.145698 -218.059178)
			(xy 99.121417 -218.014877) (xy 99.104161 -217.967398) (xy 99.094331 -217.917845) (xy 99.092766 -217.89263)
			(xy 99.091556 -217.877118) (xy 99.080963 -217.847879) (xy 99.062067 -217.82318) (xy 99.036616 -217.805308)
			(xy 99.006969 -217.79592) (xy 98.99142 -217.795348) (xy 98.914712 -217.795348) (xy 98.89917 -217.795945)
			(xy 98.869543 -217.805358) (xy 98.844106 -217.823229) (xy 98.825204 -217.847909) (xy 98.814581 -217.877125)
			(xy 98.813366 -217.89263) (xy 98.811861 -217.917011) (xy 98.802555 -217.964963) (xy 98.794824 -217.988134)
			(xy 98.787204 -218.010232) (xy 98.990912 -218.363038) (xy 99.013772 -218.367356) (xy 99.038702 -218.372507)
			(xy 99.086706 -218.389448) (xy 99.131542 -218.413552) (xy 99.172152 -218.444248) (xy 99.207572 -218.480809)
			(xy 99.236966 -218.52237) (xy 99.259638 -218.567948) (xy 99.275051 -218.616464) (xy 99.28284 -218.666769)
			(xy 99.283266 -218.692222) (xy 99.282757 -218.718189) (xy 99.274632 -218.769484) (xy 99.258584 -218.818877)
			(xy 99.235006 -218.865151) (xy 99.20448 -218.907167) (xy 99.167757 -218.94389) (xy 99.125741 -218.974416)
			(xy 99.079467 -218.997994) (xy 99.030074 -219.014042) (xy 98.978779 -219.022167) (xy 98.926845 -219.022167)
			(xy 98.87555 -219.014042) (xy 98.826157 -218.997994) (xy 98.779883 -218.974416) (xy 98.737867 -218.94389)
			(xy 98.701144 -218.907167) (xy 98.670618 -218.865151) (xy 98.64704 -218.818877) (xy 98.630992 -218.769484)
			(xy 98.622867 -218.718189) (xy 98.622358 -218.692222) (xy 98.62297 -218.664242) (xy 98.632419 -218.609083)
			(xy 98.641154 -218.582494) (xy 98.648774 -218.560396) (xy 98.445066 -218.20759) (xy 98.422206 -218.203272)
			(xy 98.398053 -218.198279) (xy 98.351468 -218.182086) (xy 98.307807 -218.159149) (xy 98.26804 -218.129977)
			(xy 98.233051 -218.095219) (xy 98.203617 -218.055646) (xy 98.180391 -218.012138) (xy 98.163891 -217.965661)
			(xy 98.154482 -217.917247) (xy 98.152966 -217.89263) (xy 98.151756 -217.877118) (xy 98.141163 -217.847879)
			(xy 98.122267 -217.82318) (xy 98.096816 -217.805308) (xy 98.067169 -217.79592) (xy 98.05162 -217.795348)
			(xy 97.974912 -217.795348) (xy 97.95937 -217.795945) (xy 97.929743 -217.805358) (xy 97.904306 -217.823229)
			(xy 97.885404 -217.847909) (xy 97.874781 -217.877125) (xy 97.873566 -217.89263) (xy 97.872001 -217.917845)
			(xy 97.862171 -217.967398) (xy 97.844915 -218.014877) (xy 97.820634 -218.059178) (xy 97.789895 -218.099267)
			(xy 97.753413 -218.134212) (xy 97.712037 -218.163197) (xy 97.666733 -218.185549) (xy 97.618555 -218.200746)
			(xy 97.568625 -218.208434) (xy 97.518107 -218.208434) (xy 97.468177 -218.200746) (xy 97.419999 -218.185549)
			(xy 97.374695 -218.163197) (xy 97.333319 -218.134212) (xy 97.296837 -218.099267) (xy 97.266098 -218.059178)
			(xy 97.241817 -218.014877) (xy 97.224561 -217.967398) (xy 97.214731 -217.917845) (xy 97.213166 -217.89263)
			(xy 97.211956 -217.877118) (xy 97.201363 -217.847879) (xy 97.182467 -217.82318) (xy 97.157016 -217.805308)
			(xy 97.127369 -217.79592) (xy 97.11182 -217.795348) (xy 97.035112 -217.795348) (xy 97.01957 -217.795945)
			(xy 96.989943 -217.805358) (xy 96.964506 -217.823229) (xy 96.945604 -217.847909) (xy 96.934981 -217.877125)
			(xy 96.933766 -217.89263) (xy 96.932261 -217.917011) (xy 96.922955 -217.964963) (xy 96.915224 -217.988134)
			(xy 96.907604 -218.010232) (xy 97.111312 -218.363038) (xy 97.134172 -218.367356) (xy 97.159102 -218.372507)
			(xy 97.207106 -218.389448) (xy 97.251942 -218.413552) (xy 97.292552 -218.444248) (xy 97.327972 -218.480809)
			(xy 97.357366 -218.52237) (xy 97.380038 -218.567948) (xy 97.395451 -218.616464) (xy 97.40324 -218.666769)
			(xy 97.403666 -218.692222) (xy 97.403157 -218.718189) (xy 97.395032 -218.769484) (xy 97.378984 -218.818877)
			(xy 97.355406 -218.865151) (xy 97.32488 -218.907167) (xy 97.288157 -218.94389) (xy 97.246141 -218.974416)
			(xy 97.199867 -218.997994) (xy 97.150474 -219.014042) (xy 97.099179 -219.022167) (xy 97.047245 -219.022167)
			(xy 96.99595 -219.014042) (xy 96.946557 -218.997994) (xy 96.900283 -218.974416) (xy 96.858267 -218.94389)
			(xy 96.821544 -218.907167) (xy 96.791018 -218.865151) (xy 96.76744 -218.818877) (xy 96.751392 -218.769484)
			(xy 96.743267 -218.718189) (xy 96.742758 -218.692222) (xy 96.74337 -218.664242) (xy 96.752819 -218.609083)
			(xy 96.761554 -218.582494) (xy 96.769174 -218.560396) (xy 96.565466 -218.20759) (xy 96.542606 -218.203272)
			(xy 96.518453 -218.198279) (xy 96.471868 -218.182086) (xy 96.428207 -218.159149) (xy 96.38844 -218.129977)
			(xy 96.353451 -218.095219) (xy 96.324017 -218.055646) (xy 96.300791 -218.012138) (xy 96.284291 -217.965661)
			(xy 96.274882 -217.917247) (xy 96.273366 -217.89263) (xy 96.272156 -217.877118) (xy 96.261563 -217.847879)
			(xy 96.242667 -217.82318) (xy 96.217216 -217.805308) (xy 96.187569 -217.79592) (xy 96.17202 -217.795348)
			(xy 96.095312 -217.795348) (xy 96.07977 -217.795945) (xy 96.050143 -217.805358) (xy 96.024706 -217.823229)
			(xy 96.005804 -217.847909) (xy 95.995181 -217.877125) (xy 95.993966 -217.89263) (xy 95.992401 -217.917845)
			(xy 95.982571 -217.967398) (xy 95.965315 -218.014877) (xy 95.941034 -218.059178) (xy 95.910295 -218.099267)
			(xy 95.873813 -218.134212) (xy 95.832437 -218.163197) (xy 95.787133 -218.185549) (xy 95.738955 -218.200746)
			(xy 95.689025 -218.208434) (xy 95.638507 -218.208434) (xy 95.588577 -218.200746) (xy 95.540399 -218.185549)
			(xy 95.495095 -218.163197) (xy 95.453719 -218.134212) (xy 95.417237 -218.099267) (xy 95.386498 -218.059178)
			(xy 95.362217 -218.014877) (xy 95.344961 -217.967398) (xy 95.335131 -217.917845) (xy 95.333566 -217.89263)
			(xy 95.332356 -217.877118) (xy 95.321763 -217.847879) (xy 95.302867 -217.82318) (xy 95.277416 -217.805308)
			(xy 95.247769 -217.79592) (xy 95.23222 -217.795348) (xy 95.155512 -217.795348) (xy 95.13997 -217.795945)
			(xy 95.110343 -217.805358) (xy 95.084906 -217.823229) (xy 95.066004 -217.847909) (xy 95.055381 -217.877125)
			(xy 95.054166 -217.89263) (xy 95.052661 -217.917011) (xy 95.043355 -217.964963) (xy 95.035624 -217.988134)
			(xy 95.028004 -218.010232) (xy 95.231712 -218.363038) (xy 95.254572 -218.367356) (xy 95.279502 -218.372507)
			(xy 95.327506 -218.389448) (xy 95.372342 -218.413552) (xy 95.412952 -218.444248) (xy 95.448372 -218.480809)
			(xy 95.477766 -218.52237) (xy 95.500438 -218.567948) (xy 95.515851 -218.616464) (xy 95.52364 -218.666769)
			(xy 95.524066 -218.692222) (xy 95.523557 -218.718189) (xy 95.515432 -218.769484) (xy 95.499384 -218.818877)
			(xy 95.475806 -218.865151) (xy 95.44528 -218.907167) (xy 95.408557 -218.94389) (xy 95.366541 -218.974416)
			(xy 95.320267 -218.997994) (xy 95.270874 -219.014042) (xy 95.219579 -219.022167) (xy 95.167645 -219.022167)
			(xy 95.11635 -219.014042) (xy 95.066957 -218.997994) (xy 95.020683 -218.974416) (xy 94.978667 -218.94389)
			(xy 94.941944 -218.907167) (xy 94.911418 -218.865151) (xy 94.88784 -218.818877) (xy 94.871792 -218.769484)
			(xy 94.863667 -218.718189) (xy 94.863158 -218.692222) (xy 94.86377 -218.664242) (xy 94.873219 -218.609083)
			(xy 94.881954 -218.582494) (xy 94.889574 -218.560396) (xy 94.685866 -218.20759) (xy 94.663006 -218.203272)
			(xy 94.638853 -218.198279) (xy 94.592268 -218.182086) (xy 94.548607 -218.159149) (xy 94.50884 -218.129977)
			(xy 94.473851 -218.095219) (xy 94.444417 -218.055646) (xy 94.421191 -218.012138) (xy 94.404691 -217.965661)
			(xy 94.395282 -217.917247) (xy 94.393766 -217.89263) (xy 94.392556 -217.877118) (xy 94.381963 -217.847879)
			(xy 94.363067 -217.82318) (xy 94.337616 -217.805308) (xy 94.307969 -217.79592) (xy 94.29242 -217.795348)
			(xy 94.215712 -217.795348) (xy 94.20017 -217.795945) (xy 94.170543 -217.805358) (xy 94.145106 -217.823229)
			(xy 94.126204 -217.847909) (xy 94.115581 -217.877125) (xy 94.114366 -217.89263) (xy 94.112801 -217.917845)
			(xy 94.102971 -217.967398) (xy 94.085715 -218.014877) (xy 94.061434 -218.059178) (xy 94.030695 -218.099267)
			(xy 93.994213 -218.134212) (xy 93.952837 -218.163197) (xy 93.907533 -218.185549) (xy 93.859355 -218.200746)
			(xy 93.809425 -218.208434) (xy 93.758907 -218.208434) (xy 93.708977 -218.200746) (xy 93.660799 -218.185549)
			(xy 93.615495 -218.163197) (xy 93.574119 -218.134212) (xy 93.537637 -218.099267) (xy 93.506898 -218.059178)
			(xy 93.482617 -218.014877) (xy 93.465361 -217.967398) (xy 93.455531 -217.917845) (xy 93.453966 -217.89263)
			(xy 93.452756 -217.877118) (xy 93.442163 -217.847879) (xy 93.423267 -217.82318) (xy 93.397816 -217.805308)
			(xy 93.368169 -217.79592) (xy 93.35262 -217.795348) (xy 93.275912 -217.795348) (xy 93.26037 -217.795945)
			(xy 93.230743 -217.805358) (xy 93.205306 -217.823229) (xy 93.186404 -217.847909) (xy 93.175781 -217.877125)
			(xy 93.174566 -217.89263) (xy 93.173061 -217.917011) (xy 93.163755 -217.964963) (xy 93.156024 -217.988134)
			(xy 93.148404 -218.010232) (xy 93.352112 -218.363038) (xy 93.374972 -218.367356) (xy 93.399902 -218.372507)
			(xy 93.447906 -218.389448) (xy 93.492742 -218.413552) (xy 93.533352 -218.444248) (xy 93.568772 -218.480809)
			(xy 93.598166 -218.52237) (xy 93.620838 -218.567948) (xy 93.636251 -218.616464) (xy 93.64404 -218.666769)
			(xy 93.644466 -218.692222) (xy 93.643957 -218.718189) (xy 93.635832 -218.769484) (xy 93.619784 -218.818877)
			(xy 93.596206 -218.865151) (xy 93.56568 -218.907167) (xy 93.528957 -218.94389) (xy 93.486941 -218.974416)
			(xy 93.440667 -218.997994) (xy 93.391274 -219.014042) (xy 93.339979 -219.022167) (xy 93.288045 -219.022167)
			(xy 93.23675 -219.014042) (xy 93.187357 -218.997994) (xy 93.141083 -218.974416) (xy 93.099067 -218.94389)
			(xy 93.062344 -218.907167) (xy 93.031818 -218.865151) (xy 93.00824 -218.818877) (xy 92.992192 -218.769484)
			(xy 92.984067 -218.718189) (xy 92.983558 -218.692222) (xy 92.98417 -218.664242) (xy 92.993619 -218.609083)
			(xy 93.002354 -218.582494) (xy 93.009974 -218.560396) (xy 92.806266 -218.20759) (xy 92.783406 -218.203272)
			(xy 92.759253 -218.198279) (xy 92.712668 -218.182086) (xy 92.669007 -218.159149) (xy 92.62924 -218.129977)
			(xy 92.594251 -218.095219) (xy 92.564817 -218.055646) (xy 92.541591 -218.012138) (xy 92.525091 -217.965661)
			(xy 92.515682 -217.917247) (xy 92.514166 -217.89263) (xy 92.512956 -217.877118) (xy 92.502363 -217.847879)
			(xy 92.483467 -217.82318) (xy 92.458016 -217.805308) (xy 92.428369 -217.79592) (xy 92.41282 -217.795348)
			(xy 92.336112 -217.795348) (xy 92.32057 -217.795945) (xy 92.290943 -217.805358) (xy 92.265506 -217.823229)
			(xy 92.246604 -217.847909) (xy 92.235981 -217.877125) (xy 92.234766 -217.89263) (xy 92.233201 -217.917845)
			(xy 92.223371 -217.967398) (xy 92.206115 -218.014877) (xy 92.181834 -218.059178) (xy 92.151095 -218.099267)
			(xy 92.114613 -218.134212) (xy 92.073237 -218.163197) (xy 92.027933 -218.185549) (xy 91.979755 -218.200746)
			(xy 91.929825 -218.208434) (xy 91.879307 -218.208434) (xy 91.829377 -218.200746) (xy 91.781199 -218.185549)
			(xy 91.735895 -218.163197) (xy 91.694519 -218.134212) (xy 91.658037 -218.099267) (xy 91.627298 -218.059178)
			(xy 91.603017 -218.014877) (xy 91.585761 -217.967398) (xy 91.575931 -217.917845) (xy 91.574366 -217.89263)
			(xy 91.573156 -217.877118) (xy 91.562563 -217.847879) (xy 91.543667 -217.82318) (xy 91.518216 -217.805308)
			(xy 91.488569 -217.79592) (xy 91.47302 -217.795348) (xy 91.396312 -217.795348) (xy 91.38077 -217.795945)
			(xy 91.351143 -217.805358) (xy 91.325706 -217.823229) (xy 91.306804 -217.847909) (xy 91.296181 -217.877125)
			(xy 91.294966 -217.89263) (xy 91.293461 -217.917011) (xy 91.284155 -217.964963) (xy 91.276424 -217.988134)
			(xy 91.268804 -218.010232) (xy 91.472512 -218.363038) (xy 91.495372 -218.367356) (xy 91.520302 -218.372507)
			(xy 91.568306 -218.389448) (xy 91.613142 -218.413552) (xy 91.653752 -218.444248) (xy 91.689172 -218.480809)
			(xy 91.718566 -218.52237) (xy 91.741238 -218.567948) (xy 91.756651 -218.616464) (xy 91.76444 -218.666769)
			(xy 91.764866 -218.692222) (xy 91.764357 -218.718189) (xy 91.756232 -218.769484) (xy 91.740184 -218.818877)
			(xy 91.716606 -218.865151) (xy 91.68608 -218.907167) (xy 91.649357 -218.94389) (xy 91.607341 -218.974416)
			(xy 91.561067 -218.997994) (xy 91.511674 -219.014042) (xy 91.460379 -219.022167) (xy 91.408445 -219.022167)
			(xy 91.35715 -219.014042) (xy 91.307757 -218.997994) (xy 91.261483 -218.974416) (xy 91.219467 -218.94389)
			(xy 91.182744 -218.907167) (xy 91.152218 -218.865151) (xy 91.12864 -218.818877) (xy 91.112592 -218.769484)
			(xy 91.104467 -218.718189) (xy 91.103958 -218.692222) (xy 91.10457 -218.664242) (xy 91.114019 -218.609083)
			(xy 91.122754 -218.582494) (xy 91.130374 -218.560396) (xy 90.926666 -218.20759) (xy 90.903806 -218.203272)
			(xy 90.879653 -218.198279) (xy 90.833068 -218.182086) (xy 90.789407 -218.159149) (xy 90.74964 -218.129977)
			(xy 90.714651 -218.095219) (xy 90.685217 -218.055646) (xy 90.661991 -218.012138) (xy 90.645491 -217.965661)
			(xy 90.636082 -217.917247) (xy 90.634566 -217.89263) (xy 90.633356 -217.877118) (xy 90.622763 -217.847879)
			(xy 90.603867 -217.82318) (xy 90.578416 -217.805308) (xy 90.548769 -217.79592) (xy 90.53322 -217.795348)
			(xy 90.456512 -217.795348) (xy 90.44097 -217.795945) (xy 90.411343 -217.805358) (xy 90.385906 -217.823229)
			(xy 90.367004 -217.847909) (xy 90.356381 -217.877125) (xy 90.355166 -217.89263) (xy 90.353601 -217.917845)
			(xy 90.343771 -217.967398) (xy 90.326515 -218.014877) (xy 90.302234 -218.059178) (xy 90.271495 -218.099267)
			(xy 90.235013 -218.134212) (xy 90.193637 -218.163197) (xy 90.148333 -218.185549) (xy 90.100155 -218.200746)
			(xy 90.050225 -218.208434) (xy 89.999707 -218.208434) (xy 89.949777 -218.200746) (xy 89.901599 -218.185549)
			(xy 89.856295 -218.163197) (xy 89.814919 -218.134212) (xy 89.778437 -218.099267) (xy 89.747698 -218.059178)
			(xy 89.723417 -218.014877) (xy 89.706161 -217.967398) (xy 89.696331 -217.917845) (xy 89.694766 -217.89263)
			(xy 89.693556 -217.877118) (xy 89.682963 -217.847879) (xy 89.664067 -217.82318) (xy 89.638616 -217.805308)
			(xy 89.608969 -217.79592) (xy 89.59342 -217.795348) (xy 89.516712 -217.795348) (xy 89.50117 -217.795945)
			(xy 89.471543 -217.805358) (xy 89.446106 -217.823229) (xy 89.427204 -217.847909) (xy 89.416581 -217.877125)
			(xy 89.415366 -217.89263) (xy 89.413861 -217.917011) (xy 89.404555 -217.964963) (xy 89.396824 -217.988134)
			(xy 89.389204 -218.010232) (xy 89.592912 -218.363038) (xy 89.615772 -218.367356) (xy 89.640702 -218.372507)
			(xy 89.688706 -218.389448) (xy 89.733542 -218.413552) (xy 89.774152 -218.444248) (xy 89.809572 -218.480809)
			(xy 89.838966 -218.52237) (xy 89.861638 -218.567948) (xy 89.877051 -218.616464) (xy 89.88484 -218.666769)
			(xy 89.885266 -218.692222) (xy 89.884757 -218.718189) (xy 89.876632 -218.769484) (xy 89.860584 -218.818877)
			(xy 89.837006 -218.865151) (xy 89.80648 -218.907167) (xy 89.769757 -218.94389) (xy 89.727741 -218.974416)
			(xy 89.681467 -218.997994) (xy 89.632074 -219.014042) (xy 89.580779 -219.022167) (xy 89.528845 -219.022167)
			(xy 89.47755 -219.014042) (xy 89.428157 -218.997994) (xy 89.381883 -218.974416) (xy 89.339867 -218.94389)
			(xy 89.303144 -218.907167) (xy 89.272618 -218.865151) (xy 89.24904 -218.818877) (xy 89.232992 -218.769484)
			(xy 89.224867 -218.718189) (xy 89.224358 -218.692222) (xy 89.22497 -218.664242) (xy 89.234419 -218.609083)
			(xy 89.243154 -218.582494) (xy 89.250774 -218.560396) (xy 89.047066 -218.20759) (xy 89.024206 -218.203272)
			(xy 88.997448 -218.197718) (xy 88.946125 -218.178952) (xy 88.898591 -218.151993) (xy 88.856144 -218.117578)
			(xy 88.819942 -218.076643) (xy 88.790972 -218.030308) (xy 88.770025 -217.979836) (xy 88.763348 -217.953336)
			(xy 88.759847 -217.940278) (xy 88.746978 -217.916514) (xy 88.728326 -217.896958) (xy 88.705197 -217.882979)
			(xy 88.679212 -217.875556) (xy 88.652189 -217.875209) (xy 88.626022 -217.881962) (xy 88.602542 -217.895342)
			(xy 88.59266 -217.904568) (xy 88.24468 -218.252548) (xy 88.24468 -219.189046) (xy 88.275414 -219.202254)
			(xy 88.298854 -219.212819) (xy 88.342414 -219.240126) (xy 88.381218 -219.273851) (xy 88.414331 -219.31318)
			(xy 88.440952 -219.357163) (xy 88.460439 -219.404739) (xy 88.472321 -219.454758) (xy 88.476313 -219.506015)
			(xy 88.474287 -219.532005) (xy 88.755221 -219.532005) (xy 88.755221 -219.480071) (xy 88.763346 -219.428776)
			(xy 88.779394 -219.379383) (xy 88.802972 -219.333109) (xy 88.833498 -219.291093) (xy 88.870221 -219.25437)
			(xy 88.912237 -219.223844) (xy 88.958511 -219.200266) (xy 89.007904 -219.184218) (xy 89.059199 -219.176093)
			(xy 89.111133 -219.176093) (xy 89.162428 -219.184218) (xy 89.211821 -219.200266) (xy 89.258095 -219.223844)
			(xy 89.300111 -219.25437) (xy 89.336834 -219.291093) (xy 89.36736 -219.333109) (xy 89.390938 -219.379383)
			(xy 89.406986 -219.428776) (xy 89.415111 -219.480071) (xy 89.41562 -219.506038) (xy 89.415111 -219.532005)
			(xy 89.695021 -219.532005) (xy 89.695021 -219.480071) (xy 89.703146 -219.428776) (xy 89.719194 -219.379383)
			(xy 89.742772 -219.333109) (xy 89.773298 -219.291093) (xy 89.810021 -219.25437) (xy 89.852037 -219.223844)
			(xy 89.898311 -219.200266) (xy 89.947704 -219.184218) (xy 89.998999 -219.176093) (xy 90.050933 -219.176093)
			(xy 90.102228 -219.184218) (xy 90.151621 -219.200266) (xy 90.197895 -219.223844) (xy 90.239911 -219.25437)
			(xy 90.276634 -219.291093) (xy 90.30716 -219.333109) (xy 90.330738 -219.379383) (xy 90.346786 -219.428776)
			(xy 90.354911 -219.480071) (xy 90.35542 -219.506038) (xy 90.354911 -219.532005) (xy 90.634821 -219.532005)
			(xy 90.634821 -219.480071) (xy 90.642946 -219.428776) (xy 90.658994 -219.379383) (xy 90.682572 -219.333109)
			(xy 90.713098 -219.291093) (xy 90.749821 -219.25437) (xy 90.791837 -219.223844) (xy 90.838111 -219.200266)
			(xy 90.887504 -219.184218) (xy 90.938799 -219.176093) (xy 90.990733 -219.176093) (xy 91.042028 -219.184218)
			(xy 91.091421 -219.200266) (xy 91.137695 -219.223844) (xy 91.179711 -219.25437) (xy 91.216434 -219.291093)
			(xy 91.24696 -219.333109) (xy 91.270538 -219.379383) (xy 91.286586 -219.428776) (xy 91.294711 -219.480071)
			(xy 91.29522 -219.506038) (xy 91.294711 -219.532005) (xy 91.574621 -219.532005) (xy 91.574621 -219.480071)
			(xy 91.582746 -219.428776) (xy 91.598794 -219.379383) (xy 91.622372 -219.333109) (xy 91.652898 -219.291093)
			(xy 91.689621 -219.25437) (xy 91.731637 -219.223844) (xy 91.777911 -219.200266) (xy 91.827304 -219.184218)
			(xy 91.878599 -219.176093) (xy 91.930533 -219.176093) (xy 91.981828 -219.184218) (xy 92.031221 -219.200266)
			(xy 92.077495 -219.223844) (xy 92.119511 -219.25437) (xy 92.156234 -219.291093) (xy 92.18676 -219.333109)
			(xy 92.210338 -219.379383) (xy 92.226386 -219.428776) (xy 92.234511 -219.480071) (xy 92.23502 -219.506038)
			(xy 92.234511 -219.532005) (xy 92.514421 -219.532005) (xy 92.514421 -219.480071) (xy 92.522546 -219.428776)
			(xy 92.538594 -219.379383) (xy 92.562172 -219.333109) (xy 92.592698 -219.291093) (xy 92.629421 -219.25437)
			(xy 92.671437 -219.223844) (xy 92.717711 -219.200266) (xy 92.767104 -219.184218) (xy 92.818399 -219.176093)
			(xy 92.870333 -219.176093) (xy 92.921628 -219.184218) (xy 92.971021 -219.200266) (xy 93.017295 -219.223844)
			(xy 93.059311 -219.25437) (xy 93.096034 -219.291093) (xy 93.12656 -219.333109) (xy 93.150138 -219.379383)
			(xy 93.166186 -219.428776) (xy 93.174311 -219.480071) (xy 93.17482 -219.506038) (xy 93.174311 -219.532005)
			(xy 93.454221 -219.532005) (xy 93.454221 -219.480071) (xy 93.462346 -219.428776) (xy 93.478394 -219.379383)
			(xy 93.501972 -219.333109) (xy 93.532498 -219.291093) (xy 93.569221 -219.25437) (xy 93.611237 -219.223844)
			(xy 93.657511 -219.200266) (xy 93.706904 -219.184218) (xy 93.758199 -219.176093) (xy 93.810133 -219.176093)
			(xy 93.861428 -219.184218) (xy 93.910821 -219.200266) (xy 93.957095 -219.223844) (xy 93.999111 -219.25437)
			(xy 94.035834 -219.291093) (xy 94.06636 -219.333109) (xy 94.089938 -219.379383) (xy 94.105986 -219.428776)
			(xy 94.114111 -219.480071) (xy 94.11462 -219.506038) (xy 94.114111 -219.532005) (xy 94.394021 -219.532005)
			(xy 94.394021 -219.480071) (xy 94.402146 -219.428776) (xy 94.418194 -219.379383) (xy 94.441772 -219.333109)
			(xy 94.472298 -219.291093) (xy 94.509021 -219.25437) (xy 94.551037 -219.223844) (xy 94.597311 -219.200266)
			(xy 94.646704 -219.184218) (xy 94.697999 -219.176093) (xy 94.749933 -219.176093) (xy 94.801228 -219.184218)
			(xy 94.850621 -219.200266) (xy 94.896895 -219.223844) (xy 94.938911 -219.25437) (xy 94.975634 -219.291093)
			(xy 95.00616 -219.333109) (xy 95.029738 -219.379383) (xy 95.045786 -219.428776) (xy 95.053911 -219.480071)
			(xy 95.05442 -219.506038) (xy 95.053911 -219.532005) (xy 95.333821 -219.532005) (xy 95.333821 -219.480071)
			(xy 95.341946 -219.428776) (xy 95.357994 -219.379383) (xy 95.381572 -219.333109) (xy 95.412098 -219.291093)
			(xy 95.448821 -219.25437) (xy 95.490837 -219.223844) (xy 95.537111 -219.200266) (xy 95.586504 -219.184218)
			(xy 95.637799 -219.176093) (xy 95.689733 -219.176093) (xy 95.741028 -219.184218) (xy 95.790421 -219.200266)
			(xy 95.836695 -219.223844) (xy 95.878711 -219.25437) (xy 95.915434 -219.291093) (xy 95.94596 -219.333109)
			(xy 95.969538 -219.379383) (xy 95.985586 -219.428776) (xy 95.993711 -219.480071) (xy 95.99422 -219.506038)
			(xy 95.993711 -219.532005) (xy 96.273621 -219.532005) (xy 96.273621 -219.480071) (xy 96.281746 -219.428776)
			(xy 96.297794 -219.379383) (xy 96.321372 -219.333109) (xy 96.351898 -219.291093) (xy 96.388621 -219.25437)
			(xy 96.430637 -219.223844) (xy 96.476911 -219.200266) (xy 96.526304 -219.184218) (xy 96.577599 -219.176093)
			(xy 96.629533 -219.176093) (xy 96.680828 -219.184218) (xy 96.730221 -219.200266) (xy 96.776495 -219.223844)
			(xy 96.818511 -219.25437) (xy 96.855234 -219.291093) (xy 96.88576 -219.333109) (xy 96.909338 -219.379383)
			(xy 96.925386 -219.428776) (xy 96.933511 -219.480071) (xy 96.93402 -219.506038) (xy 96.933511 -219.532005)
			(xy 97.213421 -219.532005) (xy 97.213421 -219.480071) (xy 97.221546 -219.428776) (xy 97.237594 -219.379383)
			(xy 97.261172 -219.333109) (xy 97.291698 -219.291093) (xy 97.328421 -219.25437) (xy 97.370437 -219.223844)
			(xy 97.416711 -219.200266) (xy 97.466104 -219.184218) (xy 97.517399 -219.176093) (xy 97.569333 -219.176093)
			(xy 97.620628 -219.184218) (xy 97.670021 -219.200266) (xy 97.716295 -219.223844) (xy 97.758311 -219.25437)
			(xy 97.795034 -219.291093) (xy 97.82556 -219.333109) (xy 97.849138 -219.379383) (xy 97.865186 -219.428776)
			(xy 97.873311 -219.480071) (xy 97.87382 -219.506038) (xy 97.873311 -219.532005) (xy 98.153221 -219.532005)
			(xy 98.153221 -219.480071) (xy 98.161346 -219.428776) (xy 98.177394 -219.379383) (xy 98.200972 -219.333109)
			(xy 98.231498 -219.291093) (xy 98.268221 -219.25437) (xy 98.310237 -219.223844) (xy 98.356511 -219.200266)
			(xy 98.405904 -219.184218) (xy 98.457199 -219.176093) (xy 98.509133 -219.176093) (xy 98.560428 -219.184218)
			(xy 98.609821 -219.200266) (xy 98.656095 -219.223844) (xy 98.698111 -219.25437) (xy 98.734834 -219.291093)
			(xy 98.76536 -219.333109) (xy 98.788938 -219.379383) (xy 98.804986 -219.428776) (xy 98.813111 -219.480071)
			(xy 98.81362 -219.506038) (xy 98.813111 -219.532005) (xy 99.093021 -219.532005) (xy 99.093021 -219.480071)
			(xy 99.101146 -219.428776) (xy 99.117194 -219.379383) (xy 99.140772 -219.333109) (xy 99.171298 -219.291093)
			(xy 99.208021 -219.25437) (xy 99.250037 -219.223844) (xy 99.296311 -219.200266) (xy 99.345704 -219.184218)
			(xy 99.396999 -219.176093) (xy 99.448933 -219.176093) (xy 99.500228 -219.184218) (xy 99.549621 -219.200266)
			(xy 99.595895 -219.223844) (xy 99.637911 -219.25437) (xy 99.674634 -219.291093) (xy 99.70516 -219.333109)
			(xy 99.728738 -219.379383) (xy 99.744786 -219.428776) (xy 99.752911 -219.480071) (xy 99.75342 -219.506038)
			(xy 99.752911 -219.532005) (xy 100.032821 -219.532005) (xy 100.032821 -219.480071) (xy 100.040946 -219.428776)
			(xy 100.056994 -219.379383) (xy 100.080572 -219.333109) (xy 100.111098 -219.291093) (xy 100.147821 -219.25437)
			(xy 100.189837 -219.223844) (xy 100.236111 -219.200266) (xy 100.285504 -219.184218) (xy 100.336799 -219.176093)
			(xy 100.388733 -219.176093) (xy 100.440028 -219.184218) (xy 100.489421 -219.200266) (xy 100.535695 -219.223844)
			(xy 100.577711 -219.25437) (xy 100.614434 -219.291093) (xy 100.64496 -219.333109) (xy 100.668538 -219.379383)
			(xy 100.684586 -219.428776) (xy 100.692711 -219.480071) (xy 100.69322 -219.506038) (xy 100.692711 -219.532005)
			(xy 100.972621 -219.532005) (xy 100.972621 -219.480071) (xy 100.980746 -219.428776) (xy 100.996794 -219.379383)
			(xy 101.020372 -219.333109) (xy 101.050898 -219.291093) (xy 101.087621 -219.25437) (xy 101.129637 -219.223844)
			(xy 101.175911 -219.200266) (xy 101.225304 -219.184218) (xy 101.276599 -219.176093) (xy 101.328533 -219.176093)
			(xy 101.379828 -219.184218) (xy 101.429221 -219.200266) (xy 101.475495 -219.223844) (xy 101.517511 -219.25437)
			(xy 101.554234 -219.291093) (xy 101.58476 -219.333109) (xy 101.608338 -219.379383) (xy 101.624386 -219.428776)
			(xy 101.632511 -219.480071) (xy 101.63302 -219.506038) (xy 101.632511 -219.532005) (xy 101.912421 -219.532005)
			(xy 101.912421 -219.480071) (xy 101.920546 -219.428776) (xy 101.936594 -219.379383) (xy 101.960172 -219.333109)
			(xy 101.990698 -219.291093) (xy 102.027421 -219.25437) (xy 102.069437 -219.223844) (xy 102.115711 -219.200266)
			(xy 102.165104 -219.184218) (xy 102.216399 -219.176093) (xy 102.268333 -219.176093) (xy 102.319628 -219.184218)
			(xy 102.369021 -219.200266) (xy 102.415295 -219.223844) (xy 102.457311 -219.25437) (xy 102.494034 -219.291093)
			(xy 102.52456 -219.333109) (xy 102.548138 -219.379383) (xy 102.564186 -219.428776) (xy 102.572311 -219.480071)
			(xy 102.57282 -219.506038) (xy 102.572311 -219.532005) (xy 102.564186 -219.5833) (xy 102.548138 -219.632693)
			(xy 102.52456 -219.678967) (xy 102.494034 -219.720983) (xy 102.457311 -219.757706) (xy 102.415295 -219.788232)
			(xy 102.369021 -219.81181) (xy 102.319628 -219.827858) (xy 102.268333 -219.835983) (xy 102.216399 -219.835983)
			(xy 102.165104 -219.827858) (xy 102.115711 -219.81181) (xy 102.069437 -219.788232) (xy 102.027421 -219.757706)
			(xy 101.990698 -219.720983) (xy 101.960172 -219.678967) (xy 101.936594 -219.632693) (xy 101.920546 -219.5833)
			(xy 101.912421 -219.532005) (xy 101.632511 -219.532005) (xy 101.624386 -219.5833) (xy 101.608338 -219.632693)
			(xy 101.58476 -219.678967) (xy 101.554234 -219.720983) (xy 101.517511 -219.757706) (xy 101.475495 -219.788232)
			(xy 101.429221 -219.81181) (xy 101.379828 -219.827858) (xy 101.328533 -219.835983) (xy 101.276599 -219.835983)
			(xy 101.225304 -219.827858) (xy 101.175911 -219.81181) (xy 101.129637 -219.788232) (xy 101.087621 -219.757706)
			(xy 101.050898 -219.720983) (xy 101.020372 -219.678967) (xy 100.996794 -219.632693) (xy 100.980746 -219.5833)
			(xy 100.972621 -219.532005) (xy 100.692711 -219.532005) (xy 100.684586 -219.5833) (xy 100.668538 -219.632693)
			(xy 100.64496 -219.678967) (xy 100.614434 -219.720983) (xy 100.577711 -219.757706) (xy 100.535695 -219.788232)
			(xy 100.489421 -219.81181) (xy 100.440028 -219.827858) (xy 100.388733 -219.835983) (xy 100.336799 -219.835983)
			(xy 100.285504 -219.827858) (xy 100.236111 -219.81181) (xy 100.189837 -219.788232) (xy 100.147821 -219.757706)
			(xy 100.111098 -219.720983) (xy 100.080572 -219.678967) (xy 100.056994 -219.632693) (xy 100.040946 -219.5833)
			(xy 100.032821 -219.532005) (xy 99.752911 -219.532005) (xy 99.744786 -219.5833) (xy 99.728738 -219.632693)
			(xy 99.70516 -219.678967) (xy 99.674634 -219.720983) (xy 99.637911 -219.757706) (xy 99.595895 -219.788232)
			(xy 99.549621 -219.81181) (xy 99.500228 -219.827858) (xy 99.448933 -219.835983) (xy 99.396999 -219.835983)
			(xy 99.345704 -219.827858) (xy 99.296311 -219.81181) (xy 99.250037 -219.788232) (xy 99.208021 -219.757706)
			(xy 99.171298 -219.720983) (xy 99.140772 -219.678967) (xy 99.117194 -219.632693) (xy 99.101146 -219.5833)
			(xy 99.093021 -219.532005) (xy 98.813111 -219.532005) (xy 98.804986 -219.5833) (xy 98.788938 -219.632693)
			(xy 98.76536 -219.678967) (xy 98.734834 -219.720983) (xy 98.698111 -219.757706) (xy 98.656095 -219.788232)
			(xy 98.609821 -219.81181) (xy 98.560428 -219.827858) (xy 98.509133 -219.835983) (xy 98.457199 -219.835983)
			(xy 98.405904 -219.827858) (xy 98.356511 -219.81181) (xy 98.310237 -219.788232) (xy 98.268221 -219.757706)
			(xy 98.231498 -219.720983) (xy 98.200972 -219.678967) (xy 98.177394 -219.632693) (xy 98.161346 -219.5833)
			(xy 98.153221 -219.532005) (xy 97.873311 -219.532005) (xy 97.865186 -219.5833) (xy 97.849138 -219.632693)
			(xy 97.82556 -219.678967) (xy 97.795034 -219.720983) (xy 97.758311 -219.757706) (xy 97.716295 -219.788232)
			(xy 97.670021 -219.81181) (xy 97.620628 -219.827858) (xy 97.569333 -219.835983) (xy 97.517399 -219.835983)
			(xy 97.466104 -219.827858) (xy 97.416711 -219.81181) (xy 97.370437 -219.788232) (xy 97.328421 -219.757706)
			(xy 97.291698 -219.720983) (xy 97.261172 -219.678967) (xy 97.237594 -219.632693) (xy 97.221546 -219.5833)
			(xy 97.213421 -219.532005) (xy 96.933511 -219.532005) (xy 96.925386 -219.5833) (xy 96.909338 -219.632693)
			(xy 96.88576 -219.678967) (xy 96.855234 -219.720983) (xy 96.818511 -219.757706) (xy 96.776495 -219.788232)
			(xy 96.730221 -219.81181) (xy 96.680828 -219.827858) (xy 96.629533 -219.835983) (xy 96.577599 -219.835983)
			(xy 96.526304 -219.827858) (xy 96.476911 -219.81181) (xy 96.430637 -219.788232) (xy 96.388621 -219.757706)
			(xy 96.351898 -219.720983) (xy 96.321372 -219.678967) (xy 96.297794 -219.632693) (xy 96.281746 -219.5833)
			(xy 96.273621 -219.532005) (xy 95.993711 -219.532005) (xy 95.985586 -219.5833) (xy 95.969538 -219.632693)
			(xy 95.94596 -219.678967) (xy 95.915434 -219.720983) (xy 95.878711 -219.757706) (xy 95.836695 -219.788232)
			(xy 95.790421 -219.81181) (xy 95.741028 -219.827858) (xy 95.689733 -219.835983) (xy 95.637799 -219.835983)
			(xy 95.586504 -219.827858) (xy 95.537111 -219.81181) (xy 95.490837 -219.788232) (xy 95.448821 -219.757706)
			(xy 95.412098 -219.720983) (xy 95.381572 -219.678967) (xy 95.357994 -219.632693) (xy 95.341946 -219.5833)
			(xy 95.333821 -219.532005) (xy 95.053911 -219.532005) (xy 95.045786 -219.5833) (xy 95.029738 -219.632693)
			(xy 95.00616 -219.678967) (xy 94.975634 -219.720983) (xy 94.938911 -219.757706) (xy 94.896895 -219.788232)
			(xy 94.850621 -219.81181) (xy 94.801228 -219.827858) (xy 94.749933 -219.835983) (xy 94.697999 -219.835983)
			(xy 94.646704 -219.827858) (xy 94.597311 -219.81181) (xy 94.551037 -219.788232) (xy 94.509021 -219.757706)
			(xy 94.472298 -219.720983) (xy 94.441772 -219.678967) (xy 94.418194 -219.632693) (xy 94.402146 -219.5833)
			(xy 94.394021 -219.532005) (xy 94.114111 -219.532005) (xy 94.105986 -219.5833) (xy 94.089938 -219.632693)
			(xy 94.06636 -219.678967) (xy 94.035834 -219.720983) (xy 93.999111 -219.757706) (xy 93.957095 -219.788232)
			(xy 93.910821 -219.81181) (xy 93.861428 -219.827858) (xy 93.810133 -219.835983) (xy 93.758199 -219.835983)
			(xy 93.706904 -219.827858) (xy 93.657511 -219.81181) (xy 93.611237 -219.788232) (xy 93.569221 -219.757706)
			(xy 93.532498 -219.720983) (xy 93.501972 -219.678967) (xy 93.478394 -219.632693) (xy 93.462346 -219.5833)
			(xy 93.454221 -219.532005) (xy 93.174311 -219.532005) (xy 93.166186 -219.5833) (xy 93.150138 -219.632693)
			(xy 93.12656 -219.678967) (xy 93.096034 -219.720983) (xy 93.059311 -219.757706) (xy 93.017295 -219.788232)
			(xy 92.971021 -219.81181) (xy 92.921628 -219.827858) (xy 92.870333 -219.835983) (xy 92.818399 -219.835983)
			(xy 92.767104 -219.827858) (xy 92.717711 -219.81181) (xy 92.671437 -219.788232) (xy 92.629421 -219.757706)
			(xy 92.592698 -219.720983) (xy 92.562172 -219.678967) (xy 92.538594 -219.632693) (xy 92.522546 -219.5833)
			(xy 92.514421 -219.532005) (xy 92.234511 -219.532005) (xy 92.226386 -219.5833) (xy 92.210338 -219.632693)
			(xy 92.18676 -219.678967) (xy 92.156234 -219.720983) (xy 92.119511 -219.757706) (xy 92.077495 -219.788232)
			(xy 92.031221 -219.81181) (xy 91.981828 -219.827858) (xy 91.930533 -219.835983) (xy 91.878599 -219.835983)
			(xy 91.827304 -219.827858) (xy 91.777911 -219.81181) (xy 91.731637 -219.788232) (xy 91.689621 -219.757706)
			(xy 91.652898 -219.720983) (xy 91.622372 -219.678967) (xy 91.598794 -219.632693) (xy 91.582746 -219.5833)
			(xy 91.574621 -219.532005) (xy 91.294711 -219.532005) (xy 91.286586 -219.5833) (xy 91.270538 -219.632693)
			(xy 91.24696 -219.678967) (xy 91.216434 -219.720983) (xy 91.179711 -219.757706) (xy 91.137695 -219.788232)
			(xy 91.091421 -219.81181) (xy 91.042028 -219.827858) (xy 90.990733 -219.835983) (xy 90.938799 -219.835983)
			(xy 90.887504 -219.827858) (xy 90.838111 -219.81181) (xy 90.791837 -219.788232) (xy 90.749821 -219.757706)
			(xy 90.713098 -219.720983) (xy 90.682572 -219.678967) (xy 90.658994 -219.632693) (xy 90.642946 -219.5833)
			(xy 90.634821 -219.532005) (xy 90.354911 -219.532005) (xy 90.346786 -219.5833) (xy 90.330738 -219.632693)
			(xy 90.30716 -219.678967) (xy 90.276634 -219.720983) (xy 90.239911 -219.757706) (xy 90.197895 -219.788232)
			(xy 90.151621 -219.81181) (xy 90.102228 -219.827858) (xy 90.050933 -219.835983) (xy 89.998999 -219.835983)
			(xy 89.947704 -219.827858) (xy 89.898311 -219.81181) (xy 89.852037 -219.788232) (xy 89.810021 -219.757706)
			(xy 89.773298 -219.720983) (xy 89.742772 -219.678967) (xy 89.719194 -219.632693) (xy 89.703146 -219.5833)
			(xy 89.695021 -219.532005) (xy 89.415111 -219.532005) (xy 89.406986 -219.5833) (xy 89.390938 -219.632693)
			(xy 89.36736 -219.678967) (xy 89.336834 -219.720983) (xy 89.300111 -219.757706) (xy 89.258095 -219.788232)
			(xy 89.211821 -219.81181) (xy 89.162428 -219.827858) (xy 89.111133 -219.835983) (xy 89.059199 -219.835983)
			(xy 89.007904 -219.827858) (xy 88.958511 -219.81181) (xy 88.912237 -219.788232) (xy 88.870221 -219.757706)
			(xy 88.833498 -219.720983) (xy 88.802972 -219.678967) (xy 88.779394 -219.632693) (xy 88.763346 -219.5833)
			(xy 88.755221 -219.532005) (xy 88.474287 -219.532005) (xy 88.472317 -219.557271) (xy 88.460429 -219.60729)
			(xy 88.440938 -219.654864) (xy 88.414313 -219.698844) (xy 88.381197 -219.73817) (xy 88.34239 -219.771892)
			(xy 88.298827 -219.799195) (xy 88.275414 -219.809822) (xy 88.24468 -219.82303) (xy 88.24468 -219.98178)
			(xy 88.245157 -219.996052) (xy 88.25305 -220.023483) (xy 88.268225 -220.047659) (xy 88.289498 -220.066692)
			(xy 88.315206 -220.079095) (xy 88.343343 -220.0839) (xy 88.371711 -220.080731) (xy 88.398094 -220.069837)
			(xy 88.409526 -220.061282) (xy 88.43162 -220.044437) (xy 88.480268 -220.01761) (xy 88.532716 -219.999293)
			(xy 88.587489 -219.99) (xy 88.615266 -219.9894) (xy 88.641241 -219.98988) (xy 88.692551 -219.998002)
			(xy 88.741959 -220.014051) (xy 88.788248 -220.037633) (xy 88.830277 -220.068165) (xy 88.867013 -220.104897)
			(xy 88.89755 -220.146923) (xy 88.921136 -220.19321) (xy 88.93719 -220.242616) (xy 88.945317 -220.293925)
			(xy 88.945317 -220.345821) (xy 89.225121 -220.345821) (xy 89.225121 -220.293887) (xy 89.233246 -220.242592)
			(xy 89.249294 -220.193199) (xy 89.272872 -220.146925) (xy 89.303398 -220.104909) (xy 89.340121 -220.068186)
			(xy 89.382137 -220.03766) (xy 89.428411 -220.014082) (xy 89.477804 -219.998034) (xy 89.529099 -219.989909)
			(xy 89.581033 -219.989909) (xy 89.632328 -219.998034) (xy 89.681721 -220.014082) (xy 89.727995 -220.03766)
			(xy 89.770011 -220.068186) (xy 89.806734 -220.104909) (xy 89.83726 -220.146925) (xy 89.860838 -220.193199)
			(xy 89.876886 -220.242592) (xy 89.885011 -220.293887) (xy 89.88552 -220.319854) (xy 89.885011 -220.345821)
			(xy 89.876886 -220.397116) (xy 89.860838 -220.446509) (xy 89.83726 -220.492783) (xy 89.806734 -220.534799)
			(xy 89.770011 -220.571522) (xy 89.727995 -220.602048) (xy 89.681721 -220.625626) (xy 89.632328 -220.641674)
			(xy 89.581033 -220.649799) (xy 89.529099 -220.649799) (xy 89.477804 -220.641674) (xy 89.428411 -220.625626)
			(xy 89.382137 -220.602048) (xy 89.340121 -220.571522) (xy 89.303398 -220.534799) (xy 89.272872 -220.492783)
			(xy 89.249294 -220.446509) (xy 89.233246 -220.397116) (xy 89.225121 -220.345821) (xy 88.945317 -220.345821)
			(xy 88.945317 -220.345875) (xy 88.93719 -220.397184) (xy 88.921136 -220.44659) (xy 88.89755 -220.492877)
			(xy 88.867013 -220.534903) (xy 88.830277 -220.571635) (xy 88.788248 -220.602167) (xy 88.741959 -220.625749)
			(xy 88.692551 -220.641798) (xy 88.641241 -220.64992) (xy 88.615266 -220.650308) (xy 88.587485 -220.649742)
			(xy 88.532705 -220.640457) (xy 88.480251 -220.622137) (xy 88.431602 -220.5953) (xy 88.409526 -220.578426)
			(xy 88.398065 -220.569921) (xy 88.371697 -220.559032) (xy 88.343346 -220.555865) (xy 88.315225 -220.560667)
			(xy 88.289532 -220.573063) (xy 88.268272 -220.592085) (xy 88.253106 -220.616248) (xy 88.245219 -220.643664)
			(xy 88.24468 -220.657928) (xy 88.24468 -220.816932) (xy 88.275414 -220.83014) (xy 88.300522 -220.841486)
			(xy 88.346875 -220.871266) (xy 88.387646 -220.908321) (xy 88.421706 -220.951626) (xy 88.448112 -220.99998)
			(xy 88.466131 -221.052045) (xy 88.475266 -221.106377) (xy 88.47582 -221.133924) (xy 88.47582 -221.134432)
			(xy 88.475352 -221.158932) (xy 88.468078 -221.207391) (xy 88.461342 -221.230952) (xy 88.452452 -221.260162)
			(xy 89.073736 -221.881446) (xy 89.084534 -221.891489) (xy 89.110497 -221.905448) (xy 89.139364 -221.911414)
			(xy 89.168733 -221.908893) (xy 89.196161 -221.898094) (xy 89.219365 -221.879916) (xy 89.236416 -221.85587)
			(xy 89.24163 -221.842076) (xy 89.243154 -221.838012) (xy 89.250774 -221.815914) (xy 89.047066 -221.463108)
			(xy 89.024206 -221.45879) (xy 88.999279 -221.453638) (xy 88.951282 -221.436693) (xy 88.906452 -221.412586)
			(xy 88.865851 -221.381889) (xy 88.830438 -221.345327) (xy 88.801052 -221.303766) (xy 88.778389 -221.258189)
			(xy 88.762985 -221.209676) (xy 88.755205 -221.159374) (xy 88.754712 -221.133924) (xy 88.755221 -221.107957)
			(xy 88.763346 -221.056662) (xy 88.779394 -221.007269) (xy 88.802972 -220.960995) (xy 88.833498 -220.918979)
			(xy 88.870221 -220.882256) (xy 88.912237 -220.85173) (xy 88.958511 -220.828152) (xy 89.007904 -220.812104)
			(xy 89.059199 -220.803979) (xy 89.111133 -220.803979) (xy 89.162428 -220.812104) (xy 89.211821 -220.828152)
			(xy 89.258095 -220.85173) (xy 89.300111 -220.882256) (xy 89.336834 -220.918979) (xy 89.36736 -220.960995)
			(xy 89.390938 -221.007269) (xy 89.406986 -221.056662) (xy 89.415111 -221.107957) (xy 89.41562 -221.133924)
			(xy 89.694512 -221.133924) (xy 89.694958 -221.108472) (xy 89.702746 -221.058168) (xy 89.718157 -221.009654)
			(xy 89.740827 -220.964077) (xy 89.770218 -220.922517) (xy 89.805636 -220.885956) (xy 89.846243 -220.855259)
			(xy 89.891076 -220.831154) (xy 89.939077 -220.81421) (xy 89.964006 -220.809058) (xy 89.986866 -220.80474)
			(xy 90.190574 -220.45168) (xy 90.182954 -220.429582) (xy 90.174214 -220.402995) (xy 90.164768 -220.347835)
			(xy 90.164158 -220.319854) (xy 90.164667 -220.293887) (xy 90.172792 -220.242592) (xy 90.18884 -220.193199)
			(xy 90.212418 -220.146925) (xy 90.242944 -220.104909) (xy 90.279667 -220.068186) (xy 90.321683 -220.03766)
			(xy 90.367957 -220.014082) (xy 90.41735 -219.998034) (xy 90.468645 -219.989909) (xy 90.520579 -219.989909)
			(xy 90.571874 -219.998034) (xy 90.621267 -220.014082) (xy 90.667541 -220.03766) (xy 90.709557 -220.068186)
			(xy 90.74628 -220.104909) (xy 90.776806 -220.146925) (xy 90.800384 -220.193199) (xy 90.816432 -220.242592)
			(xy 90.824557 -220.293887) (xy 90.825066 -220.319854) (xy 90.824618 -220.345306) (xy 90.824538 -220.345821)
			(xy 91.104721 -220.345821) (xy 91.104721 -220.293887) (xy 91.112846 -220.242592) (xy 91.128894 -220.193199)
			(xy 91.152472 -220.146925) (xy 91.182998 -220.104909) (xy 91.219721 -220.068186) (xy 91.261737 -220.03766)
			(xy 91.308011 -220.014082) (xy 91.357404 -219.998034) (xy 91.408699 -219.989909) (xy 91.460633 -219.989909)
			(xy 91.511928 -219.998034) (xy 91.561321 -220.014082) (xy 91.607595 -220.03766) (xy 91.649611 -220.068186)
			(xy 91.686334 -220.104909) (xy 91.71686 -220.146925) (xy 91.740438 -220.193199) (xy 91.756486 -220.242592)
			(xy 91.764611 -220.293887) (xy 91.76512 -220.319854) (xy 91.764611 -220.345821) (xy 91.756486 -220.397116)
			(xy 91.740438 -220.446509) (xy 91.71686 -220.492783) (xy 91.686334 -220.534799) (xy 91.649611 -220.571522)
			(xy 91.607595 -220.602048) (xy 91.561321 -220.625626) (xy 91.511928 -220.641674) (xy 91.460633 -220.649799)
			(xy 91.408699 -220.649799) (xy 91.357404 -220.641674) (xy 91.308011 -220.625626) (xy 91.261737 -220.602048)
			(xy 91.219721 -220.571522) (xy 91.182998 -220.534799) (xy 91.152472 -220.492783) (xy 91.128894 -220.446509)
			(xy 91.112846 -220.397116) (xy 91.104721 -220.345821) (xy 90.824538 -220.345821) (xy 90.816833 -220.395611)
			(xy 90.801423 -220.444126) (xy 90.778755 -220.489704) (xy 90.749363 -220.531265) (xy 90.713945 -220.567826)
			(xy 90.673338 -220.598523) (xy 90.628503 -220.622627) (xy 90.580502 -220.639569) (xy 90.555572 -220.64472)
			(xy 90.532712 -220.649038) (xy 90.329004 -221.002098) (xy 90.336624 -221.024196) (xy 90.345361 -221.050784)
			(xy 90.354809 -221.105943) (xy 90.35542 -221.133924) (xy 90.634312 -221.133924) (xy 90.634821 -221.107957)
			(xy 90.642946 -221.056662) (xy 90.658994 -221.007269) (xy 90.682572 -220.960995) (xy 90.713098 -220.918979)
			(xy 90.749821 -220.882256) (xy 90.791837 -220.85173) (xy 90.838111 -220.828152) (xy 90.887504 -220.812104)
			(xy 90.938799 -220.803979) (xy 90.990733 -220.803979) (xy 91.042028 -220.812104) (xy 91.091421 -220.828152)
			(xy 91.137695 -220.85173) (xy 91.179711 -220.882256) (xy 91.216434 -220.918979) (xy 91.24696 -220.960995)
			(xy 91.270538 -221.007269) (xy 91.286586 -221.056662) (xy 91.294711 -221.107957) (xy 91.29522 -221.133924)
			(xy 91.574112 -221.133924) (xy 91.574558 -221.108472) (xy 91.582346 -221.058168) (xy 91.597757 -221.009654)
			(xy 91.620427 -220.964077) (xy 91.649818 -220.922517) (xy 91.685236 -220.885956) (xy 91.725843 -220.855259)
			(xy 91.770676 -220.831154) (xy 91.818677 -220.81421) (xy 91.843606 -220.809058) (xy 91.866466 -220.80474)
			(xy 92.070174 -220.45168) (xy 92.062554 -220.429582) (xy 92.053814 -220.402995) (xy 92.044368 -220.347835)
			(xy 92.043758 -220.319854) (xy 92.044267 -220.293887) (xy 92.052392 -220.242592) (xy 92.06844 -220.193199)
			(xy 92.092018 -220.146925) (xy 92.122544 -220.104909) (xy 92.159267 -220.068186) (xy 92.201283 -220.03766)
			(xy 92.247557 -220.014082) (xy 92.29695 -219.998034) (xy 92.348245 -219.989909) (xy 92.400179 -219.989909)
			(xy 92.451474 -219.998034) (xy 92.500867 -220.014082) (xy 92.547141 -220.03766) (xy 92.589157 -220.068186)
			(xy 92.62588 -220.104909) (xy 92.656406 -220.146925) (xy 92.679984 -220.193199) (xy 92.696032 -220.242592)
			(xy 92.704157 -220.293887) (xy 92.704666 -220.319854) (xy 92.704218 -220.345306) (xy 92.704138 -220.345821)
			(xy 92.984321 -220.345821) (xy 92.984321 -220.293887) (xy 92.992446 -220.242592) (xy 93.008494 -220.193199)
			(xy 93.032072 -220.146925) (xy 93.062598 -220.104909) (xy 93.099321 -220.068186) (xy 93.141337 -220.03766)
			(xy 93.187611 -220.014082) (xy 93.237004 -219.998034) (xy 93.288299 -219.989909) (xy 93.340233 -219.989909)
			(xy 93.391528 -219.998034) (xy 93.440921 -220.014082) (xy 93.487195 -220.03766) (xy 93.529211 -220.068186)
			(xy 93.565934 -220.104909) (xy 93.59646 -220.146925) (xy 93.620038 -220.193199) (xy 93.636086 -220.242592)
			(xy 93.644211 -220.293887) (xy 93.64472 -220.319854) (xy 93.644211 -220.345821) (xy 93.636086 -220.397116)
			(xy 93.620038 -220.446509) (xy 93.59646 -220.492783) (xy 93.565934 -220.534799) (xy 93.529211 -220.571522)
			(xy 93.487195 -220.602048) (xy 93.440921 -220.625626) (xy 93.391528 -220.641674) (xy 93.340233 -220.649799)
			(xy 93.288299 -220.649799) (xy 93.237004 -220.641674) (xy 93.187611 -220.625626) (xy 93.141337 -220.602048)
			(xy 93.099321 -220.571522) (xy 93.062598 -220.534799) (xy 93.032072 -220.492783) (xy 93.008494 -220.446509)
			(xy 92.992446 -220.397116) (xy 92.984321 -220.345821) (xy 92.704138 -220.345821) (xy 92.696433 -220.395611)
			(xy 92.681023 -220.444126) (xy 92.658355 -220.489704) (xy 92.628963 -220.531265) (xy 92.593545 -220.567826)
			(xy 92.552938 -220.598523) (xy 92.508103 -220.622627) (xy 92.460102 -220.639569) (xy 92.435172 -220.64472)
			(xy 92.412312 -220.649038) (xy 92.208604 -221.002098) (xy 92.216224 -221.024196) (xy 92.224961 -221.050784)
			(xy 92.234409 -221.105943) (xy 92.23502 -221.133924) (xy 92.513912 -221.133924) (xy 92.514421 -221.107957)
			(xy 92.522546 -221.056662) (xy 92.538594 -221.007269) (xy 92.562172 -220.960995) (xy 92.592698 -220.918979)
			(xy 92.629421 -220.882256) (xy 92.671437 -220.85173) (xy 92.717711 -220.828152) (xy 92.767104 -220.812104)
			(xy 92.818399 -220.803979) (xy 92.870333 -220.803979) (xy 92.921628 -220.812104) (xy 92.971021 -220.828152)
			(xy 93.017295 -220.85173) (xy 93.059311 -220.882256) (xy 93.096034 -220.918979) (xy 93.12656 -220.960995)
			(xy 93.150138 -221.007269) (xy 93.166186 -221.056662) (xy 93.174311 -221.107957) (xy 93.17482 -221.133924)
			(xy 93.453712 -221.133924) (xy 93.454158 -221.108472) (xy 93.461946 -221.058168) (xy 93.477357 -221.009654)
			(xy 93.500027 -220.964077) (xy 93.529418 -220.922517) (xy 93.564836 -220.885956) (xy 93.605443 -220.855259)
			(xy 93.650276 -220.831154) (xy 93.698277 -220.81421) (xy 93.723206 -220.809058) (xy 93.746066 -220.80474)
			(xy 93.949774 -220.45168) (xy 93.942154 -220.429582) (xy 93.933414 -220.402995) (xy 93.923968 -220.347835)
			(xy 93.923358 -220.319854) (xy 93.923867 -220.293887) (xy 93.931992 -220.242592) (xy 93.94804 -220.193199)
			(xy 93.971618 -220.146925) (xy 94.002144 -220.104909) (xy 94.038867 -220.068186) (xy 94.080883 -220.03766)
			(xy 94.127157 -220.014082) (xy 94.17655 -219.998034) (xy 94.227845 -219.989909) (xy 94.279779 -219.989909)
			(xy 94.331074 -219.998034) (xy 94.380467 -220.014082) (xy 94.426741 -220.03766) (xy 94.468757 -220.068186)
			(xy 94.50548 -220.104909) (xy 94.536006 -220.146925) (xy 94.559584 -220.193199) (xy 94.575632 -220.242592)
			(xy 94.583757 -220.293887) (xy 94.584266 -220.319854) (xy 94.583818 -220.345306) (xy 94.583738 -220.345821)
			(xy 94.863921 -220.345821) (xy 94.863921 -220.293887) (xy 94.872046 -220.242592) (xy 94.888094 -220.193199)
			(xy 94.911672 -220.146925) (xy 94.942198 -220.104909) (xy 94.978921 -220.068186) (xy 95.020937 -220.03766)
			(xy 95.067211 -220.014082) (xy 95.116604 -219.998034) (xy 95.167899 -219.989909) (xy 95.219833 -219.989909)
			(xy 95.271128 -219.998034) (xy 95.320521 -220.014082) (xy 95.366795 -220.03766) (xy 95.408811 -220.068186)
			(xy 95.445534 -220.104909) (xy 95.47606 -220.146925) (xy 95.499638 -220.193199) (xy 95.515686 -220.242592)
			(xy 95.523811 -220.293887) (xy 95.52432 -220.319854) (xy 95.523811 -220.345821) (xy 95.515686 -220.397116)
			(xy 95.499638 -220.446509) (xy 95.47606 -220.492783) (xy 95.445534 -220.534799) (xy 95.408811 -220.571522)
			(xy 95.366795 -220.602048) (xy 95.320521 -220.625626) (xy 95.271128 -220.641674) (xy 95.219833 -220.649799)
			(xy 95.167899 -220.649799) (xy 95.116604 -220.641674) (xy 95.067211 -220.625626) (xy 95.020937 -220.602048)
			(xy 94.978921 -220.571522) (xy 94.942198 -220.534799) (xy 94.911672 -220.492783) (xy 94.888094 -220.446509)
			(xy 94.872046 -220.397116) (xy 94.863921 -220.345821) (xy 94.583738 -220.345821) (xy 94.576033 -220.395611)
			(xy 94.560623 -220.444126) (xy 94.537955 -220.489704) (xy 94.508563 -220.531265) (xy 94.473145 -220.567826)
			(xy 94.432538 -220.598523) (xy 94.387703 -220.622627) (xy 94.339702 -220.639569) (xy 94.314772 -220.64472)
			(xy 94.291912 -220.649038) (xy 94.088204 -221.002098) (xy 94.095824 -221.024196) (xy 94.104561 -221.050784)
			(xy 94.114009 -221.105943) (xy 94.11462 -221.133924) (xy 94.393512 -221.133924) (xy 94.394021 -221.107957)
			(xy 94.402146 -221.056662) (xy 94.418194 -221.007269) (xy 94.441772 -220.960995) (xy 94.472298 -220.918979)
			(xy 94.509021 -220.882256) (xy 94.551037 -220.85173) (xy 94.597311 -220.828152) (xy 94.646704 -220.812104)
			(xy 94.697999 -220.803979) (xy 94.749933 -220.803979) (xy 94.801228 -220.812104) (xy 94.850621 -220.828152)
			(xy 94.896895 -220.85173) (xy 94.938911 -220.882256) (xy 94.975634 -220.918979) (xy 95.00616 -220.960995)
			(xy 95.029738 -221.007269) (xy 95.045786 -221.056662) (xy 95.053911 -221.107957) (xy 95.05442 -221.133924)
			(xy 95.333312 -221.133924) (xy 95.333758 -221.108472) (xy 95.341546 -221.058168) (xy 95.356957 -221.009654)
			(xy 95.379627 -220.964077) (xy 95.409018 -220.922517) (xy 95.444436 -220.885956) (xy 95.485043 -220.855259)
			(xy 95.529876 -220.831154) (xy 95.577877 -220.81421) (xy 95.602806 -220.809058) (xy 95.625666 -220.80474)
			(xy 95.829374 -220.45168) (xy 95.821754 -220.429582) (xy 95.813014 -220.402995) (xy 95.803568 -220.347835)
			(xy 95.802958 -220.319854) (xy 95.803467 -220.293887) (xy 95.811592 -220.242592) (xy 95.82764 -220.193199)
			(xy 95.851218 -220.146925) (xy 95.881744 -220.104909) (xy 95.918467 -220.068186) (xy 95.960483 -220.03766)
			(xy 96.006757 -220.014082) (xy 96.05615 -219.998034) (xy 96.107445 -219.989909) (xy 96.159379 -219.989909)
			(xy 96.210674 -219.998034) (xy 96.260067 -220.014082) (xy 96.306341 -220.03766) (xy 96.348357 -220.068186)
			(xy 96.38508 -220.104909) (xy 96.415606 -220.146925) (xy 96.439184 -220.193199) (xy 96.455232 -220.242592)
			(xy 96.463357 -220.293887) (xy 96.463866 -220.319854) (xy 96.463418 -220.345306) (xy 96.463338 -220.345821)
			(xy 96.743521 -220.345821) (xy 96.743521 -220.293887) (xy 96.751646 -220.242592) (xy 96.767694 -220.193199)
			(xy 96.791272 -220.146925) (xy 96.821798 -220.104909) (xy 96.858521 -220.068186) (xy 96.900537 -220.03766)
			(xy 96.946811 -220.014082) (xy 96.996204 -219.998034) (xy 97.047499 -219.989909) (xy 97.099433 -219.989909)
			(xy 97.150728 -219.998034) (xy 97.200121 -220.014082) (xy 97.246395 -220.03766) (xy 97.288411 -220.068186)
			(xy 97.325134 -220.104909) (xy 97.35566 -220.146925) (xy 97.379238 -220.193199) (xy 97.395286 -220.242592)
			(xy 97.403411 -220.293887) (xy 97.40392 -220.319854) (xy 97.403411 -220.345821) (xy 97.395286 -220.397116)
			(xy 97.379238 -220.446509) (xy 97.35566 -220.492783) (xy 97.325134 -220.534799) (xy 97.288411 -220.571522)
			(xy 97.246395 -220.602048) (xy 97.200121 -220.625626) (xy 97.150728 -220.641674) (xy 97.099433 -220.649799)
			(xy 97.047499 -220.649799) (xy 96.996204 -220.641674) (xy 96.946811 -220.625626) (xy 96.900537 -220.602048)
			(xy 96.858521 -220.571522) (xy 96.821798 -220.534799) (xy 96.791272 -220.492783) (xy 96.767694 -220.446509)
			(xy 96.751646 -220.397116) (xy 96.743521 -220.345821) (xy 96.463338 -220.345821) (xy 96.455633 -220.395611)
			(xy 96.440223 -220.444126) (xy 96.417555 -220.489704) (xy 96.388163 -220.531265) (xy 96.352745 -220.567826)
			(xy 96.312138 -220.598523) (xy 96.267303 -220.622627) (xy 96.219302 -220.639569) (xy 96.194372 -220.64472)
			(xy 96.171512 -220.649038) (xy 95.967804 -221.002098) (xy 95.975424 -221.024196) (xy 95.984161 -221.050784)
			(xy 95.993609 -221.105943) (xy 95.99422 -221.133924) (xy 96.273112 -221.133924) (xy 96.273621 -221.107957)
			(xy 96.281746 -221.056662) (xy 96.297794 -221.007269) (xy 96.321372 -220.960995) (xy 96.351898 -220.918979)
			(xy 96.388621 -220.882256) (xy 96.430637 -220.85173) (xy 96.476911 -220.828152) (xy 96.526304 -220.812104)
			(xy 96.577599 -220.803979) (xy 96.629533 -220.803979) (xy 96.680828 -220.812104) (xy 96.730221 -220.828152)
			(xy 96.776495 -220.85173) (xy 96.818511 -220.882256) (xy 96.855234 -220.918979) (xy 96.88576 -220.960995)
			(xy 96.909338 -221.007269) (xy 96.925386 -221.056662) (xy 96.933511 -221.107957) (xy 96.93402 -221.133924)
			(xy 97.212912 -221.133924) (xy 97.213358 -221.108472) (xy 97.221146 -221.058168) (xy 97.236557 -221.009654)
			(xy 97.259227 -220.964077) (xy 97.288618 -220.922517) (xy 97.324036 -220.885956) (xy 97.364643 -220.855259)
			(xy 97.409476 -220.831154) (xy 97.457477 -220.81421) (xy 97.482406 -220.809058) (xy 97.505266 -220.80474)
			(xy 97.708974 -220.45168) (xy 97.701354 -220.429582) (xy 97.692614 -220.402995) (xy 97.683168 -220.347835)
			(xy 97.682558 -220.319854) (xy 97.683067 -220.293887) (xy 97.691192 -220.242592) (xy 97.70724 -220.193199)
			(xy 97.730818 -220.146925) (xy 97.761344 -220.104909) (xy 97.798067 -220.068186) (xy 97.840083 -220.03766)
			(xy 97.886357 -220.014082) (xy 97.93575 -219.998034) (xy 97.987045 -219.989909) (xy 98.038979 -219.989909)
			(xy 98.090274 -219.998034) (xy 98.139667 -220.014082) (xy 98.185941 -220.03766) (xy 98.227957 -220.068186)
			(xy 98.26468 -220.104909) (xy 98.295206 -220.146925) (xy 98.318784 -220.193199) (xy 98.334832 -220.242592)
			(xy 98.342957 -220.293887) (xy 98.343466 -220.319854) (xy 98.343018 -220.345306) (xy 98.342938 -220.345821)
			(xy 98.623121 -220.345821) (xy 98.623121 -220.293887) (xy 98.631246 -220.242592) (xy 98.647294 -220.193199)
			(xy 98.670872 -220.146925) (xy 98.701398 -220.104909) (xy 98.738121 -220.068186) (xy 98.780137 -220.03766)
			(xy 98.826411 -220.014082) (xy 98.875804 -219.998034) (xy 98.927099 -219.989909) (xy 98.979033 -219.989909)
			(xy 99.030328 -219.998034) (xy 99.079721 -220.014082) (xy 99.125995 -220.03766) (xy 99.168011 -220.068186)
			(xy 99.204734 -220.104909) (xy 99.23526 -220.146925) (xy 99.258838 -220.193199) (xy 99.274886 -220.242592)
			(xy 99.283011 -220.293887) (xy 99.28352 -220.319854) (xy 99.283011 -220.345821) (xy 99.274886 -220.397116)
			(xy 99.258838 -220.446509) (xy 99.23526 -220.492783) (xy 99.204734 -220.534799) (xy 99.168011 -220.571522)
			(xy 99.125995 -220.602048) (xy 99.079721 -220.625626) (xy 99.030328 -220.641674) (xy 98.979033 -220.649799)
			(xy 98.927099 -220.649799) (xy 98.875804 -220.641674) (xy 98.826411 -220.625626) (xy 98.780137 -220.602048)
			(xy 98.738121 -220.571522) (xy 98.701398 -220.534799) (xy 98.670872 -220.492783) (xy 98.647294 -220.446509)
			(xy 98.631246 -220.397116) (xy 98.623121 -220.345821) (xy 98.342938 -220.345821) (xy 98.335233 -220.395611)
			(xy 98.319823 -220.444126) (xy 98.297155 -220.489704) (xy 98.267763 -220.531265) (xy 98.232345 -220.567826)
			(xy 98.191738 -220.598523) (xy 98.146903 -220.622627) (xy 98.098902 -220.639569) (xy 98.073972 -220.64472)
			(xy 98.051112 -220.649038) (xy 97.847404 -221.002098) (xy 97.855024 -221.024196) (xy 97.863761 -221.050784)
			(xy 97.873209 -221.105943) (xy 97.87382 -221.133924) (xy 98.152712 -221.133924) (xy 98.153221 -221.107957)
			(xy 98.161346 -221.056662) (xy 98.177394 -221.007269) (xy 98.200972 -220.960995) (xy 98.231498 -220.918979)
			(xy 98.268221 -220.882256) (xy 98.310237 -220.85173) (xy 98.356511 -220.828152) (xy 98.405904 -220.812104)
			(xy 98.457199 -220.803979) (xy 98.509133 -220.803979) (xy 98.560428 -220.812104) (xy 98.609821 -220.828152)
			(xy 98.656095 -220.85173) (xy 98.698111 -220.882256) (xy 98.734834 -220.918979) (xy 98.76536 -220.960995)
			(xy 98.788938 -221.007269) (xy 98.804986 -221.056662) (xy 98.813111 -221.107957) (xy 98.81362 -221.133924)
			(xy 99.092512 -221.133924) (xy 99.092958 -221.108472) (xy 99.100746 -221.058168) (xy 99.116157 -221.009654)
			(xy 99.138827 -220.964077) (xy 99.168218 -220.922517) (xy 99.203636 -220.885956) (xy 99.244243 -220.855259)
			(xy 99.289076 -220.831154) (xy 99.337077 -220.81421) (xy 99.362006 -220.809058) (xy 99.384866 -220.80474)
			(xy 99.588574 -220.45168) (xy 99.580954 -220.429582) (xy 99.572214 -220.402995) (xy 99.562768 -220.347835)
			(xy 99.562158 -220.319854) (xy 99.562667 -220.293887) (xy 99.570792 -220.242592) (xy 99.58684 -220.193199)
			(xy 99.610418 -220.146925) (xy 99.640944 -220.104909) (xy 99.677667 -220.068186) (xy 99.719683 -220.03766)
			(xy 99.765957 -220.014082) (xy 99.81535 -219.998034) (xy 99.866645 -219.989909) (xy 99.918579 -219.989909)
			(xy 99.969874 -219.998034) (xy 100.019267 -220.014082) (xy 100.065541 -220.03766) (xy 100.107557 -220.068186)
			(xy 100.14428 -220.104909) (xy 100.174806 -220.146925) (xy 100.198384 -220.193199) (xy 100.214432 -220.242592)
			(xy 100.222557 -220.293887) (xy 100.223066 -220.319854) (xy 100.222618 -220.345306) (xy 100.222538 -220.345821)
			(xy 100.502721 -220.345821) (xy 100.502721 -220.293887) (xy 100.510846 -220.242592) (xy 100.526894 -220.193199)
			(xy 100.550472 -220.146925) (xy 100.580998 -220.104909) (xy 100.617721 -220.068186) (xy 100.659737 -220.03766)
			(xy 100.706011 -220.014082) (xy 100.755404 -219.998034) (xy 100.806699 -219.989909) (xy 100.858633 -219.989909)
			(xy 100.909928 -219.998034) (xy 100.959321 -220.014082) (xy 101.005595 -220.03766) (xy 101.047611 -220.068186)
			(xy 101.084334 -220.104909) (xy 101.11486 -220.146925) (xy 101.138438 -220.193199) (xy 101.154486 -220.242592)
			(xy 101.162611 -220.293887) (xy 101.16312 -220.319854) (xy 101.162611 -220.345821) (xy 101.154486 -220.397116)
			(xy 101.138438 -220.446509) (xy 101.11486 -220.492783) (xy 101.084334 -220.534799) (xy 101.047611 -220.571522)
			(xy 101.005595 -220.602048) (xy 100.959321 -220.625626) (xy 100.909928 -220.641674) (xy 100.858633 -220.649799)
			(xy 100.806699 -220.649799) (xy 100.755404 -220.641674) (xy 100.706011 -220.625626) (xy 100.659737 -220.602048)
			(xy 100.617721 -220.571522) (xy 100.580998 -220.534799) (xy 100.550472 -220.492783) (xy 100.526894 -220.446509)
			(xy 100.510846 -220.397116) (xy 100.502721 -220.345821) (xy 100.222538 -220.345821) (xy 100.214833 -220.395611)
			(xy 100.199423 -220.444126) (xy 100.176755 -220.489704) (xy 100.147363 -220.531265) (xy 100.111945 -220.567826)
			(xy 100.071338 -220.598523) (xy 100.026503 -220.622627) (xy 99.978502 -220.639569) (xy 99.953572 -220.64472)
			(xy 99.930712 -220.649038) (xy 99.727004 -221.002098) (xy 99.734624 -221.024196) (xy 99.743361 -221.050784)
			(xy 99.752809 -221.105943) (xy 99.75342 -221.133924) (xy 100.032312 -221.133924) (xy 100.032821 -221.107957)
			(xy 100.040946 -221.056662) (xy 100.056994 -221.007269) (xy 100.080572 -220.960995) (xy 100.111098 -220.918979)
			(xy 100.147821 -220.882256) (xy 100.189837 -220.85173) (xy 100.236111 -220.828152) (xy 100.285504 -220.812104)
			(xy 100.336799 -220.803979) (xy 100.388733 -220.803979) (xy 100.440028 -220.812104) (xy 100.489421 -220.828152)
			(xy 100.535695 -220.85173) (xy 100.577711 -220.882256) (xy 100.614434 -220.918979) (xy 100.64496 -220.960995)
			(xy 100.668538 -221.007269) (xy 100.684586 -221.056662) (xy 100.692711 -221.107957) (xy 100.69322 -221.133924)
			(xy 100.972112 -221.133924) (xy 100.972558 -221.108472) (xy 100.980346 -221.058168) (xy 100.995757 -221.009654)
			(xy 101.018427 -220.964077) (xy 101.047818 -220.922517) (xy 101.083236 -220.885956) (xy 101.123843 -220.855259)
			(xy 101.168676 -220.831154) (xy 101.216677 -220.81421) (xy 101.241606 -220.809058) (xy 101.264466 -220.80474)
			(xy 101.468174 -220.45168) (xy 101.460554 -220.429582) (xy 101.451814 -220.402995) (xy 101.442368 -220.347835)
			(xy 101.441758 -220.319854) (xy 101.442267 -220.293887) (xy 101.450392 -220.242592) (xy 101.46644 -220.193199)
			(xy 101.490018 -220.146925) (xy 101.520544 -220.104909) (xy 101.557267 -220.068186) (xy 101.599283 -220.03766)
			(xy 101.645557 -220.014082) (xy 101.69495 -219.998034) (xy 101.746245 -219.989909) (xy 101.798179 -219.989909)
			(xy 101.849474 -219.998034) (xy 101.898867 -220.014082) (xy 101.945141 -220.03766) (xy 101.987157 -220.068186)
			(xy 102.02388 -220.104909) (xy 102.054406 -220.146925) (xy 102.077984 -220.193199) (xy 102.094032 -220.242592)
			(xy 102.102157 -220.293887) (xy 102.102666 -220.319854) (xy 102.102218 -220.345306) (xy 102.102138 -220.345821)
			(xy 102.382321 -220.345821) (xy 102.382321 -220.293887) (xy 102.390446 -220.242592) (xy 102.406494 -220.193199)
			(xy 102.430072 -220.146925) (xy 102.460598 -220.104909) (xy 102.497321 -220.068186) (xy 102.539337 -220.03766)
			(xy 102.585611 -220.014082) (xy 102.635004 -219.998034) (xy 102.686299 -219.989909) (xy 102.738233 -219.989909)
			(xy 102.789528 -219.998034) (xy 102.838921 -220.014082) (xy 102.885195 -220.03766) (xy 102.927211 -220.068186)
			(xy 102.963934 -220.104909) (xy 102.99446 -220.146925) (xy 103.018038 -220.193199) (xy 103.034086 -220.242592)
			(xy 103.042211 -220.293887) (xy 103.04272 -220.319854) (xy 103.042211 -220.345821) (xy 103.034086 -220.397116)
			(xy 103.018038 -220.446509) (xy 102.99446 -220.492783) (xy 102.963934 -220.534799) (xy 102.927211 -220.571522)
			(xy 102.885195 -220.602048) (xy 102.838921 -220.625626) (xy 102.789528 -220.641674) (xy 102.738233 -220.649799)
			(xy 102.686299 -220.649799) (xy 102.635004 -220.641674) (xy 102.585611 -220.625626) (xy 102.539337 -220.602048)
			(xy 102.497321 -220.571522) (xy 102.460598 -220.534799) (xy 102.430072 -220.492783) (xy 102.406494 -220.446509)
			(xy 102.390446 -220.397116) (xy 102.382321 -220.345821) (xy 102.102138 -220.345821) (xy 102.094433 -220.395611)
			(xy 102.079023 -220.444126) (xy 102.056355 -220.489704) (xy 102.026963 -220.531265) (xy 101.991545 -220.567826)
			(xy 101.950938 -220.598523) (xy 101.906103 -220.622627) (xy 101.858102 -220.639569) (xy 101.833172 -220.64472)
			(xy 101.810312 -220.649038) (xy 101.606604 -221.002098) (xy 101.614224 -221.024196) (xy 101.622961 -221.050784)
			(xy 101.632409 -221.105943) (xy 101.63302 -221.133924) (xy 101.911912 -221.133924) (xy 101.912421 -221.107957)
			(xy 101.920546 -221.056662) (xy 101.936594 -221.007269) (xy 101.960172 -220.960995) (xy 101.990698 -220.918979)
			(xy 102.027421 -220.882256) (xy 102.069437 -220.85173) (xy 102.115711 -220.828152) (xy 102.165104 -220.812104)
			(xy 102.216399 -220.803979) (xy 102.268333 -220.803979) (xy 102.319628 -220.812104) (xy 102.369021 -220.828152)
			(xy 102.415295 -220.85173) (xy 102.457311 -220.882256) (xy 102.494034 -220.918979) (xy 102.52456 -220.960995)
			(xy 102.548138 -221.007269) (xy 102.564186 -221.056662) (xy 102.572311 -221.107957) (xy 102.57282 -221.133924)
			(xy 102.572272 -221.16191) (xy 102.562819 -221.217078) (xy 102.554024 -221.243652) (xy 102.546404 -221.26575)
			(xy 102.750112 -221.618556) (xy 102.772972 -221.622874) (xy 102.7979 -221.628011) (xy 102.845885 -221.644981)
			(xy 102.890703 -221.669103) (xy 102.931295 -221.699808) (xy 102.966703 -221.736369) (xy 102.99609 -221.777925)
			(xy 103.018763 -221.823493) (xy 103.034185 -221.871997) (xy 103.041993 -221.922292) (xy 103.042466 -221.94774)
			(xy 103.041957 -221.973707) (xy 103.033832 -222.025002) (xy 103.017784 -222.074395) (xy 102.994206 -222.120669)
			(xy 102.96368 -222.162685) (xy 102.926957 -222.199408) (xy 102.884941 -222.229934) (xy 102.838667 -222.253512)
			(xy 102.789274 -222.26956) (xy 102.737979 -222.277685) (xy 102.686045 -222.277685) (xy 102.63475 -222.26956)
			(xy 102.585357 -222.253512) (xy 102.539083 -222.229934) (xy 102.497067 -222.199408) (xy 102.460344 -222.162685)
			(xy 102.429818 -222.120669) (xy 102.40624 -222.074395) (xy 102.390192 -222.025002) (xy 102.382067 -221.973707)
			(xy 102.381558 -221.94774) (xy 102.382118 -221.919754) (xy 102.391563 -221.864587) (xy 102.400354 -221.838012)
			(xy 102.407974 -221.815914) (xy 102.204266 -221.463108) (xy 102.181406 -221.45879) (xy 102.156482 -221.45363)
			(xy 102.108495 -221.436669) (xy 102.063674 -221.412553) (xy 102.023079 -221.381853) (xy 101.987668 -221.345294)
			(xy 101.95828 -221.303739) (xy 101.935607 -221.258171) (xy 101.920187 -221.209667) (xy 101.912382 -221.159372)
			(xy 101.911912 -221.133924) (xy 101.63302 -221.133924) (xy 101.632511 -221.159891) (xy 101.624386 -221.211186)
			(xy 101.608338 -221.260579) (xy 101.58476 -221.306853) (xy 101.554234 -221.348869) (xy 101.517511 -221.385592)
			(xy 101.475495 -221.416118) (xy 101.429221 -221.439696) (xy 101.379828 -221.455744) (xy 101.328533 -221.463869)
			(xy 101.276599 -221.463869) (xy 101.225304 -221.455744) (xy 101.175911 -221.439696) (xy 101.129637 -221.416118)
			(xy 101.087621 -221.385592) (xy 101.050898 -221.348869) (xy 101.020372 -221.306853) (xy 100.996794 -221.260579)
			(xy 100.980746 -221.211186) (xy 100.972621 -221.159891) (xy 100.972112 -221.133924) (xy 100.69322 -221.133924)
			(xy 100.692672 -221.16191) (xy 100.683219 -221.217078) (xy 100.674424 -221.243652) (xy 100.666804 -221.26575)
			(xy 100.870512 -221.618556) (xy 100.893372 -221.622874) (xy 100.9183 -221.628011) (xy 100.966285 -221.644981)
			(xy 101.011103 -221.669103) (xy 101.051695 -221.699808) (xy 101.087103 -221.736369) (xy 101.11649 -221.777925)
			(xy 101.139163 -221.823493) (xy 101.154585 -221.871997) (xy 101.162393 -221.922292) (xy 101.162866 -221.94774)
			(xy 101.162357 -221.973707) (xy 101.442267 -221.973707) (xy 101.442267 -221.921773) (xy 101.450392 -221.870478)
			(xy 101.46644 -221.821085) (xy 101.490018 -221.774811) (xy 101.520544 -221.732795) (xy 101.557267 -221.696072)
			(xy 101.599283 -221.665546) (xy 101.645557 -221.641968) (xy 101.69495 -221.62592) (xy 101.746245 -221.617795)
			(xy 101.798179 -221.617795) (xy 101.849474 -221.62592) (xy 101.898867 -221.641968) (xy 101.945141 -221.665546)
			(xy 101.987157 -221.696072) (xy 102.02388 -221.732795) (xy 102.054406 -221.774811) (xy 102.077984 -221.821085)
			(xy 102.094032 -221.870478) (xy 102.102157 -221.921773) (xy 102.102666 -221.94774) (xy 102.102157 -221.973707)
			(xy 102.094032 -222.025002) (xy 102.077984 -222.074395) (xy 102.054406 -222.120669) (xy 102.02388 -222.162685)
			(xy 101.987157 -222.199408) (xy 101.945141 -222.229934) (xy 101.898867 -222.253512) (xy 101.849474 -222.26956)
			(xy 101.798179 -222.277685) (xy 101.746245 -222.277685) (xy 101.69495 -222.26956) (xy 101.645557 -222.253512)
			(xy 101.599283 -222.229934) (xy 101.557267 -222.199408) (xy 101.520544 -222.162685) (xy 101.490018 -222.120669)
			(xy 101.46644 -222.074395) (xy 101.450392 -222.025002) (xy 101.442267 -221.973707) (xy 101.162357 -221.973707)
			(xy 101.154232 -222.025002) (xy 101.138184 -222.074395) (xy 101.114606 -222.120669) (xy 101.08408 -222.162685)
			(xy 101.047357 -222.199408) (xy 101.005341 -222.229934) (xy 100.959067 -222.253512) (xy 100.909674 -222.26956)
			(xy 100.858379 -222.277685) (xy 100.806445 -222.277685) (xy 100.75515 -222.26956) (xy 100.705757 -222.253512)
			(xy 100.659483 -222.229934) (xy 100.617467 -222.199408) (xy 100.580744 -222.162685) (xy 100.550218 -222.120669)
			(xy 100.52664 -222.074395) (xy 100.510592 -222.025002) (xy 100.502467 -221.973707) (xy 100.501958 -221.94774)
			(xy 100.502518 -221.919754) (xy 100.511963 -221.864587) (xy 100.520754 -221.838012) (xy 100.528374 -221.815914)
			(xy 100.324666 -221.463108) (xy 100.301806 -221.45879) (xy 100.276882 -221.45363) (xy 100.228895 -221.436669)
			(xy 100.184074 -221.412553) (xy 100.143479 -221.381853) (xy 100.108068 -221.345294) (xy 100.07868 -221.303739)
			(xy 100.056007 -221.258171) (xy 100.040587 -221.209667) (xy 100.032782 -221.159372) (xy 100.032312 -221.133924)
			(xy 99.75342 -221.133924) (xy 99.752911 -221.159891) (xy 99.744786 -221.211186) (xy 99.728738 -221.260579)
			(xy 99.70516 -221.306853) (xy 99.674634 -221.348869) (xy 99.637911 -221.385592) (xy 99.595895 -221.416118)
			(xy 99.549621 -221.439696) (xy 99.500228 -221.455744) (xy 99.448933 -221.463869) (xy 99.396999 -221.463869)
			(xy 99.345704 -221.455744) (xy 99.296311 -221.439696) (xy 99.250037 -221.416118) (xy 99.208021 -221.385592)
			(xy 99.171298 -221.348869) (xy 99.140772 -221.306853) (xy 99.117194 -221.260579) (xy 99.101146 -221.211186)
			(xy 99.093021 -221.159891) (xy 99.092512 -221.133924) (xy 98.81362 -221.133924) (xy 98.813072 -221.16191)
			(xy 98.803619 -221.217078) (xy 98.794824 -221.243652) (xy 98.787204 -221.26575) (xy 98.990912 -221.618556)
			(xy 99.013772 -221.622874) (xy 99.0387 -221.628011) (xy 99.086685 -221.644981) (xy 99.131503 -221.669103)
			(xy 99.172095 -221.699808) (xy 99.207503 -221.736369) (xy 99.23689 -221.777925) (xy 99.259563 -221.823493)
			(xy 99.274985 -221.871997) (xy 99.282793 -221.922292) (xy 99.283266 -221.94774) (xy 99.282757 -221.973707)
			(xy 99.274632 -222.025002) (xy 99.258584 -222.074395) (xy 99.235006 -222.120669) (xy 99.20448 -222.162685)
			(xy 99.167757 -222.199408) (xy 99.125741 -222.229934) (xy 99.079467 -222.253512) (xy 99.030074 -222.26956)
			(xy 98.978779 -222.277685) (xy 98.926845 -222.277685) (xy 98.87555 -222.26956) (xy 98.826157 -222.253512)
			(xy 98.779883 -222.229934) (xy 98.737867 -222.199408) (xy 98.701144 -222.162685) (xy 98.670618 -222.120669)
			(xy 98.64704 -222.074395) (xy 98.630992 -222.025002) (xy 98.622867 -221.973707) (xy 98.622358 -221.94774)
			(xy 98.622918 -221.919754) (xy 98.632363 -221.864587) (xy 98.641154 -221.838012) (xy 98.648774 -221.815914)
			(xy 98.445066 -221.463108) (xy 98.422206 -221.45879) (xy 98.397282 -221.45363) (xy 98.349295 -221.436669)
			(xy 98.304474 -221.412553) (xy 98.263879 -221.381853) (xy 98.228468 -221.345294) (xy 98.19908 -221.303739)
			(xy 98.176407 -221.258171) (xy 98.160987 -221.209667) (xy 98.153182 -221.159372) (xy 98.152712 -221.133924)
			(xy 97.87382 -221.133924) (xy 97.873311 -221.159891) (xy 97.865186 -221.211186) (xy 97.849138 -221.260579)
			(xy 97.82556 -221.306853) (xy 97.795034 -221.348869) (xy 97.758311 -221.385592) (xy 97.716295 -221.416118)
			(xy 97.670021 -221.439696) (xy 97.620628 -221.455744) (xy 97.569333 -221.463869) (xy 97.517399 -221.463869)
			(xy 97.466104 -221.455744) (xy 97.416711 -221.439696) (xy 97.370437 -221.416118) (xy 97.328421 -221.385592)
			(xy 97.291698 -221.348869) (xy 97.261172 -221.306853) (xy 97.237594 -221.260579) (xy 97.221546 -221.211186)
			(xy 97.213421 -221.159891) (xy 97.212912 -221.133924) (xy 96.93402 -221.133924) (xy 96.933472 -221.16191)
			(xy 96.924019 -221.217078) (xy 96.915224 -221.243652) (xy 96.907604 -221.26575) (xy 97.111312 -221.618556)
			(xy 97.134172 -221.622874) (xy 97.1591 -221.628011) (xy 97.207085 -221.644981) (xy 97.251903 -221.669103)
			(xy 97.292495 -221.699808) (xy 97.327903 -221.736369) (xy 97.35729 -221.777925) (xy 97.379963 -221.823493)
			(xy 97.395385 -221.871997) (xy 97.403193 -221.922292) (xy 97.403666 -221.94774) (xy 97.403157 -221.973707)
			(xy 97.395032 -222.025002) (xy 97.378984 -222.074395) (xy 97.355406 -222.120669) (xy 97.32488 -222.162685)
			(xy 97.288157 -222.199408) (xy 97.246141 -222.229934) (xy 97.199867 -222.253512) (xy 97.150474 -222.26956)
			(xy 97.099179 -222.277685) (xy 97.047245 -222.277685) (xy 96.99595 -222.26956) (xy 96.946557 -222.253512)
			(xy 96.900283 -222.229934) (xy 96.858267 -222.199408) (xy 96.821544 -222.162685) (xy 96.791018 -222.120669)
			(xy 96.76744 -222.074395) (xy 96.751392 -222.025002) (xy 96.743267 -221.973707) (xy 96.742758 -221.94774)
			(xy 96.743318 -221.919754) (xy 96.752763 -221.864587) (xy 96.761554 -221.838012) (xy 96.769174 -221.815914)
			(xy 96.565466 -221.463108) (xy 96.542606 -221.45879) (xy 96.517682 -221.45363) (xy 96.469695 -221.436669)
			(xy 96.424874 -221.412553) (xy 96.384279 -221.381853) (xy 96.348868 -221.345294) (xy 96.31948 -221.303739)
			(xy 96.296807 -221.258171) (xy 96.281387 -221.209667) (xy 96.273582 -221.159372) (xy 96.273112 -221.133924)
			(xy 95.99422 -221.133924) (xy 95.993711 -221.159891) (xy 95.985586 -221.211186) (xy 95.969538 -221.260579)
			(xy 95.94596 -221.306853) (xy 95.915434 -221.348869) (xy 95.878711 -221.385592) (xy 95.836695 -221.416118)
			(xy 95.790421 -221.439696) (xy 95.741028 -221.455744) (xy 95.689733 -221.463869) (xy 95.637799 -221.463869)
			(xy 95.586504 -221.455744) (xy 95.537111 -221.439696) (xy 95.490837 -221.416118) (xy 95.448821 -221.385592)
			(xy 95.412098 -221.348869) (xy 95.381572 -221.306853) (xy 95.357994 -221.260579) (xy 95.341946 -221.211186)
			(xy 95.333821 -221.159891) (xy 95.333312 -221.133924) (xy 95.05442 -221.133924) (xy 95.053872 -221.16191)
			(xy 95.044419 -221.217078) (xy 95.035624 -221.243652) (xy 95.028004 -221.26575) (xy 95.231712 -221.618556)
			(xy 95.254572 -221.622874) (xy 95.2795 -221.628011) (xy 95.327485 -221.644981) (xy 95.372303 -221.669103)
			(xy 95.412895 -221.699808) (xy 95.448303 -221.736369) (xy 95.47769 -221.777925) (xy 95.500363 -221.823493)
			(xy 95.515785 -221.871997) (xy 95.523593 -221.922292) (xy 95.524066 -221.94774) (xy 95.523557 -221.973707)
			(xy 95.515432 -222.025002) (xy 95.499384 -222.074395) (xy 95.475806 -222.120669) (xy 95.44528 -222.162685)
			(xy 95.408557 -222.199408) (xy 95.366541 -222.229934) (xy 95.320267 -222.253512) (xy 95.270874 -222.26956)
			(xy 95.219579 -222.277685) (xy 95.167645 -222.277685) (xy 95.11635 -222.26956) (xy 95.066957 -222.253512)
			(xy 95.020683 -222.229934) (xy 94.978667 -222.199408) (xy 94.941944 -222.162685) (xy 94.911418 -222.120669)
			(xy 94.88784 -222.074395) (xy 94.871792 -222.025002) (xy 94.863667 -221.973707) (xy 94.863158 -221.94774)
			(xy 94.863718 -221.919754) (xy 94.873163 -221.864587) (xy 94.881954 -221.838012) (xy 94.889574 -221.815914)
			(xy 94.685866 -221.463108) (xy 94.663006 -221.45879) (xy 94.638082 -221.45363) (xy 94.590095 -221.436669)
			(xy 94.545274 -221.412553) (xy 94.504679 -221.381853) (xy 94.469268 -221.345294) (xy 94.43988 -221.303739)
			(xy 94.417207 -221.258171) (xy 94.401787 -221.209667) (xy 94.393982 -221.159372) (xy 94.393512 -221.133924)
			(xy 94.11462 -221.133924) (xy 94.114111 -221.159891) (xy 94.105986 -221.211186) (xy 94.089938 -221.260579)
			(xy 94.06636 -221.306853) (xy 94.035834 -221.348869) (xy 93.999111 -221.385592) (xy 93.957095 -221.416118)
			(xy 93.910821 -221.439696) (xy 93.861428 -221.455744) (xy 93.810133 -221.463869) (xy 93.758199 -221.463869)
			(xy 93.706904 -221.455744) (xy 93.657511 -221.439696) (xy 93.611237 -221.416118) (xy 93.569221 -221.385592)
			(xy 93.532498 -221.348869) (xy 93.501972 -221.306853) (xy 93.478394 -221.260579) (xy 93.462346 -221.211186)
			(xy 93.454221 -221.159891) (xy 93.453712 -221.133924) (xy 93.17482 -221.133924) (xy 93.174272 -221.16191)
			(xy 93.164819 -221.217078) (xy 93.156024 -221.243652) (xy 93.148404 -221.26575) (xy 93.352112 -221.618556)
			(xy 93.374972 -221.622874) (xy 93.3999 -221.628011) (xy 93.447885 -221.644981) (xy 93.492703 -221.669103)
			(xy 93.533295 -221.699808) (xy 93.568703 -221.736369) (xy 93.59809 -221.777925) (xy 93.620763 -221.823493)
			(xy 93.636185 -221.871997) (xy 93.643993 -221.922292) (xy 93.644466 -221.94774) (xy 93.643957 -221.973707)
			(xy 93.635832 -222.025002) (xy 93.619784 -222.074395) (xy 93.596206 -222.120669) (xy 93.56568 -222.162685)
			(xy 93.528957 -222.199408) (xy 93.486941 -222.229934) (xy 93.440667 -222.253512) (xy 93.391274 -222.26956)
			(xy 93.339979 -222.277685) (xy 93.288045 -222.277685) (xy 93.23675 -222.26956) (xy 93.187357 -222.253512)
			(xy 93.141083 -222.229934) (xy 93.099067 -222.199408) (xy 93.062344 -222.162685) (xy 93.031818 -222.120669)
			(xy 93.00824 -222.074395) (xy 92.992192 -222.025002) (xy 92.984067 -221.973707) (xy 92.983558 -221.94774)
			(xy 92.984118 -221.919754) (xy 92.993563 -221.864587) (xy 93.002354 -221.838012) (xy 93.009974 -221.815914)
			(xy 92.806266 -221.463108) (xy 92.783406 -221.45879) (xy 92.758482 -221.45363) (xy 92.710495 -221.436669)
			(xy 92.665674 -221.412553) (xy 92.625079 -221.381853) (xy 92.589668 -221.345294) (xy 92.56028 -221.303739)
			(xy 92.537607 -221.258171) (xy 92.522187 -221.209667) (xy 92.514382 -221.159372) (xy 92.513912 -221.133924)
			(xy 92.23502 -221.133924) (xy 92.234511 -221.159891) (xy 92.226386 -221.211186) (xy 92.210338 -221.260579)
			(xy 92.18676 -221.306853) (xy 92.156234 -221.348869) (xy 92.119511 -221.385592) (xy 92.077495 -221.416118)
			(xy 92.031221 -221.439696) (xy 91.981828 -221.455744) (xy 91.930533 -221.463869) (xy 91.878599 -221.463869)
			(xy 91.827304 -221.455744) (xy 91.777911 -221.439696) (xy 91.731637 -221.416118) (xy 91.689621 -221.385592)
			(xy 91.652898 -221.348869) (xy 91.622372 -221.306853) (xy 91.598794 -221.260579) (xy 91.582746 -221.211186)
			(xy 91.574621 -221.159891) (xy 91.574112 -221.133924) (xy 91.29522 -221.133924) (xy 91.294672 -221.16191)
			(xy 91.285219 -221.217078) (xy 91.276424 -221.243652) (xy 91.268804 -221.26575) (xy 91.472512 -221.618556)
			(xy 91.495372 -221.622874) (xy 91.5203 -221.628011) (xy 91.568285 -221.644981) (xy 91.613103 -221.669103)
			(xy 91.653695 -221.699808) (xy 91.689103 -221.736369) (xy 91.71849 -221.777925) (xy 91.741163 -221.823493)
			(xy 91.756585 -221.871997) (xy 91.764393 -221.922292) (xy 91.764866 -221.94774) (xy 91.764357 -221.973707)
			(xy 91.756232 -222.025002) (xy 91.740184 -222.074395) (xy 91.716606 -222.120669) (xy 91.68608 -222.162685)
			(xy 91.649357 -222.199408) (xy 91.607341 -222.229934) (xy 91.561067 -222.253512) (xy 91.511674 -222.26956)
			(xy 91.460379 -222.277685) (xy 91.408445 -222.277685) (xy 91.35715 -222.26956) (xy 91.307757 -222.253512)
			(xy 91.261483 -222.229934) (xy 91.219467 -222.199408) (xy 91.182744 -222.162685) (xy 91.152218 -222.120669)
			(xy 91.12864 -222.074395) (xy 91.112592 -222.025002) (xy 91.104467 -221.973707) (xy 91.103958 -221.94774)
			(xy 91.104518 -221.919754) (xy 91.113963 -221.864587) (xy 91.122754 -221.838012) (xy 91.130374 -221.815914)
			(xy 90.926666 -221.463108) (xy 90.903806 -221.45879) (xy 90.878882 -221.45363) (xy 90.830895 -221.436669)
			(xy 90.786074 -221.412553) (xy 90.745479 -221.381853) (xy 90.710068 -221.345294) (xy 90.68068 -221.303739)
			(xy 90.658007 -221.258171) (xy 90.642587 -221.209667) (xy 90.634782 -221.159372) (xy 90.634312 -221.133924)
			(xy 90.35542 -221.133924) (xy 90.354911 -221.159891) (xy 90.346786 -221.211186) (xy 90.330738 -221.260579)
			(xy 90.30716 -221.306853) (xy 90.276634 -221.348869) (xy 90.239911 -221.385592) (xy 90.197895 -221.416118)
			(xy 90.151621 -221.439696) (xy 90.102228 -221.455744) (xy 90.050933 -221.463869) (xy 89.998999 -221.463869)
			(xy 89.947704 -221.455744) (xy 89.898311 -221.439696) (xy 89.852037 -221.416118) (xy 89.810021 -221.385592)
			(xy 89.773298 -221.348869) (xy 89.742772 -221.306853) (xy 89.719194 -221.260579) (xy 89.703146 -221.211186)
			(xy 89.695021 -221.159891) (xy 89.694512 -221.133924) (xy 89.41562 -221.133924) (xy 89.415005 -221.161904)
			(xy 89.40555 -221.21706) (xy 89.396824 -221.243652) (xy 89.389204 -221.26575) (xy 89.592912 -221.618556)
			(xy 89.615772 -221.622874) (xy 89.640315 -221.627951) (xy 89.687614 -221.644523) (xy 89.731869 -221.668045)
			(xy 89.772066 -221.697976) (xy 89.807285 -221.733633) (xy 89.836719 -221.774197) (xy 89.859693 -221.818738)
			(xy 89.87568 -221.866237) (xy 89.88044 -221.890844) (xy 89.883454 -221.90528) (xy 89.896598 -221.931666)
			(xy 89.916744 -221.953186) (xy 89.942206 -221.968041) (xy 89.970854 -221.974989) (xy 89.985596 -221.974664)
			(xy 90.026658 -221.973139) (xy 90.10871 -221.977595) (xy 90.189853 -221.99057) (xy 90.269204 -222.011923)
			(xy 90.3459 -222.041422) (xy 90.419108 -222.078746) (xy 90.488032 -222.12349) (xy 90.551923 -222.175166)
			(xy 90.610086 -222.233214) (xy 90.661889 -222.297002) (xy 90.706769 -222.365836) (xy 90.726006 -222.402146)
			(xy 90.733174 -222.41502) (xy 90.753547 -222.436291) (xy 90.77914 -222.450868) (xy 90.807827 -222.457542)
			(xy 90.837226 -222.455758) (xy 90.851228 -222.451168) (xy 90.87862 -222.441853) (xy 90.935587 -222.431771)
			(xy 90.964512 -222.431102) (xy 90.964766 -222.431102) (xy 90.990736 -222.431609) (xy 91.042038 -222.439729)
			(xy 91.091438 -222.455774) (xy 91.13772 -222.479349) (xy 91.179744 -222.509874) (xy 91.216476 -222.546597)
			(xy 91.24701 -222.588614) (xy 91.270597 -222.63489) (xy 91.286653 -222.684286) (xy 91.294785 -222.735586)
			(xy 91.29522 -222.761556) (xy 91.294788 -222.785639) (xy 91.294512 -222.787523) (xy 91.574621 -222.787523)
			(xy 91.574621 -222.735589) (xy 91.582746 -222.684294) (xy 91.598794 -222.634901) (xy 91.622372 -222.588627)
			(xy 91.652898 -222.546611) (xy 91.689621 -222.509888) (xy 91.731637 -222.479362) (xy 91.777911 -222.455784)
			(xy 91.827304 -222.439736) (xy 91.878599 -222.431611) (xy 91.930533 -222.431611) (xy 91.981828 -222.439736)
			(xy 92.031221 -222.455784) (xy 92.077495 -222.479362) (xy 92.119511 -222.509888) (xy 92.156234 -222.546611)
			(xy 92.18676 -222.588627) (xy 92.210338 -222.634901) (xy 92.226386 -222.684294) (xy 92.234511 -222.735589)
			(xy 92.23502 -222.761556) (xy 92.234511 -222.787523) (xy 92.514421 -222.787523) (xy 92.514421 -222.735589)
			(xy 92.522546 -222.684294) (xy 92.538594 -222.634901) (xy 92.562172 -222.588627) (xy 92.592698 -222.546611)
			(xy 92.629421 -222.509888) (xy 92.671437 -222.479362) (xy 92.717711 -222.455784) (xy 92.767104 -222.439736)
			(xy 92.818399 -222.431611) (xy 92.870333 -222.431611) (xy 92.921628 -222.439736) (xy 92.971021 -222.455784)
			(xy 93.017295 -222.479362) (xy 93.059311 -222.509888) (xy 93.096034 -222.546611) (xy 93.12656 -222.588627)
			(xy 93.150138 -222.634901) (xy 93.166186 -222.684294) (xy 93.174311 -222.735589) (xy 93.17482 -222.761556)
			(xy 93.174311 -222.787523) (xy 93.454221 -222.787523) (xy 93.454221 -222.735589) (xy 93.462346 -222.684294)
			(xy 93.478394 -222.634901) (xy 93.501972 -222.588627) (xy 93.532498 -222.546611) (xy 93.569221 -222.509888)
			(xy 93.611237 -222.479362) (xy 93.657511 -222.455784) (xy 93.706904 -222.439736) (xy 93.758199 -222.431611)
			(xy 93.810133 -222.431611) (xy 93.861428 -222.439736) (xy 93.910821 -222.455784) (xy 93.957095 -222.479362)
			(xy 93.999111 -222.509888) (xy 94.035834 -222.546611) (xy 94.06636 -222.588627) (xy 94.089938 -222.634901)
			(xy 94.105986 -222.684294) (xy 94.114111 -222.735589) (xy 94.11462 -222.761556) (xy 94.114111 -222.787523)
			(xy 94.394021 -222.787523) (xy 94.394021 -222.735589) (xy 94.402146 -222.684294) (xy 94.418194 -222.634901)
			(xy 94.441772 -222.588627) (xy 94.472298 -222.546611) (xy 94.509021 -222.509888) (xy 94.551037 -222.479362)
			(xy 94.597311 -222.455784) (xy 94.646704 -222.439736) (xy 94.697999 -222.431611) (xy 94.749933 -222.431611)
			(xy 94.801228 -222.439736) (xy 94.850621 -222.455784) (xy 94.896895 -222.479362) (xy 94.938911 -222.509888)
			(xy 94.975634 -222.546611) (xy 95.00616 -222.588627) (xy 95.029738 -222.634901) (xy 95.045786 -222.684294)
			(xy 95.053911 -222.735589) (xy 95.05442 -222.761556) (xy 95.053911 -222.787523) (xy 95.333821 -222.787523)
			(xy 95.333821 -222.735589) (xy 95.341946 -222.684294) (xy 95.357994 -222.634901) (xy 95.381572 -222.588627)
			(xy 95.412098 -222.546611) (xy 95.448821 -222.509888) (xy 95.490837 -222.479362) (xy 95.537111 -222.455784)
			(xy 95.586504 -222.439736) (xy 95.637799 -222.431611) (xy 95.689733 -222.431611) (xy 95.741028 -222.439736)
			(xy 95.790421 -222.455784) (xy 95.836695 -222.479362) (xy 95.878711 -222.509888) (xy 95.915434 -222.546611)
			(xy 95.94596 -222.588627) (xy 95.969538 -222.634901) (xy 95.985586 -222.684294) (xy 95.993711 -222.735589)
			(xy 95.99422 -222.761556) (xy 95.993711 -222.787523) (xy 96.273621 -222.787523) (xy 96.273621 -222.735589)
			(xy 96.281746 -222.684294) (xy 96.297794 -222.634901) (xy 96.321372 -222.588627) (xy 96.351898 -222.546611)
			(xy 96.388621 -222.509888) (xy 96.430637 -222.479362) (xy 96.476911 -222.455784) (xy 96.526304 -222.439736)
			(xy 96.577599 -222.431611) (xy 96.629533 -222.431611) (xy 96.680828 -222.439736) (xy 96.730221 -222.455784)
			(xy 96.776495 -222.479362) (xy 96.818511 -222.509888) (xy 96.855234 -222.546611) (xy 96.88576 -222.588627)
			(xy 96.909338 -222.634901) (xy 96.925386 -222.684294) (xy 96.933511 -222.735589) (xy 96.93402 -222.761556)
			(xy 96.933511 -222.787523) (xy 97.213421 -222.787523) (xy 97.213421 -222.735589) (xy 97.221546 -222.684294)
			(xy 97.237594 -222.634901) (xy 97.261172 -222.588627) (xy 97.291698 -222.546611) (xy 97.328421 -222.509888)
			(xy 97.370437 -222.479362) (xy 97.416711 -222.455784) (xy 97.466104 -222.439736) (xy 97.517399 -222.431611)
			(xy 97.569333 -222.431611) (xy 97.620628 -222.439736) (xy 97.670021 -222.455784) (xy 97.716295 -222.479362)
			(xy 97.758311 -222.509888) (xy 97.795034 -222.546611) (xy 97.82556 -222.588627) (xy 97.849138 -222.634901)
			(xy 97.865186 -222.684294) (xy 97.873311 -222.735589) (xy 97.87382 -222.761556) (xy 97.873311 -222.787523)
			(xy 98.153221 -222.787523) (xy 98.153221 -222.735589) (xy 98.161346 -222.684294) (xy 98.177394 -222.634901)
			(xy 98.200972 -222.588627) (xy 98.231498 -222.546611) (xy 98.268221 -222.509888) (xy 98.310237 -222.479362)
			(xy 98.356511 -222.455784) (xy 98.405904 -222.439736) (xy 98.457199 -222.431611) (xy 98.509133 -222.431611)
			(xy 98.560428 -222.439736) (xy 98.609821 -222.455784) (xy 98.656095 -222.479362) (xy 98.698111 -222.509888)
			(xy 98.734834 -222.546611) (xy 98.76536 -222.588627) (xy 98.788938 -222.634901) (xy 98.804986 -222.684294)
			(xy 98.813111 -222.735589) (xy 98.81362 -222.761556) (xy 98.813111 -222.787523) (xy 99.093021 -222.787523)
			(xy 99.093021 -222.735589) (xy 99.101146 -222.684294) (xy 99.117194 -222.634901) (xy 99.140772 -222.588627)
			(xy 99.171298 -222.546611) (xy 99.208021 -222.509888) (xy 99.250037 -222.479362) (xy 99.296311 -222.455784)
			(xy 99.345704 -222.439736) (xy 99.396999 -222.431611) (xy 99.448933 -222.431611) (xy 99.500228 -222.439736)
			(xy 99.549621 -222.455784) (xy 99.595895 -222.479362) (xy 99.637911 -222.509888) (xy 99.674634 -222.546611)
			(xy 99.70516 -222.588627) (xy 99.728738 -222.634901) (xy 99.744786 -222.684294) (xy 99.752911 -222.735589)
			(xy 99.75342 -222.761556) (xy 99.752911 -222.787523) (xy 100.032821 -222.787523) (xy 100.032821 -222.735589)
			(xy 100.040946 -222.684294) (xy 100.056994 -222.634901) (xy 100.080572 -222.588627) (xy 100.111098 -222.546611)
			(xy 100.147821 -222.509888) (xy 100.189837 -222.479362) (xy 100.236111 -222.455784) (xy 100.285504 -222.439736)
			(xy 100.336799 -222.431611) (xy 100.388733 -222.431611) (xy 100.440028 -222.439736) (xy 100.489421 -222.455784)
			(xy 100.535695 -222.479362) (xy 100.577711 -222.509888) (xy 100.614434 -222.546611) (xy 100.64496 -222.588627)
			(xy 100.668538 -222.634901) (xy 100.684586 -222.684294) (xy 100.692711 -222.735589) (xy 100.69322 -222.761556)
			(xy 100.692711 -222.787523) (xy 100.972621 -222.787523) (xy 100.972621 -222.735589) (xy 100.980746 -222.684294)
			(xy 100.996794 -222.634901) (xy 101.020372 -222.588627) (xy 101.050898 -222.546611) (xy 101.087621 -222.509888)
			(xy 101.129637 -222.479362) (xy 101.175911 -222.455784) (xy 101.225304 -222.439736) (xy 101.276599 -222.431611)
			(xy 101.328533 -222.431611) (xy 101.379828 -222.439736) (xy 101.429221 -222.455784) (xy 101.475495 -222.479362)
			(xy 101.517511 -222.509888) (xy 101.554234 -222.546611) (xy 101.58476 -222.588627) (xy 101.608338 -222.634901)
			(xy 101.624386 -222.684294) (xy 101.632511 -222.735589) (xy 101.63302 -222.761556) (xy 101.632511 -222.787523)
			(xy 101.912421 -222.787523) (xy 101.912421 -222.735589) (xy 101.920546 -222.684294) (xy 101.936594 -222.634901)
			(xy 101.960172 -222.588627) (xy 101.990698 -222.546611) (xy 102.027421 -222.509888) (xy 102.069437 -222.479362)
			(xy 102.115711 -222.455784) (xy 102.165104 -222.439736) (xy 102.216399 -222.431611) (xy 102.268333 -222.431611)
			(xy 102.319628 -222.439736) (xy 102.369021 -222.455784) (xy 102.415295 -222.479362) (xy 102.457311 -222.509888)
			(xy 102.494034 -222.546611) (xy 102.52456 -222.588627) (xy 102.548138 -222.634901) (xy 102.564186 -222.684294)
			(xy 102.572311 -222.735589) (xy 102.57282 -222.761556) (xy 102.572311 -222.787523) (xy 102.564186 -222.838818)
			(xy 102.548138 -222.888211) (xy 102.52456 -222.934485) (xy 102.494034 -222.976501) (xy 102.457311 -223.013224)
			(xy 102.415295 -223.04375) (xy 102.369021 -223.067328) (xy 102.319628 -223.083376) (xy 102.268333 -223.091501)
			(xy 102.216399 -223.091501) (xy 102.165104 -223.083376) (xy 102.115711 -223.067328) (xy 102.069437 -223.04375)
			(xy 102.027421 -223.013224) (xy 101.990698 -222.976501) (xy 101.960172 -222.934485) (xy 101.936594 -222.888211)
			(xy 101.920546 -222.838818) (xy 101.912421 -222.787523) (xy 101.632511 -222.787523) (xy 101.624386 -222.838818)
			(xy 101.608338 -222.888211) (xy 101.58476 -222.934485) (xy 101.554234 -222.976501) (xy 101.517511 -223.013224)
			(xy 101.475495 -223.04375) (xy 101.429221 -223.067328) (xy 101.379828 -223.083376) (xy 101.328533 -223.091501)
			(xy 101.276599 -223.091501) (xy 101.225304 -223.083376) (xy 101.175911 -223.067328) (xy 101.129637 -223.04375)
			(xy 101.087621 -223.013224) (xy 101.050898 -222.976501) (xy 101.020372 -222.934485) (xy 100.996794 -222.888211)
			(xy 100.980746 -222.838818) (xy 100.972621 -222.787523) (xy 100.692711 -222.787523) (xy 100.684586 -222.838818)
			(xy 100.668538 -222.888211) (xy 100.64496 -222.934485) (xy 100.614434 -222.976501) (xy 100.577711 -223.013224)
			(xy 100.535695 -223.04375) (xy 100.489421 -223.067328) (xy 100.440028 -223.083376) (xy 100.388733 -223.091501)
			(xy 100.336799 -223.091501) (xy 100.285504 -223.083376) (xy 100.236111 -223.067328) (xy 100.189837 -223.04375)
			(xy 100.147821 -223.013224) (xy 100.111098 -222.976501) (xy 100.080572 -222.934485) (xy 100.056994 -222.888211)
			(xy 100.040946 -222.838818) (xy 100.032821 -222.787523) (xy 99.752911 -222.787523) (xy 99.744786 -222.838818)
			(xy 99.728738 -222.888211) (xy 99.70516 -222.934485) (xy 99.674634 -222.976501) (xy 99.637911 -223.013224)
			(xy 99.595895 -223.04375) (xy 99.549621 -223.067328) (xy 99.500228 -223.083376) (xy 99.448933 -223.091501)
			(xy 99.396999 -223.091501) (xy 99.345704 -223.083376) (xy 99.296311 -223.067328) (xy 99.250037 -223.04375)
			(xy 99.208021 -223.013224) (xy 99.171298 -222.976501) (xy 99.140772 -222.934485) (xy 99.117194 -222.888211)
			(xy 99.101146 -222.838818) (xy 99.093021 -222.787523) (xy 98.813111 -222.787523) (xy 98.804986 -222.838818)
			(xy 98.788938 -222.888211) (xy 98.76536 -222.934485) (xy 98.734834 -222.976501) (xy 98.698111 -223.013224)
			(xy 98.656095 -223.04375) (xy 98.609821 -223.067328) (xy 98.560428 -223.083376) (xy 98.509133 -223.091501)
			(xy 98.457199 -223.091501) (xy 98.405904 -223.083376) (xy 98.356511 -223.067328) (xy 98.310237 -223.04375)
			(xy 98.268221 -223.013224) (xy 98.231498 -222.976501) (xy 98.200972 -222.934485) (xy 98.177394 -222.888211)
			(xy 98.161346 -222.838818) (xy 98.153221 -222.787523) (xy 97.873311 -222.787523) (xy 97.865186 -222.838818)
			(xy 97.849138 -222.888211) (xy 97.82556 -222.934485) (xy 97.795034 -222.976501) (xy 97.758311 -223.013224)
			(xy 97.716295 -223.04375) (xy 97.670021 -223.067328) (xy 97.620628 -223.083376) (xy 97.569333 -223.091501)
			(xy 97.517399 -223.091501) (xy 97.466104 -223.083376) (xy 97.416711 -223.067328) (xy 97.370437 -223.04375)
			(xy 97.328421 -223.013224) (xy 97.291698 -222.976501) (xy 97.261172 -222.934485) (xy 97.237594 -222.888211)
			(xy 97.221546 -222.838818) (xy 97.213421 -222.787523) (xy 96.933511 -222.787523) (xy 96.925386 -222.838818)
			(xy 96.909338 -222.888211) (xy 96.88576 -222.934485) (xy 96.855234 -222.976501) (xy 96.818511 -223.013224)
			(xy 96.776495 -223.04375) (xy 96.730221 -223.067328) (xy 96.680828 -223.083376) (xy 96.629533 -223.091501)
			(xy 96.577599 -223.091501) (xy 96.526304 -223.083376) (xy 96.476911 -223.067328) (xy 96.430637 -223.04375)
			(xy 96.388621 -223.013224) (xy 96.351898 -222.976501) (xy 96.321372 -222.934485) (xy 96.297794 -222.888211)
			(xy 96.281746 -222.838818) (xy 96.273621 -222.787523) (xy 95.993711 -222.787523) (xy 95.985586 -222.838818)
			(xy 95.969538 -222.888211) (xy 95.94596 -222.934485) (xy 95.915434 -222.976501) (xy 95.878711 -223.013224)
			(xy 95.836695 -223.04375) (xy 95.790421 -223.067328) (xy 95.741028 -223.083376) (xy 95.689733 -223.091501)
			(xy 95.637799 -223.091501) (xy 95.586504 -223.083376) (xy 95.537111 -223.067328) (xy 95.490837 -223.04375)
			(xy 95.448821 -223.013224) (xy 95.412098 -222.976501) (xy 95.381572 -222.934485) (xy 95.357994 -222.888211)
			(xy 95.341946 -222.838818) (xy 95.333821 -222.787523) (xy 95.053911 -222.787523) (xy 95.045786 -222.838818)
			(xy 95.029738 -222.888211) (xy 95.00616 -222.934485) (xy 94.975634 -222.976501) (xy 94.938911 -223.013224)
			(xy 94.896895 -223.04375) (xy 94.850621 -223.067328) (xy 94.801228 -223.083376) (xy 94.749933 -223.091501)
			(xy 94.697999 -223.091501) (xy 94.646704 -223.083376) (xy 94.597311 -223.067328) (xy 94.551037 -223.04375)
			(xy 94.509021 -223.013224) (xy 94.472298 -222.976501) (xy 94.441772 -222.934485) (xy 94.418194 -222.888211)
			(xy 94.402146 -222.838818) (xy 94.394021 -222.787523) (xy 94.114111 -222.787523) (xy 94.105986 -222.838818)
			(xy 94.089938 -222.888211) (xy 94.06636 -222.934485) (xy 94.035834 -222.976501) (xy 93.999111 -223.013224)
			(xy 93.957095 -223.04375) (xy 93.910821 -223.067328) (xy 93.861428 -223.083376) (xy 93.810133 -223.091501)
			(xy 93.758199 -223.091501) (xy 93.706904 -223.083376) (xy 93.657511 -223.067328) (xy 93.611237 -223.04375)
			(xy 93.569221 -223.013224) (xy 93.532498 -222.976501) (xy 93.501972 -222.934485) (xy 93.478394 -222.888211)
			(xy 93.462346 -222.838818) (xy 93.454221 -222.787523) (xy 93.174311 -222.787523) (xy 93.166186 -222.838818)
			(xy 93.150138 -222.888211) (xy 93.12656 -222.934485) (xy 93.096034 -222.976501) (xy 93.059311 -223.013224)
			(xy 93.017295 -223.04375) (xy 92.971021 -223.067328) (xy 92.921628 -223.083376) (xy 92.870333 -223.091501)
			(xy 92.818399 -223.091501) (xy 92.767104 -223.083376) (xy 92.717711 -223.067328) (xy 92.671437 -223.04375)
			(xy 92.629421 -223.013224) (xy 92.592698 -222.976501) (xy 92.562172 -222.934485) (xy 92.538594 -222.888211)
			(xy 92.522546 -222.838818) (xy 92.514421 -222.787523) (xy 92.234511 -222.787523) (xy 92.226386 -222.838818)
			(xy 92.210338 -222.888211) (xy 92.18676 -222.934485) (xy 92.156234 -222.976501) (xy 92.119511 -223.013224)
			(xy 92.077495 -223.04375) (xy 92.031221 -223.067328) (xy 91.981828 -223.083376) (xy 91.930533 -223.091501)
			(xy 91.878599 -223.091501) (xy 91.827304 -223.083376) (xy 91.777911 -223.067328) (xy 91.731637 -223.04375)
			(xy 91.689621 -223.013224) (xy 91.652898 -222.976501) (xy 91.622372 -222.934485) (xy 91.598794 -222.888211)
			(xy 91.582746 -222.838818) (xy 91.574621 -222.787523) (xy 91.294512 -222.787523) (xy 91.287803 -222.833297)
			(xy 91.273974 -222.879436) (xy 91.253595 -222.923079) (xy 91.227097 -222.963302) (xy 91.195041 -222.999253)
			(xy 91.176856 -223.015048) (xy 91.165851 -223.024878) (xy 91.149545 -223.049455) (xy 91.140932 -223.077664)
			(xy 91.140732 -223.107159) (xy 91.148959 -223.135483) (xy 91.156536 -223.148144) (xy 91.167114 -223.164726)
			(xy 91.186808 -223.198778) (xy 91.195906 -223.216216) (xy 91.203072 -223.229093) (xy 91.223443 -223.25037)
			(xy 91.249037 -223.264952) (xy 91.277728 -223.271628) (xy 91.30713 -223.269843) (xy 91.321128 -223.265238)
			(xy 91.34852 -223.255924) (xy 91.405487 -223.245843) (xy 91.434412 -223.245172) (xy 91.434666 -223.245172)
			(xy 91.460636 -223.245652) (xy 91.511938 -223.253773) (xy 91.561337 -223.26982) (xy 91.607618 -223.293399)
			(xy 91.64964 -223.323927) (xy 91.686367 -223.360654) (xy 91.716897 -223.402675) (xy 91.740476 -223.448955)
			(xy 91.756525 -223.498354) (xy 91.764647 -223.549656) (xy 91.76512 -223.575626) (xy 91.76469 -223.59971)
			(xy 91.757709 -223.64737) (xy 91.743883 -223.693512) (xy 91.723507 -223.737158) (xy 91.69701 -223.777384)
			(xy 91.664956 -223.813339) (xy 91.646756 -223.829118) (xy 91.635747 -223.838947) (xy 91.619432 -223.863526)
			(xy 91.610813 -223.891739) (xy 91.610605 -223.921238) (xy 91.618827 -223.94957) (xy 91.626436 -223.962214)
			(xy 91.637017 -223.978729) (xy 91.656711 -224.012654) (xy 91.665806 -224.030032) (xy 91.672973 -224.042907)
			(xy 91.693345 -224.064181) (xy 91.718939 -224.078761) (xy 91.747627 -224.085436) (xy 91.777028 -224.083651)
			(xy 91.791028 -224.079054) (xy 91.803893 -224.074485) (xy 91.830217 -224.067241) (xy 91.843606 -224.064576)
			(xy 91.86672 -224.060258) (xy 92.070174 -223.707198) (xy 92.062554 -223.6851) (xy 92.053836 -223.658573)
			(xy 92.04439 -223.603542) (xy 92.043758 -223.575626) (xy 92.044267 -223.549659) (xy 92.052392 -223.498364)
			(xy 92.06844 -223.448971) (xy 92.092018 -223.402697) (xy 92.122544 -223.360681) (xy 92.159267 -223.323958)
			(xy 92.201283 -223.293432) (xy 92.247557 -223.269854) (xy 92.29695 -223.253806) (xy 92.348245 -223.245681)
			(xy 92.400179 -223.245681) (xy 92.451474 -223.253806) (xy 92.500867 -223.269854) (xy 92.547141 -223.293432)
			(xy 92.589157 -223.323958) (xy 92.62588 -223.360681) (xy 92.656406 -223.402697) (xy 92.679984 -223.448971)
			(xy 92.696032 -223.498364) (xy 92.704157 -223.549659) (xy 92.704666 -223.575626) (xy 92.704196 -223.601076)
			(xy 92.704116 -223.601593) (xy 92.984321 -223.601593) (xy 92.984321 -223.549659) (xy 92.992446 -223.498364)
			(xy 93.008494 -223.448971) (xy 93.032072 -223.402697) (xy 93.062598 -223.360681) (xy 93.099321 -223.323958)
			(xy 93.141337 -223.293432) (xy 93.187611 -223.269854) (xy 93.237004 -223.253806) (xy 93.288299 -223.245681)
			(xy 93.340233 -223.245681) (xy 93.391528 -223.253806) (xy 93.440921 -223.269854) (xy 93.487195 -223.293432)
			(xy 93.529211 -223.323958) (xy 93.565934 -223.360681) (xy 93.59646 -223.402697) (xy 93.620038 -223.448971)
			(xy 93.636086 -223.498364) (xy 93.644211 -223.549659) (xy 93.64472 -223.575626) (xy 93.644211 -223.601593)
			(xy 93.636086 -223.652888) (xy 93.620038 -223.702281) (xy 93.59646 -223.748555) (xy 93.565934 -223.790571)
			(xy 93.529211 -223.827294) (xy 93.487195 -223.85782) (xy 93.440921 -223.881398) (xy 93.391528 -223.897446)
			(xy 93.340233 -223.905571) (xy 93.288299 -223.905571) (xy 93.237004 -223.897446) (xy 93.187611 -223.881398)
			(xy 93.141337 -223.85782) (xy 93.099321 -223.827294) (xy 93.062598 -223.790571) (xy 93.032072 -223.748555)
			(xy 93.008494 -223.702281) (xy 92.992446 -223.652888) (xy 92.984321 -223.601593) (xy 92.704116 -223.601593)
			(xy 92.696392 -223.651374) (xy 92.680972 -223.699882) (xy 92.658302 -223.745455) (xy 92.628915 -223.787015)
			(xy 92.593508 -223.823581) (xy 92.552914 -223.85429) (xy 92.508095 -223.878415) (xy 92.460108 -223.895387)
			(xy 92.435172 -223.900492) (xy 92.412058 -223.90481) (xy 92.208604 -224.257616) (xy 92.216224 -224.279714)
			(xy 92.225013 -224.306289) (xy 92.234456 -224.361457) (xy 92.23502 -224.389442) (xy 92.234589 -224.413526)
			(xy 92.227606 -224.461184) (xy 92.213779 -224.507325) (xy 92.193401 -224.550969) (xy 92.166903 -224.591194)
			(xy 92.134848 -224.627146) (xy 92.116656 -224.642934) (xy 92.105649 -224.652764) (xy 92.089339 -224.677341)
			(xy 92.080723 -224.705552) (xy 92.08052 -224.735049) (xy 92.088745 -224.763377) (xy 92.096336 -224.77603)
			(xy 92.119455 -224.81293) (xy 92.158316 -224.890859) (xy 92.188346 -224.972598) (xy 92.209178 -225.05715)
			(xy 92.220559 -225.143483) (xy 92.222066 -225.187002) (xy 92.22232 -225.193606) (xy 92.22232 -225.207576)
			(xy 92.223128 -225.22301) (xy 92.230219 -225.253087) (xy 92.243221 -225.28112) (xy 92.261602 -225.305961)
			(xy 92.272866 -225.316542) (xy 92.35567 -225.316542) (xy 92.383356 -225.307906) (xy 92.389198 -225.304096)
			(xy 92.408553 -225.292028) (xy 92.449988 -225.27296) (xy 92.493722 -225.260009) (xy 92.538859 -225.253442)
			(xy 92.561664 -225.253042) (xy 92.653358 -225.253042) (xy 92.6592 -225.251518) (xy 92.704803 -225.241269)
			(xy 92.79763 -225.230323) (xy 92.844366 -225.229674) (xy 92.900246 -225.231452) (xy 92.9259 -225.23323)
			(xy 92.941902 -225.219006) (xy 92.958158 -225.184716) (xy 92.95892 -225.175318) (xy 92.961665 -225.147566)
			(xy 92.974676 -225.093341) (xy 92.984828 -225.067368) (xy 92.99448 -225.044254) (xy 92.80652 -224.718626)
			(xy 92.783406 -224.714308) (xy 92.758478 -224.709156) (xy 92.71048 -224.692211) (xy 92.665649 -224.668105)
			(xy 92.625046 -224.637408) (xy 92.589631 -224.600846) (xy 92.560244 -224.559286) (xy 92.537578 -224.513709)
			(xy 92.522172 -224.465195) (xy 92.514389 -224.414893) (xy 92.513912 -224.389442) (xy 92.514421 -224.363475)
			(xy 92.522546 -224.31218) (xy 92.538594 -224.262787) (xy 92.562172 -224.216513) (xy 92.592698 -224.174497)
			(xy 92.629421 -224.137774) (xy 92.671437 -224.107248) (xy 92.717711 -224.08367) (xy 92.767104 -224.067622)
			(xy 92.818399 -224.059497) (xy 92.870333 -224.059497) (xy 92.921628 -224.067622) (xy 92.971021 -224.08367)
			(xy 93.017295 -224.107248) (xy 93.059311 -224.137774) (xy 93.096034 -224.174497) (xy 93.12656 -224.216513)
			(xy 93.150138 -224.262787) (xy 93.166186 -224.31218) (xy 93.174311 -224.363475) (xy 93.17482 -224.389442)
			(xy 93.453712 -224.389442) (xy 93.454174 -224.363991) (xy 93.46196 -224.313687) (xy 93.477368 -224.265174)
			(xy 93.500036 -224.219597) (xy 93.529425 -224.178036) (xy 93.564841 -224.141475) (xy 93.605446 -224.110778)
			(xy 93.650278 -224.086672) (xy 93.698277 -224.069728) (xy 93.723206 -224.064576) (xy 93.746066 -224.060258)
			(xy 93.949774 -223.707198) (xy 93.942154 -223.685354) (xy 93.933431 -223.658761) (xy 93.923974 -223.603606)
			(xy 93.923358 -223.575626) (xy 93.923867 -223.549659) (xy 93.931992 -223.498364) (xy 93.94804 -223.448971)
			(xy 93.971618 -223.402697) (xy 94.002144 -223.360681) (xy 94.038867 -223.323958) (xy 94.080883 -223.293432)
			(xy 94.127157 -223.269854) (xy 94.17655 -223.253806) (xy 94.227845 -223.245681) (xy 94.279779 -223.245681)
			(xy 94.331074 -223.253806) (xy 94.380467 -223.269854) (xy 94.426741 -223.293432) (xy 94.468757 -223.323958)
			(xy 94.50548 -223.360681) (xy 94.536006 -223.402697) (xy 94.559584 -223.448971) (xy 94.575632 -223.498364)
			(xy 94.583757 -223.549659) (xy 94.584266 -223.575626) (xy 94.583793 -223.601077) (xy 94.583713 -223.601593)
			(xy 94.863921 -223.601593) (xy 94.863921 -223.549659) (xy 94.872046 -223.498364) (xy 94.888094 -223.448971)
			(xy 94.911672 -223.402697) (xy 94.942198 -223.360681) (xy 94.978921 -223.323958) (xy 95.020937 -223.293432)
			(xy 95.067211 -223.269854) (xy 95.116604 -223.253806) (xy 95.167899 -223.245681) (xy 95.219833 -223.245681)
			(xy 95.271128 -223.253806) (xy 95.320521 -223.269854) (xy 95.366795 -223.293432) (xy 95.408811 -223.323958)
			(xy 95.445534 -223.360681) (xy 95.47606 -223.402697) (xy 95.499638 -223.448971) (xy 95.515686 -223.498364)
			(xy 95.523811 -223.549659) (xy 95.52432 -223.575626) (xy 95.523811 -223.601593) (xy 95.515686 -223.652888)
			(xy 95.499638 -223.702281) (xy 95.47606 -223.748555) (xy 95.445534 -223.790571) (xy 95.408811 -223.827294)
			(xy 95.366795 -223.85782) (xy 95.320521 -223.881398) (xy 95.271128 -223.897446) (xy 95.219833 -223.905571)
			(xy 95.167899 -223.905571) (xy 95.116604 -223.897446) (xy 95.067211 -223.881398) (xy 95.020937 -223.85782)
			(xy 94.978921 -223.827294) (xy 94.942198 -223.790571) (xy 94.911672 -223.748555) (xy 94.888094 -223.702281)
			(xy 94.872046 -223.652888) (xy 94.863921 -223.601593) (xy 94.583713 -223.601593) (xy 94.576011 -223.651381)
			(xy 94.560606 -223.699896) (xy 94.537941 -223.745473) (xy 94.508553 -223.787035) (xy 94.473137 -223.823597)
			(xy 94.432533 -223.854293) (xy 94.3877 -223.878398) (xy 94.339701 -223.895341) (xy 94.314772 -223.900492)
			(xy 94.291658 -223.90481) (xy 94.088204 -224.257616) (xy 94.095824 -224.279714) (xy 94.104566 -224.306301)
			(xy 94.11401 -224.361461) (xy 94.11462 -224.389442) (xy 94.114111 -224.415409) (xy 94.105986 -224.466704)
			(xy 94.089938 -224.516097) (xy 94.06636 -224.562371) (xy 94.035834 -224.604387) (xy 93.999111 -224.64111)
			(xy 93.957095 -224.671636) (xy 93.910821 -224.695214) (xy 93.861428 -224.711262) (xy 93.810133 -224.719387)
			(xy 93.758199 -224.719387) (xy 93.706904 -224.711262) (xy 93.657511 -224.695214) (xy 93.611237 -224.671636)
			(xy 93.569221 -224.64111) (xy 93.532498 -224.604387) (xy 93.501972 -224.562371) (xy 93.478394 -224.516097)
			(xy 93.462346 -224.466704) (xy 93.454221 -224.415409) (xy 93.453712 -224.389442) (xy 93.17482 -224.389442)
			(xy 93.174212 -224.417423) (xy 93.16477 -224.472584) (xy 93.156024 -224.49917) (xy 93.148404 -224.521268)
			(xy 93.336364 -224.846896) (xy 93.361002 -224.850198) (xy 93.388362 -224.854365) (xy 93.441432 -224.870062)
			(xy 93.491432 -224.893784) (xy 93.537157 -224.924959) (xy 93.577506 -224.962836) (xy 93.611506 -225.006503)
			(xy 93.638336 -225.054906) (xy 93.657352 -225.106878) (xy 93.663262 -225.133916) (xy 93.665294 -225.145346)
			(xy 93.668262 -225.15952) (xy 93.680996 -225.185513) (xy 93.700505 -225.206895) (xy 93.725226 -225.221951)
			(xy 93.753176 -225.229474) (xy 93.767656 -225.229674) (xy 93.784166 -225.229674) (xy 93.823089 -225.230143)
			(xy 93.900556 -225.237817) (xy 93.976888 -225.253092) (xy 94.051342 -225.275821) (xy 94.087442 -225.29038)
			(xy 94.09684 -225.29419) (xy 94.268036 -225.29419) (xy 94.290642 -225.288602) (xy 94.295722 -225.286062)
			(xy 94.317805 -225.275685) (xy 94.364333 -225.260998) (xy 94.412551 -225.253541) (xy 94.436946 -225.253042)
			(xy 94.532958 -225.253042) (xy 94.5388 -225.251518) (xy 94.584403 -225.241269) (xy 94.67723 -225.230323)
			(xy 94.723966 -225.229674) (xy 94.779846 -225.231452) (xy 94.8055 -225.23323) (xy 94.821756 -225.218498)
			(xy 94.837758 -225.184462) (xy 94.83852 -225.175064) (xy 94.841276 -225.147376) (xy 94.85429 -225.09328)
			(xy 94.864428 -225.067368) (xy 94.87408 -225.044254) (xy 94.685866 -224.718626) (xy 94.663006 -224.714308)
			(xy 94.638078 -224.709156) (xy 94.59008 -224.692211) (xy 94.545249 -224.668105) (xy 94.504646 -224.637408)
			(xy 94.469231 -224.600846) (xy 94.439844 -224.559286) (xy 94.417178 -224.513709) (xy 94.401772 -224.465195)
			(xy 94.393989 -224.414893) (xy 94.393512 -224.389442) (xy 94.394021 -224.363475) (xy 94.402146 -224.31218)
			(xy 94.418194 -224.262787) (xy 94.441772 -224.216513) (xy 94.472298 -224.174497) (xy 94.509021 -224.137774)
			(xy 94.551037 -224.107248) (xy 94.597311 -224.08367) (xy 94.646704 -224.067622) (xy 94.697999 -224.059497)
			(xy 94.749933 -224.059497) (xy 94.801228 -224.067622) (xy 94.850621 -224.08367) (xy 94.896895 -224.107248)
			(xy 94.938911 -224.137774) (xy 94.975634 -224.174497) (xy 95.00616 -224.216513) (xy 95.029738 -224.262787)
			(xy 95.045786 -224.31218) (xy 95.053911 -224.363475) (xy 95.05442 -224.389442) (xy 95.333312 -224.389442)
			(xy 95.333774 -224.363991) (xy 95.34156 -224.313687) (xy 95.356968 -224.265174) (xy 95.379636 -224.219597)
			(xy 95.409025 -224.178036) (xy 95.444441 -224.141475) (xy 95.485046 -224.110778) (xy 95.529878 -224.086672)
			(xy 95.577877 -224.069728) (xy 95.602806 -224.064576) (xy 95.625666 -224.060258) (xy 95.829374 -223.707198)
			(xy 95.821754 -223.685354) (xy 95.813031 -223.658761) (xy 95.803574 -223.603606) (xy 95.802958 -223.575626)
			(xy 95.803467 -223.549659) (xy 95.811592 -223.498364) (xy 95.82764 -223.448971) (xy 95.851218 -223.402697)
			(xy 95.881744 -223.360681) (xy 95.918467 -223.323958) (xy 95.960483 -223.293432) (xy 96.006757 -223.269854)
			(xy 96.05615 -223.253806) (xy 96.107445 -223.245681) (xy 96.159379 -223.245681) (xy 96.210674 -223.253806)
			(xy 96.260067 -223.269854) (xy 96.306341 -223.293432) (xy 96.348357 -223.323958) (xy 96.38508 -223.360681)
			(xy 96.415606 -223.402697) (xy 96.439184 -223.448971) (xy 96.455232 -223.498364) (xy 96.463357 -223.549659)
			(xy 96.463866 -223.575626) (xy 96.463393 -223.601077) (xy 96.463313 -223.601593) (xy 96.743521 -223.601593)
			(xy 96.743521 -223.549659) (xy 96.751646 -223.498364) (xy 96.767694 -223.448971) (xy 96.791272 -223.402697)
			(xy 96.821798 -223.360681) (xy 96.858521 -223.323958) (xy 96.900537 -223.293432) (xy 96.946811 -223.269854)
			(xy 96.996204 -223.253806) (xy 97.047499 -223.245681) (xy 97.099433 -223.245681) (xy 97.150728 -223.253806)
			(xy 97.200121 -223.269854) (xy 97.246395 -223.293432) (xy 97.288411 -223.323958) (xy 97.325134 -223.360681)
			(xy 97.35566 -223.402697) (xy 97.379238 -223.448971) (xy 97.395286 -223.498364) (xy 97.403411 -223.549659)
			(xy 97.40392 -223.575626) (xy 97.403411 -223.601593) (xy 97.395286 -223.652888) (xy 97.379238 -223.702281)
			(xy 97.35566 -223.748555) (xy 97.325134 -223.790571) (xy 97.288411 -223.827294) (xy 97.246395 -223.85782)
			(xy 97.200121 -223.881398) (xy 97.150728 -223.897446) (xy 97.099433 -223.905571) (xy 97.047499 -223.905571)
			(xy 96.996204 -223.897446) (xy 96.946811 -223.881398) (xy 96.900537 -223.85782) (xy 96.858521 -223.827294)
			(xy 96.821798 -223.790571) (xy 96.791272 -223.748555) (xy 96.767694 -223.702281) (xy 96.751646 -223.652888)
			(xy 96.743521 -223.601593) (xy 96.463313 -223.601593) (xy 96.455611 -223.651381) (xy 96.440206 -223.699896)
			(xy 96.417541 -223.745473) (xy 96.388153 -223.787035) (xy 96.352737 -223.823597) (xy 96.312133 -223.854293)
			(xy 96.2673 -223.878398) (xy 96.219301 -223.895341) (xy 96.194372 -223.900492) (xy 96.171258 -223.90481)
			(xy 95.967804 -224.257616) (xy 95.975424 -224.279714) (xy 95.984166 -224.306301) (xy 95.99361 -224.361461)
			(xy 95.99422 -224.389442) (xy 95.993711 -224.415409) (xy 95.985586 -224.466704) (xy 95.969538 -224.516097)
			(xy 95.94596 -224.562371) (xy 95.915434 -224.604387) (xy 95.878711 -224.64111) (xy 95.836695 -224.671636)
			(xy 95.790421 -224.695214) (xy 95.741028 -224.711262) (xy 95.689733 -224.719387) (xy 95.637799 -224.719387)
			(xy 95.586504 -224.711262) (xy 95.537111 -224.695214) (xy 95.490837 -224.671636) (xy 95.448821 -224.64111)
			(xy 95.412098 -224.604387) (xy 95.381572 -224.562371) (xy 95.357994 -224.516097) (xy 95.341946 -224.466704)
			(xy 95.333821 -224.415409) (xy 95.333312 -224.389442) (xy 95.05442 -224.389442) (xy 95.053812 -224.417423)
			(xy 95.04437 -224.472584) (xy 95.035624 -224.49917) (xy 95.028004 -224.521268) (xy 95.215964 -224.846896)
			(xy 95.240602 -224.850198) (xy 95.267962 -224.854365) (xy 95.321032 -224.870062) (xy 95.371032 -224.893784)
			(xy 95.416757 -224.924959) (xy 95.457106 -224.962836) (xy 95.491106 -225.006503) (xy 95.517936 -225.054906)
			(xy 95.536952 -225.106878) (xy 95.542862 -225.133916) (xy 95.544894 -225.145346) (xy 95.547862 -225.15952)
			(xy 95.560596 -225.185513) (xy 95.580105 -225.206895) (xy 95.604826 -225.221951) (xy 95.632776 -225.229474)
			(xy 95.647256 -225.229674) (xy 95.663766 -225.229674) (xy 95.703898 -225.230172) (xy 95.783747 -225.238333)
			(xy 95.862351 -225.254574) (xy 95.938896 -225.278726) (xy 95.975932 -225.29419) (xy 95.985584 -225.298254)
			(xy 96.1136 -225.298254) (xy 96.137476 -225.291904) (xy 96.141032 -225.290126) (xy 96.164007 -225.278479)
			(xy 96.212797 -225.261971) (xy 96.263615 -225.253571) (xy 96.289368 -225.253042) (xy 96.412558 -225.253042)
			(xy 96.4184 -225.251518) (xy 96.464003 -225.241269) (xy 96.55683 -225.230323) (xy 96.603566 -225.229674)
			(xy 96.619568 -225.229674) (xy 96.634055 -225.229496) (xy 96.662026 -225.222) (xy 96.686765 -225.206948)
			(xy 96.706278 -225.18555) (xy 96.718992 -225.159533) (xy 96.72193 -225.145346) (xy 96.722946 -225.138996)
			(xy 96.726563 -225.120642) (xy 96.737123 -225.084753) (xy 96.744028 -225.067368) (xy 96.75368 -225.044254)
			(xy 96.565466 -224.718626) (xy 96.542606 -224.714308) (xy 96.517678 -224.709156) (xy 96.46968 -224.692211)
			(xy 96.424849 -224.668105) (xy 96.384246 -224.637408) (xy 96.348831 -224.600846) (xy 96.319444 -224.559286)
			(xy 96.296778 -224.513709) (xy 96.281372 -224.465195) (xy 96.273589 -224.414893) (xy 96.273112 -224.389442)
			(xy 96.273621 -224.363475) (xy 96.281746 -224.31218) (xy 96.297794 -224.262787) (xy 96.321372 -224.216513)
			(xy 96.351898 -224.174497) (xy 96.388621 -224.137774) (xy 96.430637 -224.107248) (xy 96.476911 -224.08367)
			(xy 96.526304 -224.067622) (xy 96.577599 -224.059497) (xy 96.629533 -224.059497) (xy 96.680828 -224.067622)
			(xy 96.730221 -224.08367) (xy 96.776495 -224.107248) (xy 96.818511 -224.137774) (xy 96.855234 -224.174497)
			(xy 96.88576 -224.216513) (xy 96.909338 -224.262787) (xy 96.925386 -224.31218) (xy 96.933511 -224.363475)
			(xy 96.93402 -224.389442) (xy 97.212912 -224.389442) (xy 97.213374 -224.363991) (xy 97.22116 -224.313687)
			(xy 97.236568 -224.265174) (xy 97.259236 -224.219597) (xy 97.288625 -224.178036) (xy 97.324041 -224.141475)
			(xy 97.364646 -224.110778) (xy 97.409478 -224.086672) (xy 97.457477 -224.069728) (xy 97.482406 -224.064576)
			(xy 97.505266 -224.060258) (xy 97.708974 -223.707198) (xy 97.701354 -223.685354) (xy 97.692631 -223.658761)
			(xy 97.683174 -223.603606) (xy 97.682558 -223.575626) (xy 97.683067 -223.549659) (xy 97.691192 -223.498364)
			(xy 97.70724 -223.448971) (xy 97.730818 -223.402697) (xy 97.761344 -223.360681) (xy 97.798067 -223.323958)
			(xy 97.840083 -223.293432) (xy 97.886357 -223.269854) (xy 97.93575 -223.253806) (xy 97.987045 -223.245681)
			(xy 98.038979 -223.245681) (xy 98.090274 -223.253806) (xy 98.139667 -223.269854) (xy 98.185941 -223.293432)
			(xy 98.227957 -223.323958) (xy 98.26468 -223.360681) (xy 98.295206 -223.402697) (xy 98.318784 -223.448971)
			(xy 98.334832 -223.498364) (xy 98.342957 -223.549659) (xy 98.343466 -223.575626) (xy 98.342993 -223.601077)
			(xy 98.342913 -223.601593) (xy 98.623121 -223.601593) (xy 98.623121 -223.549659) (xy 98.631246 -223.498364)
			(xy 98.647294 -223.448971) (xy 98.670872 -223.402697) (xy 98.701398 -223.360681) (xy 98.738121 -223.323958)
			(xy 98.780137 -223.293432) (xy 98.826411 -223.269854) (xy 98.875804 -223.253806) (xy 98.927099 -223.245681)
			(xy 98.979033 -223.245681) (xy 99.030328 -223.253806) (xy 99.079721 -223.269854) (xy 99.125995 -223.293432)
			(xy 99.168011 -223.323958) (xy 99.204734 -223.360681) (xy 99.23526 -223.402697) (xy 99.258838 -223.448971)
			(xy 99.274886 -223.498364) (xy 99.283011 -223.549659) (xy 99.28352 -223.575626) (xy 99.283011 -223.601593)
			(xy 99.274886 -223.652888) (xy 99.258838 -223.702281) (xy 99.23526 -223.748555) (xy 99.204734 -223.790571)
			(xy 99.168011 -223.827294) (xy 99.125995 -223.85782) (xy 99.079721 -223.881398) (xy 99.030328 -223.897446)
			(xy 98.979033 -223.905571) (xy 98.927099 -223.905571) (xy 98.875804 -223.897446) (xy 98.826411 -223.881398)
			(xy 98.780137 -223.85782) (xy 98.738121 -223.827294) (xy 98.701398 -223.790571) (xy 98.670872 -223.748555)
			(xy 98.647294 -223.702281) (xy 98.631246 -223.652888) (xy 98.623121 -223.601593) (xy 98.342913 -223.601593)
			(xy 98.335211 -223.651381) (xy 98.319806 -223.699896) (xy 98.297141 -223.745473) (xy 98.267753 -223.787035)
			(xy 98.232337 -223.823597) (xy 98.191733 -223.854293) (xy 98.1469 -223.878398) (xy 98.098901 -223.895341)
			(xy 98.073972 -223.900492) (xy 98.050858 -223.90481) (xy 97.847404 -224.257616) (xy 97.855024 -224.279714)
			(xy 97.863766 -224.306301) (xy 97.87321 -224.361461) (xy 97.87382 -224.389442) (xy 97.873311 -224.415409)
			(xy 97.865186 -224.466704) (xy 97.849138 -224.516097) (xy 97.82556 -224.562371) (xy 97.795034 -224.604387)
			(xy 97.758311 -224.64111) (xy 97.716295 -224.671636) (xy 97.670021 -224.695214) (xy 97.620628 -224.711262)
			(xy 97.569333 -224.719387) (xy 97.517399 -224.719387) (xy 97.466104 -224.711262) (xy 97.416711 -224.695214)
			(xy 97.370437 -224.671636) (xy 97.328421 -224.64111) (xy 97.291698 -224.604387) (xy 97.261172 -224.562371)
			(xy 97.237594 -224.516097) (xy 97.221546 -224.466704) (xy 97.213421 -224.415409) (xy 97.212912 -224.389442)
			(xy 96.93402 -224.389442) (xy 96.933412 -224.417423) (xy 96.92397 -224.472584) (xy 96.915224 -224.49917)
			(xy 96.907604 -224.521268) (xy 97.095564 -224.846896) (xy 97.120202 -224.850198) (xy 97.147562 -224.854365)
			(xy 97.200632 -224.870062) (xy 97.250632 -224.893784) (xy 97.296357 -224.924959) (xy 97.336706 -224.962836)
			(xy 97.370706 -225.006503) (xy 97.397536 -225.054906) (xy 97.416552 -225.106878) (xy 97.422462 -225.133916)
			(xy 97.424494 -225.145346) (xy 97.427462 -225.15952) (xy 97.440196 -225.185513) (xy 97.459705 -225.206895)
			(xy 97.484426 -225.221951) (xy 97.512376 -225.229474) (xy 97.526856 -225.229674) (xy 97.543366 -225.229674)
			(xy 97.590104 -225.230282) (xy 97.682934 -225.241239) (xy 97.728532 -225.251518) (xy 97.734374 -225.253042)
			(xy 97.74174 -225.253042) (xy 97.770019 -225.253699) (xy 97.82567 -225.263793) (xy 97.878654 -225.283583)
			(xy 97.903284 -225.297492) (xy 97.906078 -225.299016) (xy 97.931732 -225.306382) (xy 98.055684 -225.306382)
			(xy 98.081338 -225.299016) (xy 98.084132 -225.297492) (xy 98.108771 -225.283602) (xy 98.161754 -225.26382)
			(xy 98.217399 -225.253714) (xy 98.245676 -225.253042) (xy 98.292158 -225.253042) (xy 98.298 -225.251518)
			(xy 98.343603 -225.241269) (xy 98.43643 -225.230323) (xy 98.483166 -225.229674) (xy 98.539046 -225.231452)
			(xy 98.564954 -225.23323) (xy 98.580448 -225.219514) (xy 98.596958 -225.18497) (xy 98.59772 -225.175572)
			(xy 98.600405 -225.147749) (xy 98.61342 -225.09339) (xy 98.623628 -225.067368) (xy 98.63328 -225.044254)
			(xy 98.445066 -224.718626) (xy 98.422206 -224.714308) (xy 98.397278 -224.709156) (xy 98.34928 -224.692211)
			(xy 98.304449 -224.668105) (xy 98.263846 -224.637408) (xy 98.228431 -224.600846) (xy 98.199044 -224.559286)
			(xy 98.176378 -224.513709) (xy 98.160972 -224.465195) (xy 98.153189 -224.414893) (xy 98.152712 -224.389442)
			(xy 98.153221 -224.363475) (xy 98.161346 -224.31218) (xy 98.177394 -224.262787) (xy 98.200972 -224.216513)
			(xy 98.231498 -224.174497) (xy 98.268221 -224.137774) (xy 98.310237 -224.107248) (xy 98.356511 -224.08367)
			(xy 98.405904 -224.067622) (xy 98.457199 -224.059497) (xy 98.509133 -224.059497) (xy 98.560428 -224.067622)
			(xy 98.609821 -224.08367) (xy 98.656095 -224.107248) (xy 98.698111 -224.137774) (xy 98.734834 -224.174497)
			(xy 98.76536 -224.216513) (xy 98.788938 -224.262787) (xy 98.804986 -224.31218) (xy 98.813111 -224.363475)
			(xy 98.81362 -224.389442) (xy 99.092512 -224.389442) (xy 99.092974 -224.363991) (xy 99.10076 -224.313687)
			(xy 99.116168 -224.265174) (xy 99.138836 -224.219597) (xy 99.168225 -224.178036) (xy 99.203641 -224.141475)
			(xy 99.244246 -224.110778) (xy 99.289078 -224.086672) (xy 99.337077 -224.069728) (xy 99.362006 -224.064576)
			(xy 99.384866 -224.060258) (xy 99.588574 -223.707198) (xy 99.580954 -223.685354) (xy 99.572231 -223.658761)
			(xy 99.562774 -223.603606) (xy 99.562158 -223.575626) (xy 99.562667 -223.549659) (xy 99.570792 -223.498364)
			(xy 99.58684 -223.448971) (xy 99.610418 -223.402697) (xy 99.640944 -223.360681) (xy 99.677667 -223.323958)
			(xy 99.719683 -223.293432) (xy 99.765957 -223.269854) (xy 99.81535 -223.253806) (xy 99.866645 -223.245681)
			(xy 99.918579 -223.245681) (xy 99.969874 -223.253806) (xy 100.019267 -223.269854) (xy 100.065541 -223.293432)
			(xy 100.107557 -223.323958) (xy 100.14428 -223.360681) (xy 100.174806 -223.402697) (xy 100.198384 -223.448971)
			(xy 100.214432 -223.498364) (xy 100.222557 -223.549659) (xy 100.223066 -223.575626) (xy 100.222593 -223.601077)
			(xy 100.222513 -223.601593) (xy 100.502721 -223.601593) (xy 100.502721 -223.549659) (xy 100.510846 -223.498364)
			(xy 100.526894 -223.448971) (xy 100.550472 -223.402697) (xy 100.580998 -223.360681) (xy 100.617721 -223.323958)
			(xy 100.659737 -223.293432) (xy 100.706011 -223.269854) (xy 100.755404 -223.253806) (xy 100.806699 -223.245681)
			(xy 100.858633 -223.245681) (xy 100.909928 -223.253806) (xy 100.959321 -223.269854) (xy 101.005595 -223.293432)
			(xy 101.047611 -223.323958) (xy 101.084334 -223.360681) (xy 101.11486 -223.402697) (xy 101.138438 -223.448971)
			(xy 101.154486 -223.498364) (xy 101.162611 -223.549659) (xy 101.16312 -223.575626) (xy 101.162611 -223.601593)
			(xy 101.154486 -223.652888) (xy 101.138438 -223.702281) (xy 101.11486 -223.748555) (xy 101.084334 -223.790571)
			(xy 101.047611 -223.827294) (xy 101.005595 -223.85782) (xy 100.959321 -223.881398) (xy 100.909928 -223.897446)
			(xy 100.858633 -223.905571) (xy 100.806699 -223.905571) (xy 100.755404 -223.897446) (xy 100.706011 -223.881398)
			(xy 100.659737 -223.85782) (xy 100.617721 -223.827294) (xy 100.580998 -223.790571) (xy 100.550472 -223.748555)
			(xy 100.526894 -223.702281) (xy 100.510846 -223.652888) (xy 100.502721 -223.601593) (xy 100.222513 -223.601593)
			(xy 100.214811 -223.651381) (xy 100.199406 -223.699896) (xy 100.176741 -223.745473) (xy 100.147353 -223.787035)
			(xy 100.111937 -223.823597) (xy 100.071333 -223.854293) (xy 100.0265 -223.878398) (xy 99.978501 -223.895341)
			(xy 99.953572 -223.900492) (xy 99.930458 -223.90481) (xy 99.727004 -224.257616) (xy 99.734624 -224.279714)
			(xy 99.743366 -224.306301) (xy 99.75281 -224.361461) (xy 99.75342 -224.389442) (xy 99.752911 -224.415409)
			(xy 99.744786 -224.466704) (xy 99.728738 -224.516097) (xy 99.70516 -224.562371) (xy 99.674634 -224.604387)
			(xy 99.637911 -224.64111) (xy 99.595895 -224.671636) (xy 99.549621 -224.695214) (xy 99.500228 -224.711262)
			(xy 99.448933 -224.719387) (xy 99.396999 -224.719387) (xy 99.345704 -224.711262) (xy 99.296311 -224.695214)
			(xy 99.250037 -224.671636) (xy 99.208021 -224.64111) (xy 99.171298 -224.604387) (xy 99.140772 -224.562371)
			(xy 99.117194 -224.516097) (xy 99.101146 -224.466704) (xy 99.093021 -224.415409) (xy 99.092512 -224.389442)
			(xy 98.81362 -224.389442) (xy 98.813012 -224.417423) (xy 98.80357 -224.472584) (xy 98.794824 -224.49917)
			(xy 98.787204 -224.521268) (xy 98.975164 -224.846896) (xy 98.999802 -224.850198) (xy 99.027162 -224.854365)
			(xy 99.080232 -224.870062) (xy 99.130232 -224.893784) (xy 99.175957 -224.924959) (xy 99.216306 -224.962836)
			(xy 99.250306 -225.006503) (xy 99.277136 -225.054906) (xy 99.296152 -225.106878) (xy 99.302062 -225.133916)
			(xy 99.304094 -225.145346) (xy 99.307062 -225.15952) (xy 99.319796 -225.185513) (xy 99.339305 -225.206895)
			(xy 99.364026 -225.221951) (xy 99.391976 -225.229474) (xy 99.406456 -225.229674) (xy 99.422966 -225.229674)
			(xy 99.46277 -225.230157) (xy 99.541974 -225.238156) (xy 99.619967 -225.254107) (xy 99.695953 -225.277845)
			(xy 99.769155 -225.30913) (xy 99.80422 -225.327972) (xy 99.81565 -225.334322) (xy 99.852226 -225.334322)
			(xy 99.879404 -225.326194) (xy 99.883214 -225.323908) (xy 99.902518 -225.311978) (xy 99.943788 -225.293109)
			(xy 99.987319 -225.28029) (xy 100.032229 -225.273781) (xy 100.054918 -225.273362) (xy 100.103686 -225.273362)
			(xy 100.11156 -225.270822) (xy 100.152139 -225.257768) (xy 100.235395 -225.239455) (xy 100.320143 -225.230243)
			(xy 100.362766 -225.229674) (xy 100.416868 -225.231452) (xy 100.439982 -225.232976) (xy 100.461064 -225.213418)
			(xy 100.476812 -225.180144) (xy 100.477574 -225.174302) (xy 100.479808 -225.15128) (xy 100.489497 -225.106053)
			(xy 100.496878 -225.084132) (xy 100.503228 -225.067368) (xy 100.51288 -225.044254) (xy 100.324666 -224.718626)
			(xy 100.301806 -224.714308) (xy 100.276878 -224.709156) (xy 100.22888 -224.692211) (xy 100.184049 -224.668105)
			(xy 100.143446 -224.637408) (xy 100.108031 -224.600846) (xy 100.078644 -224.559286) (xy 100.055978 -224.513709)
			(xy 100.040572 -224.465195) (xy 100.032789 -224.414893) (xy 100.032312 -224.389442) (xy 100.032821 -224.363475)
			(xy 100.040946 -224.31218) (xy 100.056994 -224.262787) (xy 100.080572 -224.216513) (xy 100.111098 -224.174497)
			(xy 100.147821 -224.137774) (xy 100.189837 -224.107248) (xy 100.236111 -224.08367) (xy 100.285504 -224.067622)
			(xy 100.336799 -224.059497) (xy 100.388733 -224.059497) (xy 100.440028 -224.067622) (xy 100.489421 -224.08367)
			(xy 100.535695 -224.107248) (xy 100.577711 -224.137774) (xy 100.614434 -224.174497) (xy 100.64496 -224.216513)
			(xy 100.668538 -224.262787) (xy 100.684586 -224.31218) (xy 100.692711 -224.363475) (xy 100.69322 -224.389442)
			(xy 100.972112 -224.389442) (xy 100.972574 -224.363991) (xy 100.98036 -224.313687) (xy 100.995768 -224.265174)
			(xy 101.018436 -224.219597) (xy 101.047825 -224.178036) (xy 101.083241 -224.141475) (xy 101.123846 -224.110778)
			(xy 101.168678 -224.086672) (xy 101.216677 -224.069728) (xy 101.241606 -224.064576) (xy 101.264466 -224.060258)
			(xy 101.468174 -223.707198) (xy 101.460554 -223.685354) (xy 101.451831 -223.658761) (xy 101.442374 -223.603606)
			(xy 101.441758 -223.575626) (xy 101.442267 -223.549659) (xy 101.450392 -223.498364) (xy 101.46644 -223.448971)
			(xy 101.490018 -223.402697) (xy 101.520544 -223.360681) (xy 101.557267 -223.323958) (xy 101.599283 -223.293432)
			(xy 101.645557 -223.269854) (xy 101.69495 -223.253806) (xy 101.746245 -223.245681) (xy 101.798179 -223.245681)
			(xy 101.849474 -223.253806) (xy 101.898867 -223.269854) (xy 101.945141 -223.293432) (xy 101.987157 -223.323958)
			(xy 102.02388 -223.360681) (xy 102.054406 -223.402697) (xy 102.077984 -223.448971) (xy 102.094032 -223.498364)
			(xy 102.102157 -223.549659) (xy 102.102666 -223.575626) (xy 102.102193 -223.601077) (xy 102.102113 -223.601593)
			(xy 102.382321 -223.601593) (xy 102.382321 -223.549659) (xy 102.390446 -223.498364) (xy 102.406494 -223.448971)
			(xy 102.430072 -223.402697) (xy 102.460598 -223.360681) (xy 102.497321 -223.323958) (xy 102.539337 -223.293432)
			(xy 102.585611 -223.269854) (xy 102.635004 -223.253806) (xy 102.686299 -223.245681) (xy 102.738233 -223.245681)
			(xy 102.789528 -223.253806) (xy 102.838921 -223.269854) (xy 102.885195 -223.293432) (xy 102.927211 -223.323958)
			(xy 102.963934 -223.360681) (xy 102.99446 -223.402697) (xy 103.018038 -223.448971) (xy 103.034086 -223.498364)
			(xy 103.042211 -223.549659) (xy 103.04272 -223.575626) (xy 103.042211 -223.601593) (xy 103.034086 -223.652888)
			(xy 103.018038 -223.702281) (xy 102.99446 -223.748555) (xy 102.963934 -223.790571) (xy 102.927211 -223.827294)
			(xy 102.885195 -223.85782) (xy 102.838921 -223.881398) (xy 102.789528 -223.897446) (xy 102.738233 -223.905571)
			(xy 102.686299 -223.905571) (xy 102.635004 -223.897446) (xy 102.585611 -223.881398) (xy 102.539337 -223.85782)
			(xy 102.497321 -223.827294) (xy 102.460598 -223.790571) (xy 102.430072 -223.748555) (xy 102.406494 -223.702281)
			(xy 102.390446 -223.652888) (xy 102.382321 -223.601593) (xy 102.102113 -223.601593) (xy 102.094411 -223.651381)
			(xy 102.079006 -223.699896) (xy 102.056341 -223.745473) (xy 102.026953 -223.787035) (xy 101.991537 -223.823597)
			(xy 101.950933 -223.854293) (xy 101.9061 -223.878398) (xy 101.858101 -223.895341) (xy 101.833172 -223.900492)
			(xy 101.810058 -223.90481) (xy 101.606604 -224.257616) (xy 101.614224 -224.279714) (xy 101.622966 -224.306301)
			(xy 101.63241 -224.361461) (xy 101.63302 -224.389442) (xy 101.911912 -224.389442) (xy 101.912421 -224.363475)
			(xy 101.920546 -224.31218) (xy 101.936594 -224.262787) (xy 101.960172 -224.216513) (xy 101.990698 -224.174497)
			(xy 102.027421 -224.137774) (xy 102.069437 -224.107248) (xy 102.115711 -224.08367) (xy 102.165104 -224.067622)
			(xy 102.216399 -224.059497) (xy 102.268333 -224.059497) (xy 102.319628 -224.067622) (xy 102.369021 -224.08367)
			(xy 102.415295 -224.107248) (xy 102.457311 -224.137774) (xy 102.494034 -224.174497) (xy 102.52456 -224.216513)
			(xy 102.548138 -224.262787) (xy 102.564186 -224.31218) (xy 102.572311 -224.363475) (xy 102.57282 -224.389442)
			(xy 102.572277 -224.417428) (xy 102.56282 -224.472596) (xy 102.554024 -224.49917) (xy 102.546404 -224.521268)
			(xy 102.750112 -224.874074) (xy 102.772972 -224.878392) (xy 102.797904 -224.883512) (xy 102.84589 -224.900483)
			(xy 102.890709 -224.924607) (xy 102.931302 -224.955314) (xy 102.966709 -224.991878) (xy 102.996096 -225.033436)
			(xy 103.018768 -225.079006) (xy 103.034189 -225.127512) (xy 103.041994 -225.177809) (xy 103.042466 -225.203258)
			(xy 103.041957 -225.229225) (xy 103.321867 -225.229225) (xy 103.321867 -225.177291) (xy 103.329992 -225.125996)
			(xy 103.34604 -225.076603) (xy 103.369618 -225.030329) (xy 103.400144 -224.988313) (xy 103.436867 -224.95159)
			(xy 103.478883 -224.921064) (xy 103.525157 -224.897486) (xy 103.57455 -224.881438) (xy 103.625845 -224.873313)
			(xy 103.677779 -224.873313) (xy 103.729074 -224.881438) (xy 103.778467 -224.897486) (xy 103.824741 -224.921064)
			(xy 103.866757 -224.95159) (xy 103.90348 -224.988313) (xy 103.934006 -225.030329) (xy 103.957584 -225.076603)
			(xy 103.973632 -225.125996) (xy 103.981757 -225.177291) (xy 103.982266 -225.203258) (xy 103.981757 -225.229225)
			(xy 103.973632 -225.28052) (xy 103.957584 -225.329913) (xy 103.934006 -225.376187) (xy 103.90348 -225.418203)
			(xy 103.866757 -225.454926) (xy 103.824741 -225.485452) (xy 103.778467 -225.50903) (xy 103.729074 -225.525078)
			(xy 103.677779 -225.533203) (xy 103.625845 -225.533203) (xy 103.57455 -225.525078) (xy 103.525157 -225.50903)
			(xy 103.478883 -225.485452) (xy 103.436867 -225.454926) (xy 103.400144 -225.418203) (xy 103.369618 -225.376187)
			(xy 103.34604 -225.329913) (xy 103.329992 -225.28052) (xy 103.321867 -225.229225) (xy 103.041957 -225.229225)
			(xy 103.033832 -225.28052) (xy 103.017784 -225.329913) (xy 102.994206 -225.376187) (xy 102.96368 -225.418203)
			(xy 102.926957 -225.454926) (xy 102.884941 -225.485452) (xy 102.838667 -225.50903) (xy 102.789274 -225.525078)
			(xy 102.737979 -225.533203) (xy 102.686045 -225.533203) (xy 102.63475 -225.525078) (xy 102.585357 -225.50903)
			(xy 102.539083 -225.485452) (xy 102.497067 -225.454926) (xy 102.460344 -225.418203) (xy 102.429818 -225.376187)
			(xy 102.40624 -225.329913) (xy 102.390192 -225.28052) (xy 102.382067 -225.229225) (xy 102.381558 -225.203258)
			(xy 102.382097 -225.175271) (xy 102.391556 -225.120104) (xy 102.400354 -225.09353) (xy 102.407974 -225.071432)
			(xy 102.204266 -224.718626) (xy 102.181406 -224.714308) (xy 102.156486 -224.709131) (xy 102.1085 -224.692171)
			(xy 102.06368 -224.668057) (xy 102.023085 -224.637359) (xy 101.987675 -224.600802) (xy 101.958286 -224.55925)
			(xy 101.935612 -224.513684) (xy 101.92019 -224.465182) (xy 101.912384 -224.414889) (xy 101.911912 -224.389442)
			(xy 101.63302 -224.389442) (xy 101.632511 -224.415409) (xy 101.624386 -224.466704) (xy 101.608338 -224.516097)
			(xy 101.58476 -224.562371) (xy 101.554234 -224.604387) (xy 101.517511 -224.64111) (xy 101.475495 -224.671636)
			(xy 101.429221 -224.695214) (xy 101.379828 -224.711262) (xy 101.328533 -224.719387) (xy 101.276599 -224.719387)
			(xy 101.225304 -224.711262) (xy 101.175911 -224.695214) (xy 101.129637 -224.671636) (xy 101.087621 -224.64111)
			(xy 101.050898 -224.604387) (xy 101.020372 -224.562371) (xy 100.996794 -224.516097) (xy 100.980746 -224.466704)
			(xy 100.972621 -224.415409) (xy 100.972112 -224.389442) (xy 100.69322 -224.389442) (xy 100.692612 -224.417423)
			(xy 100.68317 -224.472584) (xy 100.674424 -224.49917) (xy 100.666804 -224.521268) (xy 100.854764 -224.846896)
			(xy 100.879402 -224.850198) (xy 100.906893 -224.854397) (xy 100.960206 -224.870211) (xy 101.010415 -224.894118)
			(xy 101.056298 -224.925537) (xy 101.096742 -224.963704) (xy 101.130763 -225.007692) (xy 101.157535 -225.056433)
			(xy 101.176408 -225.108742) (xy 101.18217 -225.135948) (xy 101.183694 -225.145346) (xy 101.186662 -225.15952)
			(xy 101.199396 -225.185513) (xy 101.218905 -225.206895) (xy 101.243626 -225.221951) (xy 101.271576 -225.229474)
			(xy 101.286056 -225.229674) (xy 101.30282 -225.229674) (xy 101.351922 -225.230442) (xy 101.449362 -225.242667)
			(xy 101.49713 -225.254058) (xy 101.50348 -225.255582) (xy 101.525578 -225.255582) (xy 101.55056 -225.256099)
			(xy 101.599902 -225.263959) (xy 101.647412 -225.279427) (xy 101.691924 -225.302124) (xy 101.732346 -225.331492)
			(xy 101.750368 -225.3488) (xy 101.945948 -225.54438) (xy 101.965958 -225.565232) (xy 101.998805 -225.612774)
			(xy 102.011226 -225.638868) (xy 102.014782 -225.646996) (xy 102.039928 -225.672904) (xy 102.102158 -225.701352)
			(xy 102.107105 -225.703463) (xy 102.117609 -225.705772) (xy 102.122986 -225.705924) (xy 102.138226 -225.703384)
			(xy 102.139496 -225.70313) (xy 102.164517 -225.695444) (xy 102.216196 -225.68715) (xy 102.242366 -225.68662)
			(xy 102.268356 -225.687101) (xy 102.319697 -225.695228) (xy 102.369135 -225.711287) (xy 102.41545 -225.734884)
			(xy 102.457504 -225.765436) (xy 102.49426 -225.802191) (xy 102.524813 -225.844244) (xy 102.54841 -225.89056)
			(xy 102.564471 -225.939997) (xy 102.572599 -225.991338) (xy 102.573074 -226.017328) (xy 102.572556 -226.043295)
			(xy 102.852221 -226.043295) (xy 102.852221 -225.991361) (xy 102.860346 -225.940066) (xy 102.876394 -225.890673)
			(xy 102.899972 -225.844399) (xy 102.930498 -225.802383) (xy 102.967221 -225.76566) (xy 103.009237 -225.735134)
			(xy 103.055511 -225.711556) (xy 103.104904 -225.695508) (xy 103.156199 -225.687383) (xy 103.208133 -225.687383)
			(xy 103.259428 -225.695508) (xy 103.308821 -225.711556) (xy 103.355095 -225.735134) (xy 103.397111 -225.76566)
			(xy 103.433834 -225.802383) (xy 103.46436 -225.844399) (xy 103.487938 -225.890673) (xy 103.503986 -225.940066)
			(xy 103.512111 -225.991361) (xy 103.51262 -226.017328) (xy 103.512111 -226.043295) (xy 103.792021 -226.043295)
			(xy 103.792021 -225.991361) (xy 103.800146 -225.940066) (xy 103.816194 -225.890673) (xy 103.839772 -225.844399)
			(xy 103.870298 -225.802383) (xy 103.907021 -225.76566) (xy 103.949037 -225.735134) (xy 103.995311 -225.711556)
			(xy 104.044704 -225.695508) (xy 104.095999 -225.687383) (xy 104.147933 -225.687383) (xy 104.199228 -225.695508)
			(xy 104.248621 -225.711556) (xy 104.294895 -225.735134) (xy 104.336911 -225.76566) (xy 104.373634 -225.802383)
			(xy 104.40416 -225.844399) (xy 104.427738 -225.890673) (xy 104.443786 -225.940066) (xy 104.451911 -225.991361)
			(xy 104.45242 -226.017328) (xy 104.451911 -226.043295) (xy 104.443786 -226.09459) (xy 104.427738 -226.143983)
			(xy 104.40416 -226.190257) (xy 104.373634 -226.232273) (xy 104.336911 -226.268996) (xy 104.294895 -226.299522)
			(xy 104.248621 -226.3231) (xy 104.199228 -226.339148) (xy 104.147933 -226.347273) (xy 104.095999 -226.347273)
			(xy 104.044704 -226.339148) (xy 103.995311 -226.3231) (xy 103.949037 -226.299522) (xy 103.907021 -226.268996)
			(xy 103.870298 -226.232273) (xy 103.839772 -226.190257) (xy 103.816194 -226.143983) (xy 103.800146 -226.09459)
			(xy 103.792021 -226.043295) (xy 103.512111 -226.043295) (xy 103.503986 -226.09459) (xy 103.487938 -226.143983)
			(xy 103.46436 -226.190257) (xy 103.433834 -226.232273) (xy 103.397111 -226.268996) (xy 103.355095 -226.299522)
			(xy 103.308821 -226.3231) (xy 103.259428 -226.339148) (xy 103.208133 -226.347273) (xy 103.156199 -226.347273)
			(xy 103.104904 -226.339148) (xy 103.055511 -226.3231) (xy 103.009237 -226.299522) (xy 102.967221 -226.268996)
			(xy 102.930498 -226.232273) (xy 102.899972 -226.190257) (xy 102.876394 -226.143983) (xy 102.860346 -226.09459)
			(xy 102.852221 -226.043295) (xy 102.572556 -226.043295) (xy 102.572533 -226.044459) (xy 102.563683 -226.097995)
			(xy 102.546208 -226.149367) (xy 102.520579 -226.197195) (xy 102.487482 -226.240195) (xy 102.447808 -226.277213)
			(xy 102.4255 -226.292664) (xy 102.422452 -226.294696) (xy 102.400354 -226.331272) (xy 102.396798 -226.364038)
			(xy 102.54615 -226.51339) (xy 102.547928 -226.51339) (xy 102.5779 -226.501198) (xy 102.599231 -226.492908)
			(xy 102.643488 -226.481252) (xy 102.688875 -226.475373) (xy 102.711758 -226.475036) (xy 102.712012 -226.475036)
			(xy 102.738657 -226.475535) (xy 102.791353 -226.483479) (xy 102.842276 -226.499188) (xy 102.890288 -226.522311)
			(xy 102.934319 -226.552332) (xy 102.973383 -226.58858) (xy 103.006609 -226.630245) (xy 103.033254 -226.676396)
			(xy 103.052723 -226.726003) (xy 103.064581 -226.777958) (xy 103.068563 -226.8311) (xy 103.066614 -226.857111)
			(xy 103.322121 -226.857111) (xy 103.322121 -226.805177) (xy 103.330246 -226.753882) (xy 103.346294 -226.704489)
			(xy 103.369872 -226.658215) (xy 103.400398 -226.616199) (xy 103.437121 -226.579476) (xy 103.479137 -226.54895)
			(xy 103.525411 -226.525372) (xy 103.574804 -226.509324) (xy 103.626099 -226.501199) (xy 103.678033 -226.501199)
			(xy 103.729328 -226.509324) (xy 103.778721 -226.525372) (xy 103.824995 -226.54895) (xy 103.867011 -226.579476)
			(xy 103.903734 -226.616199) (xy 103.93426 -226.658215) (xy 103.957838 -226.704489) (xy 103.973886 -226.753882)
			(xy 103.982011 -226.805177) (xy 103.98252 -226.831144) (xy 103.982011 -226.857111) (xy 104.261921 -226.857111)
			(xy 104.261921 -226.805177) (xy 104.270046 -226.753882) (xy 104.286094 -226.704489) (xy 104.309672 -226.658215)
			(xy 104.340198 -226.616199) (xy 104.376921 -226.579476) (xy 104.418937 -226.54895) (xy 104.465211 -226.525372)
			(xy 104.514604 -226.509324) (xy 104.565899 -226.501199) (xy 104.617833 -226.501199) (xy 104.669128 -226.509324)
			(xy 104.718521 -226.525372) (xy 104.764795 -226.54895) (xy 104.806811 -226.579476) (xy 104.843534 -226.616199)
			(xy 104.87406 -226.658215) (xy 104.897638 -226.704489) (xy 104.913686 -226.753882) (xy 104.921811 -226.805177)
			(xy 104.92232 -226.831144) (xy 104.921811 -226.857111) (xy 105.201467 -226.857111) (xy 105.201467 -226.805177)
			(xy 105.209592 -226.753882) (xy 105.22564 -226.704489) (xy 105.249218 -226.658215) (xy 105.279744 -226.616199)
			(xy 105.316467 -226.579476) (xy 105.358483 -226.54895) (xy 105.404757 -226.525372) (xy 105.45415 -226.509324)
			(xy 105.505445 -226.501199) (xy 105.557379 -226.501199) (xy 105.608674 -226.509324) (xy 105.658067 -226.525372)
			(xy 105.704341 -226.54895) (xy 105.746357 -226.579476) (xy 105.78308 -226.616199) (xy 105.813606 -226.658215)
			(xy 105.837184 -226.704489) (xy 105.853232 -226.753882) (xy 105.861357 -226.805177) (xy 105.861866 -226.831144)
			(xy 105.861357 -226.857111) (xy 106.141521 -226.857111) (xy 106.141521 -226.805177) (xy 106.149646 -226.753882)
			(xy 106.165694 -226.704489) (xy 106.189272 -226.658215) (xy 106.219798 -226.616199) (xy 106.256521 -226.579476)
			(xy 106.298537 -226.54895) (xy 106.344811 -226.525372) (xy 106.394204 -226.509324) (xy 106.445499 -226.501199)
			(xy 106.497433 -226.501199) (xy 106.548728 -226.509324) (xy 106.598121 -226.525372) (xy 106.644395 -226.54895)
			(xy 106.686411 -226.579476) (xy 106.723134 -226.616199) (xy 106.75366 -226.658215) (xy 106.777238 -226.704489)
			(xy 106.793286 -226.753882) (xy 106.801411 -226.805177) (xy 106.80192 -226.831144) (xy 106.801411 -226.857111)
			(xy 107.081067 -226.857111) (xy 107.081067 -226.805177) (xy 107.089192 -226.753882) (xy 107.10524 -226.704489)
			(xy 107.128818 -226.658215) (xy 107.159344 -226.616199) (xy 107.196067 -226.579476) (xy 107.238083 -226.54895)
			(xy 107.284357 -226.525372) (xy 107.33375 -226.509324) (xy 107.385045 -226.501199) (xy 107.436979 -226.501199)
			(xy 107.488274 -226.509324) (xy 107.537667 -226.525372) (xy 107.583941 -226.54895) (xy 107.625957 -226.579476)
			(xy 107.66268 -226.616199) (xy 107.693206 -226.658215) (xy 107.716784 -226.704489) (xy 107.732832 -226.753882)
			(xy 107.740957 -226.805177) (xy 107.741466 -226.831144) (xy 107.740957 -226.857111) (xy 108.021121 -226.857111)
			(xy 108.021121 -226.805177) (xy 108.029246 -226.753882) (xy 108.045294 -226.704489) (xy 108.068872 -226.658215)
			(xy 108.099398 -226.616199) (xy 108.136121 -226.579476) (xy 108.178137 -226.54895) (xy 108.224411 -226.525372)
			(xy 108.273804 -226.509324) (xy 108.325099 -226.501199) (xy 108.377033 -226.501199) (xy 108.428328 -226.509324)
			(xy 108.477721 -226.525372) (xy 108.523995 -226.54895) (xy 108.566011 -226.579476) (xy 108.602734 -226.616199)
			(xy 108.63326 -226.658215) (xy 108.656838 -226.704489) (xy 108.672886 -226.753882) (xy 108.681011 -226.805177)
			(xy 108.68152 -226.831144) (xy 108.681011 -226.857111) (xy 108.960667 -226.857111) (xy 108.960667 -226.805177)
			(xy 108.968792 -226.753882) (xy 108.98484 -226.704489) (xy 109.008418 -226.658215) (xy 109.038944 -226.616199)
			(xy 109.075667 -226.579476) (xy 109.117683 -226.54895) (xy 109.163957 -226.525372) (xy 109.21335 -226.509324)
			(xy 109.264645 -226.501199) (xy 109.316579 -226.501199) (xy 109.367874 -226.509324) (xy 109.417267 -226.525372)
			(xy 109.463541 -226.54895) (xy 109.505557 -226.579476) (xy 109.54228 -226.616199) (xy 109.572806 -226.658215)
			(xy 109.596384 -226.704489) (xy 109.612432 -226.753882) (xy 109.620557 -226.805177) (xy 109.621066 -226.831144)
			(xy 109.620557 -226.857111) (xy 109.900721 -226.857111) (xy 109.900721 -226.805177) (xy 109.908846 -226.753882)
			(xy 109.924894 -226.704489) (xy 109.948472 -226.658215) (xy 109.978998 -226.616199) (xy 110.015721 -226.579476)
			(xy 110.057737 -226.54895) (xy 110.104011 -226.525372) (xy 110.153404 -226.509324) (xy 110.204699 -226.501199)
			(xy 110.256633 -226.501199) (xy 110.307928 -226.509324) (xy 110.357321 -226.525372) (xy 110.403595 -226.54895)
			(xy 110.445611 -226.579476) (xy 110.482334 -226.616199) (xy 110.51286 -226.658215) (xy 110.536438 -226.704489)
			(xy 110.552486 -226.753882) (xy 110.560611 -226.805177) (xy 110.56112 -226.831144) (xy 110.560611 -226.857111)
			(xy 110.840267 -226.857111) (xy 110.840267 -226.805177) (xy 110.848392 -226.753882) (xy 110.86444 -226.704489)
			(xy 110.888018 -226.658215) (xy 110.918544 -226.616199) (xy 110.955267 -226.579476) (xy 110.997283 -226.54895)
			(xy 111.043557 -226.525372) (xy 111.09295 -226.509324) (xy 111.144245 -226.501199) (xy 111.196179 -226.501199)
			(xy 111.247474 -226.509324) (xy 111.296867 -226.525372) (xy 111.343141 -226.54895) (xy 111.385157 -226.579476)
			(xy 111.42188 -226.616199) (xy 111.452406 -226.658215) (xy 111.475984 -226.704489) (xy 111.492032 -226.753882)
			(xy 111.500157 -226.805177) (xy 111.500666 -226.831144) (xy 111.500157 -226.857111) (xy 111.780321 -226.857111)
			(xy 111.780321 -226.805177) (xy 111.788446 -226.753882) (xy 111.804494 -226.704489) (xy 111.828072 -226.658215)
			(xy 111.858598 -226.616199) (xy 111.895321 -226.579476) (xy 111.937337 -226.54895) (xy 111.983611 -226.525372)
			(xy 112.033004 -226.509324) (xy 112.084299 -226.501199) (xy 112.136233 -226.501199) (xy 112.187528 -226.509324)
			(xy 112.236921 -226.525372) (xy 112.283195 -226.54895) (xy 112.325211 -226.579476) (xy 112.361934 -226.616199)
			(xy 112.39246 -226.658215) (xy 112.416038 -226.704489) (xy 112.432086 -226.753882) (xy 112.440211 -226.805177)
			(xy 112.44072 -226.831144) (xy 112.440211 -226.857111) (xy 112.719867 -226.857111) (xy 112.719867 -226.805177)
			(xy 112.727992 -226.753882) (xy 112.74404 -226.704489) (xy 112.767618 -226.658215) (xy 112.798144 -226.616199)
			(xy 112.834867 -226.579476) (xy 112.876883 -226.54895) (xy 112.923157 -226.525372) (xy 112.97255 -226.509324)
			(xy 113.023845 -226.501199) (xy 113.075779 -226.501199) (xy 113.127074 -226.509324) (xy 113.176467 -226.525372)
			(xy 113.222741 -226.54895) (xy 113.264757 -226.579476) (xy 113.30148 -226.616199) (xy 113.332006 -226.658215)
			(xy 113.355584 -226.704489) (xy 113.371632 -226.753882) (xy 113.379757 -226.805177) (xy 113.380266 -226.831144)
			(xy 113.379757 -226.857111) (xy 113.659921 -226.857111) (xy 113.659921 -226.805177) (xy 113.668046 -226.753882)
			(xy 113.684094 -226.704489) (xy 113.707672 -226.658215) (xy 113.738198 -226.616199) (xy 113.774921 -226.579476)
			(xy 113.816937 -226.54895) (xy 113.863211 -226.525372) (xy 113.912604 -226.509324) (xy 113.963899 -226.501199)
			(xy 114.015833 -226.501199) (xy 114.067128 -226.509324) (xy 114.116521 -226.525372) (xy 114.162795 -226.54895)
			(xy 114.204811 -226.579476) (xy 114.241534 -226.616199) (xy 114.27206 -226.658215) (xy 114.295638 -226.704489)
			(xy 114.311686 -226.753882) (xy 114.319811 -226.805177) (xy 114.32032 -226.831144) (xy 114.319811 -226.857111)
			(xy 114.599721 -226.857111) (xy 114.599721 -226.805177) (xy 114.607846 -226.753882) (xy 114.623894 -226.704489)
			(xy 114.647472 -226.658215) (xy 114.677998 -226.616199) (xy 114.714721 -226.579476) (xy 114.756737 -226.54895)
			(xy 114.803011 -226.525372) (xy 114.852404 -226.509324) (xy 114.903699 -226.501199) (xy 114.955633 -226.501199)
			(xy 115.006928 -226.509324) (xy 115.056321 -226.525372) (xy 115.102595 -226.54895) (xy 115.144611 -226.579476)
			(xy 115.181334 -226.616199) (xy 115.21186 -226.658215) (xy 115.235438 -226.704489) (xy 115.251486 -226.753882)
			(xy 115.259611 -226.805177) (xy 115.26012 -226.831144) (xy 115.259611 -226.857111) (xy 115.539521 -226.857111)
			(xy 115.539521 -226.805177) (xy 115.547646 -226.753882) (xy 115.563694 -226.704489) (xy 115.587272 -226.658215)
			(xy 115.617798 -226.616199) (xy 115.654521 -226.579476) (xy 115.696537 -226.54895) (xy 115.742811 -226.525372)
			(xy 115.792204 -226.509324) (xy 115.843499 -226.501199) (xy 115.895433 -226.501199) (xy 115.946728 -226.509324)
			(xy 115.996121 -226.525372) (xy 116.042395 -226.54895) (xy 116.084411 -226.579476) (xy 116.121134 -226.616199)
			(xy 116.15166 -226.658215) (xy 116.175238 -226.704489) (xy 116.191286 -226.753882) (xy 116.199411 -226.805177)
			(xy 116.19992 -226.831144) (xy 116.199411 -226.857111) (xy 116.479067 -226.857111) (xy 116.479067 -226.805177)
			(xy 116.487192 -226.753882) (xy 116.50324 -226.704489) (xy 116.526818 -226.658215) (xy 116.557344 -226.616199)
			(xy 116.594067 -226.579476) (xy 116.636083 -226.54895) (xy 116.682357 -226.525372) (xy 116.73175 -226.509324)
			(xy 116.783045 -226.501199) (xy 116.834979 -226.501199) (xy 116.886274 -226.509324) (xy 116.935667 -226.525372)
			(xy 116.981941 -226.54895) (xy 117.023957 -226.579476) (xy 117.06068 -226.616199) (xy 117.091206 -226.658215)
			(xy 117.114784 -226.704489) (xy 117.130832 -226.753882) (xy 117.138957 -226.805177) (xy 117.139466 -226.831144)
			(xy 117.138957 -226.857111) (xy 117.419121 -226.857111) (xy 117.419121 -226.805177) (xy 117.427246 -226.753882)
			(xy 117.443294 -226.704489) (xy 117.466872 -226.658215) (xy 117.497398 -226.616199) (xy 117.534121 -226.579476)
			(xy 117.576137 -226.54895) (xy 117.622411 -226.525372) (xy 117.671804 -226.509324) (xy 117.723099 -226.501199)
			(xy 117.775033 -226.501199) (xy 117.826328 -226.509324) (xy 117.875721 -226.525372) (xy 117.921995 -226.54895)
			(xy 117.964011 -226.579476) (xy 118.000734 -226.616199) (xy 118.03126 -226.658215) (xy 118.054838 -226.704489)
			(xy 118.070886 -226.753882) (xy 118.079011 -226.805177) (xy 118.07952 -226.831144) (xy 118.079011 -226.857111)
			(xy 118.358667 -226.857111) (xy 118.358667 -226.805177) (xy 118.366792 -226.753882) (xy 118.38284 -226.704489)
			(xy 118.406418 -226.658215) (xy 118.436944 -226.616199) (xy 118.473667 -226.579476) (xy 118.515683 -226.54895)
			(xy 118.561957 -226.525372) (xy 118.61135 -226.509324) (xy 118.662645 -226.501199) (xy 118.714579 -226.501199)
			(xy 118.765874 -226.509324) (xy 118.815267 -226.525372) (xy 118.861541 -226.54895) (xy 118.903557 -226.579476)
			(xy 118.94028 -226.616199) (xy 118.970806 -226.658215) (xy 118.994384 -226.704489) (xy 119.010432 -226.753882)
			(xy 119.018557 -226.805177) (xy 119.019066 -226.831144) (xy 119.018557 -226.857111) (xy 119.298721 -226.857111)
			(xy 119.298721 -226.805177) (xy 119.306846 -226.753882) (xy 119.322894 -226.704489) (xy 119.346472 -226.658215)
			(xy 119.376998 -226.616199) (xy 119.413721 -226.579476) (xy 119.455737 -226.54895) (xy 119.502011 -226.525372)
			(xy 119.551404 -226.509324) (xy 119.602699 -226.501199) (xy 119.654633 -226.501199) (xy 119.705928 -226.509324)
			(xy 119.755321 -226.525372) (xy 119.801595 -226.54895) (xy 119.843611 -226.579476) (xy 119.880334 -226.616199)
			(xy 119.91086 -226.658215) (xy 119.934438 -226.704489) (xy 119.950486 -226.753882) (xy 119.958611 -226.805177)
			(xy 119.95912 -226.831144) (xy 119.958611 -226.857111) (xy 120.238267 -226.857111) (xy 120.238267 -226.805177)
			(xy 120.246392 -226.753882) (xy 120.26244 -226.704489) (xy 120.286018 -226.658215) (xy 120.316544 -226.616199)
			(xy 120.353267 -226.579476) (xy 120.395283 -226.54895) (xy 120.441557 -226.525372) (xy 120.49095 -226.509324)
			(xy 120.542245 -226.501199) (xy 120.594179 -226.501199) (xy 120.645474 -226.509324) (xy 120.694867 -226.525372)
			(xy 120.741141 -226.54895) (xy 120.783157 -226.579476) (xy 120.81988 -226.616199) (xy 120.850406 -226.658215)
			(xy 120.873984 -226.704489) (xy 120.890032 -226.753882) (xy 120.898157 -226.805177) (xy 120.898666 -226.831144)
			(xy 120.898157 -226.857111) (xy 121.178321 -226.857111) (xy 121.178321 -226.805177) (xy 121.186446 -226.753882)
			(xy 121.202494 -226.704489) (xy 121.226072 -226.658215) (xy 121.256598 -226.616199) (xy 121.293321 -226.579476)
			(xy 121.335337 -226.54895) (xy 121.381611 -226.525372) (xy 121.431004 -226.509324) (xy 121.482299 -226.501199)
			(xy 121.534233 -226.501199) (xy 121.585528 -226.509324) (xy 121.634921 -226.525372) (xy 121.681195 -226.54895)
			(xy 121.723211 -226.579476) (xy 121.759934 -226.616199) (xy 121.79046 -226.658215) (xy 121.814038 -226.704489)
			(xy 121.830086 -226.753882) (xy 121.838211 -226.805177) (xy 121.83872 -226.831144) (xy 121.838211 -226.857111)
			(xy 122.117867 -226.857111) (xy 122.117867 -226.805177) (xy 122.125992 -226.753882) (xy 122.14204 -226.704489)
			(xy 122.165618 -226.658215) (xy 122.196144 -226.616199) (xy 122.232867 -226.579476) (xy 122.274883 -226.54895)
			(xy 122.321157 -226.525372) (xy 122.37055 -226.509324) (xy 122.421845 -226.501199) (xy 122.473779 -226.501199)
			(xy 122.525074 -226.509324) (xy 122.574467 -226.525372) (xy 122.620741 -226.54895) (xy 122.662757 -226.579476)
			(xy 122.69948 -226.616199) (xy 122.730006 -226.658215) (xy 122.753584 -226.704489) (xy 122.769632 -226.753882)
			(xy 122.777757 -226.805177) (xy 122.778266 -226.831144) (xy 122.777757 -226.857111) (xy 123.057667 -226.857111)
			(xy 123.057667 -226.805177) (xy 123.065792 -226.753882) (xy 123.08184 -226.704489) (xy 123.105418 -226.658215)
			(xy 123.135944 -226.616199) (xy 123.172667 -226.579476) (xy 123.214683 -226.54895) (xy 123.260957 -226.525372)
			(xy 123.31035 -226.509324) (xy 123.361645 -226.501199) (xy 123.413579 -226.501199) (xy 123.464874 -226.509324)
			(xy 123.514267 -226.525372) (xy 123.560541 -226.54895) (xy 123.602557 -226.579476) (xy 123.63928 -226.616199)
			(xy 123.669806 -226.658215) (xy 123.693384 -226.704489) (xy 123.709432 -226.753882) (xy 123.717557 -226.805177)
			(xy 123.718066 -226.831144) (xy 123.717557 -226.857111) (xy 123.997721 -226.857111) (xy 123.997721 -226.805177)
			(xy 124.005846 -226.753882) (xy 124.021894 -226.704489) (xy 124.045472 -226.658215) (xy 124.075998 -226.616199)
			(xy 124.112721 -226.579476) (xy 124.154737 -226.54895) (xy 124.201011 -226.525372) (xy 124.250404 -226.509324)
			(xy 124.301699 -226.501199) (xy 124.353633 -226.501199) (xy 124.404928 -226.509324) (xy 124.454321 -226.525372)
			(xy 124.500595 -226.54895) (xy 124.542611 -226.579476) (xy 124.579334 -226.616199) (xy 124.60986 -226.658215)
			(xy 124.633438 -226.704489) (xy 124.649486 -226.753882) (xy 124.657611 -226.805177) (xy 124.65812 -226.831144)
			(xy 124.657611 -226.857111) (xy 124.937267 -226.857111) (xy 124.937267 -226.805177) (xy 124.945392 -226.753882)
			(xy 124.96144 -226.704489) (xy 124.985018 -226.658215) (xy 125.015544 -226.616199) (xy 125.052267 -226.579476)
			(xy 125.094283 -226.54895) (xy 125.140557 -226.525372) (xy 125.18995 -226.509324) (xy 125.241245 -226.501199)
			(xy 125.293179 -226.501199) (xy 125.344474 -226.509324) (xy 125.393867 -226.525372) (xy 125.440141 -226.54895)
			(xy 125.482157 -226.579476) (xy 125.51888 -226.616199) (xy 125.549406 -226.658215) (xy 125.572984 -226.704489)
			(xy 125.589032 -226.753882) (xy 125.597157 -226.805177) (xy 125.597666 -226.831144) (xy 125.597157 -226.857111)
			(xy 125.877067 -226.857111) (xy 125.877067 -226.805177) (xy 125.885192 -226.753882) (xy 125.90124 -226.704489)
			(xy 125.924818 -226.658215) (xy 125.955344 -226.616199) (xy 125.992067 -226.579476) (xy 126.034083 -226.54895)
			(xy 126.080357 -226.525372) (xy 126.12975 -226.509324) (xy 126.181045 -226.501199) (xy 126.232979 -226.501199)
			(xy 126.284274 -226.509324) (xy 126.333667 -226.525372) (xy 126.379941 -226.54895) (xy 126.421957 -226.579476)
			(xy 126.45868 -226.616199) (xy 126.489206 -226.658215) (xy 126.512784 -226.704489) (xy 126.528832 -226.753882)
			(xy 126.536957 -226.805177) (xy 126.537466 -226.831144) (xy 126.536957 -226.857111) (xy 126.817121 -226.857111)
			(xy 126.817121 -226.805177) (xy 126.825246 -226.753882) (xy 126.841294 -226.704489) (xy 126.864872 -226.658215)
			(xy 126.895398 -226.616199) (xy 126.932121 -226.579476) (xy 126.974137 -226.54895) (xy 127.020411 -226.525372)
			(xy 127.069804 -226.509324) (xy 127.121099 -226.501199) (xy 127.173033 -226.501199) (xy 127.224328 -226.509324)
			(xy 127.273721 -226.525372) (xy 127.319995 -226.54895) (xy 127.362011 -226.579476) (xy 127.398734 -226.616199)
			(xy 127.42926 -226.658215) (xy 127.452838 -226.704489) (xy 127.468886 -226.753882) (xy 127.477011 -226.805177)
			(xy 127.47752 -226.831144) (xy 127.477011 -226.857111) (xy 127.756921 -226.857111) (xy 127.756921 -226.805177)
			(xy 127.765046 -226.753882) (xy 127.781094 -226.704489) (xy 127.804672 -226.658215) (xy 127.835198 -226.616199)
			(xy 127.871921 -226.579476) (xy 127.913937 -226.54895) (xy 127.960211 -226.525372) (xy 128.009604 -226.509324)
			(xy 128.060899 -226.501199) (xy 128.112833 -226.501199) (xy 128.164128 -226.509324) (xy 128.213521 -226.525372)
			(xy 128.259795 -226.54895) (xy 128.301811 -226.579476) (xy 128.338534 -226.616199) (xy 128.36906 -226.658215)
			(xy 128.392638 -226.704489) (xy 128.408686 -226.753882) (xy 128.416811 -226.805177) (xy 128.41732 -226.831144)
			(xy 128.416811 -226.857111) (xy 128.696467 -226.857111) (xy 128.696467 -226.805177) (xy 128.704592 -226.753882)
			(xy 128.72064 -226.704489) (xy 128.744218 -226.658215) (xy 128.774744 -226.616199) (xy 128.811467 -226.579476)
			(xy 128.853483 -226.54895) (xy 128.899757 -226.525372) (xy 128.94915 -226.509324) (xy 129.000445 -226.501199)
			(xy 129.052379 -226.501199) (xy 129.103674 -226.509324) (xy 129.153067 -226.525372) (xy 129.199341 -226.54895)
			(xy 129.241357 -226.579476) (xy 129.27808 -226.616199) (xy 129.308606 -226.658215) (xy 129.332184 -226.704489)
			(xy 129.348232 -226.753882) (xy 129.356357 -226.805177) (xy 129.356866 -226.831144) (xy 129.356357 -226.857111)
			(xy 129.636267 -226.857111) (xy 129.636267 -226.805177) (xy 129.644392 -226.753882) (xy 129.66044 -226.704489)
			(xy 129.684018 -226.658215) (xy 129.714544 -226.616199) (xy 129.751267 -226.579476) (xy 129.793283 -226.54895)
			(xy 129.839557 -226.525372) (xy 129.88895 -226.509324) (xy 129.940245 -226.501199) (xy 129.992179 -226.501199)
			(xy 130.043474 -226.509324) (xy 130.092867 -226.525372) (xy 130.139141 -226.54895) (xy 130.181157 -226.579476)
			(xy 130.21788 -226.616199) (xy 130.248406 -226.658215) (xy 130.271984 -226.704489) (xy 130.288032 -226.753882)
			(xy 130.296157 -226.805177) (xy 130.296666 -226.831144) (xy 130.296157 -226.857111) (xy 130.576321 -226.857111)
			(xy 130.576321 -226.805177) (xy 130.584446 -226.753882) (xy 130.600494 -226.704489) (xy 130.624072 -226.658215)
			(xy 130.654598 -226.616199) (xy 130.691321 -226.579476) (xy 130.733337 -226.54895) (xy 130.779611 -226.525372)
			(xy 130.829004 -226.509324) (xy 130.880299 -226.501199) (xy 130.932233 -226.501199) (xy 130.983528 -226.509324)
			(xy 131.032921 -226.525372) (xy 131.079195 -226.54895) (xy 131.121211 -226.579476) (xy 131.157934 -226.616199)
			(xy 131.18846 -226.658215) (xy 131.212038 -226.704489) (xy 131.228086 -226.753882) (xy 131.236211 -226.805177)
			(xy 131.23672 -226.831144) (xy 131.236211 -226.857111) (xy 131.515867 -226.857111) (xy 131.515867 -226.805177)
			(xy 131.523992 -226.753882) (xy 131.54004 -226.704489) (xy 131.563618 -226.658215) (xy 131.594144 -226.616199)
			(xy 131.630867 -226.579476) (xy 131.672883 -226.54895) (xy 131.719157 -226.525372) (xy 131.76855 -226.509324)
			(xy 131.819845 -226.501199) (xy 131.871779 -226.501199) (xy 131.923074 -226.509324) (xy 131.972467 -226.525372)
			(xy 132.018741 -226.54895) (xy 132.060757 -226.579476) (xy 132.09748 -226.616199) (xy 132.128006 -226.658215)
			(xy 132.151584 -226.704489) (xy 132.167632 -226.753882) (xy 132.175757 -226.805177) (xy 132.176266 -226.831144)
			(xy 132.175757 -226.857111) (xy 132.455667 -226.857111) (xy 132.455667 -226.805177) (xy 132.463792 -226.753882)
			(xy 132.47984 -226.704489) (xy 132.503418 -226.658215) (xy 132.533944 -226.616199) (xy 132.570667 -226.579476)
			(xy 132.612683 -226.54895) (xy 132.658957 -226.525372) (xy 132.70835 -226.509324) (xy 132.759645 -226.501199)
			(xy 132.811579 -226.501199) (xy 132.862874 -226.509324) (xy 132.912267 -226.525372) (xy 132.958541 -226.54895)
			(xy 133.000557 -226.579476) (xy 133.03728 -226.616199) (xy 133.067806 -226.658215) (xy 133.091384 -226.704489)
			(xy 133.107432 -226.753882) (xy 133.115557 -226.805177) (xy 133.116066 -226.831144) (xy 133.115557 -226.857111)
			(xy 133.395721 -226.857111) (xy 133.395721 -226.805177) (xy 133.403846 -226.753882) (xy 133.419894 -226.704489)
			(xy 133.443472 -226.658215) (xy 133.473998 -226.616199) (xy 133.510721 -226.579476) (xy 133.552737 -226.54895)
			(xy 133.599011 -226.525372) (xy 133.648404 -226.509324) (xy 133.699699 -226.501199) (xy 133.751633 -226.501199)
			(xy 133.802928 -226.509324) (xy 133.852321 -226.525372) (xy 133.898595 -226.54895) (xy 133.940611 -226.579476)
			(xy 133.977334 -226.616199) (xy 134.00786 -226.658215) (xy 134.031438 -226.704489) (xy 134.047486 -226.753882)
			(xy 134.055611 -226.805177) (xy 134.05612 -226.831144) (xy 134.055611 -226.857111) (xy 134.047486 -226.908406)
			(xy 134.031438 -226.957799) (xy 134.00786 -227.004073) (xy 133.977334 -227.046089) (xy 133.940611 -227.082812)
			(xy 133.898595 -227.113338) (xy 133.852321 -227.136916) (xy 133.802928 -227.152964) (xy 133.751633 -227.161089)
			(xy 133.699699 -227.161089) (xy 133.648404 -227.152964) (xy 133.599011 -227.136916) (xy 133.552737 -227.113338)
			(xy 133.510721 -227.082812) (xy 133.473998 -227.046089) (xy 133.443472 -227.004073) (xy 133.419894 -226.957799)
			(xy 133.403846 -226.908406) (xy 133.395721 -226.857111) (xy 133.115557 -226.857111) (xy 133.107432 -226.908406)
			(xy 133.091384 -226.957799) (xy 133.067806 -227.004073) (xy 133.03728 -227.046089) (xy 133.000557 -227.082812)
			(xy 132.958541 -227.113338) (xy 132.912267 -227.136916) (xy 132.862874 -227.152964) (xy 132.811579 -227.161089)
			(xy 132.759645 -227.161089) (xy 132.70835 -227.152964) (xy 132.658957 -227.136916) (xy 132.612683 -227.113338)
			(xy 132.570667 -227.082812) (xy 132.533944 -227.046089) (xy 132.503418 -227.004073) (xy 132.47984 -226.957799)
			(xy 132.463792 -226.908406) (xy 132.455667 -226.857111) (xy 132.175757 -226.857111) (xy 132.167632 -226.908406)
			(xy 132.151584 -226.957799) (xy 132.128006 -227.004073) (xy 132.09748 -227.046089) (xy 132.060757 -227.082812)
			(xy 132.018741 -227.113338) (xy 131.972467 -227.136916) (xy 131.923074 -227.152964) (xy 131.871779 -227.161089)
			(xy 131.819845 -227.161089) (xy 131.76855 -227.152964) (xy 131.719157 -227.136916) (xy 131.672883 -227.113338)
			(xy 131.630867 -227.082812) (xy 131.594144 -227.046089) (xy 131.563618 -227.004073) (xy 131.54004 -226.957799)
			(xy 131.523992 -226.908406) (xy 131.515867 -226.857111) (xy 131.236211 -226.857111) (xy 131.228086 -226.908406)
			(xy 131.212038 -226.957799) (xy 131.18846 -227.004073) (xy 131.157934 -227.046089) (xy 131.121211 -227.082812)
			(xy 131.079195 -227.113338) (xy 131.032921 -227.136916) (xy 130.983528 -227.152964) (xy 130.932233 -227.161089)
			(xy 130.880299 -227.161089) (xy 130.829004 -227.152964) (xy 130.779611 -227.136916) (xy 130.733337 -227.113338)
			(xy 130.691321 -227.082812) (xy 130.654598 -227.046089) (xy 130.624072 -227.004073) (xy 130.600494 -226.957799)
			(xy 130.584446 -226.908406) (xy 130.576321 -226.857111) (xy 130.296157 -226.857111) (xy 130.288032 -226.908406)
			(xy 130.271984 -226.957799) (xy 130.248406 -227.004073) (xy 130.21788 -227.046089) (xy 130.181157 -227.082812)
			(xy 130.139141 -227.113338) (xy 130.092867 -227.136916) (xy 130.043474 -227.152964) (xy 129.992179 -227.161089)
			(xy 129.940245 -227.161089) (xy 129.88895 -227.152964) (xy 129.839557 -227.136916) (xy 129.793283 -227.113338)
			(xy 129.751267 -227.082812) (xy 129.714544 -227.046089) (xy 129.684018 -227.004073) (xy 129.66044 -226.957799)
			(xy 129.644392 -226.908406) (xy 129.636267 -226.857111) (xy 129.356357 -226.857111) (xy 129.348232 -226.908406)
			(xy 129.332184 -226.957799) (xy 129.308606 -227.004073) (xy 129.27808 -227.046089) (xy 129.241357 -227.082812)
			(xy 129.199341 -227.113338) (xy 129.153067 -227.136916) (xy 129.103674 -227.152964) (xy 129.052379 -227.161089)
			(xy 129.000445 -227.161089) (xy 128.94915 -227.152964) (xy 128.899757 -227.136916) (xy 128.853483 -227.113338)
			(xy 128.811467 -227.082812) (xy 128.774744 -227.046089) (xy 128.744218 -227.004073) (xy 128.72064 -226.957799)
			(xy 128.704592 -226.908406) (xy 128.696467 -226.857111) (xy 128.416811 -226.857111) (xy 128.408686 -226.908406)
			(xy 128.392638 -226.957799) (xy 128.36906 -227.004073) (xy 128.338534 -227.046089) (xy 128.301811 -227.082812)
			(xy 128.259795 -227.113338) (xy 128.213521 -227.136916) (xy 128.164128 -227.152964) (xy 128.112833 -227.161089)
			(xy 128.060899 -227.161089) (xy 128.009604 -227.152964) (xy 127.960211 -227.136916) (xy 127.913937 -227.113338)
			(xy 127.871921 -227.082812) (xy 127.835198 -227.046089) (xy 127.804672 -227.004073) (xy 127.781094 -226.957799)
			(xy 127.765046 -226.908406) (xy 127.756921 -226.857111) (xy 127.477011 -226.857111) (xy 127.468886 -226.908406)
			(xy 127.452838 -226.957799) (xy 127.42926 -227.004073) (xy 127.398734 -227.046089) (xy 127.362011 -227.082812)
			(xy 127.319995 -227.113338) (xy 127.273721 -227.136916) (xy 127.224328 -227.152964) (xy 127.173033 -227.161089)
			(xy 127.121099 -227.161089) (xy 127.069804 -227.152964) (xy 127.020411 -227.136916) (xy 126.974137 -227.113338)
			(xy 126.932121 -227.082812) (xy 126.895398 -227.046089) (xy 126.864872 -227.004073) (xy 126.841294 -226.957799)
			(xy 126.825246 -226.908406) (xy 126.817121 -226.857111) (xy 126.536957 -226.857111) (xy 126.528832 -226.908406)
			(xy 126.512784 -226.957799) (xy 126.489206 -227.004073) (xy 126.45868 -227.046089) (xy 126.421957 -227.082812)
			(xy 126.379941 -227.113338) (xy 126.333667 -227.136916) (xy 126.284274 -227.152964) (xy 126.232979 -227.161089)
			(xy 126.181045 -227.161089) (xy 126.12975 -227.152964) (xy 126.080357 -227.136916) (xy 126.034083 -227.113338)
			(xy 125.992067 -227.082812) (xy 125.955344 -227.046089) (xy 125.924818 -227.004073) (xy 125.90124 -226.957799)
			(xy 125.885192 -226.908406) (xy 125.877067 -226.857111) (xy 125.597157 -226.857111) (xy 125.589032 -226.908406)
			(xy 125.572984 -226.957799) (xy 125.549406 -227.004073) (xy 125.51888 -227.046089) (xy 125.482157 -227.082812)
			(xy 125.440141 -227.113338) (xy 125.393867 -227.136916) (xy 125.344474 -227.152964) (xy 125.293179 -227.161089)
			(xy 125.241245 -227.161089) (xy 125.18995 -227.152964) (xy 125.140557 -227.136916) (xy 125.094283 -227.113338)
			(xy 125.052267 -227.082812) (xy 125.015544 -227.046089) (xy 124.985018 -227.004073) (xy 124.96144 -226.957799)
			(xy 124.945392 -226.908406) (xy 124.937267 -226.857111) (xy 124.657611 -226.857111) (xy 124.649486 -226.908406)
			(xy 124.633438 -226.957799) (xy 124.60986 -227.004073) (xy 124.579334 -227.046089) (xy 124.542611 -227.082812)
			(xy 124.500595 -227.113338) (xy 124.454321 -227.136916) (xy 124.404928 -227.152964) (xy 124.353633 -227.161089)
			(xy 124.301699 -227.161089) (xy 124.250404 -227.152964) (xy 124.201011 -227.136916) (xy 124.154737 -227.113338)
			(xy 124.112721 -227.082812) (xy 124.075998 -227.046089) (xy 124.045472 -227.004073) (xy 124.021894 -226.957799)
			(xy 124.005846 -226.908406) (xy 123.997721 -226.857111) (xy 123.717557 -226.857111) (xy 123.709432 -226.908406)
			(xy 123.693384 -226.957799) (xy 123.669806 -227.004073) (xy 123.63928 -227.046089) (xy 123.602557 -227.082812)
			(xy 123.560541 -227.113338) (xy 123.514267 -227.136916) (xy 123.464874 -227.152964) (xy 123.413579 -227.161089)
			(xy 123.361645 -227.161089) (xy 123.31035 -227.152964) (xy 123.260957 -227.136916) (xy 123.214683 -227.113338)
			(xy 123.172667 -227.082812) (xy 123.135944 -227.046089) (xy 123.105418 -227.004073) (xy 123.08184 -226.957799)
			(xy 123.065792 -226.908406) (xy 123.057667 -226.857111) (xy 122.777757 -226.857111) (xy 122.769632 -226.908406)
			(xy 122.753584 -226.957799) (xy 122.730006 -227.004073) (xy 122.69948 -227.046089) (xy 122.662757 -227.082812)
			(xy 122.620741 -227.113338) (xy 122.574467 -227.136916) (xy 122.525074 -227.152964) (xy 122.473779 -227.161089)
			(xy 122.421845 -227.161089) (xy 122.37055 -227.152964) (xy 122.321157 -227.136916) (xy 122.274883 -227.113338)
			(xy 122.232867 -227.082812) (xy 122.196144 -227.046089) (xy 122.165618 -227.004073) (xy 122.14204 -226.957799)
			(xy 122.125992 -226.908406) (xy 122.117867 -226.857111) (xy 121.838211 -226.857111) (xy 121.830086 -226.908406)
			(xy 121.814038 -226.957799) (xy 121.79046 -227.004073) (xy 121.759934 -227.046089) (xy 121.723211 -227.082812)
			(xy 121.681195 -227.113338) (xy 121.634921 -227.136916) (xy 121.585528 -227.152964) (xy 121.534233 -227.161089)
			(xy 121.482299 -227.161089) (xy 121.431004 -227.152964) (xy 121.381611 -227.136916) (xy 121.335337 -227.113338)
			(xy 121.293321 -227.082812) (xy 121.256598 -227.046089) (xy 121.226072 -227.004073) (xy 121.202494 -226.957799)
			(xy 121.186446 -226.908406) (xy 121.178321 -226.857111) (xy 120.898157 -226.857111) (xy 120.890032 -226.908406)
			(xy 120.873984 -226.957799) (xy 120.850406 -227.004073) (xy 120.81988 -227.046089) (xy 120.783157 -227.082812)
			(xy 120.741141 -227.113338) (xy 120.694867 -227.136916) (xy 120.645474 -227.152964) (xy 120.594179 -227.161089)
			(xy 120.542245 -227.161089) (xy 120.49095 -227.152964) (xy 120.441557 -227.136916) (xy 120.395283 -227.113338)
			(xy 120.353267 -227.082812) (xy 120.316544 -227.046089) (xy 120.286018 -227.004073) (xy 120.26244 -226.957799)
			(xy 120.246392 -226.908406) (xy 120.238267 -226.857111) (xy 119.958611 -226.857111) (xy 119.950486 -226.908406)
			(xy 119.934438 -226.957799) (xy 119.91086 -227.004073) (xy 119.880334 -227.046089) (xy 119.843611 -227.082812)
			(xy 119.801595 -227.113338) (xy 119.755321 -227.136916) (xy 119.705928 -227.152964) (xy 119.654633 -227.161089)
			(xy 119.602699 -227.161089) (xy 119.551404 -227.152964) (xy 119.502011 -227.136916) (xy 119.455737 -227.113338)
			(xy 119.413721 -227.082812) (xy 119.376998 -227.046089) (xy 119.346472 -227.004073) (xy 119.322894 -226.957799)
			(xy 119.306846 -226.908406) (xy 119.298721 -226.857111) (xy 119.018557 -226.857111) (xy 119.010432 -226.908406)
			(xy 118.994384 -226.957799) (xy 118.970806 -227.004073) (xy 118.94028 -227.046089) (xy 118.903557 -227.082812)
			(xy 118.861541 -227.113338) (xy 118.815267 -227.136916) (xy 118.765874 -227.152964) (xy 118.714579 -227.161089)
			(xy 118.662645 -227.161089) (xy 118.61135 -227.152964) (xy 118.561957 -227.136916) (xy 118.515683 -227.113338)
			(xy 118.473667 -227.082812) (xy 118.436944 -227.046089) (xy 118.406418 -227.004073) (xy 118.38284 -226.957799)
			(xy 118.366792 -226.908406) (xy 118.358667 -226.857111) (xy 118.079011 -226.857111) (xy 118.070886 -226.908406)
			(xy 118.054838 -226.957799) (xy 118.03126 -227.004073) (xy 118.000734 -227.046089) (xy 117.964011 -227.082812)
			(xy 117.921995 -227.113338) (xy 117.875721 -227.136916) (xy 117.826328 -227.152964) (xy 117.775033 -227.161089)
			(xy 117.723099 -227.161089) (xy 117.671804 -227.152964) (xy 117.622411 -227.136916) (xy 117.576137 -227.113338)
			(xy 117.534121 -227.082812) (xy 117.497398 -227.046089) (xy 117.466872 -227.004073) (xy 117.443294 -226.957799)
			(xy 117.427246 -226.908406) (xy 117.419121 -226.857111) (xy 117.138957 -226.857111) (xy 117.130832 -226.908406)
			(xy 117.114784 -226.957799) (xy 117.091206 -227.004073) (xy 117.06068 -227.046089) (xy 117.023957 -227.082812)
			(xy 116.981941 -227.113338) (xy 116.935667 -227.136916) (xy 116.886274 -227.152964) (xy 116.834979 -227.161089)
			(xy 116.783045 -227.161089) (xy 116.73175 -227.152964) (xy 116.682357 -227.136916) (xy 116.636083 -227.113338)
			(xy 116.594067 -227.082812) (xy 116.557344 -227.046089) (xy 116.526818 -227.004073) (xy 116.50324 -226.957799)
			(xy 116.487192 -226.908406) (xy 116.479067 -226.857111) (xy 116.199411 -226.857111) (xy 116.191286 -226.908406)
			(xy 116.175238 -226.957799) (xy 116.15166 -227.004073) (xy 116.121134 -227.046089) (xy 116.084411 -227.082812)
			(xy 116.042395 -227.113338) (xy 115.996121 -227.136916) (xy 115.946728 -227.152964) (xy 115.895433 -227.161089)
			(xy 115.843499 -227.161089) (xy 115.792204 -227.152964) (xy 115.742811 -227.136916) (xy 115.696537 -227.113338)
			(xy 115.654521 -227.082812) (xy 115.617798 -227.046089) (xy 115.587272 -227.004073) (xy 115.563694 -226.957799)
			(xy 115.547646 -226.908406) (xy 115.539521 -226.857111) (xy 115.259611 -226.857111) (xy 115.251486 -226.908406)
			(xy 115.235438 -226.957799) (xy 115.21186 -227.004073) (xy 115.181334 -227.046089) (xy 115.144611 -227.082812)
			(xy 115.102595 -227.113338) (xy 115.056321 -227.136916) (xy 115.006928 -227.152964) (xy 114.955633 -227.161089)
			(xy 114.903699 -227.161089) (xy 114.852404 -227.152964) (xy 114.803011 -227.136916) (xy 114.756737 -227.113338)
			(xy 114.714721 -227.082812) (xy 114.677998 -227.046089) (xy 114.647472 -227.004073) (xy 114.623894 -226.957799)
			(xy 114.607846 -226.908406) (xy 114.599721 -226.857111) (xy 114.319811 -226.857111) (xy 114.311686 -226.908406)
			(xy 114.295638 -226.957799) (xy 114.27206 -227.004073) (xy 114.241534 -227.046089) (xy 114.204811 -227.082812)
			(xy 114.162795 -227.113338) (xy 114.116521 -227.136916) (xy 114.067128 -227.152964) (xy 114.015833 -227.161089)
			(xy 113.963899 -227.161089) (xy 113.912604 -227.152964) (xy 113.863211 -227.136916) (xy 113.816937 -227.113338)
			(xy 113.774921 -227.082812) (xy 113.738198 -227.046089) (xy 113.707672 -227.004073) (xy 113.684094 -226.957799)
			(xy 113.668046 -226.908406) (xy 113.659921 -226.857111) (xy 113.379757 -226.857111) (xy 113.371632 -226.908406)
			(xy 113.355584 -226.957799) (xy 113.332006 -227.004073) (xy 113.30148 -227.046089) (xy 113.264757 -227.082812)
			(xy 113.222741 -227.113338) (xy 113.176467 -227.136916) (xy 113.127074 -227.152964) (xy 113.075779 -227.161089)
			(xy 113.023845 -227.161089) (xy 112.97255 -227.152964) (xy 112.923157 -227.136916) (xy 112.876883 -227.113338)
			(xy 112.834867 -227.082812) (xy 112.798144 -227.046089) (xy 112.767618 -227.004073) (xy 112.74404 -226.957799)
			(xy 112.727992 -226.908406) (xy 112.719867 -226.857111) (xy 112.440211 -226.857111) (xy 112.432086 -226.908406)
			(xy 112.416038 -226.957799) (xy 112.39246 -227.004073) (xy 112.361934 -227.046089) (xy 112.325211 -227.082812)
			(xy 112.283195 -227.113338) (xy 112.236921 -227.136916) (xy 112.187528 -227.152964) (xy 112.136233 -227.161089)
			(xy 112.084299 -227.161089) (xy 112.033004 -227.152964) (xy 111.983611 -227.136916) (xy 111.937337 -227.113338)
			(xy 111.895321 -227.082812) (xy 111.858598 -227.046089) (xy 111.828072 -227.004073) (xy 111.804494 -226.957799)
			(xy 111.788446 -226.908406) (xy 111.780321 -226.857111) (xy 111.500157 -226.857111) (xy 111.492032 -226.908406)
			(xy 111.475984 -226.957799) (xy 111.452406 -227.004073) (xy 111.42188 -227.046089) (xy 111.385157 -227.082812)
			(xy 111.343141 -227.113338) (xy 111.296867 -227.136916) (xy 111.247474 -227.152964) (xy 111.196179 -227.161089)
			(xy 111.144245 -227.161089) (xy 111.09295 -227.152964) (xy 111.043557 -227.136916) (xy 110.997283 -227.113338)
			(xy 110.955267 -227.082812) (xy 110.918544 -227.046089) (xy 110.888018 -227.004073) (xy 110.86444 -226.957799)
			(xy 110.848392 -226.908406) (xy 110.840267 -226.857111) (xy 110.560611 -226.857111) (xy 110.552486 -226.908406)
			(xy 110.536438 -226.957799) (xy 110.51286 -227.004073) (xy 110.482334 -227.046089) (xy 110.445611 -227.082812)
			(xy 110.403595 -227.113338) (xy 110.357321 -227.136916) (xy 110.307928 -227.152964) (xy 110.256633 -227.161089)
			(xy 110.204699 -227.161089) (xy 110.153404 -227.152964) (xy 110.104011 -227.136916) (xy 110.057737 -227.113338)
			(xy 110.015721 -227.082812) (xy 109.978998 -227.046089) (xy 109.948472 -227.004073) (xy 109.924894 -226.957799)
			(xy 109.908846 -226.908406) (xy 109.900721 -226.857111) (xy 109.620557 -226.857111) (xy 109.612432 -226.908406)
			(xy 109.596384 -226.957799) (xy 109.572806 -227.004073) (xy 109.54228 -227.046089) (xy 109.505557 -227.082812)
			(xy 109.463541 -227.113338) (xy 109.417267 -227.136916) (xy 109.367874 -227.152964) (xy 109.316579 -227.161089)
			(xy 109.264645 -227.161089) (xy 109.21335 -227.152964) (xy 109.163957 -227.136916) (xy 109.117683 -227.113338)
			(xy 109.075667 -227.082812) (xy 109.038944 -227.046089) (xy 109.008418 -227.004073) (xy 108.98484 -226.957799)
			(xy 108.968792 -226.908406) (xy 108.960667 -226.857111) (xy 108.681011 -226.857111) (xy 108.672886 -226.908406)
			(xy 108.656838 -226.957799) (xy 108.63326 -227.004073) (xy 108.602734 -227.046089) (xy 108.566011 -227.082812)
			(xy 108.523995 -227.113338) (xy 108.477721 -227.136916) (xy 108.428328 -227.152964) (xy 108.377033 -227.161089)
			(xy 108.325099 -227.161089) (xy 108.273804 -227.152964) (xy 108.224411 -227.136916) (xy 108.178137 -227.113338)
			(xy 108.136121 -227.082812) (xy 108.099398 -227.046089) (xy 108.068872 -227.004073) (xy 108.045294 -226.957799)
			(xy 108.029246 -226.908406) (xy 108.021121 -226.857111) (xy 107.740957 -226.857111) (xy 107.732832 -226.908406)
			(xy 107.716784 -226.957799) (xy 107.693206 -227.004073) (xy 107.66268 -227.046089) (xy 107.625957 -227.082812)
			(xy 107.583941 -227.113338) (xy 107.537667 -227.136916) (xy 107.488274 -227.152964) (xy 107.436979 -227.161089)
			(xy 107.385045 -227.161089) (xy 107.33375 -227.152964) (xy 107.284357 -227.136916) (xy 107.238083 -227.113338)
			(xy 107.196067 -227.082812) (xy 107.159344 -227.046089) (xy 107.128818 -227.004073) (xy 107.10524 -226.957799)
			(xy 107.089192 -226.908406) (xy 107.081067 -226.857111) (xy 106.801411 -226.857111) (xy 106.793286 -226.908406)
			(xy 106.777238 -226.957799) (xy 106.75366 -227.004073) (xy 106.723134 -227.046089) (xy 106.686411 -227.082812)
			(xy 106.644395 -227.113338) (xy 106.598121 -227.136916) (xy 106.548728 -227.152964) (xy 106.497433 -227.161089)
			(xy 106.445499 -227.161089) (xy 106.394204 -227.152964) (xy 106.344811 -227.136916) (xy 106.298537 -227.113338)
			(xy 106.256521 -227.082812) (xy 106.219798 -227.046089) (xy 106.189272 -227.004073) (xy 106.165694 -226.957799)
			(xy 106.149646 -226.908406) (xy 106.141521 -226.857111) (xy 105.861357 -226.857111) (xy 105.853232 -226.908406)
			(xy 105.837184 -226.957799) (xy 105.813606 -227.004073) (xy 105.78308 -227.046089) (xy 105.746357 -227.082812)
			(xy 105.704341 -227.113338) (xy 105.658067 -227.136916) (xy 105.608674 -227.152964) (xy 105.557379 -227.161089)
			(xy 105.505445 -227.161089) (xy 105.45415 -227.152964) (xy 105.404757 -227.136916) (xy 105.358483 -227.113338)
			(xy 105.316467 -227.082812) (xy 105.279744 -227.046089) (xy 105.249218 -227.004073) (xy 105.22564 -226.957799)
			(xy 105.209592 -226.908406) (xy 105.201467 -226.857111) (xy 104.921811 -226.857111) (xy 104.913686 -226.908406)
			(xy 104.897638 -226.957799) (xy 104.87406 -227.004073) (xy 104.843534 -227.046089) (xy 104.806811 -227.082812)
			(xy 104.764795 -227.113338) (xy 104.718521 -227.136916) (xy 104.669128 -227.152964) (xy 104.617833 -227.161089)
			(xy 104.565899 -227.161089) (xy 104.514604 -227.152964) (xy 104.465211 -227.136916) (xy 104.418937 -227.113338)
			(xy 104.376921 -227.082812) (xy 104.340198 -227.046089) (xy 104.309672 -227.004073) (xy 104.286094 -226.957799)
			(xy 104.270046 -226.908406) (xy 104.261921 -226.857111) (xy 103.982011 -226.857111) (xy 103.973886 -226.908406)
			(xy 103.957838 -226.957799) (xy 103.93426 -227.004073) (xy 103.903734 -227.046089) (xy 103.867011 -227.082812)
			(xy 103.824995 -227.113338) (xy 103.778721 -227.136916) (xy 103.729328 -227.152964) (xy 103.678033 -227.161089)
			(xy 103.626099 -227.161089) (xy 103.574804 -227.152964) (xy 103.525411 -227.136916) (xy 103.479137 -227.113338)
			(xy 103.437121 -227.082812) (xy 103.400398 -227.046089) (xy 103.369872 -227.004073) (xy 103.346294 -226.957799)
			(xy 103.330246 -226.908406) (xy 103.322121 -226.857111) (xy 103.066614 -226.857111) (xy 103.064581 -226.884242)
			(xy 103.052723 -226.936197) (xy 103.033254 -226.985804) (xy 103.006609 -227.031955) (xy 102.973383 -227.07362)
			(xy 102.934319 -227.109868) (xy 102.890288 -227.139889) (xy 102.842276 -227.163012) (xy 102.791353 -227.178721)
			(xy 102.738657 -227.186665) (xy 102.712012 -227.187252) (xy 102.686034 -227.186782) (xy 102.634628 -227.179239)
			(xy 102.584863 -227.164311) (xy 102.561136 -227.153724) (xy 102.55885 -227.152708) (xy 102.550976 -227.149152)
			(xy 102.414324 -227.149152) (xy 102.405942 -227.148898) (xy 102.338124 -227.148898) (xy 102.313239 -227.148393)
			(xy 102.264083 -227.140589) (xy 102.216745 -227.125214) (xy 102.172385 -227.102646) (xy 102.151942 -227.088446)
			(xy 102.145592 -227.083874) (xy 102.115874 -227.073714) (xy 102.112826 -227.073714) (xy 102.048056 -227.077016)
			(xy 102.01656 -227.090478) (xy 102.010972 -227.095304) (xy 101.991245 -227.112531) (xy 101.947682 -227.1416)
			(xy 101.900328 -227.163967) (xy 101.850205 -227.179148) (xy 101.798398 -227.186815) (xy 101.772212 -227.187252)
			(xy 101.744227 -227.186704) (xy 101.688946 -227.177951) (xy 101.635714 -227.160658) (xy 101.585843 -227.135251)
			(xy 101.54056 -227.102356) (xy 101.500981 -227.062782) (xy 101.468078 -227.017505) (xy 101.442664 -226.967637)
			(xy 101.425362 -226.914409) (xy 101.4166 -226.859129) (xy 101.416104 -226.831144) (xy 101.416554 -226.805408)
			(xy 101.423956 -226.754471) (xy 101.438613 -226.70513) (xy 101.46022 -226.658412) (xy 101.488325 -226.615291)
			(xy 101.505004 -226.595686) (xy 101.510846 -226.589082) (xy 101.524054 -226.555554) (xy 101.5238 -226.54006)
			(xy 101.522784 -226.484688) (xy 101.522163 -226.475133) (xy 101.514721 -226.457507) (xy 101.508306 -226.450398)
			(xy 101.496368 -226.43846) (xy 101.4817 -226.423303) (xy 101.456092 -226.389788) (xy 101.445314 -226.371658)
			(xy 101.43998 -226.362514) (xy 101.396292 -226.336352) (xy 101.389942 -226.336606) (xy 101.378258 -226.339146)
			(xy 101.359608 -226.343282) (xy 101.321667 -226.347735) (xy 101.302566 -226.348036) (xy 101.276445 -226.347548)
			(xy 101.224852 -226.339348) (xy 101.175188 -226.323142) (xy 101.128688 -226.299331) (xy 101.086508 -226.268509)
			(xy 101.049697 -226.231441) (xy 101.019168 -226.189048) (xy 100.995681 -226.142384) (xy 100.97982 -226.092609)
			(xy 100.975414 -226.066858) (xy 100.974906 -226.063048) (xy 100.971935 -226.05208) (xy 100.957886 -226.034249)
			(xy 100.937486 -226.024291) (xy 100.926138 -226.023678) (xy 100.739194 -226.023678) (xy 100.727819 -226.024207)
			(xy 100.707355 -226.034139) (xy 100.693314 -226.052035) (xy 100.690426 -226.063048) (xy 100.689918 -226.066858)
			(xy 100.685498 -226.092602) (xy 100.669618 -226.142361) (xy 100.64612 -226.189009) (xy 100.615588 -226.231388)
			(xy 100.578778 -226.268445) (xy 100.536605 -226.299261) (xy 100.490116 -226.323071) (xy 100.440464 -226.339284)
			(xy 100.388882 -226.347498) (xy 100.362766 -226.348036) (xy 100.337489 -226.347555) (xy 100.287525 -226.339859)
			(xy 100.239313 -226.324651) (xy 100.193976 -226.302285) (xy 100.152569 -226.273282) (xy 100.116057 -226.238318)
			(xy 100.085289 -226.198205) (xy 100.060982 -226.153879) (xy 100.043702 -226.10637) (xy 100.03385 -226.056786)
			(xy 100.032312 -226.031552) (xy 100.03155 -226.01936) (xy 99.996752 -225.984816) (xy 99.972876 -225.987356)
			(xy 99.812856 -225.987356) (xy 99.78898 -225.984816) (xy 99.754182 -226.01936) (xy 99.75342 -226.031552)
			(xy 99.751859 -226.056787) (xy 99.74203 -226.106379) (xy 99.724765 -226.153897) (xy 99.700468 -226.198233)
			(xy 99.669704 -226.238352) (xy 99.633191 -226.273321) (xy 99.591779 -226.302323) (xy 99.546435 -226.324682)
			(xy 99.498216 -226.339877) (xy 99.448245 -226.347553) (xy 99.422966 -226.348036) (xy 99.398372 -226.347591)
			(xy 99.349725 -226.340318) (xy 99.302691 -226.325922) (xy 99.258307 -226.304722) (xy 99.217551 -226.277184)
			(xy 99.181322 -226.243915) (xy 99.150417 -226.205648) (xy 99.125519 -226.163228) (xy 99.107176 -226.117588)
			(xy 99.095792 -226.069736) (xy 99.093274 -226.045268) (xy 99.092512 -226.036378) (xy 99.077272 -226.003104)
			(xy 99.057714 -225.984816) (xy 99.032314 -225.987356) (xy 98.873818 -225.987356) (xy 98.848418 -225.984816)
			(xy 98.82886 -226.003104) (xy 98.81362 -226.036378) (xy 98.812858 -226.045268) (xy 98.81018 -226.07127)
			(xy 98.797672 -226.122021) (xy 98.777338 -226.170174) (xy 98.749686 -226.214531) (xy 98.715402 -226.253986)
			(xy 98.67534 -226.28756) (xy 98.630497 -226.314416) (xy 98.581988 -226.333886) (xy 98.531022 -226.345486)
			(xy 98.478865 -226.348927) (xy 98.426816 -226.344123) (xy 98.376171 -226.331194) (xy 98.328188 -226.310461)
			(xy 98.284063 -226.282441) (xy 98.244893 -226.247831) (xy 98.211654 -226.207491) (xy 98.185171 -226.162427)
			(xy 98.166104 -226.113758) (xy 98.154928 -226.062697) (xy 98.152966 -226.036632) (xy 98.152966 -226.034854)
			(xy 98.151878 -226.026492) (xy 98.144872 -226.011166) (xy 98.13925 -226.004882) (xy 98.117914 -225.984816)
			(xy 98.0948 -225.987102) (xy 97.931732 -225.987102) (xy 97.908364 -225.984816) (xy 97.88906 -226.003104)
			(xy 97.882746 -226.009603) (xy 97.874809 -226.025878) (xy 97.873566 -226.034854) (xy 97.873566 -226.036632)
			(xy 97.871651 -226.061588) (xy 97.861242 -226.110543) (xy 97.843573 -226.15737) (xy 97.819048 -226.200999)
			(xy 97.788228 -226.240433) (xy 97.751816 -226.274771) (xy 97.710644 -226.303229) (xy 97.665653 -226.325156)
			(xy 97.617872 -226.340052) (xy 97.568391 -226.347575) (xy 97.543366 -226.348036) (xy 97.517454 -226.347537)
			(xy 97.466262 -226.339461) (xy 97.416957 -226.323498) (xy 97.370747 -226.300037) (xy 97.328763 -226.269654)
			(xy 97.292033 -226.233093) (xy 97.261458 -226.191249) (xy 97.237785 -226.145146) (xy 97.221596 -226.095916)
			(xy 97.216976 -226.070414) (xy 97.213452 -226.05652) (xy 97.199828 -226.031315) (xy 97.179751 -226.010875)
			(xy 97.154794 -225.996802) (xy 97.126914 -225.990198) (xy 97.112582 -225.990404) (xy 97.03435 -225.990404)
			(xy 97.020009 -225.990166) (xy 96.992103 -225.996733) (xy 96.967125 -226.010802) (xy 96.947046 -226.031264)
			(xy 96.93345 -226.056504) (xy 96.929956 -226.070414) (xy 96.925298 -226.095906) (xy 96.909102 -226.145129)
			(xy 96.885428 -226.191224) (xy 96.854855 -226.233063) (xy 96.818131 -226.269623) (xy 96.776155 -226.300007)
			(xy 96.729954 -226.323474) (xy 96.680659 -226.339449) (xy 96.629475 -226.34754) (xy 96.603566 -226.348036)
			(xy 96.578569 -226.347576) (xy 96.529144 -226.340049) (xy 96.481414 -226.32517) (xy 96.436466 -226.303279)
			(xy 96.395324 -226.274874) (xy 96.358924 -226.240603) (xy 96.328096 -226.201244) (xy 96.30354 -226.157695)
			(xy 96.285816 -226.110947) (xy 96.275329 -226.062065) (xy 96.273366 -226.03714) (xy 96.272858 -226.030028)
			(xy 96.257872 -225.996246) (xy 96.245172 -225.984054) (xy 96.215454 -225.987102) (xy 96.051878 -225.987102)
			(xy 96.02216 -225.984054) (xy 96.00946 -225.996246) (xy 95.994474 -226.030028) (xy 95.993966 -226.03714)
			(xy 95.991882 -226.063382) (xy 95.980447 -226.114764) (xy 95.96102 -226.163687) (xy 95.93409 -226.208916)
			(xy 95.900337 -226.249309) (xy 95.860613 -226.283847) (xy 95.81592 -226.311658) (xy 95.767387 -226.33204)
			(xy 95.716239 -226.344478) (xy 95.663766 -226.34866) (xy 95.611293 -226.344478) (xy 95.560145 -226.33204)
			(xy 95.511612 -226.311658) (xy 95.466919 -226.283847) (xy 95.427195 -226.249309) (xy 95.393442 -226.208916)
			(xy 95.366512 -226.163687) (xy 95.347085 -226.114764) (xy 95.33565 -226.063382) (xy 95.333566 -226.03714)
			(xy 95.333058 -226.030028) (xy 95.318072 -225.996246) (xy 95.305372 -225.984054) (xy 95.275654 -225.987102)
			(xy 95.112078 -225.987102) (xy 95.08236 -225.984054) (xy 95.06966 -225.996246) (xy 95.054674 -226.030028)
			(xy 95.054166 -226.03714) (xy 95.052216 -226.06207) (xy 95.041749 -226.110965) (xy 95.024039 -226.157728)
			(xy 94.99949 -226.20129) (xy 94.968662 -226.24066) (xy 94.932257 -226.274938) (xy 94.891106 -226.303345)
			(xy 94.846146 -226.325231) (xy 94.798404 -226.340098) (xy 94.748968 -226.347607) (xy 94.723966 -226.348036)
			(xy 94.698733 -226.347557) (xy 94.648854 -226.339883) (xy 94.600721 -226.324718) (xy 94.555451 -226.302415)
			(xy 94.514096 -226.273491) (xy 94.477617 -226.238618) (xy 94.446861 -226.198608) (xy 94.422543 -226.154388)
			(xy 94.405227 -226.106986) (xy 94.395315 -226.057503) (xy 94.393766 -226.032314) (xy 94.393258 -226.02698)
			(xy 94.378272 -225.992944) (xy 94.36862 -225.983546) (xy 94.337124 -225.987102) (xy 94.171008 -225.987102)
			(xy 94.139258 -225.9838) (xy 94.12986 -225.992944) (xy 94.114874 -226.02698) (xy 94.114366 -226.032314)
			(xy 94.112765 -226.0575) (xy 94.102877 -226.106987) (xy 94.085579 -226.154394) (xy 94.061272 -226.198619)
			(xy 94.030522 -226.238634) (xy 93.994045 -226.273507) (xy 93.952689 -226.302427) (xy 93.907416 -226.324722)
			(xy 93.85928 -226.339872) (xy 93.809399 -226.347527) (xy 93.784166 -226.348036) (xy 93.758476 -226.347555)
			(xy 93.707712 -226.339622) (xy 93.658785 -226.323937) (xy 93.612871 -226.300876) (xy 93.571074 -226.270994)
			(xy 93.5344 -226.235009) (xy 93.503729 -226.193788) (xy 93.4798 -226.14832) (xy 93.463187 -226.0997)
			(xy 93.458284 -226.074478) (xy 93.455285 -226.060029) (xy 93.442159 -226.033612) (xy 93.422019 -226.01206)
			(xy 93.39655 -225.997178) (xy 93.367887 -225.990212) (xy 93.353128 -225.990404) (xy 93.333642 -225.991245)
			(xy 93.294636 -225.991245) (xy 93.27515 -225.990404) (xy 93.260426 -225.990207) (xy 93.231851 -225.997269)
			(xy 93.206476 -226.012184) (xy 93.186404 -226.033713) (xy 93.173303 -226.060071) (xy 93.170248 -226.074478)
			(xy 93.165311 -226.099691) (xy 93.148684 -226.1483) (xy 93.124748 -226.193757) (xy 93.094078 -226.234971)
			(xy 93.057409 -226.270953) (xy 93.015622 -226.300839) (xy 92.969721 -226.323912) (xy 92.920806 -226.339617)
			(xy 92.870053 -226.347578) (xy 92.844366 -226.348036) (xy 92.817462 -226.347514) (xy 92.764361 -226.338817)
			(xy 92.713367 -226.321641) (xy 92.665826 -226.29644) (xy 92.622989 -226.263877) (xy 92.585986 -226.22481)
			(xy 92.555794 -226.180271) (xy 92.533207 -226.131433) (xy 92.518821 -226.079583) (xy 92.515436 -226.052888)
			(xy 92.51442 -226.044252) (xy 92.498926 -226.01174) (xy 92.470224 -225.985578) (xy 92.447872 -225.98761)
			(xy 92.30106 -225.98761) (xy 92.278708 -225.985578) (xy 92.250006 -226.01174) (xy 92.234512 -226.044252)
			(xy 92.233496 -226.052888) (xy 92.230058 -226.079571) (xy 92.215655 -226.131405) (xy 92.19306 -226.180228)
			(xy 92.162868 -226.224755) (xy 92.125874 -226.263814) (xy 92.083051 -226.296378) (xy 92.035526 -226.321588)
			(xy 91.98455 -226.338783) (xy 91.931465 -226.347508) (xy 91.904566 -226.348036) (xy 91.877643 -226.347506)
			(xy 91.824506 -226.338785) (xy 91.773482 -226.32158) (xy 91.725915 -226.296343) (xy 91.70416 -226.280472)
			(xy 91.69781 -226.275646) (xy 91.66733 -226.264724) (xy 91.661602 -226.26484) (xy 91.650441 -226.267416)
			(xy 91.645232 -226.269804) (xy 91.604846 -226.289362) (xy 91.56192 -226.309936) (xy 91.554117 -226.314492)
			(xy 91.542138 -226.328) (xy 91.53566 -226.344854) (xy 91.53525 -226.353878) (xy 91.53525 -226.481386)
			(xy 91.565222 -226.526852) (xy 91.577922 -226.532948) (xy 91.601624 -226.544919) (xy 91.645197 -226.575259)
			(xy 91.683363 -226.612171) (xy 91.715143 -226.654705) (xy 91.73972 -226.70177) (xy 91.756463 -226.752157)
			(xy 91.764942 -226.804571) (xy 91.764939 -226.857111) (xy 92.044521 -226.857111) (xy 92.044521 -226.805177)
			(xy 92.052646 -226.753882) (xy 92.068694 -226.704489) (xy 92.092272 -226.658215) (xy 92.122798 -226.616199)
			(xy 92.159521 -226.579476) (xy 92.201537 -226.54895) (xy 92.247811 -226.525372) (xy 92.297204 -226.509324)
			(xy 92.348499 -226.501199) (xy 92.400433 -226.501199) (xy 92.451728 -226.509324) (xy 92.501121 -226.525372)
			(xy 92.547395 -226.54895) (xy 92.589411 -226.579476) (xy 92.626134 -226.616199) (xy 92.65666 -226.658215)
			(xy 92.680238 -226.704489) (xy 92.696286 -226.753882) (xy 92.704411 -226.805177) (xy 92.70492 -226.831144)
			(xy 92.704411 -226.857111) (xy 92.984321 -226.857111) (xy 92.984321 -226.805177) (xy 92.992446 -226.753882)
			(xy 93.008494 -226.704489) (xy 93.032072 -226.658215) (xy 93.062598 -226.616199) (xy 93.099321 -226.579476)
			(xy 93.141337 -226.54895) (xy 93.187611 -226.525372) (xy 93.237004 -226.509324) (xy 93.288299 -226.501199)
			(xy 93.340233 -226.501199) (xy 93.391528 -226.509324) (xy 93.440921 -226.525372) (xy 93.487195 -226.54895)
			(xy 93.529211 -226.579476) (xy 93.565934 -226.616199) (xy 93.59646 -226.658215) (xy 93.620038 -226.704489)
			(xy 93.636086 -226.753882) (xy 93.644211 -226.805177) (xy 93.64472 -226.831144) (xy 93.644211 -226.857111)
			(xy 93.923867 -226.857111) (xy 93.923867 -226.805177) (xy 93.931992 -226.753882) (xy 93.94804 -226.704489)
			(xy 93.971618 -226.658215) (xy 94.002144 -226.616199) (xy 94.038867 -226.579476) (xy 94.080883 -226.54895)
			(xy 94.127157 -226.525372) (xy 94.17655 -226.509324) (xy 94.227845 -226.501199) (xy 94.279779 -226.501199)
			(xy 94.331074 -226.509324) (xy 94.380467 -226.525372) (xy 94.426741 -226.54895) (xy 94.468757 -226.579476)
			(xy 94.50548 -226.616199) (xy 94.536006 -226.658215) (xy 94.559584 -226.704489) (xy 94.575632 -226.753882)
			(xy 94.583757 -226.805177) (xy 94.584266 -226.831144) (xy 94.583757 -226.857111) (xy 94.863667 -226.857111)
			(xy 94.863667 -226.805177) (xy 94.871792 -226.753882) (xy 94.88784 -226.704489) (xy 94.911418 -226.658215)
			(xy 94.941944 -226.616199) (xy 94.978667 -226.579476) (xy 95.020683 -226.54895) (xy 95.066957 -226.525372)
			(xy 95.11635 -226.509324) (xy 95.167645 -226.501199) (xy 95.219579 -226.501199) (xy 95.270874 -226.509324)
			(xy 95.320267 -226.525372) (xy 95.366541 -226.54895) (xy 95.408557 -226.579476) (xy 95.44528 -226.616199)
			(xy 95.475806 -226.658215) (xy 95.499384 -226.704489) (xy 95.515432 -226.753882) (xy 95.523557 -226.805177)
			(xy 95.524066 -226.831144) (xy 95.523557 -226.857111) (xy 95.803721 -226.857111) (xy 95.803721 -226.805177)
			(xy 95.811846 -226.753882) (xy 95.827894 -226.704489) (xy 95.851472 -226.658215) (xy 95.881998 -226.616199)
			(xy 95.918721 -226.579476) (xy 95.960737 -226.54895) (xy 96.007011 -226.525372) (xy 96.056404 -226.509324)
			(xy 96.107699 -226.501199) (xy 96.159633 -226.501199) (xy 96.210928 -226.509324) (xy 96.260321 -226.525372)
			(xy 96.306595 -226.54895) (xy 96.348611 -226.579476) (xy 96.385334 -226.616199) (xy 96.41586 -226.658215)
			(xy 96.439438 -226.704489) (xy 96.455486 -226.753882) (xy 96.463611 -226.805177) (xy 96.46412 -226.831144)
			(xy 96.463611 -226.857111) (xy 96.743267 -226.857111) (xy 96.743267 -226.805177) (xy 96.751392 -226.753882)
			(xy 96.76744 -226.704489) (xy 96.791018 -226.658215) (xy 96.821544 -226.616199) (xy 96.858267 -226.579476)
			(xy 96.900283 -226.54895) (xy 96.946557 -226.525372) (xy 96.99595 -226.509324) (xy 97.047245 -226.501199)
			(xy 97.099179 -226.501199) (xy 97.150474 -226.509324) (xy 97.199867 -226.525372) (xy 97.246141 -226.54895)
			(xy 97.288157 -226.579476) (xy 97.32488 -226.616199) (xy 97.355406 -226.658215) (xy 97.378984 -226.704489)
			(xy 97.395032 -226.753882) (xy 97.403157 -226.805177) (xy 97.403666 -226.831144) (xy 97.403157 -226.857111)
			(xy 97.683067 -226.857111) (xy 97.683067 -226.805177) (xy 97.691192 -226.753882) (xy 97.70724 -226.704489)
			(xy 97.730818 -226.658215) (xy 97.761344 -226.616199) (xy 97.798067 -226.579476) (xy 97.840083 -226.54895)
			(xy 97.886357 -226.525372) (xy 97.93575 -226.509324) (xy 97.987045 -226.501199) (xy 98.038979 -226.501199)
			(xy 98.090274 -226.509324) (xy 98.139667 -226.525372) (xy 98.185941 -226.54895) (xy 98.227957 -226.579476)
			(xy 98.26468 -226.616199) (xy 98.295206 -226.658215) (xy 98.318784 -226.704489) (xy 98.334832 -226.753882)
			(xy 98.342957 -226.805177) (xy 98.343466 -226.831144) (xy 98.342957 -226.857111) (xy 98.623121 -226.857111)
			(xy 98.623121 -226.805177) (xy 98.631246 -226.753882) (xy 98.647294 -226.704489) (xy 98.670872 -226.658215)
			(xy 98.701398 -226.616199) (xy 98.738121 -226.579476) (xy 98.780137 -226.54895) (xy 98.826411 -226.525372)
			(xy 98.875804 -226.509324) (xy 98.927099 -226.501199) (xy 98.979033 -226.501199) (xy 99.030328 -226.509324)
			(xy 99.079721 -226.525372) (xy 99.125995 -226.54895) (xy 99.168011 -226.579476) (xy 99.204734 -226.616199)
			(xy 99.23526 -226.658215) (xy 99.258838 -226.704489) (xy 99.274886 -226.753882) (xy 99.283011 -226.805177)
			(xy 99.28352 -226.831144) (xy 99.283011 -226.857111) (xy 99.562921 -226.857111) (xy 99.562921 -226.805177)
			(xy 99.571046 -226.753882) (xy 99.587094 -226.704489) (xy 99.610672 -226.658215) (xy 99.641198 -226.616199)
			(xy 99.677921 -226.579476) (xy 99.719937 -226.54895) (xy 99.766211 -226.525372) (xy 99.815604 -226.509324)
			(xy 99.866899 -226.501199) (xy 99.918833 -226.501199) (xy 99.970128 -226.509324) (xy 100.019521 -226.525372)
			(xy 100.065795 -226.54895) (xy 100.107811 -226.579476) (xy 100.144534 -226.616199) (xy 100.17506 -226.658215)
			(xy 100.198638 -226.704489) (xy 100.214686 -226.753882) (xy 100.222811 -226.805177) (xy 100.22332 -226.831144)
			(xy 100.222811 -226.857111) (xy 100.502721 -226.857111) (xy 100.502721 -226.805177) (xy 100.510846 -226.753882)
			(xy 100.526894 -226.704489) (xy 100.550472 -226.658215) (xy 100.580998 -226.616199) (xy 100.617721 -226.579476)
			(xy 100.659737 -226.54895) (xy 100.706011 -226.525372) (xy 100.755404 -226.509324) (xy 100.806699 -226.501199)
			(xy 100.858633 -226.501199) (xy 100.909928 -226.509324) (xy 100.959321 -226.525372) (xy 101.005595 -226.54895)
			(xy 101.047611 -226.579476) (xy 101.084334 -226.616199) (xy 101.11486 -226.658215) (xy 101.138438 -226.704489)
			(xy 101.154486 -226.753882) (xy 101.162611 -226.805177) (xy 101.16312 -226.831144) (xy 101.162611 -226.857111)
			(xy 101.154486 -226.908406) (xy 101.138438 -226.957799) (xy 101.11486 -227.004073) (xy 101.084334 -227.046089)
			(xy 101.047611 -227.082812) (xy 101.005595 -227.113338) (xy 100.959321 -227.136916) (xy 100.909928 -227.152964)
			(xy 100.858633 -227.161089) (xy 100.806699 -227.161089) (xy 100.755404 -227.152964) (xy 100.706011 -227.136916)
			(xy 100.659737 -227.113338) (xy 100.617721 -227.082812) (xy 100.580998 -227.046089) (xy 100.550472 -227.004073)
			(xy 100.526894 -226.957799) (xy 100.510846 -226.908406) (xy 100.502721 -226.857111) (xy 100.222811 -226.857111)
			(xy 100.214686 -226.908406) (xy 100.198638 -226.957799) (xy 100.17506 -227.004073) (xy 100.144534 -227.046089)
			(xy 100.107811 -227.082812) (xy 100.065795 -227.113338) (xy 100.019521 -227.136916) (xy 99.970128 -227.152964)
			(xy 99.918833 -227.161089) (xy 99.866899 -227.161089) (xy 99.815604 -227.152964) (xy 99.766211 -227.136916)
			(xy 99.719937 -227.113338) (xy 99.677921 -227.082812) (xy 99.641198 -227.046089) (xy 99.610672 -227.004073)
			(xy 99.587094 -226.957799) (xy 99.571046 -226.908406) (xy 99.562921 -226.857111) (xy 99.283011 -226.857111)
			(xy 99.274886 -226.908406) (xy 99.258838 -226.957799) (xy 99.23526 -227.004073) (xy 99.204734 -227.046089)
			(xy 99.168011 -227.082812) (xy 99.125995 -227.113338) (xy 99.079721 -227.136916) (xy 99.030328 -227.152964)
			(xy 98.979033 -227.161089) (xy 98.927099 -227.161089) (xy 98.875804 -227.152964) (xy 98.826411 -227.136916)
			(xy 98.780137 -227.113338) (xy 98.738121 -227.082812) (xy 98.701398 -227.046089) (xy 98.670872 -227.004073)
			(xy 98.647294 -226.957799) (xy 98.631246 -226.908406) (xy 98.623121 -226.857111) (xy 98.342957 -226.857111)
			(xy 98.334832 -226.908406) (xy 98.318784 -226.957799) (xy 98.295206 -227.004073) (xy 98.26468 -227.046089)
			(xy 98.227957 -227.082812) (xy 98.185941 -227.113338) (xy 98.139667 -227.136916) (xy 98.090274 -227.152964)
			(xy 98.038979 -227.161089) (xy 97.987045 -227.161089) (xy 97.93575 -227.152964) (xy 97.886357 -227.136916)
			(xy 97.840083 -227.113338) (xy 97.798067 -227.082812) (xy 97.761344 -227.046089) (xy 97.730818 -227.004073)
			(xy 97.70724 -226.957799) (xy 97.691192 -226.908406) (xy 97.683067 -226.857111) (xy 97.403157 -226.857111)
			(xy 97.395032 -226.908406) (xy 97.378984 -226.957799) (xy 97.355406 -227.004073) (xy 97.32488 -227.046089)
			(xy 97.288157 -227.082812) (xy 97.246141 -227.113338) (xy 97.199867 -227.136916) (xy 97.150474 -227.152964)
			(xy 97.099179 -227.161089) (xy 97.047245 -227.161089) (xy 96.99595 -227.152964) (xy 96.946557 -227.136916)
			(xy 96.900283 -227.113338) (xy 96.858267 -227.082812) (xy 96.821544 -227.046089) (xy 96.791018 -227.004073)
			(xy 96.76744 -226.957799) (xy 96.751392 -226.908406) (xy 96.743267 -226.857111) (xy 96.463611 -226.857111)
			(xy 96.455486 -226.908406) (xy 96.439438 -226.957799) (xy 96.41586 -227.004073) (xy 96.385334 -227.046089)
			(xy 96.348611 -227.082812) (xy 96.306595 -227.113338) (xy 96.260321 -227.136916) (xy 96.210928 -227.152964)
			(xy 96.159633 -227.161089) (xy 96.107699 -227.161089) (xy 96.056404 -227.152964) (xy 96.007011 -227.136916)
			(xy 95.960737 -227.113338) (xy 95.918721 -227.082812) (xy 95.881998 -227.046089) (xy 95.851472 -227.004073)
			(xy 95.827894 -226.957799) (xy 95.811846 -226.908406) (xy 95.803721 -226.857111) (xy 95.523557 -226.857111)
			(xy 95.515432 -226.908406) (xy 95.499384 -226.957799) (xy 95.475806 -227.004073) (xy 95.44528 -227.046089)
			(xy 95.408557 -227.082812) (xy 95.366541 -227.113338) (xy 95.320267 -227.136916) (xy 95.270874 -227.152964)
			(xy 95.219579 -227.161089) (xy 95.167645 -227.161089) (xy 95.11635 -227.152964) (xy 95.066957 -227.136916)
			(xy 95.020683 -227.113338) (xy 94.978667 -227.082812) (xy 94.941944 -227.046089) (xy 94.911418 -227.004073)
			(xy 94.88784 -226.957799) (xy 94.871792 -226.908406) (xy 94.863667 -226.857111) (xy 94.583757 -226.857111)
			(xy 94.575632 -226.908406) (xy 94.559584 -226.957799) (xy 94.536006 -227.004073) (xy 94.50548 -227.046089)
			(xy 94.468757 -227.082812) (xy 94.426741 -227.113338) (xy 94.380467 -227.136916) (xy 94.331074 -227.152964)
			(xy 94.279779 -227.161089) (xy 94.227845 -227.161089) (xy 94.17655 -227.152964) (xy 94.127157 -227.136916)
			(xy 94.080883 -227.113338) (xy 94.038867 -227.082812) (xy 94.002144 -227.046089) (xy 93.971618 -227.004073)
			(xy 93.94804 -226.957799) (xy 93.931992 -226.908406) (xy 93.923867 -226.857111) (xy 93.644211 -226.857111)
			(xy 93.636086 -226.908406) (xy 93.620038 -226.957799) (xy 93.59646 -227.004073) (xy 93.565934 -227.046089)
			(xy 93.529211 -227.082812) (xy 93.487195 -227.113338) (xy 93.440921 -227.136916) (xy 93.391528 -227.152964)
			(xy 93.340233 -227.161089) (xy 93.288299 -227.161089) (xy 93.237004 -227.152964) (xy 93.187611 -227.136916)
			(xy 93.141337 -227.113338) (xy 93.099321 -227.082812) (xy 93.062598 -227.046089) (xy 93.032072 -227.004073)
			(xy 93.008494 -226.957799) (xy 92.992446 -226.908406) (xy 92.984321 -226.857111) (xy 92.704411 -226.857111)
			(xy 92.696286 -226.908406) (xy 92.680238 -226.957799) (xy 92.65666 -227.004073) (xy 92.626134 -227.046089)
			(xy 92.589411 -227.082812) (xy 92.547395 -227.113338) (xy 92.501121 -227.136916) (xy 92.451728 -227.152964)
			(xy 92.400433 -227.161089) (xy 92.348499 -227.161089) (xy 92.297204 -227.152964) (xy 92.247811 -227.136916)
			(xy 92.201537 -227.113338) (xy 92.159521 -227.082812) (xy 92.122798 -227.046089) (xy 92.092272 -227.004073)
			(xy 92.068694 -226.957799) (xy 92.052646 -226.908406) (xy 92.044521 -226.857111) (xy 91.764939 -226.857111)
			(xy 91.764939 -226.857667) (xy 91.756454 -226.91008) (xy 91.739705 -226.960465) (xy 91.715123 -227.007527)
			(xy 91.683338 -227.050058) (xy 91.645167 -227.086965) (xy 91.601591 -227.117301) (xy 91.577922 -227.12934)
			(xy 91.565222 -227.135436) (xy 91.53525 -227.180902) (xy 91.53525 -227.308156) (xy 91.535718 -227.317333)
			(xy 91.54238 -227.334441) (xy 91.554699 -227.348054) (xy 91.562682 -227.352606) (xy 91.648026 -227.393754)
			(xy 91.652482 -227.395408) (xy 91.661816 -227.397193) (xy 91.666568 -227.39731) (xy 91.69781 -227.386388)
			(xy 91.70416 -227.381562) (xy 91.725893 -227.365733) (xy 91.773414 -227.340586) (xy 91.824372 -227.323446)
			(xy 91.87743 -227.314763) (xy 91.904312 -227.314252) (xy 91.930302 -227.314763) (xy 91.981641 -227.322896)
			(xy 92.031076 -227.33896) (xy 92.077389 -227.362559) (xy 92.119441 -227.393113) (xy 92.156195 -227.429868)
			(xy 92.186747 -227.471921) (xy 92.210345 -227.518235) (xy 92.226407 -227.567671) (xy 92.234538 -227.61901)
			(xy 92.234538 -227.670927) (xy 92.514421 -227.670927) (xy 92.514421 -227.618993) (xy 92.522546 -227.567698)
			(xy 92.538594 -227.518305) (xy 92.562172 -227.472031) (xy 92.592698 -227.430015) (xy 92.629421 -227.393292)
			(xy 92.671437 -227.362766) (xy 92.717711 -227.339188) (xy 92.767104 -227.32314) (xy 92.818399 -227.315015)
			(xy 92.870333 -227.315015) (xy 92.921628 -227.32314) (xy 92.971021 -227.339188) (xy 93.017295 -227.362766)
			(xy 93.059311 -227.393292) (xy 93.096034 -227.430015) (xy 93.12656 -227.472031) (xy 93.150138 -227.518305)
			(xy 93.166186 -227.567698) (xy 93.174311 -227.618993) (xy 93.17482 -227.64496) (xy 93.174311 -227.670927)
			(xy 93.454221 -227.670927) (xy 93.454221 -227.618993) (xy 93.462346 -227.567698) (xy 93.478394 -227.518305)
			(xy 93.501972 -227.472031) (xy 93.532498 -227.430015) (xy 93.569221 -227.393292) (xy 93.611237 -227.362766)
			(xy 93.657511 -227.339188) (xy 93.706904 -227.32314) (xy 93.758199 -227.315015) (xy 93.810133 -227.315015)
			(xy 93.861428 -227.32314) (xy 93.910821 -227.339188) (xy 93.957095 -227.362766) (xy 93.999111 -227.393292)
			(xy 94.035834 -227.430015) (xy 94.06636 -227.472031) (xy 94.089938 -227.518305) (xy 94.105986 -227.567698)
			(xy 94.114111 -227.618993) (xy 94.11462 -227.64496) (xy 94.114111 -227.670927) (xy 94.394021 -227.670927)
			(xy 94.394021 -227.618993) (xy 94.402146 -227.567698) (xy 94.418194 -227.518305) (xy 94.441772 -227.472031)
			(xy 94.472298 -227.430015) (xy 94.509021 -227.393292) (xy 94.551037 -227.362766) (xy 94.597311 -227.339188)
			(xy 94.646704 -227.32314) (xy 94.697999 -227.315015) (xy 94.749933 -227.315015) (xy 94.801228 -227.32314)
			(xy 94.850621 -227.339188) (xy 94.896895 -227.362766) (xy 94.938911 -227.393292) (xy 94.975634 -227.430015)
			(xy 95.00616 -227.472031) (xy 95.029738 -227.518305) (xy 95.045786 -227.567698) (xy 95.053911 -227.618993)
			(xy 95.05442 -227.64496) (xy 95.053911 -227.670927) (xy 95.333821 -227.670927) (xy 95.333821 -227.618993)
			(xy 95.341946 -227.567698) (xy 95.357994 -227.518305) (xy 95.381572 -227.472031) (xy 95.412098 -227.430015)
			(xy 95.448821 -227.393292) (xy 95.490837 -227.362766) (xy 95.537111 -227.339188) (xy 95.586504 -227.32314)
			(xy 95.637799 -227.315015) (xy 95.689733 -227.315015) (xy 95.741028 -227.32314) (xy 95.790421 -227.339188)
			(xy 95.836695 -227.362766) (xy 95.878711 -227.393292) (xy 95.915434 -227.430015) (xy 95.94596 -227.472031)
			(xy 95.969538 -227.518305) (xy 95.985586 -227.567698) (xy 95.993711 -227.618993) (xy 95.99422 -227.64496)
			(xy 95.993711 -227.670927) (xy 96.273621 -227.670927) (xy 96.273621 -227.618993) (xy 96.281746 -227.567698)
			(xy 96.297794 -227.518305) (xy 96.321372 -227.472031) (xy 96.351898 -227.430015) (xy 96.388621 -227.393292)
			(xy 96.430637 -227.362766) (xy 96.476911 -227.339188) (xy 96.526304 -227.32314) (xy 96.577599 -227.315015)
			(xy 96.629533 -227.315015) (xy 96.680828 -227.32314) (xy 96.730221 -227.339188) (xy 96.776495 -227.362766)
			(xy 96.818511 -227.393292) (xy 96.855234 -227.430015) (xy 96.88576 -227.472031) (xy 96.909338 -227.518305)
			(xy 96.925386 -227.567698) (xy 96.933511 -227.618993) (xy 96.93402 -227.64496) (xy 96.933511 -227.670927)
			(xy 97.213421 -227.670927) (xy 97.213421 -227.618993) (xy 97.221546 -227.567698) (xy 97.237594 -227.518305)
			(xy 97.261172 -227.472031) (xy 97.291698 -227.430015) (xy 97.328421 -227.393292) (xy 97.370437 -227.362766)
			(xy 97.416711 -227.339188) (xy 97.466104 -227.32314) (xy 97.517399 -227.315015) (xy 97.569333 -227.315015)
			(xy 97.620628 -227.32314) (xy 97.670021 -227.339188) (xy 97.716295 -227.362766) (xy 97.758311 -227.393292)
			(xy 97.795034 -227.430015) (xy 97.82556 -227.472031) (xy 97.849138 -227.518305) (xy 97.865186 -227.567698)
			(xy 97.873311 -227.618993) (xy 97.87382 -227.64496) (xy 97.873311 -227.670927) (xy 98.153221 -227.670927)
			(xy 98.153221 -227.618993) (xy 98.161346 -227.567698) (xy 98.177394 -227.518305) (xy 98.200972 -227.472031)
			(xy 98.231498 -227.430015) (xy 98.268221 -227.393292) (xy 98.310237 -227.362766) (xy 98.356511 -227.339188)
			(xy 98.405904 -227.32314) (xy 98.457199 -227.315015) (xy 98.509133 -227.315015) (xy 98.560428 -227.32314)
			(xy 98.609821 -227.339188) (xy 98.656095 -227.362766) (xy 98.698111 -227.393292) (xy 98.734834 -227.430015)
			(xy 98.76536 -227.472031) (xy 98.788938 -227.518305) (xy 98.804986 -227.567698) (xy 98.813111 -227.618993)
			(xy 98.81362 -227.64496) (xy 98.813111 -227.670927) (xy 99.092767 -227.670927) (xy 99.092767 -227.618993)
			(xy 99.100892 -227.567698) (xy 99.11694 -227.518305) (xy 99.140518 -227.472031) (xy 99.171044 -227.430015)
			(xy 99.207767 -227.393292) (xy 99.249783 -227.362766) (xy 99.296057 -227.339188) (xy 99.34545 -227.32314)
			(xy 99.396745 -227.315015) (xy 99.448679 -227.315015) (xy 99.499974 -227.32314) (xy 99.549367 -227.339188)
			(xy 99.595641 -227.362766) (xy 99.637657 -227.393292) (xy 99.67438 -227.430015) (xy 99.704906 -227.472031)
			(xy 99.728484 -227.518305) (xy 99.744532 -227.567698) (xy 99.752657 -227.618993) (xy 99.753166 -227.64496)
			(xy 99.752657 -227.670927) (xy 100.032821 -227.670927) (xy 100.032821 -227.618993) (xy 100.040946 -227.567698)
			(xy 100.056994 -227.518305) (xy 100.080572 -227.472031) (xy 100.111098 -227.430015) (xy 100.147821 -227.393292)
			(xy 100.189837 -227.362766) (xy 100.236111 -227.339188) (xy 100.285504 -227.32314) (xy 100.336799 -227.315015)
			(xy 100.388733 -227.315015) (xy 100.440028 -227.32314) (xy 100.489421 -227.339188) (xy 100.535695 -227.362766)
			(xy 100.577711 -227.393292) (xy 100.614434 -227.430015) (xy 100.64496 -227.472031) (xy 100.668538 -227.518305)
			(xy 100.684586 -227.567698) (xy 100.692711 -227.618993) (xy 100.69322 -227.64496) (xy 100.692711 -227.670927)
			(xy 100.972621 -227.670927) (xy 100.972621 -227.618993) (xy 100.980746 -227.567698) (xy 100.996794 -227.518305)
			(xy 101.020372 -227.472031) (xy 101.050898 -227.430015) (xy 101.087621 -227.393292) (xy 101.129637 -227.362766)
			(xy 101.175911 -227.339188) (xy 101.225304 -227.32314) (xy 101.276599 -227.315015) (xy 101.328533 -227.315015)
			(xy 101.379828 -227.32314) (xy 101.429221 -227.339188) (xy 101.475495 -227.362766) (xy 101.517511 -227.393292)
			(xy 101.554234 -227.430015) (xy 101.58476 -227.472031) (xy 101.608338 -227.518305) (xy 101.624386 -227.567698)
			(xy 101.632511 -227.618993) (xy 101.63302 -227.64496) (xy 101.632511 -227.670927) (xy 101.912421 -227.670927)
			(xy 101.912421 -227.618993) (xy 101.920546 -227.567698) (xy 101.936594 -227.518305) (xy 101.960172 -227.472031)
			(xy 101.990698 -227.430015) (xy 102.027421 -227.393292) (xy 102.069437 -227.362766) (xy 102.115711 -227.339188)
			(xy 102.165104 -227.32314) (xy 102.216399 -227.315015) (xy 102.268333 -227.315015) (xy 102.319628 -227.32314)
			(xy 102.369021 -227.339188) (xy 102.415295 -227.362766) (xy 102.457311 -227.393292) (xy 102.494034 -227.430015)
			(xy 102.52456 -227.472031) (xy 102.548138 -227.518305) (xy 102.564186 -227.567698) (xy 102.572311 -227.618993)
			(xy 102.57282 -227.64496) (xy 102.572311 -227.670927) (xy 102.852221 -227.670927) (xy 102.852221 -227.618993)
			(xy 102.860346 -227.567698) (xy 102.876394 -227.518305) (xy 102.899972 -227.472031) (xy 102.930498 -227.430015)
			(xy 102.967221 -227.393292) (xy 103.009237 -227.362766) (xy 103.055511 -227.339188) (xy 103.104904 -227.32314)
			(xy 103.156199 -227.315015) (xy 103.208133 -227.315015) (xy 103.259428 -227.32314) (xy 103.308821 -227.339188)
			(xy 103.355095 -227.362766) (xy 103.397111 -227.393292) (xy 103.433834 -227.430015) (xy 103.46436 -227.472031)
			(xy 103.487938 -227.518305) (xy 103.503986 -227.567698) (xy 103.512111 -227.618993) (xy 103.51262 -227.64496)
			(xy 103.512111 -227.670927) (xy 103.792021 -227.670927) (xy 103.792021 -227.618993) (xy 103.800146 -227.567698)
			(xy 103.816194 -227.518305) (xy 103.839772 -227.472031) (xy 103.870298 -227.430015) (xy 103.907021 -227.393292)
			(xy 103.949037 -227.362766) (xy 103.995311 -227.339188) (xy 104.044704 -227.32314) (xy 104.095999 -227.315015)
			(xy 104.147933 -227.315015) (xy 104.199228 -227.32314) (xy 104.248621 -227.339188) (xy 104.294895 -227.362766)
			(xy 104.336911 -227.393292) (xy 104.373634 -227.430015) (xy 104.40416 -227.472031) (xy 104.427738 -227.518305)
			(xy 104.443786 -227.567698) (xy 104.451911 -227.618993) (xy 104.45242 -227.64496) (xy 104.451911 -227.670927)
			(xy 104.731821 -227.670927) (xy 104.731821 -227.618993) (xy 104.739946 -227.567698) (xy 104.755994 -227.518305)
			(xy 104.779572 -227.472031) (xy 104.810098 -227.430015) (xy 104.846821 -227.393292) (xy 104.888837 -227.362766)
			(xy 104.935111 -227.339188) (xy 104.984504 -227.32314) (xy 105.035799 -227.315015) (xy 105.087733 -227.315015)
			(xy 105.139028 -227.32314) (xy 105.188421 -227.339188) (xy 105.234695 -227.362766) (xy 105.276711 -227.393292)
			(xy 105.313434 -227.430015) (xy 105.34396 -227.472031) (xy 105.367538 -227.518305) (xy 105.383586 -227.567698)
			(xy 105.391711 -227.618993) (xy 105.39222 -227.64496) (xy 105.391711 -227.670927) (xy 105.671621 -227.670927)
			(xy 105.671621 -227.618993) (xy 105.679746 -227.567698) (xy 105.695794 -227.518305) (xy 105.719372 -227.472031)
			(xy 105.749898 -227.430015) (xy 105.786621 -227.393292) (xy 105.828637 -227.362766) (xy 105.874911 -227.339188)
			(xy 105.924304 -227.32314) (xy 105.975599 -227.315015) (xy 106.027533 -227.315015) (xy 106.078828 -227.32314)
			(xy 106.128221 -227.339188) (xy 106.174495 -227.362766) (xy 106.216511 -227.393292) (xy 106.253234 -227.430015)
			(xy 106.28376 -227.472031) (xy 106.307338 -227.518305) (xy 106.323386 -227.567698) (xy 106.331511 -227.618993)
			(xy 106.33202 -227.64496) (xy 106.331511 -227.670927) (xy 106.611421 -227.670927) (xy 106.611421 -227.618993)
			(xy 106.619546 -227.567698) (xy 106.635594 -227.518305) (xy 106.659172 -227.472031) (xy 106.689698 -227.430015)
			(xy 106.726421 -227.393292) (xy 106.768437 -227.362766) (xy 106.814711 -227.339188) (xy 106.864104 -227.32314)
			(xy 106.915399 -227.315015) (xy 106.967333 -227.315015) (xy 107.018628 -227.32314) (xy 107.068021 -227.339188)
			(xy 107.114295 -227.362766) (xy 107.156311 -227.393292) (xy 107.193034 -227.430015) (xy 107.22356 -227.472031)
			(xy 107.247138 -227.518305) (xy 107.263186 -227.567698) (xy 107.271311 -227.618993) (xy 107.27182 -227.64496)
			(xy 107.271311 -227.670927) (xy 107.551221 -227.670927) (xy 107.551221 -227.618993) (xy 107.559346 -227.567698)
			(xy 107.575394 -227.518305) (xy 107.598972 -227.472031) (xy 107.629498 -227.430015) (xy 107.666221 -227.393292)
			(xy 107.708237 -227.362766) (xy 107.754511 -227.339188) (xy 107.803904 -227.32314) (xy 107.855199 -227.315015)
			(xy 107.907133 -227.315015) (xy 107.958428 -227.32314) (xy 108.007821 -227.339188) (xy 108.054095 -227.362766)
			(xy 108.096111 -227.393292) (xy 108.132834 -227.430015) (xy 108.16336 -227.472031) (xy 108.186938 -227.518305)
			(xy 108.202986 -227.567698) (xy 108.211111 -227.618993) (xy 108.21162 -227.64496) (xy 108.211111 -227.670927)
			(xy 108.491021 -227.670927) (xy 108.491021 -227.618993) (xy 108.499146 -227.567698) (xy 108.515194 -227.518305)
			(xy 108.538772 -227.472031) (xy 108.569298 -227.430015) (xy 108.606021 -227.393292) (xy 108.648037 -227.362766)
			(xy 108.694311 -227.339188) (xy 108.743704 -227.32314) (xy 108.794999 -227.315015) (xy 108.846933 -227.315015)
			(xy 108.898228 -227.32314) (xy 108.947621 -227.339188) (xy 108.993895 -227.362766) (xy 109.035911 -227.393292)
			(xy 109.072634 -227.430015) (xy 109.10316 -227.472031) (xy 109.126738 -227.518305) (xy 109.142786 -227.567698)
			(xy 109.150911 -227.618993) (xy 109.15142 -227.64496) (xy 109.150911 -227.670927) (xy 109.430821 -227.670927)
			(xy 109.430821 -227.618993) (xy 109.438946 -227.567698) (xy 109.454994 -227.518305) (xy 109.478572 -227.472031)
			(xy 109.509098 -227.430015) (xy 109.545821 -227.393292) (xy 109.587837 -227.362766) (xy 109.634111 -227.339188)
			(xy 109.683504 -227.32314) (xy 109.734799 -227.315015) (xy 109.786733 -227.315015) (xy 109.838028 -227.32314)
			(xy 109.887421 -227.339188) (xy 109.933695 -227.362766) (xy 109.975711 -227.393292) (xy 110.012434 -227.430015)
			(xy 110.04296 -227.472031) (xy 110.066538 -227.518305) (xy 110.082586 -227.567698) (xy 110.090711 -227.618993)
			(xy 110.09122 -227.64496) (xy 110.090711 -227.670927) (xy 110.370621 -227.670927) (xy 110.370621 -227.618993)
			(xy 110.378746 -227.567698) (xy 110.394794 -227.518305) (xy 110.418372 -227.472031) (xy 110.448898 -227.430015)
			(xy 110.485621 -227.393292) (xy 110.527637 -227.362766) (xy 110.573911 -227.339188) (xy 110.623304 -227.32314)
			(xy 110.674599 -227.315015) (xy 110.726533 -227.315015) (xy 110.777828 -227.32314) (xy 110.827221 -227.339188)
			(xy 110.873495 -227.362766) (xy 110.915511 -227.393292) (xy 110.952234 -227.430015) (xy 110.98276 -227.472031)
			(xy 111.006338 -227.518305) (xy 111.022386 -227.567698) (xy 111.030511 -227.618993) (xy 111.03102 -227.64496)
			(xy 111.030511 -227.670927) (xy 111.310421 -227.670927) (xy 111.310421 -227.618993) (xy 111.318546 -227.567698)
			(xy 111.334594 -227.518305) (xy 111.358172 -227.472031) (xy 111.388698 -227.430015) (xy 111.425421 -227.393292)
			(xy 111.467437 -227.362766) (xy 111.513711 -227.339188) (xy 111.563104 -227.32314) (xy 111.614399 -227.315015)
			(xy 111.666333 -227.315015) (xy 111.717628 -227.32314) (xy 111.767021 -227.339188) (xy 111.813295 -227.362766)
			(xy 111.855311 -227.393292) (xy 111.892034 -227.430015) (xy 111.92256 -227.472031) (xy 111.946138 -227.518305)
			(xy 111.962186 -227.567698) (xy 111.970311 -227.618993) (xy 111.97082 -227.64496) (xy 111.970311 -227.670927)
			(xy 112.250221 -227.670927) (xy 112.250221 -227.618993) (xy 112.258346 -227.567698) (xy 112.274394 -227.518305)
			(xy 112.297972 -227.472031) (xy 112.328498 -227.430015) (xy 112.365221 -227.393292) (xy 112.407237 -227.362766)
			(xy 112.453511 -227.339188) (xy 112.502904 -227.32314) (xy 112.554199 -227.315015) (xy 112.606133 -227.315015)
			(xy 112.657428 -227.32314) (xy 112.706821 -227.339188) (xy 112.753095 -227.362766) (xy 112.795111 -227.393292)
			(xy 112.831834 -227.430015) (xy 112.86236 -227.472031) (xy 112.885938 -227.518305) (xy 112.901986 -227.567698)
			(xy 112.910111 -227.618993) (xy 112.91062 -227.64496) (xy 112.910111 -227.670927) (xy 113.190021 -227.670927)
			(xy 113.190021 -227.618993) (xy 113.198146 -227.567698) (xy 113.214194 -227.518305) (xy 113.237772 -227.472031)
			(xy 113.268298 -227.430015) (xy 113.305021 -227.393292) (xy 113.347037 -227.362766) (xy 113.393311 -227.339188)
			(xy 113.442704 -227.32314) (xy 113.493999 -227.315015) (xy 113.545933 -227.315015) (xy 113.597228 -227.32314)
			(xy 113.646621 -227.339188) (xy 113.692895 -227.362766) (xy 113.734911 -227.393292) (xy 113.771634 -227.430015)
			(xy 113.80216 -227.472031) (xy 113.825738 -227.518305) (xy 113.841786 -227.567698) (xy 113.849911 -227.618993)
			(xy 113.85042 -227.64496) (xy 113.849911 -227.670927) (xy 114.130075 -227.670927) (xy 114.130075 -227.618993)
			(xy 114.1382 -227.567698) (xy 114.154248 -227.518305) (xy 114.177826 -227.472031) (xy 114.208352 -227.430015)
			(xy 114.245075 -227.393292) (xy 114.287091 -227.362766) (xy 114.333365 -227.339188) (xy 114.382758 -227.32314)
			(xy 114.434053 -227.315015) (xy 114.485987 -227.315015) (xy 114.537282 -227.32314) (xy 114.586675 -227.339188)
			(xy 114.632949 -227.362766) (xy 114.674965 -227.393292) (xy 114.711688 -227.430015) (xy 114.742214 -227.472031)
			(xy 114.765792 -227.518305) (xy 114.78184 -227.567698) (xy 114.789965 -227.618993) (xy 114.790474 -227.64496)
			(xy 114.789965 -227.670927) (xy 115.069621 -227.670927) (xy 115.069621 -227.618993) (xy 115.077746 -227.567698)
			(xy 115.093794 -227.518305) (xy 115.117372 -227.472031) (xy 115.147898 -227.430015) (xy 115.184621 -227.393292)
			(xy 115.226637 -227.362766) (xy 115.272911 -227.339188) (xy 115.322304 -227.32314) (xy 115.373599 -227.315015)
			(xy 115.425533 -227.315015) (xy 115.476828 -227.32314) (xy 115.526221 -227.339188) (xy 115.572495 -227.362766)
			(xy 115.614511 -227.393292) (xy 115.651234 -227.430015) (xy 115.68176 -227.472031) (xy 115.705338 -227.518305)
			(xy 115.721386 -227.567698) (xy 115.729511 -227.618993) (xy 115.73002 -227.64496) (xy 115.729511 -227.670927)
			(xy 116.009421 -227.670927) (xy 116.009421 -227.618993) (xy 116.017546 -227.567698) (xy 116.033594 -227.518305)
			(xy 116.057172 -227.472031) (xy 116.087698 -227.430015) (xy 116.124421 -227.393292) (xy 116.166437 -227.362766)
			(xy 116.212711 -227.339188) (xy 116.262104 -227.32314) (xy 116.313399 -227.315015) (xy 116.365333 -227.315015)
			(xy 116.416628 -227.32314) (xy 116.466021 -227.339188) (xy 116.512295 -227.362766) (xy 116.554311 -227.393292)
			(xy 116.591034 -227.430015) (xy 116.62156 -227.472031) (xy 116.645138 -227.518305) (xy 116.661186 -227.567698)
			(xy 116.669311 -227.618993) (xy 116.66982 -227.64496) (xy 116.669311 -227.670927) (xy 116.949221 -227.670927)
			(xy 116.949221 -227.618993) (xy 116.957346 -227.567698) (xy 116.973394 -227.518305) (xy 116.996972 -227.472031)
			(xy 117.027498 -227.430015) (xy 117.064221 -227.393292) (xy 117.106237 -227.362766) (xy 117.152511 -227.339188)
			(xy 117.201904 -227.32314) (xy 117.253199 -227.315015) (xy 117.305133 -227.315015) (xy 117.356428 -227.32314)
			(xy 117.405821 -227.339188) (xy 117.452095 -227.362766) (xy 117.494111 -227.393292) (xy 117.530834 -227.430015)
			(xy 117.56136 -227.472031) (xy 117.584938 -227.518305) (xy 117.600986 -227.567698) (xy 117.609111 -227.618993)
			(xy 117.60962 -227.64496) (xy 117.609111 -227.670927) (xy 117.889021 -227.670927) (xy 117.889021 -227.618993)
			(xy 117.897146 -227.567698) (xy 117.913194 -227.518305) (xy 117.936772 -227.472031) (xy 117.967298 -227.430015)
			(xy 118.004021 -227.393292) (xy 118.046037 -227.362766) (xy 118.092311 -227.339188) (xy 118.141704 -227.32314)
			(xy 118.192999 -227.315015) (xy 118.244933 -227.315015) (xy 118.296228 -227.32314) (xy 118.345621 -227.339188)
			(xy 118.391895 -227.362766) (xy 118.433911 -227.393292) (xy 118.470634 -227.430015) (xy 118.50116 -227.472031)
			(xy 118.524738 -227.518305) (xy 118.540786 -227.567698) (xy 118.548911 -227.618993) (xy 118.54942 -227.64496)
			(xy 118.548911 -227.670927) (xy 118.828821 -227.670927) (xy 118.828821 -227.618993) (xy 118.836946 -227.567698)
			(xy 118.852994 -227.518305) (xy 118.876572 -227.472031) (xy 118.907098 -227.430015) (xy 118.943821 -227.393292)
			(xy 118.985837 -227.362766) (xy 119.032111 -227.339188) (xy 119.081504 -227.32314) (xy 119.132799 -227.315015)
			(xy 119.184733 -227.315015) (xy 119.236028 -227.32314) (xy 119.285421 -227.339188) (xy 119.331695 -227.362766)
			(xy 119.373711 -227.393292) (xy 119.410434 -227.430015) (xy 119.44096 -227.472031) (xy 119.464538 -227.518305)
			(xy 119.480586 -227.567698) (xy 119.488711 -227.618993) (xy 119.48922 -227.64496) (xy 119.488711 -227.670927)
			(xy 119.768621 -227.670927) (xy 119.768621 -227.618993) (xy 119.776746 -227.567698) (xy 119.792794 -227.518305)
			(xy 119.816372 -227.472031) (xy 119.846898 -227.430015) (xy 119.883621 -227.393292) (xy 119.925637 -227.362766)
			(xy 119.971911 -227.339188) (xy 120.021304 -227.32314) (xy 120.072599 -227.315015) (xy 120.124533 -227.315015)
			(xy 120.175828 -227.32314) (xy 120.225221 -227.339188) (xy 120.271495 -227.362766) (xy 120.313511 -227.393292)
			(xy 120.350234 -227.430015) (xy 120.38076 -227.472031) (xy 120.404338 -227.518305) (xy 120.420386 -227.567698)
			(xy 120.428511 -227.618993) (xy 120.42902 -227.64496) (xy 120.428511 -227.670927) (xy 120.708421 -227.670927)
			(xy 120.708421 -227.618993) (xy 120.716546 -227.567698) (xy 120.732594 -227.518305) (xy 120.756172 -227.472031)
			(xy 120.786698 -227.430015) (xy 120.823421 -227.393292) (xy 120.865437 -227.362766) (xy 120.911711 -227.339188)
			(xy 120.961104 -227.32314) (xy 121.012399 -227.315015) (xy 121.064333 -227.315015) (xy 121.115628 -227.32314)
			(xy 121.165021 -227.339188) (xy 121.211295 -227.362766) (xy 121.253311 -227.393292) (xy 121.290034 -227.430015)
			(xy 121.32056 -227.472031) (xy 121.344138 -227.518305) (xy 121.360186 -227.567698) (xy 121.368311 -227.618993)
			(xy 121.36882 -227.64496) (xy 121.368311 -227.670927) (xy 121.647967 -227.670927) (xy 121.647967 -227.618993)
			(xy 121.656092 -227.567698) (xy 121.67214 -227.518305) (xy 121.695718 -227.472031) (xy 121.726244 -227.430015)
			(xy 121.762967 -227.393292) (xy 121.804983 -227.362766) (xy 121.851257 -227.339188) (xy 121.90065 -227.32314)
			(xy 121.951945 -227.315015) (xy 122.003879 -227.315015) (xy 122.055174 -227.32314) (xy 122.104567 -227.339188)
			(xy 122.150841 -227.362766) (xy 122.192857 -227.393292) (xy 122.22958 -227.430015) (xy 122.260106 -227.472031)
			(xy 122.283684 -227.518305) (xy 122.299732 -227.567698) (xy 122.307857 -227.618993) (xy 122.308366 -227.64496)
			(xy 122.307857 -227.670927) (xy 122.588021 -227.670927) (xy 122.588021 -227.618993) (xy 122.596146 -227.567698)
			(xy 122.612194 -227.518305) (xy 122.635772 -227.472031) (xy 122.666298 -227.430015) (xy 122.703021 -227.393292)
			(xy 122.745037 -227.362766) (xy 122.791311 -227.339188) (xy 122.840704 -227.32314) (xy 122.891999 -227.315015)
			(xy 122.943933 -227.315015) (xy 122.995228 -227.32314) (xy 123.044621 -227.339188) (xy 123.090895 -227.362766)
			(xy 123.132911 -227.393292) (xy 123.169634 -227.430015) (xy 123.20016 -227.472031) (xy 123.223738 -227.518305)
			(xy 123.239786 -227.567698) (xy 123.247911 -227.618993) (xy 123.24842 -227.64496) (xy 123.247911 -227.670927)
			(xy 123.527821 -227.670927) (xy 123.527821 -227.618993) (xy 123.535946 -227.567698) (xy 123.551994 -227.518305)
			(xy 123.575572 -227.472031) (xy 123.606098 -227.430015) (xy 123.642821 -227.393292) (xy 123.684837 -227.362766)
			(xy 123.731111 -227.339188) (xy 123.780504 -227.32314) (xy 123.831799 -227.315015) (xy 123.883733 -227.315015)
			(xy 123.935028 -227.32314) (xy 123.984421 -227.339188) (xy 124.030695 -227.362766) (xy 124.072711 -227.393292)
			(xy 124.109434 -227.430015) (xy 124.13996 -227.472031) (xy 124.163538 -227.518305) (xy 124.179586 -227.567698)
			(xy 124.187711 -227.618993) (xy 124.18822 -227.64496) (xy 124.187711 -227.670927) (xy 124.467621 -227.670927)
			(xy 124.467621 -227.618993) (xy 124.475746 -227.567698) (xy 124.491794 -227.518305) (xy 124.515372 -227.472031)
			(xy 124.545898 -227.430015) (xy 124.582621 -227.393292) (xy 124.624637 -227.362766) (xy 124.670911 -227.339188)
			(xy 124.720304 -227.32314) (xy 124.771599 -227.315015) (xy 124.823533 -227.315015) (xy 124.874828 -227.32314)
			(xy 124.924221 -227.339188) (xy 124.970495 -227.362766) (xy 125.012511 -227.393292) (xy 125.049234 -227.430015)
			(xy 125.07976 -227.472031) (xy 125.103338 -227.518305) (xy 125.119386 -227.567698) (xy 125.127511 -227.618993)
			(xy 125.12802 -227.64496) (xy 125.127511 -227.670927) (xy 125.407421 -227.670927) (xy 125.407421 -227.618993)
			(xy 125.415546 -227.567698) (xy 125.431594 -227.518305) (xy 125.455172 -227.472031) (xy 125.485698 -227.430015)
			(xy 125.522421 -227.393292) (xy 125.564437 -227.362766) (xy 125.610711 -227.339188) (xy 125.660104 -227.32314)
			(xy 125.711399 -227.315015) (xy 125.763333 -227.315015) (xy 125.814628 -227.32314) (xy 125.864021 -227.339188)
			(xy 125.910295 -227.362766) (xy 125.952311 -227.393292) (xy 125.989034 -227.430015) (xy 126.01956 -227.472031)
			(xy 126.043138 -227.518305) (xy 126.059186 -227.567698) (xy 126.067311 -227.618993) (xy 126.06782 -227.64496)
			(xy 126.067311 -227.670927) (xy 126.347221 -227.670927) (xy 126.347221 -227.618993) (xy 126.355346 -227.567698)
			(xy 126.371394 -227.518305) (xy 126.394972 -227.472031) (xy 126.425498 -227.430015) (xy 126.462221 -227.393292)
			(xy 126.504237 -227.362766) (xy 126.550511 -227.339188) (xy 126.599904 -227.32314) (xy 126.651199 -227.315015)
			(xy 126.703133 -227.315015) (xy 126.754428 -227.32314) (xy 126.803821 -227.339188) (xy 126.850095 -227.362766)
			(xy 126.892111 -227.393292) (xy 126.928834 -227.430015) (xy 126.95936 -227.472031) (xy 126.982938 -227.518305)
			(xy 126.998986 -227.567698) (xy 127.007111 -227.618993) (xy 127.00762 -227.64496) (xy 127.007111 -227.670927)
			(xy 127.286767 -227.670927) (xy 127.286767 -227.618993) (xy 127.294892 -227.567698) (xy 127.31094 -227.518305)
			(xy 127.334518 -227.472031) (xy 127.365044 -227.430015) (xy 127.401767 -227.393292) (xy 127.443783 -227.362766)
			(xy 127.490057 -227.339188) (xy 127.53945 -227.32314) (xy 127.590745 -227.315015) (xy 127.642679 -227.315015)
			(xy 127.693974 -227.32314) (xy 127.743367 -227.339188) (xy 127.789641 -227.362766) (xy 127.831657 -227.393292)
			(xy 127.86838 -227.430015) (xy 127.898906 -227.472031) (xy 127.922484 -227.518305) (xy 127.938532 -227.567698)
			(xy 127.946657 -227.618993) (xy 127.947166 -227.64496) (xy 127.946657 -227.670927) (xy 128.226567 -227.670927)
			(xy 128.226567 -227.618993) (xy 128.234692 -227.567698) (xy 128.25074 -227.518305) (xy 128.274318 -227.472031)
			(xy 128.304844 -227.430015) (xy 128.341567 -227.393292) (xy 128.383583 -227.362766) (xy 128.429857 -227.339188)
			(xy 128.47925 -227.32314) (xy 128.530545 -227.315015) (xy 128.582479 -227.315015) (xy 128.633774 -227.32314)
			(xy 128.683167 -227.339188) (xy 128.729441 -227.362766) (xy 128.771457 -227.393292) (xy 128.80818 -227.430015)
			(xy 128.838706 -227.472031) (xy 128.862284 -227.518305) (xy 128.878332 -227.567698) (xy 128.886457 -227.618993)
			(xy 128.886966 -227.64496) (xy 128.886457 -227.670927) (xy 129.166621 -227.670927) (xy 129.166621 -227.618993)
			(xy 129.174746 -227.567698) (xy 129.190794 -227.518305) (xy 129.214372 -227.472031) (xy 129.244898 -227.430015)
			(xy 129.281621 -227.393292) (xy 129.323637 -227.362766) (xy 129.369911 -227.339188) (xy 129.419304 -227.32314)
			(xy 129.470599 -227.315015) (xy 129.522533 -227.315015) (xy 129.573828 -227.32314) (xy 129.623221 -227.339188)
			(xy 129.669495 -227.362766) (xy 129.711511 -227.393292) (xy 129.748234 -227.430015) (xy 129.77876 -227.472031)
			(xy 129.802338 -227.518305) (xy 129.818386 -227.567698) (xy 129.826511 -227.618993) (xy 129.82702 -227.64496)
			(xy 129.826511 -227.670927) (xy 130.106421 -227.670927) (xy 130.106421 -227.618993) (xy 130.114546 -227.567698)
			(xy 130.130594 -227.518305) (xy 130.154172 -227.472031) (xy 130.184698 -227.430015) (xy 130.221421 -227.393292)
			(xy 130.263437 -227.362766) (xy 130.309711 -227.339188) (xy 130.359104 -227.32314) (xy 130.410399 -227.315015)
			(xy 130.462333 -227.315015) (xy 130.513628 -227.32314) (xy 130.563021 -227.339188) (xy 130.609295 -227.362766)
			(xy 130.651311 -227.393292) (xy 130.688034 -227.430015) (xy 130.71856 -227.472031) (xy 130.742138 -227.518305)
			(xy 130.758186 -227.567698) (xy 130.766311 -227.618993) (xy 130.76682 -227.64496) (xy 130.766311 -227.670927)
			(xy 131.046221 -227.670927) (xy 131.046221 -227.618993) (xy 131.054346 -227.567698) (xy 131.070394 -227.518305)
			(xy 131.093972 -227.472031) (xy 131.124498 -227.430015) (xy 131.161221 -227.393292) (xy 131.203237 -227.362766)
			(xy 131.249511 -227.339188) (xy 131.298904 -227.32314) (xy 131.350199 -227.315015) (xy 131.402133 -227.315015)
			(xy 131.453428 -227.32314) (xy 131.502821 -227.339188) (xy 131.549095 -227.362766) (xy 131.591111 -227.393292)
			(xy 131.627834 -227.430015) (xy 131.65836 -227.472031) (xy 131.681938 -227.518305) (xy 131.697986 -227.567698)
			(xy 131.706111 -227.618993) (xy 131.70662 -227.64496) (xy 131.706111 -227.670927) (xy 131.986021 -227.670927)
			(xy 131.986021 -227.618993) (xy 131.994146 -227.567698) (xy 132.010194 -227.518305) (xy 132.033772 -227.472031)
			(xy 132.064298 -227.430015) (xy 132.101021 -227.393292) (xy 132.143037 -227.362766) (xy 132.189311 -227.339188)
			(xy 132.238704 -227.32314) (xy 132.289999 -227.315015) (xy 132.341933 -227.315015) (xy 132.393228 -227.32314)
			(xy 132.442621 -227.339188) (xy 132.488895 -227.362766) (xy 132.530911 -227.393292) (xy 132.567634 -227.430015)
			(xy 132.59816 -227.472031) (xy 132.621738 -227.518305) (xy 132.637786 -227.567698) (xy 132.645911 -227.618993)
			(xy 132.64642 -227.64496) (xy 132.645911 -227.670927) (xy 132.637786 -227.722222) (xy 132.621738 -227.771615)
			(xy 132.59816 -227.817889) (xy 132.567634 -227.859905) (xy 132.530911 -227.896628) (xy 132.488895 -227.927154)
			(xy 132.442621 -227.950732) (xy 132.393228 -227.96678) (xy 132.341933 -227.974905) (xy 132.289999 -227.974905)
			(xy 132.238704 -227.96678) (xy 132.189311 -227.950732) (xy 132.143037 -227.927154) (xy 132.101021 -227.896628)
			(xy 132.064298 -227.859905) (xy 132.033772 -227.817889) (xy 132.010194 -227.771615) (xy 131.994146 -227.722222)
			(xy 131.986021 -227.670927) (xy 131.706111 -227.670927) (xy 131.697986 -227.722222) (xy 131.681938 -227.771615)
			(xy 131.65836 -227.817889) (xy 131.627834 -227.859905) (xy 131.591111 -227.896628) (xy 131.549095 -227.927154)
			(xy 131.502821 -227.950732) (xy 131.453428 -227.96678) (xy 131.402133 -227.974905) (xy 131.350199 -227.974905)
			(xy 131.298904 -227.96678) (xy 131.249511 -227.950732) (xy 131.203237 -227.927154) (xy 131.161221 -227.896628)
			(xy 131.124498 -227.859905) (xy 131.093972 -227.817889) (xy 131.070394 -227.771615) (xy 131.054346 -227.722222)
			(xy 131.046221 -227.670927) (xy 130.766311 -227.670927) (xy 130.758186 -227.722222) (xy 130.742138 -227.771615)
			(xy 130.71856 -227.817889) (xy 130.688034 -227.859905) (xy 130.651311 -227.896628) (xy 130.609295 -227.927154)
			(xy 130.563021 -227.950732) (xy 130.513628 -227.96678) (xy 130.462333 -227.974905) (xy 130.410399 -227.974905)
			(xy 130.359104 -227.96678) (xy 130.309711 -227.950732) (xy 130.263437 -227.927154) (xy 130.221421 -227.896628)
			(xy 130.184698 -227.859905) (xy 130.154172 -227.817889) (xy 130.130594 -227.771615) (xy 130.114546 -227.722222)
			(xy 130.106421 -227.670927) (xy 129.826511 -227.670927) (xy 129.818386 -227.722222) (xy 129.802338 -227.771615)
			(xy 129.77876 -227.817889) (xy 129.748234 -227.859905) (xy 129.711511 -227.896628) (xy 129.669495 -227.927154)
			(xy 129.623221 -227.950732) (xy 129.573828 -227.96678) (xy 129.522533 -227.974905) (xy 129.470599 -227.974905)
			(xy 129.419304 -227.96678) (xy 129.369911 -227.950732) (xy 129.323637 -227.927154) (xy 129.281621 -227.896628)
			(xy 129.244898 -227.859905) (xy 129.214372 -227.817889) (xy 129.190794 -227.771615) (xy 129.174746 -227.722222)
			(xy 129.166621 -227.670927) (xy 128.886457 -227.670927) (xy 128.878332 -227.722222) (xy 128.862284 -227.771615)
			(xy 128.838706 -227.817889) (xy 128.80818 -227.859905) (xy 128.771457 -227.896628) (xy 128.729441 -227.927154)
			(xy 128.683167 -227.950732) (xy 128.633774 -227.96678) (xy 128.582479 -227.974905) (xy 128.530545 -227.974905)
			(xy 128.47925 -227.96678) (xy 128.429857 -227.950732) (xy 128.383583 -227.927154) (xy 128.341567 -227.896628)
			(xy 128.304844 -227.859905) (xy 128.274318 -227.817889) (xy 128.25074 -227.771615) (xy 128.234692 -227.722222)
			(xy 128.226567 -227.670927) (xy 127.946657 -227.670927) (xy 127.938532 -227.722222) (xy 127.922484 -227.771615)
			(xy 127.898906 -227.817889) (xy 127.86838 -227.859905) (xy 127.831657 -227.896628) (xy 127.789641 -227.927154)
			(xy 127.743367 -227.950732) (xy 127.693974 -227.96678) (xy 127.642679 -227.974905) (xy 127.590745 -227.974905)
			(xy 127.53945 -227.96678) (xy 127.490057 -227.950732) (xy 127.443783 -227.927154) (xy 127.401767 -227.896628)
			(xy 127.365044 -227.859905) (xy 127.334518 -227.817889) (xy 127.31094 -227.771615) (xy 127.294892 -227.722222)
			(xy 127.286767 -227.670927) (xy 127.007111 -227.670927) (xy 126.998986 -227.722222) (xy 126.982938 -227.771615)
			(xy 126.95936 -227.817889) (xy 126.928834 -227.859905) (xy 126.892111 -227.896628) (xy 126.850095 -227.927154)
			(xy 126.803821 -227.950732) (xy 126.754428 -227.96678) (xy 126.703133 -227.974905) (xy 126.651199 -227.974905)
			(xy 126.599904 -227.96678) (xy 126.550511 -227.950732) (xy 126.504237 -227.927154) (xy 126.462221 -227.896628)
			(xy 126.425498 -227.859905) (xy 126.394972 -227.817889) (xy 126.371394 -227.771615) (xy 126.355346 -227.722222)
			(xy 126.347221 -227.670927) (xy 126.067311 -227.670927) (xy 126.059186 -227.722222) (xy 126.043138 -227.771615)
			(xy 126.01956 -227.817889) (xy 125.989034 -227.859905) (xy 125.952311 -227.896628) (xy 125.910295 -227.927154)
			(xy 125.864021 -227.950732) (xy 125.814628 -227.96678) (xy 125.763333 -227.974905) (xy 125.711399 -227.974905)
			(xy 125.660104 -227.96678) (xy 125.610711 -227.950732) (xy 125.564437 -227.927154) (xy 125.522421 -227.896628)
			(xy 125.485698 -227.859905) (xy 125.455172 -227.817889) (xy 125.431594 -227.771615) (xy 125.415546 -227.722222)
			(xy 125.407421 -227.670927) (xy 125.127511 -227.670927) (xy 125.119386 -227.722222) (xy 125.103338 -227.771615)
			(xy 125.07976 -227.817889) (xy 125.049234 -227.859905) (xy 125.012511 -227.896628) (xy 124.970495 -227.927154)
			(xy 124.924221 -227.950732) (xy 124.874828 -227.96678) (xy 124.823533 -227.974905) (xy 124.771599 -227.974905)
			(xy 124.720304 -227.96678) (xy 124.670911 -227.950732) (xy 124.624637 -227.927154) (xy 124.582621 -227.896628)
			(xy 124.545898 -227.859905) (xy 124.515372 -227.817889) (xy 124.491794 -227.771615) (xy 124.475746 -227.722222)
			(xy 124.467621 -227.670927) (xy 124.187711 -227.670927) (xy 124.179586 -227.722222) (xy 124.163538 -227.771615)
			(xy 124.13996 -227.817889) (xy 124.109434 -227.859905) (xy 124.072711 -227.896628) (xy 124.030695 -227.927154)
			(xy 123.984421 -227.950732) (xy 123.935028 -227.96678) (xy 123.883733 -227.974905) (xy 123.831799 -227.974905)
			(xy 123.780504 -227.96678) (xy 123.731111 -227.950732) (xy 123.684837 -227.927154) (xy 123.642821 -227.896628)
			(xy 123.606098 -227.859905) (xy 123.575572 -227.817889) (xy 123.551994 -227.771615) (xy 123.535946 -227.722222)
			(xy 123.527821 -227.670927) (xy 123.247911 -227.670927) (xy 123.239786 -227.722222) (xy 123.223738 -227.771615)
			(xy 123.20016 -227.817889) (xy 123.169634 -227.859905) (xy 123.132911 -227.896628) (xy 123.090895 -227.927154)
			(xy 123.044621 -227.950732) (xy 122.995228 -227.96678) (xy 122.943933 -227.974905) (xy 122.891999 -227.974905)
			(xy 122.840704 -227.96678) (xy 122.791311 -227.950732) (xy 122.745037 -227.927154) (xy 122.703021 -227.896628)
			(xy 122.666298 -227.859905) (xy 122.635772 -227.817889) (xy 122.612194 -227.771615) (xy 122.596146 -227.722222)
			(xy 122.588021 -227.670927) (xy 122.307857 -227.670927) (xy 122.299732 -227.722222) (xy 122.283684 -227.771615)
			(xy 122.260106 -227.817889) (xy 122.22958 -227.859905) (xy 122.192857 -227.896628) (xy 122.150841 -227.927154)
			(xy 122.104567 -227.950732) (xy 122.055174 -227.96678) (xy 122.003879 -227.974905) (xy 121.951945 -227.974905)
			(xy 121.90065 -227.96678) (xy 121.851257 -227.950732) (xy 121.804983 -227.927154) (xy 121.762967 -227.896628)
			(xy 121.726244 -227.859905) (xy 121.695718 -227.817889) (xy 121.67214 -227.771615) (xy 121.656092 -227.722222)
			(xy 121.647967 -227.670927) (xy 121.368311 -227.670927) (xy 121.360186 -227.722222) (xy 121.344138 -227.771615)
			(xy 121.32056 -227.817889) (xy 121.290034 -227.859905) (xy 121.253311 -227.896628) (xy 121.211295 -227.927154)
			(xy 121.165021 -227.950732) (xy 121.115628 -227.96678) (xy 121.064333 -227.974905) (xy 121.012399 -227.974905)
			(xy 120.961104 -227.96678) (xy 120.911711 -227.950732) (xy 120.865437 -227.927154) (xy 120.823421 -227.896628)
			(xy 120.786698 -227.859905) (xy 120.756172 -227.817889) (xy 120.732594 -227.771615) (xy 120.716546 -227.722222)
			(xy 120.708421 -227.670927) (xy 120.428511 -227.670927) (xy 120.420386 -227.722222) (xy 120.404338 -227.771615)
			(xy 120.38076 -227.817889) (xy 120.350234 -227.859905) (xy 120.313511 -227.896628) (xy 120.271495 -227.927154)
			(xy 120.225221 -227.950732) (xy 120.175828 -227.96678) (xy 120.124533 -227.974905) (xy 120.072599 -227.974905)
			(xy 120.021304 -227.96678) (xy 119.971911 -227.950732) (xy 119.925637 -227.927154) (xy 119.883621 -227.896628)
			(xy 119.846898 -227.859905) (xy 119.816372 -227.817889) (xy 119.792794 -227.771615) (xy 119.776746 -227.722222)
			(xy 119.768621 -227.670927) (xy 119.488711 -227.670927) (xy 119.480586 -227.722222) (xy 119.464538 -227.771615)
			(xy 119.44096 -227.817889) (xy 119.410434 -227.859905) (xy 119.373711 -227.896628) (xy 119.331695 -227.927154)
			(xy 119.285421 -227.950732) (xy 119.236028 -227.96678) (xy 119.184733 -227.974905) (xy 119.132799 -227.974905)
			(xy 119.081504 -227.96678) (xy 119.032111 -227.950732) (xy 118.985837 -227.927154) (xy 118.943821 -227.896628)
			(xy 118.907098 -227.859905) (xy 118.876572 -227.817889) (xy 118.852994 -227.771615) (xy 118.836946 -227.722222)
			(xy 118.828821 -227.670927) (xy 118.548911 -227.670927) (xy 118.540786 -227.722222) (xy 118.524738 -227.771615)
			(xy 118.50116 -227.817889) (xy 118.470634 -227.859905) (xy 118.433911 -227.896628) (xy 118.391895 -227.927154)
			(xy 118.345621 -227.950732) (xy 118.296228 -227.96678) (xy 118.244933 -227.974905) (xy 118.192999 -227.974905)
			(xy 118.141704 -227.96678) (xy 118.092311 -227.950732) (xy 118.046037 -227.927154) (xy 118.004021 -227.896628)
			(xy 117.967298 -227.859905) (xy 117.936772 -227.817889) (xy 117.913194 -227.771615) (xy 117.897146 -227.722222)
			(xy 117.889021 -227.670927) (xy 117.609111 -227.670927) (xy 117.600986 -227.722222) (xy 117.584938 -227.771615)
			(xy 117.56136 -227.817889) (xy 117.530834 -227.859905) (xy 117.494111 -227.896628) (xy 117.452095 -227.927154)
			(xy 117.405821 -227.950732) (xy 117.356428 -227.96678) (xy 117.305133 -227.974905) (xy 117.253199 -227.974905)
			(xy 117.201904 -227.96678) (xy 117.152511 -227.950732) (xy 117.106237 -227.927154) (xy 117.064221 -227.896628)
			(xy 117.027498 -227.859905) (xy 116.996972 -227.817889) (xy 116.973394 -227.771615) (xy 116.957346 -227.722222)
			(xy 116.949221 -227.670927) (xy 116.669311 -227.670927) (xy 116.661186 -227.722222) (xy 116.645138 -227.771615)
			(xy 116.62156 -227.817889) (xy 116.591034 -227.859905) (xy 116.554311 -227.896628) (xy 116.512295 -227.927154)
			(xy 116.466021 -227.950732) (xy 116.416628 -227.96678) (xy 116.365333 -227.974905) (xy 116.313399 -227.974905)
			(xy 116.262104 -227.96678) (xy 116.212711 -227.950732) (xy 116.166437 -227.927154) (xy 116.124421 -227.896628)
			(xy 116.087698 -227.859905) (xy 116.057172 -227.817889) (xy 116.033594 -227.771615) (xy 116.017546 -227.722222)
			(xy 116.009421 -227.670927) (xy 115.729511 -227.670927) (xy 115.721386 -227.722222) (xy 115.705338 -227.771615)
			(xy 115.68176 -227.817889) (xy 115.651234 -227.859905) (xy 115.614511 -227.896628) (xy 115.572495 -227.927154)
			(xy 115.526221 -227.950732) (xy 115.476828 -227.96678) (xy 115.425533 -227.974905) (xy 115.373599 -227.974905)
			(xy 115.322304 -227.96678) (xy 115.272911 -227.950732) (xy 115.226637 -227.927154) (xy 115.184621 -227.896628)
			(xy 115.147898 -227.859905) (xy 115.117372 -227.817889) (xy 115.093794 -227.771615) (xy 115.077746 -227.722222)
			(xy 115.069621 -227.670927) (xy 114.789965 -227.670927) (xy 114.78184 -227.722222) (xy 114.765792 -227.771615)
			(xy 114.742214 -227.817889) (xy 114.711688 -227.859905) (xy 114.674965 -227.896628) (xy 114.632949 -227.927154)
			(xy 114.586675 -227.950732) (xy 114.537282 -227.96678) (xy 114.485987 -227.974905) (xy 114.434053 -227.974905)
			(xy 114.382758 -227.96678) (xy 114.333365 -227.950732) (xy 114.287091 -227.927154) (xy 114.245075 -227.896628)
			(xy 114.208352 -227.859905) (xy 114.177826 -227.817889) (xy 114.154248 -227.771615) (xy 114.1382 -227.722222)
			(xy 114.130075 -227.670927) (xy 113.849911 -227.670927) (xy 113.841786 -227.722222) (xy 113.825738 -227.771615)
			(xy 113.80216 -227.817889) (xy 113.771634 -227.859905) (xy 113.734911 -227.896628) (xy 113.692895 -227.927154)
			(xy 113.646621 -227.950732) (xy 113.597228 -227.96678) (xy 113.545933 -227.974905) (xy 113.493999 -227.974905)
			(xy 113.442704 -227.96678) (xy 113.393311 -227.950732) (xy 113.347037 -227.927154) (xy 113.305021 -227.896628)
			(xy 113.268298 -227.859905) (xy 113.237772 -227.817889) (xy 113.214194 -227.771615) (xy 113.198146 -227.722222)
			(xy 113.190021 -227.670927) (xy 112.910111 -227.670927) (xy 112.901986 -227.722222) (xy 112.885938 -227.771615)
			(xy 112.86236 -227.817889) (xy 112.831834 -227.859905) (xy 112.795111 -227.896628) (xy 112.753095 -227.927154)
			(xy 112.706821 -227.950732) (xy 112.657428 -227.96678) (xy 112.606133 -227.974905) (xy 112.554199 -227.974905)
			(xy 112.502904 -227.96678) (xy 112.453511 -227.950732) (xy 112.407237 -227.927154) (xy 112.365221 -227.896628)
			(xy 112.328498 -227.859905) (xy 112.297972 -227.817889) (xy 112.274394 -227.771615) (xy 112.258346 -227.722222)
			(xy 112.250221 -227.670927) (xy 111.970311 -227.670927) (xy 111.962186 -227.722222) (xy 111.946138 -227.771615)
			(xy 111.92256 -227.817889) (xy 111.892034 -227.859905) (xy 111.855311 -227.896628) (xy 111.813295 -227.927154)
			(xy 111.767021 -227.950732) (xy 111.717628 -227.96678) (xy 111.666333 -227.974905) (xy 111.614399 -227.974905)
			(xy 111.563104 -227.96678) (xy 111.513711 -227.950732) (xy 111.467437 -227.927154) (xy 111.425421 -227.896628)
			(xy 111.388698 -227.859905) (xy 111.358172 -227.817889) (xy 111.334594 -227.771615) (xy 111.318546 -227.722222)
			(xy 111.310421 -227.670927) (xy 111.030511 -227.670927) (xy 111.022386 -227.722222) (xy 111.006338 -227.771615)
			(xy 110.98276 -227.817889) (xy 110.952234 -227.859905) (xy 110.915511 -227.896628) (xy 110.873495 -227.927154)
			(xy 110.827221 -227.950732) (xy 110.777828 -227.96678) (xy 110.726533 -227.974905) (xy 110.674599 -227.974905)
			(xy 110.623304 -227.96678) (xy 110.573911 -227.950732) (xy 110.527637 -227.927154) (xy 110.485621 -227.896628)
			(xy 110.448898 -227.859905) (xy 110.418372 -227.817889) (xy 110.394794 -227.771615) (xy 110.378746 -227.722222)
			(xy 110.370621 -227.670927) (xy 110.090711 -227.670927) (xy 110.082586 -227.722222) (xy 110.066538 -227.771615)
			(xy 110.04296 -227.817889) (xy 110.012434 -227.859905) (xy 109.975711 -227.896628) (xy 109.933695 -227.927154)
			(xy 109.887421 -227.950732) (xy 109.838028 -227.96678) (xy 109.786733 -227.974905) (xy 109.734799 -227.974905)
			(xy 109.683504 -227.96678) (xy 109.634111 -227.950732) (xy 109.587837 -227.927154) (xy 109.545821 -227.896628)
			(xy 109.509098 -227.859905) (xy 109.478572 -227.817889) (xy 109.454994 -227.771615) (xy 109.438946 -227.722222)
			(xy 109.430821 -227.670927) (xy 109.150911 -227.670927) (xy 109.142786 -227.722222) (xy 109.126738 -227.771615)
			(xy 109.10316 -227.817889) (xy 109.072634 -227.859905) (xy 109.035911 -227.896628) (xy 108.993895 -227.927154)
			(xy 108.947621 -227.950732) (xy 108.898228 -227.96678) (xy 108.846933 -227.974905) (xy 108.794999 -227.974905)
			(xy 108.743704 -227.96678) (xy 108.694311 -227.950732) (xy 108.648037 -227.927154) (xy 108.606021 -227.896628)
			(xy 108.569298 -227.859905) (xy 108.538772 -227.817889) (xy 108.515194 -227.771615) (xy 108.499146 -227.722222)
			(xy 108.491021 -227.670927) (xy 108.211111 -227.670927) (xy 108.202986 -227.722222) (xy 108.186938 -227.771615)
			(xy 108.16336 -227.817889) (xy 108.132834 -227.859905) (xy 108.096111 -227.896628) (xy 108.054095 -227.927154)
			(xy 108.007821 -227.950732) (xy 107.958428 -227.96678) (xy 107.907133 -227.974905) (xy 107.855199 -227.974905)
			(xy 107.803904 -227.96678) (xy 107.754511 -227.950732) (xy 107.708237 -227.927154) (xy 107.666221 -227.896628)
			(xy 107.629498 -227.859905) (xy 107.598972 -227.817889) (xy 107.575394 -227.771615) (xy 107.559346 -227.722222)
			(xy 107.551221 -227.670927) (xy 107.271311 -227.670927) (xy 107.263186 -227.722222) (xy 107.247138 -227.771615)
			(xy 107.22356 -227.817889) (xy 107.193034 -227.859905) (xy 107.156311 -227.896628) (xy 107.114295 -227.927154)
			(xy 107.068021 -227.950732) (xy 107.018628 -227.96678) (xy 106.967333 -227.974905) (xy 106.915399 -227.974905)
			(xy 106.864104 -227.96678) (xy 106.814711 -227.950732) (xy 106.768437 -227.927154) (xy 106.726421 -227.896628)
			(xy 106.689698 -227.859905) (xy 106.659172 -227.817889) (xy 106.635594 -227.771615) (xy 106.619546 -227.722222)
			(xy 106.611421 -227.670927) (xy 106.331511 -227.670927) (xy 106.323386 -227.722222) (xy 106.307338 -227.771615)
			(xy 106.28376 -227.817889) (xy 106.253234 -227.859905) (xy 106.216511 -227.896628) (xy 106.174495 -227.927154)
			(xy 106.128221 -227.950732) (xy 106.078828 -227.96678) (xy 106.027533 -227.974905) (xy 105.975599 -227.974905)
			(xy 105.924304 -227.96678) (xy 105.874911 -227.950732) (xy 105.828637 -227.927154) (xy 105.786621 -227.896628)
			(xy 105.749898 -227.859905) (xy 105.719372 -227.817889) (xy 105.695794 -227.771615) (xy 105.679746 -227.722222)
			(xy 105.671621 -227.670927) (xy 105.391711 -227.670927) (xy 105.383586 -227.722222) (xy 105.367538 -227.771615)
			(xy 105.34396 -227.817889) (xy 105.313434 -227.859905) (xy 105.276711 -227.896628) (xy 105.234695 -227.927154)
			(xy 105.188421 -227.950732) (xy 105.139028 -227.96678) (xy 105.087733 -227.974905) (xy 105.035799 -227.974905)
			(xy 104.984504 -227.96678) (xy 104.935111 -227.950732) (xy 104.888837 -227.927154) (xy 104.846821 -227.896628)
			(xy 104.810098 -227.859905) (xy 104.779572 -227.817889) (xy 104.755994 -227.771615) (xy 104.739946 -227.722222)
			(xy 104.731821 -227.670927) (xy 104.451911 -227.670927) (xy 104.443786 -227.722222) (xy 104.427738 -227.771615)
			(xy 104.40416 -227.817889) (xy 104.373634 -227.859905) (xy 104.336911 -227.896628) (xy 104.294895 -227.927154)
			(xy 104.248621 -227.950732) (xy 104.199228 -227.96678) (xy 104.147933 -227.974905) (xy 104.095999 -227.974905)
			(xy 104.044704 -227.96678) (xy 103.995311 -227.950732) (xy 103.949037 -227.927154) (xy 103.907021 -227.896628)
			(xy 103.870298 -227.859905) (xy 103.839772 -227.817889) (xy 103.816194 -227.771615) (xy 103.800146 -227.722222)
			(xy 103.792021 -227.670927) (xy 103.512111 -227.670927) (xy 103.503986 -227.722222) (xy 103.487938 -227.771615)
			(xy 103.46436 -227.817889) (xy 103.433834 -227.859905) (xy 103.397111 -227.896628) (xy 103.355095 -227.927154)
			(xy 103.308821 -227.950732) (xy 103.259428 -227.96678) (xy 103.208133 -227.974905) (xy 103.156199 -227.974905)
			(xy 103.104904 -227.96678) (xy 103.055511 -227.950732) (xy 103.009237 -227.927154) (xy 102.967221 -227.896628)
			(xy 102.930498 -227.859905) (xy 102.899972 -227.817889) (xy 102.876394 -227.771615) (xy 102.860346 -227.722222)
			(xy 102.852221 -227.670927) (xy 102.572311 -227.670927) (xy 102.564186 -227.722222) (xy 102.548138 -227.771615)
			(xy 102.52456 -227.817889) (xy 102.494034 -227.859905) (xy 102.457311 -227.896628) (xy 102.415295 -227.927154)
			(xy 102.369021 -227.950732) (xy 102.319628 -227.96678) (xy 102.268333 -227.974905) (xy 102.216399 -227.974905)
			(xy 102.165104 -227.96678) (xy 102.115711 -227.950732) (xy 102.069437 -227.927154) (xy 102.027421 -227.896628)
			(xy 101.990698 -227.859905) (xy 101.960172 -227.817889) (xy 101.936594 -227.771615) (xy 101.920546 -227.722222)
			(xy 101.912421 -227.670927) (xy 101.632511 -227.670927) (xy 101.624386 -227.722222) (xy 101.608338 -227.771615)
			(xy 101.58476 -227.817889) (xy 101.554234 -227.859905) (xy 101.517511 -227.896628) (xy 101.475495 -227.927154)
			(xy 101.429221 -227.950732) (xy 101.379828 -227.96678) (xy 101.328533 -227.974905) (xy 101.276599 -227.974905)
			(xy 101.225304 -227.96678) (xy 101.175911 -227.950732) (xy 101.129637 -227.927154) (xy 101.087621 -227.896628)
			(xy 101.050898 -227.859905) (xy 101.020372 -227.817889) (xy 100.996794 -227.771615) (xy 100.980746 -227.722222)
			(xy 100.972621 -227.670927) (xy 100.692711 -227.670927) (xy 100.684586 -227.722222) (xy 100.668538 -227.771615)
			(xy 100.64496 -227.817889) (xy 100.614434 -227.859905) (xy 100.577711 -227.896628) (xy 100.535695 -227.927154)
			(xy 100.489421 -227.950732) (xy 100.440028 -227.96678) (xy 100.388733 -227.974905) (xy 100.336799 -227.974905)
			(xy 100.285504 -227.96678) (xy 100.236111 -227.950732) (xy 100.189837 -227.927154) (xy 100.147821 -227.896628)
			(xy 100.111098 -227.859905) (xy 100.080572 -227.817889) (xy 100.056994 -227.771615) (xy 100.040946 -227.722222)
			(xy 100.032821 -227.670927) (xy 99.752657 -227.670927) (xy 99.744532 -227.722222) (xy 99.728484 -227.771615)
			(xy 99.704906 -227.817889) (xy 99.67438 -227.859905) (xy 99.637657 -227.896628) (xy 99.595641 -227.927154)
			(xy 99.549367 -227.950732) (xy 99.499974 -227.96678) (xy 99.448679 -227.974905) (xy 99.396745 -227.974905)
			(xy 99.34545 -227.96678) (xy 99.296057 -227.950732) (xy 99.249783 -227.927154) (xy 99.207767 -227.896628)
			(xy 99.171044 -227.859905) (xy 99.140518 -227.817889) (xy 99.11694 -227.771615) (xy 99.100892 -227.722222)
			(xy 99.092767 -227.670927) (xy 98.813111 -227.670927) (xy 98.804986 -227.722222) (xy 98.788938 -227.771615)
			(xy 98.76536 -227.817889) (xy 98.734834 -227.859905) (xy 98.698111 -227.896628) (xy 98.656095 -227.927154)
			(xy 98.609821 -227.950732) (xy 98.560428 -227.96678) (xy 98.509133 -227.974905) (xy 98.457199 -227.974905)
			(xy 98.405904 -227.96678) (xy 98.356511 -227.950732) (xy 98.310237 -227.927154) (xy 98.268221 -227.896628)
			(xy 98.231498 -227.859905) (xy 98.200972 -227.817889) (xy 98.177394 -227.771615) (xy 98.161346 -227.722222)
			(xy 98.153221 -227.670927) (xy 97.873311 -227.670927) (xy 97.865186 -227.722222) (xy 97.849138 -227.771615)
			(xy 97.82556 -227.817889) (xy 97.795034 -227.859905) (xy 97.758311 -227.896628) (xy 97.716295 -227.927154)
			(xy 97.670021 -227.950732) (xy 97.620628 -227.96678) (xy 97.569333 -227.974905) (xy 97.517399 -227.974905)
			(xy 97.466104 -227.96678) (xy 97.416711 -227.950732) (xy 97.370437 -227.927154) (xy 97.328421 -227.896628)
			(xy 97.291698 -227.859905) (xy 97.261172 -227.817889) (xy 97.237594 -227.771615) (xy 97.221546 -227.722222)
			(xy 97.213421 -227.670927) (xy 96.933511 -227.670927) (xy 96.925386 -227.722222) (xy 96.909338 -227.771615)
			(xy 96.88576 -227.817889) (xy 96.855234 -227.859905) (xy 96.818511 -227.896628) (xy 96.776495 -227.927154)
			(xy 96.730221 -227.950732) (xy 96.680828 -227.96678) (xy 96.629533 -227.974905) (xy 96.577599 -227.974905)
			(xy 96.526304 -227.96678) (xy 96.476911 -227.950732) (xy 96.430637 -227.927154) (xy 96.388621 -227.896628)
			(xy 96.351898 -227.859905) (xy 96.321372 -227.817889) (xy 96.297794 -227.771615) (xy 96.281746 -227.722222)
			(xy 96.273621 -227.670927) (xy 95.993711 -227.670927) (xy 95.985586 -227.722222) (xy 95.969538 -227.771615)
			(xy 95.94596 -227.817889) (xy 95.915434 -227.859905) (xy 95.878711 -227.896628) (xy 95.836695 -227.927154)
			(xy 95.790421 -227.950732) (xy 95.741028 -227.96678) (xy 95.689733 -227.974905) (xy 95.637799 -227.974905)
			(xy 95.586504 -227.96678) (xy 95.537111 -227.950732) (xy 95.490837 -227.927154) (xy 95.448821 -227.896628)
			(xy 95.412098 -227.859905) (xy 95.381572 -227.817889) (xy 95.357994 -227.771615) (xy 95.341946 -227.722222)
			(xy 95.333821 -227.670927) (xy 95.053911 -227.670927) (xy 95.045786 -227.722222) (xy 95.029738 -227.771615)
			(xy 95.00616 -227.817889) (xy 94.975634 -227.859905) (xy 94.938911 -227.896628) (xy 94.896895 -227.927154)
			(xy 94.850621 -227.950732) (xy 94.801228 -227.96678) (xy 94.749933 -227.974905) (xy 94.697999 -227.974905)
			(xy 94.646704 -227.96678) (xy 94.597311 -227.950732) (xy 94.551037 -227.927154) (xy 94.509021 -227.896628)
			(xy 94.472298 -227.859905) (xy 94.441772 -227.817889) (xy 94.418194 -227.771615) (xy 94.402146 -227.722222)
			(xy 94.394021 -227.670927) (xy 94.114111 -227.670927) (xy 94.105986 -227.722222) (xy 94.089938 -227.771615)
			(xy 94.06636 -227.817889) (xy 94.035834 -227.859905) (xy 93.999111 -227.896628) (xy 93.957095 -227.927154)
			(xy 93.910821 -227.950732) (xy 93.861428 -227.96678) (xy 93.810133 -227.974905) (xy 93.758199 -227.974905)
			(xy 93.706904 -227.96678) (xy 93.657511 -227.950732) (xy 93.611237 -227.927154) (xy 93.569221 -227.896628)
			(xy 93.532498 -227.859905) (xy 93.501972 -227.817889) (xy 93.478394 -227.771615) (xy 93.462346 -227.722222)
			(xy 93.454221 -227.670927) (xy 93.174311 -227.670927) (xy 93.166186 -227.722222) (xy 93.150138 -227.771615)
			(xy 93.12656 -227.817889) (xy 93.096034 -227.859905) (xy 93.059311 -227.896628) (xy 93.017295 -227.927154)
			(xy 92.971021 -227.950732) (xy 92.921628 -227.96678) (xy 92.870333 -227.974905) (xy 92.818399 -227.974905)
			(xy 92.767104 -227.96678) (xy 92.717711 -227.950732) (xy 92.671437 -227.927154) (xy 92.629421 -227.896628)
			(xy 92.592698 -227.859905) (xy 92.562172 -227.817889) (xy 92.538594 -227.771615) (xy 92.522546 -227.722222)
			(xy 92.514421 -227.670927) (xy 92.234538 -227.670927) (xy 92.234538 -227.67099) (xy 92.226407 -227.722329)
			(xy 92.210345 -227.771765) (xy 92.186747 -227.818079) (xy 92.156195 -227.860132) (xy 92.119441 -227.896887)
			(xy 92.077389 -227.927441) (xy 92.031076 -227.95104) (xy 91.981641 -227.967104) (xy 91.930302 -227.975237)
			(xy 91.904312 -227.975668) (xy 91.87743 -227.975146) (xy 91.824372 -227.966466) (xy 91.773413 -227.949332)
			(xy 91.725889 -227.924193) (xy 91.70416 -227.908358) (xy 91.69781 -227.903532) (xy 91.666568 -227.89261)
			(xy 91.661816 -227.892724) (xy 91.652484 -227.894517) (xy 91.648026 -227.896166) (xy 91.562682 -227.937314)
			(xy 91.554666 -227.941824) (xy 91.542325 -227.955441) (xy 91.535688 -227.972577) (xy 91.53525 -227.981764)
			(xy 91.53525 -228.109272) (xy 91.565222 -228.154738) (xy 91.577922 -228.160834) (xy 91.601625 -228.172805)
			(xy 91.6452 -228.203146) (xy 91.683369 -228.240058) (xy 91.71515 -228.282593) (xy 91.739729 -228.32966)
			(xy 91.756474 -228.380048) (xy 91.764954 -228.432464) (xy 91.764952 -228.484997) (xy 92.044267 -228.484997)
			(xy 92.044267 -228.433063) (xy 92.052392 -228.381768) (xy 92.06844 -228.332375) (xy 92.092018 -228.286101)
			(xy 92.122544 -228.244085) (xy 92.159267 -228.207362) (xy 92.201283 -228.176836) (xy 92.247557 -228.153258)
			(xy 92.29695 -228.13721) (xy 92.348245 -228.129085) (xy 92.400179 -228.129085) (xy 92.451474 -228.13721)
			(xy 92.500867 -228.153258) (xy 92.547141 -228.176836) (xy 92.589157 -228.207362) (xy 92.62588 -228.244085)
			(xy 92.656406 -228.286101) (xy 92.679984 -228.332375) (xy 92.696032 -228.381768) (xy 92.704157 -228.433063)
			(xy 92.704666 -228.45903) (xy 92.704157 -228.484997) (xy 92.984067 -228.484997) (xy 92.984067 -228.433063)
			(xy 92.992192 -228.381768) (xy 93.00824 -228.332375) (xy 93.031818 -228.286101) (xy 93.062344 -228.244085)
			(xy 93.099067 -228.207362) (xy 93.141083 -228.176836) (xy 93.187357 -228.153258) (xy 93.23675 -228.13721)
			(xy 93.288045 -228.129085) (xy 93.339979 -228.129085) (xy 93.391274 -228.13721) (xy 93.440667 -228.153258)
			(xy 93.486941 -228.176836) (xy 93.528957 -228.207362) (xy 93.56568 -228.244085) (xy 93.596206 -228.286101)
			(xy 93.619784 -228.332375) (xy 93.635832 -228.381768) (xy 93.643957 -228.433063) (xy 93.644466 -228.45903)
			(xy 93.643957 -228.484997) (xy 93.923867 -228.484997) (xy 93.923867 -228.433063) (xy 93.931992 -228.381768)
			(xy 93.94804 -228.332375) (xy 93.971618 -228.286101) (xy 94.002144 -228.244085) (xy 94.038867 -228.207362)
			(xy 94.080883 -228.176836) (xy 94.127157 -228.153258) (xy 94.17655 -228.13721) (xy 94.227845 -228.129085)
			(xy 94.279779 -228.129085) (xy 94.331074 -228.13721) (xy 94.380467 -228.153258) (xy 94.426741 -228.176836)
			(xy 94.468757 -228.207362) (xy 94.50548 -228.244085) (xy 94.536006 -228.286101) (xy 94.559584 -228.332375)
			(xy 94.575632 -228.381768) (xy 94.583757 -228.433063) (xy 94.584266 -228.45903) (xy 94.583757 -228.484997)
			(xy 94.863667 -228.484997) (xy 94.863667 -228.433063) (xy 94.871792 -228.381768) (xy 94.88784 -228.332375)
			(xy 94.911418 -228.286101) (xy 94.941944 -228.244085) (xy 94.978667 -228.207362) (xy 95.020683 -228.176836)
			(xy 95.066957 -228.153258) (xy 95.11635 -228.13721) (xy 95.167645 -228.129085) (xy 95.219579 -228.129085)
			(xy 95.270874 -228.13721) (xy 95.320267 -228.153258) (xy 95.366541 -228.176836) (xy 95.408557 -228.207362)
			(xy 95.44528 -228.244085) (xy 95.475806 -228.286101) (xy 95.499384 -228.332375) (xy 95.515432 -228.381768)
			(xy 95.523557 -228.433063) (xy 95.524066 -228.45903) (xy 95.523557 -228.484997) (xy 95.803467 -228.484997)
			(xy 95.803467 -228.433063) (xy 95.811592 -228.381768) (xy 95.82764 -228.332375) (xy 95.851218 -228.286101)
			(xy 95.881744 -228.244085) (xy 95.918467 -228.207362) (xy 95.960483 -228.176836) (xy 96.006757 -228.153258)
			(xy 96.05615 -228.13721) (xy 96.107445 -228.129085) (xy 96.159379 -228.129085) (xy 96.210674 -228.13721)
			(xy 96.260067 -228.153258) (xy 96.306341 -228.176836) (xy 96.348357 -228.207362) (xy 96.38508 -228.244085)
			(xy 96.415606 -228.286101) (xy 96.439184 -228.332375) (xy 96.455232 -228.381768) (xy 96.463357 -228.433063)
			(xy 96.463866 -228.45903) (xy 96.463357 -228.484997) (xy 96.743267 -228.484997) (xy 96.743267 -228.433063)
			(xy 96.751392 -228.381768) (xy 96.76744 -228.332375) (xy 96.791018 -228.286101) (xy 96.821544 -228.244085)
			(xy 96.858267 -228.207362) (xy 96.900283 -228.176836) (xy 96.946557 -228.153258) (xy 96.99595 -228.13721)
			(xy 97.047245 -228.129085) (xy 97.099179 -228.129085) (xy 97.150474 -228.13721) (xy 97.199867 -228.153258)
			(xy 97.246141 -228.176836) (xy 97.288157 -228.207362) (xy 97.32488 -228.244085) (xy 97.355406 -228.286101)
			(xy 97.378984 -228.332375) (xy 97.395032 -228.381768) (xy 97.403157 -228.433063) (xy 97.403666 -228.45903)
			(xy 97.403157 -228.484997) (xy 97.683321 -228.484997) (xy 97.683321 -228.433063) (xy 97.691446 -228.381768)
			(xy 97.707494 -228.332375) (xy 97.731072 -228.286101) (xy 97.761598 -228.244085) (xy 97.798321 -228.207362)
			(xy 97.840337 -228.176836) (xy 97.886611 -228.153258) (xy 97.936004 -228.13721) (xy 97.987299 -228.129085)
			(xy 98.039233 -228.129085) (xy 98.090528 -228.13721) (xy 98.139921 -228.153258) (xy 98.186195 -228.176836)
			(xy 98.228211 -228.207362) (xy 98.264934 -228.244085) (xy 98.29546 -228.286101) (xy 98.319038 -228.332375)
			(xy 98.335086 -228.381768) (xy 98.343211 -228.433063) (xy 98.34372 -228.45903) (xy 98.343211 -228.484997)
			(xy 98.622867 -228.484997) (xy 98.622867 -228.433063) (xy 98.630992 -228.381768) (xy 98.64704 -228.332375)
			(xy 98.670618 -228.286101) (xy 98.701144 -228.244085) (xy 98.737867 -228.207362) (xy 98.779883 -228.176836)
			(xy 98.826157 -228.153258) (xy 98.87555 -228.13721) (xy 98.926845 -228.129085) (xy 98.978779 -228.129085)
			(xy 99.030074 -228.13721) (xy 99.079467 -228.153258) (xy 99.125741 -228.176836) (xy 99.167757 -228.207362)
			(xy 99.20448 -228.244085) (xy 99.235006 -228.286101) (xy 99.258584 -228.332375) (xy 99.274632 -228.381768)
			(xy 99.282757 -228.433063) (xy 99.283266 -228.45903) (xy 99.282757 -228.484997) (xy 99.562667 -228.484997)
			(xy 99.562667 -228.433063) (xy 99.570792 -228.381768) (xy 99.58684 -228.332375) (xy 99.610418 -228.286101)
			(xy 99.640944 -228.244085) (xy 99.677667 -228.207362) (xy 99.719683 -228.176836) (xy 99.765957 -228.153258)
			(xy 99.81535 -228.13721) (xy 99.866645 -228.129085) (xy 99.918579 -228.129085) (xy 99.969874 -228.13721)
			(xy 100.019267 -228.153258) (xy 100.065541 -228.176836) (xy 100.107557 -228.207362) (xy 100.14428 -228.244085)
			(xy 100.174806 -228.286101) (xy 100.198384 -228.332375) (xy 100.214432 -228.381768) (xy 100.222557 -228.433063)
			(xy 100.223066 -228.45903) (xy 100.222557 -228.484997) (xy 100.502467 -228.484997) (xy 100.502467 -228.433063)
			(xy 100.510592 -228.381768) (xy 100.52664 -228.332375) (xy 100.550218 -228.286101) (xy 100.580744 -228.244085)
			(xy 100.617467 -228.207362) (xy 100.659483 -228.176836) (xy 100.705757 -228.153258) (xy 100.75515 -228.13721)
			(xy 100.806445 -228.129085) (xy 100.858379 -228.129085) (xy 100.909674 -228.13721) (xy 100.959067 -228.153258)
			(xy 101.005341 -228.176836) (xy 101.047357 -228.207362) (xy 101.08408 -228.244085) (xy 101.114606 -228.286101)
			(xy 101.138184 -228.332375) (xy 101.154232 -228.381768) (xy 101.162357 -228.433063) (xy 101.162866 -228.45903)
			(xy 101.162357 -228.484997) (xy 101.442267 -228.484997) (xy 101.442267 -228.433063) (xy 101.450392 -228.381768)
			(xy 101.46644 -228.332375) (xy 101.490018 -228.286101) (xy 101.520544 -228.244085) (xy 101.557267 -228.207362)
			(xy 101.599283 -228.176836) (xy 101.645557 -228.153258) (xy 101.69495 -228.13721) (xy 101.746245 -228.129085)
			(xy 101.798179 -228.129085) (xy 101.849474 -228.13721) (xy 101.898867 -228.153258) (xy 101.945141 -228.176836)
			(xy 101.987157 -228.207362) (xy 102.02388 -228.244085) (xy 102.054406 -228.286101) (xy 102.077984 -228.332375)
			(xy 102.094032 -228.381768) (xy 102.102157 -228.433063) (xy 102.102666 -228.45903) (xy 102.102157 -228.484997)
			(xy 102.382067 -228.484997) (xy 102.382067 -228.433063) (xy 102.390192 -228.381768) (xy 102.40624 -228.332375)
			(xy 102.429818 -228.286101) (xy 102.460344 -228.244085) (xy 102.497067 -228.207362) (xy 102.539083 -228.176836)
			(xy 102.585357 -228.153258) (xy 102.63475 -228.13721) (xy 102.686045 -228.129085) (xy 102.737979 -228.129085)
			(xy 102.789274 -228.13721) (xy 102.838667 -228.153258) (xy 102.884941 -228.176836) (xy 102.926957 -228.207362)
			(xy 102.96368 -228.244085) (xy 102.994206 -228.286101) (xy 103.017784 -228.332375) (xy 103.033832 -228.381768)
			(xy 103.041957 -228.433063) (xy 103.042466 -228.45903) (xy 103.041957 -228.484997) (xy 103.321867 -228.484997)
			(xy 103.321867 -228.433063) (xy 103.329992 -228.381768) (xy 103.34604 -228.332375) (xy 103.369618 -228.286101)
			(xy 103.400144 -228.244085) (xy 103.436867 -228.207362) (xy 103.478883 -228.176836) (xy 103.525157 -228.153258)
			(xy 103.57455 -228.13721) (xy 103.625845 -228.129085) (xy 103.677779 -228.129085) (xy 103.729074 -228.13721)
			(xy 103.778467 -228.153258) (xy 103.824741 -228.176836) (xy 103.866757 -228.207362) (xy 103.90348 -228.244085)
			(xy 103.934006 -228.286101) (xy 103.957584 -228.332375) (xy 103.973632 -228.381768) (xy 103.981757 -228.433063)
			(xy 103.982266 -228.45903) (xy 103.981757 -228.484997) (xy 104.261667 -228.484997) (xy 104.261667 -228.433063)
			(xy 104.269792 -228.381768) (xy 104.28584 -228.332375) (xy 104.309418 -228.286101) (xy 104.339944 -228.244085)
			(xy 104.376667 -228.207362) (xy 104.418683 -228.176836) (xy 104.464957 -228.153258) (xy 104.51435 -228.13721)
			(xy 104.565645 -228.129085) (xy 104.617579 -228.129085) (xy 104.668874 -228.13721) (xy 104.718267 -228.153258)
			(xy 104.764541 -228.176836) (xy 104.806557 -228.207362) (xy 104.84328 -228.244085) (xy 104.873806 -228.286101)
			(xy 104.897384 -228.332375) (xy 104.913432 -228.381768) (xy 104.921557 -228.433063) (xy 104.922066 -228.45903)
			(xy 104.921557 -228.484997) (xy 105.201467 -228.484997) (xy 105.201467 -228.433063) (xy 105.209592 -228.381768)
			(xy 105.22564 -228.332375) (xy 105.249218 -228.286101) (xy 105.279744 -228.244085) (xy 105.316467 -228.207362)
			(xy 105.358483 -228.176836) (xy 105.404757 -228.153258) (xy 105.45415 -228.13721) (xy 105.505445 -228.129085)
			(xy 105.557379 -228.129085) (xy 105.608674 -228.13721) (xy 105.658067 -228.153258) (xy 105.704341 -228.176836)
			(xy 105.746357 -228.207362) (xy 105.78308 -228.244085) (xy 105.813606 -228.286101) (xy 105.837184 -228.332375)
			(xy 105.853232 -228.381768) (xy 105.861357 -228.433063) (xy 105.861866 -228.45903) (xy 105.861357 -228.484997)
			(xy 106.141267 -228.484997) (xy 106.141267 -228.433063) (xy 106.149392 -228.381768) (xy 106.16544 -228.332375)
			(xy 106.189018 -228.286101) (xy 106.219544 -228.244085) (xy 106.256267 -228.207362) (xy 106.298283 -228.176836)
			(xy 106.344557 -228.153258) (xy 106.39395 -228.13721) (xy 106.445245 -228.129085) (xy 106.497179 -228.129085)
			(xy 106.548474 -228.13721) (xy 106.597867 -228.153258) (xy 106.644141 -228.176836) (xy 106.686157 -228.207362)
			(xy 106.72288 -228.244085) (xy 106.753406 -228.286101) (xy 106.776984 -228.332375) (xy 106.793032 -228.381768)
			(xy 106.801157 -228.433063) (xy 106.801666 -228.45903) (xy 106.801157 -228.484997) (xy 107.081067 -228.484997)
			(xy 107.081067 -228.433063) (xy 107.089192 -228.381768) (xy 107.10524 -228.332375) (xy 107.128818 -228.286101)
			(xy 107.159344 -228.244085) (xy 107.196067 -228.207362) (xy 107.238083 -228.176836) (xy 107.284357 -228.153258)
			(xy 107.33375 -228.13721) (xy 107.385045 -228.129085) (xy 107.436979 -228.129085) (xy 107.488274 -228.13721)
			(xy 107.537667 -228.153258) (xy 107.583941 -228.176836) (xy 107.625957 -228.207362) (xy 107.66268 -228.244085)
			(xy 107.693206 -228.286101) (xy 107.716784 -228.332375) (xy 107.732832 -228.381768) (xy 107.740957 -228.433063)
			(xy 107.741466 -228.45903) (xy 107.740957 -228.484997) (xy 108.020867 -228.484997) (xy 108.020867 -228.433063)
			(xy 108.028992 -228.381768) (xy 108.04504 -228.332375) (xy 108.068618 -228.286101) (xy 108.099144 -228.244085)
			(xy 108.135867 -228.207362) (xy 108.177883 -228.176836) (xy 108.224157 -228.153258) (xy 108.27355 -228.13721)
			(xy 108.324845 -228.129085) (xy 108.376779 -228.129085) (xy 108.428074 -228.13721) (xy 108.477467 -228.153258)
			(xy 108.523741 -228.176836) (xy 108.565757 -228.207362) (xy 108.60248 -228.244085) (xy 108.633006 -228.286101)
			(xy 108.656584 -228.332375) (xy 108.672632 -228.381768) (xy 108.680757 -228.433063) (xy 108.681266 -228.45903)
			(xy 108.680757 -228.484997) (xy 108.960667 -228.484997) (xy 108.960667 -228.433063) (xy 108.968792 -228.381768)
			(xy 108.98484 -228.332375) (xy 109.008418 -228.286101) (xy 109.038944 -228.244085) (xy 109.075667 -228.207362)
			(xy 109.117683 -228.176836) (xy 109.163957 -228.153258) (xy 109.21335 -228.13721) (xy 109.264645 -228.129085)
			(xy 109.316579 -228.129085) (xy 109.367874 -228.13721) (xy 109.417267 -228.153258) (xy 109.463541 -228.176836)
			(xy 109.505557 -228.207362) (xy 109.54228 -228.244085) (xy 109.572806 -228.286101) (xy 109.596384 -228.332375)
			(xy 109.612432 -228.381768) (xy 109.620557 -228.433063) (xy 109.621066 -228.45903) (xy 109.620557 -228.484997)
			(xy 109.900467 -228.484997) (xy 109.900467 -228.433063) (xy 109.908592 -228.381768) (xy 109.92464 -228.332375)
			(xy 109.948218 -228.286101) (xy 109.978744 -228.244085) (xy 110.015467 -228.207362) (xy 110.057483 -228.176836)
			(xy 110.103757 -228.153258) (xy 110.15315 -228.13721) (xy 110.204445 -228.129085) (xy 110.256379 -228.129085)
			(xy 110.307674 -228.13721) (xy 110.357067 -228.153258) (xy 110.403341 -228.176836) (xy 110.445357 -228.207362)
			(xy 110.48208 -228.244085) (xy 110.512606 -228.286101) (xy 110.536184 -228.332375) (xy 110.552232 -228.381768)
			(xy 110.560357 -228.433063) (xy 110.560866 -228.45903) (xy 110.560357 -228.484997) (xy 110.840521 -228.484997)
			(xy 110.840521 -228.433063) (xy 110.848646 -228.381768) (xy 110.864694 -228.332375) (xy 110.888272 -228.286101)
			(xy 110.918798 -228.244085) (xy 110.955521 -228.207362) (xy 110.997537 -228.176836) (xy 111.043811 -228.153258)
			(xy 111.093204 -228.13721) (xy 111.144499 -228.129085) (xy 111.196433 -228.129085) (xy 111.247728 -228.13721)
			(xy 111.297121 -228.153258) (xy 111.343395 -228.176836) (xy 111.385411 -228.207362) (xy 111.422134 -228.244085)
			(xy 111.45266 -228.286101) (xy 111.476238 -228.332375) (xy 111.492286 -228.381768) (xy 111.500411 -228.433063)
			(xy 111.50092 -228.45903) (xy 111.500411 -228.484997) (xy 111.780067 -228.484997) (xy 111.780067 -228.433063)
			(xy 111.788192 -228.381768) (xy 111.80424 -228.332375) (xy 111.827818 -228.286101) (xy 111.858344 -228.244085)
			(xy 111.895067 -228.207362) (xy 111.937083 -228.176836) (xy 111.983357 -228.153258) (xy 112.03275 -228.13721)
			(xy 112.084045 -228.129085) (xy 112.135979 -228.129085) (xy 112.187274 -228.13721) (xy 112.236667 -228.153258)
			(xy 112.282941 -228.176836) (xy 112.324957 -228.207362) (xy 112.36168 -228.244085) (xy 112.392206 -228.286101)
			(xy 112.415784 -228.332375) (xy 112.431832 -228.381768) (xy 112.439957 -228.433063) (xy 112.440466 -228.45903)
			(xy 112.439957 -228.484997) (xy 112.719867 -228.484997) (xy 112.719867 -228.433063) (xy 112.727992 -228.381768)
			(xy 112.74404 -228.332375) (xy 112.767618 -228.286101) (xy 112.798144 -228.244085) (xy 112.834867 -228.207362)
			(xy 112.876883 -228.176836) (xy 112.923157 -228.153258) (xy 112.97255 -228.13721) (xy 113.023845 -228.129085)
			(xy 113.075779 -228.129085) (xy 113.127074 -228.13721) (xy 113.176467 -228.153258) (xy 113.222741 -228.176836)
			(xy 113.264757 -228.207362) (xy 113.30148 -228.244085) (xy 113.332006 -228.286101) (xy 113.355584 -228.332375)
			(xy 113.371632 -228.381768) (xy 113.379757 -228.433063) (xy 113.380266 -228.45903) (xy 113.379757 -228.484997)
			(xy 113.659667 -228.484997) (xy 113.659667 -228.433063) (xy 113.667792 -228.381768) (xy 113.68384 -228.332375)
			(xy 113.707418 -228.286101) (xy 113.737944 -228.244085) (xy 113.774667 -228.207362) (xy 113.816683 -228.176836)
			(xy 113.862957 -228.153258) (xy 113.91235 -228.13721) (xy 113.963645 -228.129085) (xy 114.015579 -228.129085)
			(xy 114.066874 -228.13721) (xy 114.116267 -228.153258) (xy 114.162541 -228.176836) (xy 114.204557 -228.207362)
			(xy 114.24128 -228.244085) (xy 114.271806 -228.286101) (xy 114.295384 -228.332375) (xy 114.311432 -228.381768)
			(xy 114.319557 -228.433063) (xy 114.320066 -228.45903) (xy 114.319557 -228.484997) (xy 114.599467 -228.484997)
			(xy 114.599467 -228.433063) (xy 114.607592 -228.381768) (xy 114.62364 -228.332375) (xy 114.647218 -228.286101)
			(xy 114.677744 -228.244085) (xy 114.714467 -228.207362) (xy 114.756483 -228.176836) (xy 114.802757 -228.153258)
			(xy 114.85215 -228.13721) (xy 114.903445 -228.129085) (xy 114.955379 -228.129085) (xy 115.006674 -228.13721)
			(xy 115.056067 -228.153258) (xy 115.102341 -228.176836) (xy 115.144357 -228.207362) (xy 115.18108 -228.244085)
			(xy 115.211606 -228.286101) (xy 115.235184 -228.332375) (xy 115.251232 -228.381768) (xy 115.259357 -228.433063)
			(xy 115.259866 -228.45903) (xy 115.259357 -228.484997) (xy 115.539267 -228.484997) (xy 115.539267 -228.433063)
			(xy 115.547392 -228.381768) (xy 115.56344 -228.332375) (xy 115.587018 -228.286101) (xy 115.617544 -228.244085)
			(xy 115.654267 -228.207362) (xy 115.696283 -228.176836) (xy 115.742557 -228.153258) (xy 115.79195 -228.13721)
			(xy 115.843245 -228.129085) (xy 115.895179 -228.129085) (xy 115.946474 -228.13721) (xy 115.995867 -228.153258)
			(xy 116.042141 -228.176836) (xy 116.084157 -228.207362) (xy 116.12088 -228.244085) (xy 116.151406 -228.286101)
			(xy 116.174984 -228.332375) (xy 116.191032 -228.381768) (xy 116.199157 -228.433063) (xy 116.199666 -228.45903)
			(xy 116.199157 -228.484997) (xy 116.479067 -228.484997) (xy 116.479067 -228.433063) (xy 116.487192 -228.381768)
			(xy 116.50324 -228.332375) (xy 116.526818 -228.286101) (xy 116.557344 -228.244085) (xy 116.594067 -228.207362)
			(xy 116.636083 -228.176836) (xy 116.682357 -228.153258) (xy 116.73175 -228.13721) (xy 116.783045 -228.129085)
			(xy 116.834979 -228.129085) (xy 116.886274 -228.13721) (xy 116.935667 -228.153258) (xy 116.981941 -228.176836)
			(xy 117.023957 -228.207362) (xy 117.06068 -228.244085) (xy 117.091206 -228.286101) (xy 117.114784 -228.332375)
			(xy 117.130832 -228.381768) (xy 117.138957 -228.433063) (xy 117.139466 -228.45903) (xy 117.138957 -228.484997)
			(xy 117.418867 -228.484997) (xy 117.418867 -228.433063) (xy 117.426992 -228.381768) (xy 117.44304 -228.332375)
			(xy 117.466618 -228.286101) (xy 117.497144 -228.244085) (xy 117.533867 -228.207362) (xy 117.575883 -228.176836)
			(xy 117.622157 -228.153258) (xy 117.67155 -228.13721) (xy 117.722845 -228.129085) (xy 117.774779 -228.129085)
			(xy 117.826074 -228.13721) (xy 117.875467 -228.153258) (xy 117.921741 -228.176836) (xy 117.963757 -228.207362)
			(xy 118.00048 -228.244085) (xy 118.031006 -228.286101) (xy 118.054584 -228.332375) (xy 118.070632 -228.381768)
			(xy 118.078757 -228.433063) (xy 118.079266 -228.45903) (xy 118.078757 -228.484997) (xy 118.358667 -228.484997)
			(xy 118.358667 -228.433063) (xy 118.366792 -228.381768) (xy 118.38284 -228.332375) (xy 118.406418 -228.286101)
			(xy 118.436944 -228.244085) (xy 118.473667 -228.207362) (xy 118.515683 -228.176836) (xy 118.561957 -228.153258)
			(xy 118.61135 -228.13721) (xy 118.662645 -228.129085) (xy 118.714579 -228.129085) (xy 118.765874 -228.13721)
			(xy 118.815267 -228.153258) (xy 118.861541 -228.176836) (xy 118.903557 -228.207362) (xy 118.94028 -228.244085)
			(xy 118.970806 -228.286101) (xy 118.994384 -228.332375) (xy 119.010432 -228.381768) (xy 119.018557 -228.433063)
			(xy 119.019066 -228.45903) (xy 119.018557 -228.484997) (xy 119.298467 -228.484997) (xy 119.298467 -228.433063)
			(xy 119.306592 -228.381768) (xy 119.32264 -228.332375) (xy 119.346218 -228.286101) (xy 119.376744 -228.244085)
			(xy 119.413467 -228.207362) (xy 119.455483 -228.176836) (xy 119.501757 -228.153258) (xy 119.55115 -228.13721)
			(xy 119.602445 -228.129085) (xy 119.654379 -228.129085) (xy 119.705674 -228.13721) (xy 119.755067 -228.153258)
			(xy 119.801341 -228.176836) (xy 119.843357 -228.207362) (xy 119.88008 -228.244085) (xy 119.910606 -228.286101)
			(xy 119.934184 -228.332375) (xy 119.950232 -228.381768) (xy 119.958357 -228.433063) (xy 119.958866 -228.45903)
			(xy 119.958357 -228.484997) (xy 120.238267 -228.484997) (xy 120.238267 -228.433063) (xy 120.246392 -228.381768)
			(xy 120.26244 -228.332375) (xy 120.286018 -228.286101) (xy 120.316544 -228.244085) (xy 120.353267 -228.207362)
			(xy 120.395283 -228.176836) (xy 120.441557 -228.153258) (xy 120.49095 -228.13721) (xy 120.542245 -228.129085)
			(xy 120.594179 -228.129085) (xy 120.645474 -228.13721) (xy 120.694867 -228.153258) (xy 120.741141 -228.176836)
			(xy 120.783157 -228.207362) (xy 120.81988 -228.244085) (xy 120.850406 -228.286101) (xy 120.873984 -228.332375)
			(xy 120.890032 -228.381768) (xy 120.898157 -228.433063) (xy 120.898666 -228.45903) (xy 120.898157 -228.484997)
			(xy 121.178067 -228.484997) (xy 121.178067 -228.433063) (xy 121.186192 -228.381768) (xy 121.20224 -228.332375)
			(xy 121.225818 -228.286101) (xy 121.256344 -228.244085) (xy 121.293067 -228.207362) (xy 121.335083 -228.176836)
			(xy 121.381357 -228.153258) (xy 121.43075 -228.13721) (xy 121.482045 -228.129085) (xy 121.533979 -228.129085)
			(xy 121.585274 -228.13721) (xy 121.634667 -228.153258) (xy 121.680941 -228.176836) (xy 121.722957 -228.207362)
			(xy 121.75968 -228.244085) (xy 121.790206 -228.286101) (xy 121.813784 -228.332375) (xy 121.829832 -228.381768)
			(xy 121.837957 -228.433063) (xy 121.838466 -228.45903) (xy 121.837957 -228.484997) (xy 122.117867 -228.484997)
			(xy 122.117867 -228.433063) (xy 122.125992 -228.381768) (xy 122.14204 -228.332375) (xy 122.165618 -228.286101)
			(xy 122.196144 -228.244085) (xy 122.232867 -228.207362) (xy 122.274883 -228.176836) (xy 122.321157 -228.153258)
			(xy 122.37055 -228.13721) (xy 122.421845 -228.129085) (xy 122.473779 -228.129085) (xy 122.525074 -228.13721)
			(xy 122.574467 -228.153258) (xy 122.620741 -228.176836) (xy 122.662757 -228.207362) (xy 122.69948 -228.244085)
			(xy 122.730006 -228.286101) (xy 122.753584 -228.332375) (xy 122.769632 -228.381768) (xy 122.777757 -228.433063)
			(xy 122.778266 -228.45903) (xy 122.777757 -228.484997) (xy 123.057667 -228.484997) (xy 123.057667 -228.433063)
			(xy 123.065792 -228.381768) (xy 123.08184 -228.332375) (xy 123.105418 -228.286101) (xy 123.135944 -228.244085)
			(xy 123.172667 -228.207362) (xy 123.214683 -228.176836) (xy 123.260957 -228.153258) (xy 123.31035 -228.13721)
			(xy 123.361645 -228.129085) (xy 123.413579 -228.129085) (xy 123.464874 -228.13721) (xy 123.514267 -228.153258)
			(xy 123.560541 -228.176836) (xy 123.602557 -228.207362) (xy 123.63928 -228.244085) (xy 123.669806 -228.286101)
			(xy 123.693384 -228.332375) (xy 123.709432 -228.381768) (xy 123.717557 -228.433063) (xy 123.718066 -228.45903)
			(xy 123.717557 -228.484997) (xy 123.997467 -228.484997) (xy 123.997467 -228.433063) (xy 124.005592 -228.381768)
			(xy 124.02164 -228.332375) (xy 124.045218 -228.286101) (xy 124.075744 -228.244085) (xy 124.112467 -228.207362)
			(xy 124.154483 -228.176836) (xy 124.200757 -228.153258) (xy 124.25015 -228.13721) (xy 124.301445 -228.129085)
			(xy 124.353379 -228.129085) (xy 124.404674 -228.13721) (xy 124.454067 -228.153258) (xy 124.500341 -228.176836)
			(xy 124.542357 -228.207362) (xy 124.57908 -228.244085) (xy 124.609606 -228.286101) (xy 124.633184 -228.332375)
			(xy 124.649232 -228.381768) (xy 124.657357 -228.433063) (xy 124.657866 -228.45903) (xy 124.657357 -228.484997)
			(xy 124.937267 -228.484997) (xy 124.937267 -228.433063) (xy 124.945392 -228.381768) (xy 124.96144 -228.332375)
			(xy 124.985018 -228.286101) (xy 125.015544 -228.244085) (xy 125.052267 -228.207362) (xy 125.094283 -228.176836)
			(xy 125.140557 -228.153258) (xy 125.18995 -228.13721) (xy 125.241245 -228.129085) (xy 125.293179 -228.129085)
			(xy 125.344474 -228.13721) (xy 125.393867 -228.153258) (xy 125.440141 -228.176836) (xy 125.482157 -228.207362)
			(xy 125.51888 -228.244085) (xy 125.549406 -228.286101) (xy 125.572984 -228.332375) (xy 125.589032 -228.381768)
			(xy 125.597157 -228.433063) (xy 125.597666 -228.45903) (xy 125.597157 -228.484997) (xy 125.877321 -228.484997)
			(xy 125.877321 -228.433063) (xy 125.885446 -228.381768) (xy 125.901494 -228.332375) (xy 125.925072 -228.286101)
			(xy 125.955598 -228.244085) (xy 125.992321 -228.207362) (xy 126.034337 -228.176836) (xy 126.080611 -228.153258)
			(xy 126.130004 -228.13721) (xy 126.181299 -228.129085) (xy 126.233233 -228.129085) (xy 126.284528 -228.13721)
			(xy 126.333921 -228.153258) (xy 126.380195 -228.176836) (xy 126.422211 -228.207362) (xy 126.458934 -228.244085)
			(xy 126.48946 -228.286101) (xy 126.513038 -228.332375) (xy 126.529086 -228.381768) (xy 126.537211 -228.433063)
			(xy 126.53772 -228.45903) (xy 126.537211 -228.484997) (xy 126.816867 -228.484997) (xy 126.816867 -228.433063)
			(xy 126.824992 -228.381768) (xy 126.84104 -228.332375) (xy 126.864618 -228.286101) (xy 126.895144 -228.244085)
			(xy 126.931867 -228.207362) (xy 126.973883 -228.176836) (xy 127.020157 -228.153258) (xy 127.06955 -228.13721)
			(xy 127.120845 -228.129085) (xy 127.172779 -228.129085) (xy 127.224074 -228.13721) (xy 127.273467 -228.153258)
			(xy 127.319741 -228.176836) (xy 127.361757 -228.207362) (xy 127.39848 -228.244085) (xy 127.429006 -228.286101)
			(xy 127.452584 -228.332375) (xy 127.468632 -228.381768) (xy 127.476757 -228.433063) (xy 127.477266 -228.45903)
			(xy 127.476757 -228.484997) (xy 127.756667 -228.484997) (xy 127.756667 -228.433063) (xy 127.764792 -228.381768)
			(xy 127.78084 -228.332375) (xy 127.804418 -228.286101) (xy 127.834944 -228.244085) (xy 127.871667 -228.207362)
			(xy 127.913683 -228.176836) (xy 127.959957 -228.153258) (xy 128.00935 -228.13721) (xy 128.060645 -228.129085)
			(xy 128.112579 -228.129085) (xy 128.163874 -228.13721) (xy 128.213267 -228.153258) (xy 128.259541 -228.176836)
			(xy 128.301557 -228.207362) (xy 128.33828 -228.244085) (xy 128.368806 -228.286101) (xy 128.392384 -228.332375)
			(xy 128.408432 -228.381768) (xy 128.416557 -228.433063) (xy 128.417066 -228.45903) (xy 128.416557 -228.484997)
			(xy 128.696467 -228.484997) (xy 128.696467 -228.433063) (xy 128.704592 -228.381768) (xy 128.72064 -228.332375)
			(xy 128.744218 -228.286101) (xy 128.774744 -228.244085) (xy 128.811467 -228.207362) (xy 128.853483 -228.176836)
			(xy 128.899757 -228.153258) (xy 128.94915 -228.13721) (xy 129.000445 -228.129085) (xy 129.052379 -228.129085)
			(xy 129.103674 -228.13721) (xy 129.153067 -228.153258) (xy 129.199341 -228.176836) (xy 129.241357 -228.207362)
			(xy 129.27808 -228.244085) (xy 129.308606 -228.286101) (xy 129.332184 -228.332375) (xy 129.348232 -228.381768)
			(xy 129.356357 -228.433063) (xy 129.356866 -228.45903) (xy 129.356357 -228.484997) (xy 129.636267 -228.484997)
			(xy 129.636267 -228.433063) (xy 129.644392 -228.381768) (xy 129.66044 -228.332375) (xy 129.684018 -228.286101)
			(xy 129.714544 -228.244085) (xy 129.751267 -228.207362) (xy 129.793283 -228.176836) (xy 129.839557 -228.153258)
			(xy 129.88895 -228.13721) (xy 129.940245 -228.129085) (xy 129.992179 -228.129085) (xy 130.043474 -228.13721)
			(xy 130.092867 -228.153258) (xy 130.139141 -228.176836) (xy 130.181157 -228.207362) (xy 130.21788 -228.244085)
			(xy 130.248406 -228.286101) (xy 130.271984 -228.332375) (xy 130.288032 -228.381768) (xy 130.296157 -228.433063)
			(xy 130.296666 -228.45903) (xy 130.296157 -228.484997) (xy 130.576067 -228.484997) (xy 130.576067 -228.433063)
			(xy 130.584192 -228.381768) (xy 130.60024 -228.332375) (xy 130.623818 -228.286101) (xy 130.654344 -228.244085)
			(xy 130.691067 -228.207362) (xy 130.733083 -228.176836) (xy 130.779357 -228.153258) (xy 130.82875 -228.13721)
			(xy 130.880045 -228.129085) (xy 130.931979 -228.129085) (xy 130.983274 -228.13721) (xy 131.032667 -228.153258)
			(xy 131.078941 -228.176836) (xy 131.120957 -228.207362) (xy 131.15768 -228.244085) (xy 131.188206 -228.286101)
			(xy 131.211784 -228.332375) (xy 131.227832 -228.381768) (xy 131.235957 -228.433063) (xy 131.236466 -228.45903)
			(xy 131.235957 -228.484997) (xy 131.515867 -228.484997) (xy 131.515867 -228.433063) (xy 131.523992 -228.381768)
			(xy 131.54004 -228.332375) (xy 131.563618 -228.286101) (xy 131.594144 -228.244085) (xy 131.630867 -228.207362)
			(xy 131.672883 -228.176836) (xy 131.719157 -228.153258) (xy 131.76855 -228.13721) (xy 131.819845 -228.129085)
			(xy 131.871779 -228.129085) (xy 131.923074 -228.13721) (xy 131.972467 -228.153258) (xy 132.018741 -228.176836)
			(xy 132.060757 -228.207362) (xy 132.09748 -228.244085) (xy 132.128006 -228.286101) (xy 132.151584 -228.332375)
			(xy 132.167632 -228.381768) (xy 132.175757 -228.433063) (xy 132.176266 -228.45903) (xy 132.175757 -228.484997)
			(xy 132.167632 -228.536292) (xy 132.151584 -228.585685) (xy 132.128006 -228.631959) (xy 132.09748 -228.673975)
			(xy 132.060757 -228.710698) (xy 132.018741 -228.741224) (xy 131.972467 -228.764802) (xy 131.923074 -228.78085)
			(xy 131.871779 -228.788975) (xy 131.819845 -228.788975) (xy 131.76855 -228.78085) (xy 131.719157 -228.764802)
			(xy 131.672883 -228.741224) (xy 131.630867 -228.710698) (xy 131.594144 -228.673975) (xy 131.563618 -228.631959)
			(xy 131.54004 -228.585685) (xy 131.523992 -228.536292) (xy 131.515867 -228.484997) (xy 131.235957 -228.484997)
			(xy 131.227832 -228.536292) (xy 131.211784 -228.585685) (xy 131.188206 -228.631959) (xy 131.15768 -228.673975)
			(xy 131.120957 -228.710698) (xy 131.078941 -228.741224) (xy 131.032667 -228.764802) (xy 130.983274 -228.78085)
			(xy 130.931979 -228.788975) (xy 130.880045 -228.788975) (xy 130.82875 -228.78085) (xy 130.779357 -228.764802)
			(xy 130.733083 -228.741224) (xy 130.691067 -228.710698) (xy 130.654344 -228.673975) (xy 130.623818 -228.631959)
			(xy 130.60024 -228.585685) (xy 130.584192 -228.536292) (xy 130.576067 -228.484997) (xy 130.296157 -228.484997)
			(xy 130.288032 -228.536292) (xy 130.271984 -228.585685) (xy 130.248406 -228.631959) (xy 130.21788 -228.673975)
			(xy 130.181157 -228.710698) (xy 130.139141 -228.741224) (xy 130.092867 -228.764802) (xy 130.043474 -228.78085)
			(xy 129.992179 -228.788975) (xy 129.940245 -228.788975) (xy 129.88895 -228.78085) (xy 129.839557 -228.764802)
			(xy 129.793283 -228.741224) (xy 129.751267 -228.710698) (xy 129.714544 -228.673975) (xy 129.684018 -228.631959)
			(xy 129.66044 -228.585685) (xy 129.644392 -228.536292) (xy 129.636267 -228.484997) (xy 129.356357 -228.484997)
			(xy 129.348232 -228.536292) (xy 129.332184 -228.585685) (xy 129.308606 -228.631959) (xy 129.27808 -228.673975)
			(xy 129.241357 -228.710698) (xy 129.199341 -228.741224) (xy 129.153067 -228.764802) (xy 129.103674 -228.78085)
			(xy 129.052379 -228.788975) (xy 129.000445 -228.788975) (xy 128.94915 -228.78085) (xy 128.899757 -228.764802)
			(xy 128.853483 -228.741224) (xy 128.811467 -228.710698) (xy 128.774744 -228.673975) (xy 128.744218 -228.631959)
			(xy 128.72064 -228.585685) (xy 128.704592 -228.536292) (xy 128.696467 -228.484997) (xy 128.416557 -228.484997)
			(xy 128.408432 -228.536292) (xy 128.392384 -228.585685) (xy 128.368806 -228.631959) (xy 128.33828 -228.673975)
			(xy 128.301557 -228.710698) (xy 128.259541 -228.741224) (xy 128.213267 -228.764802) (xy 128.163874 -228.78085)
			(xy 128.112579 -228.788975) (xy 128.060645 -228.788975) (xy 128.00935 -228.78085) (xy 127.959957 -228.764802)
			(xy 127.913683 -228.741224) (xy 127.871667 -228.710698) (xy 127.834944 -228.673975) (xy 127.804418 -228.631959)
			(xy 127.78084 -228.585685) (xy 127.764792 -228.536292) (xy 127.756667 -228.484997) (xy 127.476757 -228.484997)
			(xy 127.468632 -228.536292) (xy 127.452584 -228.585685) (xy 127.429006 -228.631959) (xy 127.39848 -228.673975)
			(xy 127.361757 -228.710698) (xy 127.319741 -228.741224) (xy 127.273467 -228.764802) (xy 127.224074 -228.78085)
			(xy 127.172779 -228.788975) (xy 127.120845 -228.788975) (xy 127.06955 -228.78085) (xy 127.020157 -228.764802)
			(xy 126.973883 -228.741224) (xy 126.931867 -228.710698) (xy 126.895144 -228.673975) (xy 126.864618 -228.631959)
			(xy 126.84104 -228.585685) (xy 126.824992 -228.536292) (xy 126.816867 -228.484997) (xy 126.537211 -228.484997)
			(xy 126.529086 -228.536292) (xy 126.513038 -228.585685) (xy 126.48946 -228.631959) (xy 126.458934 -228.673975)
			(xy 126.422211 -228.710698) (xy 126.380195 -228.741224) (xy 126.333921 -228.764802) (xy 126.284528 -228.78085)
			(xy 126.233233 -228.788975) (xy 126.181299 -228.788975) (xy 126.130004 -228.78085) (xy 126.080611 -228.764802)
			(xy 126.034337 -228.741224) (xy 125.992321 -228.710698) (xy 125.955598 -228.673975) (xy 125.925072 -228.631959)
			(xy 125.901494 -228.585685) (xy 125.885446 -228.536292) (xy 125.877321 -228.484997) (xy 125.597157 -228.484997)
			(xy 125.589032 -228.536292) (xy 125.572984 -228.585685) (xy 125.549406 -228.631959) (xy 125.51888 -228.673975)
			(xy 125.482157 -228.710698) (xy 125.440141 -228.741224) (xy 125.393867 -228.764802) (xy 125.344474 -228.78085)
			(xy 125.293179 -228.788975) (xy 125.241245 -228.788975) (xy 125.18995 -228.78085) (xy 125.140557 -228.764802)
			(xy 125.094283 -228.741224) (xy 125.052267 -228.710698) (xy 125.015544 -228.673975) (xy 124.985018 -228.631959)
			(xy 124.96144 -228.585685) (xy 124.945392 -228.536292) (xy 124.937267 -228.484997) (xy 124.657357 -228.484997)
			(xy 124.649232 -228.536292) (xy 124.633184 -228.585685) (xy 124.609606 -228.631959) (xy 124.57908 -228.673975)
			(xy 124.542357 -228.710698) (xy 124.500341 -228.741224) (xy 124.454067 -228.764802) (xy 124.404674 -228.78085)
			(xy 124.353379 -228.788975) (xy 124.301445 -228.788975) (xy 124.25015 -228.78085) (xy 124.200757 -228.764802)
			(xy 124.154483 -228.741224) (xy 124.112467 -228.710698) (xy 124.075744 -228.673975) (xy 124.045218 -228.631959)
			(xy 124.02164 -228.585685) (xy 124.005592 -228.536292) (xy 123.997467 -228.484997) (xy 123.717557 -228.484997)
			(xy 123.709432 -228.536292) (xy 123.693384 -228.585685) (xy 123.669806 -228.631959) (xy 123.63928 -228.673975)
			(xy 123.602557 -228.710698) (xy 123.560541 -228.741224) (xy 123.514267 -228.764802) (xy 123.464874 -228.78085)
			(xy 123.413579 -228.788975) (xy 123.361645 -228.788975) (xy 123.31035 -228.78085) (xy 123.260957 -228.764802)
			(xy 123.214683 -228.741224) (xy 123.172667 -228.710698) (xy 123.135944 -228.673975) (xy 123.105418 -228.631959)
			(xy 123.08184 -228.585685) (xy 123.065792 -228.536292) (xy 123.057667 -228.484997) (xy 122.777757 -228.484997)
			(xy 122.769632 -228.536292) (xy 122.753584 -228.585685) (xy 122.730006 -228.631959) (xy 122.69948 -228.673975)
			(xy 122.662757 -228.710698) (xy 122.620741 -228.741224) (xy 122.574467 -228.764802) (xy 122.525074 -228.78085)
			(xy 122.473779 -228.788975) (xy 122.421845 -228.788975) (xy 122.37055 -228.78085) (xy 122.321157 -228.764802)
			(xy 122.274883 -228.741224) (xy 122.232867 -228.710698) (xy 122.196144 -228.673975) (xy 122.165618 -228.631959)
			(xy 122.14204 -228.585685) (xy 122.125992 -228.536292) (xy 122.117867 -228.484997) (xy 121.837957 -228.484997)
			(xy 121.829832 -228.536292) (xy 121.813784 -228.585685) (xy 121.790206 -228.631959) (xy 121.75968 -228.673975)
			(xy 121.722957 -228.710698) (xy 121.680941 -228.741224) (xy 121.634667 -228.764802) (xy 121.585274 -228.78085)
			(xy 121.533979 -228.788975) (xy 121.482045 -228.788975) (xy 121.43075 -228.78085) (xy 121.381357 -228.764802)
			(xy 121.335083 -228.741224) (xy 121.293067 -228.710698) (xy 121.256344 -228.673975) (xy 121.225818 -228.631959)
			(xy 121.20224 -228.585685) (xy 121.186192 -228.536292) (xy 121.178067 -228.484997) (xy 120.898157 -228.484997)
			(xy 120.890032 -228.536292) (xy 120.873984 -228.585685) (xy 120.850406 -228.631959) (xy 120.81988 -228.673975)
			(xy 120.783157 -228.710698) (xy 120.741141 -228.741224) (xy 120.694867 -228.764802) (xy 120.645474 -228.78085)
			(xy 120.594179 -228.788975) (xy 120.542245 -228.788975) (xy 120.49095 -228.78085) (xy 120.441557 -228.764802)
			(xy 120.395283 -228.741224) (xy 120.353267 -228.710698) (xy 120.316544 -228.673975) (xy 120.286018 -228.631959)
			(xy 120.26244 -228.585685) (xy 120.246392 -228.536292) (xy 120.238267 -228.484997) (xy 119.958357 -228.484997)
			(xy 119.950232 -228.536292) (xy 119.934184 -228.585685) (xy 119.910606 -228.631959) (xy 119.88008 -228.673975)
			(xy 119.843357 -228.710698) (xy 119.801341 -228.741224) (xy 119.755067 -228.764802) (xy 119.705674 -228.78085)
			(xy 119.654379 -228.788975) (xy 119.602445 -228.788975) (xy 119.55115 -228.78085) (xy 119.501757 -228.764802)
			(xy 119.455483 -228.741224) (xy 119.413467 -228.710698) (xy 119.376744 -228.673975) (xy 119.346218 -228.631959)
			(xy 119.32264 -228.585685) (xy 119.306592 -228.536292) (xy 119.298467 -228.484997) (xy 119.018557 -228.484997)
			(xy 119.010432 -228.536292) (xy 118.994384 -228.585685) (xy 118.970806 -228.631959) (xy 118.94028 -228.673975)
			(xy 118.903557 -228.710698) (xy 118.861541 -228.741224) (xy 118.815267 -228.764802) (xy 118.765874 -228.78085)
			(xy 118.714579 -228.788975) (xy 118.662645 -228.788975) (xy 118.61135 -228.78085) (xy 118.561957 -228.764802)
			(xy 118.515683 -228.741224) (xy 118.473667 -228.710698) (xy 118.436944 -228.673975) (xy 118.406418 -228.631959)
			(xy 118.38284 -228.585685) (xy 118.366792 -228.536292) (xy 118.358667 -228.484997) (xy 118.078757 -228.484997)
			(xy 118.070632 -228.536292) (xy 118.054584 -228.585685) (xy 118.031006 -228.631959) (xy 118.00048 -228.673975)
			(xy 117.963757 -228.710698) (xy 117.921741 -228.741224) (xy 117.875467 -228.764802) (xy 117.826074 -228.78085)
			(xy 117.774779 -228.788975) (xy 117.722845 -228.788975) (xy 117.67155 -228.78085) (xy 117.622157 -228.764802)
			(xy 117.575883 -228.741224) (xy 117.533867 -228.710698) (xy 117.497144 -228.673975) (xy 117.466618 -228.631959)
			(xy 117.44304 -228.585685) (xy 117.426992 -228.536292) (xy 117.418867 -228.484997) (xy 117.138957 -228.484997)
			(xy 117.130832 -228.536292) (xy 117.114784 -228.585685) (xy 117.091206 -228.631959) (xy 117.06068 -228.673975)
			(xy 117.023957 -228.710698) (xy 116.981941 -228.741224) (xy 116.935667 -228.764802) (xy 116.886274 -228.78085)
			(xy 116.834979 -228.788975) (xy 116.783045 -228.788975) (xy 116.73175 -228.78085) (xy 116.682357 -228.764802)
			(xy 116.636083 -228.741224) (xy 116.594067 -228.710698) (xy 116.557344 -228.673975) (xy 116.526818 -228.631959)
			(xy 116.50324 -228.585685) (xy 116.487192 -228.536292) (xy 116.479067 -228.484997) (xy 116.199157 -228.484997)
			(xy 116.191032 -228.536292) (xy 116.174984 -228.585685) (xy 116.151406 -228.631959) (xy 116.12088 -228.673975)
			(xy 116.084157 -228.710698) (xy 116.042141 -228.741224) (xy 115.995867 -228.764802) (xy 115.946474 -228.78085)
			(xy 115.895179 -228.788975) (xy 115.843245 -228.788975) (xy 115.79195 -228.78085) (xy 115.742557 -228.764802)
			(xy 115.696283 -228.741224) (xy 115.654267 -228.710698) (xy 115.617544 -228.673975) (xy 115.587018 -228.631959)
			(xy 115.56344 -228.585685) (xy 115.547392 -228.536292) (xy 115.539267 -228.484997) (xy 115.259357 -228.484997)
			(xy 115.251232 -228.536292) (xy 115.235184 -228.585685) (xy 115.211606 -228.631959) (xy 115.18108 -228.673975)
			(xy 115.144357 -228.710698) (xy 115.102341 -228.741224) (xy 115.056067 -228.764802) (xy 115.006674 -228.78085)
			(xy 114.955379 -228.788975) (xy 114.903445 -228.788975) (xy 114.85215 -228.78085) (xy 114.802757 -228.764802)
			(xy 114.756483 -228.741224) (xy 114.714467 -228.710698) (xy 114.677744 -228.673975) (xy 114.647218 -228.631959)
			(xy 114.62364 -228.585685) (xy 114.607592 -228.536292) (xy 114.599467 -228.484997) (xy 114.319557 -228.484997)
			(xy 114.311432 -228.536292) (xy 114.295384 -228.585685) (xy 114.271806 -228.631959) (xy 114.24128 -228.673975)
			(xy 114.204557 -228.710698) (xy 114.162541 -228.741224) (xy 114.116267 -228.764802) (xy 114.066874 -228.78085)
			(xy 114.015579 -228.788975) (xy 113.963645 -228.788975) (xy 113.91235 -228.78085) (xy 113.862957 -228.764802)
			(xy 113.816683 -228.741224) (xy 113.774667 -228.710698) (xy 113.737944 -228.673975) (xy 113.707418 -228.631959)
			(xy 113.68384 -228.585685) (xy 113.667792 -228.536292) (xy 113.659667 -228.484997) (xy 113.379757 -228.484997)
			(xy 113.371632 -228.536292) (xy 113.355584 -228.585685) (xy 113.332006 -228.631959) (xy 113.30148 -228.673975)
			(xy 113.264757 -228.710698) (xy 113.222741 -228.741224) (xy 113.176467 -228.764802) (xy 113.127074 -228.78085)
			(xy 113.075779 -228.788975) (xy 113.023845 -228.788975) (xy 112.97255 -228.78085) (xy 112.923157 -228.764802)
			(xy 112.876883 -228.741224) (xy 112.834867 -228.710698) (xy 112.798144 -228.673975) (xy 112.767618 -228.631959)
			(xy 112.74404 -228.585685) (xy 112.727992 -228.536292) (xy 112.719867 -228.484997) (xy 112.439957 -228.484997)
			(xy 112.431832 -228.536292) (xy 112.415784 -228.585685) (xy 112.392206 -228.631959) (xy 112.36168 -228.673975)
			(xy 112.324957 -228.710698) (xy 112.282941 -228.741224) (xy 112.236667 -228.764802) (xy 112.187274 -228.78085)
			(xy 112.135979 -228.788975) (xy 112.084045 -228.788975) (xy 112.03275 -228.78085) (xy 111.983357 -228.764802)
			(xy 111.937083 -228.741224) (xy 111.895067 -228.710698) (xy 111.858344 -228.673975) (xy 111.827818 -228.631959)
			(xy 111.80424 -228.585685) (xy 111.788192 -228.536292) (xy 111.780067 -228.484997) (xy 111.500411 -228.484997)
			(xy 111.492286 -228.536292) (xy 111.476238 -228.585685) (xy 111.45266 -228.631959) (xy 111.422134 -228.673975)
			(xy 111.385411 -228.710698) (xy 111.343395 -228.741224) (xy 111.297121 -228.764802) (xy 111.247728 -228.78085)
			(xy 111.196433 -228.788975) (xy 111.144499 -228.788975) (xy 111.093204 -228.78085) (xy 111.043811 -228.764802)
			(xy 110.997537 -228.741224) (xy 110.955521 -228.710698) (xy 110.918798 -228.673975) (xy 110.888272 -228.631959)
			(xy 110.864694 -228.585685) (xy 110.848646 -228.536292) (xy 110.840521 -228.484997) (xy 110.560357 -228.484997)
			(xy 110.552232 -228.536292) (xy 110.536184 -228.585685) (xy 110.512606 -228.631959) (xy 110.48208 -228.673975)
			(xy 110.445357 -228.710698) (xy 110.403341 -228.741224) (xy 110.357067 -228.764802) (xy 110.307674 -228.78085)
			(xy 110.256379 -228.788975) (xy 110.204445 -228.788975) (xy 110.15315 -228.78085) (xy 110.103757 -228.764802)
			(xy 110.057483 -228.741224) (xy 110.015467 -228.710698) (xy 109.978744 -228.673975) (xy 109.948218 -228.631959)
			(xy 109.92464 -228.585685) (xy 109.908592 -228.536292) (xy 109.900467 -228.484997) (xy 109.620557 -228.484997)
			(xy 109.612432 -228.536292) (xy 109.596384 -228.585685) (xy 109.572806 -228.631959) (xy 109.54228 -228.673975)
			(xy 109.505557 -228.710698) (xy 109.463541 -228.741224) (xy 109.417267 -228.764802) (xy 109.367874 -228.78085)
			(xy 109.316579 -228.788975) (xy 109.264645 -228.788975) (xy 109.21335 -228.78085) (xy 109.163957 -228.764802)
			(xy 109.117683 -228.741224) (xy 109.075667 -228.710698) (xy 109.038944 -228.673975) (xy 109.008418 -228.631959)
			(xy 108.98484 -228.585685) (xy 108.968792 -228.536292) (xy 108.960667 -228.484997) (xy 108.680757 -228.484997)
			(xy 108.672632 -228.536292) (xy 108.656584 -228.585685) (xy 108.633006 -228.631959) (xy 108.60248 -228.673975)
			(xy 108.565757 -228.710698) (xy 108.523741 -228.741224) (xy 108.477467 -228.764802) (xy 108.428074 -228.78085)
			(xy 108.376779 -228.788975) (xy 108.324845 -228.788975) (xy 108.27355 -228.78085) (xy 108.224157 -228.764802)
			(xy 108.177883 -228.741224) (xy 108.135867 -228.710698) (xy 108.099144 -228.673975) (xy 108.068618 -228.631959)
			(xy 108.04504 -228.585685) (xy 108.028992 -228.536292) (xy 108.020867 -228.484997) (xy 107.740957 -228.484997)
			(xy 107.732832 -228.536292) (xy 107.716784 -228.585685) (xy 107.693206 -228.631959) (xy 107.66268 -228.673975)
			(xy 107.625957 -228.710698) (xy 107.583941 -228.741224) (xy 107.537667 -228.764802) (xy 107.488274 -228.78085)
			(xy 107.436979 -228.788975) (xy 107.385045 -228.788975) (xy 107.33375 -228.78085) (xy 107.284357 -228.764802)
			(xy 107.238083 -228.741224) (xy 107.196067 -228.710698) (xy 107.159344 -228.673975) (xy 107.128818 -228.631959)
			(xy 107.10524 -228.585685) (xy 107.089192 -228.536292) (xy 107.081067 -228.484997) (xy 106.801157 -228.484997)
			(xy 106.793032 -228.536292) (xy 106.776984 -228.585685) (xy 106.753406 -228.631959) (xy 106.72288 -228.673975)
			(xy 106.686157 -228.710698) (xy 106.644141 -228.741224) (xy 106.597867 -228.764802) (xy 106.548474 -228.78085)
			(xy 106.497179 -228.788975) (xy 106.445245 -228.788975) (xy 106.39395 -228.78085) (xy 106.344557 -228.764802)
			(xy 106.298283 -228.741224) (xy 106.256267 -228.710698) (xy 106.219544 -228.673975) (xy 106.189018 -228.631959)
			(xy 106.16544 -228.585685) (xy 106.149392 -228.536292) (xy 106.141267 -228.484997) (xy 105.861357 -228.484997)
			(xy 105.853232 -228.536292) (xy 105.837184 -228.585685) (xy 105.813606 -228.631959) (xy 105.78308 -228.673975)
			(xy 105.746357 -228.710698) (xy 105.704341 -228.741224) (xy 105.658067 -228.764802) (xy 105.608674 -228.78085)
			(xy 105.557379 -228.788975) (xy 105.505445 -228.788975) (xy 105.45415 -228.78085) (xy 105.404757 -228.764802)
			(xy 105.358483 -228.741224) (xy 105.316467 -228.710698) (xy 105.279744 -228.673975) (xy 105.249218 -228.631959)
			(xy 105.22564 -228.585685) (xy 105.209592 -228.536292) (xy 105.201467 -228.484997) (xy 104.921557 -228.484997)
			(xy 104.913432 -228.536292) (xy 104.897384 -228.585685) (xy 104.873806 -228.631959) (xy 104.84328 -228.673975)
			(xy 104.806557 -228.710698) (xy 104.764541 -228.741224) (xy 104.718267 -228.764802) (xy 104.668874 -228.78085)
			(xy 104.617579 -228.788975) (xy 104.565645 -228.788975) (xy 104.51435 -228.78085) (xy 104.464957 -228.764802)
			(xy 104.418683 -228.741224) (xy 104.376667 -228.710698) (xy 104.339944 -228.673975) (xy 104.309418 -228.631959)
			(xy 104.28584 -228.585685) (xy 104.269792 -228.536292) (xy 104.261667 -228.484997) (xy 103.981757 -228.484997)
			(xy 103.973632 -228.536292) (xy 103.957584 -228.585685) (xy 103.934006 -228.631959) (xy 103.90348 -228.673975)
			(xy 103.866757 -228.710698) (xy 103.824741 -228.741224) (xy 103.778467 -228.764802) (xy 103.729074 -228.78085)
			(xy 103.677779 -228.788975) (xy 103.625845 -228.788975) (xy 103.57455 -228.78085) (xy 103.525157 -228.764802)
			(xy 103.478883 -228.741224) (xy 103.436867 -228.710698) (xy 103.400144 -228.673975) (xy 103.369618 -228.631959)
			(xy 103.34604 -228.585685) (xy 103.329992 -228.536292) (xy 103.321867 -228.484997) (xy 103.041957 -228.484997)
			(xy 103.033832 -228.536292) (xy 103.017784 -228.585685) (xy 102.994206 -228.631959) (xy 102.96368 -228.673975)
			(xy 102.926957 -228.710698) (xy 102.884941 -228.741224) (xy 102.838667 -228.764802) (xy 102.789274 -228.78085)
			(xy 102.737979 -228.788975) (xy 102.686045 -228.788975) (xy 102.63475 -228.78085) (xy 102.585357 -228.764802)
			(xy 102.539083 -228.741224) (xy 102.497067 -228.710698) (xy 102.460344 -228.673975) (xy 102.429818 -228.631959)
			(xy 102.40624 -228.585685) (xy 102.390192 -228.536292) (xy 102.382067 -228.484997) (xy 102.102157 -228.484997)
			(xy 102.094032 -228.536292) (xy 102.077984 -228.585685) (xy 102.054406 -228.631959) (xy 102.02388 -228.673975)
			(xy 101.987157 -228.710698) (xy 101.945141 -228.741224) (xy 101.898867 -228.764802) (xy 101.849474 -228.78085)
			(xy 101.798179 -228.788975) (xy 101.746245 -228.788975) (xy 101.69495 -228.78085) (xy 101.645557 -228.764802)
			(xy 101.599283 -228.741224) (xy 101.557267 -228.710698) (xy 101.520544 -228.673975) (xy 101.490018 -228.631959)
			(xy 101.46644 -228.585685) (xy 101.450392 -228.536292) (xy 101.442267 -228.484997) (xy 101.162357 -228.484997)
			(xy 101.154232 -228.536292) (xy 101.138184 -228.585685) (xy 101.114606 -228.631959) (xy 101.08408 -228.673975)
			(xy 101.047357 -228.710698) (xy 101.005341 -228.741224) (xy 100.959067 -228.764802) (xy 100.909674 -228.78085)
			(xy 100.858379 -228.788975) (xy 100.806445 -228.788975) (xy 100.75515 -228.78085) (xy 100.705757 -228.764802)
			(xy 100.659483 -228.741224) (xy 100.617467 -228.710698) (xy 100.580744 -228.673975) (xy 100.550218 -228.631959)
			(xy 100.52664 -228.585685) (xy 100.510592 -228.536292) (xy 100.502467 -228.484997) (xy 100.222557 -228.484997)
			(xy 100.214432 -228.536292) (xy 100.198384 -228.585685) (xy 100.174806 -228.631959) (xy 100.14428 -228.673975)
			(xy 100.107557 -228.710698) (xy 100.065541 -228.741224) (xy 100.019267 -228.764802) (xy 99.969874 -228.78085)
			(xy 99.918579 -228.788975) (xy 99.866645 -228.788975) (xy 99.81535 -228.78085) (xy 99.765957 -228.764802)
			(xy 99.719683 -228.741224) (xy 99.677667 -228.710698) (xy 99.640944 -228.673975) (xy 99.610418 -228.631959)
			(xy 99.58684 -228.585685) (xy 99.570792 -228.536292) (xy 99.562667 -228.484997) (xy 99.282757 -228.484997)
			(xy 99.274632 -228.536292) (xy 99.258584 -228.585685) (xy 99.235006 -228.631959) (xy 99.20448 -228.673975)
			(xy 99.167757 -228.710698) (xy 99.125741 -228.741224) (xy 99.079467 -228.764802) (xy 99.030074 -228.78085)
			(xy 98.978779 -228.788975) (xy 98.926845 -228.788975) (xy 98.87555 -228.78085) (xy 98.826157 -228.764802)
			(xy 98.779883 -228.741224) (xy 98.737867 -228.710698) (xy 98.701144 -228.673975) (xy 98.670618 -228.631959)
			(xy 98.64704 -228.585685) (xy 98.630992 -228.536292) (xy 98.622867 -228.484997) (xy 98.343211 -228.484997)
			(xy 98.335086 -228.536292) (xy 98.319038 -228.585685) (xy 98.29546 -228.631959) (xy 98.264934 -228.673975)
			(xy 98.228211 -228.710698) (xy 98.186195 -228.741224) (xy 98.139921 -228.764802) (xy 98.090528 -228.78085)
			(xy 98.039233 -228.788975) (xy 97.987299 -228.788975) (xy 97.936004 -228.78085) (xy 97.886611 -228.764802)
			(xy 97.840337 -228.741224) (xy 97.798321 -228.710698) (xy 97.761598 -228.673975) (xy 97.731072 -228.631959)
			(xy 97.707494 -228.585685) (xy 97.691446 -228.536292) (xy 97.683321 -228.484997) (xy 97.403157 -228.484997)
			(xy 97.395032 -228.536292) (xy 97.378984 -228.585685) (xy 97.355406 -228.631959) (xy 97.32488 -228.673975)
			(xy 97.288157 -228.710698) (xy 97.246141 -228.741224) (xy 97.199867 -228.764802) (xy 97.150474 -228.78085)
			(xy 97.099179 -228.788975) (xy 97.047245 -228.788975) (xy 96.99595 -228.78085) (xy 96.946557 -228.764802)
			(xy 96.900283 -228.741224) (xy 96.858267 -228.710698) (xy 96.821544 -228.673975) (xy 96.791018 -228.631959)
			(xy 96.76744 -228.585685) (xy 96.751392 -228.536292) (xy 96.743267 -228.484997) (xy 96.463357 -228.484997)
			(xy 96.455232 -228.536292) (xy 96.439184 -228.585685) (xy 96.415606 -228.631959) (xy 96.38508 -228.673975)
			(xy 96.348357 -228.710698) (xy 96.306341 -228.741224) (xy 96.260067 -228.764802) (xy 96.210674 -228.78085)
			(xy 96.159379 -228.788975) (xy 96.107445 -228.788975) (xy 96.05615 -228.78085) (xy 96.006757 -228.764802)
			(xy 95.960483 -228.741224) (xy 95.918467 -228.710698) (xy 95.881744 -228.673975) (xy 95.851218 -228.631959)
			(xy 95.82764 -228.585685) (xy 95.811592 -228.536292) (xy 95.803467 -228.484997) (xy 95.523557 -228.484997)
			(xy 95.515432 -228.536292) (xy 95.499384 -228.585685) (xy 95.475806 -228.631959) (xy 95.44528 -228.673975)
			(xy 95.408557 -228.710698) (xy 95.366541 -228.741224) (xy 95.320267 -228.764802) (xy 95.270874 -228.78085)
			(xy 95.219579 -228.788975) (xy 95.167645 -228.788975) (xy 95.11635 -228.78085) (xy 95.066957 -228.764802)
			(xy 95.020683 -228.741224) (xy 94.978667 -228.710698) (xy 94.941944 -228.673975) (xy 94.911418 -228.631959)
			(xy 94.88784 -228.585685) (xy 94.871792 -228.536292) (xy 94.863667 -228.484997) (xy 94.583757 -228.484997)
			(xy 94.575632 -228.536292) (xy 94.559584 -228.585685) (xy 94.536006 -228.631959) (xy 94.50548 -228.673975)
			(xy 94.468757 -228.710698) (xy 94.426741 -228.741224) (xy 94.380467 -228.764802) (xy 94.331074 -228.78085)
			(xy 94.279779 -228.788975) (xy 94.227845 -228.788975) (xy 94.17655 -228.78085) (xy 94.127157 -228.764802)
			(xy 94.080883 -228.741224) (xy 94.038867 -228.710698) (xy 94.002144 -228.673975) (xy 93.971618 -228.631959)
			(xy 93.94804 -228.585685) (xy 93.931992 -228.536292) (xy 93.923867 -228.484997) (xy 93.643957 -228.484997)
			(xy 93.635832 -228.536292) (xy 93.619784 -228.585685) (xy 93.596206 -228.631959) (xy 93.56568 -228.673975)
			(xy 93.528957 -228.710698) (xy 93.486941 -228.741224) (xy 93.440667 -228.764802) (xy 93.391274 -228.78085)
			(xy 93.339979 -228.788975) (xy 93.288045 -228.788975) (xy 93.23675 -228.78085) (xy 93.187357 -228.764802)
			(xy 93.141083 -228.741224) (xy 93.099067 -228.710698) (xy 93.062344 -228.673975) (xy 93.031818 -228.631959)
			(xy 93.00824 -228.585685) (xy 92.992192 -228.536292) (xy 92.984067 -228.484997) (xy 92.704157 -228.484997)
			(xy 92.696032 -228.536292) (xy 92.679984 -228.585685) (xy 92.656406 -228.631959) (xy 92.62588 -228.673975)
			(xy 92.589157 -228.710698) (xy 92.547141 -228.741224) (xy 92.500867 -228.764802) (xy 92.451474 -228.78085)
			(xy 92.400179 -228.788975) (xy 92.348245 -228.788975) (xy 92.29695 -228.78085) (xy 92.247557 -228.764802)
			(xy 92.201283 -228.741224) (xy 92.159267 -228.710698) (xy 92.122544 -228.673975) (xy 92.092018 -228.631959)
			(xy 92.06844 -228.585685) (xy 92.052392 -228.536292) (xy 92.044267 -228.484997) (xy 91.764952 -228.484997)
			(xy 91.764952 -228.485562) (xy 91.756467 -228.537977) (xy 91.739719 -228.588364) (xy 91.715137 -228.635429)
			(xy 91.683351 -228.677962) (xy 91.64518 -228.714871) (xy 91.601602 -228.745209) (xy 91.577922 -228.757226)
			(xy 91.565222 -228.763322) (xy 91.53525 -228.808788) (xy 91.53525 -228.936296) (xy 91.535671 -228.945323)
			(xy 91.542118 -228.962192) (xy 91.554108 -228.975695) (xy 91.56192 -228.980238) (xy 91.604846 -229.000812)
			(xy 91.645232 -229.02037) (xy 91.650455 -229.022712) (xy 91.661609 -229.025269) (xy 91.66733 -229.02545)
			(xy 91.69781 -229.014528) (xy 91.70416 -229.009702) (xy 91.725907 -228.993819) (xy 91.773475 -228.968583)
			(xy 91.824503 -228.951382) (xy 91.877642 -228.942673) (xy 91.904566 -228.942138) (xy 91.930553 -228.942618)
			(xy 91.981889 -228.950744) (xy 92.031321 -228.966801) (xy 92.077633 -228.990394) (xy 92.119683 -229.020941)
			(xy 92.156437 -229.057691) (xy 92.186988 -229.099738) (xy 92.210586 -229.146047) (xy 92.226648 -229.195478)
			(xy 92.234779 -229.246813) (xy 92.234779 -229.298787) (xy 92.234775 -229.298813) (xy 92.514421 -229.298813)
			(xy 92.514421 -229.246879) (xy 92.522546 -229.195584) (xy 92.538594 -229.146191) (xy 92.562172 -229.099917)
			(xy 92.592698 -229.057901) (xy 92.629421 -229.021178) (xy 92.671437 -228.990652) (xy 92.717711 -228.967074)
			(xy 92.767104 -228.951026) (xy 92.818399 -228.942901) (xy 92.870333 -228.942901) (xy 92.921628 -228.951026)
			(xy 92.971021 -228.967074) (xy 93.017295 -228.990652) (xy 93.059311 -229.021178) (xy 93.096034 -229.057901)
			(xy 93.12656 -229.099917) (xy 93.150138 -229.146191) (xy 93.166186 -229.195584) (xy 93.174311 -229.246879)
			(xy 93.17482 -229.272846) (xy 93.174311 -229.298813) (xy 93.454221 -229.298813) (xy 93.454221 -229.246879)
			(xy 93.462346 -229.195584) (xy 93.478394 -229.146191) (xy 93.501972 -229.099917) (xy 93.532498 -229.057901)
			(xy 93.569221 -229.021178) (xy 93.611237 -228.990652) (xy 93.657511 -228.967074) (xy 93.706904 -228.951026)
			(xy 93.758199 -228.942901) (xy 93.810133 -228.942901) (xy 93.861428 -228.951026) (xy 93.910821 -228.967074)
			(xy 93.957095 -228.990652) (xy 93.999111 -229.021178) (xy 94.035834 -229.057901) (xy 94.06636 -229.099917)
			(xy 94.089938 -229.146191) (xy 94.105986 -229.195584) (xy 94.114111 -229.246879) (xy 94.11462 -229.272846)
			(xy 94.114111 -229.298813) (xy 94.393767 -229.298813) (xy 94.393767 -229.246879) (xy 94.401892 -229.195584)
			(xy 94.41794 -229.146191) (xy 94.441518 -229.099917) (xy 94.472044 -229.057901) (xy 94.508767 -229.021178)
			(xy 94.550783 -228.990652) (xy 94.597057 -228.967074) (xy 94.64645 -228.951026) (xy 94.697745 -228.942901)
			(xy 94.749679 -228.942901) (xy 94.800974 -228.951026) (xy 94.850367 -228.967074) (xy 94.896641 -228.990652)
			(xy 94.938657 -229.021178) (xy 94.97538 -229.057901) (xy 95.005906 -229.099917) (xy 95.029484 -229.146191)
			(xy 95.045532 -229.195584) (xy 95.053657 -229.246879) (xy 95.054166 -229.272846) (xy 95.053657 -229.298813)
			(xy 95.333821 -229.298813) (xy 95.333821 -229.246879) (xy 95.341946 -229.195584) (xy 95.357994 -229.146191)
			(xy 95.381572 -229.099917) (xy 95.412098 -229.057901) (xy 95.448821 -229.021178) (xy 95.490837 -228.990652)
			(xy 95.537111 -228.967074) (xy 95.586504 -228.951026) (xy 95.637799 -228.942901) (xy 95.689733 -228.942901)
			(xy 95.741028 -228.951026) (xy 95.790421 -228.967074) (xy 95.836695 -228.990652) (xy 95.878711 -229.021178)
			(xy 95.915434 -229.057901) (xy 95.94596 -229.099917) (xy 95.969538 -229.146191) (xy 95.985586 -229.195584)
			(xy 95.993711 -229.246879) (xy 95.99422 -229.272846) (xy 95.993711 -229.298813) (xy 96.273621 -229.298813)
			(xy 96.273621 -229.246879) (xy 96.281746 -229.195584) (xy 96.297794 -229.146191) (xy 96.321372 -229.099917)
			(xy 96.351898 -229.057901) (xy 96.388621 -229.021178) (xy 96.430637 -228.990652) (xy 96.476911 -228.967074)
			(xy 96.526304 -228.951026) (xy 96.577599 -228.942901) (xy 96.629533 -228.942901) (xy 96.680828 -228.951026)
			(xy 96.730221 -228.967074) (xy 96.776495 -228.990652) (xy 96.818511 -229.021178) (xy 96.855234 -229.057901)
			(xy 96.88576 -229.099917) (xy 96.909338 -229.146191) (xy 96.925386 -229.195584) (xy 96.933511 -229.246879)
			(xy 96.93402 -229.272846) (xy 96.933511 -229.298813) (xy 97.213421 -229.298813) (xy 97.213421 -229.246879)
			(xy 97.221546 -229.195584) (xy 97.237594 -229.146191) (xy 97.261172 -229.099917) (xy 97.291698 -229.057901)
			(xy 97.328421 -229.021178) (xy 97.370437 -228.990652) (xy 97.416711 -228.967074) (xy 97.466104 -228.951026)
			(xy 97.517399 -228.942901) (xy 97.569333 -228.942901) (xy 97.620628 -228.951026) (xy 97.670021 -228.967074)
			(xy 97.716295 -228.990652) (xy 97.758311 -229.021178) (xy 97.795034 -229.057901) (xy 97.82556 -229.099917)
			(xy 97.849138 -229.146191) (xy 97.865186 -229.195584) (xy 97.873311 -229.246879) (xy 97.87382 -229.272846)
			(xy 97.873311 -229.298813) (xy 98.153221 -229.298813) (xy 98.153221 -229.246879) (xy 98.161346 -229.195584)
			(xy 98.177394 -229.146191) (xy 98.200972 -229.099917) (xy 98.231498 -229.057901) (xy 98.268221 -229.021178)
			(xy 98.310237 -228.990652) (xy 98.356511 -228.967074) (xy 98.405904 -228.951026) (xy 98.457199 -228.942901)
			(xy 98.509133 -228.942901) (xy 98.560428 -228.951026) (xy 98.609821 -228.967074) (xy 98.656095 -228.990652)
			(xy 98.698111 -229.021178) (xy 98.734834 -229.057901) (xy 98.76536 -229.099917) (xy 98.788938 -229.146191)
			(xy 98.804986 -229.195584) (xy 98.813111 -229.246879) (xy 98.81362 -229.272846) (xy 98.813111 -229.298813)
			(xy 99.093021 -229.298813) (xy 99.093021 -229.246879) (xy 99.101146 -229.195584) (xy 99.117194 -229.146191)
			(xy 99.140772 -229.099917) (xy 99.171298 -229.057901) (xy 99.208021 -229.021178) (xy 99.250037 -228.990652)
			(xy 99.296311 -228.967074) (xy 99.345704 -228.951026) (xy 99.396999 -228.942901) (xy 99.448933 -228.942901)
			(xy 99.500228 -228.951026) (xy 99.549621 -228.967074) (xy 99.595895 -228.990652) (xy 99.637911 -229.021178)
			(xy 99.674634 -229.057901) (xy 99.70516 -229.099917) (xy 99.728738 -229.146191) (xy 99.744786 -229.195584)
			(xy 99.752911 -229.246879) (xy 99.75342 -229.272846) (xy 99.752911 -229.298813) (xy 100.032821 -229.298813)
			(xy 100.032821 -229.246879) (xy 100.040946 -229.195584) (xy 100.056994 -229.146191) (xy 100.080572 -229.099917)
			(xy 100.111098 -229.057901) (xy 100.147821 -229.021178) (xy 100.189837 -228.990652) (xy 100.236111 -228.967074)
			(xy 100.285504 -228.951026) (xy 100.336799 -228.942901) (xy 100.388733 -228.942901) (xy 100.440028 -228.951026)
			(xy 100.489421 -228.967074) (xy 100.535695 -228.990652) (xy 100.577711 -229.021178) (xy 100.614434 -229.057901)
			(xy 100.64496 -229.099917) (xy 100.668538 -229.146191) (xy 100.684586 -229.195584) (xy 100.692711 -229.246879)
			(xy 100.69322 -229.272846) (xy 100.692711 -229.298813) (xy 100.972367 -229.298813) (xy 100.972367 -229.246879)
			(xy 100.980492 -229.195584) (xy 100.99654 -229.146191) (xy 101.020118 -229.099917) (xy 101.050644 -229.057901)
			(xy 101.087367 -229.021178) (xy 101.129383 -228.990652) (xy 101.175657 -228.967074) (xy 101.22505 -228.951026)
			(xy 101.276345 -228.942901) (xy 101.328279 -228.942901) (xy 101.379574 -228.951026) (xy 101.428967 -228.967074)
			(xy 101.475241 -228.990652) (xy 101.517257 -229.021178) (xy 101.55398 -229.057901) (xy 101.584506 -229.099917)
			(xy 101.608084 -229.146191) (xy 101.624132 -229.195584) (xy 101.632257 -229.246879) (xy 101.632766 -229.272846)
			(xy 101.632257 -229.298813) (xy 101.912421 -229.298813) (xy 101.912421 -229.246879) (xy 101.920546 -229.195584)
			(xy 101.936594 -229.146191) (xy 101.960172 -229.099917) (xy 101.990698 -229.057901) (xy 102.027421 -229.021178)
			(xy 102.069437 -228.990652) (xy 102.115711 -228.967074) (xy 102.165104 -228.951026) (xy 102.216399 -228.942901)
			(xy 102.268333 -228.942901) (xy 102.319628 -228.951026) (xy 102.369021 -228.967074) (xy 102.415295 -228.990652)
			(xy 102.457311 -229.021178) (xy 102.494034 -229.057901) (xy 102.52456 -229.099917) (xy 102.548138 -229.146191)
			(xy 102.564186 -229.195584) (xy 102.572311 -229.246879) (xy 102.57282 -229.272846) (xy 102.572311 -229.298813)
			(xy 102.564186 -229.350108) (xy 102.548138 -229.399501) (xy 102.52456 -229.445775) (xy 102.494034 -229.487791)
			(xy 102.457311 -229.524514) (xy 102.415295 -229.55504) (xy 102.369021 -229.578618) (xy 102.319628 -229.594666)
			(xy 102.268333 -229.602791) (xy 102.216399 -229.602791) (xy 102.165104 -229.594666) (xy 102.115711 -229.578618)
			(xy 102.069437 -229.55504) (xy 102.027421 -229.524514) (xy 101.990698 -229.487791) (xy 101.960172 -229.445775)
			(xy 101.936594 -229.399501) (xy 101.920546 -229.350108) (xy 101.912421 -229.298813) (xy 101.632257 -229.298813)
			(xy 101.624132 -229.350108) (xy 101.608084 -229.399501) (xy 101.584506 -229.445775) (xy 101.55398 -229.487791)
			(xy 101.517257 -229.524514) (xy 101.475241 -229.55504) (xy 101.428967 -229.578618) (xy 101.379574 -229.594666)
			(xy 101.328279 -229.602791) (xy 101.276345 -229.602791) (xy 101.22505 -229.594666) (xy 101.175657 -229.578618)
			(xy 101.129383 -229.55504) (xy 101.087367 -229.524514) (xy 101.050644 -229.487791) (xy 101.020118 -229.445775)
			(xy 100.99654 -229.399501) (xy 100.980492 -229.350108) (xy 100.972367 -229.298813) (xy 100.692711 -229.298813)
			(xy 100.684586 -229.350108) (xy 100.668538 -229.399501) (xy 100.64496 -229.445775) (xy 100.614434 -229.487791)
			(xy 100.577711 -229.524514) (xy 100.535695 -229.55504) (xy 100.489421 -229.578618) (xy 100.440028 -229.594666)
			(xy 100.388733 -229.602791) (xy 100.336799 -229.602791) (xy 100.285504 -229.594666) (xy 100.236111 -229.578618)
			(xy 100.189837 -229.55504) (xy 100.147821 -229.524514) (xy 100.111098 -229.487791) (xy 100.080572 -229.445775)
			(xy 100.056994 -229.399501) (xy 100.040946 -229.350108) (xy 100.032821 -229.298813) (xy 99.752911 -229.298813)
			(xy 99.744786 -229.350108) (xy 99.728738 -229.399501) (xy 99.70516 -229.445775) (xy 99.674634 -229.487791)
			(xy 99.637911 -229.524514) (xy 99.595895 -229.55504) (xy 99.549621 -229.578618) (xy 99.500228 -229.594666)
			(xy 99.448933 -229.602791) (xy 99.396999 -229.602791) (xy 99.345704 -229.594666) (xy 99.296311 -229.578618)
			(xy 99.250037 -229.55504) (xy 99.208021 -229.524514) (xy 99.171298 -229.487791) (xy 99.140772 -229.445775)
			(xy 99.117194 -229.399501) (xy 99.101146 -229.350108) (xy 99.093021 -229.298813) (xy 98.813111 -229.298813)
			(xy 98.804986 -229.350108) (xy 98.788938 -229.399501) (xy 98.76536 -229.445775) (xy 98.734834 -229.487791)
			(xy 98.698111 -229.524514) (xy 98.656095 -229.55504) (xy 98.609821 -229.578618) (xy 98.560428 -229.594666)
			(xy 98.509133 -229.602791) (xy 98.457199 -229.602791) (xy 98.405904 -229.594666) (xy 98.356511 -229.578618)
			(xy 98.310237 -229.55504) (xy 98.268221 -229.524514) (xy 98.231498 -229.487791) (xy 98.200972 -229.445775)
			(xy 98.177394 -229.399501) (xy 98.161346 -229.350108) (xy 98.153221 -229.298813) (xy 97.873311 -229.298813)
			(xy 97.865186 -229.350108) (xy 97.849138 -229.399501) (xy 97.82556 -229.445775) (xy 97.795034 -229.487791)
			(xy 97.758311 -229.524514) (xy 97.716295 -229.55504) (xy 97.670021 -229.578618) (xy 97.620628 -229.594666)
			(xy 97.569333 -229.602791) (xy 97.517399 -229.602791) (xy 97.466104 -229.594666) (xy 97.416711 -229.578618)
			(xy 97.370437 -229.55504) (xy 97.328421 -229.524514) (xy 97.291698 -229.487791) (xy 97.261172 -229.445775)
			(xy 97.237594 -229.399501) (xy 97.221546 -229.350108) (xy 97.213421 -229.298813) (xy 96.933511 -229.298813)
			(xy 96.925386 -229.350108) (xy 96.909338 -229.399501) (xy 96.88576 -229.445775) (xy 96.855234 -229.487791)
			(xy 96.818511 -229.524514) (xy 96.776495 -229.55504) (xy 96.730221 -229.578618) (xy 96.680828 -229.594666)
			(xy 96.629533 -229.602791) (xy 96.577599 -229.602791) (xy 96.526304 -229.594666) (xy 96.476911 -229.578618)
			(xy 96.430637 -229.55504) (xy 96.388621 -229.524514) (xy 96.351898 -229.487791) (xy 96.321372 -229.445775)
			(xy 96.297794 -229.399501) (xy 96.281746 -229.350108) (xy 96.273621 -229.298813) (xy 95.993711 -229.298813)
			(xy 95.985586 -229.350108) (xy 95.969538 -229.399501) (xy 95.94596 -229.445775) (xy 95.915434 -229.487791)
			(xy 95.878711 -229.524514) (xy 95.836695 -229.55504) (xy 95.790421 -229.578618) (xy 95.741028 -229.594666)
			(xy 95.689733 -229.602791) (xy 95.637799 -229.602791) (xy 95.586504 -229.594666) (xy 95.537111 -229.578618)
			(xy 95.490837 -229.55504) (xy 95.448821 -229.524514) (xy 95.412098 -229.487791) (xy 95.381572 -229.445775)
			(xy 95.357994 -229.399501) (xy 95.341946 -229.350108) (xy 95.333821 -229.298813) (xy 95.053657 -229.298813)
			(xy 95.045532 -229.350108) (xy 95.029484 -229.399501) (xy 95.005906 -229.445775) (xy 94.97538 -229.487791)
			(xy 94.938657 -229.524514) (xy 94.896641 -229.55504) (xy 94.850367 -229.578618) (xy 94.800974 -229.594666)
			(xy 94.749679 -229.602791) (xy 94.697745 -229.602791) (xy 94.64645 -229.594666) (xy 94.597057 -229.578618)
			(xy 94.550783 -229.55504) (xy 94.508767 -229.524514) (xy 94.472044 -229.487791) (xy 94.441518 -229.445775)
			(xy 94.41794 -229.399501) (xy 94.401892 -229.350108) (xy 94.393767 -229.298813) (xy 94.114111 -229.298813)
			(xy 94.105986 -229.350108) (xy 94.089938 -229.399501) (xy 94.06636 -229.445775) (xy 94.035834 -229.487791)
			(xy 93.999111 -229.524514) (xy 93.957095 -229.55504) (xy 93.910821 -229.578618) (xy 93.861428 -229.594666)
			(xy 93.810133 -229.602791) (xy 93.758199 -229.602791) (xy 93.706904 -229.594666) (xy 93.657511 -229.578618)
			(xy 93.611237 -229.55504) (xy 93.569221 -229.524514) (xy 93.532498 -229.487791) (xy 93.501972 -229.445775)
			(xy 93.478394 -229.399501) (xy 93.462346 -229.350108) (xy 93.454221 -229.298813) (xy 93.174311 -229.298813)
			(xy 93.166186 -229.350108) (xy 93.150138 -229.399501) (xy 93.12656 -229.445775) (xy 93.096034 -229.487791)
			(xy 93.059311 -229.524514) (xy 93.017295 -229.55504) (xy 92.971021 -229.578618) (xy 92.921628 -229.594666)
			(xy 92.870333 -229.602791) (xy 92.818399 -229.602791) (xy 92.767104 -229.594666) (xy 92.717711 -229.578618)
			(xy 92.671437 -229.55504) (xy 92.629421 -229.524514) (xy 92.592698 -229.487791) (xy 92.562172 -229.445775)
			(xy 92.538594 -229.399501) (xy 92.522546 -229.350108) (xy 92.514421 -229.298813) (xy 92.234775 -229.298813)
			(xy 92.226648 -229.350122) (xy 92.210586 -229.399553) (xy 92.186988 -229.445862) (xy 92.156437 -229.487909)
			(xy 92.119683 -229.524659) (xy 92.077633 -229.555206) (xy 92.031321 -229.578799) (xy 91.981889 -229.594856)
			(xy 91.930553 -229.602982) (xy 91.904566 -229.603554) (xy 91.877642 -229.603024) (xy 91.824506 -229.594304)
			(xy 91.773481 -229.577099) (xy 91.725913 -229.551863) (xy 91.70416 -229.53599) (xy 91.69781 -229.531164)
			(xy 91.66733 -229.520242) (xy 91.661602 -229.520358) (xy 91.650441 -229.522935) (xy 91.645232 -229.525322)
			(xy 91.604846 -229.54488) (xy 91.56192 -229.565454) (xy 91.554119 -229.570011) (xy 91.542144 -229.58352)
			(xy 91.535673 -229.600373) (xy 91.53525 -229.609396) (xy 91.53525 -229.737158) (xy 91.565222 -229.782624)
			(xy 91.577922 -229.78872) (xy 91.601603 -229.800686) (xy 91.645137 -229.831011) (xy 91.68327 -229.8679)
			(xy 91.715022 -229.910404) (xy 91.739579 -229.957434) (xy 91.756309 -230.007782) (xy 91.764785 -230.060156)
			(xy 91.764788 -230.112629) (xy 92.044267 -230.112629) (xy 92.044267 -230.060695) (xy 92.052392 -230.0094)
			(xy 92.06844 -229.960007) (xy 92.092018 -229.913733) (xy 92.122544 -229.871717) (xy 92.159267 -229.834994)
			(xy 92.201283 -229.804468) (xy 92.247557 -229.78089) (xy 92.29695 -229.764842) (xy 92.348245 -229.756717)
			(xy 92.400179 -229.756717) (xy 92.451474 -229.764842) (xy 92.500867 -229.78089) (xy 92.547141 -229.804468)
			(xy 92.589157 -229.834994) (xy 92.62588 -229.871717) (xy 92.656406 -229.913733) (xy 92.679984 -229.960007)
			(xy 92.696032 -230.0094) (xy 92.704157 -230.060695) (xy 92.704666 -230.086662) (xy 92.704157 -230.112629)
			(xy 92.984067 -230.112629) (xy 92.984067 -230.060695) (xy 92.992192 -230.0094) (xy 93.00824 -229.960007)
			(xy 93.031818 -229.913733) (xy 93.062344 -229.871717) (xy 93.099067 -229.834994) (xy 93.141083 -229.804468)
			(xy 93.187357 -229.78089) (xy 93.23675 -229.764842) (xy 93.288045 -229.756717) (xy 93.339979 -229.756717)
			(xy 93.391274 -229.764842) (xy 93.440667 -229.78089) (xy 93.486941 -229.804468) (xy 93.528957 -229.834994)
			(xy 93.56568 -229.871717) (xy 93.596206 -229.913733) (xy 93.619784 -229.960007) (xy 93.635832 -230.0094)
			(xy 93.643957 -230.060695) (xy 93.644466 -230.086662) (xy 93.643957 -230.112629) (xy 93.923867 -230.112629)
			(xy 93.923867 -230.060695) (xy 93.931992 -230.0094) (xy 93.94804 -229.960007) (xy 93.971618 -229.913733)
			(xy 94.002144 -229.871717) (xy 94.038867 -229.834994) (xy 94.080883 -229.804468) (xy 94.127157 -229.78089)
			(xy 94.17655 -229.764842) (xy 94.227845 -229.756717) (xy 94.279779 -229.756717) (xy 94.331074 -229.764842)
			(xy 94.380467 -229.78089) (xy 94.426741 -229.804468) (xy 94.468757 -229.834994) (xy 94.50548 -229.871717)
			(xy 94.536006 -229.913733) (xy 94.559584 -229.960007) (xy 94.575632 -230.0094) (xy 94.583757 -230.060695)
			(xy 94.584266 -230.086662) (xy 94.583757 -230.112629) (xy 94.863667 -230.112629) (xy 94.863667 -230.060695)
			(xy 94.871792 -230.0094) (xy 94.88784 -229.960007) (xy 94.911418 -229.913733) (xy 94.941944 -229.871717)
			(xy 94.978667 -229.834994) (xy 95.020683 -229.804468) (xy 95.066957 -229.78089) (xy 95.11635 -229.764842)
			(xy 95.167645 -229.756717) (xy 95.219579 -229.756717) (xy 95.270874 -229.764842) (xy 95.320267 -229.78089)
			(xy 95.366541 -229.804468) (xy 95.408557 -229.834994) (xy 95.44528 -229.871717) (xy 95.475806 -229.913733)
			(xy 95.499384 -229.960007) (xy 95.515432 -230.0094) (xy 95.523557 -230.060695) (xy 95.524066 -230.086662)
			(xy 95.523557 -230.112629) (xy 95.803467 -230.112629) (xy 95.803467 -230.060695) (xy 95.811592 -230.0094)
			(xy 95.82764 -229.960007) (xy 95.851218 -229.913733) (xy 95.881744 -229.871717) (xy 95.918467 -229.834994)
			(xy 95.960483 -229.804468) (xy 96.006757 -229.78089) (xy 96.05615 -229.764842) (xy 96.107445 -229.756717)
			(xy 96.159379 -229.756717) (xy 96.210674 -229.764842) (xy 96.260067 -229.78089) (xy 96.306341 -229.804468)
			(xy 96.348357 -229.834994) (xy 96.38508 -229.871717) (xy 96.415606 -229.913733) (xy 96.439184 -229.960007)
			(xy 96.455232 -230.0094) (xy 96.463357 -230.060695) (xy 96.463866 -230.086662) (xy 96.463357 -230.112629)
			(xy 96.743521 -230.112629) (xy 96.743521 -230.060695) (xy 96.751646 -230.0094) (xy 96.767694 -229.960007)
			(xy 96.791272 -229.913733) (xy 96.821798 -229.871717) (xy 96.858521 -229.834994) (xy 96.900537 -229.804468)
			(xy 96.946811 -229.78089) (xy 96.996204 -229.764842) (xy 97.047499 -229.756717) (xy 97.099433 -229.756717)
			(xy 97.150728 -229.764842) (xy 97.200121 -229.78089) (xy 97.246395 -229.804468) (xy 97.288411 -229.834994)
			(xy 97.325134 -229.871717) (xy 97.35566 -229.913733) (xy 97.379238 -229.960007) (xy 97.395286 -230.0094)
			(xy 97.403411 -230.060695) (xy 97.40392 -230.086662) (xy 97.403411 -230.112629) (xy 97.683067 -230.112629)
			(xy 97.683067 -230.060695) (xy 97.691192 -230.0094) (xy 97.70724 -229.960007) (xy 97.730818 -229.913733)
			(xy 97.761344 -229.871717) (xy 97.798067 -229.834994) (xy 97.840083 -229.804468) (xy 97.886357 -229.78089)
			(xy 97.93575 -229.764842) (xy 97.987045 -229.756717) (xy 98.038979 -229.756717) (xy 98.090274 -229.764842)
			(xy 98.139667 -229.78089) (xy 98.185941 -229.804468) (xy 98.227957 -229.834994) (xy 98.26468 -229.871717)
			(xy 98.295206 -229.913733) (xy 98.318784 -229.960007) (xy 98.334832 -230.0094) (xy 98.342957 -230.060695)
			(xy 98.343466 -230.086662) (xy 98.342957 -230.112629) (xy 98.622867 -230.112629) (xy 98.622867 -230.060695)
			(xy 98.630992 -230.0094) (xy 98.64704 -229.960007) (xy 98.670618 -229.913733) (xy 98.701144 -229.871717)
			(xy 98.737867 -229.834994) (xy 98.779883 -229.804468) (xy 98.826157 -229.78089) (xy 98.87555 -229.764842)
			(xy 98.926845 -229.756717) (xy 98.978779 -229.756717) (xy 99.030074 -229.764842) (xy 99.079467 -229.78089)
			(xy 99.125741 -229.804468) (xy 99.167757 -229.834994) (xy 99.20448 -229.871717) (xy 99.235006 -229.913733)
			(xy 99.258584 -229.960007) (xy 99.274632 -230.0094) (xy 99.282757 -230.060695) (xy 99.283266 -230.086662)
			(xy 99.282757 -230.112629) (xy 99.562667 -230.112629) (xy 99.562667 -230.060695) (xy 99.570792 -230.0094)
			(xy 99.58684 -229.960007) (xy 99.610418 -229.913733) (xy 99.640944 -229.871717) (xy 99.677667 -229.834994)
			(xy 99.719683 -229.804468) (xy 99.765957 -229.78089) (xy 99.81535 -229.764842) (xy 99.866645 -229.756717)
			(xy 99.918579 -229.756717) (xy 99.969874 -229.764842) (xy 100.019267 -229.78089) (xy 100.065541 -229.804468)
			(xy 100.107557 -229.834994) (xy 100.14428 -229.871717) (xy 100.174806 -229.913733) (xy 100.198384 -229.960007)
			(xy 100.214432 -230.0094) (xy 100.222557 -230.060695) (xy 100.223066 -230.086662) (xy 100.222557 -230.112629)
			(xy 100.502467 -230.112629) (xy 100.502467 -230.060695) (xy 100.510592 -230.0094) (xy 100.52664 -229.960007)
			(xy 100.550218 -229.913733) (xy 100.580744 -229.871717) (xy 100.617467 -229.834994) (xy 100.659483 -229.804468)
			(xy 100.705757 -229.78089) (xy 100.75515 -229.764842) (xy 100.806445 -229.756717) (xy 100.858379 -229.756717)
			(xy 100.909674 -229.764842) (xy 100.959067 -229.78089) (xy 101.005341 -229.804468) (xy 101.047357 -229.834994)
			(xy 101.08408 -229.871717) (xy 101.114606 -229.913733) (xy 101.138184 -229.960007) (xy 101.154232 -230.0094)
			(xy 101.162357 -230.060695) (xy 101.162866 -230.086662) (xy 101.162357 -230.112629) (xy 101.154232 -230.163924)
			(xy 101.138184 -230.213317) (xy 101.114606 -230.259591) (xy 101.08408 -230.301607) (xy 101.047357 -230.33833)
			(xy 101.005341 -230.368856) (xy 100.959067 -230.392434) (xy 100.909674 -230.408482) (xy 100.858379 -230.416607)
			(xy 100.806445 -230.416607) (xy 100.75515 -230.408482) (xy 100.705757 -230.392434) (xy 100.659483 -230.368856)
			(xy 100.617467 -230.33833) (xy 100.580744 -230.301607) (xy 100.550218 -230.259591) (xy 100.52664 -230.213317)
			(xy 100.510592 -230.163924) (xy 100.502467 -230.112629) (xy 100.222557 -230.112629) (xy 100.214432 -230.163924)
			(xy 100.198384 -230.213317) (xy 100.174806 -230.259591) (xy 100.14428 -230.301607) (xy 100.107557 -230.33833)
			(xy 100.065541 -230.368856) (xy 100.019267 -230.392434) (xy 99.969874 -230.408482) (xy 99.918579 -230.416607)
			(xy 99.866645 -230.416607) (xy 99.81535 -230.408482) (xy 99.765957 -230.392434) (xy 99.719683 -230.368856)
			(xy 99.677667 -230.33833) (xy 99.640944 -230.301607) (xy 99.610418 -230.259591) (xy 99.58684 -230.213317)
			(xy 99.570792 -230.163924) (xy 99.562667 -230.112629) (xy 99.282757 -230.112629) (xy 99.274632 -230.163924)
			(xy 99.258584 -230.213317) (xy 99.235006 -230.259591) (xy 99.20448 -230.301607) (xy 99.167757 -230.33833)
			(xy 99.125741 -230.368856) (xy 99.079467 -230.392434) (xy 99.030074 -230.408482) (xy 98.978779 -230.416607)
			(xy 98.926845 -230.416607) (xy 98.87555 -230.408482) (xy 98.826157 -230.392434) (xy 98.779883 -230.368856)
			(xy 98.737867 -230.33833) (xy 98.701144 -230.301607) (xy 98.670618 -230.259591) (xy 98.64704 -230.213317)
			(xy 98.630992 -230.163924) (xy 98.622867 -230.112629) (xy 98.342957 -230.112629) (xy 98.334832 -230.163924)
			(xy 98.318784 -230.213317) (xy 98.295206 -230.259591) (xy 98.26468 -230.301607) (xy 98.227957 -230.33833)
			(xy 98.185941 -230.368856) (xy 98.139667 -230.392434) (xy 98.090274 -230.408482) (xy 98.038979 -230.416607)
			(xy 97.987045 -230.416607) (xy 97.93575 -230.408482) (xy 97.886357 -230.392434) (xy 97.840083 -230.368856)
			(xy 97.798067 -230.33833) (xy 97.761344 -230.301607) (xy 97.730818 -230.259591) (xy 97.70724 -230.213317)
			(xy 97.691192 -230.163924) (xy 97.683067 -230.112629) (xy 97.403411 -230.112629) (xy 97.395286 -230.163924)
			(xy 97.379238 -230.213317) (xy 97.35566 -230.259591) (xy 97.325134 -230.301607) (xy 97.288411 -230.33833)
			(xy 97.246395 -230.368856) (xy 97.200121 -230.392434) (xy 97.150728 -230.408482) (xy 97.099433 -230.416607)
			(xy 97.047499 -230.416607) (xy 96.996204 -230.408482) (xy 96.946811 -230.392434) (xy 96.900537 -230.368856)
			(xy 96.858521 -230.33833) (xy 96.821798 -230.301607) (xy 96.791272 -230.259591) (xy 96.767694 -230.213317)
			(xy 96.751646 -230.163924) (xy 96.743521 -230.112629) (xy 96.463357 -230.112629) (xy 96.455232 -230.163924)
			(xy 96.439184 -230.213317) (xy 96.415606 -230.259591) (xy 96.38508 -230.301607) (xy 96.348357 -230.33833)
			(xy 96.306341 -230.368856) (xy 96.260067 -230.392434) (xy 96.210674 -230.408482) (xy 96.159379 -230.416607)
			(xy 96.107445 -230.416607) (xy 96.05615 -230.408482) (xy 96.006757 -230.392434) (xy 95.960483 -230.368856)
			(xy 95.918467 -230.33833) (xy 95.881744 -230.301607) (xy 95.851218 -230.259591) (xy 95.82764 -230.213317)
			(xy 95.811592 -230.163924) (xy 95.803467 -230.112629) (xy 95.523557 -230.112629) (xy 95.515432 -230.163924)
			(xy 95.499384 -230.213317) (xy 95.475806 -230.259591) (xy 95.44528 -230.301607) (xy 95.408557 -230.33833)
			(xy 95.366541 -230.368856) (xy 95.320267 -230.392434) (xy 95.270874 -230.408482) (xy 95.219579 -230.416607)
			(xy 95.167645 -230.416607) (xy 95.11635 -230.408482) (xy 95.066957 -230.392434) (xy 95.020683 -230.368856)
			(xy 94.978667 -230.33833) (xy 94.941944 -230.301607) (xy 94.911418 -230.259591) (xy 94.88784 -230.213317)
			(xy 94.871792 -230.163924) (xy 94.863667 -230.112629) (xy 94.583757 -230.112629) (xy 94.575632 -230.163924)
			(xy 94.559584 -230.213317) (xy 94.536006 -230.259591) (xy 94.50548 -230.301607) (xy 94.468757 -230.33833)
			(xy 94.426741 -230.368856) (xy 94.380467 -230.392434) (xy 94.331074 -230.408482) (xy 94.279779 -230.416607)
			(xy 94.227845 -230.416607) (xy 94.17655 -230.408482) (xy 94.127157 -230.392434) (xy 94.080883 -230.368856)
			(xy 94.038867 -230.33833) (xy 94.002144 -230.301607) (xy 93.971618 -230.259591) (xy 93.94804 -230.213317)
			(xy 93.931992 -230.163924) (xy 93.923867 -230.112629) (xy 93.643957 -230.112629) (xy 93.635832 -230.163924)
			(xy 93.619784 -230.213317) (xy 93.596206 -230.259591) (xy 93.56568 -230.301607) (xy 93.528957 -230.33833)
			(xy 93.486941 -230.368856) (xy 93.440667 -230.392434) (xy 93.391274 -230.408482) (xy 93.339979 -230.416607)
			(xy 93.288045 -230.416607) (xy 93.23675 -230.408482) (xy 93.187357 -230.392434) (xy 93.141083 -230.368856)
			(xy 93.099067 -230.33833) (xy 93.062344 -230.301607) (xy 93.031818 -230.259591) (xy 93.00824 -230.213317)
			(xy 92.992192 -230.163924) (xy 92.984067 -230.112629) (xy 92.704157 -230.112629) (xy 92.696032 -230.163924)
			(xy 92.679984 -230.213317) (xy 92.656406 -230.259591) (xy 92.62588 -230.301607) (xy 92.589157 -230.33833)
			(xy 92.547141 -230.368856) (xy 92.500867 -230.392434) (xy 92.451474 -230.408482) (xy 92.400179 -230.416607)
			(xy 92.348245 -230.416607) (xy 92.29695 -230.408482) (xy 92.247557 -230.392434) (xy 92.201283 -230.368856)
			(xy 92.159267 -230.33833) (xy 92.122544 -230.301607) (xy 92.092018 -230.259591) (xy 92.06844 -230.213317)
			(xy 92.052392 -230.163924) (xy 92.044267 -230.112629) (xy 91.764788 -230.112629) (xy 91.764788 -230.113211)
			(xy 91.756317 -230.165586) (xy 91.739592 -230.215935) (xy 91.71504 -230.262968) (xy 91.683292 -230.305476)
			(xy 91.645163 -230.342368) (xy 91.601632 -230.372697) (xy 91.577922 -230.384604) (xy 91.565222 -230.3907)
			(xy 91.53525 -230.436166) (xy 91.53525 -230.563928) (xy 91.535677 -230.572952) (xy 91.54213 -230.589812)
			(xy 91.554122 -230.603306) (xy 91.56192 -230.60787) (xy 91.604846 -230.628444) (xy 91.645232 -230.648002)
			(xy 91.650455 -230.650342) (xy 91.661609 -230.652898) (xy 91.66733 -230.653082) (xy 91.69781 -230.64216)
			(xy 91.70416 -230.637334) (xy 91.725908 -230.621454) (xy 91.773477 -230.596223) (xy 91.824504 -230.579026)
			(xy 91.877643 -230.570318) (xy 91.904566 -230.56977) (xy 91.930559 -230.570251) (xy 91.981905 -230.578378)
			(xy 92.031347 -230.594439) (xy 92.077668 -230.618036) (xy 92.119727 -230.64859) (xy 92.156488 -230.685347)
			(xy 92.187046 -230.727403) (xy 92.210648 -230.773721) (xy 92.226714 -230.823162) (xy 92.234847 -230.874507)
			(xy 92.234847 -230.926445) (xy 92.514421 -230.926445) (xy 92.514421 -230.874511) (xy 92.522546 -230.823216)
			(xy 92.538594 -230.773823) (xy 92.562172 -230.727549) (xy 92.592698 -230.685533) (xy 92.629421 -230.64881)
			(xy 92.671437 -230.618284) (xy 92.717711 -230.594706) (xy 92.767104 -230.578658) (xy 92.818399 -230.570533)
			(xy 92.870333 -230.570533) (xy 92.921628 -230.578658) (xy 92.971021 -230.594706) (xy 93.017295 -230.618284)
			(xy 93.059311 -230.64881) (xy 93.096034 -230.685533) (xy 93.12656 -230.727549) (xy 93.150138 -230.773823)
			(xy 93.166186 -230.823216) (xy 93.174311 -230.874511) (xy 93.17482 -230.900478) (xy 93.174311 -230.926445)
			(xy 93.454221 -230.926445) (xy 93.454221 -230.874511) (xy 93.462346 -230.823216) (xy 93.478394 -230.773823)
			(xy 93.501972 -230.727549) (xy 93.532498 -230.685533) (xy 93.569221 -230.64881) (xy 93.611237 -230.618284)
			(xy 93.657511 -230.594706) (xy 93.706904 -230.578658) (xy 93.758199 -230.570533) (xy 93.810133 -230.570533)
			(xy 93.861428 -230.578658) (xy 93.910821 -230.594706) (xy 93.957095 -230.618284) (xy 93.999111 -230.64881)
			(xy 94.035834 -230.685533) (xy 94.06636 -230.727549) (xy 94.089938 -230.773823) (xy 94.105986 -230.823216)
			(xy 94.114111 -230.874511) (xy 94.11462 -230.900478) (xy 94.114111 -230.926445) (xy 94.394021 -230.926445)
			(xy 94.394021 -230.874511) (xy 94.402146 -230.823216) (xy 94.418194 -230.773823) (xy 94.441772 -230.727549)
			(xy 94.472298 -230.685533) (xy 94.509021 -230.64881) (xy 94.551037 -230.618284) (xy 94.597311 -230.594706)
			(xy 94.646704 -230.578658) (xy 94.697999 -230.570533) (xy 94.749933 -230.570533) (xy 94.801228 -230.578658)
			(xy 94.850621 -230.594706) (xy 94.896895 -230.618284) (xy 94.938911 -230.64881) (xy 94.975634 -230.685533)
			(xy 95.00616 -230.727549) (xy 95.029738 -230.773823) (xy 95.045786 -230.823216) (xy 95.053911 -230.874511)
			(xy 95.05442 -230.900478) (xy 95.053911 -230.926445) (xy 95.333821 -230.926445) (xy 95.333821 -230.874511)
			(xy 95.341946 -230.823216) (xy 95.357994 -230.773823) (xy 95.381572 -230.727549) (xy 95.412098 -230.685533)
			(xy 95.448821 -230.64881) (xy 95.490837 -230.618284) (xy 95.537111 -230.594706) (xy 95.586504 -230.578658)
			(xy 95.637799 -230.570533) (xy 95.689733 -230.570533) (xy 95.741028 -230.578658) (xy 95.790421 -230.594706)
			(xy 95.836695 -230.618284) (xy 95.878711 -230.64881) (xy 95.915434 -230.685533) (xy 95.94596 -230.727549)
			(xy 95.969538 -230.773823) (xy 95.985586 -230.823216) (xy 95.993711 -230.874511) (xy 95.99422 -230.900478)
			(xy 95.993711 -230.926445) (xy 96.273621 -230.926445) (xy 96.273621 -230.874511) (xy 96.281746 -230.823216)
			(xy 96.297794 -230.773823) (xy 96.321372 -230.727549) (xy 96.351898 -230.685533) (xy 96.388621 -230.64881)
			(xy 96.430637 -230.618284) (xy 96.476911 -230.594706) (xy 96.526304 -230.578658) (xy 96.577599 -230.570533)
			(xy 96.629533 -230.570533) (xy 96.680828 -230.578658) (xy 96.730221 -230.594706) (xy 96.776495 -230.618284)
			(xy 96.818511 -230.64881) (xy 96.855234 -230.685533) (xy 96.88576 -230.727549) (xy 96.909338 -230.773823)
			(xy 96.925386 -230.823216) (xy 96.933511 -230.874511) (xy 96.93402 -230.900478) (xy 96.933511 -230.926445)
			(xy 97.213167 -230.926445) (xy 97.213167 -230.874511) (xy 97.221292 -230.823216) (xy 97.23734 -230.773823)
			(xy 97.260918 -230.727549) (xy 97.291444 -230.685533) (xy 97.328167 -230.64881) (xy 97.370183 -230.618284)
			(xy 97.416457 -230.594706) (xy 97.46585 -230.578658) (xy 97.517145 -230.570533) (xy 97.569079 -230.570533)
			(xy 97.620374 -230.578658) (xy 97.669767 -230.594706) (xy 97.716041 -230.618284) (xy 97.758057 -230.64881)
			(xy 97.79478 -230.685533) (xy 97.825306 -230.727549) (xy 97.848884 -230.773823) (xy 97.864932 -230.823216)
			(xy 97.873057 -230.874511) (xy 97.873566 -230.900478) (xy 97.873057 -230.926445) (xy 98.153221 -230.926445)
			(xy 98.153221 -230.874511) (xy 98.161346 -230.823216) (xy 98.177394 -230.773823) (xy 98.200972 -230.727549)
			(xy 98.231498 -230.685533) (xy 98.268221 -230.64881) (xy 98.310237 -230.618284) (xy 98.356511 -230.594706)
			(xy 98.405904 -230.578658) (xy 98.457199 -230.570533) (xy 98.509133 -230.570533) (xy 98.560428 -230.578658)
			(xy 98.609821 -230.594706) (xy 98.656095 -230.618284) (xy 98.698111 -230.64881) (xy 98.734834 -230.685533)
			(xy 98.76536 -230.727549) (xy 98.788938 -230.773823) (xy 98.804986 -230.823216) (xy 98.813111 -230.874511)
			(xy 98.81362 -230.900478) (xy 98.813111 -230.926445) (xy 99.093021 -230.926445) (xy 99.093021 -230.874511)
			(xy 99.101146 -230.823216) (xy 99.117194 -230.773823) (xy 99.140772 -230.727549) (xy 99.171298 -230.685533)
			(xy 99.208021 -230.64881) (xy 99.250037 -230.618284) (xy 99.296311 -230.594706) (xy 99.345704 -230.578658)
			(xy 99.396999 -230.570533) (xy 99.448933 -230.570533) (xy 99.500228 -230.578658) (xy 99.549621 -230.594706)
			(xy 99.595895 -230.618284) (xy 99.637911 -230.64881) (xy 99.674634 -230.685533) (xy 99.70516 -230.727549)
			(xy 99.728738 -230.773823) (xy 99.744786 -230.823216) (xy 99.752911 -230.874511) (xy 99.75342 -230.900478)
			(xy 99.752911 -230.926445) (xy 100.032821 -230.926445) (xy 100.032821 -230.874511) (xy 100.040946 -230.823216)
			(xy 100.056994 -230.773823) (xy 100.080572 -230.727549) (xy 100.111098 -230.685533) (xy 100.147821 -230.64881)
			(xy 100.189837 -230.618284) (xy 100.236111 -230.594706) (xy 100.285504 -230.578658) (xy 100.336799 -230.570533)
			(xy 100.388733 -230.570533) (xy 100.440028 -230.578658) (xy 100.489421 -230.594706) (xy 100.535695 -230.618284)
			(xy 100.577711 -230.64881) (xy 100.614434 -230.685533) (xy 100.64496 -230.727549) (xy 100.668538 -230.773823)
			(xy 100.684586 -230.823216) (xy 100.692711 -230.874511) (xy 100.69322 -230.900478) (xy 100.692711 -230.926445)
			(xy 100.972621 -230.926445) (xy 100.972621 -230.874511) (xy 100.980746 -230.823216) (xy 100.996794 -230.773823)
			(xy 101.020372 -230.727549) (xy 101.050898 -230.685533) (xy 101.087621 -230.64881) (xy 101.129637 -230.618284)
			(xy 101.175911 -230.594706) (xy 101.225304 -230.578658) (xy 101.276599 -230.570533) (xy 101.328533 -230.570533)
			(xy 101.379828 -230.578658) (xy 101.429221 -230.594706) (xy 101.475495 -230.618284) (xy 101.517511 -230.64881)
			(xy 101.554234 -230.685533) (xy 101.58476 -230.727549) (xy 101.608338 -230.773823) (xy 101.624386 -230.823216)
			(xy 101.632511 -230.874511) (xy 101.63302 -230.900478) (xy 101.632511 -230.926445) (xy 101.624386 -230.97774)
			(xy 101.608338 -231.027133) (xy 101.58476 -231.073407) (xy 101.554234 -231.115423) (xy 101.517511 -231.152146)
			(xy 101.475495 -231.182672) (xy 101.429221 -231.20625) (xy 101.379828 -231.222298) (xy 101.328533 -231.230423)
			(xy 101.276599 -231.230423) (xy 101.225304 -231.222298) (xy 101.175911 -231.20625) (xy 101.129637 -231.182672)
			(xy 101.087621 -231.152146) (xy 101.050898 -231.115423) (xy 101.020372 -231.073407) (xy 100.996794 -231.027133)
			(xy 100.980746 -230.97774) (xy 100.972621 -230.926445) (xy 100.692711 -230.926445) (xy 100.684586 -230.97774)
			(xy 100.668538 -231.027133) (xy 100.64496 -231.073407) (xy 100.614434 -231.115423) (xy 100.577711 -231.152146)
			(xy 100.535695 -231.182672) (xy 100.489421 -231.20625) (xy 100.440028 -231.222298) (xy 100.388733 -231.230423)
			(xy 100.336799 -231.230423) (xy 100.285504 -231.222298) (xy 100.236111 -231.20625) (xy 100.189837 -231.182672)
			(xy 100.147821 -231.152146) (xy 100.111098 -231.115423) (xy 100.080572 -231.073407) (xy 100.056994 -231.027133)
			(xy 100.040946 -230.97774) (xy 100.032821 -230.926445) (xy 99.752911 -230.926445) (xy 99.744786 -230.97774)
			(xy 99.728738 -231.027133) (xy 99.70516 -231.073407) (xy 99.674634 -231.115423) (xy 99.637911 -231.152146)
			(xy 99.595895 -231.182672) (xy 99.549621 -231.20625) (xy 99.500228 -231.222298) (xy 99.448933 -231.230423)
			(xy 99.396999 -231.230423) (xy 99.345704 -231.222298) (xy 99.296311 -231.20625) (xy 99.250037 -231.182672)
			(xy 99.208021 -231.152146) (xy 99.171298 -231.115423) (xy 99.140772 -231.073407) (xy 99.117194 -231.027133)
			(xy 99.101146 -230.97774) (xy 99.093021 -230.926445) (xy 98.813111 -230.926445) (xy 98.804986 -230.97774)
			(xy 98.788938 -231.027133) (xy 98.76536 -231.073407) (xy 98.734834 -231.115423) (xy 98.698111 -231.152146)
			(xy 98.656095 -231.182672) (xy 98.609821 -231.20625) (xy 98.560428 -231.222298) (xy 98.509133 -231.230423)
			(xy 98.457199 -231.230423) (xy 98.405904 -231.222298) (xy 98.356511 -231.20625) (xy 98.310237 -231.182672)
			(xy 98.268221 -231.152146) (xy 98.231498 -231.115423) (xy 98.200972 -231.073407) (xy 98.177394 -231.027133)
			(xy 98.161346 -230.97774) (xy 98.153221 -230.926445) (xy 97.873057 -230.926445) (xy 97.864932 -230.97774)
			(xy 97.848884 -231.027133) (xy 97.825306 -231.073407) (xy 97.79478 -231.115423) (xy 97.758057 -231.152146)
			(xy 97.716041 -231.182672) (xy 97.669767 -231.20625) (xy 97.620374 -231.222298) (xy 97.569079 -231.230423)
			(xy 97.517145 -231.230423) (xy 97.46585 -231.222298) (xy 97.416457 -231.20625) (xy 97.370183 -231.182672)
			(xy 97.328167 -231.152146) (xy 97.291444 -231.115423) (xy 97.260918 -231.073407) (xy 97.23734 -231.027133)
			(xy 97.221292 -230.97774) (xy 97.213167 -230.926445) (xy 96.933511 -230.926445) (xy 96.925386 -230.97774)
			(xy 96.909338 -231.027133) (xy 96.88576 -231.073407) (xy 96.855234 -231.115423) (xy 96.818511 -231.152146)
			(xy 96.776495 -231.182672) (xy 96.730221 -231.20625) (xy 96.680828 -231.222298) (xy 96.629533 -231.230423)
			(xy 96.577599 -231.230423) (xy 96.526304 -231.222298) (xy 96.476911 -231.20625) (xy 96.430637 -231.182672)
			(xy 96.388621 -231.152146) (xy 96.351898 -231.115423) (xy 96.321372 -231.073407) (xy 96.297794 -231.027133)
			(xy 96.281746 -230.97774) (xy 96.273621 -230.926445) (xy 95.993711 -230.926445) (xy 95.985586 -230.97774)
			(xy 95.969538 -231.027133) (xy 95.94596 -231.073407) (xy 95.915434 -231.115423) (xy 95.878711 -231.152146)
			(xy 95.836695 -231.182672) (xy 95.790421 -231.20625) (xy 95.741028 -231.222298) (xy 95.689733 -231.230423)
			(xy 95.637799 -231.230423) (xy 95.586504 -231.222298) (xy 95.537111 -231.20625) (xy 95.490837 -231.182672)
			(xy 95.448821 -231.152146) (xy 95.412098 -231.115423) (xy 95.381572 -231.073407) (xy 95.357994 -231.027133)
			(xy 95.341946 -230.97774) (xy 95.333821 -230.926445) (xy 95.053911 -230.926445) (xy 95.045786 -230.97774)
			(xy 95.029738 -231.027133) (xy 95.00616 -231.073407) (xy 94.975634 -231.115423) (xy 94.938911 -231.152146)
			(xy 94.896895 -231.182672) (xy 94.850621 -231.20625) (xy 94.801228 -231.222298) (xy 94.749933 -231.230423)
			(xy 94.697999 -231.230423) (xy 94.646704 -231.222298) (xy 94.597311 -231.20625) (xy 94.551037 -231.182672)
			(xy 94.509021 -231.152146) (xy 94.472298 -231.115423) (xy 94.441772 -231.073407) (xy 94.418194 -231.027133)
			(xy 94.402146 -230.97774) (xy 94.394021 -230.926445) (xy 94.114111 -230.926445) (xy 94.105986 -230.97774)
			(xy 94.089938 -231.027133) (xy 94.06636 -231.073407) (xy 94.035834 -231.115423) (xy 93.999111 -231.152146)
			(xy 93.957095 -231.182672) (xy 93.910821 -231.20625) (xy 93.861428 -231.222298) (xy 93.810133 -231.230423)
			(xy 93.758199 -231.230423) (xy 93.706904 -231.222298) (xy 93.657511 -231.20625) (xy 93.611237 -231.182672)
			(xy 93.569221 -231.152146) (xy 93.532498 -231.115423) (xy 93.501972 -231.073407) (xy 93.478394 -231.027133)
			(xy 93.462346 -230.97774) (xy 93.454221 -230.926445) (xy 93.174311 -230.926445) (xy 93.166186 -230.97774)
			(xy 93.150138 -231.027133) (xy 93.12656 -231.073407) (xy 93.096034 -231.115423) (xy 93.059311 -231.152146)
			(xy 93.017295 -231.182672) (xy 92.971021 -231.20625) (xy 92.921628 -231.222298) (xy 92.870333 -231.230423)
			(xy 92.818399 -231.230423) (xy 92.767104 -231.222298) (xy 92.717711 -231.20625) (xy 92.671437 -231.182672)
			(xy 92.629421 -231.152146) (xy 92.592698 -231.115423) (xy 92.562172 -231.073407) (xy 92.538594 -231.027133)
			(xy 92.522546 -230.97774) (xy 92.514421 -230.926445) (xy 92.234847 -230.926445) (xy 92.234847 -230.926493)
			(xy 92.226714 -230.977838) (xy 92.210648 -231.027279) (xy 92.187046 -231.073597) (xy 92.156488 -231.115653)
			(xy 92.119727 -231.15241) (xy 92.077668 -231.182964) (xy 92.031347 -231.206562) (xy 91.981905 -231.222622)
			(xy 91.930559 -231.230749) (xy 91.904566 -231.231186) (xy 91.877643 -231.230655) (xy 91.824507 -231.221934)
			(xy 91.773484 -231.204726) (xy 91.72592 -231.179486) (xy 91.70416 -231.163622) (xy 91.69781 -231.158796)
			(xy 91.66733 -231.147874) (xy 91.661602 -231.14799) (xy 91.650439 -231.150563) (xy 91.645232 -231.152954)
			(xy 91.604846 -231.172512) (xy 91.56192 -231.193086) (xy 91.554123 -231.197644) (xy 91.542156 -231.211155)
			(xy 91.535695 -231.228007) (xy 91.53525 -231.237028) (xy 91.53525 -231.365044) (xy 91.565222 -231.41051)
			(xy 91.577922 -231.416606) (xy 91.601596 -231.428572) (xy 91.645117 -231.458895) (xy 91.683236 -231.495779)
			(xy 91.714976 -231.538277) (xy 91.739521 -231.585299) (xy 91.756243 -231.635637) (xy 91.76471 -231.687999)
			(xy 91.764707 -231.740515) (xy 92.044267 -231.740515) (xy 92.044267 -231.688581) (xy 92.052392 -231.637286)
			(xy 92.06844 -231.587893) (xy 92.092018 -231.541619) (xy 92.122544 -231.499603) (xy 92.159267 -231.46288)
			(xy 92.201283 -231.432354) (xy 92.247557 -231.408776) (xy 92.29695 -231.392728) (xy 92.348245 -231.384603)
			(xy 92.400179 -231.384603) (xy 92.451474 -231.392728) (xy 92.500867 -231.408776) (xy 92.547141 -231.432354)
			(xy 92.589157 -231.46288) (xy 92.62588 -231.499603) (xy 92.656406 -231.541619) (xy 92.679984 -231.587893)
			(xy 92.696032 -231.637286) (xy 92.704157 -231.688581) (xy 92.704666 -231.714548) (xy 92.704157 -231.740515)
			(xy 92.984067 -231.740515) (xy 92.984067 -231.688581) (xy 92.992192 -231.637286) (xy 93.00824 -231.587893)
			(xy 93.031818 -231.541619) (xy 93.062344 -231.499603) (xy 93.099067 -231.46288) (xy 93.141083 -231.432354)
			(xy 93.187357 -231.408776) (xy 93.23675 -231.392728) (xy 93.288045 -231.384603) (xy 93.339979 -231.384603)
			(xy 93.391274 -231.392728) (xy 93.440667 -231.408776) (xy 93.486941 -231.432354) (xy 93.528957 -231.46288)
			(xy 93.56568 -231.499603) (xy 93.596206 -231.541619) (xy 93.619784 -231.587893) (xy 93.635832 -231.637286)
			(xy 93.643957 -231.688581) (xy 93.644466 -231.714548) (xy 93.643957 -231.740515) (xy 93.924121 -231.740515)
			(xy 93.924121 -231.688581) (xy 93.932246 -231.637286) (xy 93.948294 -231.587893) (xy 93.971872 -231.541619)
			(xy 94.002398 -231.499603) (xy 94.039121 -231.46288) (xy 94.081137 -231.432354) (xy 94.127411 -231.408776)
			(xy 94.176804 -231.392728) (xy 94.228099 -231.384603) (xy 94.280033 -231.384603) (xy 94.331328 -231.392728)
			(xy 94.380721 -231.408776) (xy 94.426995 -231.432354) (xy 94.469011 -231.46288) (xy 94.505734 -231.499603)
			(xy 94.53626 -231.541619) (xy 94.559838 -231.587893) (xy 94.575886 -231.637286) (xy 94.584011 -231.688581)
			(xy 94.58452 -231.714548) (xy 94.584011 -231.740515) (xy 94.863667 -231.740515) (xy 94.863667 -231.688581)
			(xy 94.871792 -231.637286) (xy 94.88784 -231.587893) (xy 94.911418 -231.541619) (xy 94.941944 -231.499603)
			(xy 94.978667 -231.46288) (xy 95.020683 -231.432354) (xy 95.066957 -231.408776) (xy 95.11635 -231.392728)
			(xy 95.167645 -231.384603) (xy 95.219579 -231.384603) (xy 95.270874 -231.392728) (xy 95.320267 -231.408776)
			(xy 95.366541 -231.432354) (xy 95.408557 -231.46288) (xy 95.44528 -231.499603) (xy 95.475806 -231.541619)
			(xy 95.499384 -231.587893) (xy 95.515432 -231.637286) (xy 95.523557 -231.688581) (xy 95.524066 -231.714548)
			(xy 95.523557 -231.740515) (xy 95.803467 -231.740515) (xy 95.803467 -231.688581) (xy 95.811592 -231.637286)
			(xy 95.82764 -231.587893) (xy 95.851218 -231.541619) (xy 95.881744 -231.499603) (xy 95.918467 -231.46288)
			(xy 95.960483 -231.432354) (xy 96.006757 -231.408776) (xy 96.05615 -231.392728) (xy 96.107445 -231.384603)
			(xy 96.159379 -231.384603) (xy 96.210674 -231.392728) (xy 96.260067 -231.408776) (xy 96.306341 -231.432354)
			(xy 96.348357 -231.46288) (xy 96.38508 -231.499603) (xy 96.415606 -231.541619) (xy 96.439184 -231.587893)
			(xy 96.455232 -231.637286) (xy 96.463357 -231.688581) (xy 96.463866 -231.714548) (xy 96.463357 -231.740515)
			(xy 96.743267 -231.740515) (xy 96.743267 -231.688581) (xy 96.751392 -231.637286) (xy 96.76744 -231.587893)
			(xy 96.791018 -231.541619) (xy 96.821544 -231.499603) (xy 96.858267 -231.46288) (xy 96.900283 -231.432354)
			(xy 96.946557 -231.408776) (xy 96.99595 -231.392728) (xy 97.047245 -231.384603) (xy 97.099179 -231.384603)
			(xy 97.150474 -231.392728) (xy 97.199867 -231.408776) (xy 97.246141 -231.432354) (xy 97.288157 -231.46288)
			(xy 97.32488 -231.499603) (xy 97.355406 -231.541619) (xy 97.378984 -231.587893) (xy 97.395032 -231.637286)
			(xy 97.403157 -231.688581) (xy 97.403666 -231.714548) (xy 97.403157 -231.740515) (xy 97.683067 -231.740515)
			(xy 97.683067 -231.688581) (xy 97.691192 -231.637286) (xy 97.70724 -231.587893) (xy 97.730818 -231.541619)
			(xy 97.761344 -231.499603) (xy 97.798067 -231.46288) (xy 97.840083 -231.432354) (xy 97.886357 -231.408776)
			(xy 97.93575 -231.392728) (xy 97.987045 -231.384603) (xy 98.038979 -231.384603) (xy 98.090274 -231.392728)
			(xy 98.139667 -231.408776) (xy 98.185941 -231.432354) (xy 98.227957 -231.46288) (xy 98.26468 -231.499603)
			(xy 98.295206 -231.541619) (xy 98.318784 -231.587893) (xy 98.334832 -231.637286) (xy 98.342957 -231.688581)
			(xy 98.343466 -231.714548) (xy 98.342957 -231.740515) (xy 98.622867 -231.740515) (xy 98.622867 -231.688581)
			(xy 98.630992 -231.637286) (xy 98.64704 -231.587893) (xy 98.670618 -231.541619) (xy 98.701144 -231.499603)
			(xy 98.737867 -231.46288) (xy 98.779883 -231.432354) (xy 98.826157 -231.408776) (xy 98.87555 -231.392728)
			(xy 98.926845 -231.384603) (xy 98.978779 -231.384603) (xy 99.030074 -231.392728) (xy 99.079467 -231.408776)
			(xy 99.125741 -231.432354) (xy 99.167757 -231.46288) (xy 99.20448 -231.499603) (xy 99.235006 -231.541619)
			(xy 99.258584 -231.587893) (xy 99.274632 -231.637286) (xy 99.282757 -231.688581) (xy 99.283266 -231.714548)
			(xy 99.282757 -231.740515) (xy 99.562667 -231.740515) (xy 99.562667 -231.688581) (xy 99.570792 -231.637286)
			(xy 99.58684 -231.587893) (xy 99.610418 -231.541619) (xy 99.640944 -231.499603) (xy 99.677667 -231.46288)
			(xy 99.719683 -231.432354) (xy 99.765957 -231.408776) (xy 99.81535 -231.392728) (xy 99.866645 -231.384603)
			(xy 99.918579 -231.384603) (xy 99.969874 -231.392728) (xy 100.019267 -231.408776) (xy 100.065541 -231.432354)
			(xy 100.107557 -231.46288) (xy 100.14428 -231.499603) (xy 100.174806 -231.541619) (xy 100.198384 -231.587893)
			(xy 100.214432 -231.637286) (xy 100.222557 -231.688581) (xy 100.223066 -231.714548) (xy 100.222557 -231.740515)
			(xy 100.502721 -231.740515) (xy 100.502721 -231.688581) (xy 100.510846 -231.637286) (xy 100.526894 -231.587893)
			(xy 100.550472 -231.541619) (xy 100.580998 -231.499603) (xy 100.617721 -231.46288) (xy 100.659737 -231.432354)
			(xy 100.706011 -231.408776) (xy 100.755404 -231.392728) (xy 100.806699 -231.384603) (xy 100.858633 -231.384603)
			(xy 100.909928 -231.392728) (xy 100.959321 -231.408776) (xy 101.005595 -231.432354) (xy 101.047611 -231.46288)
			(xy 101.084334 -231.499603) (xy 101.11486 -231.541619) (xy 101.138438 -231.587893) (xy 101.154486 -231.637286)
			(xy 101.162611 -231.688581) (xy 101.16312 -231.714548) (xy 101.162611 -231.740515) (xy 101.154486 -231.79181)
			(xy 101.138438 -231.841203) (xy 101.11486 -231.887477) (xy 101.084334 -231.929493) (xy 101.047611 -231.966216)
			(xy 101.005595 -231.996742) (xy 100.959321 -232.02032) (xy 100.909928 -232.036368) (xy 100.858633 -232.044493)
			(xy 100.806699 -232.044493) (xy 100.755404 -232.036368) (xy 100.706011 -232.02032) (xy 100.659737 -231.996742)
			(xy 100.617721 -231.966216) (xy 100.580998 -231.929493) (xy 100.550472 -231.887477) (xy 100.526894 -231.841203)
			(xy 100.510846 -231.79181) (xy 100.502721 -231.740515) (xy 100.222557 -231.740515) (xy 100.214432 -231.79181)
			(xy 100.198384 -231.841203) (xy 100.174806 -231.887477) (xy 100.14428 -231.929493) (xy 100.107557 -231.966216)
			(xy 100.065541 -231.996742) (xy 100.019267 -232.02032) (xy 99.969874 -232.036368) (xy 99.918579 -232.044493)
			(xy 99.866645 -232.044493) (xy 99.81535 -232.036368) (xy 99.765957 -232.02032) (xy 99.719683 -231.996742)
			(xy 99.677667 -231.966216) (xy 99.640944 -231.929493) (xy 99.610418 -231.887477) (xy 99.58684 -231.841203)
			(xy 99.570792 -231.79181) (xy 99.562667 -231.740515) (xy 99.282757 -231.740515) (xy 99.274632 -231.79181)
			(xy 99.258584 -231.841203) (xy 99.235006 -231.887477) (xy 99.20448 -231.929493) (xy 99.167757 -231.966216)
			(xy 99.125741 -231.996742) (xy 99.079467 -232.02032) (xy 99.030074 -232.036368) (xy 98.978779 -232.044493)
			(xy 98.926845 -232.044493) (xy 98.87555 -232.036368) (xy 98.826157 -232.02032) (xy 98.779883 -231.996742)
			(xy 98.737867 -231.966216) (xy 98.701144 -231.929493) (xy 98.670618 -231.887477) (xy 98.64704 -231.841203)
			(xy 98.630992 -231.79181) (xy 98.622867 -231.740515) (xy 98.342957 -231.740515) (xy 98.334832 -231.79181)
			(xy 98.318784 -231.841203) (xy 98.295206 -231.887477) (xy 98.26468 -231.929493) (xy 98.227957 -231.966216)
			(xy 98.185941 -231.996742) (xy 98.139667 -232.02032) (xy 98.090274 -232.036368) (xy 98.038979 -232.044493)
			(xy 97.987045 -232.044493) (xy 97.93575 -232.036368) (xy 97.886357 -232.02032) (xy 97.840083 -231.996742)
			(xy 97.798067 -231.966216) (xy 97.761344 -231.929493) (xy 97.730818 -231.887477) (xy 97.70724 -231.841203)
			(xy 97.691192 -231.79181) (xy 97.683067 -231.740515) (xy 97.403157 -231.740515) (xy 97.395032 -231.79181)
			(xy 97.378984 -231.841203) (xy 97.355406 -231.887477) (xy 97.32488 -231.929493) (xy 97.288157 -231.966216)
			(xy 97.246141 -231.996742) (xy 97.199867 -232.02032) (xy 97.150474 -232.036368) (xy 97.099179 -232.044493)
			(xy 97.047245 -232.044493) (xy 96.99595 -232.036368) (xy 96.946557 -232.02032) (xy 96.900283 -231.996742)
			(xy 96.858267 -231.966216) (xy 96.821544 -231.929493) (xy 96.791018 -231.887477) (xy 96.76744 -231.841203)
			(xy 96.751392 -231.79181) (xy 96.743267 -231.740515) (xy 96.463357 -231.740515) (xy 96.455232 -231.79181)
			(xy 96.439184 -231.841203) (xy 96.415606 -231.887477) (xy 96.38508 -231.929493) (xy 96.348357 -231.966216)
			(xy 96.306341 -231.996742) (xy 96.260067 -232.02032) (xy 96.210674 -232.036368) (xy 96.159379 -232.044493)
			(xy 96.107445 -232.044493) (xy 96.05615 -232.036368) (xy 96.006757 -232.02032) (xy 95.960483 -231.996742)
			(xy 95.918467 -231.966216) (xy 95.881744 -231.929493) (xy 95.851218 -231.887477) (xy 95.82764 -231.841203)
			(xy 95.811592 -231.79181) (xy 95.803467 -231.740515) (xy 95.523557 -231.740515) (xy 95.515432 -231.79181)
			(xy 95.499384 -231.841203) (xy 95.475806 -231.887477) (xy 95.44528 -231.929493) (xy 95.408557 -231.966216)
			(xy 95.366541 -231.996742) (xy 95.320267 -232.02032) (xy 95.270874 -232.036368) (xy 95.219579 -232.044493)
			(xy 95.167645 -232.044493) (xy 95.11635 -232.036368) (xy 95.066957 -232.02032) (xy 95.020683 -231.996742)
			(xy 94.978667 -231.966216) (xy 94.941944 -231.929493) (xy 94.911418 -231.887477) (xy 94.88784 -231.841203)
			(xy 94.871792 -231.79181) (xy 94.863667 -231.740515) (xy 94.584011 -231.740515) (xy 94.575886 -231.79181)
			(xy 94.559838 -231.841203) (xy 94.53626 -231.887477) (xy 94.505734 -231.929493) (xy 94.469011 -231.966216)
			(xy 94.426995 -231.996742) (xy 94.380721 -232.02032) (xy 94.331328 -232.036368) (xy 94.280033 -232.044493)
			(xy 94.228099 -232.044493) (xy 94.176804 -232.036368) (xy 94.127411 -232.02032) (xy 94.081137 -231.996742)
			(xy 94.039121 -231.966216) (xy 94.002398 -231.929493) (xy 93.971872 -231.887477) (xy 93.948294 -231.841203)
			(xy 93.932246 -231.79181) (xy 93.924121 -231.740515) (xy 93.643957 -231.740515) (xy 93.635832 -231.79181)
			(xy 93.619784 -231.841203) (xy 93.596206 -231.887477) (xy 93.56568 -231.929493) (xy 93.528957 -231.966216)
			(xy 93.486941 -231.996742) (xy 93.440667 -232.02032) (xy 93.391274 -232.036368) (xy 93.339979 -232.044493)
			(xy 93.288045 -232.044493) (xy 93.23675 -232.036368) (xy 93.187357 -232.02032) (xy 93.141083 -231.996742)
			(xy 93.099067 -231.966216) (xy 93.062344 -231.929493) (xy 93.031818 -231.887477) (xy 93.00824 -231.841203)
			(xy 92.992192 -231.79181) (xy 92.984067 -231.740515) (xy 92.704157 -231.740515) (xy 92.696032 -231.79181)
			(xy 92.679984 -231.841203) (xy 92.656406 -231.887477) (xy 92.62588 -231.929493) (xy 92.589157 -231.966216)
			(xy 92.547141 -231.996742) (xy 92.500867 -232.02032) (xy 92.451474 -232.036368) (xy 92.400179 -232.044493)
			(xy 92.348245 -232.044493) (xy 92.29695 -232.036368) (xy 92.247557 -232.02032) (xy 92.201283 -231.996742)
			(xy 92.159267 -231.966216) (xy 92.122544 -231.929493) (xy 92.092018 -231.887477) (xy 92.06844 -231.841203)
			(xy 92.052392 -231.79181) (xy 92.044267 -231.740515) (xy 91.764707 -231.740515) (xy 91.764707 -231.741042)
			(xy 91.756233 -231.793403) (xy 91.739505 -231.843739) (xy 91.714954 -231.890758) (xy 91.683209 -231.933252)
			(xy 91.645085 -231.970131) (xy 91.60156 -232.000449) (xy 91.577922 -232.01249) (xy 91.565222 -232.018586)
			(xy 91.53525 -232.064052) (xy 91.53525 -232.19156) (xy 91.535719 -232.200736) (xy 91.542381 -232.217843)
			(xy 91.5547 -232.231455) (xy 91.562682 -232.23601) (xy 91.648026 -232.277158) (xy 91.652482 -232.278812)
			(xy 91.661816 -232.280597) (xy 91.666568 -232.280714) (xy 91.69781 -232.269792) (xy 91.70416 -232.264966)
			(xy 91.725893 -232.249137) (xy 91.773414 -232.22399) (xy 91.824372 -232.20685) (xy 91.87743 -232.198166)
			(xy 91.904312 -232.197656) (xy 91.930301 -232.198167) (xy 91.98164 -232.2063) (xy 92.031074 -232.222363)
			(xy 92.077387 -232.245962) (xy 92.119438 -232.276516) (xy 92.156192 -232.313271) (xy 92.186744 -232.355323)
			(xy 92.210341 -232.401637) (xy 92.226403 -232.451072) (xy 92.234534 -232.502411) (xy 92.234534 -232.554331)
			(xy 92.514421 -232.554331) (xy 92.514421 -232.502397) (xy 92.522546 -232.451102) (xy 92.538594 -232.401709)
			(xy 92.562172 -232.355435) (xy 92.592698 -232.313419) (xy 92.629421 -232.276696) (xy 92.671437 -232.24617)
			(xy 92.717711 -232.222592) (xy 92.767104 -232.206544) (xy 92.818399 -232.198419) (xy 92.870333 -232.198419)
			(xy 92.921628 -232.206544) (xy 92.971021 -232.222592) (xy 93.017295 -232.24617) (xy 93.059311 -232.276696)
			(xy 93.096034 -232.313419) (xy 93.12656 -232.355435) (xy 93.150138 -232.401709) (xy 93.166186 -232.451102)
			(xy 93.174311 -232.502397) (xy 93.17482 -232.528364) (xy 93.174311 -232.554331) (xy 93.454221 -232.554331)
			(xy 93.454221 -232.502397) (xy 93.462346 -232.451102) (xy 93.478394 -232.401709) (xy 93.501972 -232.355435)
			(xy 93.532498 -232.313419) (xy 93.569221 -232.276696) (xy 93.611237 -232.24617) (xy 93.657511 -232.222592)
			(xy 93.706904 -232.206544) (xy 93.758199 -232.198419) (xy 93.810133 -232.198419) (xy 93.861428 -232.206544)
			(xy 93.910821 -232.222592) (xy 93.957095 -232.24617) (xy 93.999111 -232.276696) (xy 94.035834 -232.313419)
			(xy 94.06636 -232.355435) (xy 94.089938 -232.401709) (xy 94.105986 -232.451102) (xy 94.114111 -232.502397)
			(xy 94.11462 -232.528364) (xy 94.114111 -232.554331) (xy 94.394021 -232.554331) (xy 94.394021 -232.502397)
			(xy 94.402146 -232.451102) (xy 94.418194 -232.401709) (xy 94.441772 -232.355435) (xy 94.472298 -232.313419)
			(xy 94.509021 -232.276696) (xy 94.551037 -232.24617) (xy 94.597311 -232.222592) (xy 94.646704 -232.206544)
			(xy 94.697999 -232.198419) (xy 94.749933 -232.198419) (xy 94.801228 -232.206544) (xy 94.850621 -232.222592)
			(xy 94.896895 -232.24617) (xy 94.938911 -232.276696) (xy 94.975634 -232.313419) (xy 95.00616 -232.355435)
			(xy 95.029738 -232.401709) (xy 95.045786 -232.451102) (xy 95.053911 -232.502397) (xy 95.05442 -232.528364)
			(xy 95.053911 -232.554331) (xy 95.333821 -232.554331) (xy 95.333821 -232.502397) (xy 95.341946 -232.451102)
			(xy 95.357994 -232.401709) (xy 95.381572 -232.355435) (xy 95.412098 -232.313419) (xy 95.448821 -232.276696)
			(xy 95.490837 -232.24617) (xy 95.537111 -232.222592) (xy 95.586504 -232.206544) (xy 95.637799 -232.198419)
			(xy 95.689733 -232.198419) (xy 95.741028 -232.206544) (xy 95.790421 -232.222592) (xy 95.836695 -232.24617)
			(xy 95.878711 -232.276696) (xy 95.915434 -232.313419) (xy 95.94596 -232.355435) (xy 95.969538 -232.401709)
			(xy 95.985586 -232.451102) (xy 95.993711 -232.502397) (xy 95.99422 -232.528364) (xy 95.993711 -232.554331)
			(xy 96.273621 -232.554331) (xy 96.273621 -232.502397) (xy 96.281746 -232.451102) (xy 96.297794 -232.401709)
			(xy 96.321372 -232.355435) (xy 96.351898 -232.313419) (xy 96.388621 -232.276696) (xy 96.430637 -232.24617)
			(xy 96.476911 -232.222592) (xy 96.526304 -232.206544) (xy 96.577599 -232.198419) (xy 96.629533 -232.198419)
			(xy 96.680828 -232.206544) (xy 96.730221 -232.222592) (xy 96.776495 -232.24617) (xy 96.818511 -232.276696)
			(xy 96.855234 -232.313419) (xy 96.88576 -232.355435) (xy 96.909338 -232.401709) (xy 96.925386 -232.451102)
			(xy 96.933511 -232.502397) (xy 96.93402 -232.528364) (xy 96.933511 -232.554331) (xy 97.213421 -232.554331)
			(xy 97.213421 -232.502397) (xy 97.221546 -232.451102) (xy 97.237594 -232.401709) (xy 97.261172 -232.355435)
			(xy 97.291698 -232.313419) (xy 97.328421 -232.276696) (xy 97.370437 -232.24617) (xy 97.416711 -232.222592)
			(xy 97.466104 -232.206544) (xy 97.517399 -232.198419) (xy 97.569333 -232.198419) (xy 97.620628 -232.206544)
			(xy 97.670021 -232.222592) (xy 97.716295 -232.24617) (xy 97.758311 -232.276696) (xy 97.795034 -232.313419)
			(xy 97.82556 -232.355435) (xy 97.849138 -232.401709) (xy 97.865186 -232.451102) (xy 97.873311 -232.502397)
			(xy 97.87382 -232.528364) (xy 97.873311 -232.554331) (xy 98.152967 -232.554331) (xy 98.152967 -232.502397)
			(xy 98.161092 -232.451102) (xy 98.17714 -232.401709) (xy 98.200718 -232.355435) (xy 98.231244 -232.313419)
			(xy 98.267967 -232.276696) (xy 98.309983 -232.24617) (xy 98.356257 -232.222592) (xy 98.40565 -232.206544)
			(xy 98.456945 -232.198419) (xy 98.508879 -232.198419) (xy 98.560174 -232.206544) (xy 98.609567 -232.222592)
			(xy 98.655841 -232.24617) (xy 98.697857 -232.276696) (xy 98.73458 -232.313419) (xy 98.765106 -232.355435)
			(xy 98.788684 -232.401709) (xy 98.804732 -232.451102) (xy 98.812857 -232.502397) (xy 98.813366 -232.528364)
			(xy 98.812857 -232.554331) (xy 99.093021 -232.554331) (xy 99.093021 -232.502397) (xy 99.101146 -232.451102)
			(xy 99.117194 -232.401709) (xy 99.140772 -232.355435) (xy 99.171298 -232.313419) (xy 99.208021 -232.276696)
			(xy 99.250037 -232.24617) (xy 99.296311 -232.222592) (xy 99.345704 -232.206544) (xy 99.396999 -232.198419)
			(xy 99.448933 -232.198419) (xy 99.500228 -232.206544) (xy 99.549621 -232.222592) (xy 99.595895 -232.24617)
			(xy 99.637911 -232.276696) (xy 99.674634 -232.313419) (xy 99.70516 -232.355435) (xy 99.728738 -232.401709)
			(xy 99.744786 -232.451102) (xy 99.752911 -232.502397) (xy 99.75342 -232.528364) (xy 99.752911 -232.554331)
			(xy 100.032821 -232.554331) (xy 100.032821 -232.502397) (xy 100.040946 -232.451102) (xy 100.056994 -232.401709)
			(xy 100.080572 -232.355435) (xy 100.111098 -232.313419) (xy 100.147821 -232.276696) (xy 100.189837 -232.24617)
			(xy 100.236111 -232.222592) (xy 100.285504 -232.206544) (xy 100.336799 -232.198419) (xy 100.388733 -232.198419)
			(xy 100.440028 -232.206544) (xy 100.489421 -232.222592) (xy 100.535695 -232.24617) (xy 100.577711 -232.276696)
			(xy 100.614434 -232.313419) (xy 100.64496 -232.355435) (xy 100.668538 -232.401709) (xy 100.684586 -232.451102)
			(xy 100.692711 -232.502397) (xy 100.69322 -232.528364) (xy 100.692711 -232.554331) (xy 100.684586 -232.605626)
			(xy 100.668538 -232.655019) (xy 100.64496 -232.701293) (xy 100.614434 -232.743309) (xy 100.577711 -232.780032)
			(xy 100.535695 -232.810558) (xy 100.489421 -232.834136) (xy 100.440028 -232.850184) (xy 100.388733 -232.858309)
			(xy 100.336799 -232.858309) (xy 100.285504 -232.850184) (xy 100.236111 -232.834136) (xy 100.189837 -232.810558)
			(xy 100.147821 -232.780032) (xy 100.111098 -232.743309) (xy 100.080572 -232.701293) (xy 100.056994 -232.655019)
			(xy 100.040946 -232.605626) (xy 100.032821 -232.554331) (xy 99.752911 -232.554331) (xy 99.744786 -232.605626)
			(xy 99.728738 -232.655019) (xy 99.70516 -232.701293) (xy 99.674634 -232.743309) (xy 99.637911 -232.780032)
			(xy 99.595895 -232.810558) (xy 99.549621 -232.834136) (xy 99.500228 -232.850184) (xy 99.448933 -232.858309)
			(xy 99.396999 -232.858309) (xy 99.345704 -232.850184) (xy 99.296311 -232.834136) (xy 99.250037 -232.810558)
			(xy 99.208021 -232.780032) (xy 99.171298 -232.743309) (xy 99.140772 -232.701293) (xy 99.117194 -232.655019)
			(xy 99.101146 -232.605626) (xy 99.093021 -232.554331) (xy 98.812857 -232.554331) (xy 98.804732 -232.605626)
			(xy 98.788684 -232.655019) (xy 98.765106 -232.701293) (xy 98.73458 -232.743309) (xy 98.697857 -232.780032)
			(xy 98.655841 -232.810558) (xy 98.609567 -232.834136) (xy 98.560174 -232.850184) (xy 98.508879 -232.858309)
			(xy 98.456945 -232.858309) (xy 98.40565 -232.850184) (xy 98.356257 -232.834136) (xy 98.309983 -232.810558)
			(xy 98.267967 -232.780032) (xy 98.231244 -232.743309) (xy 98.200718 -232.701293) (xy 98.17714 -232.655019)
			(xy 98.161092 -232.605626) (xy 98.152967 -232.554331) (xy 97.873311 -232.554331) (xy 97.865186 -232.605626)
			(xy 97.849138 -232.655019) (xy 97.82556 -232.701293) (xy 97.795034 -232.743309) (xy 97.758311 -232.780032)
			(xy 97.716295 -232.810558) (xy 97.670021 -232.834136) (xy 97.620628 -232.850184) (xy 97.569333 -232.858309)
			(xy 97.517399 -232.858309) (xy 97.466104 -232.850184) (xy 97.416711 -232.834136) (xy 97.370437 -232.810558)
			(xy 97.328421 -232.780032) (xy 97.291698 -232.743309) (xy 97.261172 -232.701293) (xy 97.237594 -232.655019)
			(xy 97.221546 -232.605626) (xy 97.213421 -232.554331) (xy 96.933511 -232.554331) (xy 96.925386 -232.605626)
			(xy 96.909338 -232.655019) (xy 96.88576 -232.701293) (xy 96.855234 -232.743309) (xy 96.818511 -232.780032)
			(xy 96.776495 -232.810558) (xy 96.730221 -232.834136) (xy 96.680828 -232.850184) (xy 96.629533 -232.858309)
			(xy 96.577599 -232.858309) (xy 96.526304 -232.850184) (xy 96.476911 -232.834136) (xy 96.430637 -232.810558)
			(xy 96.388621 -232.780032) (xy 96.351898 -232.743309) (xy 96.321372 -232.701293) (xy 96.297794 -232.655019)
			(xy 96.281746 -232.605626) (xy 96.273621 -232.554331) (xy 95.993711 -232.554331) (xy 95.985586 -232.605626)
			(xy 95.969538 -232.655019) (xy 95.94596 -232.701293) (xy 95.915434 -232.743309) (xy 95.878711 -232.780032)
			(xy 95.836695 -232.810558) (xy 95.790421 -232.834136) (xy 95.741028 -232.850184) (xy 95.689733 -232.858309)
			(xy 95.637799 -232.858309) (xy 95.586504 -232.850184) (xy 95.537111 -232.834136) (xy 95.490837 -232.810558)
			(xy 95.448821 -232.780032) (xy 95.412098 -232.743309) (xy 95.381572 -232.701293) (xy 95.357994 -232.655019)
			(xy 95.341946 -232.605626) (xy 95.333821 -232.554331) (xy 95.053911 -232.554331) (xy 95.045786 -232.605626)
			(xy 95.029738 -232.655019) (xy 95.00616 -232.701293) (xy 94.975634 -232.743309) (xy 94.938911 -232.780032)
			(xy 94.896895 -232.810558) (xy 94.850621 -232.834136) (xy 94.801228 -232.850184) (xy 94.749933 -232.858309)
			(xy 94.697999 -232.858309) (xy 94.646704 -232.850184) (xy 94.597311 -232.834136) (xy 94.551037 -232.810558)
			(xy 94.509021 -232.780032) (xy 94.472298 -232.743309) (xy 94.441772 -232.701293) (xy 94.418194 -232.655019)
			(xy 94.402146 -232.605626) (xy 94.394021 -232.554331) (xy 94.114111 -232.554331) (xy 94.105986 -232.605626)
			(xy 94.089938 -232.655019) (xy 94.06636 -232.701293) (xy 94.035834 -232.743309) (xy 93.999111 -232.780032)
			(xy 93.957095 -232.810558) (xy 93.910821 -232.834136) (xy 93.861428 -232.850184) (xy 93.810133 -232.858309)
			(xy 93.758199 -232.858309) (xy 93.706904 -232.850184) (xy 93.657511 -232.834136) (xy 93.611237 -232.810558)
			(xy 93.569221 -232.780032) (xy 93.532498 -232.743309) (xy 93.501972 -232.701293) (xy 93.478394 -232.655019)
			(xy 93.462346 -232.605626) (xy 93.454221 -232.554331) (xy 93.174311 -232.554331) (xy 93.166186 -232.605626)
			(xy 93.150138 -232.655019) (xy 93.12656 -232.701293) (xy 93.096034 -232.743309) (xy 93.059311 -232.780032)
			(xy 93.017295 -232.810558) (xy 92.971021 -232.834136) (xy 92.921628 -232.850184) (xy 92.870333 -232.858309)
			(xy 92.818399 -232.858309) (xy 92.767104 -232.850184) (xy 92.717711 -232.834136) (xy 92.671437 -232.810558)
			(xy 92.629421 -232.780032) (xy 92.592698 -232.743309) (xy 92.562172 -232.701293) (xy 92.538594 -232.655019)
			(xy 92.522546 -232.605626) (xy 92.514421 -232.554331) (xy 92.234534 -232.554331) (xy 92.234534 -232.554389)
			(xy 92.226403 -232.605728) (xy 92.210341 -232.655163) (xy 92.186744 -232.701477) (xy 92.156192 -232.743529)
			(xy 92.119438 -232.780284) (xy 92.077387 -232.810838) (xy 92.031074 -232.834437) (xy 91.98164 -232.8505)
			(xy 91.930301 -232.858633) (xy 91.904312 -232.859072) (xy 91.87743 -232.85855) (xy 91.824372 -232.84987)
			(xy 91.773412 -232.832736) (xy 91.725888 -232.807598) (xy 91.70416 -232.791762) (xy 91.69781 -232.786936)
			(xy 91.666568 -232.776014) (xy 91.661816 -232.776128) (xy 91.652484 -232.777921) (xy 91.648026 -232.77957)
			(xy 91.562682 -232.820718) (xy 91.554667 -232.825229) (xy 91.542327 -232.838845) (xy 91.535691 -232.855981)
			(xy 91.53525 -232.865168) (xy 91.53525 -232.992422) (xy 91.565222 -233.037888) (xy 91.577922 -233.043984)
			(xy 91.601629 -233.055955) (xy 91.645212 -233.086297) (xy 91.683388 -233.123212) (xy 91.715177 -233.165751)
			(xy 91.739762 -233.212822) (xy 91.756512 -233.263216) (xy 91.764997 -233.315639) (xy 91.764998 -233.368147)
			(xy 92.044267 -233.368147) (xy 92.044267 -233.316213) (xy 92.052392 -233.264918) (xy 92.06844 -233.215525)
			(xy 92.092018 -233.169251) (xy 92.122544 -233.127235) (xy 92.159267 -233.090512) (xy 92.201283 -233.059986)
			(xy 92.247557 -233.036408) (xy 92.29695 -233.02036) (xy 92.348245 -233.012235) (xy 92.400179 -233.012235)
			(xy 92.451474 -233.02036) (xy 92.500867 -233.036408) (xy 92.547141 -233.059986) (xy 92.589157 -233.090512)
			(xy 92.62588 -233.127235) (xy 92.656406 -233.169251) (xy 92.679984 -233.215525) (xy 92.696032 -233.264918)
			(xy 92.704157 -233.316213) (xy 92.704666 -233.34218) (xy 92.704157 -233.368147) (xy 92.984067 -233.368147)
			(xy 92.984067 -233.316213) (xy 92.992192 -233.264918) (xy 93.00824 -233.215525) (xy 93.031818 -233.169251)
			(xy 93.062344 -233.127235) (xy 93.099067 -233.090512) (xy 93.141083 -233.059986) (xy 93.187357 -233.036408)
			(xy 93.23675 -233.02036) (xy 93.288045 -233.012235) (xy 93.339979 -233.012235) (xy 93.391274 -233.02036)
			(xy 93.440667 -233.036408) (xy 93.486941 -233.059986) (xy 93.528957 -233.090512) (xy 93.56568 -233.127235)
			(xy 93.596206 -233.169251) (xy 93.619784 -233.215525) (xy 93.635832 -233.264918) (xy 93.643957 -233.316213)
			(xy 93.644466 -233.34218) (xy 93.643957 -233.368147) (xy 93.923867 -233.368147) (xy 93.923867 -233.316213)
			(xy 93.931992 -233.264918) (xy 93.94804 -233.215525) (xy 93.971618 -233.169251) (xy 94.002144 -233.127235)
			(xy 94.038867 -233.090512) (xy 94.080883 -233.059986) (xy 94.127157 -233.036408) (xy 94.17655 -233.02036)
			(xy 94.227845 -233.012235) (xy 94.279779 -233.012235) (xy 94.331074 -233.02036) (xy 94.380467 -233.036408)
			(xy 94.426741 -233.059986) (xy 94.468757 -233.090512) (xy 94.50548 -233.127235) (xy 94.536006 -233.169251)
			(xy 94.559584 -233.215525) (xy 94.575632 -233.264918) (xy 94.583757 -233.316213) (xy 94.584266 -233.34218)
			(xy 94.583757 -233.368147) (xy 94.863667 -233.368147) (xy 94.863667 -233.316213) (xy 94.871792 -233.264918)
			(xy 94.88784 -233.215525) (xy 94.911418 -233.169251) (xy 94.941944 -233.127235) (xy 94.978667 -233.090512)
			(xy 95.020683 -233.059986) (xy 95.066957 -233.036408) (xy 95.11635 -233.02036) (xy 95.167645 -233.012235)
			(xy 95.219579 -233.012235) (xy 95.270874 -233.02036) (xy 95.320267 -233.036408) (xy 95.366541 -233.059986)
			(xy 95.408557 -233.090512) (xy 95.44528 -233.127235) (xy 95.475806 -233.169251) (xy 95.499384 -233.215525)
			(xy 95.515432 -233.264918) (xy 95.523557 -233.316213) (xy 95.524066 -233.34218) (xy 95.523557 -233.368147)
			(xy 95.803467 -233.368147) (xy 95.803467 -233.316213) (xy 95.811592 -233.264918) (xy 95.82764 -233.215525)
			(xy 95.851218 -233.169251) (xy 95.881744 -233.127235) (xy 95.918467 -233.090512) (xy 95.960483 -233.059986)
			(xy 96.006757 -233.036408) (xy 96.05615 -233.02036) (xy 96.107445 -233.012235) (xy 96.159379 -233.012235)
			(xy 96.210674 -233.02036) (xy 96.260067 -233.036408) (xy 96.306341 -233.059986) (xy 96.348357 -233.090512)
			(xy 96.38508 -233.127235) (xy 96.415606 -233.169251) (xy 96.439184 -233.215525) (xy 96.455232 -233.264918)
			(xy 96.463357 -233.316213) (xy 96.463866 -233.34218) (xy 96.463357 -233.368147) (xy 96.743267 -233.368147)
			(xy 96.743267 -233.316213) (xy 96.751392 -233.264918) (xy 96.76744 -233.215525) (xy 96.791018 -233.169251)
			(xy 96.821544 -233.127235) (xy 96.858267 -233.090512) (xy 96.900283 -233.059986) (xy 96.946557 -233.036408)
			(xy 96.99595 -233.02036) (xy 97.047245 -233.012235) (xy 97.099179 -233.012235) (xy 97.150474 -233.02036)
			(xy 97.199867 -233.036408) (xy 97.246141 -233.059986) (xy 97.288157 -233.090512) (xy 97.32488 -233.127235)
			(xy 97.355406 -233.169251) (xy 97.378984 -233.215525) (xy 97.395032 -233.264918) (xy 97.403157 -233.316213)
			(xy 97.403666 -233.34218) (xy 97.403157 -233.368147) (xy 97.683321 -233.368147) (xy 97.683321 -233.316213)
			(xy 97.691446 -233.264918) (xy 97.707494 -233.215525) (xy 97.731072 -233.169251) (xy 97.761598 -233.127235)
			(xy 97.798321 -233.090512) (xy 97.840337 -233.059986) (xy 97.886611 -233.036408) (xy 97.936004 -233.02036)
			(xy 97.987299 -233.012235) (xy 98.039233 -233.012235) (xy 98.090528 -233.02036) (xy 98.139921 -233.036408)
			(xy 98.186195 -233.059986) (xy 98.228211 -233.090512) (xy 98.264934 -233.127235) (xy 98.29546 -233.169251)
			(xy 98.319038 -233.215525) (xy 98.335086 -233.264918) (xy 98.343211 -233.316213) (xy 98.34372 -233.34218)
			(xy 98.343211 -233.368147) (xy 98.622867 -233.368147) (xy 98.622867 -233.316213) (xy 98.630992 -233.264918)
			(xy 98.64704 -233.215525) (xy 98.670618 -233.169251) (xy 98.701144 -233.127235) (xy 98.737867 -233.090512)
			(xy 98.779883 -233.059986) (xy 98.826157 -233.036408) (xy 98.87555 -233.02036) (xy 98.926845 -233.012235)
			(xy 98.978779 -233.012235) (xy 99.030074 -233.02036) (xy 99.079467 -233.036408) (xy 99.125741 -233.059986)
			(xy 99.167757 -233.090512) (xy 99.20448 -233.127235) (xy 99.235006 -233.169251) (xy 99.258584 -233.215525)
			(xy 99.274632 -233.264918) (xy 99.282757 -233.316213) (xy 99.283266 -233.34218) (xy 99.282757 -233.368147)
			(xy 99.562667 -233.368147) (xy 99.562667 -233.316213) (xy 99.570792 -233.264918) (xy 99.58684 -233.215525)
			(xy 99.610418 -233.169251) (xy 99.640944 -233.127235) (xy 99.677667 -233.090512) (xy 99.719683 -233.059986)
			(xy 99.765957 -233.036408) (xy 99.81535 -233.02036) (xy 99.866645 -233.012235) (xy 99.918579 -233.012235)
			(xy 99.969874 -233.02036) (xy 100.019267 -233.036408) (xy 100.065541 -233.059986) (xy 100.107557 -233.090512)
			(xy 100.14428 -233.127235) (xy 100.174806 -233.169251) (xy 100.198384 -233.215525) (xy 100.214432 -233.264918)
			(xy 100.222557 -233.316213) (xy 100.223066 -233.34218) (xy 100.222557 -233.368147) (xy 100.502467 -233.368147)
			(xy 100.502467 -233.316213) (xy 100.510592 -233.264918) (xy 100.52664 -233.215525) (xy 100.550218 -233.169251)
			(xy 100.580744 -233.127235) (xy 100.617467 -233.090512) (xy 100.659483 -233.059986) (xy 100.705757 -233.036408)
			(xy 100.75515 -233.02036) (xy 100.806445 -233.012235) (xy 100.858379 -233.012235) (xy 100.909674 -233.02036)
			(xy 100.959067 -233.036408) (xy 101.005341 -233.059986) (xy 101.047357 -233.090512) (xy 101.08408 -233.127235)
			(xy 101.114606 -233.169251) (xy 101.138184 -233.215525) (xy 101.154232 -233.264918) (xy 101.162357 -233.316213)
			(xy 101.162866 -233.34218) (xy 101.162357 -233.368147) (xy 101.154232 -233.419442) (xy 101.138184 -233.468835)
			(xy 101.114606 -233.515109) (xy 101.08408 -233.557125) (xy 101.047357 -233.593848) (xy 101.005341 -233.624374)
			(xy 100.959067 -233.647952) (xy 100.909674 -233.664) (xy 100.858379 -233.672125) (xy 100.806445 -233.672125)
			(xy 100.75515 -233.664) (xy 100.705757 -233.647952) (xy 100.659483 -233.624374) (xy 100.617467 -233.593848)
			(xy 100.580744 -233.557125) (xy 100.550218 -233.515109) (xy 100.52664 -233.468835) (xy 100.510592 -233.419442)
			(xy 100.502467 -233.368147) (xy 100.222557 -233.368147) (xy 100.214432 -233.419442) (xy 100.198384 -233.468835)
			(xy 100.174806 -233.515109) (xy 100.14428 -233.557125) (xy 100.107557 -233.593848) (xy 100.065541 -233.624374)
			(xy 100.019267 -233.647952) (xy 99.969874 -233.664) (xy 99.918579 -233.672125) (xy 99.866645 -233.672125)
			(xy 99.81535 -233.664) (xy 99.765957 -233.647952) (xy 99.719683 -233.624374) (xy 99.677667 -233.593848)
			(xy 99.640944 -233.557125) (xy 99.610418 -233.515109) (xy 99.58684 -233.468835) (xy 99.570792 -233.419442)
			(xy 99.562667 -233.368147) (xy 99.282757 -233.368147) (xy 99.274632 -233.419442) (xy 99.258584 -233.468835)
			(xy 99.235006 -233.515109) (xy 99.20448 -233.557125) (xy 99.167757 -233.593848) (xy 99.125741 -233.624374)
			(xy 99.079467 -233.647952) (xy 99.030074 -233.664) (xy 98.978779 -233.672125) (xy 98.926845 -233.672125)
			(xy 98.87555 -233.664) (xy 98.826157 -233.647952) (xy 98.779883 -233.624374) (xy 98.737867 -233.593848)
			(xy 98.701144 -233.557125) (xy 98.670618 -233.515109) (xy 98.64704 -233.468835) (xy 98.630992 -233.419442)
			(xy 98.622867 -233.368147) (xy 98.343211 -233.368147) (xy 98.335086 -233.419442) (xy 98.319038 -233.468835)
			(xy 98.29546 -233.515109) (xy 98.264934 -233.557125) (xy 98.228211 -233.593848) (xy 98.186195 -233.624374)
			(xy 98.139921 -233.647952) (xy 98.090528 -233.664) (xy 98.039233 -233.672125) (xy 97.987299 -233.672125)
			(xy 97.936004 -233.664) (xy 97.886611 -233.647952) (xy 97.840337 -233.624374) (xy 97.798321 -233.593848)
			(xy 97.761598 -233.557125) (xy 97.731072 -233.515109) (xy 97.707494 -233.468835) (xy 97.691446 -233.419442)
			(xy 97.683321 -233.368147) (xy 97.403157 -233.368147) (xy 97.395032 -233.419442) (xy 97.378984 -233.468835)
			(xy 97.355406 -233.515109) (xy 97.32488 -233.557125) (xy 97.288157 -233.593848) (xy 97.246141 -233.624374)
			(xy 97.199867 -233.647952) (xy 97.150474 -233.664) (xy 97.099179 -233.672125) (xy 97.047245 -233.672125)
			(xy 96.99595 -233.664) (xy 96.946557 -233.647952) (xy 96.900283 -233.624374) (xy 96.858267 -233.593848)
			(xy 96.821544 -233.557125) (xy 96.791018 -233.515109) (xy 96.76744 -233.468835) (xy 96.751392 -233.419442)
			(xy 96.743267 -233.368147) (xy 96.463357 -233.368147) (xy 96.455232 -233.419442) (xy 96.439184 -233.468835)
			(xy 96.415606 -233.515109) (xy 96.38508 -233.557125) (xy 96.348357 -233.593848) (xy 96.306341 -233.624374)
			(xy 96.260067 -233.647952) (xy 96.210674 -233.664) (xy 96.159379 -233.672125) (xy 96.107445 -233.672125)
			(xy 96.05615 -233.664) (xy 96.006757 -233.647952) (xy 95.960483 -233.624374) (xy 95.918467 -233.593848)
			(xy 95.881744 -233.557125) (xy 95.851218 -233.515109) (xy 95.82764 -233.468835) (xy 95.811592 -233.419442)
			(xy 95.803467 -233.368147) (xy 95.523557 -233.368147) (xy 95.515432 -233.419442) (xy 95.499384 -233.468835)
			(xy 95.475806 -233.515109) (xy 95.44528 -233.557125) (xy 95.408557 -233.593848) (xy 95.366541 -233.624374)
			(xy 95.320267 -233.647952) (xy 95.270874 -233.664) (xy 95.219579 -233.672125) (xy 95.167645 -233.672125)
			(xy 95.11635 -233.664) (xy 95.066957 -233.647952) (xy 95.020683 -233.624374) (xy 94.978667 -233.593848)
			(xy 94.941944 -233.557125) (xy 94.911418 -233.515109) (xy 94.88784 -233.468835) (xy 94.871792 -233.419442)
			(xy 94.863667 -233.368147) (xy 94.583757 -233.368147) (xy 94.575632 -233.419442) (xy 94.559584 -233.468835)
			(xy 94.536006 -233.515109) (xy 94.50548 -233.557125) (xy 94.468757 -233.593848) (xy 94.426741 -233.624374)
			(xy 94.380467 -233.647952) (xy 94.331074 -233.664) (xy 94.279779 -233.672125) (xy 94.227845 -233.672125)
			(xy 94.17655 -233.664) (xy 94.127157 -233.647952) (xy 94.080883 -233.624374) (xy 94.038867 -233.593848)
			(xy 94.002144 -233.557125) (xy 93.971618 -233.515109) (xy 93.94804 -233.468835) (xy 93.931992 -233.419442)
			(xy 93.923867 -233.368147) (xy 93.643957 -233.368147) (xy 93.635832 -233.419442) (xy 93.619784 -233.468835)
			(xy 93.596206 -233.515109) (xy 93.56568 -233.557125) (xy 93.528957 -233.593848) (xy 93.486941 -233.624374)
			(xy 93.440667 -233.647952) (xy 93.391274 -233.664) (xy 93.339979 -233.672125) (xy 93.288045 -233.672125)
			(xy 93.23675 -233.664) (xy 93.187357 -233.647952) (xy 93.141083 -233.624374) (xy 93.099067 -233.593848)
			(xy 93.062344 -233.557125) (xy 93.031818 -233.515109) (xy 93.00824 -233.468835) (xy 92.992192 -233.419442)
			(xy 92.984067 -233.368147) (xy 92.704157 -233.368147) (xy 92.696032 -233.419442) (xy 92.679984 -233.468835)
			(xy 92.656406 -233.515109) (xy 92.62588 -233.557125) (xy 92.589157 -233.593848) (xy 92.547141 -233.624374)
			(xy 92.500867 -233.647952) (xy 92.451474 -233.664) (xy 92.400179 -233.672125) (xy 92.348245 -233.672125)
			(xy 92.29695 -233.664) (xy 92.247557 -233.647952) (xy 92.201283 -233.624374) (xy 92.159267 -233.593848)
			(xy 92.122544 -233.557125) (xy 92.092018 -233.515109) (xy 92.06844 -233.468835) (xy 92.052392 -233.419442)
			(xy 92.044267 -233.368147) (xy 91.764998 -233.368147) (xy 91.764998 -233.368744) (xy 91.756516 -233.421167)
			(xy 91.739769 -233.471562) (xy 91.715186 -233.518634) (xy 91.683399 -233.561175) (xy 91.645225 -233.598092)
			(xy 91.601644 -233.628437) (xy 91.577922 -233.640376) (xy 91.565222 -233.646472) (xy 91.53525 -233.691938)
			(xy 91.53525 -233.8197) (xy 91.535672 -233.828727) (xy 91.542119 -233.845594) (xy 91.554109 -233.859096)
			(xy 91.56192 -233.863642) (xy 91.604846 -233.884216) (xy 91.645232 -233.903774) (xy 91.650455 -233.906116)
			(xy 91.661609 -233.908672) (xy 91.66733 -233.908854) (xy 91.69781 -233.897932) (xy 91.70416 -233.893106)
			(xy 91.725907 -233.877223) (xy 91.773475 -233.851986) (xy 91.824502 -233.834786) (xy 91.877642 -233.826076)
			(xy 91.904566 -233.825542) (xy 91.930553 -233.826022) (xy 91.981888 -233.834148) (xy 92.03132 -233.850205)
			(xy 92.077631 -233.873797) (xy 92.11968 -233.904344) (xy 92.156433 -233.941094) (xy 92.186985 -233.98314)
			(xy 92.210582 -234.029449) (xy 92.226644 -234.078879) (xy 92.234775 -234.130213) (xy 92.234775 -234.182187)
			(xy 92.23477 -234.182217) (xy 92.514421 -234.182217) (xy 92.514421 -234.130283) (xy 92.522546 -234.078988)
			(xy 92.538594 -234.029595) (xy 92.562172 -233.983321) (xy 92.592698 -233.941305) (xy 92.629421 -233.904582)
			(xy 92.671437 -233.874056) (xy 92.717711 -233.850478) (xy 92.767104 -233.83443) (xy 92.818399 -233.826305)
			(xy 92.870333 -233.826305) (xy 92.921628 -233.83443) (xy 92.971021 -233.850478) (xy 93.017295 -233.874056)
			(xy 93.059311 -233.904582) (xy 93.096034 -233.941305) (xy 93.12656 -233.983321) (xy 93.150138 -234.029595)
			(xy 93.166186 -234.078988) (xy 93.174311 -234.130283) (xy 93.17482 -234.15625) (xy 93.174311 -234.182217)
			(xy 93.454221 -234.182217) (xy 93.454221 -234.130283) (xy 93.462346 -234.078988) (xy 93.478394 -234.029595)
			(xy 93.501972 -233.983321) (xy 93.532498 -233.941305) (xy 93.569221 -233.904582) (xy 93.611237 -233.874056)
			(xy 93.657511 -233.850478) (xy 93.706904 -233.83443) (xy 93.758199 -233.826305) (xy 93.810133 -233.826305)
			(xy 93.861428 -233.83443) (xy 93.910821 -233.850478) (xy 93.957095 -233.874056) (xy 93.999111 -233.904582)
			(xy 94.035834 -233.941305) (xy 94.06636 -233.983321) (xy 94.089938 -234.029595) (xy 94.105986 -234.078988)
			(xy 94.114111 -234.130283) (xy 94.11462 -234.15625) (xy 94.114111 -234.182217) (xy 94.393767 -234.182217)
			(xy 94.393767 -234.130283) (xy 94.401892 -234.078988) (xy 94.41794 -234.029595) (xy 94.441518 -233.983321)
			(xy 94.472044 -233.941305) (xy 94.508767 -233.904582) (xy 94.550783 -233.874056) (xy 94.597057 -233.850478)
			(xy 94.64645 -233.83443) (xy 94.697745 -233.826305) (xy 94.749679 -233.826305) (xy 94.800974 -233.83443)
			(xy 94.850367 -233.850478) (xy 94.896641 -233.874056) (xy 94.938657 -233.904582) (xy 94.97538 -233.941305)
			(xy 95.005906 -233.983321) (xy 95.029484 -234.029595) (xy 95.045532 -234.078988) (xy 95.053657 -234.130283)
			(xy 95.054166 -234.15625) (xy 95.053657 -234.182217) (xy 95.333821 -234.182217) (xy 95.333821 -234.130283)
			(xy 95.341946 -234.078988) (xy 95.357994 -234.029595) (xy 95.381572 -233.983321) (xy 95.412098 -233.941305)
			(xy 95.448821 -233.904582) (xy 95.490837 -233.874056) (xy 95.537111 -233.850478) (xy 95.586504 -233.83443)
			(xy 95.637799 -233.826305) (xy 95.689733 -233.826305) (xy 95.741028 -233.83443) (xy 95.790421 -233.850478)
			(xy 95.836695 -233.874056) (xy 95.878711 -233.904582) (xy 95.915434 -233.941305) (xy 95.94596 -233.983321)
			(xy 95.969538 -234.029595) (xy 95.985586 -234.078988) (xy 95.993711 -234.130283) (xy 95.99422 -234.15625)
			(xy 95.993711 -234.182217) (xy 96.273621 -234.182217) (xy 96.273621 -234.130283) (xy 96.281746 -234.078988)
			(xy 96.297794 -234.029595) (xy 96.321372 -233.983321) (xy 96.351898 -233.941305) (xy 96.388621 -233.904582)
			(xy 96.430637 -233.874056) (xy 96.476911 -233.850478) (xy 96.526304 -233.83443) (xy 96.577599 -233.826305)
			(xy 96.629533 -233.826305) (xy 96.680828 -233.83443) (xy 96.730221 -233.850478) (xy 96.776495 -233.874056)
			(xy 96.818511 -233.904582) (xy 96.855234 -233.941305) (xy 96.88576 -233.983321) (xy 96.909338 -234.029595)
			(xy 96.925386 -234.078988) (xy 96.933511 -234.130283) (xy 96.93402 -234.15625) (xy 96.933511 -234.182217)
			(xy 97.213421 -234.182217) (xy 97.213421 -234.130283) (xy 97.221546 -234.078988) (xy 97.237594 -234.029595)
			(xy 97.261172 -233.983321) (xy 97.291698 -233.941305) (xy 97.328421 -233.904582) (xy 97.370437 -233.874056)
			(xy 97.416711 -233.850478) (xy 97.466104 -233.83443) (xy 97.517399 -233.826305) (xy 97.569333 -233.826305)
			(xy 97.620628 -233.83443) (xy 97.670021 -233.850478) (xy 97.716295 -233.874056) (xy 97.758311 -233.904582)
			(xy 97.795034 -233.941305) (xy 97.82556 -233.983321) (xy 97.849138 -234.029595) (xy 97.865186 -234.078988)
			(xy 97.873311 -234.130283) (xy 97.87382 -234.15625) (xy 97.873311 -234.182217) (xy 98.153221 -234.182217)
			(xy 98.153221 -234.130283) (xy 98.161346 -234.078988) (xy 98.177394 -234.029595) (xy 98.200972 -233.983321)
			(xy 98.231498 -233.941305) (xy 98.268221 -233.904582) (xy 98.310237 -233.874056) (xy 98.356511 -233.850478)
			(xy 98.405904 -233.83443) (xy 98.457199 -233.826305) (xy 98.509133 -233.826305) (xy 98.560428 -233.83443)
			(xy 98.609821 -233.850478) (xy 98.656095 -233.874056) (xy 98.698111 -233.904582) (xy 98.734834 -233.941305)
			(xy 98.76536 -233.983321) (xy 98.788938 -234.029595) (xy 98.804986 -234.078988) (xy 98.813111 -234.130283)
			(xy 98.81362 -234.15625) (xy 98.813111 -234.182217) (xy 99.093021 -234.182217) (xy 99.093021 -234.130283)
			(xy 99.101146 -234.078988) (xy 99.117194 -234.029595) (xy 99.140772 -233.983321) (xy 99.171298 -233.941305)
			(xy 99.208021 -233.904582) (xy 99.250037 -233.874056) (xy 99.296311 -233.850478) (xy 99.345704 -233.83443)
			(xy 99.396999 -233.826305) (xy 99.448933 -233.826305) (xy 99.500228 -233.83443) (xy 99.549621 -233.850478)
			(xy 99.595895 -233.874056) (xy 99.637911 -233.904582) (xy 99.674634 -233.941305) (xy 99.70516 -233.983321)
			(xy 99.728738 -234.029595) (xy 99.744786 -234.078988) (xy 99.752911 -234.130283) (xy 99.75342 -234.15625)
			(xy 99.752911 -234.182217) (xy 100.032821 -234.182217) (xy 100.032821 -234.130283) (xy 100.040946 -234.078988)
			(xy 100.056994 -234.029595) (xy 100.080572 -233.983321) (xy 100.111098 -233.941305) (xy 100.147821 -233.904582)
			(xy 100.189837 -233.874056) (xy 100.236111 -233.850478) (xy 100.285504 -233.83443) (xy 100.336799 -233.826305)
			(xy 100.388733 -233.826305) (xy 100.440028 -233.83443) (xy 100.489421 -233.850478) (xy 100.535695 -233.874056)
			(xy 100.577711 -233.904582) (xy 100.614434 -233.941305) (xy 100.64496 -233.983321) (xy 100.668538 -234.029595)
			(xy 100.684586 -234.078988) (xy 100.692711 -234.130283) (xy 100.69322 -234.15625) (xy 100.692711 -234.182217)
			(xy 100.972367 -234.182217) (xy 100.972367 -234.130283) (xy 100.980492 -234.078988) (xy 100.99654 -234.029595)
			(xy 101.020118 -233.983321) (xy 101.050644 -233.941305) (xy 101.087367 -233.904582) (xy 101.129383 -233.874056)
			(xy 101.175657 -233.850478) (xy 101.22505 -233.83443) (xy 101.276345 -233.826305) (xy 101.328279 -233.826305)
			(xy 101.379574 -233.83443) (xy 101.428967 -233.850478) (xy 101.475241 -233.874056) (xy 101.517257 -233.904582)
			(xy 101.55398 -233.941305) (xy 101.584506 -233.983321) (xy 101.608084 -234.029595) (xy 101.624132 -234.078988)
			(xy 101.632257 -234.130283) (xy 101.632766 -234.15625) (xy 101.632257 -234.182217) (xy 101.624132 -234.233512)
			(xy 101.608084 -234.282905) (xy 101.584506 -234.329179) (xy 101.55398 -234.371195) (xy 101.517257 -234.407918)
			(xy 101.475241 -234.438444) (xy 101.428967 -234.462022) (xy 101.379574 -234.47807) (xy 101.328279 -234.486195)
			(xy 101.276345 -234.486195) (xy 101.22505 -234.47807) (xy 101.175657 -234.462022) (xy 101.129383 -234.438444)
			(xy 101.087367 -234.407918) (xy 101.050644 -234.371195) (xy 101.020118 -234.329179) (xy 100.99654 -234.282905)
			(xy 100.980492 -234.233512) (xy 100.972367 -234.182217) (xy 100.692711 -234.182217) (xy 100.684586 -234.233512)
			(xy 100.668538 -234.282905) (xy 100.64496 -234.329179) (xy 100.614434 -234.371195) (xy 100.577711 -234.407918)
			(xy 100.535695 -234.438444) (xy 100.489421 -234.462022) (xy 100.440028 -234.47807) (xy 100.388733 -234.486195)
			(xy 100.336799 -234.486195) (xy 100.285504 -234.47807) (xy 100.236111 -234.462022) (xy 100.189837 -234.438444)
			(xy 100.147821 -234.407918) (xy 100.111098 -234.371195) (xy 100.080572 -234.329179) (xy 100.056994 -234.282905)
			(xy 100.040946 -234.233512) (xy 100.032821 -234.182217) (xy 99.752911 -234.182217) (xy 99.744786 -234.233512)
			(xy 99.728738 -234.282905) (xy 99.70516 -234.329179) (xy 99.674634 -234.371195) (xy 99.637911 -234.407918)
			(xy 99.595895 -234.438444) (xy 99.549621 -234.462022) (xy 99.500228 -234.47807) (xy 99.448933 -234.486195)
			(xy 99.396999 -234.486195) (xy 99.345704 -234.47807) (xy 99.296311 -234.462022) (xy 99.250037 -234.438444)
			(xy 99.208021 -234.407918) (xy 99.171298 -234.371195) (xy 99.140772 -234.329179) (xy 99.117194 -234.282905)
			(xy 99.101146 -234.233512) (xy 99.093021 -234.182217) (xy 98.813111 -234.182217) (xy 98.804986 -234.233512)
			(xy 98.788938 -234.282905) (xy 98.76536 -234.329179) (xy 98.734834 -234.371195) (xy 98.698111 -234.407918)
			(xy 98.656095 -234.438444) (xy 98.609821 -234.462022) (xy 98.560428 -234.47807) (xy 98.509133 -234.486195)
			(xy 98.457199 -234.486195) (xy 98.405904 -234.47807) (xy 98.356511 -234.462022) (xy 98.310237 -234.438444)
			(xy 98.268221 -234.407918) (xy 98.231498 -234.371195) (xy 98.200972 -234.329179) (xy 98.177394 -234.282905)
			(xy 98.161346 -234.233512) (xy 98.153221 -234.182217) (xy 97.873311 -234.182217) (xy 97.865186 -234.233512)
			(xy 97.849138 -234.282905) (xy 97.82556 -234.329179) (xy 97.795034 -234.371195) (xy 97.758311 -234.407918)
			(xy 97.716295 -234.438444) (xy 97.670021 -234.462022) (xy 97.620628 -234.47807) (xy 97.569333 -234.486195)
			(xy 97.517399 -234.486195) (xy 97.466104 -234.47807) (xy 97.416711 -234.462022) (xy 97.370437 -234.438444)
			(xy 97.328421 -234.407918) (xy 97.291698 -234.371195) (xy 97.261172 -234.329179) (xy 97.237594 -234.282905)
			(xy 97.221546 -234.233512) (xy 97.213421 -234.182217) (xy 96.933511 -234.182217) (xy 96.925386 -234.233512)
			(xy 96.909338 -234.282905) (xy 96.88576 -234.329179) (xy 96.855234 -234.371195) (xy 96.818511 -234.407918)
			(xy 96.776495 -234.438444) (xy 96.730221 -234.462022) (xy 96.680828 -234.47807) (xy 96.629533 -234.486195)
			(xy 96.577599 -234.486195) (xy 96.526304 -234.47807) (xy 96.476911 -234.462022) (xy 96.430637 -234.438444)
			(xy 96.388621 -234.407918) (xy 96.351898 -234.371195) (xy 96.321372 -234.329179) (xy 96.297794 -234.282905)
			(xy 96.281746 -234.233512) (xy 96.273621 -234.182217) (xy 95.993711 -234.182217) (xy 95.985586 -234.233512)
			(xy 95.969538 -234.282905) (xy 95.94596 -234.329179) (xy 95.915434 -234.371195) (xy 95.878711 -234.407918)
			(xy 95.836695 -234.438444) (xy 95.790421 -234.462022) (xy 95.741028 -234.47807) (xy 95.689733 -234.486195)
			(xy 95.637799 -234.486195) (xy 95.586504 -234.47807) (xy 95.537111 -234.462022) (xy 95.490837 -234.438444)
			(xy 95.448821 -234.407918) (xy 95.412098 -234.371195) (xy 95.381572 -234.329179) (xy 95.357994 -234.282905)
			(xy 95.341946 -234.233512) (xy 95.333821 -234.182217) (xy 95.053657 -234.182217) (xy 95.045532 -234.233512)
			(xy 95.029484 -234.282905) (xy 95.005906 -234.329179) (xy 94.97538 -234.371195) (xy 94.938657 -234.407918)
			(xy 94.896641 -234.438444) (xy 94.850367 -234.462022) (xy 94.800974 -234.47807) (xy 94.749679 -234.486195)
			(xy 94.697745 -234.486195) (xy 94.64645 -234.47807) (xy 94.597057 -234.462022) (xy 94.550783 -234.438444)
			(xy 94.508767 -234.407918) (xy 94.472044 -234.371195) (xy 94.441518 -234.329179) (xy 94.41794 -234.282905)
			(xy 94.401892 -234.233512) (xy 94.393767 -234.182217) (xy 94.114111 -234.182217) (xy 94.105986 -234.233512)
			(xy 94.089938 -234.282905) (xy 94.06636 -234.329179) (xy 94.035834 -234.371195) (xy 93.999111 -234.407918)
			(xy 93.957095 -234.438444) (xy 93.910821 -234.462022) (xy 93.861428 -234.47807) (xy 93.810133 -234.486195)
			(xy 93.758199 -234.486195) (xy 93.706904 -234.47807) (xy 93.657511 -234.462022) (xy 93.611237 -234.438444)
			(xy 93.569221 -234.407918) (xy 93.532498 -234.371195) (xy 93.501972 -234.329179) (xy 93.478394 -234.282905)
			(xy 93.462346 -234.233512) (xy 93.454221 -234.182217) (xy 93.174311 -234.182217) (xy 93.166186 -234.233512)
			(xy 93.150138 -234.282905) (xy 93.12656 -234.329179) (xy 93.096034 -234.371195) (xy 93.059311 -234.407918)
			(xy 93.017295 -234.438444) (xy 92.971021 -234.462022) (xy 92.921628 -234.47807) (xy 92.870333 -234.486195)
			(xy 92.818399 -234.486195) (xy 92.767104 -234.47807) (xy 92.717711 -234.462022) (xy 92.671437 -234.438444)
			(xy 92.629421 -234.407918) (xy 92.592698 -234.371195) (xy 92.562172 -234.329179) (xy 92.538594 -234.282905)
			(xy 92.522546 -234.233512) (xy 92.514421 -234.182217) (xy 92.23477 -234.182217) (xy 92.226644 -234.233521)
			(xy 92.210582 -234.282951) (xy 92.186985 -234.32926) (xy 92.156433 -234.371306) (xy 92.11968 -234.408056)
			(xy 92.077631 -234.438603) (xy 92.03132 -234.462195) (xy 91.981888 -234.478252) (xy 91.930553 -234.486378)
			(xy 91.904566 -234.486958) (xy 91.877642 -234.486428) (xy 91.824506 -234.477708) (xy 91.773481 -234.460503)
			(xy 91.725913 -234.435268) (xy 91.70416 -234.419394) (xy 91.69781 -234.414568) (xy 91.66733 -234.403646)
			(xy 91.661602 -234.403762) (xy 91.650441 -234.406339) (xy 91.645232 -234.408726) (xy 91.604846 -234.428284)
			(xy 91.56192 -234.448858) (xy 91.55412 -234.453415) (xy 91.542146 -234.466924) (xy 91.535676 -234.483777)
			(xy 91.53525 -234.4928) (xy 91.53525 -234.620562) (xy 91.565222 -234.666028) (xy 91.577922 -234.672124)
			(xy 91.601603 -234.68409) (xy 91.645136 -234.714415) (xy 91.683268 -234.751303) (xy 91.71502 -234.793808)
			(xy 91.739576 -234.840837) (xy 91.756306 -234.891185) (xy 91.764781 -234.943558) (xy 91.764784 -234.996033)
			(xy 92.044267 -234.996033) (xy 92.044267 -234.944099) (xy 92.052392 -234.892804) (xy 92.06844 -234.843411)
			(xy 92.092018 -234.797137) (xy 92.122544 -234.755121) (xy 92.159267 -234.718398) (xy 92.201283 -234.687872)
			(xy 92.247557 -234.664294) (xy 92.29695 -234.648246) (xy 92.348245 -234.640121) (xy 92.400179 -234.640121)
			(xy 92.451474 -234.648246) (xy 92.500867 -234.664294) (xy 92.547141 -234.687872) (xy 92.589157 -234.718398)
			(xy 92.62588 -234.755121) (xy 92.656406 -234.797137) (xy 92.679984 -234.843411) (xy 92.696032 -234.892804)
			(xy 92.704157 -234.944099) (xy 92.704666 -234.970066) (xy 92.704157 -234.996033) (xy 92.984067 -234.996033)
			(xy 92.984067 -234.944099) (xy 92.992192 -234.892804) (xy 93.00824 -234.843411) (xy 93.031818 -234.797137)
			(xy 93.062344 -234.755121) (xy 93.099067 -234.718398) (xy 93.141083 -234.687872) (xy 93.187357 -234.664294)
			(xy 93.23675 -234.648246) (xy 93.288045 -234.640121) (xy 93.339979 -234.640121) (xy 93.391274 -234.648246)
			(xy 93.440667 -234.664294) (xy 93.486941 -234.687872) (xy 93.528957 -234.718398) (xy 93.56568 -234.755121)
			(xy 93.596206 -234.797137) (xy 93.619784 -234.843411) (xy 93.635832 -234.892804) (xy 93.643957 -234.944099)
			(xy 93.644466 -234.970066) (xy 93.643957 -234.996033) (xy 93.923867 -234.996033) (xy 93.923867 -234.944099)
			(xy 93.931992 -234.892804) (xy 93.94804 -234.843411) (xy 93.971618 -234.797137) (xy 94.002144 -234.755121)
			(xy 94.038867 -234.718398) (xy 94.080883 -234.687872) (xy 94.127157 -234.664294) (xy 94.17655 -234.648246)
			(xy 94.227845 -234.640121) (xy 94.279779 -234.640121) (xy 94.331074 -234.648246) (xy 94.380467 -234.664294)
			(xy 94.426741 -234.687872) (xy 94.468757 -234.718398) (xy 94.50548 -234.755121) (xy 94.536006 -234.797137)
			(xy 94.559584 -234.843411) (xy 94.575632 -234.892804) (xy 94.583757 -234.944099) (xy 94.584266 -234.970066)
			(xy 94.583757 -234.996033) (xy 94.863667 -234.996033) (xy 94.863667 -234.944099) (xy 94.871792 -234.892804)
			(xy 94.88784 -234.843411) (xy 94.911418 -234.797137) (xy 94.941944 -234.755121) (xy 94.978667 -234.718398)
			(xy 95.020683 -234.687872) (xy 95.066957 -234.664294) (xy 95.11635 -234.648246) (xy 95.167645 -234.640121)
			(xy 95.219579 -234.640121) (xy 95.270874 -234.648246) (xy 95.320267 -234.664294) (xy 95.366541 -234.687872)
			(xy 95.408557 -234.718398) (xy 95.44528 -234.755121) (xy 95.475806 -234.797137) (xy 95.499384 -234.843411)
			(xy 95.515432 -234.892804) (xy 95.523557 -234.944099) (xy 95.524066 -234.970066) (xy 95.523557 -234.996033)
			(xy 95.803467 -234.996033) (xy 95.803467 -234.944099) (xy 95.811592 -234.892804) (xy 95.82764 -234.843411)
			(xy 95.851218 -234.797137) (xy 95.881744 -234.755121) (xy 95.918467 -234.718398) (xy 95.960483 -234.687872)
			(xy 96.006757 -234.664294) (xy 96.05615 -234.648246) (xy 96.107445 -234.640121) (xy 96.159379 -234.640121)
			(xy 96.210674 -234.648246) (xy 96.260067 -234.664294) (xy 96.306341 -234.687872) (xy 96.348357 -234.718398)
			(xy 96.38508 -234.755121) (xy 96.415606 -234.797137) (xy 96.439184 -234.843411) (xy 96.455232 -234.892804)
			(xy 96.463357 -234.944099) (xy 96.463866 -234.970066) (xy 96.463357 -234.996033) (xy 96.743521 -234.996033)
			(xy 96.743521 -234.944099) (xy 96.751646 -234.892804) (xy 96.767694 -234.843411) (xy 96.791272 -234.797137)
			(xy 96.821798 -234.755121) (xy 96.858521 -234.718398) (xy 96.900537 -234.687872) (xy 96.946811 -234.664294)
			(xy 96.996204 -234.648246) (xy 97.047499 -234.640121) (xy 97.099433 -234.640121) (xy 97.150728 -234.648246)
			(xy 97.200121 -234.664294) (xy 97.246395 -234.687872) (xy 97.288411 -234.718398) (xy 97.325134 -234.755121)
			(xy 97.35566 -234.797137) (xy 97.379238 -234.843411) (xy 97.395286 -234.892804) (xy 97.403411 -234.944099)
			(xy 97.40392 -234.970066) (xy 97.403411 -234.996033) (xy 97.683067 -234.996033) (xy 97.683067 -234.944099)
			(xy 97.691192 -234.892804) (xy 97.70724 -234.843411) (xy 97.730818 -234.797137) (xy 97.761344 -234.755121)
			(xy 97.798067 -234.718398) (xy 97.840083 -234.687872) (xy 97.886357 -234.664294) (xy 97.93575 -234.648246)
			(xy 97.987045 -234.640121) (xy 98.038979 -234.640121) (xy 98.090274 -234.648246) (xy 98.139667 -234.664294)
			(xy 98.185941 -234.687872) (xy 98.227957 -234.718398) (xy 98.26468 -234.755121) (xy 98.295206 -234.797137)
			(xy 98.318784 -234.843411) (xy 98.334832 -234.892804) (xy 98.342957 -234.944099) (xy 98.343466 -234.970066)
			(xy 98.342957 -234.996033) (xy 98.622867 -234.996033) (xy 98.622867 -234.944099) (xy 98.630992 -234.892804)
			(xy 98.64704 -234.843411) (xy 98.670618 -234.797137) (xy 98.701144 -234.755121) (xy 98.737867 -234.718398)
			(xy 98.779883 -234.687872) (xy 98.826157 -234.664294) (xy 98.87555 -234.648246) (xy 98.926845 -234.640121)
			(xy 98.978779 -234.640121) (xy 99.030074 -234.648246) (xy 99.079467 -234.664294) (xy 99.125741 -234.687872)
			(xy 99.167757 -234.718398) (xy 99.20448 -234.755121) (xy 99.235006 -234.797137) (xy 99.258584 -234.843411)
			(xy 99.274632 -234.892804) (xy 99.282757 -234.944099) (xy 99.283266 -234.970066) (xy 99.282757 -234.996033)
			(xy 99.562667 -234.996033) (xy 99.562667 -234.944099) (xy 99.570792 -234.892804) (xy 99.58684 -234.843411)
			(xy 99.610418 -234.797137) (xy 99.640944 -234.755121) (xy 99.677667 -234.718398) (xy 99.719683 -234.687872)
			(xy 99.765957 -234.664294) (xy 99.81535 -234.648246) (xy 99.866645 -234.640121) (xy 99.918579 -234.640121)
			(xy 99.969874 -234.648246) (xy 100.019267 -234.664294) (xy 100.065541 -234.687872) (xy 100.107557 -234.718398)
			(xy 100.14428 -234.755121) (xy 100.174806 -234.797137) (xy 100.198384 -234.843411) (xy 100.214432 -234.892804)
			(xy 100.222557 -234.944099) (xy 100.223066 -234.970066) (xy 100.222557 -234.996033) (xy 100.502467 -234.996033)
			(xy 100.502467 -234.944099) (xy 100.510592 -234.892804) (xy 100.52664 -234.843411) (xy 100.550218 -234.797137)
			(xy 100.580744 -234.755121) (xy 100.617467 -234.718398) (xy 100.659483 -234.687872) (xy 100.705757 -234.664294)
			(xy 100.75515 -234.648246) (xy 100.806445 -234.640121) (xy 100.858379 -234.640121) (xy 100.909674 -234.648246)
			(xy 100.959067 -234.664294) (xy 101.005341 -234.687872) (xy 101.047357 -234.718398) (xy 101.08408 -234.755121)
			(xy 101.114606 -234.797137) (xy 101.138184 -234.843411) (xy 101.154232 -234.892804) (xy 101.162357 -234.944099)
			(xy 101.162866 -234.970066) (xy 101.162865 -234.970096) (xy 101.441143 -234.970096) (xy 101.445075 -234.919234)
			(xy 101.456773 -234.869579) (xy 101.475962 -234.822312) (xy 101.502185 -234.778553) (xy 101.534819 -234.739343)
			(xy 101.57309 -234.705613) (xy 101.616089 -234.678162) (xy 101.662795 -234.657644) (xy 101.712098 -234.644545)
			(xy 101.737414 -234.64139) (xy 101.78288 -234.636564) (xy 101.78288 -232.04805) (xy 101.737414 -232.043224)
			(xy 101.712115 -232.039975) (xy 101.662823 -232.02688) (xy 101.616129 -232.006367) (xy 101.57314 -231.978923)
			(xy 101.534878 -231.945201) (xy 101.502252 -231.906001) (xy 101.476035 -231.862253) (xy 101.456851 -231.814997)
			(xy 101.445155 -231.765355) (xy 101.441225 -231.714505) (xy 101.445154 -231.663655) (xy 101.456848 -231.614012)
			(xy 101.476031 -231.566756) (xy 101.502246 -231.523008) (xy 101.534871 -231.483806) (xy 101.573132 -231.450083)
			(xy 101.61612 -231.422638) (xy 101.662814 -231.402124) (xy 101.712105 -231.389027) (xy 101.737414 -231.385872)
			(xy 101.78288 -231.381046) (xy 101.78288 -230.420164) (xy 101.737414 -230.415338) (xy 101.710708 -230.411929)
			(xy 101.658803 -230.397649) (xy 101.609899 -230.375146) (xy 101.565287 -230.345015) (xy 101.526148 -230.308054)
			(xy 101.493515 -230.265239) (xy 101.468252 -230.217702) (xy 101.451026 -230.166699) (xy 101.442292 -230.113579)
			(xy 101.441758 -230.086662) (xy 101.44222 -230.060693) (xy 101.450351 -230.009396) (xy 101.466405 -229.960001)
			(xy 101.489989 -229.913727) (xy 101.52052 -229.871711) (xy 101.557249 -229.834988) (xy 101.599269 -229.804463)
			(xy 101.645548 -229.780886) (xy 101.694944 -229.764839) (xy 101.746243 -229.756716) (xy 101.772212 -229.756208)
			(xy 101.797567 -229.756653) (xy 101.847685 -229.764375) (xy 101.896034 -229.779666) (xy 101.941477 -229.802167)
			(xy 101.982948 -229.831349) (xy 102.019471 -229.866527) (xy 102.050189 -229.906874) (xy 102.074379 -229.951441)
			(xy 102.083362 -229.975156) (xy 102.088693 -229.988795) (xy 102.105946 -230.012444) (xy 102.129205 -230.030221)
			(xy 102.156553 -230.040663) (xy 102.185741 -230.042911) (xy 102.214365 -230.036779) (xy 102.240071 -230.022772)
			(xy 102.250748 -230.012748) (xy 102.756716 -229.50678) (xy 102.77094 -229.50678) (xy 102.784614 -229.506329)
			(xy 102.810983 -229.499081) (xy 102.83448 -229.485091) (xy 102.853418 -229.465363) (xy 102.866436 -229.441314)
			(xy 102.8726 -229.414671) (xy 102.871467 -229.387348) (xy 102.867714 -229.374192) (xy 102.860257 -229.349521)
			(xy 102.852224 -229.298614) (xy 102.851712 -229.272846) (xy 102.852221 -229.246879) (xy 102.860346 -229.195584)
			(xy 102.876394 -229.146191) (xy 102.899972 -229.099917) (xy 102.930498 -229.057901) (xy 102.967221 -229.021178)
			(xy 103.009237 -228.990652) (xy 103.055511 -228.967074) (xy 103.104904 -228.951026) (xy 103.156199 -228.942901)
			(xy 103.208133 -228.942901) (xy 103.259428 -228.951026) (xy 103.308821 -228.967074) (xy 103.355095 -228.990652)
			(xy 103.397111 -229.021178) (xy 103.433834 -229.057901) (xy 103.46436 -229.099917) (xy 103.487938 -229.146191)
			(xy 103.503986 -229.195584) (xy 103.512111 -229.246879) (xy 103.51262 -229.272846) (xy 103.512114 -229.298614)
			(xy 103.504073 -229.34952) (xy 103.496618 -229.374192) (xy 103.492914 -229.387359) (xy 103.491783 -229.414674)
			(xy 103.497944 -229.44131) (xy 103.510955 -229.465354) (xy 103.529881 -229.485082) (xy 103.553366 -229.499077)
			(xy 103.579723 -229.506337) (xy 103.593392 -229.50678) (xy 103.71074 -229.50678) (xy 103.724414 -229.506329)
			(xy 103.750783 -229.499081) (xy 103.77428 -229.485091) (xy 103.793218 -229.465363) (xy 103.806236 -229.441314)
			(xy 103.8124 -229.414671) (xy 103.811267 -229.387348) (xy 103.807514 -229.374192) (xy 103.800057 -229.349521)
			(xy 103.792024 -229.298614) (xy 103.791512 -229.272846) (xy 103.792021 -229.246879) (xy 103.800146 -229.195584)
			(xy 103.816194 -229.146191) (xy 103.839772 -229.099917) (xy 103.870298 -229.057901) (xy 103.907021 -229.021178)
			(xy 103.949037 -228.990652) (xy 103.995311 -228.967074) (xy 104.044704 -228.951026) (xy 104.095999 -228.942901)
			(xy 104.147933 -228.942901) (xy 104.199228 -228.951026) (xy 104.248621 -228.967074) (xy 104.294895 -228.990652)
			(xy 104.336911 -229.021178) (xy 104.373634 -229.057901) (xy 104.40416 -229.099917) (xy 104.427738 -229.146191)
			(xy 104.443786 -229.195584) (xy 104.451911 -229.246879) (xy 104.45242 -229.272846) (xy 104.451914 -229.298614)
			(xy 104.443873 -229.34952) (xy 104.436418 -229.374192) (xy 104.432714 -229.387359) (xy 104.431583 -229.414674)
			(xy 104.437744 -229.44131) (xy 104.450755 -229.465354) (xy 104.469681 -229.485082) (xy 104.493166 -229.499077)
			(xy 104.519523 -229.506337) (xy 104.533192 -229.50678) (xy 104.65054 -229.50678) (xy 104.664214 -229.506329)
			(xy 104.690583 -229.499081) (xy 104.71408 -229.485091) (xy 104.733018 -229.465363) (xy 104.746036 -229.441314)
			(xy 104.7522 -229.414671) (xy 104.751067 -229.387348) (xy 104.747314 -229.374192) (xy 104.739857 -229.349521)
			(xy 104.731824 -229.298614) (xy 104.731312 -229.272846) (xy 104.731821 -229.246879) (xy 104.739946 -229.195584)
			(xy 104.755994 -229.146191) (xy 104.779572 -229.099917) (xy 104.810098 -229.057901) (xy 104.846821 -229.021178)
			(xy 104.888837 -228.990652) (xy 104.935111 -228.967074) (xy 104.984504 -228.951026) (xy 105.035799 -228.942901)
			(xy 105.087733 -228.942901) (xy 105.139028 -228.951026) (xy 105.188421 -228.967074) (xy 105.234695 -228.990652)
			(xy 105.276711 -229.021178) (xy 105.313434 -229.057901) (xy 105.34396 -229.099917) (xy 105.367538 -229.146191)
			(xy 105.383586 -229.195584) (xy 105.391711 -229.246879) (xy 105.39222 -229.272846) (xy 105.391744 -229.296993)
			(xy 105.391476 -229.298813) (xy 105.671621 -229.298813) (xy 105.671621 -229.246879) (xy 105.679746 -229.195584)
			(xy 105.695794 -229.146191) (xy 105.719372 -229.099917) (xy 105.749898 -229.057901) (xy 105.786621 -229.021178)
			(xy 105.828637 -228.990652) (xy 105.874911 -228.967074) (xy 105.924304 -228.951026) (xy 105.975599 -228.942901)
			(xy 106.027533 -228.942901) (xy 106.078828 -228.951026) (xy 106.128221 -228.967074) (xy 106.174495 -228.990652)
			(xy 106.216511 -229.021178) (xy 106.253234 -229.057901) (xy 106.28376 -229.099917) (xy 106.307338 -229.146191)
			(xy 106.323386 -229.195584) (xy 106.331511 -229.246879) (xy 106.33202 -229.272846) (xy 106.331511 -229.298813)
			(xy 106.611421 -229.298813) (xy 106.611421 -229.246879) (xy 106.619546 -229.195584) (xy 106.635594 -229.146191)
			(xy 106.659172 -229.099917) (xy 106.689698 -229.057901) (xy 106.726421 -229.021178) (xy 106.768437 -228.990652)
			(xy 106.814711 -228.967074) (xy 106.864104 -228.951026) (xy 106.915399 -228.942901) (xy 106.967333 -228.942901)
			(xy 107.018628 -228.951026) (xy 107.068021 -228.967074) (xy 107.114295 -228.990652) (xy 107.156311 -229.021178)
			(xy 107.193034 -229.057901) (xy 107.22356 -229.099917) (xy 107.247138 -229.146191) (xy 107.263186 -229.195584)
			(xy 107.271311 -229.246879) (xy 107.27182 -229.272846) (xy 107.271311 -229.298813) (xy 107.551221 -229.298813)
			(xy 107.551221 -229.246879) (xy 107.559346 -229.195584) (xy 107.575394 -229.146191) (xy 107.598972 -229.099917)
			(xy 107.629498 -229.057901) (xy 107.666221 -229.021178) (xy 107.708237 -228.990652) (xy 107.754511 -228.967074)
			(xy 107.803904 -228.951026) (xy 107.855199 -228.942901) (xy 107.907133 -228.942901) (xy 107.958428 -228.951026)
			(xy 108.007821 -228.967074) (xy 108.054095 -228.990652) (xy 108.096111 -229.021178) (xy 108.132834 -229.057901)
			(xy 108.16336 -229.099917) (xy 108.186938 -229.146191) (xy 108.202986 -229.195584) (xy 108.211111 -229.246879)
			(xy 108.21162 -229.272846) (xy 108.211111 -229.298813) (xy 108.491021 -229.298813) (xy 108.491021 -229.246879)
			(xy 108.499146 -229.195584) (xy 108.515194 -229.146191) (xy 108.538772 -229.099917) (xy 108.569298 -229.057901)
			(xy 108.606021 -229.021178) (xy 108.648037 -228.990652) (xy 108.694311 -228.967074) (xy 108.743704 -228.951026)
			(xy 108.794999 -228.942901) (xy 108.846933 -228.942901) (xy 108.898228 -228.951026) (xy 108.947621 -228.967074)
			(xy 108.993895 -228.990652) (xy 109.035911 -229.021178) (xy 109.072634 -229.057901) (xy 109.10316 -229.099917)
			(xy 109.126738 -229.146191) (xy 109.142786 -229.195584) (xy 109.150911 -229.246879) (xy 109.15142 -229.272846)
			(xy 109.150911 -229.298813) (xy 109.430821 -229.298813) (xy 109.430821 -229.246879) (xy 109.438946 -229.195584)
			(xy 109.454994 -229.146191) (xy 109.478572 -229.099917) (xy 109.509098 -229.057901) (xy 109.545821 -229.021178)
			(xy 109.587837 -228.990652) (xy 109.634111 -228.967074) (xy 109.683504 -228.951026) (xy 109.734799 -228.942901)
			(xy 109.786733 -228.942901) (xy 109.838028 -228.951026) (xy 109.887421 -228.967074) (xy 109.933695 -228.990652)
			(xy 109.975711 -229.021178) (xy 110.012434 -229.057901) (xy 110.04296 -229.099917) (xy 110.066538 -229.146191)
			(xy 110.082586 -229.195584) (xy 110.090711 -229.246879) (xy 110.09122 -229.272846) (xy 110.090711 -229.298813)
			(xy 110.370621 -229.298813) (xy 110.370621 -229.246879) (xy 110.378746 -229.195584) (xy 110.394794 -229.146191)
			(xy 110.418372 -229.099917) (xy 110.448898 -229.057901) (xy 110.485621 -229.021178) (xy 110.527637 -228.990652)
			(xy 110.573911 -228.967074) (xy 110.623304 -228.951026) (xy 110.674599 -228.942901) (xy 110.726533 -228.942901)
			(xy 110.777828 -228.951026) (xy 110.827221 -228.967074) (xy 110.873495 -228.990652) (xy 110.915511 -229.021178)
			(xy 110.952234 -229.057901) (xy 110.98276 -229.099917) (xy 111.006338 -229.146191) (xy 111.022386 -229.195584)
			(xy 111.030511 -229.246879) (xy 111.03102 -229.272846) (xy 111.030511 -229.298813) (xy 111.310167 -229.298813)
			(xy 111.310167 -229.246879) (xy 111.318292 -229.195584) (xy 111.33434 -229.146191) (xy 111.357918 -229.099917)
			(xy 111.388444 -229.057901) (xy 111.425167 -229.021178) (xy 111.467183 -228.990652) (xy 111.513457 -228.967074)
			(xy 111.56285 -228.951026) (xy 111.614145 -228.942901) (xy 111.666079 -228.942901) (xy 111.717374 -228.951026)
			(xy 111.766767 -228.967074) (xy 111.813041 -228.990652) (xy 111.855057 -229.021178) (xy 111.89178 -229.057901)
			(xy 111.922306 -229.099917) (xy 111.945884 -229.146191) (xy 111.961932 -229.195584) (xy 111.970057 -229.246879)
			(xy 111.970566 -229.272846) (xy 111.970057 -229.298813) (xy 112.250221 -229.298813) (xy 112.250221 -229.246879)
			(xy 112.258346 -229.195584) (xy 112.274394 -229.146191) (xy 112.297972 -229.099917) (xy 112.328498 -229.057901)
			(xy 112.365221 -229.021178) (xy 112.407237 -228.990652) (xy 112.453511 -228.967074) (xy 112.502904 -228.951026)
			(xy 112.554199 -228.942901) (xy 112.606133 -228.942901) (xy 112.657428 -228.951026) (xy 112.706821 -228.967074)
			(xy 112.753095 -228.990652) (xy 112.795111 -229.021178) (xy 112.831834 -229.057901) (xy 112.86236 -229.099917)
			(xy 112.885938 -229.146191) (xy 112.901986 -229.195584) (xy 112.910111 -229.246879) (xy 112.91062 -229.272846)
			(xy 112.910111 -229.298813) (xy 113.190021 -229.298813) (xy 113.190021 -229.246879) (xy 113.198146 -229.195584)
			(xy 113.214194 -229.146191) (xy 113.237772 -229.099917) (xy 113.268298 -229.057901) (xy 113.305021 -229.021178)
			(xy 113.347037 -228.990652) (xy 113.393311 -228.967074) (xy 113.442704 -228.951026) (xy 113.493999 -228.942901)
			(xy 113.545933 -228.942901) (xy 113.597228 -228.951026) (xy 113.646621 -228.967074) (xy 113.692895 -228.990652)
			(xy 113.734911 -229.021178) (xy 113.771634 -229.057901) (xy 113.80216 -229.099917) (xy 113.825738 -229.146191)
			(xy 113.841786 -229.195584) (xy 113.849911 -229.246879) (xy 113.85042 -229.272846) (xy 113.849911 -229.298813)
			(xy 114.129821 -229.298813) (xy 114.129821 -229.246879) (xy 114.137946 -229.195584) (xy 114.153994 -229.146191)
			(xy 114.177572 -229.099917) (xy 114.208098 -229.057901) (xy 114.244821 -229.021178) (xy 114.286837 -228.990652)
			(xy 114.333111 -228.967074) (xy 114.382504 -228.951026) (xy 114.433799 -228.942901) (xy 114.485733 -228.942901)
			(xy 114.537028 -228.951026) (xy 114.586421 -228.967074) (xy 114.632695 -228.990652) (xy 114.674711 -229.021178)
			(xy 114.711434 -229.057901) (xy 114.74196 -229.099917) (xy 114.765538 -229.146191) (xy 114.781586 -229.195584)
			(xy 114.789711 -229.246879) (xy 114.79022 -229.272846) (xy 114.789711 -229.298813) (xy 115.069621 -229.298813)
			(xy 115.069621 -229.246879) (xy 115.077746 -229.195584) (xy 115.093794 -229.146191) (xy 115.117372 -229.099917)
			(xy 115.147898 -229.057901) (xy 115.184621 -229.021178) (xy 115.226637 -228.990652) (xy 115.272911 -228.967074)
			(xy 115.322304 -228.951026) (xy 115.373599 -228.942901) (xy 115.425533 -228.942901) (xy 115.476828 -228.951026)
			(xy 115.526221 -228.967074) (xy 115.572495 -228.990652) (xy 115.614511 -229.021178) (xy 115.651234 -229.057901)
			(xy 115.68176 -229.099917) (xy 115.705338 -229.146191) (xy 115.721386 -229.195584) (xy 115.729511 -229.246879)
			(xy 115.73002 -229.272846) (xy 115.729511 -229.298813) (xy 116.009421 -229.298813) (xy 116.009421 -229.246879)
			(xy 116.017546 -229.195584) (xy 116.033594 -229.146191) (xy 116.057172 -229.099917) (xy 116.087698 -229.057901)
			(xy 116.124421 -229.021178) (xy 116.166437 -228.990652) (xy 116.212711 -228.967074) (xy 116.262104 -228.951026)
			(xy 116.313399 -228.942901) (xy 116.365333 -228.942901) (xy 116.416628 -228.951026) (xy 116.466021 -228.967074)
			(xy 116.512295 -228.990652) (xy 116.554311 -229.021178) (xy 116.591034 -229.057901) (xy 116.62156 -229.099917)
			(xy 116.645138 -229.146191) (xy 116.661186 -229.195584) (xy 116.669311 -229.246879) (xy 116.66982 -229.272846)
			(xy 116.669311 -229.298813) (xy 116.949221 -229.298813) (xy 116.949221 -229.246879) (xy 116.957346 -229.195584)
			(xy 116.973394 -229.146191) (xy 116.996972 -229.099917) (xy 117.027498 -229.057901) (xy 117.064221 -229.021178)
			(xy 117.106237 -228.990652) (xy 117.152511 -228.967074) (xy 117.201904 -228.951026) (xy 117.253199 -228.942901)
			(xy 117.305133 -228.942901) (xy 117.356428 -228.951026) (xy 117.405821 -228.967074) (xy 117.452095 -228.990652)
			(xy 117.494111 -229.021178) (xy 117.530834 -229.057901) (xy 117.56136 -229.099917) (xy 117.584938 -229.146191)
			(xy 117.600986 -229.195584) (xy 117.609111 -229.246879) (xy 117.60962 -229.272846) (xy 117.609111 -229.298813)
			(xy 117.889021 -229.298813) (xy 117.889021 -229.246879) (xy 117.897146 -229.195584) (xy 117.913194 -229.146191)
			(xy 117.936772 -229.099917) (xy 117.967298 -229.057901) (xy 118.004021 -229.021178) (xy 118.046037 -228.990652)
			(xy 118.092311 -228.967074) (xy 118.141704 -228.951026) (xy 118.192999 -228.942901) (xy 118.244933 -228.942901)
			(xy 118.296228 -228.951026) (xy 118.345621 -228.967074) (xy 118.391895 -228.990652) (xy 118.433911 -229.021178)
			(xy 118.470634 -229.057901) (xy 118.50116 -229.099917) (xy 118.524738 -229.146191) (xy 118.540786 -229.195584)
			(xy 118.548911 -229.246879) (xy 118.54942 -229.272846) (xy 118.548911 -229.298813) (xy 118.828821 -229.298813)
			(xy 118.828821 -229.246879) (xy 118.836946 -229.195584) (xy 118.852994 -229.146191) (xy 118.876572 -229.099917)
			(xy 118.907098 -229.057901) (xy 118.943821 -229.021178) (xy 118.985837 -228.990652) (xy 119.032111 -228.967074)
			(xy 119.081504 -228.951026) (xy 119.132799 -228.942901) (xy 119.184733 -228.942901) (xy 119.236028 -228.951026)
			(xy 119.285421 -228.967074) (xy 119.331695 -228.990652) (xy 119.373711 -229.021178) (xy 119.410434 -229.057901)
			(xy 119.44096 -229.099917) (xy 119.464538 -229.146191) (xy 119.480586 -229.195584) (xy 119.488711 -229.246879)
			(xy 119.48922 -229.272846) (xy 119.488711 -229.298813) (xy 119.768621 -229.298813) (xy 119.768621 -229.246879)
			(xy 119.776746 -229.195584) (xy 119.792794 -229.146191) (xy 119.816372 -229.099917) (xy 119.846898 -229.057901)
			(xy 119.883621 -229.021178) (xy 119.925637 -228.990652) (xy 119.971911 -228.967074) (xy 120.021304 -228.951026)
			(xy 120.072599 -228.942901) (xy 120.124533 -228.942901) (xy 120.175828 -228.951026) (xy 120.225221 -228.967074)
			(xy 120.271495 -228.990652) (xy 120.313511 -229.021178) (xy 120.350234 -229.057901) (xy 120.38076 -229.099917)
			(xy 120.404338 -229.146191) (xy 120.420386 -229.195584) (xy 120.428511 -229.246879) (xy 120.42902 -229.272846)
			(xy 120.428511 -229.298813) (xy 120.708421 -229.298813) (xy 120.708421 -229.246879) (xy 120.716546 -229.195584)
			(xy 120.732594 -229.146191) (xy 120.756172 -229.099917) (xy 120.786698 -229.057901) (xy 120.823421 -229.021178)
			(xy 120.865437 -228.990652) (xy 120.911711 -228.967074) (xy 120.961104 -228.951026) (xy 121.012399 -228.942901)
			(xy 121.064333 -228.942901) (xy 121.115628 -228.951026) (xy 121.165021 -228.967074) (xy 121.211295 -228.990652)
			(xy 121.253311 -229.021178) (xy 121.290034 -229.057901) (xy 121.32056 -229.099917) (xy 121.344138 -229.146191)
			(xy 121.360186 -229.195584) (xy 121.368311 -229.246879) (xy 121.36882 -229.272846) (xy 121.368311 -229.298813)
			(xy 121.648221 -229.298813) (xy 121.648221 -229.246879) (xy 121.656346 -229.195584) (xy 121.672394 -229.146191)
			(xy 121.695972 -229.099917) (xy 121.726498 -229.057901) (xy 121.763221 -229.021178) (xy 121.805237 -228.990652)
			(xy 121.851511 -228.967074) (xy 121.900904 -228.951026) (xy 121.952199 -228.942901) (xy 122.004133 -228.942901)
			(xy 122.055428 -228.951026) (xy 122.104821 -228.967074) (xy 122.151095 -228.990652) (xy 122.193111 -229.021178)
			(xy 122.229834 -229.057901) (xy 122.26036 -229.099917) (xy 122.283938 -229.146191) (xy 122.299986 -229.195584)
			(xy 122.308111 -229.246879) (xy 122.30862 -229.272846) (xy 122.308111 -229.298813) (xy 122.587767 -229.298813)
			(xy 122.587767 -229.246879) (xy 122.595892 -229.195584) (xy 122.61194 -229.146191) (xy 122.635518 -229.099917)
			(xy 122.666044 -229.057901) (xy 122.702767 -229.021178) (xy 122.744783 -228.990652) (xy 122.791057 -228.967074)
			(xy 122.84045 -228.951026) (xy 122.891745 -228.942901) (xy 122.943679 -228.942901) (xy 122.994974 -228.951026)
			(xy 123.044367 -228.967074) (xy 123.090641 -228.990652) (xy 123.132657 -229.021178) (xy 123.16938 -229.057901)
			(xy 123.199906 -229.099917) (xy 123.223484 -229.146191) (xy 123.239532 -229.195584) (xy 123.247657 -229.246879)
			(xy 123.248166 -229.272846) (xy 123.247657 -229.298813) (xy 123.527821 -229.298813) (xy 123.527821 -229.246879)
			(xy 123.535946 -229.195584) (xy 123.551994 -229.146191) (xy 123.575572 -229.099917) (xy 123.606098 -229.057901)
			(xy 123.642821 -229.021178) (xy 123.684837 -228.990652) (xy 123.731111 -228.967074) (xy 123.780504 -228.951026)
			(xy 123.831799 -228.942901) (xy 123.883733 -228.942901) (xy 123.935028 -228.951026) (xy 123.984421 -228.967074)
			(xy 124.030695 -228.990652) (xy 124.072711 -229.021178) (xy 124.109434 -229.057901) (xy 124.13996 -229.099917)
			(xy 124.163538 -229.146191) (xy 124.179586 -229.195584) (xy 124.187711 -229.246879) (xy 124.18822 -229.272846)
			(xy 124.187711 -229.298813) (xy 124.467621 -229.298813) (xy 124.467621 -229.246879) (xy 124.475746 -229.195584)
			(xy 124.491794 -229.146191) (xy 124.515372 -229.099917) (xy 124.545898 -229.057901) (xy 124.582621 -229.021178)
			(xy 124.624637 -228.990652) (xy 124.670911 -228.967074) (xy 124.720304 -228.951026) (xy 124.771599 -228.942901)
			(xy 124.823533 -228.942901) (xy 124.874828 -228.951026) (xy 124.924221 -228.967074) (xy 124.970495 -228.990652)
			(xy 125.012511 -229.021178) (xy 125.049234 -229.057901) (xy 125.07976 -229.099917) (xy 125.103338 -229.146191)
			(xy 125.119386 -229.195584) (xy 125.127511 -229.246879) (xy 125.12802 -229.272846) (xy 125.127511 -229.298813)
			(xy 125.407421 -229.298813) (xy 125.407421 -229.246879) (xy 125.415546 -229.195584) (xy 125.431594 -229.146191)
			(xy 125.455172 -229.099917) (xy 125.485698 -229.057901) (xy 125.522421 -229.021178) (xy 125.564437 -228.990652)
			(xy 125.610711 -228.967074) (xy 125.660104 -228.951026) (xy 125.711399 -228.942901) (xy 125.763333 -228.942901)
			(xy 125.814628 -228.951026) (xy 125.864021 -228.967074) (xy 125.910295 -228.990652) (xy 125.952311 -229.021178)
			(xy 125.989034 -229.057901) (xy 126.01956 -229.099917) (xy 126.043138 -229.146191) (xy 126.059186 -229.195584)
			(xy 126.067311 -229.246879) (xy 126.06782 -229.272846) (xy 126.067311 -229.298813) (xy 126.347221 -229.298813)
			(xy 126.347221 -229.246879) (xy 126.355346 -229.195584) (xy 126.371394 -229.146191) (xy 126.394972 -229.099917)
			(xy 126.425498 -229.057901) (xy 126.462221 -229.021178) (xy 126.504237 -228.990652) (xy 126.550511 -228.967074)
			(xy 126.599904 -228.951026) (xy 126.651199 -228.942901) (xy 126.703133 -228.942901) (xy 126.754428 -228.951026)
			(xy 126.803821 -228.967074) (xy 126.850095 -228.990652) (xy 126.892111 -229.021178) (xy 126.928834 -229.057901)
			(xy 126.95936 -229.099917) (xy 126.982938 -229.146191) (xy 126.998986 -229.195584) (xy 127.007111 -229.246879)
			(xy 127.00762 -229.272846) (xy 127.007111 -229.298813) (xy 127.287021 -229.298813) (xy 127.287021 -229.246879)
			(xy 127.295146 -229.195584) (xy 127.311194 -229.146191) (xy 127.334772 -229.099917) (xy 127.365298 -229.057901)
			(xy 127.402021 -229.021178) (xy 127.444037 -228.990652) (xy 127.490311 -228.967074) (xy 127.539704 -228.951026)
			(xy 127.590999 -228.942901) (xy 127.642933 -228.942901) (xy 127.694228 -228.951026) (xy 127.743621 -228.967074)
			(xy 127.789895 -228.990652) (xy 127.831911 -229.021178) (xy 127.868634 -229.057901) (xy 127.89916 -229.099917)
			(xy 127.922738 -229.146191) (xy 127.938786 -229.195584) (xy 127.946911 -229.246879) (xy 127.94742 -229.272846)
			(xy 127.946911 -229.298813) (xy 128.226821 -229.298813) (xy 128.226821 -229.246879) (xy 128.234946 -229.195584)
			(xy 128.250994 -229.146191) (xy 128.274572 -229.099917) (xy 128.305098 -229.057901) (xy 128.341821 -229.021178)
			(xy 128.383837 -228.990652) (xy 128.430111 -228.967074) (xy 128.479504 -228.951026) (xy 128.530799 -228.942901)
			(xy 128.582733 -228.942901) (xy 128.634028 -228.951026) (xy 128.683421 -228.967074) (xy 128.729695 -228.990652)
			(xy 128.771711 -229.021178) (xy 128.808434 -229.057901) (xy 128.83896 -229.099917) (xy 128.862538 -229.146191)
			(xy 128.878586 -229.195584) (xy 128.886711 -229.246879) (xy 128.88722 -229.272846) (xy 128.886711 -229.298813)
			(xy 129.166367 -229.298813) (xy 129.166367 -229.246879) (xy 129.174492 -229.195584) (xy 129.19054 -229.146191)
			(xy 129.214118 -229.099917) (xy 129.244644 -229.057901) (xy 129.281367 -229.021178) (xy 129.323383 -228.990652)
			(xy 129.369657 -228.967074) (xy 129.41905 -228.951026) (xy 129.470345 -228.942901) (xy 129.522279 -228.942901)
			(xy 129.573574 -228.951026) (xy 129.622967 -228.967074) (xy 129.669241 -228.990652) (xy 129.711257 -229.021178)
			(xy 129.74798 -229.057901) (xy 129.778506 -229.099917) (xy 129.802084 -229.146191) (xy 129.818132 -229.195584)
			(xy 129.826257 -229.246879) (xy 129.826766 -229.272846) (xy 129.826257 -229.298813) (xy 130.106421 -229.298813)
			(xy 130.106421 -229.246879) (xy 130.114546 -229.195584) (xy 130.130594 -229.146191) (xy 130.154172 -229.099917)
			(xy 130.184698 -229.057901) (xy 130.221421 -229.021178) (xy 130.263437 -228.990652) (xy 130.309711 -228.967074)
			(xy 130.359104 -228.951026) (xy 130.410399 -228.942901) (xy 130.462333 -228.942901) (xy 130.513628 -228.951026)
			(xy 130.563021 -228.967074) (xy 130.609295 -228.990652) (xy 130.651311 -229.021178) (xy 130.688034 -229.057901)
			(xy 130.71856 -229.099917) (xy 130.742138 -229.146191) (xy 130.758186 -229.195584) (xy 130.766311 -229.246879)
			(xy 130.76682 -229.272846) (xy 130.766311 -229.298813) (xy 131.046221 -229.298813) (xy 131.046221 -229.246879)
			(xy 131.054346 -229.195584) (xy 131.070394 -229.146191) (xy 131.093972 -229.099917) (xy 131.124498 -229.057901)
			(xy 131.161221 -229.021178) (xy 131.203237 -228.990652) (xy 131.249511 -228.967074) (xy 131.298904 -228.951026)
			(xy 131.350199 -228.942901) (xy 131.402133 -228.942901) (xy 131.453428 -228.951026) (xy 131.502821 -228.967074)
			(xy 131.549095 -228.990652) (xy 131.591111 -229.021178) (xy 131.627834 -229.057901) (xy 131.65836 -229.099917)
			(xy 131.681938 -229.146191) (xy 131.697986 -229.195584) (xy 131.706111 -229.246879) (xy 131.70662 -229.272846)
			(xy 131.706111 -229.298813) (xy 131.697986 -229.350108) (xy 131.681938 -229.399501) (xy 131.65836 -229.445775)
			(xy 131.627834 -229.487791) (xy 131.591111 -229.524514) (xy 131.549095 -229.55504) (xy 131.502821 -229.578618)
			(xy 131.453428 -229.594666) (xy 131.402133 -229.602791) (xy 131.350199 -229.602791) (xy 131.298904 -229.594666)
			(xy 131.249511 -229.578618) (xy 131.203237 -229.55504) (xy 131.161221 -229.524514) (xy 131.124498 -229.487791)
			(xy 131.093972 -229.445775) (xy 131.070394 -229.399501) (xy 131.054346 -229.350108) (xy 131.046221 -229.298813)
			(xy 130.766311 -229.298813) (xy 130.758186 -229.350108) (xy 130.742138 -229.399501) (xy 130.71856 -229.445775)
			(xy 130.688034 -229.487791) (xy 130.651311 -229.524514) (xy 130.609295 -229.55504) (xy 130.563021 -229.578618)
			(xy 130.513628 -229.594666) (xy 130.462333 -229.602791) (xy 130.410399 -229.602791) (xy 130.359104 -229.594666)
			(xy 130.309711 -229.578618) (xy 130.263437 -229.55504) (xy 130.221421 -229.524514) (xy 130.184698 -229.487791)
			(xy 130.154172 -229.445775) (xy 130.130594 -229.399501) (xy 130.114546 -229.350108) (xy 130.106421 -229.298813)
			(xy 129.826257 -229.298813) (xy 129.818132 -229.350108) (xy 129.802084 -229.399501) (xy 129.778506 -229.445775)
			(xy 129.74798 -229.487791) (xy 129.711257 -229.524514) (xy 129.669241 -229.55504) (xy 129.622967 -229.578618)
			(xy 129.573574 -229.594666) (xy 129.522279 -229.602791) (xy 129.470345 -229.602791) (xy 129.41905 -229.594666)
			(xy 129.369657 -229.578618) (xy 129.323383 -229.55504) (xy 129.281367 -229.524514) (xy 129.244644 -229.487791)
			(xy 129.214118 -229.445775) (xy 129.19054 -229.399501) (xy 129.174492 -229.350108) (xy 129.166367 -229.298813)
			(xy 128.886711 -229.298813) (xy 128.878586 -229.350108) (xy 128.862538 -229.399501) (xy 128.83896 -229.445775)
			(xy 128.808434 -229.487791) (xy 128.771711 -229.524514) (xy 128.729695 -229.55504) (xy 128.683421 -229.578618)
			(xy 128.634028 -229.594666) (xy 128.582733 -229.602791) (xy 128.530799 -229.602791) (xy 128.479504 -229.594666)
			(xy 128.430111 -229.578618) (xy 128.383837 -229.55504) (xy 128.341821 -229.524514) (xy 128.305098 -229.487791)
			(xy 128.274572 -229.445775) (xy 128.250994 -229.399501) (xy 128.234946 -229.350108) (xy 128.226821 -229.298813)
			(xy 127.946911 -229.298813) (xy 127.938786 -229.350108) (xy 127.922738 -229.399501) (xy 127.89916 -229.445775)
			(xy 127.868634 -229.487791) (xy 127.831911 -229.524514) (xy 127.789895 -229.55504) (xy 127.743621 -229.578618)
			(xy 127.694228 -229.594666) (xy 127.642933 -229.602791) (xy 127.590999 -229.602791) (xy 127.539704 -229.594666)
			(xy 127.490311 -229.578618) (xy 127.444037 -229.55504) (xy 127.402021 -229.524514) (xy 127.365298 -229.487791)
			(xy 127.334772 -229.445775) (xy 127.311194 -229.399501) (xy 127.295146 -229.350108) (xy 127.287021 -229.298813)
			(xy 127.007111 -229.298813) (xy 126.998986 -229.350108) (xy 126.982938 -229.399501) (xy 126.95936 -229.445775)
			(xy 126.928834 -229.487791) (xy 126.892111 -229.524514) (xy 126.850095 -229.55504) (xy 126.803821 -229.578618)
			(xy 126.754428 -229.594666) (xy 126.703133 -229.602791) (xy 126.651199 -229.602791) (xy 126.599904 -229.594666)
			(xy 126.550511 -229.578618) (xy 126.504237 -229.55504) (xy 126.462221 -229.524514) (xy 126.425498 -229.487791)
			(xy 126.394972 -229.445775) (xy 126.371394 -229.399501) (xy 126.355346 -229.350108) (xy 126.347221 -229.298813)
			(xy 126.067311 -229.298813) (xy 126.059186 -229.350108) (xy 126.043138 -229.399501) (xy 126.01956 -229.445775)
			(xy 125.989034 -229.487791) (xy 125.952311 -229.524514) (xy 125.910295 -229.55504) (xy 125.864021 -229.578618)
			(xy 125.814628 -229.594666) (xy 125.763333 -229.602791) (xy 125.711399 -229.602791) (xy 125.660104 -229.594666)
			(xy 125.610711 -229.578618) (xy 125.564437 -229.55504) (xy 125.522421 -229.524514) (xy 125.485698 -229.487791)
			(xy 125.455172 -229.445775) (xy 125.431594 -229.399501) (xy 125.415546 -229.350108) (xy 125.407421 -229.298813)
			(xy 125.127511 -229.298813) (xy 125.119386 -229.350108) (xy 125.103338 -229.399501) (xy 125.07976 -229.445775)
			(xy 125.049234 -229.487791) (xy 125.012511 -229.524514) (xy 124.970495 -229.55504) (xy 124.924221 -229.578618)
			(xy 124.874828 -229.594666) (xy 124.823533 -229.602791) (xy 124.771599 -229.602791) (xy 124.720304 -229.594666)
			(xy 124.670911 -229.578618) (xy 124.624637 -229.55504) (xy 124.582621 -229.524514) (xy 124.545898 -229.487791)
			(xy 124.515372 -229.445775) (xy 124.491794 -229.399501) (xy 124.475746 -229.350108) (xy 124.467621 -229.298813)
			(xy 124.187711 -229.298813) (xy 124.179586 -229.350108) (xy 124.163538 -229.399501) (xy 124.13996 -229.445775)
			(xy 124.109434 -229.487791) (xy 124.072711 -229.524514) (xy 124.030695 -229.55504) (xy 123.984421 -229.578618)
			(xy 123.935028 -229.594666) (xy 123.883733 -229.602791) (xy 123.831799 -229.602791) (xy 123.780504 -229.594666)
			(xy 123.731111 -229.578618) (xy 123.684837 -229.55504) (xy 123.642821 -229.524514) (xy 123.606098 -229.487791)
			(xy 123.575572 -229.445775) (xy 123.551994 -229.399501) (xy 123.535946 -229.350108) (xy 123.527821 -229.298813)
			(xy 123.247657 -229.298813) (xy 123.239532 -229.350108) (xy 123.223484 -229.399501) (xy 123.199906 -229.445775)
			(xy 123.16938 -229.487791) (xy 123.132657 -229.524514) (xy 123.090641 -229.55504) (xy 123.044367 -229.578618)
			(xy 122.994974 -229.594666) (xy 122.943679 -229.602791) (xy 122.891745 -229.602791) (xy 122.84045 -229.594666)
			(xy 122.791057 -229.578618) (xy 122.744783 -229.55504) (xy 122.702767 -229.524514) (xy 122.666044 -229.487791)
			(xy 122.635518 -229.445775) (xy 122.61194 -229.399501) (xy 122.595892 -229.350108) (xy 122.587767 -229.298813)
			(xy 122.308111 -229.298813) (xy 122.299986 -229.350108) (xy 122.283938 -229.399501) (xy 122.26036 -229.445775)
			(xy 122.229834 -229.487791) (xy 122.193111 -229.524514) (xy 122.151095 -229.55504) (xy 122.104821 -229.578618)
			(xy 122.055428 -229.594666) (xy 122.004133 -229.602791) (xy 121.952199 -229.602791) (xy 121.900904 -229.594666)
			(xy 121.851511 -229.578618) (xy 121.805237 -229.55504) (xy 121.763221 -229.524514) (xy 121.726498 -229.487791)
			(xy 121.695972 -229.445775) (xy 121.672394 -229.399501) (xy 121.656346 -229.350108) (xy 121.648221 -229.298813)
			(xy 121.368311 -229.298813) (xy 121.360186 -229.350108) (xy 121.344138 -229.399501) (xy 121.32056 -229.445775)
			(xy 121.290034 -229.487791) (xy 121.253311 -229.524514) (xy 121.211295 -229.55504) (xy 121.165021 -229.578618)
			(xy 121.115628 -229.594666) (xy 121.064333 -229.602791) (xy 121.012399 -229.602791) (xy 120.961104 -229.594666)
			(xy 120.911711 -229.578618) (xy 120.865437 -229.55504) (xy 120.823421 -229.524514) (xy 120.786698 -229.487791)
			(xy 120.756172 -229.445775) (xy 120.732594 -229.399501) (xy 120.716546 -229.350108) (xy 120.708421 -229.298813)
			(xy 120.428511 -229.298813) (xy 120.420386 -229.350108) (xy 120.404338 -229.399501) (xy 120.38076 -229.445775)
			(xy 120.350234 -229.487791) (xy 120.313511 -229.524514) (xy 120.271495 -229.55504) (xy 120.225221 -229.578618)
			(xy 120.175828 -229.594666) (xy 120.124533 -229.602791) (xy 120.072599 -229.602791) (xy 120.021304 -229.594666)
			(xy 119.971911 -229.578618) (xy 119.925637 -229.55504) (xy 119.883621 -229.524514) (xy 119.846898 -229.487791)
			(xy 119.816372 -229.445775) (xy 119.792794 -229.399501) (xy 119.776746 -229.350108) (xy 119.768621 -229.298813)
			(xy 119.488711 -229.298813) (xy 119.480586 -229.350108) (xy 119.464538 -229.399501) (xy 119.44096 -229.445775)
			(xy 119.410434 -229.487791) (xy 119.373711 -229.524514) (xy 119.331695 -229.55504) (xy 119.285421 -229.578618)
			(xy 119.236028 -229.594666) (xy 119.184733 -229.602791) (xy 119.132799 -229.602791) (xy 119.081504 -229.594666)
			(xy 119.032111 -229.578618) (xy 118.985837 -229.55504) (xy 118.943821 -229.524514) (xy 118.907098 -229.487791)
			(xy 118.876572 -229.445775) (xy 118.852994 -229.399501) (xy 118.836946 -229.350108) (xy 118.828821 -229.298813)
			(xy 118.548911 -229.298813) (xy 118.540786 -229.350108) (xy 118.524738 -229.399501) (xy 118.50116 -229.445775)
			(xy 118.470634 -229.487791) (xy 118.433911 -229.524514) (xy 118.391895 -229.55504) (xy 118.345621 -229.578618)
			(xy 118.296228 -229.594666) (xy 118.244933 -229.602791) (xy 118.192999 -229.602791) (xy 118.141704 -229.594666)
			(xy 118.092311 -229.578618) (xy 118.046037 -229.55504) (xy 118.004021 -229.524514) (xy 117.967298 -229.487791)
			(xy 117.936772 -229.445775) (xy 117.913194 -229.399501) (xy 117.897146 -229.350108) (xy 117.889021 -229.298813)
			(xy 117.609111 -229.298813) (xy 117.600986 -229.350108) (xy 117.584938 -229.399501) (xy 117.56136 -229.445775)
			(xy 117.530834 -229.487791) (xy 117.494111 -229.524514) (xy 117.452095 -229.55504) (xy 117.405821 -229.578618)
			(xy 117.356428 -229.594666) (xy 117.305133 -229.602791) (xy 117.253199 -229.602791) (xy 117.201904 -229.594666)
			(xy 117.152511 -229.578618) (xy 117.106237 -229.55504) (xy 117.064221 -229.524514) (xy 117.027498 -229.487791)
			(xy 116.996972 -229.445775) (xy 116.973394 -229.399501) (xy 116.957346 -229.350108) (xy 116.949221 -229.298813)
			(xy 116.669311 -229.298813) (xy 116.661186 -229.350108) (xy 116.645138 -229.399501) (xy 116.62156 -229.445775)
			(xy 116.591034 -229.487791) (xy 116.554311 -229.524514) (xy 116.512295 -229.55504) (xy 116.466021 -229.578618)
			(xy 116.416628 -229.594666) (xy 116.365333 -229.602791) (xy 116.313399 -229.602791) (xy 116.262104 -229.594666)
			(xy 116.212711 -229.578618) (xy 116.166437 -229.55504) (xy 116.124421 -229.524514) (xy 116.087698 -229.487791)
			(xy 116.057172 -229.445775) (xy 116.033594 -229.399501) (xy 116.017546 -229.350108) (xy 116.009421 -229.298813)
			(xy 115.729511 -229.298813) (xy 115.721386 -229.350108) (xy 115.705338 -229.399501) (xy 115.68176 -229.445775)
			(xy 115.651234 -229.487791) (xy 115.614511 -229.524514) (xy 115.572495 -229.55504) (xy 115.526221 -229.578618)
			(xy 115.476828 -229.594666) (xy 115.425533 -229.602791) (xy 115.373599 -229.602791) (xy 115.322304 -229.594666)
			(xy 115.272911 -229.578618) (xy 115.226637 -229.55504) (xy 115.184621 -229.524514) (xy 115.147898 -229.487791)
			(xy 115.117372 -229.445775) (xy 115.093794 -229.399501) (xy 115.077746 -229.350108) (xy 115.069621 -229.298813)
			(xy 114.789711 -229.298813) (xy 114.781586 -229.350108) (xy 114.765538 -229.399501) (xy 114.74196 -229.445775)
			(xy 114.711434 -229.487791) (xy 114.674711 -229.524514) (xy 114.632695 -229.55504) (xy 114.586421 -229.578618)
			(xy 114.537028 -229.594666) (xy 114.485733 -229.602791) (xy 114.433799 -229.602791) (xy 114.382504 -229.594666)
			(xy 114.333111 -229.578618) (xy 114.286837 -229.55504) (xy 114.244821 -229.524514) (xy 114.208098 -229.487791)
			(xy 114.177572 -229.445775) (xy 114.153994 -229.399501) (xy 114.137946 -229.350108) (xy 114.129821 -229.298813)
			(xy 113.849911 -229.298813) (xy 113.841786 -229.350108) (xy 113.825738 -229.399501) (xy 113.80216 -229.445775)
			(xy 113.771634 -229.487791) (xy 113.734911 -229.524514) (xy 113.692895 -229.55504) (xy 113.646621 -229.578618)
			(xy 113.597228 -229.594666) (xy 113.545933 -229.602791) (xy 113.493999 -229.602791) (xy 113.442704 -229.594666)
			(xy 113.393311 -229.578618) (xy 113.347037 -229.55504) (xy 113.305021 -229.524514) (xy 113.268298 -229.487791)
			(xy 113.237772 -229.445775) (xy 113.214194 -229.399501) (xy 113.198146 -229.350108) (xy 113.190021 -229.298813)
			(xy 112.910111 -229.298813) (xy 112.901986 -229.350108) (xy 112.885938 -229.399501) (xy 112.86236 -229.445775)
			(xy 112.831834 -229.487791) (xy 112.795111 -229.524514) (xy 112.753095 -229.55504) (xy 112.706821 -229.578618)
			(xy 112.657428 -229.594666) (xy 112.606133 -229.602791) (xy 112.554199 -229.602791) (xy 112.502904 -229.594666)
			(xy 112.453511 -229.578618) (xy 112.407237 -229.55504) (xy 112.365221 -229.524514) (xy 112.328498 -229.487791)
			(xy 112.297972 -229.445775) (xy 112.274394 -229.399501) (xy 112.258346 -229.350108) (xy 112.250221 -229.298813)
			(xy 111.970057 -229.298813) (xy 111.961932 -229.350108) (xy 111.945884 -229.399501) (xy 111.922306 -229.445775)
			(xy 111.89178 -229.487791) (xy 111.855057 -229.524514) (xy 111.813041 -229.55504) (xy 111.766767 -229.578618)
			(xy 111.717374 -229.594666) (xy 111.666079 -229.602791) (xy 111.614145 -229.602791) (xy 111.56285 -229.594666)
			(xy 111.513457 -229.578618) (xy 111.467183 -229.55504) (xy 111.425167 -229.524514) (xy 111.388444 -229.487791)
			(xy 111.357918 -229.445775) (xy 111.33434 -229.399501) (xy 111.318292 -229.350108) (xy 111.310167 -229.298813)
			(xy 111.030511 -229.298813) (xy 111.022386 -229.350108) (xy 111.006338 -229.399501) (xy 110.98276 -229.445775)
			(xy 110.952234 -229.487791) (xy 110.915511 -229.524514) (xy 110.873495 -229.55504) (xy 110.827221 -229.578618)
			(xy 110.777828 -229.594666) (xy 110.726533 -229.602791) (xy 110.674599 -229.602791) (xy 110.623304 -229.594666)
			(xy 110.573911 -229.578618) (xy 110.527637 -229.55504) (xy 110.485621 -229.524514) (xy 110.448898 -229.487791)
			(xy 110.418372 -229.445775) (xy 110.394794 -229.399501) (xy 110.378746 -229.350108) (xy 110.370621 -229.298813)
			(xy 110.090711 -229.298813) (xy 110.082586 -229.350108) (xy 110.066538 -229.399501) (xy 110.04296 -229.445775)
			(xy 110.012434 -229.487791) (xy 109.975711 -229.524514) (xy 109.933695 -229.55504) (xy 109.887421 -229.578618)
			(xy 109.838028 -229.594666) (xy 109.786733 -229.602791) (xy 109.734799 -229.602791) (xy 109.683504 -229.594666)
			(xy 109.634111 -229.578618) (xy 109.587837 -229.55504) (xy 109.545821 -229.524514) (xy 109.509098 -229.487791)
			(xy 109.478572 -229.445775) (xy 109.454994 -229.399501) (xy 109.438946 -229.350108) (xy 109.430821 -229.298813)
			(xy 109.150911 -229.298813) (xy 109.142786 -229.350108) (xy 109.126738 -229.399501) (xy 109.10316 -229.445775)
			(xy 109.072634 -229.487791) (xy 109.035911 -229.524514) (xy 108.993895 -229.55504) (xy 108.947621 -229.578618)
			(xy 108.898228 -229.594666) (xy 108.846933 -229.602791) (xy 108.794999 -229.602791) (xy 108.743704 -229.594666)
			(xy 108.694311 -229.578618) (xy 108.648037 -229.55504) (xy 108.606021 -229.524514) (xy 108.569298 -229.487791)
			(xy 108.538772 -229.445775) (xy 108.515194 -229.399501) (xy 108.499146 -229.350108) (xy 108.491021 -229.298813)
			(xy 108.211111 -229.298813) (xy 108.202986 -229.350108) (xy 108.186938 -229.399501) (xy 108.16336 -229.445775)
			(xy 108.132834 -229.487791) (xy 108.096111 -229.524514) (xy 108.054095 -229.55504) (xy 108.007821 -229.578618)
			(xy 107.958428 -229.594666) (xy 107.907133 -229.602791) (xy 107.855199 -229.602791) (xy 107.803904 -229.594666)
			(xy 107.754511 -229.578618) (xy 107.708237 -229.55504) (xy 107.666221 -229.524514) (xy 107.629498 -229.487791)
			(xy 107.598972 -229.445775) (xy 107.575394 -229.399501) (xy 107.559346 -229.350108) (xy 107.551221 -229.298813)
			(xy 107.271311 -229.298813) (xy 107.263186 -229.350108) (xy 107.247138 -229.399501) (xy 107.22356 -229.445775)
			(xy 107.193034 -229.487791) (xy 107.156311 -229.524514) (xy 107.114295 -229.55504) (xy 107.068021 -229.578618)
			(xy 107.018628 -229.594666) (xy 106.967333 -229.602791) (xy 106.915399 -229.602791) (xy 106.864104 -229.594666)
			(xy 106.814711 -229.578618) (xy 106.768437 -229.55504) (xy 106.726421 -229.524514) (xy 106.689698 -229.487791)
			(xy 106.659172 -229.445775) (xy 106.635594 -229.399501) (xy 106.619546 -229.350108) (xy 106.611421 -229.298813)
			(xy 106.331511 -229.298813) (xy 106.323386 -229.350108) (xy 106.307338 -229.399501) (xy 106.28376 -229.445775)
			(xy 106.253234 -229.487791) (xy 106.216511 -229.524514) (xy 106.174495 -229.55504) (xy 106.128221 -229.578618)
			(xy 106.078828 -229.594666) (xy 106.027533 -229.602791) (xy 105.975599 -229.602791) (xy 105.924304 -229.594666)
			(xy 105.874911 -229.578618) (xy 105.828637 -229.55504) (xy 105.786621 -229.524514) (xy 105.749898 -229.487791)
			(xy 105.719372 -229.445775) (xy 105.695794 -229.399501) (xy 105.679746 -229.350108) (xy 105.671621 -229.298813)
			(xy 105.391476 -229.298813) (xy 105.38471 -229.344772) (xy 105.3708 -229.391019) (xy 105.350308 -229.434751)
			(xy 105.323672 -229.475035) (xy 105.307892 -229.493318) (xy 105.275888 -229.529132) (xy 105.415588 -229.668832)
			(xy 105.418153 -229.683568) (xy 105.430615 -229.710744) (xy 105.45042 -229.733139) (xy 105.475867 -229.74883)
			(xy 105.504771 -229.756469) (xy 105.519728 -229.756462) (xy 105.531412 -229.756208) (xy 105.557376 -229.756794)
			(xy 105.608663 -229.764919) (xy 105.658049 -229.780967) (xy 105.704316 -229.804542) (xy 105.746325 -229.835065)
			(xy 105.783042 -229.871784) (xy 105.813564 -229.913795) (xy 105.837138 -229.960062) (xy 105.853184 -230.009448)
			(xy 105.861307 -230.060736) (xy 105.861307 -230.112629) (xy 106.141521 -230.112629) (xy 106.141521 -230.060695)
			(xy 106.149646 -230.0094) (xy 106.165694 -229.960007) (xy 106.189272 -229.913733) (xy 106.219798 -229.871717)
			(xy 106.256521 -229.834994) (xy 106.298537 -229.804468) (xy 106.344811 -229.78089) (xy 106.394204 -229.764842)
			(xy 106.445499 -229.756717) (xy 106.497433 -229.756717) (xy 106.548728 -229.764842) (xy 106.598121 -229.78089)
			(xy 106.644395 -229.804468) (xy 106.686411 -229.834994) (xy 106.723134 -229.871717) (xy 106.75366 -229.913733)
			(xy 106.777238 -229.960007) (xy 106.793286 -230.0094) (xy 106.801411 -230.060695) (xy 106.80192 -230.086662)
			(xy 106.801411 -230.112629) (xy 107.081067 -230.112629) (xy 107.081067 -230.060695) (xy 107.089192 -230.0094)
			(xy 107.10524 -229.960007) (xy 107.128818 -229.913733) (xy 107.159344 -229.871717) (xy 107.196067 -229.834994)
			(xy 107.238083 -229.804468) (xy 107.284357 -229.78089) (xy 107.33375 -229.764842) (xy 107.385045 -229.756717)
			(xy 107.436979 -229.756717) (xy 107.488274 -229.764842) (xy 107.537667 -229.78089) (xy 107.583941 -229.804468)
			(xy 107.625957 -229.834994) (xy 107.66268 -229.871717) (xy 107.693206 -229.913733) (xy 107.716784 -229.960007)
			(xy 107.732832 -230.0094) (xy 107.740957 -230.060695) (xy 107.741466 -230.086662) (xy 107.740957 -230.112629)
			(xy 108.020867 -230.112629) (xy 108.020867 -230.060695) (xy 108.028992 -230.0094) (xy 108.04504 -229.960007)
			(xy 108.068618 -229.913733) (xy 108.099144 -229.871717) (xy 108.135867 -229.834994) (xy 108.177883 -229.804468)
			(xy 108.224157 -229.78089) (xy 108.27355 -229.764842) (xy 108.324845 -229.756717) (xy 108.376779 -229.756717)
			(xy 108.428074 -229.764842) (xy 108.477467 -229.78089) (xy 108.523741 -229.804468) (xy 108.565757 -229.834994)
			(xy 108.60248 -229.871717) (xy 108.633006 -229.913733) (xy 108.656584 -229.960007) (xy 108.672632 -230.0094)
			(xy 108.680757 -230.060695) (xy 108.681266 -230.086662) (xy 108.680757 -230.112629) (xy 108.960667 -230.112629)
			(xy 108.960667 -230.060695) (xy 108.968792 -230.0094) (xy 108.98484 -229.960007) (xy 109.008418 -229.913733)
			(xy 109.038944 -229.871717) (xy 109.075667 -229.834994) (xy 109.117683 -229.804468) (xy 109.163957 -229.78089)
			(xy 109.21335 -229.764842) (xy 109.264645 -229.756717) (xy 109.316579 -229.756717) (xy 109.367874 -229.764842)
			(xy 109.417267 -229.78089) (xy 109.463541 -229.804468) (xy 109.505557 -229.834994) (xy 109.54228 -229.871717)
			(xy 109.572806 -229.913733) (xy 109.596384 -229.960007) (xy 109.612432 -230.0094) (xy 109.620557 -230.060695)
			(xy 109.621066 -230.086662) (xy 109.620557 -230.112629) (xy 109.900467 -230.112629) (xy 109.900467 -230.060695)
			(xy 109.908592 -230.0094) (xy 109.92464 -229.960007) (xy 109.948218 -229.913733) (xy 109.978744 -229.871717)
			(xy 110.015467 -229.834994) (xy 110.057483 -229.804468) (xy 110.103757 -229.78089) (xy 110.15315 -229.764842)
			(xy 110.204445 -229.756717) (xy 110.256379 -229.756717) (xy 110.307674 -229.764842) (xy 110.357067 -229.78089)
			(xy 110.403341 -229.804468) (xy 110.445357 -229.834994) (xy 110.48208 -229.871717) (xy 110.512606 -229.913733)
			(xy 110.536184 -229.960007) (xy 110.552232 -230.0094) (xy 110.560357 -230.060695) (xy 110.560866 -230.086662)
			(xy 110.560357 -230.112629) (xy 110.840521 -230.112629) (xy 110.840521 -230.060695) (xy 110.848646 -230.0094)
			(xy 110.864694 -229.960007) (xy 110.888272 -229.913733) (xy 110.918798 -229.871717) (xy 110.955521 -229.834994)
			(xy 110.997537 -229.804468) (xy 111.043811 -229.78089) (xy 111.093204 -229.764842) (xy 111.144499 -229.756717)
			(xy 111.196433 -229.756717) (xy 111.247728 -229.764842) (xy 111.297121 -229.78089) (xy 111.343395 -229.804468)
			(xy 111.385411 -229.834994) (xy 111.422134 -229.871717) (xy 111.45266 -229.913733) (xy 111.476238 -229.960007)
			(xy 111.492286 -230.0094) (xy 111.500411 -230.060695) (xy 111.50092 -230.086662) (xy 111.500411 -230.112629)
			(xy 111.780321 -230.112629) (xy 111.780321 -230.060695) (xy 111.788446 -230.0094) (xy 111.804494 -229.960007)
			(xy 111.828072 -229.913733) (xy 111.858598 -229.871717) (xy 111.895321 -229.834994) (xy 111.937337 -229.804468)
			(xy 111.983611 -229.78089) (xy 112.033004 -229.764842) (xy 112.084299 -229.756717) (xy 112.136233 -229.756717)
			(xy 112.187528 -229.764842) (xy 112.236921 -229.78089) (xy 112.283195 -229.804468) (xy 112.325211 -229.834994)
			(xy 112.361934 -229.871717) (xy 112.39246 -229.913733) (xy 112.416038 -229.960007) (xy 112.432086 -230.0094)
			(xy 112.440211 -230.060695) (xy 112.44072 -230.086662) (xy 112.440211 -230.112629) (xy 112.720121 -230.112629)
			(xy 112.720121 -230.060695) (xy 112.728246 -230.0094) (xy 112.744294 -229.960007) (xy 112.767872 -229.913733)
			(xy 112.798398 -229.871717) (xy 112.835121 -229.834994) (xy 112.877137 -229.804468) (xy 112.923411 -229.78089)
			(xy 112.972804 -229.764842) (xy 113.024099 -229.756717) (xy 113.076033 -229.756717) (xy 113.127328 -229.764842)
			(xy 113.176721 -229.78089) (xy 113.222995 -229.804468) (xy 113.265011 -229.834994) (xy 113.301734 -229.871717)
			(xy 113.33226 -229.913733) (xy 113.355838 -229.960007) (xy 113.371886 -230.0094) (xy 113.380011 -230.060695)
			(xy 113.38052 -230.086662) (xy 113.380011 -230.112629) (xy 113.659921 -230.112629) (xy 113.659921 -230.060695)
			(xy 113.668046 -230.0094) (xy 113.684094 -229.960007) (xy 113.707672 -229.913733) (xy 113.738198 -229.871717)
			(xy 113.774921 -229.834994) (xy 113.816937 -229.804468) (xy 113.863211 -229.78089) (xy 113.912604 -229.764842)
			(xy 113.963899 -229.756717) (xy 114.015833 -229.756717) (xy 114.067128 -229.764842) (xy 114.116521 -229.78089)
			(xy 114.162795 -229.804468) (xy 114.204811 -229.834994) (xy 114.241534 -229.871717) (xy 114.27206 -229.913733)
			(xy 114.295638 -229.960007) (xy 114.311686 -230.0094) (xy 114.319811 -230.060695) (xy 114.32032 -230.086662)
			(xy 114.319811 -230.112629) (xy 114.599721 -230.112629) (xy 114.599721 -230.060695) (xy 114.607846 -230.0094)
			(xy 114.623894 -229.960007) (xy 114.647472 -229.913733) (xy 114.677998 -229.871717) (xy 114.714721 -229.834994)
			(xy 114.756737 -229.804468) (xy 114.803011 -229.78089) (xy 114.852404 -229.764842) (xy 114.903699 -229.756717)
			(xy 114.955633 -229.756717) (xy 115.006928 -229.764842) (xy 115.056321 -229.78089) (xy 115.102595 -229.804468)
			(xy 115.144611 -229.834994) (xy 115.181334 -229.871717) (xy 115.21186 -229.913733) (xy 115.235438 -229.960007)
			(xy 115.251486 -230.0094) (xy 115.259611 -230.060695) (xy 115.26012 -230.086662) (xy 115.259611 -230.112629)
			(xy 115.539267 -230.112629) (xy 115.539267 -230.060695) (xy 115.547392 -230.0094) (xy 115.56344 -229.960007)
			(xy 115.587018 -229.913733) (xy 115.617544 -229.871717) (xy 115.654267 -229.834994) (xy 115.696283 -229.804468)
			(xy 115.742557 -229.78089) (xy 115.79195 -229.764842) (xy 115.843245 -229.756717) (xy 115.895179 -229.756717)
			(xy 115.946474 -229.764842) (xy 115.995867 -229.78089) (xy 116.042141 -229.804468) (xy 116.084157 -229.834994)
			(xy 116.12088 -229.871717) (xy 116.151406 -229.913733) (xy 116.174984 -229.960007) (xy 116.191032 -230.0094)
			(xy 116.199157 -230.060695) (xy 116.199666 -230.086662) (xy 116.199157 -230.112629) (xy 116.479067 -230.112629)
			(xy 116.479067 -230.060695) (xy 116.487192 -230.0094) (xy 116.50324 -229.960007) (xy 116.526818 -229.913733)
			(xy 116.557344 -229.871717) (xy 116.594067 -229.834994) (xy 116.636083 -229.804468) (xy 116.682357 -229.78089)
			(xy 116.73175 -229.764842) (xy 116.783045 -229.756717) (xy 116.834979 -229.756717) (xy 116.886274 -229.764842)
			(xy 116.935667 -229.78089) (xy 116.981941 -229.804468) (xy 117.023957 -229.834994) (xy 117.06068 -229.871717)
			(xy 117.091206 -229.913733) (xy 117.114784 -229.960007) (xy 117.130832 -230.0094) (xy 117.138957 -230.060695)
			(xy 117.139466 -230.086662) (xy 117.138957 -230.112629) (xy 117.418867 -230.112629) (xy 117.418867 -230.060695)
			(xy 117.426992 -230.0094) (xy 117.44304 -229.960007) (xy 117.466618 -229.913733) (xy 117.497144 -229.871717)
			(xy 117.533867 -229.834994) (xy 117.575883 -229.804468) (xy 117.622157 -229.78089) (xy 117.67155 -229.764842)
			(xy 117.722845 -229.756717) (xy 117.774779 -229.756717) (xy 117.826074 -229.764842) (xy 117.875467 -229.78089)
			(xy 117.921741 -229.804468) (xy 117.963757 -229.834994) (xy 118.00048 -229.871717) (xy 118.031006 -229.913733)
			(xy 118.054584 -229.960007) (xy 118.070632 -230.0094) (xy 118.078757 -230.060695) (xy 118.079266 -230.086662)
			(xy 118.078757 -230.112629) (xy 118.358667 -230.112629) (xy 118.358667 -230.060695) (xy 118.366792 -230.0094)
			(xy 118.38284 -229.960007) (xy 118.406418 -229.913733) (xy 118.436944 -229.871717) (xy 118.473667 -229.834994)
			(xy 118.515683 -229.804468) (xy 118.561957 -229.78089) (xy 118.61135 -229.764842) (xy 118.662645 -229.756717)
			(xy 118.714579 -229.756717) (xy 118.765874 -229.764842) (xy 118.815267 -229.78089) (xy 118.861541 -229.804468)
			(xy 118.903557 -229.834994) (xy 118.94028 -229.871717) (xy 118.970806 -229.913733) (xy 118.994384 -229.960007)
			(xy 119.010432 -230.0094) (xy 119.018557 -230.060695) (xy 119.019066 -230.086662) (xy 119.018557 -230.112629)
			(xy 119.298467 -230.112629) (xy 119.298467 -230.060695) (xy 119.306592 -230.0094) (xy 119.32264 -229.960007)
			(xy 119.346218 -229.913733) (xy 119.376744 -229.871717) (xy 119.413467 -229.834994) (xy 119.455483 -229.804468)
			(xy 119.501757 -229.78089) (xy 119.55115 -229.764842) (xy 119.602445 -229.756717) (xy 119.654379 -229.756717)
			(xy 119.705674 -229.764842) (xy 119.755067 -229.78089) (xy 119.801341 -229.804468) (xy 119.843357 -229.834994)
			(xy 119.88008 -229.871717) (xy 119.910606 -229.913733) (xy 119.934184 -229.960007) (xy 119.950232 -230.0094)
			(xy 119.958357 -230.060695) (xy 119.958866 -230.086662) (xy 119.958357 -230.112629) (xy 120.238267 -230.112629)
			(xy 120.238267 -230.060695) (xy 120.246392 -230.0094) (xy 120.26244 -229.960007) (xy 120.286018 -229.913733)
			(xy 120.316544 -229.871717) (xy 120.353267 -229.834994) (xy 120.395283 -229.804468) (xy 120.441557 -229.78089)
			(xy 120.49095 -229.764842) (xy 120.542245 -229.756717) (xy 120.594179 -229.756717) (xy 120.645474 -229.764842)
			(xy 120.694867 -229.78089) (xy 120.741141 -229.804468) (xy 120.783157 -229.834994) (xy 120.81988 -229.871717)
			(xy 120.850406 -229.913733) (xy 120.873984 -229.960007) (xy 120.890032 -230.0094) (xy 120.898157 -230.060695)
			(xy 120.898666 -230.086662) (xy 120.898157 -230.112629) (xy 121.178067 -230.112629) (xy 121.178067 -230.060695)
			(xy 121.186192 -230.0094) (xy 121.20224 -229.960007) (xy 121.225818 -229.913733) (xy 121.256344 -229.871717)
			(xy 121.293067 -229.834994) (xy 121.335083 -229.804468) (xy 121.381357 -229.78089) (xy 121.43075 -229.764842)
			(xy 121.482045 -229.756717) (xy 121.533979 -229.756717) (xy 121.585274 -229.764842) (xy 121.634667 -229.78089)
			(xy 121.680941 -229.804468) (xy 121.722957 -229.834994) (xy 121.75968 -229.871717) (xy 121.790206 -229.913733)
			(xy 121.813784 -229.960007) (xy 121.829832 -230.0094) (xy 121.837957 -230.060695) (xy 121.838466 -230.086662)
			(xy 121.837957 -230.112629) (xy 122.117867 -230.112629) (xy 122.117867 -230.060695) (xy 122.125992 -230.0094)
			(xy 122.14204 -229.960007) (xy 122.165618 -229.913733) (xy 122.196144 -229.871717) (xy 122.232867 -229.834994)
			(xy 122.274883 -229.804468) (xy 122.321157 -229.78089) (xy 122.37055 -229.764842) (xy 122.421845 -229.756717)
			(xy 122.473779 -229.756717) (xy 122.525074 -229.764842) (xy 122.574467 -229.78089) (xy 122.620741 -229.804468)
			(xy 122.662757 -229.834994) (xy 122.69948 -229.871717) (xy 122.730006 -229.913733) (xy 122.753584 -229.960007)
			(xy 122.769632 -230.0094) (xy 122.777757 -230.060695) (xy 122.778266 -230.086662) (xy 122.777757 -230.112629)
			(xy 123.057667 -230.112629) (xy 123.057667 -230.060695) (xy 123.065792 -230.0094) (xy 123.08184 -229.960007)
			(xy 123.105418 -229.913733) (xy 123.135944 -229.871717) (xy 123.172667 -229.834994) (xy 123.214683 -229.804468)
			(xy 123.260957 -229.78089) (xy 123.31035 -229.764842) (xy 123.361645 -229.756717) (xy 123.413579 -229.756717)
			(xy 123.464874 -229.764842) (xy 123.514267 -229.78089) (xy 123.560541 -229.804468) (xy 123.602557 -229.834994)
			(xy 123.63928 -229.871717) (xy 123.669806 -229.913733) (xy 123.693384 -229.960007) (xy 123.709432 -230.0094)
			(xy 123.717557 -230.060695) (xy 123.718066 -230.086662) (xy 123.717557 -230.112629) (xy 123.997467 -230.112629)
			(xy 123.997467 -230.060695) (xy 124.005592 -230.0094) (xy 124.02164 -229.960007) (xy 124.045218 -229.913733)
			(xy 124.075744 -229.871717) (xy 124.112467 -229.834994) (xy 124.154483 -229.804468) (xy 124.200757 -229.78089)
			(xy 124.25015 -229.764842) (xy 124.301445 -229.756717) (xy 124.353379 -229.756717) (xy 124.404674 -229.764842)
			(xy 124.454067 -229.78089) (xy 124.500341 -229.804468) (xy 124.542357 -229.834994) (xy 124.57908 -229.871717)
			(xy 124.609606 -229.913733) (xy 124.633184 -229.960007) (xy 124.649232 -230.0094) (xy 124.657357 -230.060695)
			(xy 124.657866 -230.086662) (xy 124.657357 -230.112629) (xy 124.937521 -230.112629) (xy 124.937521 -230.060695)
			(xy 124.945646 -230.0094) (xy 124.961694 -229.960007) (xy 124.985272 -229.913733) (xy 125.015798 -229.871717)
			(xy 125.052521 -229.834994) (xy 125.094537 -229.804468) (xy 125.140811 -229.78089) (xy 125.190204 -229.764842)
			(xy 125.241499 -229.756717) (xy 125.293433 -229.756717) (xy 125.344728 -229.764842) (xy 125.394121 -229.78089)
			(xy 125.440395 -229.804468) (xy 125.482411 -229.834994) (xy 125.519134 -229.871717) (xy 125.54966 -229.913733)
			(xy 125.573238 -229.960007) (xy 125.589286 -230.0094) (xy 125.597411 -230.060695) (xy 125.59792 -230.086662)
			(xy 125.597411 -230.112629) (xy 125.877067 -230.112629) (xy 125.877067 -230.060695) (xy 125.885192 -230.0094)
			(xy 125.90124 -229.960007) (xy 125.924818 -229.913733) (xy 125.955344 -229.871717) (xy 125.992067 -229.834994)
			(xy 126.034083 -229.804468) (xy 126.080357 -229.78089) (xy 126.12975 -229.764842) (xy 126.181045 -229.756717)
			(xy 126.232979 -229.756717) (xy 126.284274 -229.764842) (xy 126.333667 -229.78089) (xy 126.379941 -229.804468)
			(xy 126.421957 -229.834994) (xy 126.45868 -229.871717) (xy 126.489206 -229.913733) (xy 126.512784 -229.960007)
			(xy 126.528832 -230.0094) (xy 126.536957 -230.060695) (xy 126.537466 -230.086662) (xy 126.536957 -230.112629)
			(xy 126.816867 -230.112629) (xy 126.816867 -230.060695) (xy 126.824992 -230.0094) (xy 126.84104 -229.960007)
			(xy 126.864618 -229.913733) (xy 126.895144 -229.871717) (xy 126.931867 -229.834994) (xy 126.973883 -229.804468)
			(xy 127.020157 -229.78089) (xy 127.06955 -229.764842) (xy 127.120845 -229.756717) (xy 127.172779 -229.756717)
			(xy 127.224074 -229.764842) (xy 127.273467 -229.78089) (xy 127.319741 -229.804468) (xy 127.361757 -229.834994)
			(xy 127.39848 -229.871717) (xy 127.429006 -229.913733) (xy 127.452584 -229.960007) (xy 127.468632 -230.0094)
			(xy 127.476757 -230.060695) (xy 127.477266 -230.086662) (xy 127.476757 -230.112629) (xy 127.756667 -230.112629)
			(xy 127.756667 -230.060695) (xy 127.764792 -230.0094) (xy 127.78084 -229.960007) (xy 127.804418 -229.913733)
			(xy 127.834944 -229.871717) (xy 127.871667 -229.834994) (xy 127.913683 -229.804468) (xy 127.959957 -229.78089)
			(xy 128.00935 -229.764842) (xy 128.060645 -229.756717) (xy 128.112579 -229.756717) (xy 128.163874 -229.764842)
			(xy 128.213267 -229.78089) (xy 128.259541 -229.804468) (xy 128.301557 -229.834994) (xy 128.33828 -229.871717)
			(xy 128.368806 -229.913733) (xy 128.392384 -229.960007) (xy 128.408432 -230.0094) (xy 128.416557 -230.060695)
			(xy 128.417066 -230.086662) (xy 128.416557 -230.112629) (xy 128.696467 -230.112629) (xy 128.696467 -230.060695)
			(xy 128.704592 -230.0094) (xy 128.72064 -229.960007) (xy 128.744218 -229.913733) (xy 128.774744 -229.871717)
			(xy 128.811467 -229.834994) (xy 128.853483 -229.804468) (xy 128.899757 -229.78089) (xy 128.94915 -229.764842)
			(xy 129.000445 -229.756717) (xy 129.052379 -229.756717) (xy 129.103674 -229.764842) (xy 129.153067 -229.78089)
			(xy 129.199341 -229.804468) (xy 129.241357 -229.834994) (xy 129.27808 -229.871717) (xy 129.308606 -229.913733)
			(xy 129.332184 -229.960007) (xy 129.348232 -230.0094) (xy 129.356357 -230.060695) (xy 129.356866 -230.086662)
			(xy 129.356357 -230.112629) (xy 129.636267 -230.112629) (xy 129.636267 -230.060695) (xy 129.644392 -230.0094)
			(xy 129.66044 -229.960007) (xy 129.684018 -229.913733) (xy 129.714544 -229.871717) (xy 129.751267 -229.834994)
			(xy 129.793283 -229.804468) (xy 129.839557 -229.78089) (xy 129.88895 -229.764842) (xy 129.940245 -229.756717)
			(xy 129.992179 -229.756717) (xy 130.043474 -229.764842) (xy 130.092867 -229.78089) (xy 130.139141 -229.804468)
			(xy 130.181157 -229.834994) (xy 130.21788 -229.871717) (xy 130.248406 -229.913733) (xy 130.271984 -229.960007)
			(xy 130.288032 -230.0094) (xy 130.296157 -230.060695) (xy 130.296666 -230.086662) (xy 130.296157 -230.112629)
			(xy 130.576067 -230.112629) (xy 130.576067 -230.060695) (xy 130.584192 -230.0094) (xy 130.60024 -229.960007)
			(xy 130.623818 -229.913733) (xy 130.654344 -229.871717) (xy 130.691067 -229.834994) (xy 130.733083 -229.804468)
			(xy 130.779357 -229.78089) (xy 130.82875 -229.764842) (xy 130.880045 -229.756717) (xy 130.931979 -229.756717)
			(xy 130.983274 -229.764842) (xy 131.032667 -229.78089) (xy 131.078941 -229.804468) (xy 131.120957 -229.834994)
			(xy 131.15768 -229.871717) (xy 131.188206 -229.913733) (xy 131.211784 -229.960007) (xy 131.227832 -230.0094)
			(xy 131.235957 -230.060695) (xy 131.236466 -230.086662) (xy 131.235957 -230.112629) (xy 131.227832 -230.163924)
			(xy 131.211784 -230.213317) (xy 131.188206 -230.259591) (xy 131.15768 -230.301607) (xy 131.120957 -230.33833)
			(xy 131.078941 -230.368856) (xy 131.032667 -230.392434) (xy 130.983274 -230.408482) (xy 130.931979 -230.416607)
			(xy 130.880045 -230.416607) (xy 130.82875 -230.408482) (xy 130.779357 -230.392434) (xy 130.733083 -230.368856)
			(xy 130.691067 -230.33833) (xy 130.654344 -230.301607) (xy 130.623818 -230.259591) (xy 130.60024 -230.213317)
			(xy 130.584192 -230.163924) (xy 130.576067 -230.112629) (xy 130.296157 -230.112629) (xy 130.288032 -230.163924)
			(xy 130.271984 -230.213317) (xy 130.248406 -230.259591) (xy 130.21788 -230.301607) (xy 130.181157 -230.33833)
			(xy 130.139141 -230.368856) (xy 130.092867 -230.392434) (xy 130.043474 -230.408482) (xy 129.992179 -230.416607)
			(xy 129.940245 -230.416607) (xy 129.88895 -230.408482) (xy 129.839557 -230.392434) (xy 129.793283 -230.368856)
			(xy 129.751267 -230.33833) (xy 129.714544 -230.301607) (xy 129.684018 -230.259591) (xy 129.66044 -230.213317)
			(xy 129.644392 -230.163924) (xy 129.636267 -230.112629) (xy 129.356357 -230.112629) (xy 129.348232 -230.163924)
			(xy 129.332184 -230.213317) (xy 129.308606 -230.259591) (xy 129.27808 -230.301607) (xy 129.241357 -230.33833)
			(xy 129.199341 -230.368856) (xy 129.153067 -230.392434) (xy 129.103674 -230.408482) (xy 129.052379 -230.416607)
			(xy 129.000445 -230.416607) (xy 128.94915 -230.408482) (xy 128.899757 -230.392434) (xy 128.853483 -230.368856)
			(xy 128.811467 -230.33833) (xy 128.774744 -230.301607) (xy 128.744218 -230.259591) (xy 128.72064 -230.213317)
			(xy 128.704592 -230.163924) (xy 128.696467 -230.112629) (xy 128.416557 -230.112629) (xy 128.408432 -230.163924)
			(xy 128.392384 -230.213317) (xy 128.368806 -230.259591) (xy 128.33828 -230.301607) (xy 128.301557 -230.33833)
			(xy 128.259541 -230.368856) (xy 128.213267 -230.392434) (xy 128.163874 -230.408482) (xy 128.112579 -230.416607)
			(xy 128.060645 -230.416607) (xy 128.00935 -230.408482) (xy 127.959957 -230.392434) (xy 127.913683 -230.368856)
			(xy 127.871667 -230.33833) (xy 127.834944 -230.301607) (xy 127.804418 -230.259591) (xy 127.78084 -230.213317)
			(xy 127.764792 -230.163924) (xy 127.756667 -230.112629) (xy 127.476757 -230.112629) (xy 127.468632 -230.163924)
			(xy 127.452584 -230.213317) (xy 127.429006 -230.259591) (xy 127.39848 -230.301607) (xy 127.361757 -230.33833)
			(xy 127.319741 -230.368856) (xy 127.273467 -230.392434) (xy 127.224074 -230.408482) (xy 127.172779 -230.416607)
			(xy 127.120845 -230.416607) (xy 127.06955 -230.408482) (xy 127.020157 -230.392434) (xy 126.973883 -230.368856)
			(xy 126.931867 -230.33833) (xy 126.895144 -230.301607) (xy 126.864618 -230.259591) (xy 126.84104 -230.213317)
			(xy 126.824992 -230.163924) (xy 126.816867 -230.112629) (xy 126.536957 -230.112629) (xy 126.528832 -230.163924)
			(xy 126.512784 -230.213317) (xy 126.489206 -230.259591) (xy 126.45868 -230.301607) (xy 126.421957 -230.33833)
			(xy 126.379941 -230.368856) (xy 126.333667 -230.392434) (xy 126.284274 -230.408482) (xy 126.232979 -230.416607)
			(xy 126.181045 -230.416607) (xy 126.12975 -230.408482) (xy 126.080357 -230.392434) (xy 126.034083 -230.368856)
			(xy 125.992067 -230.33833) (xy 125.955344 -230.301607) (xy 125.924818 -230.259591) (xy 125.90124 -230.213317)
			(xy 125.885192 -230.163924) (xy 125.877067 -230.112629) (xy 125.597411 -230.112629) (xy 125.589286 -230.163924)
			(xy 125.573238 -230.213317) (xy 125.54966 -230.259591) (xy 125.519134 -230.301607) (xy 125.482411 -230.33833)
			(xy 125.440395 -230.368856) (xy 125.394121 -230.392434) (xy 125.344728 -230.408482) (xy 125.293433 -230.416607)
			(xy 125.241499 -230.416607) (xy 125.190204 -230.408482) (xy 125.140811 -230.392434) (xy 125.094537 -230.368856)
			(xy 125.052521 -230.33833) (xy 125.015798 -230.301607) (xy 124.985272 -230.259591) (xy 124.961694 -230.213317)
			(xy 124.945646 -230.163924) (xy 124.937521 -230.112629) (xy 124.657357 -230.112629) (xy 124.649232 -230.163924)
			(xy 124.633184 -230.213317) (xy 124.609606 -230.259591) (xy 124.57908 -230.301607) (xy 124.542357 -230.33833)
			(xy 124.500341 -230.368856) (xy 124.454067 -230.392434) (xy 124.404674 -230.408482) (xy 124.353379 -230.416607)
			(xy 124.301445 -230.416607) (xy 124.25015 -230.408482) (xy 124.200757 -230.392434) (xy 124.154483 -230.368856)
			(xy 124.112467 -230.33833) (xy 124.075744 -230.301607) (xy 124.045218 -230.259591) (xy 124.02164 -230.213317)
			(xy 124.005592 -230.163924) (xy 123.997467 -230.112629) (xy 123.717557 -230.112629) (xy 123.709432 -230.163924)
			(xy 123.693384 -230.213317) (xy 123.669806 -230.259591) (xy 123.63928 -230.301607) (xy 123.602557 -230.33833)
			(xy 123.560541 -230.368856) (xy 123.514267 -230.392434) (xy 123.464874 -230.408482) (xy 123.413579 -230.416607)
			(xy 123.361645 -230.416607) (xy 123.31035 -230.408482) (xy 123.260957 -230.392434) (xy 123.214683 -230.368856)
			(xy 123.172667 -230.33833) (xy 123.135944 -230.301607) (xy 123.105418 -230.259591) (xy 123.08184 -230.213317)
			(xy 123.065792 -230.163924) (xy 123.057667 -230.112629) (xy 122.777757 -230.112629) (xy 122.769632 -230.163924)
			(xy 122.753584 -230.213317) (xy 122.730006 -230.259591) (xy 122.69948 -230.301607) (xy 122.662757 -230.33833)
			(xy 122.620741 -230.368856) (xy 122.574467 -230.392434) (xy 122.525074 -230.408482) (xy 122.473779 -230.416607)
			(xy 122.421845 -230.416607) (xy 122.37055 -230.408482) (xy 122.321157 -230.392434) (xy 122.274883 -230.368856)
			(xy 122.232867 -230.33833) (xy 122.196144 -230.301607) (xy 122.165618 -230.259591) (xy 122.14204 -230.213317)
			(xy 122.125992 -230.163924) (xy 122.117867 -230.112629) (xy 121.837957 -230.112629) (xy 121.829832 -230.163924)
			(xy 121.813784 -230.213317) (xy 121.790206 -230.259591) (xy 121.75968 -230.301607) (xy 121.722957 -230.33833)
			(xy 121.680941 -230.368856) (xy 121.634667 -230.392434) (xy 121.585274 -230.408482) (xy 121.533979 -230.416607)
			(xy 121.482045 -230.416607) (xy 121.43075 -230.408482) (xy 121.381357 -230.392434) (xy 121.335083 -230.368856)
			(xy 121.293067 -230.33833) (xy 121.256344 -230.301607) (xy 121.225818 -230.259591) (xy 121.20224 -230.213317)
			(xy 121.186192 -230.163924) (xy 121.178067 -230.112629) (xy 120.898157 -230.112629) (xy 120.890032 -230.163924)
			(xy 120.873984 -230.213317) (xy 120.850406 -230.259591) (xy 120.81988 -230.301607) (xy 120.783157 -230.33833)
			(xy 120.741141 -230.368856) (xy 120.694867 -230.392434) (xy 120.645474 -230.408482) (xy 120.594179 -230.416607)
			(xy 120.542245 -230.416607) (xy 120.49095 -230.408482) (xy 120.441557 -230.392434) (xy 120.395283 -230.368856)
			(xy 120.353267 -230.33833) (xy 120.316544 -230.301607) (xy 120.286018 -230.259591) (xy 120.26244 -230.213317)
			(xy 120.246392 -230.163924) (xy 120.238267 -230.112629) (xy 119.958357 -230.112629) (xy 119.950232 -230.163924)
			(xy 119.934184 -230.213317) (xy 119.910606 -230.259591) (xy 119.88008 -230.301607) (xy 119.843357 -230.33833)
			(xy 119.801341 -230.368856) (xy 119.755067 -230.392434) (xy 119.705674 -230.408482) (xy 119.654379 -230.416607)
			(xy 119.602445 -230.416607) (xy 119.55115 -230.408482) (xy 119.501757 -230.392434) (xy 119.455483 -230.368856)
			(xy 119.413467 -230.33833) (xy 119.376744 -230.301607) (xy 119.346218 -230.259591) (xy 119.32264 -230.213317)
			(xy 119.306592 -230.163924) (xy 119.298467 -230.112629) (xy 119.018557 -230.112629) (xy 119.010432 -230.163924)
			(xy 118.994384 -230.213317) (xy 118.970806 -230.259591) (xy 118.94028 -230.301607) (xy 118.903557 -230.33833)
			(xy 118.861541 -230.368856) (xy 118.815267 -230.392434) (xy 118.765874 -230.408482) (xy 118.714579 -230.416607)
			(xy 118.662645 -230.416607) (xy 118.61135 -230.408482) (xy 118.561957 -230.392434) (xy 118.515683 -230.368856)
			(xy 118.473667 -230.33833) (xy 118.436944 -230.301607) (xy 118.406418 -230.259591) (xy 118.38284 -230.213317)
			(xy 118.366792 -230.163924) (xy 118.358667 -230.112629) (xy 118.078757 -230.112629) (xy 118.070632 -230.163924)
			(xy 118.054584 -230.213317) (xy 118.031006 -230.259591) (xy 118.00048 -230.301607) (xy 117.963757 -230.33833)
			(xy 117.921741 -230.368856) (xy 117.875467 -230.392434) (xy 117.826074 -230.408482) (xy 117.774779 -230.416607)
			(xy 117.722845 -230.416607) (xy 117.67155 -230.408482) (xy 117.622157 -230.392434) (xy 117.575883 -230.368856)
			(xy 117.533867 -230.33833) (xy 117.497144 -230.301607) (xy 117.466618 -230.259591) (xy 117.44304 -230.213317)
			(xy 117.426992 -230.163924) (xy 117.418867 -230.112629) (xy 117.138957 -230.112629) (xy 117.130832 -230.163924)
			(xy 117.114784 -230.213317) (xy 117.091206 -230.259591) (xy 117.06068 -230.301607) (xy 117.023957 -230.33833)
			(xy 116.981941 -230.368856) (xy 116.935667 -230.392434) (xy 116.886274 -230.408482) (xy 116.834979 -230.416607)
			(xy 116.783045 -230.416607) (xy 116.73175 -230.408482) (xy 116.682357 -230.392434) (xy 116.636083 -230.368856)
			(xy 116.594067 -230.33833) (xy 116.557344 -230.301607) (xy 116.526818 -230.259591) (xy 116.50324 -230.213317)
			(xy 116.487192 -230.163924) (xy 116.479067 -230.112629) (xy 116.199157 -230.112629) (xy 116.191032 -230.163924)
			(xy 116.174984 -230.213317) (xy 116.151406 -230.259591) (xy 116.12088 -230.301607) (xy 116.084157 -230.33833)
			(xy 116.042141 -230.368856) (xy 115.995867 -230.392434) (xy 115.946474 -230.408482) (xy 115.895179 -230.416607)
			(xy 115.843245 -230.416607) (xy 115.79195 -230.408482) (xy 115.742557 -230.392434) (xy 115.696283 -230.368856)
			(xy 115.654267 -230.33833) (xy 115.617544 -230.301607) (xy 115.587018 -230.259591) (xy 115.56344 -230.213317)
			(xy 115.547392 -230.163924) (xy 115.539267 -230.112629) (xy 115.259611 -230.112629) (xy 115.251486 -230.163924)
			(xy 115.235438 -230.213317) (xy 115.21186 -230.259591) (xy 115.181334 -230.301607) (xy 115.144611 -230.33833)
			(xy 115.102595 -230.368856) (xy 115.056321 -230.392434) (xy 115.006928 -230.408482) (xy 114.955633 -230.416607)
			(xy 114.903699 -230.416607) (xy 114.852404 -230.408482) (xy 114.803011 -230.392434) (xy 114.756737 -230.368856)
			(xy 114.714721 -230.33833) (xy 114.677998 -230.301607) (xy 114.647472 -230.259591) (xy 114.623894 -230.213317)
			(xy 114.607846 -230.163924) (xy 114.599721 -230.112629) (xy 114.319811 -230.112629) (xy 114.311686 -230.163924)
			(xy 114.295638 -230.213317) (xy 114.27206 -230.259591) (xy 114.241534 -230.301607) (xy 114.204811 -230.33833)
			(xy 114.162795 -230.368856) (xy 114.116521 -230.392434) (xy 114.067128 -230.408482) (xy 114.015833 -230.416607)
			(xy 113.963899 -230.416607) (xy 113.912604 -230.408482) (xy 113.863211 -230.392434) (xy 113.816937 -230.368856)
			(xy 113.774921 -230.33833) (xy 113.738198 -230.301607) (xy 113.707672 -230.259591) (xy 113.684094 -230.213317)
			(xy 113.668046 -230.163924) (xy 113.659921 -230.112629) (xy 113.380011 -230.112629) (xy 113.371886 -230.163924)
			(xy 113.355838 -230.213317) (xy 113.33226 -230.259591) (xy 113.301734 -230.301607) (xy 113.265011 -230.33833)
			(xy 113.222995 -230.368856) (xy 113.176721 -230.392434) (xy 113.127328 -230.408482) (xy 113.076033 -230.416607)
			(xy 113.024099 -230.416607) (xy 112.972804 -230.408482) (xy 112.923411 -230.392434) (xy 112.877137 -230.368856)
			(xy 112.835121 -230.33833) (xy 112.798398 -230.301607) (xy 112.767872 -230.259591) (xy 112.744294 -230.213317)
			(xy 112.728246 -230.163924) (xy 112.720121 -230.112629) (xy 112.440211 -230.112629) (xy 112.432086 -230.163924)
			(xy 112.416038 -230.213317) (xy 112.39246 -230.259591) (xy 112.361934 -230.301607) (xy 112.325211 -230.33833)
			(xy 112.283195 -230.368856) (xy 112.236921 -230.392434) (xy 112.187528 -230.408482) (xy 112.136233 -230.416607)
			(xy 112.084299 -230.416607) (xy 112.033004 -230.408482) (xy 111.983611 -230.392434) (xy 111.937337 -230.368856)
			(xy 111.895321 -230.33833) (xy 111.858598 -230.301607) (xy 111.828072 -230.259591) (xy 111.804494 -230.213317)
			(xy 111.788446 -230.163924) (xy 111.780321 -230.112629) (xy 111.500411 -230.112629) (xy 111.492286 -230.163924)
			(xy 111.476238 -230.213317) (xy 111.45266 -230.259591) (xy 111.422134 -230.301607) (xy 111.385411 -230.33833)
			(xy 111.343395 -230.368856) (xy 111.297121 -230.392434) (xy 111.247728 -230.408482) (xy 111.196433 -230.416607)
			(xy 111.144499 -230.416607) (xy 111.093204 -230.408482) (xy 111.043811 -230.392434) (xy 110.997537 -230.368856)
			(xy 110.955521 -230.33833) (xy 110.918798 -230.301607) (xy 110.888272 -230.259591) (xy 110.864694 -230.213317)
			(xy 110.848646 -230.163924) (xy 110.840521 -230.112629) (xy 110.560357 -230.112629) (xy 110.552232 -230.163924)
			(xy 110.536184 -230.213317) (xy 110.512606 -230.259591) (xy 110.48208 -230.301607) (xy 110.445357 -230.33833)
			(xy 110.403341 -230.368856) (xy 110.357067 -230.392434) (xy 110.307674 -230.408482) (xy 110.256379 -230.416607)
			(xy 110.204445 -230.416607) (xy 110.15315 -230.408482) (xy 110.103757 -230.392434) (xy 110.057483 -230.368856)
			(xy 110.015467 -230.33833) (xy 109.978744 -230.301607) (xy 109.948218 -230.259591) (xy 109.92464 -230.213317)
			(xy 109.908592 -230.163924) (xy 109.900467 -230.112629) (xy 109.620557 -230.112629) (xy 109.612432 -230.163924)
			(xy 109.596384 -230.213317) (xy 109.572806 -230.259591) (xy 109.54228 -230.301607) (xy 109.505557 -230.33833)
			(xy 109.463541 -230.368856) (xy 109.417267 -230.392434) (xy 109.367874 -230.408482) (xy 109.316579 -230.416607)
			(xy 109.264645 -230.416607) (xy 109.21335 -230.408482) (xy 109.163957 -230.392434) (xy 109.117683 -230.368856)
			(xy 109.075667 -230.33833) (xy 109.038944 -230.301607) (xy 109.008418 -230.259591) (xy 108.98484 -230.213317)
			(xy 108.968792 -230.163924) (xy 108.960667 -230.112629) (xy 108.680757 -230.112629) (xy 108.672632 -230.163924)
			(xy 108.656584 -230.213317) (xy 108.633006 -230.259591) (xy 108.60248 -230.301607) (xy 108.565757 -230.33833)
			(xy 108.523741 -230.368856) (xy 108.477467 -230.392434) (xy 108.428074 -230.408482) (xy 108.376779 -230.416607)
			(xy 108.324845 -230.416607) (xy 108.27355 -230.408482) (xy 108.224157 -230.392434) (xy 108.177883 -230.368856)
			(xy 108.135867 -230.33833) (xy 108.099144 -230.301607) (xy 108.068618 -230.259591) (xy 108.04504 -230.213317)
			(xy 108.028992 -230.163924) (xy 108.020867 -230.112629) (xy 107.740957 -230.112629) (xy 107.732832 -230.163924)
			(xy 107.716784 -230.213317) (xy 107.693206 -230.259591) (xy 107.66268 -230.301607) (xy 107.625957 -230.33833)
			(xy 107.583941 -230.368856) (xy 107.537667 -230.392434) (xy 107.488274 -230.408482) (xy 107.436979 -230.416607)
			(xy 107.385045 -230.416607) (xy 107.33375 -230.408482) (xy 107.284357 -230.392434) (xy 107.238083 -230.368856)
			(xy 107.196067 -230.33833) (xy 107.159344 -230.301607) (xy 107.128818 -230.259591) (xy 107.10524 -230.213317)
			(xy 107.089192 -230.163924) (xy 107.081067 -230.112629) (xy 106.801411 -230.112629) (xy 106.793286 -230.163924)
			(xy 106.777238 -230.213317) (xy 106.75366 -230.259591) (xy 106.723134 -230.301607) (xy 106.686411 -230.33833)
			(xy 106.644395 -230.368856) (xy 106.598121 -230.392434) (xy 106.548728 -230.408482) (xy 106.497433 -230.416607)
			(xy 106.445499 -230.416607) (xy 106.394204 -230.408482) (xy 106.344811 -230.392434) (xy 106.298537 -230.368856)
			(xy 106.256521 -230.33833) (xy 106.219798 -230.301607) (xy 106.189272 -230.259591) (xy 106.165694 -230.213317)
			(xy 106.149646 -230.163924) (xy 106.141521 -230.112629) (xy 105.861307 -230.112629) (xy 105.861307 -230.112664)
			(xy 105.853184 -230.163952) (xy 105.837138 -230.213338) (xy 105.813564 -230.259605) (xy 105.783042 -230.301616)
			(xy 105.746325 -230.338335) (xy 105.704316 -230.368858) (xy 105.658049 -230.392433) (xy 105.608663 -230.408481)
			(xy 105.557376 -230.416606) (xy 105.531412 -230.417116) (xy 105.519728 -230.416862) (xy 105.5061 -230.416804)
			(xy 105.479596 -230.423112) (xy 105.4557 -230.436197) (xy 105.43611 -230.455131) (xy 105.422218 -230.478567)
			(xy 105.415011 -230.50484) (xy 105.414572 -230.518462) (xy 105.414572 -230.926445) (xy 105.671621 -230.926445)
			(xy 105.671621 -230.874511) (xy 105.679746 -230.823216) (xy 105.695794 -230.773823) (xy 105.719372 -230.727549)
			(xy 105.749898 -230.685533) (xy 105.786621 -230.64881) (xy 105.828637 -230.618284) (xy 105.874911 -230.594706)
			(xy 105.924304 -230.578658) (xy 105.975599 -230.570533) (xy 106.027533 -230.570533) (xy 106.078828 -230.578658)
			(xy 106.128221 -230.594706) (xy 106.174495 -230.618284) (xy 106.216511 -230.64881) (xy 106.253234 -230.685533)
			(xy 106.28376 -230.727549) (xy 106.307338 -230.773823) (xy 106.323386 -230.823216) (xy 106.331511 -230.874511)
			(xy 106.33202 -230.900478) (xy 106.331511 -230.926445) (xy 106.611421 -230.926445) (xy 106.611421 -230.874511)
			(xy 106.619546 -230.823216) (xy 106.635594 -230.773823) (xy 106.659172 -230.727549) (xy 106.689698 -230.685533)
			(xy 106.726421 -230.64881) (xy 106.768437 -230.618284) (xy 106.814711 -230.594706) (xy 106.864104 -230.578658)
			(xy 106.915399 -230.570533) (xy 106.967333 -230.570533) (xy 107.018628 -230.578658) (xy 107.068021 -230.594706)
			(xy 107.114295 -230.618284) (xy 107.156311 -230.64881) (xy 107.193034 -230.685533) (xy 107.22356 -230.727549)
			(xy 107.247138 -230.773823) (xy 107.263186 -230.823216) (xy 107.271311 -230.874511) (xy 107.27182 -230.900478)
			(xy 107.271311 -230.926445) (xy 107.550967 -230.926445) (xy 107.550967 -230.874511) (xy 107.559092 -230.823216)
			(xy 107.57514 -230.773823) (xy 107.598718 -230.727549) (xy 107.629244 -230.685533) (xy 107.665967 -230.64881)
			(xy 107.707983 -230.618284) (xy 107.754257 -230.594706) (xy 107.80365 -230.578658) (xy 107.854945 -230.570533)
			(xy 107.906879 -230.570533) (xy 107.958174 -230.578658) (xy 108.007567 -230.594706) (xy 108.053841 -230.618284)
			(xy 108.095857 -230.64881) (xy 108.13258 -230.685533) (xy 108.163106 -230.727549) (xy 108.186684 -230.773823)
			(xy 108.202732 -230.823216) (xy 108.210857 -230.874511) (xy 108.211366 -230.900478) (xy 108.210857 -230.926445)
			(xy 108.491021 -230.926445) (xy 108.491021 -230.874511) (xy 108.499146 -230.823216) (xy 108.515194 -230.773823)
			(xy 108.538772 -230.727549) (xy 108.569298 -230.685533) (xy 108.606021 -230.64881) (xy 108.648037 -230.618284)
			(xy 108.694311 -230.594706) (xy 108.743704 -230.578658) (xy 108.794999 -230.570533) (xy 108.846933 -230.570533)
			(xy 108.898228 -230.578658) (xy 108.947621 -230.594706) (xy 108.993895 -230.618284) (xy 109.035911 -230.64881)
			(xy 109.072634 -230.685533) (xy 109.10316 -230.727549) (xy 109.126738 -230.773823) (xy 109.142786 -230.823216)
			(xy 109.150911 -230.874511) (xy 109.15142 -230.900478) (xy 109.150911 -230.926445) (xy 109.430567 -230.926445)
			(xy 109.430567 -230.874511) (xy 109.438692 -230.823216) (xy 109.45474 -230.773823) (xy 109.478318 -230.727549)
			(xy 109.508844 -230.685533) (xy 109.545567 -230.64881) (xy 109.587583 -230.618284) (xy 109.633857 -230.594706)
			(xy 109.68325 -230.578658) (xy 109.734545 -230.570533) (xy 109.786479 -230.570533) (xy 109.837774 -230.578658)
			(xy 109.887167 -230.594706) (xy 109.933441 -230.618284) (xy 109.975457 -230.64881) (xy 110.01218 -230.685533)
			(xy 110.042706 -230.727549) (xy 110.066284 -230.773823) (xy 110.082332 -230.823216) (xy 110.090457 -230.874511)
			(xy 110.090966 -230.900478) (xy 110.090457 -230.926445) (xy 110.370621 -230.926445) (xy 110.370621 -230.874511)
			(xy 110.378746 -230.823216) (xy 110.394794 -230.773823) (xy 110.418372 -230.727549) (xy 110.448898 -230.685533)
			(xy 110.485621 -230.64881) (xy 110.527637 -230.618284) (xy 110.573911 -230.594706) (xy 110.623304 -230.578658)
			(xy 110.674599 -230.570533) (xy 110.726533 -230.570533) (xy 110.777828 -230.578658) (xy 110.827221 -230.594706)
			(xy 110.873495 -230.618284) (xy 110.915511 -230.64881) (xy 110.952234 -230.685533) (xy 110.98276 -230.727549)
			(xy 111.006338 -230.773823) (xy 111.022386 -230.823216) (xy 111.030511 -230.874511) (xy 111.03102 -230.900478)
			(xy 111.030511 -230.926445) (xy 111.310421 -230.926445) (xy 111.310421 -230.874511) (xy 111.318546 -230.823216)
			(xy 111.334594 -230.773823) (xy 111.358172 -230.727549) (xy 111.388698 -230.685533) (xy 111.425421 -230.64881)
			(xy 111.467437 -230.618284) (xy 111.513711 -230.594706) (xy 111.563104 -230.578658) (xy 111.614399 -230.570533)
			(xy 111.666333 -230.570533) (xy 111.717628 -230.578658) (xy 111.767021 -230.594706) (xy 111.813295 -230.618284)
			(xy 111.855311 -230.64881) (xy 111.892034 -230.685533) (xy 111.92256 -230.727549) (xy 111.946138 -230.773823)
			(xy 111.962186 -230.823216) (xy 111.970311 -230.874511) (xy 111.97082 -230.900478) (xy 111.970311 -230.926445)
			(xy 112.250221 -230.926445) (xy 112.250221 -230.874511) (xy 112.258346 -230.823216) (xy 112.274394 -230.773823)
			(xy 112.297972 -230.727549) (xy 112.328498 -230.685533) (xy 112.365221 -230.64881) (xy 112.407237 -230.618284)
			(xy 112.453511 -230.594706) (xy 112.502904 -230.578658) (xy 112.554199 -230.570533) (xy 112.606133 -230.570533)
			(xy 112.657428 -230.578658) (xy 112.706821 -230.594706) (xy 112.753095 -230.618284) (xy 112.795111 -230.64881)
			(xy 112.831834 -230.685533) (xy 112.86236 -230.727549) (xy 112.885938 -230.773823) (xy 112.901986 -230.823216)
			(xy 112.910111 -230.874511) (xy 112.91062 -230.900478) (xy 112.910111 -230.926445) (xy 113.190021 -230.926445)
			(xy 113.190021 -230.874511) (xy 113.198146 -230.823216) (xy 113.214194 -230.773823) (xy 113.237772 -230.727549)
			(xy 113.268298 -230.685533) (xy 113.305021 -230.64881) (xy 113.347037 -230.618284) (xy 113.393311 -230.594706)
			(xy 113.442704 -230.578658) (xy 113.493999 -230.570533) (xy 113.545933 -230.570533) (xy 113.597228 -230.578658)
			(xy 113.646621 -230.594706) (xy 113.692895 -230.618284) (xy 113.734911 -230.64881) (xy 113.771634 -230.685533)
			(xy 113.80216 -230.727549) (xy 113.825738 -230.773823) (xy 113.841786 -230.823216) (xy 113.849911 -230.874511)
			(xy 113.85042 -230.900478) (xy 113.849911 -230.926445) (xy 114.130075 -230.926445) (xy 114.130075 -230.874511)
			(xy 114.1382 -230.823216) (xy 114.154248 -230.773823) (xy 114.177826 -230.727549) (xy 114.208352 -230.685533)
			(xy 114.245075 -230.64881) (xy 114.287091 -230.618284) (xy 114.333365 -230.594706) (xy 114.382758 -230.578658)
			(xy 114.434053 -230.570533) (xy 114.485987 -230.570533) (xy 114.537282 -230.578658) (xy 114.586675 -230.594706)
			(xy 114.632949 -230.618284) (xy 114.674965 -230.64881) (xy 114.711688 -230.685533) (xy 114.742214 -230.727549)
			(xy 114.765792 -230.773823) (xy 114.78184 -230.823216) (xy 114.789965 -230.874511) (xy 114.790474 -230.900478)
			(xy 114.789965 -230.926445) (xy 115.069621 -230.926445) (xy 115.069621 -230.874511) (xy 115.077746 -230.823216)
			(xy 115.093794 -230.773823) (xy 115.117372 -230.727549) (xy 115.147898 -230.685533) (xy 115.184621 -230.64881)
			(xy 115.226637 -230.618284) (xy 115.272911 -230.594706) (xy 115.322304 -230.578658) (xy 115.373599 -230.570533)
			(xy 115.425533 -230.570533) (xy 115.476828 -230.578658) (xy 115.526221 -230.594706) (xy 115.572495 -230.618284)
			(xy 115.614511 -230.64881) (xy 115.651234 -230.685533) (xy 115.68176 -230.727549) (xy 115.705338 -230.773823)
			(xy 115.721386 -230.823216) (xy 115.729511 -230.874511) (xy 115.73002 -230.900478) (xy 115.729511 -230.926445)
			(xy 116.009421 -230.926445) (xy 116.009421 -230.874511) (xy 116.017546 -230.823216) (xy 116.033594 -230.773823)
			(xy 116.057172 -230.727549) (xy 116.087698 -230.685533) (xy 116.124421 -230.64881) (xy 116.166437 -230.618284)
			(xy 116.212711 -230.594706) (xy 116.262104 -230.578658) (xy 116.313399 -230.570533) (xy 116.365333 -230.570533)
			(xy 116.416628 -230.578658) (xy 116.466021 -230.594706) (xy 116.512295 -230.618284) (xy 116.554311 -230.64881)
			(xy 116.591034 -230.685533) (xy 116.62156 -230.727549) (xy 116.645138 -230.773823) (xy 116.661186 -230.823216)
			(xy 116.669311 -230.874511) (xy 116.66982 -230.900478) (xy 116.669311 -230.926445) (xy 116.949221 -230.926445)
			(xy 116.949221 -230.874511) (xy 116.957346 -230.823216) (xy 116.973394 -230.773823) (xy 116.996972 -230.727549)
			(xy 117.027498 -230.685533) (xy 117.064221 -230.64881) (xy 117.106237 -230.618284) (xy 117.152511 -230.594706)
			(xy 117.201904 -230.578658) (xy 117.253199 -230.570533) (xy 117.305133 -230.570533) (xy 117.356428 -230.578658)
			(xy 117.405821 -230.594706) (xy 117.452095 -230.618284) (xy 117.494111 -230.64881) (xy 117.530834 -230.685533)
			(xy 117.56136 -230.727549) (xy 117.584938 -230.773823) (xy 117.600986 -230.823216) (xy 117.609111 -230.874511)
			(xy 117.60962 -230.900478) (xy 117.609111 -230.926445) (xy 117.889021 -230.926445) (xy 117.889021 -230.874511)
			(xy 117.897146 -230.823216) (xy 117.913194 -230.773823) (xy 117.936772 -230.727549) (xy 117.967298 -230.685533)
			(xy 118.004021 -230.64881) (xy 118.046037 -230.618284) (xy 118.092311 -230.594706) (xy 118.141704 -230.578658)
			(xy 118.192999 -230.570533) (xy 118.244933 -230.570533) (xy 118.296228 -230.578658) (xy 118.345621 -230.594706)
			(xy 118.391895 -230.618284) (xy 118.433911 -230.64881) (xy 118.470634 -230.685533) (xy 118.50116 -230.727549)
			(xy 118.524738 -230.773823) (xy 118.540786 -230.823216) (xy 118.548911 -230.874511) (xy 118.54942 -230.900478)
			(xy 118.548911 -230.926445) (xy 118.828821 -230.926445) (xy 118.828821 -230.874511) (xy 118.836946 -230.823216)
			(xy 118.852994 -230.773823) (xy 118.876572 -230.727549) (xy 118.907098 -230.685533) (xy 118.943821 -230.64881)
			(xy 118.985837 -230.618284) (xy 119.032111 -230.594706) (xy 119.081504 -230.578658) (xy 119.132799 -230.570533)
			(xy 119.184733 -230.570533) (xy 119.236028 -230.578658) (xy 119.285421 -230.594706) (xy 119.331695 -230.618284)
			(xy 119.373711 -230.64881) (xy 119.410434 -230.685533) (xy 119.44096 -230.727549) (xy 119.464538 -230.773823)
			(xy 119.480586 -230.823216) (xy 119.488711 -230.874511) (xy 119.48922 -230.900478) (xy 119.488711 -230.926445)
			(xy 119.768621 -230.926445) (xy 119.768621 -230.874511) (xy 119.776746 -230.823216) (xy 119.792794 -230.773823)
			(xy 119.816372 -230.727549) (xy 119.846898 -230.685533) (xy 119.883621 -230.64881) (xy 119.925637 -230.618284)
			(xy 119.971911 -230.594706) (xy 120.021304 -230.578658) (xy 120.072599 -230.570533) (xy 120.124533 -230.570533)
			(xy 120.175828 -230.578658) (xy 120.225221 -230.594706) (xy 120.271495 -230.618284) (xy 120.313511 -230.64881)
			(xy 120.350234 -230.685533) (xy 120.38076 -230.727549) (xy 120.404338 -230.773823) (xy 120.420386 -230.823216)
			(xy 120.428511 -230.874511) (xy 120.42902 -230.900478) (xy 120.428511 -230.926445) (xy 120.708421 -230.926445)
			(xy 120.708421 -230.874511) (xy 120.716546 -230.823216) (xy 120.732594 -230.773823) (xy 120.756172 -230.727549)
			(xy 120.786698 -230.685533) (xy 120.823421 -230.64881) (xy 120.865437 -230.618284) (xy 120.911711 -230.594706)
			(xy 120.961104 -230.578658) (xy 121.012399 -230.570533) (xy 121.064333 -230.570533) (xy 121.115628 -230.578658)
			(xy 121.165021 -230.594706) (xy 121.211295 -230.618284) (xy 121.253311 -230.64881) (xy 121.290034 -230.685533)
			(xy 121.32056 -230.727549) (xy 121.344138 -230.773823) (xy 121.360186 -230.823216) (xy 121.368311 -230.874511)
			(xy 121.36882 -230.900478) (xy 121.368311 -230.926445) (xy 121.647967 -230.926445) (xy 121.647967 -230.874511)
			(xy 121.656092 -230.823216) (xy 121.67214 -230.773823) (xy 121.695718 -230.727549) (xy 121.726244 -230.685533)
			(xy 121.762967 -230.64881) (xy 121.804983 -230.618284) (xy 121.851257 -230.594706) (xy 121.90065 -230.578658)
			(xy 121.951945 -230.570533) (xy 122.003879 -230.570533) (xy 122.055174 -230.578658) (xy 122.104567 -230.594706)
			(xy 122.150841 -230.618284) (xy 122.192857 -230.64881) (xy 122.22958 -230.685533) (xy 122.260106 -230.727549)
			(xy 122.283684 -230.773823) (xy 122.299732 -230.823216) (xy 122.307857 -230.874511) (xy 122.308366 -230.900478)
			(xy 122.307857 -230.926445) (xy 122.588021 -230.926445) (xy 122.588021 -230.874511) (xy 122.596146 -230.823216)
			(xy 122.612194 -230.773823) (xy 122.635772 -230.727549) (xy 122.666298 -230.685533) (xy 122.703021 -230.64881)
			(xy 122.745037 -230.618284) (xy 122.791311 -230.594706) (xy 122.840704 -230.578658) (xy 122.891999 -230.570533)
			(xy 122.943933 -230.570533) (xy 122.995228 -230.578658) (xy 123.044621 -230.594706) (xy 123.090895 -230.618284)
			(xy 123.132911 -230.64881) (xy 123.169634 -230.685533) (xy 123.20016 -230.727549) (xy 123.223738 -230.773823)
			(xy 123.239786 -230.823216) (xy 123.247911 -230.874511) (xy 123.24842 -230.900478) (xy 123.247911 -230.926445)
			(xy 123.527821 -230.926445) (xy 123.527821 -230.874511) (xy 123.535946 -230.823216) (xy 123.551994 -230.773823)
			(xy 123.575572 -230.727549) (xy 123.606098 -230.685533) (xy 123.642821 -230.64881) (xy 123.684837 -230.618284)
			(xy 123.731111 -230.594706) (xy 123.780504 -230.578658) (xy 123.831799 -230.570533) (xy 123.883733 -230.570533)
			(xy 123.935028 -230.578658) (xy 123.984421 -230.594706) (xy 124.030695 -230.618284) (xy 124.072711 -230.64881)
			(xy 124.109434 -230.685533) (xy 124.13996 -230.727549) (xy 124.163538 -230.773823) (xy 124.179586 -230.823216)
			(xy 124.187711 -230.874511) (xy 124.18822 -230.900478) (xy 124.187711 -230.926445) (xy 124.467621 -230.926445)
			(xy 124.467621 -230.874511) (xy 124.475746 -230.823216) (xy 124.491794 -230.773823) (xy 124.515372 -230.727549)
			(xy 124.545898 -230.685533) (xy 124.582621 -230.64881) (xy 124.624637 -230.618284) (xy 124.670911 -230.594706)
			(xy 124.720304 -230.578658) (xy 124.771599 -230.570533) (xy 124.823533 -230.570533) (xy 124.874828 -230.578658)
			(xy 124.924221 -230.594706) (xy 124.970495 -230.618284) (xy 125.012511 -230.64881) (xy 125.049234 -230.685533)
			(xy 125.07976 -230.727549) (xy 125.103338 -230.773823) (xy 125.119386 -230.823216) (xy 125.127511 -230.874511)
			(xy 125.12802 -230.900478) (xy 125.127511 -230.926445) (xy 125.407421 -230.926445) (xy 125.407421 -230.874511)
			(xy 125.415546 -230.823216) (xy 125.431594 -230.773823) (xy 125.455172 -230.727549) (xy 125.485698 -230.685533)
			(xy 125.522421 -230.64881) (xy 125.564437 -230.618284) (xy 125.610711 -230.594706) (xy 125.660104 -230.578658)
			(xy 125.711399 -230.570533) (xy 125.763333 -230.570533) (xy 125.814628 -230.578658) (xy 125.864021 -230.594706)
			(xy 125.910295 -230.618284) (xy 125.952311 -230.64881) (xy 125.989034 -230.685533) (xy 126.01956 -230.727549)
			(xy 126.043138 -230.773823) (xy 126.059186 -230.823216) (xy 126.067311 -230.874511) (xy 126.06782 -230.900478)
			(xy 126.067311 -230.926445) (xy 126.347221 -230.926445) (xy 126.347221 -230.874511) (xy 126.355346 -230.823216)
			(xy 126.371394 -230.773823) (xy 126.394972 -230.727549) (xy 126.425498 -230.685533) (xy 126.462221 -230.64881)
			(xy 126.504237 -230.618284) (xy 126.550511 -230.594706) (xy 126.599904 -230.578658) (xy 126.651199 -230.570533)
			(xy 126.703133 -230.570533) (xy 126.754428 -230.578658) (xy 126.803821 -230.594706) (xy 126.850095 -230.618284)
			(xy 126.892111 -230.64881) (xy 126.928834 -230.685533) (xy 126.95936 -230.727549) (xy 126.982938 -230.773823)
			(xy 126.998986 -230.823216) (xy 127.007111 -230.874511) (xy 127.00762 -230.900478) (xy 127.007111 -230.926445)
			(xy 127.287021 -230.926445) (xy 127.287021 -230.874511) (xy 127.295146 -230.823216) (xy 127.311194 -230.773823)
			(xy 127.334772 -230.727549) (xy 127.365298 -230.685533) (xy 127.402021 -230.64881) (xy 127.444037 -230.618284)
			(xy 127.490311 -230.594706) (xy 127.539704 -230.578658) (xy 127.590999 -230.570533) (xy 127.642933 -230.570533)
			(xy 127.694228 -230.578658) (xy 127.743621 -230.594706) (xy 127.789895 -230.618284) (xy 127.831911 -230.64881)
			(xy 127.868634 -230.685533) (xy 127.89916 -230.727549) (xy 127.922738 -230.773823) (xy 127.938786 -230.823216)
			(xy 127.946911 -230.874511) (xy 127.94742 -230.900478) (xy 127.946911 -230.926445) (xy 128.226821 -230.926445)
			(xy 128.226821 -230.874511) (xy 128.234946 -230.823216) (xy 128.250994 -230.773823) (xy 128.274572 -230.727549)
			(xy 128.305098 -230.685533) (xy 128.341821 -230.64881) (xy 128.383837 -230.618284) (xy 128.430111 -230.594706)
			(xy 128.479504 -230.578658) (xy 128.530799 -230.570533) (xy 128.582733 -230.570533) (xy 128.634028 -230.578658)
			(xy 128.683421 -230.594706) (xy 128.729695 -230.618284) (xy 128.771711 -230.64881) (xy 128.808434 -230.685533)
			(xy 128.83896 -230.727549) (xy 128.862538 -230.773823) (xy 128.878586 -230.823216) (xy 128.886711 -230.874511)
			(xy 128.88722 -230.900478) (xy 128.886711 -230.926445) (xy 129.166621 -230.926445) (xy 129.166621 -230.874511)
			(xy 129.174746 -230.823216) (xy 129.190794 -230.773823) (xy 129.214372 -230.727549) (xy 129.244898 -230.685533)
			(xy 129.281621 -230.64881) (xy 129.323637 -230.618284) (xy 129.369911 -230.594706) (xy 129.419304 -230.578658)
			(xy 129.470599 -230.570533) (xy 129.522533 -230.570533) (xy 129.573828 -230.578658) (xy 129.623221 -230.594706)
			(xy 129.669495 -230.618284) (xy 129.711511 -230.64881) (xy 129.748234 -230.685533) (xy 129.77876 -230.727549)
			(xy 129.802338 -230.773823) (xy 129.818386 -230.823216) (xy 129.826511 -230.874511) (xy 129.82702 -230.900478)
			(xy 129.826511 -230.926445) (xy 130.106421 -230.926445) (xy 130.106421 -230.874511) (xy 130.114546 -230.823216)
			(xy 130.130594 -230.773823) (xy 130.154172 -230.727549) (xy 130.184698 -230.685533) (xy 130.221421 -230.64881)
			(xy 130.263437 -230.618284) (xy 130.309711 -230.594706) (xy 130.359104 -230.578658) (xy 130.410399 -230.570533)
			(xy 130.462333 -230.570533) (xy 130.513628 -230.578658) (xy 130.563021 -230.594706) (xy 130.609295 -230.618284)
			(xy 130.651311 -230.64881) (xy 130.688034 -230.685533) (xy 130.71856 -230.727549) (xy 130.742138 -230.773823)
			(xy 130.758186 -230.823216) (xy 130.766311 -230.874511) (xy 130.76682 -230.900478) (xy 130.766311 -230.926445)
			(xy 131.046221 -230.926445) (xy 131.046221 -230.874511) (xy 131.054346 -230.823216) (xy 131.070394 -230.773823)
			(xy 131.093972 -230.727549) (xy 131.124498 -230.685533) (xy 131.161221 -230.64881) (xy 131.203237 -230.618284)
			(xy 131.249511 -230.594706) (xy 131.298904 -230.578658) (xy 131.350199 -230.570533) (xy 131.402133 -230.570533)
			(xy 131.453428 -230.578658) (xy 131.502821 -230.594706) (xy 131.549095 -230.618284) (xy 131.591111 -230.64881)
			(xy 131.627834 -230.685533) (xy 131.65836 -230.727549) (xy 131.681938 -230.773823) (xy 131.697986 -230.823216)
			(xy 131.706111 -230.874511) (xy 131.70662 -230.900478) (xy 131.706111 -230.926445) (xy 131.697986 -230.97774)
			(xy 131.681938 -231.027133) (xy 131.65836 -231.073407) (xy 131.627834 -231.115423) (xy 131.591111 -231.152146)
			(xy 131.549095 -231.182672) (xy 131.502821 -231.20625) (xy 131.453428 -231.222298) (xy 131.402133 -231.230423)
			(xy 131.350199 -231.230423) (xy 131.298904 -231.222298) (xy 131.249511 -231.20625) (xy 131.203237 -231.182672)
			(xy 131.161221 -231.152146) (xy 131.124498 -231.115423) (xy 131.093972 -231.073407) (xy 131.070394 -231.027133)
			(xy 131.054346 -230.97774) (xy 131.046221 -230.926445) (xy 130.766311 -230.926445) (xy 130.758186 -230.97774)
			(xy 130.742138 -231.027133) (xy 130.71856 -231.073407) (xy 130.688034 -231.115423) (xy 130.651311 -231.152146)
			(xy 130.609295 -231.182672) (xy 130.563021 -231.20625) (xy 130.513628 -231.222298) (xy 130.462333 -231.230423)
			(xy 130.410399 -231.230423) (xy 130.359104 -231.222298) (xy 130.309711 -231.20625) (xy 130.263437 -231.182672)
			(xy 130.221421 -231.152146) (xy 130.184698 -231.115423) (xy 130.154172 -231.073407) (xy 130.130594 -231.027133)
			(xy 130.114546 -230.97774) (xy 130.106421 -230.926445) (xy 129.826511 -230.926445) (xy 129.818386 -230.97774)
			(xy 129.802338 -231.027133) (xy 129.77876 -231.073407) (xy 129.748234 -231.115423) (xy 129.711511 -231.152146)
			(xy 129.669495 -231.182672) (xy 129.623221 -231.20625) (xy 129.573828 -231.222298) (xy 129.522533 -231.230423)
			(xy 129.470599 -231.230423) (xy 129.419304 -231.222298) (xy 129.369911 -231.20625) (xy 129.323637 -231.182672)
			(xy 129.281621 -231.152146) (xy 129.244898 -231.115423) (xy 129.214372 -231.073407) (xy 129.190794 -231.027133)
			(xy 129.174746 -230.97774) (xy 129.166621 -230.926445) (xy 128.886711 -230.926445) (xy 128.878586 -230.97774)
			(xy 128.862538 -231.027133) (xy 128.83896 -231.073407) (xy 128.808434 -231.115423) (xy 128.771711 -231.152146)
			(xy 128.729695 -231.182672) (xy 128.683421 -231.20625) (xy 128.634028 -231.222298) (xy 128.582733 -231.230423)
			(xy 128.530799 -231.230423) (xy 128.479504 -231.222298) (xy 128.430111 -231.20625) (xy 128.383837 -231.182672)
			(xy 128.341821 -231.152146) (xy 128.305098 -231.115423) (xy 128.274572 -231.073407) (xy 128.250994 -231.027133)
			(xy 128.234946 -230.97774) (xy 128.226821 -230.926445) (xy 127.946911 -230.926445) (xy 127.938786 -230.97774)
			(xy 127.922738 -231.027133) (xy 127.89916 -231.073407) (xy 127.868634 -231.115423) (xy 127.831911 -231.152146)
			(xy 127.789895 -231.182672) (xy 127.743621 -231.20625) (xy 127.694228 -231.222298) (xy 127.642933 -231.230423)
			(xy 127.590999 -231.230423) (xy 127.539704 -231.222298) (xy 127.490311 -231.20625) (xy 127.444037 -231.182672)
			(xy 127.402021 -231.152146) (xy 127.365298 -231.115423) (xy 127.334772 -231.073407) (xy 127.311194 -231.027133)
			(xy 127.295146 -230.97774) (xy 127.287021 -230.926445) (xy 127.007111 -230.926445) (xy 126.998986 -230.97774)
			(xy 126.982938 -231.027133) (xy 126.95936 -231.073407) (xy 126.928834 -231.115423) (xy 126.892111 -231.152146)
			(xy 126.850095 -231.182672) (xy 126.803821 -231.20625) (xy 126.754428 -231.222298) (xy 126.703133 -231.230423)
			(xy 126.651199 -231.230423) (xy 126.599904 -231.222298) (xy 126.550511 -231.20625) (xy 126.504237 -231.182672)
			(xy 126.462221 -231.152146) (xy 126.425498 -231.115423) (xy 126.394972 -231.073407) (xy 126.371394 -231.027133)
			(xy 126.355346 -230.97774) (xy 126.347221 -230.926445) (xy 126.067311 -230.926445) (xy 126.059186 -230.97774)
			(xy 126.043138 -231.027133) (xy 126.01956 -231.073407) (xy 125.989034 -231.115423) (xy 125.952311 -231.152146)
			(xy 125.910295 -231.182672) (xy 125.864021 -231.20625) (xy 125.814628 -231.222298) (xy 125.763333 -231.230423)
			(xy 125.711399 -231.230423) (xy 125.660104 -231.222298) (xy 125.610711 -231.20625) (xy 125.564437 -231.182672)
			(xy 125.522421 -231.152146) (xy 125.485698 -231.115423) (xy 125.455172 -231.073407) (xy 125.431594 -231.027133)
			(xy 125.415546 -230.97774) (xy 125.407421 -230.926445) (xy 125.127511 -230.926445) (xy 125.119386 -230.97774)
			(xy 125.103338 -231.027133) (xy 125.07976 -231.073407) (xy 125.049234 -231.115423) (xy 125.012511 -231.152146)
			(xy 124.970495 -231.182672) (xy 124.924221 -231.20625) (xy 124.874828 -231.222298) (xy 124.823533 -231.230423)
			(xy 124.771599 -231.230423) (xy 124.720304 -231.222298) (xy 124.670911 -231.20625) (xy 124.624637 -231.182672)
			(xy 124.582621 -231.152146) (xy 124.545898 -231.115423) (xy 124.515372 -231.073407) (xy 124.491794 -231.027133)
			(xy 124.475746 -230.97774) (xy 124.467621 -230.926445) (xy 124.187711 -230.926445) (xy 124.179586 -230.97774)
			(xy 124.163538 -231.027133) (xy 124.13996 -231.073407) (xy 124.109434 -231.115423) (xy 124.072711 -231.152146)
			(xy 124.030695 -231.182672) (xy 123.984421 -231.20625) (xy 123.935028 -231.222298) (xy 123.883733 -231.230423)
			(xy 123.831799 -231.230423) (xy 123.780504 -231.222298) (xy 123.731111 -231.20625) (xy 123.684837 -231.182672)
			(xy 123.642821 -231.152146) (xy 123.606098 -231.115423) (xy 123.575572 -231.073407) (xy 123.551994 -231.027133)
			(xy 123.535946 -230.97774) (xy 123.527821 -230.926445) (xy 123.247911 -230.926445) (xy 123.239786 -230.97774)
			(xy 123.223738 -231.027133) (xy 123.20016 -231.073407) (xy 123.169634 -231.115423) (xy 123.132911 -231.152146)
			(xy 123.090895 -231.182672) (xy 123.044621 -231.20625) (xy 122.995228 -231.222298) (xy 122.943933 -231.230423)
			(xy 122.891999 -231.230423) (xy 122.840704 -231.222298) (xy 122.791311 -231.20625) (xy 122.745037 -231.182672)
			(xy 122.703021 -231.152146) (xy 122.666298 -231.115423) (xy 122.635772 -231.073407) (xy 122.612194 -231.027133)
			(xy 122.596146 -230.97774) (xy 122.588021 -230.926445) (xy 122.307857 -230.926445) (xy 122.299732 -230.97774)
			(xy 122.283684 -231.027133) (xy 122.260106 -231.073407) (xy 122.22958 -231.115423) (xy 122.192857 -231.152146)
			(xy 122.150841 -231.182672) (xy 122.104567 -231.20625) (xy 122.055174 -231.222298) (xy 122.003879 -231.230423)
			(xy 121.951945 -231.230423) (xy 121.90065 -231.222298) (xy 121.851257 -231.20625) (xy 121.804983 -231.182672)
			(xy 121.762967 -231.152146) (xy 121.726244 -231.115423) (xy 121.695718 -231.073407) (xy 121.67214 -231.027133)
			(xy 121.656092 -230.97774) (xy 121.647967 -230.926445) (xy 121.368311 -230.926445) (xy 121.360186 -230.97774)
			(xy 121.344138 -231.027133) (xy 121.32056 -231.073407) (xy 121.290034 -231.115423) (xy 121.253311 -231.152146)
			(xy 121.211295 -231.182672) (xy 121.165021 -231.20625) (xy 121.115628 -231.222298) (xy 121.064333 -231.230423)
			(xy 121.012399 -231.230423) (xy 120.961104 -231.222298) (xy 120.911711 -231.20625) (xy 120.865437 -231.182672)
			(xy 120.823421 -231.152146) (xy 120.786698 -231.115423) (xy 120.756172 -231.073407) (xy 120.732594 -231.027133)
			(xy 120.716546 -230.97774) (xy 120.708421 -230.926445) (xy 120.428511 -230.926445) (xy 120.420386 -230.97774)
			(xy 120.404338 -231.027133) (xy 120.38076 -231.073407) (xy 120.350234 -231.115423) (xy 120.313511 -231.152146)
			(xy 120.271495 -231.182672) (xy 120.225221 -231.20625) (xy 120.175828 -231.222298) (xy 120.124533 -231.230423)
			(xy 120.072599 -231.230423) (xy 120.021304 -231.222298) (xy 119.971911 -231.20625) (xy 119.925637 -231.182672)
			(xy 119.883621 -231.152146) (xy 119.846898 -231.115423) (xy 119.816372 -231.073407) (xy 119.792794 -231.027133)
			(xy 119.776746 -230.97774) (xy 119.768621 -230.926445) (xy 119.488711 -230.926445) (xy 119.480586 -230.97774)
			(xy 119.464538 -231.027133) (xy 119.44096 -231.073407) (xy 119.410434 -231.115423) (xy 119.373711 -231.152146)
			(xy 119.331695 -231.182672) (xy 119.285421 -231.20625) (xy 119.236028 -231.222298) (xy 119.184733 -231.230423)
			(xy 119.132799 -231.230423) (xy 119.081504 -231.222298) (xy 119.032111 -231.20625) (xy 118.985837 -231.182672)
			(xy 118.943821 -231.152146) (xy 118.907098 -231.115423) (xy 118.876572 -231.073407) (xy 118.852994 -231.027133)
			(xy 118.836946 -230.97774) (xy 118.828821 -230.926445) (xy 118.548911 -230.926445) (xy 118.540786 -230.97774)
			(xy 118.524738 -231.027133) (xy 118.50116 -231.073407) (xy 118.470634 -231.115423) (xy 118.433911 -231.152146)
			(xy 118.391895 -231.182672) (xy 118.345621 -231.20625) (xy 118.296228 -231.222298) (xy 118.244933 -231.230423)
			(xy 118.192999 -231.230423) (xy 118.141704 -231.222298) (xy 118.092311 -231.20625) (xy 118.046037 -231.182672)
			(xy 118.004021 -231.152146) (xy 117.967298 -231.115423) (xy 117.936772 -231.073407) (xy 117.913194 -231.027133)
			(xy 117.897146 -230.97774) (xy 117.889021 -230.926445) (xy 117.609111 -230.926445) (xy 117.600986 -230.97774)
			(xy 117.584938 -231.027133) (xy 117.56136 -231.073407) (xy 117.530834 -231.115423) (xy 117.494111 -231.152146)
			(xy 117.452095 -231.182672) (xy 117.405821 -231.20625) (xy 117.356428 -231.222298) (xy 117.305133 -231.230423)
			(xy 117.253199 -231.230423) (xy 117.201904 -231.222298) (xy 117.152511 -231.20625) (xy 117.106237 -231.182672)
			(xy 117.064221 -231.152146) (xy 117.027498 -231.115423) (xy 116.996972 -231.073407) (xy 116.973394 -231.027133)
			(xy 116.957346 -230.97774) (xy 116.949221 -230.926445) (xy 116.669311 -230.926445) (xy 116.661186 -230.97774)
			(xy 116.645138 -231.027133) (xy 116.62156 -231.073407) (xy 116.591034 -231.115423) (xy 116.554311 -231.152146)
			(xy 116.512295 -231.182672) (xy 116.466021 -231.20625) (xy 116.416628 -231.222298) (xy 116.365333 -231.230423)
			(xy 116.313399 -231.230423) (xy 116.262104 -231.222298) (xy 116.212711 -231.20625) (xy 116.166437 -231.182672)
			(xy 116.124421 -231.152146) (xy 116.087698 -231.115423) (xy 116.057172 -231.073407) (xy 116.033594 -231.027133)
			(xy 116.017546 -230.97774) (xy 116.009421 -230.926445) (xy 115.729511 -230.926445) (xy 115.721386 -230.97774)
			(xy 115.705338 -231.027133) (xy 115.68176 -231.073407) (xy 115.651234 -231.115423) (xy 115.614511 -231.152146)
			(xy 115.572495 -231.182672) (xy 115.526221 -231.20625) (xy 115.476828 -231.222298) (xy 115.425533 -231.230423)
			(xy 115.373599 -231.230423) (xy 115.322304 -231.222298) (xy 115.272911 -231.20625) (xy 115.226637 -231.182672)
			(xy 115.184621 -231.152146) (xy 115.147898 -231.115423) (xy 115.117372 -231.073407) (xy 115.093794 -231.027133)
			(xy 115.077746 -230.97774) (xy 115.069621 -230.926445) (xy 114.789965 -230.926445) (xy 114.78184 -230.97774)
			(xy 114.765792 -231.027133) (xy 114.742214 -231.073407) (xy 114.711688 -231.115423) (xy 114.674965 -231.152146)
			(xy 114.632949 -231.182672) (xy 114.586675 -231.20625) (xy 114.537282 -231.222298) (xy 114.485987 -231.230423)
			(xy 114.434053 -231.230423) (xy 114.382758 -231.222298) (xy 114.333365 -231.20625) (xy 114.287091 -231.182672)
			(xy 114.245075 -231.152146) (xy 114.208352 -231.115423) (xy 114.177826 -231.073407) (xy 114.154248 -231.027133)
			(xy 114.1382 -230.97774) (xy 114.130075 -230.926445) (xy 113.849911 -230.926445) (xy 113.841786 -230.97774)
			(xy 113.825738 -231.027133) (xy 113.80216 -231.073407) (xy 113.771634 -231.115423) (xy 113.734911 -231.152146)
			(xy 113.692895 -231.182672) (xy 113.646621 -231.20625) (xy 113.597228 -231.222298) (xy 113.545933 -231.230423)
			(xy 113.493999 -231.230423) (xy 113.442704 -231.222298) (xy 113.393311 -231.20625) (xy 113.347037 -231.182672)
			(xy 113.305021 -231.152146) (xy 113.268298 -231.115423) (xy 113.237772 -231.073407) (xy 113.214194 -231.027133)
			(xy 113.198146 -230.97774) (xy 113.190021 -230.926445) (xy 112.910111 -230.926445) (xy 112.901986 -230.97774)
			(xy 112.885938 -231.027133) (xy 112.86236 -231.073407) (xy 112.831834 -231.115423) (xy 112.795111 -231.152146)
			(xy 112.753095 -231.182672) (xy 112.706821 -231.20625) (xy 112.657428 -231.222298) (xy 112.606133 -231.230423)
			(xy 112.554199 -231.230423) (xy 112.502904 -231.222298) (xy 112.453511 -231.20625) (xy 112.407237 -231.182672)
			(xy 112.365221 -231.152146) (xy 112.328498 -231.115423) (xy 112.297972 -231.073407) (xy 112.274394 -231.027133)
			(xy 112.258346 -230.97774) (xy 112.250221 -230.926445) (xy 111.970311 -230.926445) (xy 111.962186 -230.97774)
			(xy 111.946138 -231.027133) (xy 111.92256 -231.073407) (xy 111.892034 -231.115423) (xy 111.855311 -231.152146)
			(xy 111.813295 -231.182672) (xy 111.767021 -231.20625) (xy 111.717628 -231.222298) (xy 111.666333 -231.230423)
			(xy 111.614399 -231.230423) (xy 111.563104 -231.222298) (xy 111.513711 -231.20625) (xy 111.467437 -231.182672)
			(xy 111.425421 -231.152146) (xy 111.388698 -231.115423) (xy 111.358172 -231.073407) (xy 111.334594 -231.027133)
			(xy 111.318546 -230.97774) (xy 111.310421 -230.926445) (xy 111.030511 -230.926445) (xy 111.022386 -230.97774)
			(xy 111.006338 -231.027133) (xy 110.98276 -231.073407) (xy 110.952234 -231.115423) (xy 110.915511 -231.152146)
			(xy 110.873495 -231.182672) (xy 110.827221 -231.20625) (xy 110.777828 -231.222298) (xy 110.726533 -231.230423)
			(xy 110.674599 -231.230423) (xy 110.623304 -231.222298) (xy 110.573911 -231.20625) (xy 110.527637 -231.182672)
			(xy 110.485621 -231.152146) (xy 110.448898 -231.115423) (xy 110.418372 -231.073407) (xy 110.394794 -231.027133)
			(xy 110.378746 -230.97774) (xy 110.370621 -230.926445) (xy 110.090457 -230.926445) (xy 110.082332 -230.97774)
			(xy 110.066284 -231.027133) (xy 110.042706 -231.073407) (xy 110.01218 -231.115423) (xy 109.975457 -231.152146)
			(xy 109.933441 -231.182672) (xy 109.887167 -231.20625) (xy 109.837774 -231.222298) (xy 109.786479 -231.230423)
			(xy 109.734545 -231.230423) (xy 109.68325 -231.222298) (xy 109.633857 -231.20625) (xy 109.587583 -231.182672)
			(xy 109.545567 -231.152146) (xy 109.508844 -231.115423) (xy 109.478318 -231.073407) (xy 109.45474 -231.027133)
			(xy 109.438692 -230.97774) (xy 109.430567 -230.926445) (xy 109.150911 -230.926445) (xy 109.142786 -230.97774)
			(xy 109.126738 -231.027133) (xy 109.10316 -231.073407) (xy 109.072634 -231.115423) (xy 109.035911 -231.152146)
			(xy 108.993895 -231.182672) (xy 108.947621 -231.20625) (xy 108.898228 -231.222298) (xy 108.846933 -231.230423)
			(xy 108.794999 -231.230423) (xy 108.743704 -231.222298) (xy 108.694311 -231.20625) (xy 108.648037 -231.182672)
			(xy 108.606021 -231.152146) (xy 108.569298 -231.115423) (xy 108.538772 -231.073407) (xy 108.515194 -231.027133)
			(xy 108.499146 -230.97774) (xy 108.491021 -230.926445) (xy 108.210857 -230.926445) (xy 108.202732 -230.97774)
			(xy 108.186684 -231.027133) (xy 108.163106 -231.073407) (xy 108.13258 -231.115423) (xy 108.095857 -231.152146)
			(xy 108.053841 -231.182672) (xy 108.007567 -231.20625) (xy 107.958174 -231.222298) (xy 107.906879 -231.230423)
			(xy 107.854945 -231.230423) (xy 107.80365 -231.222298) (xy 107.754257 -231.20625) (xy 107.707983 -231.182672)
			(xy 107.665967 -231.152146) (xy 107.629244 -231.115423) (xy 107.598718 -231.073407) (xy 107.57514 -231.027133)
			(xy 107.559092 -230.97774) (xy 107.550967 -230.926445) (xy 107.271311 -230.926445) (xy 107.263186 -230.97774)
			(xy 107.247138 -231.027133) (xy 107.22356 -231.073407) (xy 107.193034 -231.115423) (xy 107.156311 -231.152146)
			(xy 107.114295 -231.182672) (xy 107.068021 -231.20625) (xy 107.018628 -231.222298) (xy 106.967333 -231.230423)
			(xy 106.915399 -231.230423) (xy 106.864104 -231.222298) (xy 106.814711 -231.20625) (xy 106.768437 -231.182672)
			(xy 106.726421 -231.152146) (xy 106.689698 -231.115423) (xy 106.659172 -231.073407) (xy 106.635594 -231.027133)
			(xy 106.619546 -230.97774) (xy 106.611421 -230.926445) (xy 106.331511 -230.926445) (xy 106.323386 -230.97774)
			(xy 106.307338 -231.027133) (xy 106.28376 -231.073407) (xy 106.253234 -231.115423) (xy 106.216511 -231.152146)
			(xy 106.174495 -231.182672) (xy 106.128221 -231.20625) (xy 106.078828 -231.222298) (xy 106.027533 -231.230423)
			(xy 105.975599 -231.230423) (xy 105.924304 -231.222298) (xy 105.874911 -231.20625) (xy 105.828637 -231.182672)
			(xy 105.786621 -231.152146) (xy 105.749898 -231.115423) (xy 105.719372 -231.073407) (xy 105.695794 -231.027133)
			(xy 105.679746 -230.97774) (xy 105.671621 -230.926445) (xy 105.414572 -230.926445) (xy 105.414572 -231.282748)
			(xy 105.415004 -231.296375) (xy 105.422182 -231.322665) (xy 105.436064 -231.346116) (xy 105.455662 -231.365053)
			(xy 105.479574 -231.378125) (xy 105.506095 -231.384398) (xy 105.519728 -231.384348) (xy 105.531412 -231.384094)
			(xy 105.557382 -231.384508) (xy 105.608683 -231.392635) (xy 105.658082 -231.408687) (xy 105.70436 -231.432269)
			(xy 105.746381 -231.4628) (xy 105.783108 -231.499528) (xy 105.813637 -231.54155) (xy 105.837217 -231.58783)
			(xy 105.853268 -231.637228) (xy 105.861393 -231.68853) (xy 105.861393 -231.74047) (xy 105.861386 -231.740515)
			(xy 106.141267 -231.740515) (xy 106.141267 -231.688581) (xy 106.149392 -231.637286) (xy 106.16544 -231.587893)
			(xy 106.189018 -231.541619) (xy 106.219544 -231.499603) (xy 106.256267 -231.46288) (xy 106.298283 -231.432354)
			(xy 106.344557 -231.408776) (xy 106.39395 -231.392728) (xy 106.445245 -231.384603) (xy 106.497179 -231.384603)
			(xy 106.548474 -231.392728) (xy 106.597867 -231.408776) (xy 106.644141 -231.432354) (xy 106.686157 -231.46288)
			(xy 106.72288 -231.499603) (xy 106.753406 -231.541619) (xy 106.776984 -231.587893) (xy 106.793032 -231.637286)
			(xy 106.801157 -231.688581) (xy 106.801666 -231.714548) (xy 106.801157 -231.740515) (xy 107.081067 -231.740515)
			(xy 107.081067 -231.688581) (xy 107.089192 -231.637286) (xy 107.10524 -231.587893) (xy 107.128818 -231.541619)
			(xy 107.159344 -231.499603) (xy 107.196067 -231.46288) (xy 107.238083 -231.432354) (xy 107.284357 -231.408776)
			(xy 107.33375 -231.392728) (xy 107.385045 -231.384603) (xy 107.436979 -231.384603) (xy 107.488274 -231.392728)
			(xy 107.537667 -231.408776) (xy 107.583941 -231.432354) (xy 107.625957 -231.46288) (xy 107.66268 -231.499603)
			(xy 107.693206 -231.541619) (xy 107.716784 -231.587893) (xy 107.732832 -231.637286) (xy 107.740957 -231.688581)
			(xy 107.741466 -231.714548) (xy 107.740957 -231.740515) (xy 108.020867 -231.740515) (xy 108.020867 -231.688581)
			(xy 108.028992 -231.637286) (xy 108.04504 -231.587893) (xy 108.068618 -231.541619) (xy 108.099144 -231.499603)
			(xy 108.135867 -231.46288) (xy 108.177883 -231.432354) (xy 108.224157 -231.408776) (xy 108.27355 -231.392728)
			(xy 108.324845 -231.384603) (xy 108.376779 -231.384603) (xy 108.428074 -231.392728) (xy 108.477467 -231.408776)
			(xy 108.523741 -231.432354) (xy 108.565757 -231.46288) (xy 108.60248 -231.499603) (xy 108.633006 -231.541619)
			(xy 108.656584 -231.587893) (xy 108.672632 -231.637286) (xy 108.680757 -231.688581) (xy 108.681266 -231.714548)
			(xy 108.680757 -231.740515) (xy 108.960667 -231.740515) (xy 108.960667 -231.688581) (xy 108.968792 -231.637286)
			(xy 108.98484 -231.587893) (xy 109.008418 -231.541619) (xy 109.038944 -231.499603) (xy 109.075667 -231.46288)
			(xy 109.117683 -231.432354) (xy 109.163957 -231.408776) (xy 109.21335 -231.392728) (xy 109.264645 -231.384603)
			(xy 109.316579 -231.384603) (xy 109.367874 -231.392728) (xy 109.417267 -231.408776) (xy 109.463541 -231.432354)
			(xy 109.505557 -231.46288) (xy 109.54228 -231.499603) (xy 109.572806 -231.541619) (xy 109.596384 -231.587893)
			(xy 109.612432 -231.637286) (xy 109.620557 -231.688581) (xy 109.621066 -231.714548) (xy 109.620557 -231.740515)
			(xy 109.900721 -231.740515) (xy 109.900721 -231.688581) (xy 109.908846 -231.637286) (xy 109.924894 -231.587893)
			(xy 109.948472 -231.541619) (xy 109.978998 -231.499603) (xy 110.015721 -231.46288) (xy 110.057737 -231.432354)
			(xy 110.104011 -231.408776) (xy 110.153404 -231.392728) (xy 110.204699 -231.384603) (xy 110.256633 -231.384603)
			(xy 110.307928 -231.392728) (xy 110.357321 -231.408776) (xy 110.403595 -231.432354) (xy 110.445611 -231.46288)
			(xy 110.482334 -231.499603) (xy 110.51286 -231.541619) (xy 110.536438 -231.587893) (xy 110.552486 -231.637286)
			(xy 110.560611 -231.688581) (xy 110.56112 -231.714548) (xy 110.560611 -231.740515) (xy 110.840267 -231.740515)
			(xy 110.840267 -231.688581) (xy 110.848392 -231.637286) (xy 110.86444 -231.587893) (xy 110.888018 -231.541619)
			(xy 110.918544 -231.499603) (xy 110.955267 -231.46288) (xy 110.997283 -231.432354) (xy 111.043557 -231.408776)
			(xy 111.09295 -231.392728) (xy 111.144245 -231.384603) (xy 111.196179 -231.384603) (xy 111.247474 -231.392728)
			(xy 111.296867 -231.408776) (xy 111.343141 -231.432354) (xy 111.385157 -231.46288) (xy 111.42188 -231.499603)
			(xy 111.452406 -231.541619) (xy 111.475984 -231.587893) (xy 111.492032 -231.637286) (xy 111.500157 -231.688581)
			(xy 111.500666 -231.714548) (xy 111.500157 -231.740515) (xy 111.780575 -231.740515) (xy 111.780575 -231.688581)
			(xy 111.7887 -231.637286) (xy 111.804748 -231.587893) (xy 111.828326 -231.541619) (xy 111.858852 -231.499603)
			(xy 111.895575 -231.46288) (xy 111.937591 -231.432354) (xy 111.983865 -231.408776) (xy 112.033258 -231.392728)
			(xy 112.084553 -231.384603) (xy 112.136487 -231.384603) (xy 112.187782 -231.392728) (xy 112.237175 -231.408776)
			(xy 112.283449 -231.432354) (xy 112.325465 -231.46288) (xy 112.362188 -231.499603) (xy 112.392714 -231.541619)
			(xy 112.416292 -231.587893) (xy 112.43234 -231.637286) (xy 112.440465 -231.688581) (xy 112.440974 -231.714548)
			(xy 112.440465 -231.740515) (xy 112.720375 -231.740515) (xy 112.720375 -231.688581) (xy 112.7285 -231.637286)
			(xy 112.744548 -231.587893) (xy 112.768126 -231.541619) (xy 112.798652 -231.499603) (xy 112.835375 -231.46288)
			(xy 112.877391 -231.432354) (xy 112.923665 -231.408776) (xy 112.973058 -231.392728) (xy 113.024353 -231.384603)
			(xy 113.076287 -231.384603) (xy 113.127582 -231.392728) (xy 113.176975 -231.408776) (xy 113.223249 -231.432354)
			(xy 113.265265 -231.46288) (xy 113.301988 -231.499603) (xy 113.332514 -231.541619) (xy 113.356092 -231.587893)
			(xy 113.37214 -231.637286) (xy 113.380265 -231.688581) (xy 113.380774 -231.714548) (xy 113.380265 -231.740515)
			(xy 113.660175 -231.740515) (xy 113.660175 -231.688581) (xy 113.6683 -231.637286) (xy 113.684348 -231.587893)
			(xy 113.707926 -231.541619) (xy 113.738452 -231.499603) (xy 113.775175 -231.46288) (xy 113.817191 -231.432354)
			(xy 113.863465 -231.408776) (xy 113.912858 -231.392728) (xy 113.964153 -231.384603) (xy 114.016087 -231.384603)
			(xy 114.067382 -231.392728) (xy 114.116775 -231.408776) (xy 114.163049 -231.432354) (xy 114.205065 -231.46288)
			(xy 114.241788 -231.499603) (xy 114.272314 -231.541619) (xy 114.295892 -231.587893) (xy 114.31194 -231.637286)
			(xy 114.320065 -231.688581) (xy 114.320574 -231.714548) (xy 114.320065 -231.740515) (xy 114.599467 -231.740515)
			(xy 114.599467 -231.688581) (xy 114.607592 -231.637286) (xy 114.62364 -231.587893) (xy 114.647218 -231.541619)
			(xy 114.677744 -231.499603) (xy 114.714467 -231.46288) (xy 114.756483 -231.432354) (xy 114.802757 -231.408776)
			(xy 114.85215 -231.392728) (xy 114.903445 -231.384603) (xy 114.955379 -231.384603) (xy 115.006674 -231.392728)
			(xy 115.056067 -231.408776) (xy 115.102341 -231.432354) (xy 115.144357 -231.46288) (xy 115.18108 -231.499603)
			(xy 115.211606 -231.541619) (xy 115.235184 -231.587893) (xy 115.251232 -231.637286) (xy 115.259357 -231.688581)
			(xy 115.259866 -231.714548) (xy 115.259357 -231.740515) (xy 115.539267 -231.740515) (xy 115.539267 -231.688581)
			(xy 115.547392 -231.637286) (xy 115.56344 -231.587893) (xy 115.587018 -231.541619) (xy 115.617544 -231.499603)
			(xy 115.654267 -231.46288) (xy 115.696283 -231.432354) (xy 115.742557 -231.408776) (xy 115.79195 -231.392728)
			(xy 115.843245 -231.384603) (xy 115.895179 -231.384603) (xy 115.946474 -231.392728) (xy 115.995867 -231.408776)
			(xy 116.042141 -231.432354) (xy 116.084157 -231.46288) (xy 116.12088 -231.499603) (xy 116.151406 -231.541619)
			(xy 116.174984 -231.587893) (xy 116.191032 -231.637286) (xy 116.199157 -231.688581) (xy 116.199666 -231.714548)
			(xy 116.199157 -231.740515) (xy 116.479067 -231.740515) (xy 116.479067 -231.688581) (xy 116.487192 -231.637286)
			(xy 116.50324 -231.587893) (xy 116.526818 -231.541619) (xy 116.557344 -231.499603) (xy 116.594067 -231.46288)
			(xy 116.636083 -231.432354) (xy 116.682357 -231.408776) (xy 116.73175 -231.392728) (xy 116.783045 -231.384603)
			(xy 116.834979 -231.384603) (xy 116.886274 -231.392728) (xy 116.935667 -231.408776) (xy 116.981941 -231.432354)
			(xy 117.023957 -231.46288) (xy 117.06068 -231.499603) (xy 117.091206 -231.541619) (xy 117.114784 -231.587893)
			(xy 117.130832 -231.637286) (xy 117.138957 -231.688581) (xy 117.139466 -231.714548) (xy 117.138957 -231.740515)
			(xy 117.418867 -231.740515) (xy 117.418867 -231.688581) (xy 117.426992 -231.637286) (xy 117.44304 -231.587893)
			(xy 117.466618 -231.541619) (xy 117.497144 -231.499603) (xy 117.533867 -231.46288) (xy 117.575883 -231.432354)
			(xy 117.622157 -231.408776) (xy 117.67155 -231.392728) (xy 117.722845 -231.384603) (xy 117.774779 -231.384603)
			(xy 117.826074 -231.392728) (xy 117.875467 -231.408776) (xy 117.921741 -231.432354) (xy 117.963757 -231.46288)
			(xy 118.00048 -231.499603) (xy 118.031006 -231.541619) (xy 118.054584 -231.587893) (xy 118.070632 -231.637286)
			(xy 118.078757 -231.688581) (xy 118.079266 -231.714548) (xy 118.078757 -231.740515) (xy 118.358667 -231.740515)
			(xy 118.358667 -231.688581) (xy 118.366792 -231.637286) (xy 118.38284 -231.587893) (xy 118.406418 -231.541619)
			(xy 118.436944 -231.499603) (xy 118.473667 -231.46288) (xy 118.515683 -231.432354) (xy 118.561957 -231.408776)
			(xy 118.61135 -231.392728) (xy 118.662645 -231.384603) (xy 118.714579 -231.384603) (xy 118.765874 -231.392728)
			(xy 118.815267 -231.408776) (xy 118.861541 -231.432354) (xy 118.903557 -231.46288) (xy 118.94028 -231.499603)
			(xy 118.970806 -231.541619) (xy 118.994384 -231.587893) (xy 119.010432 -231.637286) (xy 119.018557 -231.688581)
			(xy 119.019066 -231.714548) (xy 119.018557 -231.740515) (xy 119.298975 -231.740515) (xy 119.298975 -231.688581)
			(xy 119.3071 -231.637286) (xy 119.323148 -231.587893) (xy 119.346726 -231.541619) (xy 119.377252 -231.499603)
			(xy 119.413975 -231.46288) (xy 119.455991 -231.432354) (xy 119.502265 -231.408776) (xy 119.551658 -231.392728)
			(xy 119.602953 -231.384603) (xy 119.654887 -231.384603) (xy 119.706182 -231.392728) (xy 119.755575 -231.408776)
			(xy 119.801849 -231.432354) (xy 119.843865 -231.46288) (xy 119.880588 -231.499603) (xy 119.911114 -231.541619)
			(xy 119.934692 -231.587893) (xy 119.95074 -231.637286) (xy 119.958865 -231.688581) (xy 119.959374 -231.714548)
			(xy 119.958865 -231.740515) (xy 120.238267 -231.740515) (xy 120.238267 -231.688581) (xy 120.246392 -231.637286)
			(xy 120.26244 -231.587893) (xy 120.286018 -231.541619) (xy 120.316544 -231.499603) (xy 120.353267 -231.46288)
			(xy 120.395283 -231.432354) (xy 120.441557 -231.408776) (xy 120.49095 -231.392728) (xy 120.542245 -231.384603)
			(xy 120.594179 -231.384603) (xy 120.645474 -231.392728) (xy 120.694867 -231.408776) (xy 120.741141 -231.432354)
			(xy 120.783157 -231.46288) (xy 120.81988 -231.499603) (xy 120.850406 -231.541619) (xy 120.873984 -231.587893)
			(xy 120.890032 -231.637286) (xy 120.898157 -231.688581) (xy 120.898666 -231.714548) (xy 120.898157 -231.740515)
			(xy 121.178575 -231.740515) (xy 121.178575 -231.688581) (xy 121.1867 -231.637286) (xy 121.202748 -231.587893)
			(xy 121.226326 -231.541619) (xy 121.256852 -231.499603) (xy 121.293575 -231.46288) (xy 121.335591 -231.432354)
			(xy 121.381865 -231.408776) (xy 121.431258 -231.392728) (xy 121.482553 -231.384603) (xy 121.534487 -231.384603)
			(xy 121.585782 -231.392728) (xy 121.635175 -231.408776) (xy 121.681449 -231.432354) (xy 121.723465 -231.46288)
			(xy 121.760188 -231.499603) (xy 121.790714 -231.541619) (xy 121.814292 -231.587893) (xy 121.83034 -231.637286)
			(xy 121.838465 -231.688581) (xy 121.838974 -231.714548) (xy 121.838465 -231.740515) (xy 122.118121 -231.740515)
			(xy 122.118121 -231.688581) (xy 122.126246 -231.637286) (xy 122.142294 -231.587893) (xy 122.165872 -231.541619)
			(xy 122.196398 -231.499603) (xy 122.233121 -231.46288) (xy 122.275137 -231.432354) (xy 122.321411 -231.408776)
			(xy 122.370804 -231.392728) (xy 122.422099 -231.384603) (xy 122.474033 -231.384603) (xy 122.525328 -231.392728)
			(xy 122.574721 -231.408776) (xy 122.620995 -231.432354) (xy 122.663011 -231.46288) (xy 122.699734 -231.499603)
			(xy 122.73026 -231.541619) (xy 122.753838 -231.587893) (xy 122.769886 -231.637286) (xy 122.778011 -231.688581)
			(xy 122.77852 -231.714548) (xy 122.778011 -231.740515) (xy 123.057667 -231.740515) (xy 123.057667 -231.688581)
			(xy 123.065792 -231.637286) (xy 123.08184 -231.587893) (xy 123.105418 -231.541619) (xy 123.135944 -231.499603)
			(xy 123.172667 -231.46288) (xy 123.214683 -231.432354) (xy 123.260957 -231.408776) (xy 123.31035 -231.392728)
			(xy 123.361645 -231.384603) (xy 123.413579 -231.384603) (xy 123.464874 -231.392728) (xy 123.514267 -231.408776)
			(xy 123.560541 -231.432354) (xy 123.602557 -231.46288) (xy 123.63928 -231.499603) (xy 123.669806 -231.541619)
			(xy 123.693384 -231.587893) (xy 123.709432 -231.637286) (xy 123.717557 -231.688581) (xy 123.718066 -231.714548)
			(xy 123.717557 -231.740515) (xy 123.997467 -231.740515) (xy 123.997467 -231.688581) (xy 124.005592 -231.637286)
			(xy 124.02164 -231.587893) (xy 124.045218 -231.541619) (xy 124.075744 -231.499603) (xy 124.112467 -231.46288)
			(xy 124.154483 -231.432354) (xy 124.200757 -231.408776) (xy 124.25015 -231.392728) (xy 124.301445 -231.384603)
			(xy 124.353379 -231.384603) (xy 124.404674 -231.392728) (xy 124.454067 -231.408776) (xy 124.500341 -231.432354)
			(xy 124.542357 -231.46288) (xy 124.57908 -231.499603) (xy 124.609606 -231.541619) (xy 124.633184 -231.587893)
			(xy 124.649232 -231.637286) (xy 124.657357 -231.688581) (xy 124.657866 -231.714548) (xy 124.657357 -231.740515)
			(xy 124.937267 -231.740515) (xy 124.937267 -231.688581) (xy 124.945392 -231.637286) (xy 124.96144 -231.587893)
			(xy 124.985018 -231.541619) (xy 125.015544 -231.499603) (xy 125.052267 -231.46288) (xy 125.094283 -231.432354)
			(xy 125.140557 -231.408776) (xy 125.18995 -231.392728) (xy 125.241245 -231.384603) (xy 125.293179 -231.384603)
			(xy 125.344474 -231.392728) (xy 125.393867 -231.408776) (xy 125.440141 -231.432354) (xy 125.482157 -231.46288)
			(xy 125.51888 -231.499603) (xy 125.549406 -231.541619) (xy 125.572984 -231.587893) (xy 125.589032 -231.637286)
			(xy 125.597157 -231.688581) (xy 125.597666 -231.714548) (xy 125.597157 -231.740515) (xy 125.877067 -231.740515)
			(xy 125.877067 -231.688581) (xy 125.885192 -231.637286) (xy 125.90124 -231.587893) (xy 125.924818 -231.541619)
			(xy 125.955344 -231.499603) (xy 125.992067 -231.46288) (xy 126.034083 -231.432354) (xy 126.080357 -231.408776)
			(xy 126.12975 -231.392728) (xy 126.181045 -231.384603) (xy 126.232979 -231.384603) (xy 126.284274 -231.392728)
			(xy 126.333667 -231.408776) (xy 126.379941 -231.432354) (xy 126.421957 -231.46288) (xy 126.45868 -231.499603)
			(xy 126.489206 -231.541619) (xy 126.512784 -231.587893) (xy 126.528832 -231.637286) (xy 126.536957 -231.688581)
			(xy 126.537466 -231.714548) (xy 126.536957 -231.740515) (xy 126.816867 -231.740515) (xy 126.816867 -231.688581)
			(xy 126.824992 -231.637286) (xy 126.84104 -231.587893) (xy 126.864618 -231.541619) (xy 126.895144 -231.499603)
			(xy 126.931867 -231.46288) (xy 126.973883 -231.432354) (xy 127.020157 -231.408776) (xy 127.06955 -231.392728)
			(xy 127.120845 -231.384603) (xy 127.172779 -231.384603) (xy 127.224074 -231.392728) (xy 127.273467 -231.408776)
			(xy 127.319741 -231.432354) (xy 127.361757 -231.46288) (xy 127.39848 -231.499603) (xy 127.429006 -231.541619)
			(xy 127.452584 -231.587893) (xy 127.468632 -231.637286) (xy 127.476757 -231.688581) (xy 127.477266 -231.714548)
			(xy 127.476757 -231.740515) (xy 127.756667 -231.740515) (xy 127.756667 -231.688581) (xy 127.764792 -231.637286)
			(xy 127.78084 -231.587893) (xy 127.804418 -231.541619) (xy 127.834944 -231.499603) (xy 127.871667 -231.46288)
			(xy 127.913683 -231.432354) (xy 127.959957 -231.408776) (xy 128.00935 -231.392728) (xy 128.060645 -231.384603)
			(xy 128.112579 -231.384603) (xy 128.163874 -231.392728) (xy 128.213267 -231.408776) (xy 128.259541 -231.432354)
			(xy 128.301557 -231.46288) (xy 128.33828 -231.499603) (xy 128.368806 -231.541619) (xy 128.392384 -231.587893)
			(xy 128.408432 -231.637286) (xy 128.416557 -231.688581) (xy 128.417066 -231.714548) (xy 128.416557 -231.740515)
			(xy 128.696721 -231.740515) (xy 128.696721 -231.688581) (xy 128.704846 -231.637286) (xy 128.720894 -231.587893)
			(xy 128.744472 -231.541619) (xy 128.774998 -231.499603) (xy 128.811721 -231.46288) (xy 128.853737 -231.432354)
			(xy 128.900011 -231.408776) (xy 128.949404 -231.392728) (xy 129.000699 -231.384603) (xy 129.052633 -231.384603)
			(xy 129.103928 -231.392728) (xy 129.153321 -231.408776) (xy 129.199595 -231.432354) (xy 129.241611 -231.46288)
			(xy 129.278334 -231.499603) (xy 129.30886 -231.541619) (xy 129.332438 -231.587893) (xy 129.348486 -231.637286)
			(xy 129.356611 -231.688581) (xy 129.35712 -231.714548) (xy 129.356611 -231.740515) (xy 129.636267 -231.740515)
			(xy 129.636267 -231.688581) (xy 129.644392 -231.637286) (xy 129.66044 -231.587893) (xy 129.684018 -231.541619)
			(xy 129.714544 -231.499603) (xy 129.751267 -231.46288) (xy 129.793283 -231.432354) (xy 129.839557 -231.408776)
			(xy 129.88895 -231.392728) (xy 129.940245 -231.384603) (xy 129.992179 -231.384603) (xy 130.043474 -231.392728)
			(xy 130.092867 -231.408776) (xy 130.139141 -231.432354) (xy 130.181157 -231.46288) (xy 130.21788 -231.499603)
			(xy 130.248406 -231.541619) (xy 130.271984 -231.587893) (xy 130.288032 -231.637286) (xy 130.296157 -231.688581)
			(xy 130.296666 -231.714548) (xy 130.296157 -231.740515) (xy 130.576067 -231.740515) (xy 130.576067 -231.688581)
			(xy 130.584192 -231.637286) (xy 130.60024 -231.587893) (xy 130.623818 -231.541619) (xy 130.654344 -231.499603)
			(xy 130.691067 -231.46288) (xy 130.733083 -231.432354) (xy 130.779357 -231.408776) (xy 130.82875 -231.392728)
			(xy 130.880045 -231.384603) (xy 130.931979 -231.384603) (xy 130.983274 -231.392728) (xy 131.032667 -231.408776)
			(xy 131.078941 -231.432354) (xy 131.120957 -231.46288) (xy 131.15768 -231.499603) (xy 131.188206 -231.541619)
			(xy 131.211784 -231.587893) (xy 131.227832 -231.637286) (xy 131.235957 -231.688581) (xy 131.236466 -231.714548)
			(xy 131.235957 -231.740515) (xy 131.515867 -231.740515) (xy 131.515867 -231.688581) (xy 131.523992 -231.637286)
			(xy 131.54004 -231.587893) (xy 131.563618 -231.541619) (xy 131.594144 -231.499603) (xy 131.630867 -231.46288)
			(xy 131.672883 -231.432354) (xy 131.719157 -231.408776) (xy 131.76855 -231.392728) (xy 131.819845 -231.384603)
			(xy 131.871779 -231.384603) (xy 131.923074 -231.392728) (xy 131.972467 -231.408776) (xy 132.018741 -231.432354)
			(xy 132.060757 -231.46288) (xy 132.09748 -231.499603) (xy 132.128006 -231.541619) (xy 132.151584 -231.587893)
			(xy 132.167632 -231.637286) (xy 132.175757 -231.688581) (xy 132.176266 -231.714548) (xy 132.175757 -231.740515)
			(xy 132.167632 -231.79181) (xy 132.151584 -231.841203) (xy 132.128006 -231.887477) (xy 132.09748 -231.929493)
			(xy 132.060757 -231.966216) (xy 132.018741 -231.996742) (xy 131.972467 -232.02032) (xy 131.923074 -232.036368)
			(xy 131.871779 -232.044493) (xy 131.819845 -232.044493) (xy 131.76855 -232.036368) (xy 131.719157 -232.02032)
			(xy 131.672883 -231.996742) (xy 131.630867 -231.966216) (xy 131.594144 -231.929493) (xy 131.563618 -231.887477)
			(xy 131.54004 -231.841203) (xy 131.523992 -231.79181) (xy 131.515867 -231.740515) (xy 131.235957 -231.740515)
			(xy 131.227832 -231.79181) (xy 131.211784 -231.841203) (xy 131.188206 -231.887477) (xy 131.15768 -231.929493)
			(xy 131.120957 -231.966216) (xy 131.078941 -231.996742) (xy 131.032667 -232.02032) (xy 130.983274 -232.036368)
			(xy 130.931979 -232.044493) (xy 130.880045 -232.044493) (xy 130.82875 -232.036368) (xy 130.779357 -232.02032)
			(xy 130.733083 -231.996742) (xy 130.691067 -231.966216) (xy 130.654344 -231.929493) (xy 130.623818 -231.887477)
			(xy 130.60024 -231.841203) (xy 130.584192 -231.79181) (xy 130.576067 -231.740515) (xy 130.296157 -231.740515)
			(xy 130.288032 -231.79181) (xy 130.271984 -231.841203) (xy 130.248406 -231.887477) (xy 130.21788 -231.929493)
			(xy 130.181157 -231.966216) (xy 130.139141 -231.996742) (xy 130.092867 -232.02032) (xy 130.043474 -232.036368)
			(xy 129.992179 -232.044493) (xy 129.940245 -232.044493) (xy 129.88895 -232.036368) (xy 129.839557 -232.02032)
			(xy 129.793283 -231.996742) (xy 129.751267 -231.966216) (xy 129.714544 -231.929493) (xy 129.684018 -231.887477)
			(xy 129.66044 -231.841203) (xy 129.644392 -231.79181) (xy 129.636267 -231.740515) (xy 129.356611 -231.740515)
			(xy 129.348486 -231.79181) (xy 129.332438 -231.841203) (xy 129.30886 -231.887477) (xy 129.278334 -231.929493)
			(xy 129.241611 -231.966216) (xy 129.199595 -231.996742) (xy 129.153321 -232.02032) (xy 129.103928 -232.036368)
			(xy 129.052633 -232.044493) (xy 129.000699 -232.044493) (xy 128.949404 -232.036368) (xy 128.900011 -232.02032)
			(xy 128.853737 -231.996742) (xy 128.811721 -231.966216) (xy 128.774998 -231.929493) (xy 128.744472 -231.887477)
			(xy 128.720894 -231.841203) (xy 128.704846 -231.79181) (xy 128.696721 -231.740515) (xy 128.416557 -231.740515)
			(xy 128.408432 -231.79181) (xy 128.392384 -231.841203) (xy 128.368806 -231.887477) (xy 128.33828 -231.929493)
			(xy 128.301557 -231.966216) (xy 128.259541 -231.996742) (xy 128.213267 -232.02032) (xy 128.163874 -232.036368)
			(xy 128.112579 -232.044493) (xy 128.060645 -232.044493) (xy 128.00935 -232.036368) (xy 127.959957 -232.02032)
			(xy 127.913683 -231.996742) (xy 127.871667 -231.966216) (xy 127.834944 -231.929493) (xy 127.804418 -231.887477)
			(xy 127.78084 -231.841203) (xy 127.764792 -231.79181) (xy 127.756667 -231.740515) (xy 127.476757 -231.740515)
			(xy 127.468632 -231.79181) (xy 127.452584 -231.841203) (xy 127.429006 -231.887477) (xy 127.39848 -231.929493)
			(xy 127.361757 -231.966216) (xy 127.319741 -231.996742) (xy 127.273467 -232.02032) (xy 127.224074 -232.036368)
			(xy 127.172779 -232.044493) (xy 127.120845 -232.044493) (xy 127.06955 -232.036368) (xy 127.020157 -232.02032)
			(xy 126.973883 -231.996742) (xy 126.931867 -231.966216) (xy 126.895144 -231.929493) (xy 126.864618 -231.887477)
			(xy 126.84104 -231.841203) (xy 126.824992 -231.79181) (xy 126.816867 -231.740515) (xy 126.536957 -231.740515)
			(xy 126.528832 -231.79181) (xy 126.512784 -231.841203) (xy 126.489206 -231.887477) (xy 126.45868 -231.929493)
			(xy 126.421957 -231.966216) (xy 126.379941 -231.996742) (xy 126.333667 -232.02032) (xy 126.284274 -232.036368)
			(xy 126.232979 -232.044493) (xy 126.181045 -232.044493) (xy 126.12975 -232.036368) (xy 126.080357 -232.02032)
			(xy 126.034083 -231.996742) (xy 125.992067 -231.966216) (xy 125.955344 -231.929493) (xy 125.924818 -231.887477)
			(xy 125.90124 -231.841203) (xy 125.885192 -231.79181) (xy 125.877067 -231.740515) (xy 125.597157 -231.740515)
			(xy 125.589032 -231.79181) (xy 125.572984 -231.841203) (xy 125.549406 -231.887477) (xy 125.51888 -231.929493)
			(xy 125.482157 -231.966216) (xy 125.440141 -231.996742) (xy 125.393867 -232.02032) (xy 125.344474 -232.036368)
			(xy 125.293179 -232.044493) (xy 125.241245 -232.044493) (xy 125.18995 -232.036368) (xy 125.140557 -232.02032)
			(xy 125.094283 -231.996742) (xy 125.052267 -231.966216) (xy 125.015544 -231.929493) (xy 124.985018 -231.887477)
			(xy 124.96144 -231.841203) (xy 124.945392 -231.79181) (xy 124.937267 -231.740515) (xy 124.657357 -231.740515)
			(xy 124.649232 -231.79181) (xy 124.633184 -231.841203) (xy 124.609606 -231.887477) (xy 124.57908 -231.929493)
			(xy 124.542357 -231.966216) (xy 124.500341 -231.996742) (xy 124.454067 -232.02032) (xy 124.404674 -232.036368)
			(xy 124.353379 -232.044493) (xy 124.301445 -232.044493) (xy 124.25015 -232.036368) (xy 124.200757 -232.02032)
			(xy 124.154483 -231.996742) (xy 124.112467 -231.966216) (xy 124.075744 -231.929493) (xy 124.045218 -231.887477)
			(xy 124.02164 -231.841203) (xy 124.005592 -231.79181) (xy 123.997467 -231.740515) (xy 123.717557 -231.740515)
			(xy 123.709432 -231.79181) (xy 123.693384 -231.841203) (xy 123.669806 -231.887477) (xy 123.63928 -231.929493)
			(xy 123.602557 -231.966216) (xy 123.560541 -231.996742) (xy 123.514267 -232.02032) (xy 123.464874 -232.036368)
			(xy 123.413579 -232.044493) (xy 123.361645 -232.044493) (xy 123.31035 -232.036368) (xy 123.260957 -232.02032)
			(xy 123.214683 -231.996742) (xy 123.172667 -231.966216) (xy 123.135944 -231.929493) (xy 123.105418 -231.887477)
			(xy 123.08184 -231.841203) (xy 123.065792 -231.79181) (xy 123.057667 -231.740515) (xy 122.778011 -231.740515)
			(xy 122.769886 -231.79181) (xy 122.753838 -231.841203) (xy 122.73026 -231.887477) (xy 122.699734 -231.929493)
			(xy 122.663011 -231.966216) (xy 122.620995 -231.996742) (xy 122.574721 -232.02032) (xy 122.525328 -232.036368)
			(xy 122.474033 -232.044493) (xy 122.422099 -232.044493) (xy 122.370804 -232.036368) (xy 122.321411 -232.02032)
			(xy 122.275137 -231.996742) (xy 122.233121 -231.966216) (xy 122.196398 -231.929493) (xy 122.165872 -231.887477)
			(xy 122.142294 -231.841203) (xy 122.126246 -231.79181) (xy 122.118121 -231.740515) (xy 121.838465 -231.740515)
			(xy 121.83034 -231.79181) (xy 121.814292 -231.841203) (xy 121.790714 -231.887477) (xy 121.760188 -231.929493)
			(xy 121.723465 -231.966216) (xy 121.681449 -231.996742) (xy 121.635175 -232.02032) (xy 121.585782 -232.036368)
			(xy 121.534487 -232.044493) (xy 121.482553 -232.044493) (xy 121.431258 -232.036368) (xy 121.381865 -232.02032)
			(xy 121.335591 -231.996742) (xy 121.293575 -231.966216) (xy 121.256852 -231.929493) (xy 121.226326 -231.887477)
			(xy 121.202748 -231.841203) (xy 121.1867 -231.79181) (xy 121.178575 -231.740515) (xy 120.898157 -231.740515)
			(xy 120.890032 -231.79181) (xy 120.873984 -231.841203) (xy 120.850406 -231.887477) (xy 120.81988 -231.929493)
			(xy 120.783157 -231.966216) (xy 120.741141 -231.996742) (xy 120.694867 -232.02032) (xy 120.645474 -232.036368)
			(xy 120.594179 -232.044493) (xy 120.542245 -232.044493) (xy 120.49095 -232.036368) (xy 120.441557 -232.02032)
			(xy 120.395283 -231.996742) (xy 120.353267 -231.966216) (xy 120.316544 -231.929493) (xy 120.286018 -231.887477)
			(xy 120.26244 -231.841203) (xy 120.246392 -231.79181) (xy 120.238267 -231.740515) (xy 119.958865 -231.740515)
			(xy 119.95074 -231.79181) (xy 119.934692 -231.841203) (xy 119.911114 -231.887477) (xy 119.880588 -231.929493)
			(xy 119.843865 -231.966216) (xy 119.801849 -231.996742) (xy 119.755575 -232.02032) (xy 119.706182 -232.036368)
			(xy 119.654887 -232.044493) (xy 119.602953 -232.044493) (xy 119.551658 -232.036368) (xy 119.502265 -232.02032)
			(xy 119.455991 -231.996742) (xy 119.413975 -231.966216) (xy 119.377252 -231.929493) (xy 119.346726 -231.887477)
			(xy 119.323148 -231.841203) (xy 119.3071 -231.79181) (xy 119.298975 -231.740515) (xy 119.018557 -231.740515)
			(xy 119.010432 -231.79181) (xy 118.994384 -231.841203) (xy 118.970806 -231.887477) (xy 118.94028 -231.929493)
			(xy 118.903557 -231.966216) (xy 118.861541 -231.996742) (xy 118.815267 -232.02032) (xy 118.765874 -232.036368)
			(xy 118.714579 -232.044493) (xy 118.662645 -232.044493) (xy 118.61135 -232.036368) (xy 118.561957 -232.02032)
			(xy 118.515683 -231.996742) (xy 118.473667 -231.966216) (xy 118.436944 -231.929493) (xy 118.406418 -231.887477)
			(xy 118.38284 -231.841203) (xy 118.366792 -231.79181) (xy 118.358667 -231.740515) (xy 118.078757 -231.740515)
			(xy 118.070632 -231.79181) (xy 118.054584 -231.841203) (xy 118.031006 -231.887477) (xy 118.00048 -231.929493)
			(xy 117.963757 -231.966216) (xy 117.921741 -231.996742) (xy 117.875467 -232.02032) (xy 117.826074 -232.036368)
			(xy 117.774779 -232.044493) (xy 117.722845 -232.044493) (xy 117.67155 -232.036368) (xy 117.622157 -232.02032)
			(xy 117.575883 -231.996742) (xy 117.533867 -231.966216) (xy 117.497144 -231.929493) (xy 117.466618 -231.887477)
			(xy 117.44304 -231.841203) (xy 117.426992 -231.79181) (xy 117.418867 -231.740515) (xy 117.138957 -231.740515)
			(xy 117.130832 -231.79181) (xy 117.114784 -231.841203) (xy 117.091206 -231.887477) (xy 117.06068 -231.929493)
			(xy 117.023957 -231.966216) (xy 116.981941 -231.996742) (xy 116.935667 -232.02032) (xy 116.886274 -232.036368)
			(xy 116.834979 -232.044493) (xy 116.783045 -232.044493) (xy 116.73175 -232.036368) (xy 116.682357 -232.02032)
			(xy 116.636083 -231.996742) (xy 116.594067 -231.966216) (xy 116.557344 -231.929493) (xy 116.526818 -231.887477)
			(xy 116.50324 -231.841203) (xy 116.487192 -231.79181) (xy 116.479067 -231.740515) (xy 116.199157 -231.740515)
			(xy 116.191032 -231.79181) (xy 116.174984 -231.841203) (xy 116.151406 -231.887477) (xy 116.12088 -231.929493)
			(xy 116.084157 -231.966216) (xy 116.042141 -231.996742) (xy 115.995867 -232.02032) (xy 115.946474 -232.036368)
			(xy 115.895179 -232.044493) (xy 115.843245 -232.044493) (xy 115.79195 -232.036368) (xy 115.742557 -232.02032)
			(xy 115.696283 -231.996742) (xy 115.654267 -231.966216) (xy 115.617544 -231.929493) (xy 115.587018 -231.887477)
			(xy 115.56344 -231.841203) (xy 115.547392 -231.79181) (xy 115.539267 -231.740515) (xy 115.259357 -231.740515)
			(xy 115.251232 -231.79181) (xy 115.235184 -231.841203) (xy 115.211606 -231.887477) (xy 115.18108 -231.929493)
			(xy 115.144357 -231.966216) (xy 115.102341 -231.996742) (xy 115.056067 -232.02032) (xy 115.006674 -232.036368)
			(xy 114.955379 -232.044493) (xy 114.903445 -232.044493) (xy 114.85215 -232.036368) (xy 114.802757 -232.02032)
			(xy 114.756483 -231.996742) (xy 114.714467 -231.966216) (xy 114.677744 -231.929493) (xy 114.647218 -231.887477)
			(xy 114.62364 -231.841203) (xy 114.607592 -231.79181) (xy 114.599467 -231.740515) (xy 114.320065 -231.740515)
			(xy 114.31194 -231.79181) (xy 114.295892 -231.841203) (xy 114.272314 -231.887477) (xy 114.241788 -231.929493)
			(xy 114.205065 -231.966216) (xy 114.163049 -231.996742) (xy 114.116775 -232.02032) (xy 114.067382 -232.036368)
			(xy 114.016087 -232.044493) (xy 113.964153 -232.044493) (xy 113.912858 -232.036368) (xy 113.863465 -232.02032)
			(xy 113.817191 -231.996742) (xy 113.775175 -231.966216) (xy 113.738452 -231.929493) (xy 113.707926 -231.887477)
			(xy 113.684348 -231.841203) (xy 113.6683 -231.79181) (xy 113.660175 -231.740515) (xy 113.380265 -231.740515)
			(xy 113.37214 -231.79181) (xy 113.356092 -231.841203) (xy 113.332514 -231.887477) (xy 113.301988 -231.929493)
			(xy 113.265265 -231.966216) (xy 113.223249 -231.996742) (xy 113.176975 -232.02032) (xy 113.127582 -232.036368)
			(xy 113.076287 -232.044493) (xy 113.024353 -232.044493) (xy 112.973058 -232.036368) (xy 112.923665 -232.02032)
			(xy 112.877391 -231.996742) (xy 112.835375 -231.966216) (xy 112.798652 -231.929493) (xy 112.768126 -231.887477)
			(xy 112.744548 -231.841203) (xy 112.7285 -231.79181) (xy 112.720375 -231.740515) (xy 112.440465 -231.740515)
			(xy 112.43234 -231.79181) (xy 112.416292 -231.841203) (xy 112.392714 -231.887477) (xy 112.362188 -231.929493)
			(xy 112.325465 -231.966216) (xy 112.283449 -231.996742) (xy 112.237175 -232.02032) (xy 112.187782 -232.036368)
			(xy 112.136487 -232.044493) (xy 112.084553 -232.044493) (xy 112.033258 -232.036368) (xy 111.983865 -232.02032)
			(xy 111.937591 -231.996742) (xy 111.895575 -231.966216) (xy 111.858852 -231.929493) (xy 111.828326 -231.887477)
			(xy 111.804748 -231.841203) (xy 111.7887 -231.79181) (xy 111.780575 -231.740515) (xy 111.500157 -231.740515)
			(xy 111.492032 -231.79181) (xy 111.475984 -231.841203) (xy 111.452406 -231.887477) (xy 111.42188 -231.929493)
			(xy 111.385157 -231.966216) (xy 111.343141 -231.996742) (xy 111.296867 -232.02032) (xy 111.247474 -232.036368)
			(xy 111.196179 -232.044493) (xy 111.144245 -232.044493) (xy 111.09295 -232.036368) (xy 111.043557 -232.02032)
			(xy 110.997283 -231.996742) (xy 110.955267 -231.966216) (xy 110.918544 -231.929493) (xy 110.888018 -231.887477)
			(xy 110.86444 -231.841203) (xy 110.848392 -231.79181) (xy 110.840267 -231.740515) (xy 110.560611 -231.740515)
			(xy 110.552486 -231.79181) (xy 110.536438 -231.841203) (xy 110.51286 -231.887477) (xy 110.482334 -231.929493)
			(xy 110.445611 -231.966216) (xy 110.403595 -231.996742) (xy 110.357321 -232.02032) (xy 110.307928 -232.036368)
			(xy 110.256633 -232.044493) (xy 110.204699 -232.044493) (xy 110.153404 -232.036368) (xy 110.104011 -232.02032)
			(xy 110.057737 -231.996742) (xy 110.015721 -231.966216) (xy 109.978998 -231.929493) (xy 109.948472 -231.887477)
			(xy 109.924894 -231.841203) (xy 109.908846 -231.79181) (xy 109.900721 -231.740515) (xy 109.620557 -231.740515)
			(xy 109.612432 -231.79181) (xy 109.596384 -231.841203) (xy 109.572806 -231.887477) (xy 109.54228 -231.929493)
			(xy 109.505557 -231.966216) (xy 109.463541 -231.996742) (xy 109.417267 -232.02032) (xy 109.367874 -232.036368)
			(xy 109.316579 -232.044493) (xy 109.264645 -232.044493) (xy 109.21335 -232.036368) (xy 109.163957 -232.02032)
			(xy 109.117683 -231.996742) (xy 109.075667 -231.966216) (xy 109.038944 -231.929493) (xy 109.008418 -231.887477)
			(xy 108.98484 -231.841203) (xy 108.968792 -231.79181) (xy 108.960667 -231.740515) (xy 108.680757 -231.740515)
			(xy 108.672632 -231.79181) (xy 108.656584 -231.841203) (xy 108.633006 -231.887477) (xy 108.60248 -231.929493)
			(xy 108.565757 -231.966216) (xy 108.523741 -231.996742) (xy 108.477467 -232.02032) (xy 108.428074 -232.036368)
			(xy 108.376779 -232.044493) (xy 108.324845 -232.044493) (xy 108.27355 -232.036368) (xy 108.224157 -232.02032)
			(xy 108.177883 -231.996742) (xy 108.135867 -231.966216) (xy 108.099144 -231.929493) (xy 108.068618 -231.887477)
			(xy 108.04504 -231.841203) (xy 108.028992 -231.79181) (xy 108.020867 -231.740515) (xy 107.740957 -231.740515)
			(xy 107.732832 -231.79181) (xy 107.716784 -231.841203) (xy 107.693206 -231.887477) (xy 107.66268 -231.929493)
			(xy 107.625957 -231.966216) (xy 107.583941 -231.996742) (xy 107.537667 -232.02032) (xy 107.488274 -232.036368)
			(xy 107.436979 -232.044493) (xy 107.385045 -232.044493) (xy 107.33375 -232.036368) (xy 107.284357 -232.02032)
			(xy 107.238083 -231.996742) (xy 107.196067 -231.966216) (xy 107.159344 -231.929493) (xy 107.128818 -231.887477)
			(xy 107.10524 -231.841203) (xy 107.089192 -231.79181) (xy 107.081067 -231.740515) (xy 106.801157 -231.740515)
			(xy 106.793032 -231.79181) (xy 106.776984 -231.841203) (xy 106.753406 -231.887477) (xy 106.72288 -231.929493)
			(xy 106.686157 -231.966216) (xy 106.644141 -231.996742) (xy 106.597867 -232.02032) (xy 106.548474 -232.036368)
			(xy 106.497179 -232.044493) (xy 106.445245 -232.044493) (xy 106.39395 -232.036368) (xy 106.344557 -232.02032)
			(xy 106.298283 -231.996742) (xy 106.256267 -231.966216) (xy 106.219544 -231.929493) (xy 106.189018 -231.887477)
			(xy 106.16544 -231.841203) (xy 106.149392 -231.79181) (xy 106.141267 -231.740515) (xy 105.861386 -231.740515)
			(xy 105.853268 -231.791772) (xy 105.837217 -231.84117) (xy 105.813637 -231.88745) (xy 105.783108 -231.929472)
			(xy 105.746381 -231.9662) (xy 105.70436 -231.996731) (xy 105.658082 -232.020313) (xy 105.608683 -232.036365)
			(xy 105.557382 -232.044492) (xy 105.531412 -232.045002) (xy 105.519728 -232.044748) (xy 105.506101 -232.044704)
			(xy 105.479599 -232.051011) (xy 105.455705 -232.064094) (xy 105.436115 -232.083024) (xy 105.422222 -232.106457)
			(xy 105.415013 -232.132727) (xy 105.414572 -232.146348) (xy 105.414572 -232.554331) (xy 105.671621 -232.554331)
			(xy 105.671621 -232.502397) (xy 105.679746 -232.451102) (xy 105.695794 -232.401709) (xy 105.719372 -232.355435)
			(xy 105.749898 -232.313419) (xy 105.786621 -232.276696) (xy 105.828637 -232.24617) (xy 105.874911 -232.222592)
			(xy 105.924304 -232.206544) (xy 105.975599 -232.198419) (xy 106.027533 -232.198419) (xy 106.078828 -232.206544)
			(xy 106.128221 -232.222592) (xy 106.174495 -232.24617) (xy 106.216511 -232.276696) (xy 106.253234 -232.313419)
			(xy 106.28376 -232.355435) (xy 106.307338 -232.401709) (xy 106.323386 -232.451102) (xy 106.331511 -232.502397)
			(xy 106.33202 -232.528364) (xy 106.331511 -232.554331) (xy 106.611421 -232.554331) (xy 106.611421 -232.502397)
			(xy 106.619546 -232.451102) (xy 106.635594 -232.401709) (xy 106.659172 -232.355435) (xy 106.689698 -232.313419)
			(xy 106.726421 -232.276696) (xy 106.768437 -232.24617) (xy 106.814711 -232.222592) (xy 106.864104 -232.206544)
			(xy 106.915399 -232.198419) (xy 106.967333 -232.198419) (xy 107.018628 -232.206544) (xy 107.068021 -232.222592)
			(xy 107.114295 -232.24617) (xy 107.156311 -232.276696) (xy 107.193034 -232.313419) (xy 107.22356 -232.355435)
			(xy 107.247138 -232.401709) (xy 107.263186 -232.451102) (xy 107.271311 -232.502397) (xy 107.27182 -232.528364)
			(xy 107.271311 -232.554331) (xy 107.551221 -232.554331) (xy 107.551221 -232.502397) (xy 107.559346 -232.451102)
			(xy 107.575394 -232.401709) (xy 107.598972 -232.355435) (xy 107.629498 -232.313419) (xy 107.666221 -232.276696)
			(xy 107.708237 -232.24617) (xy 107.754511 -232.222592) (xy 107.803904 -232.206544) (xy 107.855199 -232.198419)
			(xy 107.907133 -232.198419) (xy 107.958428 -232.206544) (xy 108.007821 -232.222592) (xy 108.054095 -232.24617)
			(xy 108.096111 -232.276696) (xy 108.132834 -232.313419) (xy 108.16336 -232.355435) (xy 108.186938 -232.401709)
			(xy 108.202986 -232.451102) (xy 108.211111 -232.502397) (xy 108.21162 -232.528364) (xy 108.211111 -232.554331)
			(xy 108.491021 -232.554331) (xy 108.491021 -232.502397) (xy 108.499146 -232.451102) (xy 108.515194 -232.401709)
			(xy 108.538772 -232.355435) (xy 108.569298 -232.313419) (xy 108.606021 -232.276696) (xy 108.648037 -232.24617)
			(xy 108.694311 -232.222592) (xy 108.743704 -232.206544) (xy 108.794999 -232.198419) (xy 108.846933 -232.198419)
			(xy 108.898228 -232.206544) (xy 108.947621 -232.222592) (xy 108.993895 -232.24617) (xy 109.035911 -232.276696)
			(xy 109.072634 -232.313419) (xy 109.10316 -232.355435) (xy 109.126738 -232.401709) (xy 109.142786 -232.451102)
			(xy 109.150911 -232.502397) (xy 109.15142 -232.528364) (xy 109.150911 -232.554331) (xy 109.430821 -232.554331)
			(xy 109.430821 -232.502397) (xy 109.438946 -232.451102) (xy 109.454994 -232.401709) (xy 109.478572 -232.355435)
			(xy 109.509098 -232.313419) (xy 109.545821 -232.276696) (xy 109.587837 -232.24617) (xy 109.634111 -232.222592)
			(xy 109.683504 -232.206544) (xy 109.734799 -232.198419) (xy 109.786733 -232.198419) (xy 109.838028 -232.206544)
			(xy 109.887421 -232.222592) (xy 109.933695 -232.24617) (xy 109.975711 -232.276696) (xy 110.012434 -232.313419)
			(xy 110.04296 -232.355435) (xy 110.066538 -232.401709) (xy 110.082586 -232.451102) (xy 110.090711 -232.502397)
			(xy 110.09122 -232.528364) (xy 110.090711 -232.554331) (xy 110.370621 -232.554331) (xy 110.370621 -232.502397)
			(xy 110.378746 -232.451102) (xy 110.394794 -232.401709) (xy 110.418372 -232.355435) (xy 110.448898 -232.313419)
			(xy 110.485621 -232.276696) (xy 110.527637 -232.24617) (xy 110.573911 -232.222592) (xy 110.623304 -232.206544)
			(xy 110.674599 -232.198419) (xy 110.726533 -232.198419) (xy 110.777828 -232.206544) (xy 110.827221 -232.222592)
			(xy 110.873495 -232.24617) (xy 110.915511 -232.276696) (xy 110.952234 -232.313419) (xy 110.98276 -232.355435)
			(xy 111.006338 -232.401709) (xy 111.022386 -232.451102) (xy 111.030511 -232.502397) (xy 111.03102 -232.528364)
			(xy 111.030511 -232.554331) (xy 111.310421 -232.554331) (xy 111.310421 -232.502397) (xy 111.318546 -232.451102)
			(xy 111.334594 -232.401709) (xy 111.358172 -232.355435) (xy 111.388698 -232.313419) (xy 111.425421 -232.276696)
			(xy 111.467437 -232.24617) (xy 111.513711 -232.222592) (xy 111.563104 -232.206544) (xy 111.614399 -232.198419)
			(xy 111.666333 -232.198419) (xy 111.717628 -232.206544) (xy 111.767021 -232.222592) (xy 111.813295 -232.24617)
			(xy 111.855311 -232.276696) (xy 111.892034 -232.313419) (xy 111.92256 -232.355435) (xy 111.946138 -232.401709)
			(xy 111.962186 -232.451102) (xy 111.970311 -232.502397) (xy 111.97082 -232.528364) (xy 111.970311 -232.554331)
			(xy 112.250221 -232.554331) (xy 112.250221 -232.502397) (xy 112.258346 -232.451102) (xy 112.274394 -232.401709)
			(xy 112.297972 -232.355435) (xy 112.328498 -232.313419) (xy 112.365221 -232.276696) (xy 112.407237 -232.24617)
			(xy 112.453511 -232.222592) (xy 112.502904 -232.206544) (xy 112.554199 -232.198419) (xy 112.606133 -232.198419)
			(xy 112.657428 -232.206544) (xy 112.706821 -232.222592) (xy 112.753095 -232.24617) (xy 112.795111 -232.276696)
			(xy 112.831834 -232.313419) (xy 112.86236 -232.355435) (xy 112.885938 -232.401709) (xy 112.901986 -232.451102)
			(xy 112.910111 -232.502397) (xy 112.91062 -232.528364) (xy 112.910111 -232.554331) (xy 113.190021 -232.554331)
			(xy 113.190021 -232.502397) (xy 113.198146 -232.451102) (xy 113.214194 -232.401709) (xy 113.237772 -232.355435)
			(xy 113.268298 -232.313419) (xy 113.305021 -232.276696) (xy 113.347037 -232.24617) (xy 113.393311 -232.222592)
			(xy 113.442704 -232.206544) (xy 113.493999 -232.198419) (xy 113.545933 -232.198419) (xy 113.597228 -232.206544)
			(xy 113.646621 -232.222592) (xy 113.692895 -232.24617) (xy 113.734911 -232.276696) (xy 113.771634 -232.313419)
			(xy 113.80216 -232.355435) (xy 113.825738 -232.401709) (xy 113.841786 -232.451102) (xy 113.849911 -232.502397)
			(xy 113.85042 -232.528364) (xy 113.849911 -232.554331) (xy 114.129821 -232.554331) (xy 114.129821 -232.502397)
			(xy 114.137946 -232.451102) (xy 114.153994 -232.401709) (xy 114.177572 -232.355435) (xy 114.208098 -232.313419)
			(xy 114.244821 -232.276696) (xy 114.286837 -232.24617) (xy 114.333111 -232.222592) (xy 114.382504 -232.206544)
			(xy 114.433799 -232.198419) (xy 114.485733 -232.198419) (xy 114.537028 -232.206544) (xy 114.586421 -232.222592)
			(xy 114.632695 -232.24617) (xy 114.674711 -232.276696) (xy 114.711434 -232.313419) (xy 114.74196 -232.355435)
			(xy 114.765538 -232.401709) (xy 114.781586 -232.451102) (xy 114.789711 -232.502397) (xy 114.79022 -232.528364)
			(xy 114.789711 -232.554331) (xy 115.069621 -232.554331) (xy 115.069621 -232.502397) (xy 115.077746 -232.451102)
			(xy 115.093794 -232.401709) (xy 115.117372 -232.355435) (xy 115.147898 -232.313419) (xy 115.184621 -232.276696)
			(xy 115.226637 -232.24617) (xy 115.272911 -232.222592) (xy 115.322304 -232.206544) (xy 115.373599 -232.198419)
			(xy 115.425533 -232.198419) (xy 115.476828 -232.206544) (xy 115.526221 -232.222592) (xy 115.572495 -232.24617)
			(xy 115.614511 -232.276696) (xy 115.651234 -232.313419) (xy 115.68176 -232.355435) (xy 115.705338 -232.401709)
			(xy 115.721386 -232.451102) (xy 115.729511 -232.502397) (xy 115.73002 -232.528364) (xy 115.729511 -232.554331)
			(xy 116.009421 -232.554331) (xy 116.009421 -232.502397) (xy 116.017546 -232.451102) (xy 116.033594 -232.401709)
			(xy 116.057172 -232.355435) (xy 116.087698 -232.313419) (xy 116.124421 -232.276696) (xy 116.166437 -232.24617)
			(xy 116.212711 -232.222592) (xy 116.262104 -232.206544) (xy 116.313399 -232.198419) (xy 116.365333 -232.198419)
			(xy 116.416628 -232.206544) (xy 116.466021 -232.222592) (xy 116.512295 -232.24617) (xy 116.554311 -232.276696)
			(xy 116.591034 -232.313419) (xy 116.62156 -232.355435) (xy 116.645138 -232.401709) (xy 116.661186 -232.451102)
			(xy 116.669311 -232.502397) (xy 116.66982 -232.528364) (xy 116.669311 -232.554331) (xy 116.949221 -232.554331)
			(xy 116.949221 -232.502397) (xy 116.957346 -232.451102) (xy 116.973394 -232.401709) (xy 116.996972 -232.355435)
			(xy 117.027498 -232.313419) (xy 117.064221 -232.276696) (xy 117.106237 -232.24617) (xy 117.152511 -232.222592)
			(xy 117.201904 -232.206544) (xy 117.253199 -232.198419) (xy 117.305133 -232.198419) (xy 117.356428 -232.206544)
			(xy 117.405821 -232.222592) (xy 117.452095 -232.24617) (xy 117.494111 -232.276696) (xy 117.530834 -232.313419)
			(xy 117.56136 -232.355435) (xy 117.584938 -232.401709) (xy 117.600986 -232.451102) (xy 117.609111 -232.502397)
			(xy 117.60962 -232.528364) (xy 117.609111 -232.554331) (xy 117.889021 -232.554331) (xy 117.889021 -232.502397)
			(xy 117.897146 -232.451102) (xy 117.913194 -232.401709) (xy 117.936772 -232.355435) (xy 117.967298 -232.313419)
			(xy 118.004021 -232.276696) (xy 118.046037 -232.24617) (xy 118.092311 -232.222592) (xy 118.141704 -232.206544)
			(xy 118.192999 -232.198419) (xy 118.244933 -232.198419) (xy 118.296228 -232.206544) (xy 118.345621 -232.222592)
			(xy 118.391895 -232.24617) (xy 118.433911 -232.276696) (xy 118.470634 -232.313419) (xy 118.50116 -232.355435)
			(xy 118.524738 -232.401709) (xy 118.540786 -232.451102) (xy 118.548911 -232.502397) (xy 118.54942 -232.528364)
			(xy 118.548911 -232.554331) (xy 118.828821 -232.554331) (xy 118.828821 -232.502397) (xy 118.836946 -232.451102)
			(xy 118.852994 -232.401709) (xy 118.876572 -232.355435) (xy 118.907098 -232.313419) (xy 118.943821 -232.276696)
			(xy 118.985837 -232.24617) (xy 119.032111 -232.222592) (xy 119.081504 -232.206544) (xy 119.132799 -232.198419)
			(xy 119.184733 -232.198419) (xy 119.236028 -232.206544) (xy 119.285421 -232.222592) (xy 119.331695 -232.24617)
			(xy 119.373711 -232.276696) (xy 119.410434 -232.313419) (xy 119.44096 -232.355435) (xy 119.464538 -232.401709)
			(xy 119.480586 -232.451102) (xy 119.488711 -232.502397) (xy 119.48922 -232.528364) (xy 119.488711 -232.554331)
			(xy 119.768367 -232.554331) (xy 119.768367 -232.502397) (xy 119.776492 -232.451102) (xy 119.79254 -232.401709)
			(xy 119.816118 -232.355435) (xy 119.846644 -232.313419) (xy 119.883367 -232.276696) (xy 119.925383 -232.24617)
			(xy 119.971657 -232.222592) (xy 120.02105 -232.206544) (xy 120.072345 -232.198419) (xy 120.124279 -232.198419)
			(xy 120.175574 -232.206544) (xy 120.224967 -232.222592) (xy 120.271241 -232.24617) (xy 120.313257 -232.276696)
			(xy 120.34998 -232.313419) (xy 120.380506 -232.355435) (xy 120.404084 -232.401709) (xy 120.420132 -232.451102)
			(xy 120.428257 -232.502397) (xy 120.428766 -232.528364) (xy 120.428257 -232.554331) (xy 120.708421 -232.554331)
			(xy 120.708421 -232.502397) (xy 120.716546 -232.451102) (xy 120.732594 -232.401709) (xy 120.756172 -232.355435)
			(xy 120.786698 -232.313419) (xy 120.823421 -232.276696) (xy 120.865437 -232.24617) (xy 120.911711 -232.222592)
			(xy 120.961104 -232.206544) (xy 121.012399 -232.198419) (xy 121.064333 -232.198419) (xy 121.115628 -232.206544)
			(xy 121.165021 -232.222592) (xy 121.211295 -232.24617) (xy 121.253311 -232.276696) (xy 121.290034 -232.313419)
			(xy 121.32056 -232.355435) (xy 121.344138 -232.401709) (xy 121.360186 -232.451102) (xy 121.368311 -232.502397)
			(xy 121.36882 -232.528364) (xy 121.368311 -232.554331) (xy 121.648221 -232.554331) (xy 121.648221 -232.502397)
			(xy 121.656346 -232.451102) (xy 121.672394 -232.401709) (xy 121.695972 -232.355435) (xy 121.726498 -232.313419)
			(xy 121.763221 -232.276696) (xy 121.805237 -232.24617) (xy 121.851511 -232.222592) (xy 121.900904 -232.206544)
			(xy 121.952199 -232.198419) (xy 122.004133 -232.198419) (xy 122.055428 -232.206544) (xy 122.104821 -232.222592)
			(xy 122.151095 -232.24617) (xy 122.193111 -232.276696) (xy 122.229834 -232.313419) (xy 122.26036 -232.355435)
			(xy 122.283938 -232.401709) (xy 122.299986 -232.451102) (xy 122.308111 -232.502397) (xy 122.30862 -232.528364)
			(xy 122.308111 -232.554331) (xy 122.588021 -232.554331) (xy 122.588021 -232.502397) (xy 122.596146 -232.451102)
			(xy 122.612194 -232.401709) (xy 122.635772 -232.355435) (xy 122.666298 -232.313419) (xy 122.703021 -232.276696)
			(xy 122.745037 -232.24617) (xy 122.791311 -232.222592) (xy 122.840704 -232.206544) (xy 122.891999 -232.198419)
			(xy 122.943933 -232.198419) (xy 122.995228 -232.206544) (xy 123.044621 -232.222592) (xy 123.090895 -232.24617)
			(xy 123.132911 -232.276696) (xy 123.169634 -232.313419) (xy 123.20016 -232.355435) (xy 123.223738 -232.401709)
			(xy 123.239786 -232.451102) (xy 123.247911 -232.502397) (xy 123.24842 -232.528364) (xy 123.247911 -232.554331)
			(xy 123.527821 -232.554331) (xy 123.527821 -232.502397) (xy 123.535946 -232.451102) (xy 123.551994 -232.401709)
			(xy 123.575572 -232.355435) (xy 123.606098 -232.313419) (xy 123.642821 -232.276696) (xy 123.684837 -232.24617)
			(xy 123.731111 -232.222592) (xy 123.780504 -232.206544) (xy 123.831799 -232.198419) (xy 123.883733 -232.198419)
			(xy 123.935028 -232.206544) (xy 123.984421 -232.222592) (xy 124.030695 -232.24617) (xy 124.072711 -232.276696)
			(xy 124.109434 -232.313419) (xy 124.13996 -232.355435) (xy 124.163538 -232.401709) (xy 124.179586 -232.451102)
			(xy 124.187711 -232.502397) (xy 124.18822 -232.528364) (xy 124.187711 -232.554331) (xy 124.467621 -232.554331)
			(xy 124.467621 -232.502397) (xy 124.475746 -232.451102) (xy 124.491794 -232.401709) (xy 124.515372 -232.355435)
			(xy 124.545898 -232.313419) (xy 124.582621 -232.276696) (xy 124.624637 -232.24617) (xy 124.670911 -232.222592)
			(xy 124.720304 -232.206544) (xy 124.771599 -232.198419) (xy 124.823533 -232.198419) (xy 124.874828 -232.206544)
			(xy 124.924221 -232.222592) (xy 124.970495 -232.24617) (xy 125.012511 -232.276696) (xy 125.049234 -232.313419)
			(xy 125.07976 -232.355435) (xy 125.103338 -232.401709) (xy 125.119386 -232.451102) (xy 125.127511 -232.502397)
			(xy 125.12802 -232.528364) (xy 125.127511 -232.554331) (xy 125.407421 -232.554331) (xy 125.407421 -232.502397)
			(xy 125.415546 -232.451102) (xy 125.431594 -232.401709) (xy 125.455172 -232.355435) (xy 125.485698 -232.313419)
			(xy 125.522421 -232.276696) (xy 125.564437 -232.24617) (xy 125.610711 -232.222592) (xy 125.660104 -232.206544)
			(xy 125.711399 -232.198419) (xy 125.763333 -232.198419) (xy 125.814628 -232.206544) (xy 125.864021 -232.222592)
			(xy 125.910295 -232.24617) (xy 125.952311 -232.276696) (xy 125.989034 -232.313419) (xy 126.01956 -232.355435)
			(xy 126.043138 -232.401709) (xy 126.059186 -232.451102) (xy 126.067311 -232.502397) (xy 126.06782 -232.528364)
			(xy 126.067311 -232.554331) (xy 126.346967 -232.554331) (xy 126.346967 -232.502397) (xy 126.355092 -232.451102)
			(xy 126.37114 -232.401709) (xy 126.394718 -232.355435) (xy 126.425244 -232.313419) (xy 126.461967 -232.276696)
			(xy 126.503983 -232.24617) (xy 126.550257 -232.222592) (xy 126.59965 -232.206544) (xy 126.650945 -232.198419)
			(xy 126.702879 -232.198419) (xy 126.754174 -232.206544) (xy 126.803567 -232.222592) (xy 126.849841 -232.24617)
			(xy 126.891857 -232.276696) (xy 126.92858 -232.313419) (xy 126.959106 -232.355435) (xy 126.982684 -232.401709)
			(xy 126.998732 -232.451102) (xy 127.006857 -232.502397) (xy 127.007366 -232.528364) (xy 127.006857 -232.554331)
			(xy 127.287021 -232.554331) (xy 127.287021 -232.502397) (xy 127.295146 -232.451102) (xy 127.311194 -232.401709)
			(xy 127.334772 -232.355435) (xy 127.365298 -232.313419) (xy 127.402021 -232.276696) (xy 127.444037 -232.24617)
			(xy 127.490311 -232.222592) (xy 127.539704 -232.206544) (xy 127.590999 -232.198419) (xy 127.642933 -232.198419)
			(xy 127.694228 -232.206544) (xy 127.743621 -232.222592) (xy 127.789895 -232.24617) (xy 127.831911 -232.276696)
			(xy 127.868634 -232.313419) (xy 127.89916 -232.355435) (xy 127.922738 -232.401709) (xy 127.938786 -232.451102)
			(xy 127.946911 -232.502397) (xy 127.94742 -232.528364) (xy 127.946911 -232.554331) (xy 128.226821 -232.554331)
			(xy 128.226821 -232.502397) (xy 128.234946 -232.451102) (xy 128.250994 -232.401709) (xy 128.274572 -232.355435)
			(xy 128.305098 -232.313419) (xy 128.341821 -232.276696) (xy 128.383837 -232.24617) (xy 128.430111 -232.222592)
			(xy 128.479504 -232.206544) (xy 128.530799 -232.198419) (xy 128.582733 -232.198419) (xy 128.634028 -232.206544)
			(xy 128.683421 -232.222592) (xy 128.729695 -232.24617) (xy 128.771711 -232.276696) (xy 128.808434 -232.313419)
			(xy 128.83896 -232.355435) (xy 128.862538 -232.401709) (xy 128.878586 -232.451102) (xy 128.886711 -232.502397)
			(xy 128.88722 -232.528364) (xy 128.886711 -232.554331) (xy 129.166621 -232.554331) (xy 129.166621 -232.502397)
			(xy 129.174746 -232.451102) (xy 129.190794 -232.401709) (xy 129.214372 -232.355435) (xy 129.244898 -232.313419)
			(xy 129.281621 -232.276696) (xy 129.323637 -232.24617) (xy 129.369911 -232.222592) (xy 129.419304 -232.206544)
			(xy 129.470599 -232.198419) (xy 129.522533 -232.198419) (xy 129.573828 -232.206544) (xy 129.623221 -232.222592)
			(xy 129.669495 -232.24617) (xy 129.711511 -232.276696) (xy 129.748234 -232.313419) (xy 129.77876 -232.355435)
			(xy 129.802338 -232.401709) (xy 129.818386 -232.451102) (xy 129.826511 -232.502397) (xy 129.82702 -232.528364)
			(xy 129.826511 -232.554331) (xy 130.106421 -232.554331) (xy 130.106421 -232.502397) (xy 130.114546 -232.451102)
			(xy 130.130594 -232.401709) (xy 130.154172 -232.355435) (xy 130.184698 -232.313419) (xy 130.221421 -232.276696)
			(xy 130.263437 -232.24617) (xy 130.309711 -232.222592) (xy 130.359104 -232.206544) (xy 130.410399 -232.198419)
			(xy 130.462333 -232.198419) (xy 130.513628 -232.206544) (xy 130.563021 -232.222592) (xy 130.609295 -232.24617)
			(xy 130.651311 -232.276696) (xy 130.688034 -232.313419) (xy 130.71856 -232.355435) (xy 130.742138 -232.401709)
			(xy 130.758186 -232.451102) (xy 130.766311 -232.502397) (xy 130.76682 -232.528364) (xy 130.766311 -232.554331)
			(xy 131.046221 -232.554331) (xy 131.046221 -232.502397) (xy 131.054346 -232.451102) (xy 131.070394 -232.401709)
			(xy 131.093972 -232.355435) (xy 131.124498 -232.313419) (xy 131.161221 -232.276696) (xy 131.203237 -232.24617)
			(xy 131.249511 -232.222592) (xy 131.298904 -232.206544) (xy 131.350199 -232.198419) (xy 131.402133 -232.198419)
			(xy 131.453428 -232.206544) (xy 131.502821 -232.222592) (xy 131.549095 -232.24617) (xy 131.591111 -232.276696)
			(xy 131.627834 -232.313419) (xy 131.65836 -232.355435) (xy 131.681938 -232.401709) (xy 131.697986 -232.451102)
			(xy 131.706111 -232.502397) (xy 131.70662 -232.528364) (xy 131.706111 -232.554331) (xy 131.697986 -232.605626)
			(xy 131.681938 -232.655019) (xy 131.65836 -232.701293) (xy 131.627834 -232.743309) (xy 131.591111 -232.780032)
			(xy 131.549095 -232.810558) (xy 131.502821 -232.834136) (xy 131.453428 -232.850184) (xy 131.402133 -232.858309)
			(xy 131.350199 -232.858309) (xy 131.298904 -232.850184) (xy 131.249511 -232.834136) (xy 131.203237 -232.810558)
			(xy 131.161221 -232.780032) (xy 131.124498 -232.743309) (xy 131.093972 -232.701293) (xy 131.070394 -232.655019)
			(xy 131.054346 -232.605626) (xy 131.046221 -232.554331) (xy 130.766311 -232.554331) (xy 130.758186 -232.605626)
			(xy 130.742138 -232.655019) (xy 130.71856 -232.701293) (xy 130.688034 -232.743309) (xy 130.651311 -232.780032)
			(xy 130.609295 -232.810558) (xy 130.563021 -232.834136) (xy 130.513628 -232.850184) (xy 130.462333 -232.858309)
			(xy 130.410399 -232.858309) (xy 130.359104 -232.850184) (xy 130.309711 -232.834136) (xy 130.263437 -232.810558)
			(xy 130.221421 -232.780032) (xy 130.184698 -232.743309) (xy 130.154172 -232.701293) (xy 130.130594 -232.655019)
			(xy 130.114546 -232.605626) (xy 130.106421 -232.554331) (xy 129.826511 -232.554331) (xy 129.818386 -232.605626)
			(xy 129.802338 -232.655019) (xy 129.77876 -232.701293) (xy 129.748234 -232.743309) (xy 129.711511 -232.780032)
			(xy 129.669495 -232.810558) (xy 129.623221 -232.834136) (xy 129.573828 -232.850184) (xy 129.522533 -232.858309)
			(xy 129.470599 -232.858309) (xy 129.419304 -232.850184) (xy 129.369911 -232.834136) (xy 129.323637 -232.810558)
			(xy 129.281621 -232.780032) (xy 129.244898 -232.743309) (xy 129.214372 -232.701293) (xy 129.190794 -232.655019)
			(xy 129.174746 -232.605626) (xy 129.166621 -232.554331) (xy 128.886711 -232.554331) (xy 128.878586 -232.605626)
			(xy 128.862538 -232.655019) (xy 128.83896 -232.701293) (xy 128.808434 -232.743309) (xy 128.771711 -232.780032)
			(xy 128.729695 -232.810558) (xy 128.683421 -232.834136) (xy 128.634028 -232.850184) (xy 128.582733 -232.858309)
			(xy 128.530799 -232.858309) (xy 128.479504 -232.850184) (xy 128.430111 -232.834136) (xy 128.383837 -232.810558)
			(xy 128.341821 -232.780032) (xy 128.305098 -232.743309) (xy 128.274572 -232.701293) (xy 128.250994 -232.655019)
			(xy 128.234946 -232.605626) (xy 128.226821 -232.554331) (xy 127.946911 -232.554331) (xy 127.938786 -232.605626)
			(xy 127.922738 -232.655019) (xy 127.89916 -232.701293) (xy 127.868634 -232.743309) (xy 127.831911 -232.780032)
			(xy 127.789895 -232.810558) (xy 127.743621 -232.834136) (xy 127.694228 -232.850184) (xy 127.642933 -232.858309)
			(xy 127.590999 -232.858309) (xy 127.539704 -232.850184) (xy 127.490311 -232.834136) (xy 127.444037 -232.810558)
			(xy 127.402021 -232.780032) (xy 127.365298 -232.743309) (xy 127.334772 -232.701293) (xy 127.311194 -232.655019)
			(xy 127.295146 -232.605626) (xy 127.287021 -232.554331) (xy 127.006857 -232.554331) (xy 126.998732 -232.605626)
			(xy 126.982684 -232.655019) (xy 126.959106 -232.701293) (xy 126.92858 -232.743309) (xy 126.891857 -232.780032)
			(xy 126.849841 -232.810558) (xy 126.803567 -232.834136) (xy 126.754174 -232.850184) (xy 126.702879 -232.858309)
			(xy 126.650945 -232.858309) (xy 126.59965 -232.850184) (xy 126.550257 -232.834136) (xy 126.503983 -232.810558)
			(xy 126.461967 -232.780032) (xy 126.425244 -232.743309) (xy 126.394718 -232.701293) (xy 126.37114 -232.655019)
			(xy 126.355092 -232.605626) (xy 126.346967 -232.554331) (xy 126.067311 -232.554331) (xy 126.059186 -232.605626)
			(xy 126.043138 -232.655019) (xy 126.01956 -232.701293) (xy 125.989034 -232.743309) (xy 125.952311 -232.780032)
			(xy 125.910295 -232.810558) (xy 125.864021 -232.834136) (xy 125.814628 -232.850184) (xy 125.763333 -232.858309)
			(xy 125.711399 -232.858309) (xy 125.660104 -232.850184) (xy 125.610711 -232.834136) (xy 125.564437 -232.810558)
			(xy 125.522421 -232.780032) (xy 125.485698 -232.743309) (xy 125.455172 -232.701293) (xy 125.431594 -232.655019)
			(xy 125.415546 -232.605626) (xy 125.407421 -232.554331) (xy 125.127511 -232.554331) (xy 125.119386 -232.605626)
			(xy 125.103338 -232.655019) (xy 125.07976 -232.701293) (xy 125.049234 -232.743309) (xy 125.012511 -232.780032)
			(xy 124.970495 -232.810558) (xy 124.924221 -232.834136) (xy 124.874828 -232.850184) (xy 124.823533 -232.858309)
			(xy 124.771599 -232.858309) (xy 124.720304 -232.850184) (xy 124.670911 -232.834136) (xy 124.624637 -232.810558)
			(xy 124.582621 -232.780032) (xy 124.545898 -232.743309) (xy 124.515372 -232.701293) (xy 124.491794 -232.655019)
			(xy 124.475746 -232.605626) (xy 124.467621 -232.554331) (xy 124.187711 -232.554331) (xy 124.179586 -232.605626)
			(xy 124.163538 -232.655019) (xy 124.13996 -232.701293) (xy 124.109434 -232.743309) (xy 124.072711 -232.780032)
			(xy 124.030695 -232.810558) (xy 123.984421 -232.834136) (xy 123.935028 -232.850184) (xy 123.883733 -232.858309)
			(xy 123.831799 -232.858309) (xy 123.780504 -232.850184) (xy 123.731111 -232.834136) (xy 123.684837 -232.810558)
			(xy 123.642821 -232.780032) (xy 123.606098 -232.743309) (xy 123.575572 -232.701293) (xy 123.551994 -232.655019)
			(xy 123.535946 -232.605626) (xy 123.527821 -232.554331) (xy 123.247911 -232.554331) (xy 123.239786 -232.605626)
			(xy 123.223738 -232.655019) (xy 123.20016 -232.701293) (xy 123.169634 -232.743309) (xy 123.132911 -232.780032)
			(xy 123.090895 -232.810558) (xy 123.044621 -232.834136) (xy 122.995228 -232.850184) (xy 122.943933 -232.858309)
			(xy 122.891999 -232.858309) (xy 122.840704 -232.850184) (xy 122.791311 -232.834136) (xy 122.745037 -232.810558)
			(xy 122.703021 -232.780032) (xy 122.666298 -232.743309) (xy 122.635772 -232.701293) (xy 122.612194 -232.655019)
			(xy 122.596146 -232.605626) (xy 122.588021 -232.554331) (xy 122.308111 -232.554331) (xy 122.299986 -232.605626)
			(xy 122.283938 -232.655019) (xy 122.26036 -232.701293) (xy 122.229834 -232.743309) (xy 122.193111 -232.780032)
			(xy 122.151095 -232.810558) (xy 122.104821 -232.834136) (xy 122.055428 -232.850184) (xy 122.004133 -232.858309)
			(xy 121.952199 -232.858309) (xy 121.900904 -232.850184) (xy 121.851511 -232.834136) (xy 121.805237 -232.810558)
			(xy 121.763221 -232.780032) (xy 121.726498 -232.743309) (xy 121.695972 -232.701293) (xy 121.672394 -232.655019)
			(xy 121.656346 -232.605626) (xy 121.648221 -232.554331) (xy 121.368311 -232.554331) (xy 121.360186 -232.605626)
			(xy 121.344138 -232.655019) (xy 121.32056 -232.701293) (xy 121.290034 -232.743309) (xy 121.253311 -232.780032)
			(xy 121.211295 -232.810558) (xy 121.165021 -232.834136) (xy 121.115628 -232.850184) (xy 121.064333 -232.858309)
			(xy 121.012399 -232.858309) (xy 120.961104 -232.850184) (xy 120.911711 -232.834136) (xy 120.865437 -232.810558)
			(xy 120.823421 -232.780032) (xy 120.786698 -232.743309) (xy 120.756172 -232.701293) (xy 120.732594 -232.655019)
			(xy 120.716546 -232.605626) (xy 120.708421 -232.554331) (xy 120.428257 -232.554331) (xy 120.420132 -232.605626)
			(xy 120.404084 -232.655019) (xy 120.380506 -232.701293) (xy 120.34998 -232.743309) (xy 120.313257 -232.780032)
			(xy 120.271241 -232.810558) (xy 120.224967 -232.834136) (xy 120.175574 -232.850184) (xy 120.124279 -232.858309)
			(xy 120.072345 -232.858309) (xy 120.02105 -232.850184) (xy 119.971657 -232.834136) (xy 119.925383 -232.810558)
			(xy 119.883367 -232.780032) (xy 119.846644 -232.743309) (xy 119.816118 -232.701293) (xy 119.79254 -232.655019)
			(xy 119.776492 -232.605626) (xy 119.768367 -232.554331) (xy 119.488711 -232.554331) (xy 119.480586 -232.605626)
			(xy 119.464538 -232.655019) (xy 119.44096 -232.701293) (xy 119.410434 -232.743309) (xy 119.373711 -232.780032)
			(xy 119.331695 -232.810558) (xy 119.285421 -232.834136) (xy 119.236028 -232.850184) (xy 119.184733 -232.858309)
			(xy 119.132799 -232.858309) (xy 119.081504 -232.850184) (xy 119.032111 -232.834136) (xy 118.985837 -232.810558)
			(xy 118.943821 -232.780032) (xy 118.907098 -232.743309) (xy 118.876572 -232.701293) (xy 118.852994 -232.655019)
			(xy 118.836946 -232.605626) (xy 118.828821 -232.554331) (xy 118.548911 -232.554331) (xy 118.540786 -232.605626)
			(xy 118.524738 -232.655019) (xy 118.50116 -232.701293) (xy 118.470634 -232.743309) (xy 118.433911 -232.780032)
			(xy 118.391895 -232.810558) (xy 118.345621 -232.834136) (xy 118.296228 -232.850184) (xy 118.244933 -232.858309)
			(xy 118.192999 -232.858309) (xy 118.141704 -232.850184) (xy 118.092311 -232.834136) (xy 118.046037 -232.810558)
			(xy 118.004021 -232.780032) (xy 117.967298 -232.743309) (xy 117.936772 -232.701293) (xy 117.913194 -232.655019)
			(xy 117.897146 -232.605626) (xy 117.889021 -232.554331) (xy 117.609111 -232.554331) (xy 117.600986 -232.605626)
			(xy 117.584938 -232.655019) (xy 117.56136 -232.701293) (xy 117.530834 -232.743309) (xy 117.494111 -232.780032)
			(xy 117.452095 -232.810558) (xy 117.405821 -232.834136) (xy 117.356428 -232.850184) (xy 117.305133 -232.858309)
			(xy 117.253199 -232.858309) (xy 117.201904 -232.850184) (xy 117.152511 -232.834136) (xy 117.106237 -232.810558)
			(xy 117.064221 -232.780032) (xy 117.027498 -232.743309) (xy 116.996972 -232.701293) (xy 116.973394 -232.655019)
			(xy 116.957346 -232.605626) (xy 116.949221 -232.554331) (xy 116.669311 -232.554331) (xy 116.661186 -232.605626)
			(xy 116.645138 -232.655019) (xy 116.62156 -232.701293) (xy 116.591034 -232.743309) (xy 116.554311 -232.780032)
			(xy 116.512295 -232.810558) (xy 116.466021 -232.834136) (xy 116.416628 -232.850184) (xy 116.365333 -232.858309)
			(xy 116.313399 -232.858309) (xy 116.262104 -232.850184) (xy 116.212711 -232.834136) (xy 116.166437 -232.810558)
			(xy 116.124421 -232.780032) (xy 116.087698 -232.743309) (xy 116.057172 -232.701293) (xy 116.033594 -232.655019)
			(xy 116.017546 -232.605626) (xy 116.009421 -232.554331) (xy 115.729511 -232.554331) (xy 115.721386 -232.605626)
			(xy 115.705338 -232.655019) (xy 115.68176 -232.701293) (xy 115.651234 -232.743309) (xy 115.614511 -232.780032)
			(xy 115.572495 -232.810558) (xy 115.526221 -232.834136) (xy 115.476828 -232.850184) (xy 115.425533 -232.858309)
			(xy 115.373599 -232.858309) (xy 115.322304 -232.850184) (xy 115.272911 -232.834136) (xy 115.226637 -232.810558)
			(xy 115.184621 -232.780032) (xy 115.147898 -232.743309) (xy 115.117372 -232.701293) (xy 115.093794 -232.655019)
			(xy 115.077746 -232.605626) (xy 115.069621 -232.554331) (xy 114.789711 -232.554331) (xy 114.781586 -232.605626)
			(xy 114.765538 -232.655019) (xy 114.74196 -232.701293) (xy 114.711434 -232.743309) (xy 114.674711 -232.780032)
			(xy 114.632695 -232.810558) (xy 114.586421 -232.834136) (xy 114.537028 -232.850184) (xy 114.485733 -232.858309)
			(xy 114.433799 -232.858309) (xy 114.382504 -232.850184) (xy 114.333111 -232.834136) (xy 114.286837 -232.810558)
			(xy 114.244821 -232.780032) (xy 114.208098 -232.743309) (xy 114.177572 -232.701293) (xy 114.153994 -232.655019)
			(xy 114.137946 -232.605626) (xy 114.129821 -232.554331) (xy 113.849911 -232.554331) (xy 113.841786 -232.605626)
			(xy 113.825738 -232.655019) (xy 113.80216 -232.701293) (xy 113.771634 -232.743309) (xy 113.734911 -232.780032)
			(xy 113.692895 -232.810558) (xy 113.646621 -232.834136) (xy 113.597228 -232.850184) (xy 113.545933 -232.858309)
			(xy 113.493999 -232.858309) (xy 113.442704 -232.850184) (xy 113.393311 -232.834136) (xy 113.347037 -232.810558)
			(xy 113.305021 -232.780032) (xy 113.268298 -232.743309) (xy 113.237772 -232.701293) (xy 113.214194 -232.655019)
			(xy 113.198146 -232.605626) (xy 113.190021 -232.554331) (xy 112.910111 -232.554331) (xy 112.901986 -232.605626)
			(xy 112.885938 -232.655019) (xy 112.86236 -232.701293) (xy 112.831834 -232.743309) (xy 112.795111 -232.780032)
			(xy 112.753095 -232.810558) (xy 112.706821 -232.834136) (xy 112.657428 -232.850184) (xy 112.606133 -232.858309)
			(xy 112.554199 -232.858309) (xy 112.502904 -232.850184) (xy 112.453511 -232.834136) (xy 112.407237 -232.810558)
			(xy 112.365221 -232.780032) (xy 112.328498 -232.743309) (xy 112.297972 -232.701293) (xy 112.274394 -232.655019)
			(xy 112.258346 -232.605626) (xy 112.250221 -232.554331) (xy 111.970311 -232.554331) (xy 111.962186 -232.605626)
			(xy 111.946138 -232.655019) (xy 111.92256 -232.701293) (xy 111.892034 -232.743309) (xy 111.855311 -232.780032)
			(xy 111.813295 -232.810558) (xy 111.767021 -232.834136) (xy 111.717628 -232.850184) (xy 111.666333 -232.858309)
			(xy 111.614399 -232.858309) (xy 111.563104 -232.850184) (xy 111.513711 -232.834136) (xy 111.467437 -232.810558)
			(xy 111.425421 -232.780032) (xy 111.388698 -232.743309) (xy 111.358172 -232.701293) (xy 111.334594 -232.655019)
			(xy 111.318546 -232.605626) (xy 111.310421 -232.554331) (xy 111.030511 -232.554331) (xy 111.022386 -232.605626)
			(xy 111.006338 -232.655019) (xy 110.98276 -232.701293) (xy 110.952234 -232.743309) (xy 110.915511 -232.780032)
			(xy 110.873495 -232.810558) (xy 110.827221 -232.834136) (xy 110.777828 -232.850184) (xy 110.726533 -232.858309)
			(xy 110.674599 -232.858309) (xy 110.623304 -232.850184) (xy 110.573911 -232.834136) (xy 110.527637 -232.810558)
			(xy 110.485621 -232.780032) (xy 110.448898 -232.743309) (xy 110.418372 -232.701293) (xy 110.394794 -232.655019)
			(xy 110.378746 -232.605626) (xy 110.370621 -232.554331) (xy 110.090711 -232.554331) (xy 110.082586 -232.605626)
			(xy 110.066538 -232.655019) (xy 110.04296 -232.701293) (xy 110.012434 -232.743309) (xy 109.975711 -232.780032)
			(xy 109.933695 -232.810558) (xy 109.887421 -232.834136) (xy 109.838028 -232.850184) (xy 109.786733 -232.858309)
			(xy 109.734799 -232.858309) (xy 109.683504 -232.850184) (xy 109.634111 -232.834136) (xy 109.587837 -232.810558)
			(xy 109.545821 -232.780032) (xy 109.509098 -232.743309) (xy 109.478572 -232.701293) (xy 109.454994 -232.655019)
			(xy 109.438946 -232.605626) (xy 109.430821 -232.554331) (xy 109.150911 -232.554331) (xy 109.142786 -232.605626)
			(xy 109.126738 -232.655019) (xy 109.10316 -232.701293) (xy 109.072634 -232.743309) (xy 109.035911 -232.780032)
			(xy 108.993895 -232.810558) (xy 108.947621 -232.834136) (xy 108.898228 -232.850184) (xy 108.846933 -232.858309)
			(xy 108.794999 -232.858309) (xy 108.743704 -232.850184) (xy 108.694311 -232.834136) (xy 108.648037 -232.810558)
			(xy 108.606021 -232.780032) (xy 108.569298 -232.743309) (xy 108.538772 -232.701293) (xy 108.515194 -232.655019)
			(xy 108.499146 -232.605626) (xy 108.491021 -232.554331) (xy 108.211111 -232.554331) (xy 108.202986 -232.605626)
			(xy 108.186938 -232.655019) (xy 108.16336 -232.701293) (xy 108.132834 -232.743309) (xy 108.096111 -232.780032)
			(xy 108.054095 -232.810558) (xy 108.007821 -232.834136) (xy 107.958428 -232.850184) (xy 107.907133 -232.858309)
			(xy 107.855199 -232.858309) (xy 107.803904 -232.850184) (xy 107.754511 -232.834136) (xy 107.708237 -232.810558)
			(xy 107.666221 -232.780032) (xy 107.629498 -232.743309) (xy 107.598972 -232.701293) (xy 107.575394 -232.655019)
			(xy 107.559346 -232.605626) (xy 107.551221 -232.554331) (xy 107.271311 -232.554331) (xy 107.263186 -232.605626)
			(xy 107.247138 -232.655019) (xy 107.22356 -232.701293) (xy 107.193034 -232.743309) (xy 107.156311 -232.780032)
			(xy 107.114295 -232.810558) (xy 107.068021 -232.834136) (xy 107.018628 -232.850184) (xy 106.967333 -232.858309)
			(xy 106.915399 -232.858309) (xy 106.864104 -232.850184) (xy 106.814711 -232.834136) (xy 106.768437 -232.810558)
			(xy 106.726421 -232.780032) (xy 106.689698 -232.743309) (xy 106.659172 -232.701293) (xy 106.635594 -232.655019)
			(xy 106.619546 -232.605626) (xy 106.611421 -232.554331) (xy 106.331511 -232.554331) (xy 106.323386 -232.605626)
			(xy 106.307338 -232.655019) (xy 106.28376 -232.701293) (xy 106.253234 -232.743309) (xy 106.216511 -232.780032)
			(xy 106.174495 -232.810558) (xy 106.128221 -232.834136) (xy 106.078828 -232.850184) (xy 106.027533 -232.858309)
			(xy 105.975599 -232.858309) (xy 105.924304 -232.850184) (xy 105.874911 -232.834136) (xy 105.828637 -232.810558)
			(xy 105.786621 -232.780032) (xy 105.749898 -232.743309) (xy 105.719372 -232.701293) (xy 105.695794 -232.655019)
			(xy 105.679746 -232.605626) (xy 105.671621 -232.554331) (xy 105.414572 -232.554331) (xy 105.414572 -232.91038)
			(xy 105.414969 -232.924031) (xy 105.422177 -232.950362) (xy 105.436109 -232.97384) (xy 105.455767 -232.992783)
			(xy 105.479745 -233.005835) (xy 105.506325 -233.012062) (xy 105.519982 -233.01198) (xy 105.531666 -233.011726)
			(xy 105.557635 -233.012246) (xy 105.608936 -233.020367) (xy 105.658334 -233.036412) (xy 105.704613 -233.059989)
			(xy 105.746635 -233.090515) (xy 105.783363 -233.12724) (xy 105.813893 -233.169258) (xy 105.837475 -233.215535)
			(xy 105.853526 -233.264931) (xy 105.861651 -233.316231) (xy 105.861651 -233.368147) (xy 106.141267 -233.368147)
			(xy 106.141267 -233.316213) (xy 106.149392 -233.264918) (xy 106.16544 -233.215525) (xy 106.189018 -233.169251)
			(xy 106.219544 -233.127235) (xy 106.256267 -233.090512) (xy 106.298283 -233.059986) (xy 106.344557 -233.036408)
			(xy 106.39395 -233.02036) (xy 106.445245 -233.012235) (xy 106.497179 -233.012235) (xy 106.548474 -233.02036)
			(xy 106.597867 -233.036408) (xy 106.644141 -233.059986) (xy 106.686157 -233.090512) (xy 106.72288 -233.127235)
			(xy 106.753406 -233.169251) (xy 106.776984 -233.215525) (xy 106.793032 -233.264918) (xy 106.801157 -233.316213)
			(xy 106.801666 -233.34218) (xy 106.801157 -233.368147) (xy 107.081067 -233.368147) (xy 107.081067 -233.316213)
			(xy 107.089192 -233.264918) (xy 107.10524 -233.215525) (xy 107.128818 -233.169251) (xy 107.159344 -233.127235)
			(xy 107.196067 -233.090512) (xy 107.238083 -233.059986) (xy 107.284357 -233.036408) (xy 107.33375 -233.02036)
			(xy 107.385045 -233.012235) (xy 107.436979 -233.012235) (xy 107.488274 -233.02036) (xy 107.537667 -233.036408)
			(xy 107.583941 -233.059986) (xy 107.625957 -233.090512) (xy 107.66268 -233.127235) (xy 107.693206 -233.169251)
			(xy 107.716784 -233.215525) (xy 107.732832 -233.264918) (xy 107.740957 -233.316213) (xy 107.741466 -233.34218)
			(xy 107.740957 -233.368147) (xy 108.020867 -233.368147) (xy 108.020867 -233.316213) (xy 108.028992 -233.264918)
			(xy 108.04504 -233.215525) (xy 108.068618 -233.169251) (xy 108.099144 -233.127235) (xy 108.135867 -233.090512)
			(xy 108.177883 -233.059986) (xy 108.224157 -233.036408) (xy 108.27355 -233.02036) (xy 108.324845 -233.012235)
			(xy 108.376779 -233.012235) (xy 108.428074 -233.02036) (xy 108.477467 -233.036408) (xy 108.523741 -233.059986)
			(xy 108.565757 -233.090512) (xy 108.60248 -233.127235) (xy 108.633006 -233.169251) (xy 108.656584 -233.215525)
			(xy 108.672632 -233.264918) (xy 108.680757 -233.316213) (xy 108.681266 -233.34218) (xy 108.680757 -233.368147)
			(xy 108.960667 -233.368147) (xy 108.960667 -233.316213) (xy 108.968792 -233.264918) (xy 108.98484 -233.215525)
			(xy 109.008418 -233.169251) (xy 109.038944 -233.127235) (xy 109.075667 -233.090512) (xy 109.117683 -233.059986)
			(xy 109.163957 -233.036408) (xy 109.21335 -233.02036) (xy 109.264645 -233.012235) (xy 109.316579 -233.012235)
			(xy 109.367874 -233.02036) (xy 109.417267 -233.036408) (xy 109.463541 -233.059986) (xy 109.505557 -233.090512)
			(xy 109.54228 -233.127235) (xy 109.572806 -233.169251) (xy 109.596384 -233.215525) (xy 109.612432 -233.264918)
			(xy 109.620557 -233.316213) (xy 109.621066 -233.34218) (xy 109.620557 -233.368147) (xy 109.900721 -233.368147)
			(xy 109.900721 -233.316213) (xy 109.908846 -233.264918) (xy 109.924894 -233.215525) (xy 109.948472 -233.169251)
			(xy 109.978998 -233.127235) (xy 110.015721 -233.090512) (xy 110.057737 -233.059986) (xy 110.104011 -233.036408)
			(xy 110.153404 -233.02036) (xy 110.204699 -233.012235) (xy 110.256633 -233.012235) (xy 110.307928 -233.02036)
			(xy 110.357321 -233.036408) (xy 110.403595 -233.059986) (xy 110.445611 -233.090512) (xy 110.482334 -233.127235)
			(xy 110.51286 -233.169251) (xy 110.536438 -233.215525) (xy 110.552486 -233.264918) (xy 110.560611 -233.316213)
			(xy 110.56112 -233.34218) (xy 110.560611 -233.368147) (xy 110.840267 -233.368147) (xy 110.840267 -233.316213)
			(xy 110.848392 -233.264918) (xy 110.86444 -233.215525) (xy 110.888018 -233.169251) (xy 110.918544 -233.127235)
			(xy 110.955267 -233.090512) (xy 110.997283 -233.059986) (xy 111.043557 -233.036408) (xy 111.09295 -233.02036)
			(xy 111.144245 -233.012235) (xy 111.196179 -233.012235) (xy 111.247474 -233.02036) (xy 111.296867 -233.036408)
			(xy 111.343141 -233.059986) (xy 111.385157 -233.090512) (xy 111.42188 -233.127235) (xy 111.452406 -233.169251)
			(xy 111.475984 -233.215525) (xy 111.492032 -233.264918) (xy 111.500157 -233.316213) (xy 111.500666 -233.34218)
			(xy 111.500157 -233.368147) (xy 111.780067 -233.368147) (xy 111.780067 -233.316213) (xy 111.788192 -233.264918)
			(xy 111.80424 -233.215525) (xy 111.827818 -233.169251) (xy 111.858344 -233.127235) (xy 111.895067 -233.090512)
			(xy 111.937083 -233.059986) (xy 111.983357 -233.036408) (xy 112.03275 -233.02036) (xy 112.084045 -233.012235)
			(xy 112.135979 -233.012235) (xy 112.187274 -233.02036) (xy 112.236667 -233.036408) (xy 112.282941 -233.059986)
			(xy 112.324957 -233.090512) (xy 112.36168 -233.127235) (xy 112.392206 -233.169251) (xy 112.415784 -233.215525)
			(xy 112.431832 -233.264918) (xy 112.439957 -233.316213) (xy 112.440466 -233.34218) (xy 112.439957 -233.368147)
			(xy 112.719867 -233.368147) (xy 112.719867 -233.316213) (xy 112.727992 -233.264918) (xy 112.74404 -233.215525)
			(xy 112.767618 -233.169251) (xy 112.798144 -233.127235) (xy 112.834867 -233.090512) (xy 112.876883 -233.059986)
			(xy 112.923157 -233.036408) (xy 112.97255 -233.02036) (xy 113.023845 -233.012235) (xy 113.075779 -233.012235)
			(xy 113.127074 -233.02036) (xy 113.176467 -233.036408) (xy 113.222741 -233.059986) (xy 113.264757 -233.090512)
			(xy 113.30148 -233.127235) (xy 113.332006 -233.169251) (xy 113.355584 -233.215525) (xy 113.371632 -233.264918)
			(xy 113.379757 -233.316213) (xy 113.380266 -233.34218) (xy 113.379757 -233.368147) (xy 113.659921 -233.368147)
			(xy 113.659921 -233.316213) (xy 113.668046 -233.264918) (xy 113.684094 -233.215525) (xy 113.707672 -233.169251)
			(xy 113.738198 -233.127235) (xy 113.774921 -233.090512) (xy 113.816937 -233.059986) (xy 113.863211 -233.036408)
			(xy 113.912604 -233.02036) (xy 113.963899 -233.012235) (xy 114.015833 -233.012235) (xy 114.067128 -233.02036)
			(xy 114.116521 -233.036408) (xy 114.162795 -233.059986) (xy 114.204811 -233.090512) (xy 114.241534 -233.127235)
			(xy 114.27206 -233.169251) (xy 114.295638 -233.215525) (xy 114.311686 -233.264918) (xy 114.319811 -233.316213)
			(xy 114.32032 -233.34218) (xy 114.319811 -233.368147) (xy 114.599467 -233.368147) (xy 114.599467 -233.316213)
			(xy 114.607592 -233.264918) (xy 114.62364 -233.215525) (xy 114.647218 -233.169251) (xy 114.677744 -233.127235)
			(xy 114.714467 -233.090512) (xy 114.756483 -233.059986) (xy 114.802757 -233.036408) (xy 114.85215 -233.02036)
			(xy 114.903445 -233.012235) (xy 114.955379 -233.012235) (xy 115.006674 -233.02036) (xy 115.056067 -233.036408)
			(xy 115.102341 -233.059986) (xy 115.144357 -233.090512) (xy 115.18108 -233.127235) (xy 115.211606 -233.169251)
			(xy 115.235184 -233.215525) (xy 115.251232 -233.264918) (xy 115.259357 -233.316213) (xy 115.259866 -233.34218)
			(xy 115.259357 -233.368147) (xy 115.539267 -233.368147) (xy 115.539267 -233.316213) (xy 115.547392 -233.264918)
			(xy 115.56344 -233.215525) (xy 115.587018 -233.169251) (xy 115.617544 -233.127235) (xy 115.654267 -233.090512)
			(xy 115.696283 -233.059986) (xy 115.742557 -233.036408) (xy 115.79195 -233.02036) (xy 115.843245 -233.012235)
			(xy 115.895179 -233.012235) (xy 115.946474 -233.02036) (xy 115.995867 -233.036408) (xy 116.042141 -233.059986)
			(xy 116.084157 -233.090512) (xy 116.12088 -233.127235) (xy 116.151406 -233.169251) (xy 116.174984 -233.215525)
			(xy 116.191032 -233.264918) (xy 116.199157 -233.316213) (xy 116.199666 -233.34218) (xy 116.199157 -233.368147)
			(xy 116.479067 -233.368147) (xy 116.479067 -233.316213) (xy 116.487192 -233.264918) (xy 116.50324 -233.215525)
			(xy 116.526818 -233.169251) (xy 116.557344 -233.127235) (xy 116.594067 -233.090512) (xy 116.636083 -233.059986)
			(xy 116.682357 -233.036408) (xy 116.73175 -233.02036) (xy 116.783045 -233.012235) (xy 116.834979 -233.012235)
			(xy 116.886274 -233.02036) (xy 116.935667 -233.036408) (xy 116.981941 -233.059986) (xy 117.023957 -233.090512)
			(xy 117.06068 -233.127235) (xy 117.091206 -233.169251) (xy 117.114784 -233.215525) (xy 117.130832 -233.264918)
			(xy 117.138957 -233.316213) (xy 117.139466 -233.34218) (xy 117.138957 -233.368147) (xy 117.418867 -233.368147)
			(xy 117.418867 -233.316213) (xy 117.426992 -233.264918) (xy 117.44304 -233.215525) (xy 117.466618 -233.169251)
			(xy 117.497144 -233.127235) (xy 117.533867 -233.090512) (xy 117.575883 -233.059986) (xy 117.622157 -233.036408)
			(xy 117.67155 -233.02036) (xy 117.722845 -233.012235) (xy 117.774779 -233.012235) (xy 117.826074 -233.02036)
			(xy 117.875467 -233.036408) (xy 117.921741 -233.059986) (xy 117.963757 -233.090512) (xy 118.00048 -233.127235)
			(xy 118.031006 -233.169251) (xy 118.054584 -233.215525) (xy 118.070632 -233.264918) (xy 118.078757 -233.316213)
			(xy 118.079266 -233.34218) (xy 118.078757 -233.368147) (xy 118.358667 -233.368147) (xy 118.358667 -233.316213)
			(xy 118.366792 -233.264918) (xy 118.38284 -233.215525) (xy 118.406418 -233.169251) (xy 118.436944 -233.127235)
			(xy 118.473667 -233.090512) (xy 118.515683 -233.059986) (xy 118.561957 -233.036408) (xy 118.61135 -233.02036)
			(xy 118.662645 -233.012235) (xy 118.714579 -233.012235) (xy 118.765874 -233.02036) (xy 118.815267 -233.036408)
			(xy 118.861541 -233.059986) (xy 118.903557 -233.090512) (xy 118.94028 -233.127235) (xy 118.970806 -233.169251)
			(xy 118.994384 -233.215525) (xy 119.010432 -233.264918) (xy 119.018557 -233.316213) (xy 119.019066 -233.34218)
			(xy 119.018557 -233.368147) (xy 119.298467 -233.368147) (xy 119.298467 -233.316213) (xy 119.306592 -233.264918)
			(xy 119.32264 -233.215525) (xy 119.346218 -233.169251) (xy 119.376744 -233.127235) (xy 119.413467 -233.090512)
			(xy 119.455483 -233.059986) (xy 119.501757 -233.036408) (xy 119.55115 -233.02036) (xy 119.602445 -233.012235)
			(xy 119.654379 -233.012235) (xy 119.705674 -233.02036) (xy 119.755067 -233.036408) (xy 119.801341 -233.059986)
			(xy 119.843357 -233.090512) (xy 119.88008 -233.127235) (xy 119.910606 -233.169251) (xy 119.934184 -233.215525)
			(xy 119.950232 -233.264918) (xy 119.958357 -233.316213) (xy 119.958866 -233.34218) (xy 119.958357 -233.368147)
			(xy 120.238267 -233.368147) (xy 120.238267 -233.316213) (xy 120.246392 -233.264918) (xy 120.26244 -233.215525)
			(xy 120.286018 -233.169251) (xy 120.316544 -233.127235) (xy 120.353267 -233.090512) (xy 120.395283 -233.059986)
			(xy 120.441557 -233.036408) (xy 120.49095 -233.02036) (xy 120.542245 -233.012235) (xy 120.594179 -233.012235)
			(xy 120.645474 -233.02036) (xy 120.694867 -233.036408) (xy 120.741141 -233.059986) (xy 120.783157 -233.090512)
			(xy 120.81988 -233.127235) (xy 120.850406 -233.169251) (xy 120.873984 -233.215525) (xy 120.890032 -233.264918)
			(xy 120.898157 -233.316213) (xy 120.898666 -233.34218) (xy 120.898157 -233.368147) (xy 121.178321 -233.368147)
			(xy 121.178321 -233.316213) (xy 121.186446 -233.264918) (xy 121.202494 -233.215525) (xy 121.226072 -233.169251)
			(xy 121.256598 -233.127235) (xy 121.293321 -233.090512) (xy 121.335337 -233.059986) (xy 121.381611 -233.036408)
			(xy 121.431004 -233.02036) (xy 121.482299 -233.012235) (xy 121.534233 -233.012235) (xy 121.585528 -233.02036)
			(xy 121.634921 -233.036408) (xy 121.681195 -233.059986) (xy 121.723211 -233.090512) (xy 121.759934 -233.127235)
			(xy 121.79046 -233.169251) (xy 121.814038 -233.215525) (xy 121.830086 -233.264918) (xy 121.838211 -233.316213)
			(xy 121.83872 -233.34218) (xy 121.838211 -233.368147) (xy 122.117867 -233.368147) (xy 122.117867 -233.316213)
			(xy 122.125992 -233.264918) (xy 122.14204 -233.215525) (xy 122.165618 -233.169251) (xy 122.196144 -233.127235)
			(xy 122.232867 -233.090512) (xy 122.274883 -233.059986) (xy 122.321157 -233.036408) (xy 122.37055 -233.02036)
			(xy 122.421845 -233.012235) (xy 122.473779 -233.012235) (xy 122.525074 -233.02036) (xy 122.574467 -233.036408)
			(xy 122.620741 -233.059986) (xy 122.662757 -233.090512) (xy 122.69948 -233.127235) (xy 122.730006 -233.169251)
			(xy 122.753584 -233.215525) (xy 122.769632 -233.264918) (xy 122.777757 -233.316213) (xy 122.778266 -233.34218)
			(xy 122.777757 -233.368147) (xy 123.057667 -233.368147) (xy 123.057667 -233.316213) (xy 123.065792 -233.264918)
			(xy 123.08184 -233.215525) (xy 123.105418 -233.169251) (xy 123.135944 -233.127235) (xy 123.172667 -233.090512)
			(xy 123.214683 -233.059986) (xy 123.260957 -233.036408) (xy 123.31035 -233.02036) (xy 123.361645 -233.012235)
			(xy 123.413579 -233.012235) (xy 123.464874 -233.02036) (xy 123.514267 -233.036408) (xy 123.560541 -233.059986)
			(xy 123.602557 -233.090512) (xy 123.63928 -233.127235) (xy 123.669806 -233.169251) (xy 123.693384 -233.215525)
			(xy 123.709432 -233.264918) (xy 123.717557 -233.316213) (xy 123.718066 -233.34218) (xy 123.717557 -233.368147)
			(xy 123.997467 -233.368147) (xy 123.997467 -233.316213) (xy 124.005592 -233.264918) (xy 124.02164 -233.215525)
			(xy 124.045218 -233.169251) (xy 124.075744 -233.127235) (xy 124.112467 -233.090512) (xy 124.154483 -233.059986)
			(xy 124.200757 -233.036408) (xy 124.25015 -233.02036) (xy 124.301445 -233.012235) (xy 124.353379 -233.012235)
			(xy 124.404674 -233.02036) (xy 124.454067 -233.036408) (xy 124.500341 -233.059986) (xy 124.542357 -233.090512)
			(xy 124.57908 -233.127235) (xy 124.609606 -233.169251) (xy 124.633184 -233.215525) (xy 124.649232 -233.264918)
			(xy 124.657357 -233.316213) (xy 124.657866 -233.34218) (xy 124.657357 -233.368147) (xy 124.937267 -233.368147)
			(xy 124.937267 -233.316213) (xy 124.945392 -233.264918) (xy 124.96144 -233.215525) (xy 124.985018 -233.169251)
			(xy 125.015544 -233.127235) (xy 125.052267 -233.090512) (xy 125.094283 -233.059986) (xy 125.140557 -233.036408)
			(xy 125.18995 -233.02036) (xy 125.241245 -233.012235) (xy 125.293179 -233.012235) (xy 125.344474 -233.02036)
			(xy 125.393867 -233.036408) (xy 125.440141 -233.059986) (xy 125.482157 -233.090512) (xy 125.51888 -233.127235)
			(xy 125.549406 -233.169251) (xy 125.572984 -233.215525) (xy 125.589032 -233.264918) (xy 125.597157 -233.316213)
			(xy 125.597666 -233.34218) (xy 125.597157 -233.368147) (xy 125.877321 -233.368147) (xy 125.877321 -233.316213)
			(xy 125.885446 -233.264918) (xy 125.901494 -233.215525) (xy 125.925072 -233.169251) (xy 125.955598 -233.127235)
			(xy 125.992321 -233.090512) (xy 126.034337 -233.059986) (xy 126.080611 -233.036408) (xy 126.130004 -233.02036)
			(xy 126.181299 -233.012235) (xy 126.233233 -233.012235) (xy 126.284528 -233.02036) (xy 126.333921 -233.036408)
			(xy 126.380195 -233.059986) (xy 126.422211 -233.090512) (xy 126.458934 -233.127235) (xy 126.48946 -233.169251)
			(xy 126.513038 -233.215525) (xy 126.529086 -233.264918) (xy 126.537211 -233.316213) (xy 126.53772 -233.34218)
			(xy 126.537211 -233.368147) (xy 126.816867 -233.368147) (xy 126.816867 -233.316213) (xy 126.824992 -233.264918)
			(xy 126.84104 -233.215525) (xy 126.864618 -233.169251) (xy 126.895144 -233.127235) (xy 126.931867 -233.090512)
			(xy 126.973883 -233.059986) (xy 127.020157 -233.036408) (xy 127.06955 -233.02036) (xy 127.120845 -233.012235)
			(xy 127.172779 -233.012235) (xy 127.224074 -233.02036) (xy 127.273467 -233.036408) (xy 127.319741 -233.059986)
			(xy 127.361757 -233.090512) (xy 127.39848 -233.127235) (xy 127.429006 -233.169251) (xy 127.452584 -233.215525)
			(xy 127.468632 -233.264918) (xy 127.476757 -233.316213) (xy 127.477266 -233.34218) (xy 127.476757 -233.368147)
			(xy 127.756667 -233.368147) (xy 127.756667 -233.316213) (xy 127.764792 -233.264918) (xy 127.78084 -233.215525)
			(xy 127.804418 -233.169251) (xy 127.834944 -233.127235) (xy 127.871667 -233.090512) (xy 127.913683 -233.059986)
			(xy 127.959957 -233.036408) (xy 128.00935 -233.02036) (xy 128.060645 -233.012235) (xy 128.112579 -233.012235)
			(xy 128.163874 -233.02036) (xy 128.213267 -233.036408) (xy 128.259541 -233.059986) (xy 128.301557 -233.090512)
			(xy 128.33828 -233.127235) (xy 128.368806 -233.169251) (xy 128.392384 -233.215525) (xy 128.408432 -233.264918)
			(xy 128.416557 -233.316213) (xy 128.417066 -233.34218) (xy 128.416557 -233.368147) (xy 128.696467 -233.368147)
			(xy 128.696467 -233.316213) (xy 128.704592 -233.264918) (xy 128.72064 -233.215525) (xy 128.744218 -233.169251)
			(xy 128.774744 -233.127235) (xy 128.811467 -233.090512) (xy 128.853483 -233.059986) (xy 128.899757 -233.036408)
			(xy 128.94915 -233.02036) (xy 129.000445 -233.012235) (xy 129.052379 -233.012235) (xy 129.103674 -233.02036)
			(xy 129.153067 -233.036408) (xy 129.199341 -233.059986) (xy 129.241357 -233.090512) (xy 129.27808 -233.127235)
			(xy 129.308606 -233.169251) (xy 129.332184 -233.215525) (xy 129.348232 -233.264918) (xy 129.356357 -233.316213)
			(xy 129.356866 -233.34218) (xy 129.356357 -233.368147) (xy 129.636267 -233.368147) (xy 129.636267 -233.316213)
			(xy 129.644392 -233.264918) (xy 129.66044 -233.215525) (xy 129.684018 -233.169251) (xy 129.714544 -233.127235)
			(xy 129.751267 -233.090512) (xy 129.793283 -233.059986) (xy 129.839557 -233.036408) (xy 129.88895 -233.02036)
			(xy 129.940245 -233.012235) (xy 129.992179 -233.012235) (xy 130.043474 -233.02036) (xy 130.092867 -233.036408)
			(xy 130.139141 -233.059986) (xy 130.181157 -233.090512) (xy 130.21788 -233.127235) (xy 130.248406 -233.169251)
			(xy 130.271984 -233.215525) (xy 130.288032 -233.264918) (xy 130.296157 -233.316213) (xy 130.296666 -233.34218)
			(xy 130.296157 -233.368147) (xy 130.576067 -233.368147) (xy 130.576067 -233.316213) (xy 130.584192 -233.264918)
			(xy 130.60024 -233.215525) (xy 130.623818 -233.169251) (xy 130.654344 -233.127235) (xy 130.691067 -233.090512)
			(xy 130.733083 -233.059986) (xy 130.779357 -233.036408) (xy 130.82875 -233.02036) (xy 130.880045 -233.012235)
			(xy 130.931979 -233.012235) (xy 130.983274 -233.02036) (xy 131.032667 -233.036408) (xy 131.078941 -233.059986)
			(xy 131.120957 -233.090512) (xy 131.15768 -233.127235) (xy 131.188206 -233.169251) (xy 131.211784 -233.215525)
			(xy 131.227832 -233.264918) (xy 131.235957 -233.316213) (xy 131.236466 -233.34218) (xy 131.235957 -233.368147)
			(xy 131.515867 -233.368147) (xy 131.515867 -233.316213) (xy 131.523992 -233.264918) (xy 131.54004 -233.215525)
			(xy 131.563618 -233.169251) (xy 131.594144 -233.127235) (xy 131.630867 -233.090512) (xy 131.672883 -233.059986)
			(xy 131.719157 -233.036408) (xy 131.76855 -233.02036) (xy 131.819845 -233.012235) (xy 131.871779 -233.012235)
			(xy 131.923074 -233.02036) (xy 131.972467 -233.036408) (xy 132.018741 -233.059986) (xy 132.060757 -233.090512)
			(xy 132.09748 -233.127235) (xy 132.128006 -233.169251) (xy 132.151584 -233.215525) (xy 132.167632 -233.264918)
			(xy 132.175757 -233.316213) (xy 132.176266 -233.34218) (xy 132.175757 -233.368147) (xy 132.167632 -233.419442)
			(xy 132.151584 -233.468835) (xy 132.128006 -233.515109) (xy 132.09748 -233.557125) (xy 132.060757 -233.593848)
			(xy 132.018741 -233.624374) (xy 131.972467 -233.647952) (xy 131.923074 -233.664) (xy 131.871779 -233.672125)
			(xy 131.819845 -233.672125) (xy 131.76855 -233.664) (xy 131.719157 -233.647952) (xy 131.672883 -233.624374)
			(xy 131.630867 -233.593848) (xy 131.594144 -233.557125) (xy 131.563618 -233.515109) (xy 131.54004 -233.468835)
			(xy 131.523992 -233.419442) (xy 131.515867 -233.368147) (xy 131.235957 -233.368147) (xy 131.227832 -233.419442)
			(xy 131.211784 -233.468835) (xy 131.188206 -233.515109) (xy 131.15768 -233.557125) (xy 131.120957 -233.593848)
			(xy 131.078941 -233.624374) (xy 131.032667 -233.647952) (xy 130.983274 -233.664) (xy 130.931979 -233.672125)
			(xy 130.880045 -233.672125) (xy 130.82875 -233.664) (xy 130.779357 -233.647952) (xy 130.733083 -233.624374)
			(xy 130.691067 -233.593848) (xy 130.654344 -233.557125) (xy 130.623818 -233.515109) (xy 130.60024 -233.468835)
			(xy 130.584192 -233.419442) (xy 130.576067 -233.368147) (xy 130.296157 -233.368147) (xy 130.288032 -233.419442)
			(xy 130.271984 -233.468835) (xy 130.248406 -233.515109) (xy 130.21788 -233.557125) (xy 130.181157 -233.593848)
			(xy 130.139141 -233.624374) (xy 130.092867 -233.647952) (xy 130.043474 -233.664) (xy 129.992179 -233.672125)
			(xy 129.940245 -233.672125) (xy 129.88895 -233.664) (xy 129.839557 -233.647952) (xy 129.793283 -233.624374)
			(xy 129.751267 -233.593848) (xy 129.714544 -233.557125) (xy 129.684018 -233.515109) (xy 129.66044 -233.468835)
			(xy 129.644392 -233.419442) (xy 129.636267 -233.368147) (xy 129.356357 -233.368147) (xy 129.348232 -233.419442)
			(xy 129.332184 -233.468835) (xy 129.308606 -233.515109) (xy 129.27808 -233.557125) (xy 129.241357 -233.593848)
			(xy 129.199341 -233.624374) (xy 129.153067 -233.647952) (xy 129.103674 -233.664) (xy 129.052379 -233.672125)
			(xy 129.000445 -233.672125) (xy 128.94915 -233.664) (xy 128.899757 -233.647952) (xy 128.853483 -233.624374)
			(xy 128.811467 -233.593848) (xy 128.774744 -233.557125) (xy 128.744218 -233.515109) (xy 128.72064 -233.468835)
			(xy 128.704592 -233.419442) (xy 128.696467 -233.368147) (xy 128.416557 -233.368147) (xy 128.408432 -233.419442)
			(xy 128.392384 -233.468835) (xy 128.368806 -233.515109) (xy 128.33828 -233.557125) (xy 128.301557 -233.593848)
			(xy 128.259541 -233.624374) (xy 128.213267 -233.647952) (xy 128.163874 -233.664) (xy 128.112579 -233.672125)
			(xy 128.060645 -233.672125) (xy 128.00935 -233.664) (xy 127.959957 -233.647952) (xy 127.913683 -233.624374)
			(xy 127.871667 -233.593848) (xy 127.834944 -233.557125) (xy 127.804418 -233.515109) (xy 127.78084 -233.468835)
			(xy 127.764792 -233.419442) (xy 127.756667 -233.368147) (xy 127.476757 -233.368147) (xy 127.468632 -233.419442)
			(xy 127.452584 -233.468835) (xy 127.429006 -233.515109) (xy 127.39848 -233.557125) (xy 127.361757 -233.593848)
			(xy 127.319741 -233.624374) (xy 127.273467 -233.647952) (xy 127.224074 -233.664) (xy 127.172779 -233.672125)
			(xy 127.120845 -233.672125) (xy 127.06955 -233.664) (xy 127.020157 -233.647952) (xy 126.973883 -233.624374)
			(xy 126.931867 -233.593848) (xy 126.895144 -233.557125) (xy 126.864618 -233.515109) (xy 126.84104 -233.468835)
			(xy 126.824992 -233.419442) (xy 126.816867 -233.368147) (xy 126.537211 -233.368147) (xy 126.529086 -233.419442)
			(xy 126.513038 -233.468835) (xy 126.48946 -233.515109) (xy 126.458934 -233.557125) (xy 126.422211 -233.593848)
			(xy 126.380195 -233.624374) (xy 126.333921 -233.647952) (xy 126.284528 -233.664) (xy 126.233233 -233.672125)
			(xy 126.181299 -233.672125) (xy 126.130004 -233.664) (xy 126.080611 -233.647952) (xy 126.034337 -233.624374)
			(xy 125.992321 -233.593848) (xy 125.955598 -233.557125) (xy 125.925072 -233.515109) (xy 125.901494 -233.468835)
			(xy 125.885446 -233.419442) (xy 125.877321 -233.368147) (xy 125.597157 -233.368147) (xy 125.589032 -233.419442)
			(xy 125.572984 -233.468835) (xy 125.549406 -233.515109) (xy 125.51888 -233.557125) (xy 125.482157 -233.593848)
			(xy 125.440141 -233.624374) (xy 125.393867 -233.647952) (xy 125.344474 -233.664) (xy 125.293179 -233.672125)
			(xy 125.241245 -233.672125) (xy 125.18995 -233.664) (xy 125.140557 -233.647952) (xy 125.094283 -233.624374)
			(xy 125.052267 -233.593848) (xy 125.015544 -233.557125) (xy 124.985018 -233.515109) (xy 124.96144 -233.468835)
			(xy 124.945392 -233.419442) (xy 124.937267 -233.368147) (xy 124.657357 -233.368147) (xy 124.649232 -233.419442)
			(xy 124.633184 -233.468835) (xy 124.609606 -233.515109) (xy 124.57908 -233.557125) (xy 124.542357 -233.593848)
			(xy 124.500341 -233.624374) (xy 124.454067 -233.647952) (xy 124.404674 -233.664) (xy 124.353379 -233.672125)
			(xy 124.301445 -233.672125) (xy 124.25015 -233.664) (xy 124.200757 -233.647952) (xy 124.154483 -233.624374)
			(xy 124.112467 -233.593848) (xy 124.075744 -233.557125) (xy 124.045218 -233.515109) (xy 124.02164 -233.468835)
			(xy 124.005592 -233.419442) (xy 123.997467 -233.368147) (xy 123.717557 -233.368147) (xy 123.709432 -233.419442)
			(xy 123.693384 -233.468835) (xy 123.669806 -233.515109) (xy 123.63928 -233.557125) (xy 123.602557 -233.593848)
			(xy 123.560541 -233.624374) (xy 123.514267 -233.647952) (xy 123.464874 -233.664) (xy 123.413579 -233.672125)
			(xy 123.361645 -233.672125) (xy 123.31035 -233.664) (xy 123.260957 -233.647952) (xy 123.214683 -233.624374)
			(xy 123.172667 -233.593848) (xy 123.135944 -233.557125) (xy 123.105418 -233.515109) (xy 123.08184 -233.468835)
			(xy 123.065792 -233.419442) (xy 123.057667 -233.368147) (xy 122.777757 -233.368147) (xy 122.769632 -233.419442)
			(xy 122.753584 -233.468835) (xy 122.730006 -233.515109) (xy 122.69948 -233.557125) (xy 122.662757 -233.593848)
			(xy 122.620741 -233.624374) (xy 122.574467 -233.647952) (xy 122.525074 -233.664) (xy 122.473779 -233.672125)
			(xy 122.421845 -233.672125) (xy 122.37055 -233.664) (xy 122.321157 -233.647952) (xy 122.274883 -233.624374)
			(xy 122.232867 -233.593848) (xy 122.196144 -233.557125) (xy 122.165618 -233.515109) (xy 122.14204 -233.468835)
			(xy 122.125992 -233.419442) (xy 122.117867 -233.368147) (xy 121.838211 -233.368147) (xy 121.830086 -233.419442)
			(xy 121.814038 -233.468835) (xy 121.79046 -233.515109) (xy 121.759934 -233.557125) (xy 121.723211 -233.593848)
			(xy 121.681195 -233.624374) (xy 121.634921 -233.647952) (xy 121.585528 -233.664) (xy 121.534233 -233.672125)
			(xy 121.482299 -233.672125) (xy 121.431004 -233.664) (xy 121.381611 -233.647952) (xy 121.335337 -233.624374)
			(xy 121.293321 -233.593848) (xy 121.256598 -233.557125) (xy 121.226072 -233.515109) (xy 121.202494 -233.468835)
			(xy 121.186446 -233.419442) (xy 121.178321 -233.368147) (xy 120.898157 -233.368147) (xy 120.890032 -233.419442)
			(xy 120.873984 -233.468835) (xy 120.850406 -233.515109) (xy 120.81988 -233.557125) (xy 120.783157 -233.593848)
			(xy 120.741141 -233.624374) (xy 120.694867 -233.647952) (xy 120.645474 -233.664) (xy 120.594179 -233.672125)
			(xy 120.542245 -233.672125) (xy 120.49095 -233.664) (xy 120.441557 -233.647952) (xy 120.395283 -233.624374)
			(xy 120.353267 -233.593848) (xy 120.316544 -233.557125) (xy 120.286018 -233.515109) (xy 120.26244 -233.468835)
			(xy 120.246392 -233.419442) (xy 120.238267 -233.368147) (xy 119.958357 -233.368147) (xy 119.950232 -233.419442)
			(xy 119.934184 -233.468835) (xy 119.910606 -233.515109) (xy 119.88008 -233.557125) (xy 119.843357 -233.593848)
			(xy 119.801341 -233.624374) (xy 119.755067 -233.647952) (xy 119.705674 -233.664) (xy 119.654379 -233.672125)
			(xy 119.602445 -233.672125) (xy 119.55115 -233.664) (xy 119.501757 -233.647952) (xy 119.455483 -233.624374)
			(xy 119.413467 -233.593848) (xy 119.376744 -233.557125) (xy 119.346218 -233.515109) (xy 119.32264 -233.468835)
			(xy 119.306592 -233.419442) (xy 119.298467 -233.368147) (xy 119.018557 -233.368147) (xy 119.010432 -233.419442)
			(xy 118.994384 -233.468835) (xy 118.970806 -233.515109) (xy 118.94028 -233.557125) (xy 118.903557 -233.593848)
			(xy 118.861541 -233.624374) (xy 118.815267 -233.647952) (xy 118.765874 -233.664) (xy 118.714579 -233.672125)
			(xy 118.662645 -233.672125) (xy 118.61135 -233.664) (xy 118.561957 -233.647952) (xy 118.515683 -233.624374)
			(xy 118.473667 -233.593848) (xy 118.436944 -233.557125) (xy 118.406418 -233.515109) (xy 118.38284 -233.468835)
			(xy 118.366792 -233.419442) (xy 118.358667 -233.368147) (xy 118.078757 -233.368147) (xy 118.070632 -233.419442)
			(xy 118.054584 -233.468835) (xy 118.031006 -233.515109) (xy 118.00048 -233.557125) (xy 117.963757 -233.593848)
			(xy 117.921741 -233.624374) (xy 117.875467 -233.647952) (xy 117.826074 -233.664) (xy 117.774779 -233.672125)
			(xy 117.722845 -233.672125) (xy 117.67155 -233.664) (xy 117.622157 -233.647952) (xy 117.575883 -233.624374)
			(xy 117.533867 -233.593848) (xy 117.497144 -233.557125) (xy 117.466618 -233.515109) (xy 117.44304 -233.468835)
			(xy 117.426992 -233.419442) (xy 117.418867 -233.368147) (xy 117.138957 -233.368147) (xy 117.130832 -233.419442)
			(xy 117.114784 -233.468835) (xy 117.091206 -233.515109) (xy 117.06068 -233.557125) (xy 117.023957 -233.593848)
			(xy 116.981941 -233.624374) (xy 116.935667 -233.647952) (xy 116.886274 -233.664) (xy 116.834979 -233.672125)
			(xy 116.783045 -233.672125) (xy 116.73175 -233.664) (xy 116.682357 -233.647952) (xy 116.636083 -233.624374)
			(xy 116.594067 -233.593848) (xy 116.557344 -233.557125) (xy 116.526818 -233.515109) (xy 116.50324 -233.468835)
			(xy 116.487192 -233.419442) (xy 116.479067 -233.368147) (xy 116.199157 -233.368147) (xy 116.191032 -233.419442)
			(xy 116.174984 -233.468835) (xy 116.151406 -233.515109) (xy 116.12088 -233.557125) (xy 116.084157 -233.593848)
			(xy 116.042141 -233.624374) (xy 115.995867 -233.647952) (xy 115.946474 -233.664) (xy 115.895179 -233.672125)
			(xy 115.843245 -233.672125) (xy 115.79195 -233.664) (xy 115.742557 -233.647952) (xy 115.696283 -233.624374)
			(xy 115.654267 -233.593848) (xy 115.617544 -233.557125) (xy 115.587018 -233.515109) (xy 115.56344 -233.468835)
			(xy 115.547392 -233.419442) (xy 115.539267 -233.368147) (xy 115.259357 -233.368147) (xy 115.251232 -233.419442)
			(xy 115.235184 -233.468835) (xy 115.211606 -233.515109) (xy 115.18108 -233.557125) (xy 115.144357 -233.593848)
			(xy 115.102341 -233.624374) (xy 115.056067 -233.647952) (xy 115.006674 -233.664) (xy 114.955379 -233.672125)
			(xy 114.903445 -233.672125) (xy 114.85215 -233.664) (xy 114.802757 -233.647952) (xy 114.756483 -233.624374)
			(xy 114.714467 -233.593848) (xy 114.677744 -233.557125) (xy 114.647218 -233.515109) (xy 114.62364 -233.468835)
			(xy 114.607592 -233.419442) (xy 114.599467 -233.368147) (xy 114.319811 -233.368147) (xy 114.311686 -233.419442)
			(xy 114.295638 -233.468835) (xy 114.27206 -233.515109) (xy 114.241534 -233.557125) (xy 114.204811 -233.593848)
			(xy 114.162795 -233.624374) (xy 114.116521 -233.647952) (xy 114.067128 -233.664) (xy 114.015833 -233.672125)
			(xy 113.963899 -233.672125) (xy 113.912604 -233.664) (xy 113.863211 -233.647952) (xy 113.816937 -233.624374)
			(xy 113.774921 -233.593848) (xy 113.738198 -233.557125) (xy 113.707672 -233.515109) (xy 113.684094 -233.468835)
			(xy 113.668046 -233.419442) (xy 113.659921 -233.368147) (xy 113.379757 -233.368147) (xy 113.371632 -233.419442)
			(xy 113.355584 -233.468835) (xy 113.332006 -233.515109) (xy 113.30148 -233.557125) (xy 113.264757 -233.593848)
			(xy 113.222741 -233.624374) (xy 113.176467 -233.647952) (xy 113.127074 -233.664) (xy 113.075779 -233.672125)
			(xy 113.023845 -233.672125) (xy 112.97255 -233.664) (xy 112.923157 -233.647952) (xy 112.876883 -233.624374)
			(xy 112.834867 -233.593848) (xy 112.798144 -233.557125) (xy 112.767618 -233.515109) (xy 112.74404 -233.468835)
			(xy 112.727992 -233.419442) (xy 112.719867 -233.368147) (xy 112.439957 -233.368147) (xy 112.431832 -233.419442)
			(xy 112.415784 -233.468835) (xy 112.392206 -233.515109) (xy 112.36168 -233.557125) (xy 112.324957 -233.593848)
			(xy 112.282941 -233.624374) (xy 112.236667 -233.647952) (xy 112.187274 -233.664) (xy 112.135979 -233.672125)
			(xy 112.084045 -233.672125) (xy 112.03275 -233.664) (xy 111.983357 -233.647952) (xy 111.937083 -233.624374)
			(xy 111.895067 -233.593848) (xy 111.858344 -233.557125) (xy 111.827818 -233.515109) (xy 111.80424 -233.468835)
			(xy 111.788192 -233.419442) (xy 111.780067 -233.368147) (xy 111.500157 -233.368147) (xy 111.492032 -233.419442)
			(xy 111.475984 -233.468835) (xy 111.452406 -233.515109) (xy 111.42188 -233.557125) (xy 111.385157 -233.593848)
			(xy 111.343141 -233.624374) (xy 111.296867 -233.647952) (xy 111.247474 -233.664) (xy 111.196179 -233.672125)
			(xy 111.144245 -233.672125) (xy 111.09295 -233.664) (xy 111.043557 -233.647952) (xy 110.997283 -233.624374)
			(xy 110.955267 -233.593848) (xy 110.918544 -233.557125) (xy 110.888018 -233.515109) (xy 110.86444 -233.468835)
			(xy 110.848392 -233.419442) (xy 110.840267 -233.368147) (xy 110.560611 -233.368147) (xy 110.552486 -233.419442)
			(xy 110.536438 -233.468835) (xy 110.51286 -233.515109) (xy 110.482334 -233.557125) (xy 110.445611 -233.593848)
			(xy 110.403595 -233.624374) (xy 110.357321 -233.647952) (xy 110.307928 -233.664) (xy 110.256633 -233.672125)
			(xy 110.204699 -233.672125) (xy 110.153404 -233.664) (xy 110.104011 -233.647952) (xy 110.057737 -233.624374)
			(xy 110.015721 -233.593848) (xy 109.978998 -233.557125) (xy 109.948472 -233.515109) (xy 109.924894 -233.468835)
			(xy 109.908846 -233.419442) (xy 109.900721 -233.368147) (xy 109.620557 -233.368147) (xy 109.612432 -233.419442)
			(xy 109.596384 -233.468835) (xy 109.572806 -233.515109) (xy 109.54228 -233.557125) (xy 109.505557 -233.593848)
			(xy 109.463541 -233.624374) (xy 109.417267 -233.647952) (xy 109.367874 -233.664) (xy 109.316579 -233.672125)
			(xy 109.264645 -233.672125) (xy 109.21335 -233.664) (xy 109.163957 -233.647952) (xy 109.117683 -233.624374)
			(xy 109.075667 -233.593848) (xy 109.038944 -233.557125) (xy 109.008418 -233.515109) (xy 108.98484 -233.468835)
			(xy 108.968792 -233.419442) (xy 108.960667 -233.368147) (xy 108.680757 -233.368147) (xy 108.672632 -233.419442)
			(xy 108.656584 -233.468835) (xy 108.633006 -233.515109) (xy 108.60248 -233.557125) (xy 108.565757 -233.593848)
			(xy 108.523741 -233.624374) (xy 108.477467 -233.647952) (xy 108.428074 -233.664) (xy 108.376779 -233.672125)
			(xy 108.324845 -233.672125) (xy 108.27355 -233.664) (xy 108.224157 -233.647952) (xy 108.177883 -233.624374)
			(xy 108.135867 -233.593848) (xy 108.099144 -233.557125) (xy 108.068618 -233.515109) (xy 108.04504 -233.468835)
			(xy 108.028992 -233.419442) (xy 108.020867 -233.368147) (xy 107.740957 -233.368147) (xy 107.732832 -233.419442)
			(xy 107.716784 -233.468835) (xy 107.693206 -233.515109) (xy 107.66268 -233.557125) (xy 107.625957 -233.593848)
			(xy 107.583941 -233.624374) (xy 107.537667 -233.647952) (xy 107.488274 -233.664) (xy 107.436979 -233.672125)
			(xy 107.385045 -233.672125) (xy 107.33375 -233.664) (xy 107.284357 -233.647952) (xy 107.238083 -233.624374)
			(xy 107.196067 -233.593848) (xy 107.159344 -233.557125) (xy 107.128818 -233.515109) (xy 107.10524 -233.468835)
			(xy 107.089192 -233.419442) (xy 107.081067 -233.368147) (xy 106.801157 -233.368147) (xy 106.793032 -233.419442)
			(xy 106.776984 -233.468835) (xy 106.753406 -233.515109) (xy 106.72288 -233.557125) (xy 106.686157 -233.593848)
			(xy 106.644141 -233.624374) (xy 106.597867 -233.647952) (xy 106.548474 -233.664) (xy 106.497179 -233.672125)
			(xy 106.445245 -233.672125) (xy 106.39395 -233.664) (xy 106.344557 -233.647952) (xy 106.298283 -233.624374)
			(xy 106.256267 -233.593848) (xy 106.219544 -233.557125) (xy 106.189018 -233.515109) (xy 106.16544 -233.468835)
			(xy 106.149392 -233.419442) (xy 106.141267 -233.368147) (xy 105.861651 -233.368147) (xy 105.861651 -233.368169)
			(xy 105.853526 -233.419469) (xy 105.837475 -233.468865) (xy 105.813893 -233.515142) (xy 105.783363 -233.55716)
			(xy 105.746635 -233.593885) (xy 105.704613 -233.624411) (xy 105.658334 -233.647988) (xy 105.608936 -233.664033)
			(xy 105.557635 -233.672154) (xy 105.531666 -233.672634) (xy 105.519982 -233.67238) (xy 105.506332 -233.672281)
			(xy 105.479771 -233.678545) (xy 105.455815 -233.691613) (xy 105.43617 -233.710555) (xy 105.422238 -233.73402)
			(xy 105.415012 -233.760335) (xy 105.414572 -233.77398) (xy 105.414572 -234.182217) (xy 105.671621 -234.182217)
			(xy 105.671621 -234.130283) (xy 105.679746 -234.078988) (xy 105.695794 -234.029595) (xy 105.719372 -233.983321)
			(xy 105.749898 -233.941305) (xy 105.786621 -233.904582) (xy 105.828637 -233.874056) (xy 105.874911 -233.850478)
			(xy 105.924304 -233.83443) (xy 105.975599 -233.826305) (xy 106.027533 -233.826305) (xy 106.078828 -233.83443)
			(xy 106.128221 -233.850478) (xy 106.174495 -233.874056) (xy 106.216511 -233.904582) (xy 106.253234 -233.941305)
			(xy 106.28376 -233.983321) (xy 106.307338 -234.029595) (xy 106.323386 -234.078988) (xy 106.331511 -234.130283)
			(xy 106.33202 -234.15625) (xy 106.331511 -234.182217) (xy 106.611421 -234.182217) (xy 106.611421 -234.130283)
			(xy 106.619546 -234.078988) (xy 106.635594 -234.029595) (xy 106.659172 -233.983321) (xy 106.689698 -233.941305)
			(xy 106.726421 -233.904582) (xy 106.768437 -233.874056) (xy 106.814711 -233.850478) (xy 106.864104 -233.83443)
			(xy 106.915399 -233.826305) (xy 106.967333 -233.826305) (xy 107.018628 -233.83443) (xy 107.068021 -233.850478)
			(xy 107.114295 -233.874056) (xy 107.156311 -233.904582) (xy 107.193034 -233.941305) (xy 107.22356 -233.983321)
			(xy 107.247138 -234.029595) (xy 107.263186 -234.078988) (xy 107.271311 -234.130283) (xy 107.27182 -234.15625)
			(xy 107.271311 -234.182217) (xy 107.551221 -234.182217) (xy 107.551221 -234.130283) (xy 107.559346 -234.078988)
			(xy 107.575394 -234.029595) (xy 107.598972 -233.983321) (xy 107.629498 -233.941305) (xy 107.666221 -233.904582)
			(xy 107.708237 -233.874056) (xy 107.754511 -233.850478) (xy 107.803904 -233.83443) (xy 107.855199 -233.826305)
			(xy 107.907133 -233.826305) (xy 107.958428 -233.83443) (xy 108.007821 -233.850478) (xy 108.054095 -233.874056)
			(xy 108.096111 -233.904582) (xy 108.132834 -233.941305) (xy 108.16336 -233.983321) (xy 108.186938 -234.029595)
			(xy 108.202986 -234.078988) (xy 108.211111 -234.130283) (xy 108.21162 -234.15625) (xy 108.211111 -234.182217)
			(xy 108.491021 -234.182217) (xy 108.491021 -234.130283) (xy 108.499146 -234.078988) (xy 108.515194 -234.029595)
			(xy 108.538772 -233.983321) (xy 108.569298 -233.941305) (xy 108.606021 -233.904582) (xy 108.648037 -233.874056)
			(xy 108.694311 -233.850478) (xy 108.743704 -233.83443) (xy 108.794999 -233.826305) (xy 108.846933 -233.826305)
			(xy 108.898228 -233.83443) (xy 108.947621 -233.850478) (xy 108.993895 -233.874056) (xy 109.035911 -233.904582)
			(xy 109.072634 -233.941305) (xy 109.10316 -233.983321) (xy 109.126738 -234.029595) (xy 109.142786 -234.078988)
			(xy 109.150911 -234.130283) (xy 109.15142 -234.15625) (xy 109.150911 -234.182217) (xy 109.430821 -234.182217)
			(xy 109.430821 -234.130283) (xy 109.438946 -234.078988) (xy 109.454994 -234.029595) (xy 109.478572 -233.983321)
			(xy 109.509098 -233.941305) (xy 109.545821 -233.904582) (xy 109.587837 -233.874056) (xy 109.634111 -233.850478)
			(xy 109.683504 -233.83443) (xy 109.734799 -233.826305) (xy 109.786733 -233.826305) (xy 109.838028 -233.83443)
			(xy 109.887421 -233.850478) (xy 109.933695 -233.874056) (xy 109.975711 -233.904582) (xy 110.012434 -233.941305)
			(xy 110.04296 -233.983321) (xy 110.066538 -234.029595) (xy 110.082586 -234.078988) (xy 110.090711 -234.130283)
			(xy 110.09122 -234.15625) (xy 110.090711 -234.182217) (xy 110.370621 -234.182217) (xy 110.370621 -234.130283)
			(xy 110.378746 -234.078988) (xy 110.394794 -234.029595) (xy 110.418372 -233.983321) (xy 110.448898 -233.941305)
			(xy 110.485621 -233.904582) (xy 110.527637 -233.874056) (xy 110.573911 -233.850478) (xy 110.623304 -233.83443)
			(xy 110.674599 -233.826305) (xy 110.726533 -233.826305) (xy 110.777828 -233.83443) (xy 110.827221 -233.850478)
			(xy 110.873495 -233.874056) (xy 110.915511 -233.904582) (xy 110.952234 -233.941305) (xy 110.98276 -233.983321)
			(xy 111.006338 -234.029595) (xy 111.022386 -234.078988) (xy 111.030511 -234.130283) (xy 111.03102 -234.15625)
			(xy 111.030511 -234.182217) (xy 111.310421 -234.182217) (xy 111.310421 -234.130283) (xy 111.318546 -234.078988)
			(xy 111.334594 -234.029595) (xy 111.358172 -233.983321) (xy 111.388698 -233.941305) (xy 111.425421 -233.904582)
			(xy 111.467437 -233.874056) (xy 111.513711 -233.850478) (xy 111.563104 -233.83443) (xy 111.614399 -233.826305)
			(xy 111.666333 -233.826305) (xy 111.717628 -233.83443) (xy 111.767021 -233.850478) (xy 111.813295 -233.874056)
			(xy 111.855311 -233.904582) (xy 111.892034 -233.941305) (xy 111.92256 -233.983321) (xy 111.946138 -234.029595)
			(xy 111.962186 -234.078988) (xy 111.970311 -234.130283) (xy 111.97082 -234.15625) (xy 111.970311 -234.182217)
			(xy 112.250221 -234.182217) (xy 112.250221 -234.130283) (xy 112.258346 -234.078988) (xy 112.274394 -234.029595)
			(xy 112.297972 -233.983321) (xy 112.328498 -233.941305) (xy 112.365221 -233.904582) (xy 112.407237 -233.874056)
			(xy 112.453511 -233.850478) (xy 112.502904 -233.83443) (xy 112.554199 -233.826305) (xy 112.606133 -233.826305)
			(xy 112.657428 -233.83443) (xy 112.706821 -233.850478) (xy 112.753095 -233.874056) (xy 112.795111 -233.904582)
			(xy 112.831834 -233.941305) (xy 112.86236 -233.983321) (xy 112.885938 -234.029595) (xy 112.901986 -234.078988)
			(xy 112.910111 -234.130283) (xy 112.91062 -234.15625) (xy 112.910111 -234.182217) (xy 113.190021 -234.182217)
			(xy 113.190021 -234.130283) (xy 113.198146 -234.078988) (xy 113.214194 -234.029595) (xy 113.237772 -233.983321)
			(xy 113.268298 -233.941305) (xy 113.305021 -233.904582) (xy 113.347037 -233.874056) (xy 113.393311 -233.850478)
			(xy 113.442704 -233.83443) (xy 113.493999 -233.826305) (xy 113.545933 -233.826305) (xy 113.597228 -233.83443)
			(xy 113.646621 -233.850478) (xy 113.692895 -233.874056) (xy 113.734911 -233.904582) (xy 113.771634 -233.941305)
			(xy 113.80216 -233.983321) (xy 113.825738 -234.029595) (xy 113.841786 -234.078988) (xy 113.849911 -234.130283)
			(xy 113.85042 -234.15625) (xy 113.849911 -234.182217) (xy 114.129821 -234.182217) (xy 114.129821 -234.130283)
			(xy 114.137946 -234.078988) (xy 114.153994 -234.029595) (xy 114.177572 -233.983321) (xy 114.208098 -233.941305)
			(xy 114.244821 -233.904582) (xy 114.286837 -233.874056) (xy 114.333111 -233.850478) (xy 114.382504 -233.83443)
			(xy 114.433799 -233.826305) (xy 114.485733 -233.826305) (xy 114.537028 -233.83443) (xy 114.586421 -233.850478)
			(xy 114.632695 -233.874056) (xy 114.674711 -233.904582) (xy 114.711434 -233.941305) (xy 114.74196 -233.983321)
			(xy 114.765538 -234.029595) (xy 114.781586 -234.078988) (xy 114.789711 -234.130283) (xy 114.79022 -234.15625)
			(xy 114.789711 -234.182217) (xy 115.069621 -234.182217) (xy 115.069621 -234.130283) (xy 115.077746 -234.078988)
			(xy 115.093794 -234.029595) (xy 115.117372 -233.983321) (xy 115.147898 -233.941305) (xy 115.184621 -233.904582)
			(xy 115.226637 -233.874056) (xy 115.272911 -233.850478) (xy 115.322304 -233.83443) (xy 115.373599 -233.826305)
			(xy 115.425533 -233.826305) (xy 115.476828 -233.83443) (xy 115.526221 -233.850478) (xy 115.572495 -233.874056)
			(xy 115.614511 -233.904582) (xy 115.651234 -233.941305) (xy 115.68176 -233.983321) (xy 115.705338 -234.029595)
			(xy 115.721386 -234.078988) (xy 115.729511 -234.130283) (xy 115.73002 -234.15625) (xy 115.729511 -234.182217)
			(xy 116.009421 -234.182217) (xy 116.009421 -234.130283) (xy 116.017546 -234.078988) (xy 116.033594 -234.029595)
			(xy 116.057172 -233.983321) (xy 116.087698 -233.941305) (xy 116.124421 -233.904582) (xy 116.166437 -233.874056)
			(xy 116.212711 -233.850478) (xy 116.262104 -233.83443) (xy 116.313399 -233.826305) (xy 116.365333 -233.826305)
			(xy 116.416628 -233.83443) (xy 116.466021 -233.850478) (xy 116.512295 -233.874056) (xy 116.554311 -233.904582)
			(xy 116.591034 -233.941305) (xy 116.62156 -233.983321) (xy 116.645138 -234.029595) (xy 116.661186 -234.078988)
			(xy 116.669311 -234.130283) (xy 116.66982 -234.15625) (xy 116.669311 -234.182217) (xy 116.949221 -234.182217)
			(xy 116.949221 -234.130283) (xy 116.957346 -234.078988) (xy 116.973394 -234.029595) (xy 116.996972 -233.983321)
			(xy 117.027498 -233.941305) (xy 117.064221 -233.904582) (xy 117.106237 -233.874056) (xy 117.152511 -233.850478)
			(xy 117.201904 -233.83443) (xy 117.253199 -233.826305) (xy 117.305133 -233.826305) (xy 117.356428 -233.83443)
			(xy 117.405821 -233.850478) (xy 117.452095 -233.874056) (xy 117.494111 -233.904582) (xy 117.530834 -233.941305)
			(xy 117.56136 -233.983321) (xy 117.584938 -234.029595) (xy 117.600986 -234.078988) (xy 117.609111 -234.130283)
			(xy 117.60962 -234.15625) (xy 117.609111 -234.182217) (xy 117.889021 -234.182217) (xy 117.889021 -234.130283)
			(xy 117.897146 -234.078988) (xy 117.913194 -234.029595) (xy 117.936772 -233.983321) (xy 117.967298 -233.941305)
			(xy 118.004021 -233.904582) (xy 118.046037 -233.874056) (xy 118.092311 -233.850478) (xy 118.141704 -233.83443)
			(xy 118.192999 -233.826305) (xy 118.244933 -233.826305) (xy 118.296228 -233.83443) (xy 118.345621 -233.850478)
			(xy 118.391895 -233.874056) (xy 118.433911 -233.904582) (xy 118.470634 -233.941305) (xy 118.50116 -233.983321)
			(xy 118.524738 -234.029595) (xy 118.540786 -234.078988) (xy 118.548911 -234.130283) (xy 118.54942 -234.15625)
			(xy 118.548911 -234.182217) (xy 118.828821 -234.182217) (xy 118.828821 -234.130283) (xy 118.836946 -234.078988)
			(xy 118.852994 -234.029595) (xy 118.876572 -233.983321) (xy 118.907098 -233.941305) (xy 118.943821 -233.904582)
			(xy 118.985837 -233.874056) (xy 119.032111 -233.850478) (xy 119.081504 -233.83443) (xy 119.132799 -233.826305)
			(xy 119.184733 -233.826305) (xy 119.236028 -233.83443) (xy 119.285421 -233.850478) (xy 119.331695 -233.874056)
			(xy 119.373711 -233.904582) (xy 119.410434 -233.941305) (xy 119.44096 -233.983321) (xy 119.464538 -234.029595)
			(xy 119.480586 -234.078988) (xy 119.488711 -234.130283) (xy 119.48922 -234.15625) (xy 119.488711 -234.182217)
			(xy 119.768621 -234.182217) (xy 119.768621 -234.130283) (xy 119.776746 -234.078988) (xy 119.792794 -234.029595)
			(xy 119.816372 -233.983321) (xy 119.846898 -233.941305) (xy 119.883621 -233.904582) (xy 119.925637 -233.874056)
			(xy 119.971911 -233.850478) (xy 120.021304 -233.83443) (xy 120.072599 -233.826305) (xy 120.124533 -233.826305)
			(xy 120.175828 -233.83443) (xy 120.225221 -233.850478) (xy 120.271495 -233.874056) (xy 120.313511 -233.904582)
			(xy 120.350234 -233.941305) (xy 120.38076 -233.983321) (xy 120.404338 -234.029595) (xy 120.420386 -234.078988)
			(xy 120.428511 -234.130283) (xy 120.42902 -234.15625) (xy 120.428511 -234.182217) (xy 120.708167 -234.182217)
			(xy 120.708167 -234.130283) (xy 120.716292 -234.078988) (xy 120.73234 -234.029595) (xy 120.755918 -233.983321)
			(xy 120.786444 -233.941305) (xy 120.823167 -233.904582) (xy 120.865183 -233.874056) (xy 120.911457 -233.850478)
			(xy 120.96085 -233.83443) (xy 121.012145 -233.826305) (xy 121.064079 -233.826305) (xy 121.115374 -233.83443)
			(xy 121.164767 -233.850478) (xy 121.211041 -233.874056) (xy 121.253057 -233.904582) (xy 121.28978 -233.941305)
			(xy 121.320306 -233.983321) (xy 121.343884 -234.029595) (xy 121.359932 -234.078988) (xy 121.368057 -234.130283)
			(xy 121.368566 -234.15625) (xy 121.368057 -234.182217) (xy 121.648221 -234.182217) (xy 121.648221 -234.130283)
			(xy 121.656346 -234.078988) (xy 121.672394 -234.029595) (xy 121.695972 -233.983321) (xy 121.726498 -233.941305)
			(xy 121.763221 -233.904582) (xy 121.805237 -233.874056) (xy 121.851511 -233.850478) (xy 121.900904 -233.83443)
			(xy 121.952199 -233.826305) (xy 122.004133 -233.826305) (xy 122.055428 -233.83443) (xy 122.104821 -233.850478)
			(xy 122.151095 -233.874056) (xy 122.193111 -233.904582) (xy 122.229834 -233.941305) (xy 122.26036 -233.983321)
			(xy 122.283938 -234.029595) (xy 122.299986 -234.078988) (xy 122.308111 -234.130283) (xy 122.30862 -234.15625)
			(xy 122.308111 -234.182217) (xy 122.587767 -234.182217) (xy 122.587767 -234.130283) (xy 122.595892 -234.078988)
			(xy 122.61194 -234.029595) (xy 122.635518 -233.983321) (xy 122.666044 -233.941305) (xy 122.702767 -233.904582)
			(xy 122.744783 -233.874056) (xy 122.791057 -233.850478) (xy 122.84045 -233.83443) (xy 122.891745 -233.826305)
			(xy 122.943679 -233.826305) (xy 122.994974 -233.83443) (xy 123.044367 -233.850478) (xy 123.090641 -233.874056)
			(xy 123.132657 -233.904582) (xy 123.16938 -233.941305) (xy 123.199906 -233.983321) (xy 123.223484 -234.029595)
			(xy 123.239532 -234.078988) (xy 123.247657 -234.130283) (xy 123.248166 -234.15625) (xy 123.247657 -234.182217)
			(xy 123.527821 -234.182217) (xy 123.527821 -234.130283) (xy 123.535946 -234.078988) (xy 123.551994 -234.029595)
			(xy 123.575572 -233.983321) (xy 123.606098 -233.941305) (xy 123.642821 -233.904582) (xy 123.684837 -233.874056)
			(xy 123.731111 -233.850478) (xy 123.780504 -233.83443) (xy 123.831799 -233.826305) (xy 123.883733 -233.826305)
			(xy 123.935028 -233.83443) (xy 123.984421 -233.850478) (xy 124.030695 -233.874056) (xy 124.072711 -233.904582)
			(xy 124.109434 -233.941305) (xy 124.13996 -233.983321) (xy 124.163538 -234.029595) (xy 124.179586 -234.078988)
			(xy 124.187711 -234.130283) (xy 124.18822 -234.15625) (xy 124.187711 -234.182217) (xy 124.467621 -234.182217)
			(xy 124.467621 -234.130283) (xy 124.475746 -234.078988) (xy 124.491794 -234.029595) (xy 124.515372 -233.983321)
			(xy 124.545898 -233.941305) (xy 124.582621 -233.904582) (xy 124.624637 -233.874056) (xy 124.670911 -233.850478)
			(xy 124.720304 -233.83443) (xy 124.771599 -233.826305) (xy 124.823533 -233.826305) (xy 124.874828 -233.83443)
			(xy 124.924221 -233.850478) (xy 124.970495 -233.874056) (xy 125.012511 -233.904582) (xy 125.049234 -233.941305)
			(xy 125.07976 -233.983321) (xy 125.103338 -234.029595) (xy 125.119386 -234.078988) (xy 125.127511 -234.130283)
			(xy 125.12802 -234.15625) (xy 125.127511 -234.182217) (xy 125.407421 -234.182217) (xy 125.407421 -234.130283)
			(xy 125.415546 -234.078988) (xy 125.431594 -234.029595) (xy 125.455172 -233.983321) (xy 125.485698 -233.941305)
			(xy 125.522421 -233.904582) (xy 125.564437 -233.874056) (xy 125.610711 -233.850478) (xy 125.660104 -233.83443)
			(xy 125.711399 -233.826305) (xy 125.763333 -233.826305) (xy 125.814628 -233.83443) (xy 125.864021 -233.850478)
			(xy 125.910295 -233.874056) (xy 125.952311 -233.904582) (xy 125.989034 -233.941305) (xy 126.01956 -233.983321)
			(xy 126.043138 -234.029595) (xy 126.059186 -234.078988) (xy 126.067311 -234.130283) (xy 126.06782 -234.15625)
			(xy 126.067311 -234.182217) (xy 126.347221 -234.182217) (xy 126.347221 -234.130283) (xy 126.355346 -234.078988)
			(xy 126.371394 -234.029595) (xy 126.394972 -233.983321) (xy 126.425498 -233.941305) (xy 126.462221 -233.904582)
			(xy 126.504237 -233.874056) (xy 126.550511 -233.850478) (xy 126.599904 -233.83443) (xy 126.651199 -233.826305)
			(xy 126.703133 -233.826305) (xy 126.754428 -233.83443) (xy 126.803821 -233.850478) (xy 126.850095 -233.874056)
			(xy 126.892111 -233.904582) (xy 126.928834 -233.941305) (xy 126.95936 -233.983321) (xy 126.982938 -234.029595)
			(xy 126.998986 -234.078988) (xy 127.007111 -234.130283) (xy 127.00762 -234.15625) (xy 127.007111 -234.182217)
			(xy 127.287021 -234.182217) (xy 127.287021 -234.130283) (xy 127.295146 -234.078988) (xy 127.311194 -234.029595)
			(xy 127.334772 -233.983321) (xy 127.365298 -233.941305) (xy 127.402021 -233.904582) (xy 127.444037 -233.874056)
			(xy 127.490311 -233.850478) (xy 127.539704 -233.83443) (xy 127.590999 -233.826305) (xy 127.642933 -233.826305)
			(xy 127.694228 -233.83443) (xy 127.743621 -233.850478) (xy 127.789895 -233.874056) (xy 127.831911 -233.904582)
			(xy 127.868634 -233.941305) (xy 127.89916 -233.983321) (xy 127.922738 -234.029595) (xy 127.938786 -234.078988)
			(xy 127.946911 -234.130283) (xy 127.94742 -234.15625) (xy 127.946911 -234.182217) (xy 128.226821 -234.182217)
			(xy 128.226821 -234.130283) (xy 128.234946 -234.078988) (xy 128.250994 -234.029595) (xy 128.274572 -233.983321)
			(xy 128.305098 -233.941305) (xy 128.341821 -233.904582) (xy 128.383837 -233.874056) (xy 128.430111 -233.850478)
			(xy 128.479504 -233.83443) (xy 128.530799 -233.826305) (xy 128.582733 -233.826305) (xy 128.634028 -233.83443)
			(xy 128.683421 -233.850478) (xy 128.729695 -233.874056) (xy 128.771711 -233.904582) (xy 128.808434 -233.941305)
			(xy 128.83896 -233.983321) (xy 128.862538 -234.029595) (xy 128.878586 -234.078988) (xy 128.886711 -234.130283)
			(xy 128.88722 -234.15625) (xy 128.886711 -234.182217) (xy 129.166367 -234.182217) (xy 129.166367 -234.130283)
			(xy 129.174492 -234.078988) (xy 129.19054 -234.029595) (xy 129.214118 -233.983321) (xy 129.244644 -233.941305)
			(xy 129.281367 -233.904582) (xy 129.323383 -233.874056) (xy 129.369657 -233.850478) (xy 129.41905 -233.83443)
			(xy 129.470345 -233.826305) (xy 129.522279 -233.826305) (xy 129.573574 -233.83443) (xy 129.622967 -233.850478)
			(xy 129.669241 -233.874056) (xy 129.711257 -233.904582) (xy 129.74798 -233.941305) (xy 129.778506 -233.983321)
			(xy 129.802084 -234.029595) (xy 129.818132 -234.078988) (xy 129.826257 -234.130283) (xy 129.826766 -234.15625)
			(xy 129.826257 -234.182217) (xy 130.106421 -234.182217) (xy 130.106421 -234.130283) (xy 130.114546 -234.078988)
			(xy 130.130594 -234.029595) (xy 130.154172 -233.983321) (xy 130.184698 -233.941305) (xy 130.221421 -233.904582)
			(xy 130.263437 -233.874056) (xy 130.309711 -233.850478) (xy 130.359104 -233.83443) (xy 130.410399 -233.826305)
			(xy 130.462333 -233.826305) (xy 130.513628 -233.83443) (xy 130.563021 -233.850478) (xy 130.609295 -233.874056)
			(xy 130.651311 -233.904582) (xy 130.688034 -233.941305) (xy 130.71856 -233.983321) (xy 130.742138 -234.029595)
			(xy 130.758186 -234.078988) (xy 130.766311 -234.130283) (xy 130.76682 -234.15625) (xy 130.766311 -234.182217)
			(xy 131.046221 -234.182217) (xy 131.046221 -234.130283) (xy 131.054346 -234.078988) (xy 131.070394 -234.029595)
			(xy 131.093972 -233.983321) (xy 131.124498 -233.941305) (xy 131.161221 -233.904582) (xy 131.203237 -233.874056)
			(xy 131.249511 -233.850478) (xy 131.298904 -233.83443) (xy 131.350199 -233.826305) (xy 131.402133 -233.826305)
			(xy 131.453428 -233.83443) (xy 131.502821 -233.850478) (xy 131.549095 -233.874056) (xy 131.591111 -233.904582)
			(xy 131.627834 -233.941305) (xy 131.65836 -233.983321) (xy 131.681938 -234.029595) (xy 131.697986 -234.078988)
			(xy 131.706111 -234.130283) (xy 131.70662 -234.15625) (xy 131.706111 -234.182217) (xy 131.697986 -234.233512)
			(xy 131.681938 -234.282905) (xy 131.65836 -234.329179) (xy 131.627834 -234.371195) (xy 131.591111 -234.407918)
			(xy 131.549095 -234.438444) (xy 131.502821 -234.462022) (xy 131.453428 -234.47807) (xy 131.402133 -234.486195)
			(xy 131.350199 -234.486195) (xy 131.298904 -234.47807) (xy 131.249511 -234.462022) (xy 131.203237 -234.438444)
			(xy 131.161221 -234.407918) (xy 131.124498 -234.371195) (xy 131.093972 -234.329179) (xy 131.070394 -234.282905)
			(xy 131.054346 -234.233512) (xy 131.046221 -234.182217) (xy 130.766311 -234.182217) (xy 130.758186 -234.233512)
			(xy 130.742138 -234.282905) (xy 130.71856 -234.329179) (xy 130.688034 -234.371195) (xy 130.651311 -234.407918)
			(xy 130.609295 -234.438444) (xy 130.563021 -234.462022) (xy 130.513628 -234.47807) (xy 130.462333 -234.486195)
			(xy 130.410399 -234.486195) (xy 130.359104 -234.47807) (xy 130.309711 -234.462022) (xy 130.263437 -234.438444)
			(xy 130.221421 -234.407918) (xy 130.184698 -234.371195) (xy 130.154172 -234.329179) (xy 130.130594 -234.282905)
			(xy 130.114546 -234.233512) (xy 130.106421 -234.182217) (xy 129.826257 -234.182217) (xy 129.818132 -234.233512)
			(xy 129.802084 -234.282905) (xy 129.778506 -234.329179) (xy 129.74798 -234.371195) (xy 129.711257 -234.407918)
			(xy 129.669241 -234.438444) (xy 129.622967 -234.462022) (xy 129.573574 -234.47807) (xy 129.522279 -234.486195)
			(xy 129.470345 -234.486195) (xy 129.41905 -234.47807) (xy 129.369657 -234.462022) (xy 129.323383 -234.438444)
			(xy 129.281367 -234.407918) (xy 129.244644 -234.371195) (xy 129.214118 -234.329179) (xy 129.19054 -234.282905)
			(xy 129.174492 -234.233512) (xy 129.166367 -234.182217) (xy 128.886711 -234.182217) (xy 128.878586 -234.233512)
			(xy 128.862538 -234.282905) (xy 128.83896 -234.329179) (xy 128.808434 -234.371195) (xy 128.771711 -234.407918)
			(xy 128.729695 -234.438444) (xy 128.683421 -234.462022) (xy 128.634028 -234.47807) (xy 128.582733 -234.486195)
			(xy 128.530799 -234.486195) (xy 128.479504 -234.47807) (xy 128.430111 -234.462022) (xy 128.383837 -234.438444)
			(xy 128.341821 -234.407918) (xy 128.305098 -234.371195) (xy 128.274572 -234.329179) (xy 128.250994 -234.282905)
			(xy 128.234946 -234.233512) (xy 128.226821 -234.182217) (xy 127.946911 -234.182217) (xy 127.938786 -234.233512)
			(xy 127.922738 -234.282905) (xy 127.89916 -234.329179) (xy 127.868634 -234.371195) (xy 127.831911 -234.407918)
			(xy 127.789895 -234.438444) (xy 127.743621 -234.462022) (xy 127.694228 -234.47807) (xy 127.642933 -234.486195)
			(xy 127.590999 -234.486195) (xy 127.539704 -234.47807) (xy 127.490311 -234.462022) (xy 127.444037 -234.438444)
			(xy 127.402021 -234.407918) (xy 127.365298 -234.371195) (xy 127.334772 -234.329179) (xy 127.311194 -234.282905)
			(xy 127.295146 -234.233512) (xy 127.287021 -234.182217) (xy 127.007111 -234.182217) (xy 126.998986 -234.233512)
			(xy 126.982938 -234.282905) (xy 126.95936 -234.329179) (xy 126.928834 -234.371195) (xy 126.892111 -234.407918)
			(xy 126.850095 -234.438444) (xy 126.803821 -234.462022) (xy 126.754428 -234.47807) (xy 126.703133 -234.486195)
			(xy 126.651199 -234.486195) (xy 126.599904 -234.47807) (xy 126.550511 -234.462022) (xy 126.504237 -234.438444)
			(xy 126.462221 -234.407918) (xy 126.425498 -234.371195) (xy 126.394972 -234.329179) (xy 126.371394 -234.282905)
			(xy 126.355346 -234.233512) (xy 126.347221 -234.182217) (xy 126.067311 -234.182217) (xy 126.059186 -234.233512)
			(xy 126.043138 -234.282905) (xy 126.01956 -234.329179) (xy 125.989034 -234.371195) (xy 125.952311 -234.407918)
			(xy 125.910295 -234.438444) (xy 125.864021 -234.462022) (xy 125.814628 -234.47807) (xy 125.763333 -234.486195)
			(xy 125.711399 -234.486195) (xy 125.660104 -234.47807) (xy 125.610711 -234.462022) (xy 125.564437 -234.438444)
			(xy 125.522421 -234.407918) (xy 125.485698 -234.371195) (xy 125.455172 -234.329179) (xy 125.431594 -234.282905)
			(xy 125.415546 -234.233512) (xy 125.407421 -234.182217) (xy 125.127511 -234.182217) (xy 125.119386 -234.233512)
			(xy 125.103338 -234.282905) (xy 125.07976 -234.329179) (xy 125.049234 -234.371195) (xy 125.012511 -234.407918)
			(xy 124.970495 -234.438444) (xy 124.924221 -234.462022) (xy 124.874828 -234.47807) (xy 124.823533 -234.486195)
			(xy 124.771599 -234.486195) (xy 124.720304 -234.47807) (xy 124.670911 -234.462022) (xy 124.624637 -234.438444)
			(xy 124.582621 -234.407918) (xy 124.545898 -234.371195) (xy 124.515372 -234.329179) (xy 124.491794 -234.282905)
			(xy 124.475746 -234.233512) (xy 124.467621 -234.182217) (xy 124.187711 -234.182217) (xy 124.179586 -234.233512)
			(xy 124.163538 -234.282905) (xy 124.13996 -234.329179) (xy 124.109434 -234.371195) (xy 124.072711 -234.407918)
			(xy 124.030695 -234.438444) (xy 123.984421 -234.462022) (xy 123.935028 -234.47807) (xy 123.883733 -234.486195)
			(xy 123.831799 -234.486195) (xy 123.780504 -234.47807) (xy 123.731111 -234.462022) (xy 123.684837 -234.438444)
			(xy 123.642821 -234.407918) (xy 123.606098 -234.371195) (xy 123.575572 -234.329179) (xy 123.551994 -234.282905)
			(xy 123.535946 -234.233512) (xy 123.527821 -234.182217) (xy 123.247657 -234.182217) (xy 123.239532 -234.233512)
			(xy 123.223484 -234.282905) (xy 123.199906 -234.329179) (xy 123.16938 -234.371195) (xy 123.132657 -234.407918)
			(xy 123.090641 -234.438444) (xy 123.044367 -234.462022) (xy 122.994974 -234.47807) (xy 122.943679 -234.486195)
			(xy 122.891745 -234.486195) (xy 122.84045 -234.47807) (xy 122.791057 -234.462022) (xy 122.744783 -234.438444)
			(xy 122.702767 -234.407918) (xy 122.666044 -234.371195) (xy 122.635518 -234.329179) (xy 122.61194 -234.282905)
			(xy 122.595892 -234.233512) (xy 122.587767 -234.182217) (xy 122.308111 -234.182217) (xy 122.299986 -234.233512)
			(xy 122.283938 -234.282905) (xy 122.26036 -234.329179) (xy 122.229834 -234.371195) (xy 122.193111 -234.407918)
			(xy 122.151095 -234.438444) (xy 122.104821 -234.462022) (xy 122.055428 -234.47807) (xy 122.004133 -234.486195)
			(xy 121.952199 -234.486195) (xy 121.900904 -234.47807) (xy 121.851511 -234.462022) (xy 121.805237 -234.438444)
			(xy 121.763221 -234.407918) (xy 121.726498 -234.371195) (xy 121.695972 -234.329179) (xy 121.672394 -234.282905)
			(xy 121.656346 -234.233512) (xy 121.648221 -234.182217) (xy 121.368057 -234.182217) (xy 121.359932 -234.233512)
			(xy 121.343884 -234.282905) (xy 121.320306 -234.329179) (xy 121.28978 -234.371195) (xy 121.253057 -234.407918)
			(xy 121.211041 -234.438444) (xy 121.164767 -234.462022) (xy 121.115374 -234.47807) (xy 121.064079 -234.486195)
			(xy 121.012145 -234.486195) (xy 120.96085 -234.47807) (xy 120.911457 -234.462022) (xy 120.865183 -234.438444)
			(xy 120.823167 -234.407918) (xy 120.786444 -234.371195) (xy 120.755918 -234.329179) (xy 120.73234 -234.282905)
			(xy 120.716292 -234.233512) (xy 120.708167 -234.182217) (xy 120.428511 -234.182217) (xy 120.420386 -234.233512)
			(xy 120.404338 -234.282905) (xy 120.38076 -234.329179) (xy 120.350234 -234.371195) (xy 120.313511 -234.407918)
			(xy 120.271495 -234.438444) (xy 120.225221 -234.462022) (xy 120.175828 -234.47807) (xy 120.124533 -234.486195)
			(xy 120.072599 -234.486195) (xy 120.021304 -234.47807) (xy 119.971911 -234.462022) (xy 119.925637 -234.438444)
			(xy 119.883621 -234.407918) (xy 119.846898 -234.371195) (xy 119.816372 -234.329179) (xy 119.792794 -234.282905)
			(xy 119.776746 -234.233512) (xy 119.768621 -234.182217) (xy 119.488711 -234.182217) (xy 119.480586 -234.233512)
			(xy 119.464538 -234.282905) (xy 119.44096 -234.329179) (xy 119.410434 -234.371195) (xy 119.373711 -234.407918)
			(xy 119.331695 -234.438444) (xy 119.285421 -234.462022) (xy 119.236028 -234.47807) (xy 119.184733 -234.486195)
			(xy 119.132799 -234.486195) (xy 119.081504 -234.47807) (xy 119.032111 -234.462022) (xy 118.985837 -234.438444)
			(xy 118.943821 -234.407918) (xy 118.907098 -234.371195) (xy 118.876572 -234.329179) (xy 118.852994 -234.282905)
			(xy 118.836946 -234.233512) (xy 118.828821 -234.182217) (xy 118.548911 -234.182217) (xy 118.540786 -234.233512)
			(xy 118.524738 -234.282905) (xy 118.50116 -234.329179) (xy 118.470634 -234.371195) (xy 118.433911 -234.407918)
			(xy 118.391895 -234.438444) (xy 118.345621 -234.462022) (xy 118.296228 -234.47807) (xy 118.244933 -234.486195)
			(xy 118.192999 -234.486195) (xy 118.141704 -234.47807) (xy 118.092311 -234.462022) (xy 118.046037 -234.438444)
			(xy 118.004021 -234.407918) (xy 117.967298 -234.371195) (xy 117.936772 -234.329179) (xy 117.913194 -234.282905)
			(xy 117.897146 -234.233512) (xy 117.889021 -234.182217) (xy 117.609111 -234.182217) (xy 117.600986 -234.233512)
			(xy 117.584938 -234.282905) (xy 117.56136 -234.329179) (xy 117.530834 -234.371195) (xy 117.494111 -234.407918)
			(xy 117.452095 -234.438444) (xy 117.405821 -234.462022) (xy 117.356428 -234.47807) (xy 117.305133 -234.486195)
			(xy 117.253199 -234.486195) (xy 117.201904 -234.47807) (xy 117.152511 -234.462022) (xy 117.106237 -234.438444)
			(xy 117.064221 -234.407918) (xy 117.027498 -234.371195) (xy 116.996972 -234.329179) (xy 116.973394 -234.282905)
			(xy 116.957346 -234.233512) (xy 116.949221 -234.182217) (xy 116.669311 -234.182217) (xy 116.661186 -234.233512)
			(xy 116.645138 -234.282905) (xy 116.62156 -234.329179) (xy 116.591034 -234.371195) (xy 116.554311 -234.407918)
			(xy 116.512295 -234.438444) (xy 116.466021 -234.462022) (xy 116.416628 -234.47807) (xy 116.365333 -234.486195)
			(xy 116.313399 -234.486195) (xy 116.262104 -234.47807) (xy 116.212711 -234.462022) (xy 116.166437 -234.438444)
			(xy 116.124421 -234.407918) (xy 116.087698 -234.371195) (xy 116.057172 -234.329179) (xy 116.033594 -234.282905)
			(xy 116.017546 -234.233512) (xy 116.009421 -234.182217) (xy 115.729511 -234.182217) (xy 115.721386 -234.233512)
			(xy 115.705338 -234.282905) (xy 115.68176 -234.329179) (xy 115.651234 -234.371195) (xy 115.614511 -234.407918)
			(xy 115.572495 -234.438444) (xy 115.526221 -234.462022) (xy 115.476828 -234.47807) (xy 115.425533 -234.486195)
			(xy 115.373599 -234.486195) (xy 115.322304 -234.47807) (xy 115.272911 -234.462022) (xy 115.226637 -234.438444)
			(xy 115.184621 -234.407918) (xy 115.147898 -234.371195) (xy 115.117372 -234.329179) (xy 115.093794 -234.282905)
			(xy 115.077746 -234.233512) (xy 115.069621 -234.182217) (xy 114.789711 -234.182217) (xy 114.781586 -234.233512)
			(xy 114.765538 -234.282905) (xy 114.74196 -234.329179) (xy 114.711434 -234.371195) (xy 114.674711 -234.407918)
			(xy 114.632695 -234.438444) (xy 114.586421 -234.462022) (xy 114.537028 -234.47807) (xy 114.485733 -234.486195)
			(xy 114.433799 -234.486195) (xy 114.382504 -234.47807) (xy 114.333111 -234.462022) (xy 114.286837 -234.438444)
			(xy 114.244821 -234.407918) (xy 114.208098 -234.371195) (xy 114.177572 -234.329179) (xy 114.153994 -234.282905)
			(xy 114.137946 -234.233512) (xy 114.129821 -234.182217) (xy 113.849911 -234.182217) (xy 113.841786 -234.233512)
			(xy 113.825738 -234.282905) (xy 113.80216 -234.329179) (xy 113.771634 -234.371195) (xy 113.734911 -234.407918)
			(xy 113.692895 -234.438444) (xy 113.646621 -234.462022) (xy 113.597228 -234.47807) (xy 113.545933 -234.486195)
			(xy 113.493999 -234.486195) (xy 113.442704 -234.47807) (xy 113.393311 -234.462022) (xy 113.347037 -234.438444)
			(xy 113.305021 -234.407918) (xy 113.268298 -234.371195) (xy 113.237772 -234.329179) (xy 113.214194 -234.282905)
			(xy 113.198146 -234.233512) (xy 113.190021 -234.182217) (xy 112.910111 -234.182217) (xy 112.901986 -234.233512)
			(xy 112.885938 -234.282905) (xy 112.86236 -234.329179) (xy 112.831834 -234.371195) (xy 112.795111 -234.407918)
			(xy 112.753095 -234.438444) (xy 112.706821 -234.462022) (xy 112.657428 -234.47807) (xy 112.606133 -234.486195)
			(xy 112.554199 -234.486195) (xy 112.502904 -234.47807) (xy 112.453511 -234.462022) (xy 112.407237 -234.438444)
			(xy 112.365221 -234.407918) (xy 112.328498 -234.371195) (xy 112.297972 -234.329179) (xy 112.274394 -234.282905)
			(xy 112.258346 -234.233512) (xy 112.250221 -234.182217) (xy 111.970311 -234.182217) (xy 111.962186 -234.233512)
			(xy 111.946138 -234.282905) (xy 111.92256 -234.329179) (xy 111.892034 -234.371195) (xy 111.855311 -234.407918)
			(xy 111.813295 -234.438444) (xy 111.767021 -234.462022) (xy 111.717628 -234.47807) (xy 111.666333 -234.486195)
			(xy 111.614399 -234.486195) (xy 111.563104 -234.47807) (xy 111.513711 -234.462022) (xy 111.467437 -234.438444)
			(xy 111.425421 -234.407918) (xy 111.388698 -234.371195) (xy 111.358172 -234.329179) (xy 111.334594 -234.282905)
			(xy 111.318546 -234.233512) (xy 111.310421 -234.182217) (xy 111.030511 -234.182217) (xy 111.022386 -234.233512)
			(xy 111.006338 -234.282905) (xy 110.98276 -234.329179) (xy 110.952234 -234.371195) (xy 110.915511 -234.407918)
			(xy 110.873495 -234.438444) (xy 110.827221 -234.462022) (xy 110.777828 -234.47807) (xy 110.726533 -234.486195)
			(xy 110.674599 -234.486195) (xy 110.623304 -234.47807) (xy 110.573911 -234.462022) (xy 110.527637 -234.438444)
			(xy 110.485621 -234.407918) (xy 110.448898 -234.371195) (xy 110.418372 -234.329179) (xy 110.394794 -234.282905)
			(xy 110.378746 -234.233512) (xy 110.370621 -234.182217) (xy 110.090711 -234.182217) (xy 110.082586 -234.233512)
			(xy 110.066538 -234.282905) (xy 110.04296 -234.329179) (xy 110.012434 -234.371195) (xy 109.975711 -234.407918)
			(xy 109.933695 -234.438444) (xy 109.887421 -234.462022) (xy 109.838028 -234.47807) (xy 109.786733 -234.486195)
			(xy 109.734799 -234.486195) (xy 109.683504 -234.47807) (xy 109.634111 -234.462022) (xy 109.587837 -234.438444)
			(xy 109.545821 -234.407918) (xy 109.509098 -234.371195) (xy 109.478572 -234.329179) (xy 109.454994 -234.282905)
			(xy 109.438946 -234.233512) (xy 109.430821 -234.182217) (xy 109.150911 -234.182217) (xy 109.142786 -234.233512)
			(xy 109.126738 -234.282905) (xy 109.10316 -234.329179) (xy 109.072634 -234.371195) (xy 109.035911 -234.407918)
			(xy 108.993895 -234.438444) (xy 108.947621 -234.462022) (xy 108.898228 -234.47807) (xy 108.846933 -234.486195)
			(xy 108.794999 -234.486195) (xy 108.743704 -234.47807) (xy 108.694311 -234.462022) (xy 108.648037 -234.438444)
			(xy 108.606021 -234.407918) (xy 108.569298 -234.371195) (xy 108.538772 -234.329179) (xy 108.515194 -234.282905)
			(xy 108.499146 -234.233512) (xy 108.491021 -234.182217) (xy 108.211111 -234.182217) (xy 108.202986 -234.233512)
			(xy 108.186938 -234.282905) (xy 108.16336 -234.329179) (xy 108.132834 -234.371195) (xy 108.096111 -234.407918)
			(xy 108.054095 -234.438444) (xy 108.007821 -234.462022) (xy 107.958428 -234.47807) (xy 107.907133 -234.486195)
			(xy 107.855199 -234.486195) (xy 107.803904 -234.47807) (xy 107.754511 -234.462022) (xy 107.708237 -234.438444)
			(xy 107.666221 -234.407918) (xy 107.629498 -234.371195) (xy 107.598972 -234.329179) (xy 107.575394 -234.282905)
			(xy 107.559346 -234.233512) (xy 107.551221 -234.182217) (xy 107.271311 -234.182217) (xy 107.263186 -234.233512)
			(xy 107.247138 -234.282905) (xy 107.22356 -234.329179) (xy 107.193034 -234.371195) (xy 107.156311 -234.407918)
			(xy 107.114295 -234.438444) (xy 107.068021 -234.462022) (xy 107.018628 -234.47807) (xy 106.967333 -234.486195)
			(xy 106.915399 -234.486195) (xy 106.864104 -234.47807) (xy 106.814711 -234.462022) (xy 106.768437 -234.438444)
			(xy 106.726421 -234.407918) (xy 106.689698 -234.371195) (xy 106.659172 -234.329179) (xy 106.635594 -234.282905)
			(xy 106.619546 -234.233512) (xy 106.611421 -234.182217) (xy 106.331511 -234.182217) (xy 106.323386 -234.233512)
			(xy 106.307338 -234.282905) (xy 106.28376 -234.329179) (xy 106.253234 -234.371195) (xy 106.216511 -234.407918)
			(xy 106.174495 -234.438444) (xy 106.128221 -234.462022) (xy 106.078828 -234.47807) (xy 106.027533 -234.486195)
			(xy 105.975599 -234.486195) (xy 105.924304 -234.47807) (xy 105.874911 -234.462022) (xy 105.828637 -234.438444)
			(xy 105.786621 -234.407918) (xy 105.749898 -234.371195) (xy 105.719372 -234.329179) (xy 105.695794 -234.282905)
			(xy 105.679746 -234.233512) (xy 105.671621 -234.182217) (xy 105.414572 -234.182217) (xy 105.414572 -234.996033)
			(xy 108.960921 -234.996033) (xy 108.960921 -234.944099) (xy 108.969046 -234.892804) (xy 108.985094 -234.843411)
			(xy 109.008672 -234.797137) (xy 109.039198 -234.755121) (xy 109.075921 -234.718398) (xy 109.117937 -234.687872)
			(xy 109.164211 -234.664294) (xy 109.213604 -234.648246) (xy 109.264899 -234.640121) (xy 109.316833 -234.640121)
			(xy 109.368128 -234.648246) (xy 109.417521 -234.664294) (xy 109.463795 -234.687872) (xy 109.505811 -234.718398)
			(xy 109.542534 -234.755121) (xy 109.57306 -234.797137) (xy 109.596638 -234.843411) (xy 109.612686 -234.892804)
			(xy 109.620811 -234.944099) (xy 109.62132 -234.970066) (xy 109.620811 -234.996033) (xy 109.900975 -234.996033)
			(xy 109.900975 -234.944099) (xy 109.9091 -234.892804) (xy 109.925148 -234.843411) (xy 109.948726 -234.797137)
			(xy 109.979252 -234.755121) (xy 110.015975 -234.718398) (xy 110.057991 -234.687872) (xy 110.104265 -234.664294)
			(xy 110.153658 -234.648246) (xy 110.204953 -234.640121) (xy 110.256887 -234.640121) (xy 110.308182 -234.648246)
			(xy 110.357575 -234.664294) (xy 110.403849 -234.687872) (xy 110.445865 -234.718398) (xy 110.482588 -234.755121)
			(xy 110.513114 -234.797137) (xy 110.536692 -234.843411) (xy 110.55274 -234.892804) (xy 110.560865 -234.944099)
			(xy 110.561374 -234.970066) (xy 110.560865 -234.996033) (xy 110.840521 -234.996033) (xy 110.840521 -234.944099)
			(xy 110.848646 -234.892804) (xy 110.864694 -234.843411) (xy 110.888272 -234.797137) (xy 110.918798 -234.755121)
			(xy 110.955521 -234.718398) (xy 110.997537 -234.687872) (xy 111.043811 -234.664294) (xy 111.093204 -234.648246)
			(xy 111.144499 -234.640121) (xy 111.196433 -234.640121) (xy 111.247728 -234.648246) (xy 111.297121 -234.664294)
			(xy 111.343395 -234.687872) (xy 111.385411 -234.718398) (xy 111.422134 -234.755121) (xy 111.45266 -234.797137)
			(xy 111.476238 -234.843411) (xy 111.492286 -234.892804) (xy 111.500411 -234.944099) (xy 111.50092 -234.970066)
			(xy 111.500411 -234.996033) (xy 111.780321 -234.996033) (xy 111.780321 -234.944099) (xy 111.788446 -234.892804)
			(xy 111.804494 -234.843411) (xy 111.828072 -234.797137) (xy 111.858598 -234.755121) (xy 111.895321 -234.718398)
			(xy 111.937337 -234.687872) (xy 111.983611 -234.664294) (xy 112.033004 -234.648246) (xy 112.084299 -234.640121)
			(xy 112.136233 -234.640121) (xy 112.187528 -234.648246) (xy 112.236921 -234.664294) (xy 112.283195 -234.687872)
			(xy 112.325211 -234.718398) (xy 112.361934 -234.755121) (xy 112.39246 -234.797137) (xy 112.416038 -234.843411)
			(xy 112.432086 -234.892804) (xy 112.440211 -234.944099) (xy 112.44072 -234.970066) (xy 112.440211 -234.996033)
			(xy 112.720121 -234.996033) (xy 112.720121 -234.944099) (xy 112.728246 -234.892804) (xy 112.744294 -234.843411)
			(xy 112.767872 -234.797137) (xy 112.798398 -234.755121) (xy 112.835121 -234.718398) (xy 112.877137 -234.687872)
			(xy 112.923411 -234.664294) (xy 112.972804 -234.648246) (xy 113.024099 -234.640121) (xy 113.076033 -234.640121)
			(xy 113.127328 -234.648246) (xy 113.176721 -234.664294) (xy 113.222995 -234.687872) (xy 113.265011 -234.718398)
			(xy 113.301734 -234.755121) (xy 113.33226 -234.797137) (xy 113.355838 -234.843411) (xy 113.371886 -234.892804)
			(xy 113.380011 -234.944099) (xy 113.38052 -234.970066) (xy 113.380011 -234.996033) (xy 113.660175 -234.996033)
			(xy 113.660175 -234.944099) (xy 113.6683 -234.892804) (xy 113.684348 -234.843411) (xy 113.707926 -234.797137)
			(xy 113.738452 -234.755121) (xy 113.775175 -234.718398) (xy 113.817191 -234.687872) (xy 113.863465 -234.664294)
			(xy 113.912858 -234.648246) (xy 113.964153 -234.640121) (xy 114.016087 -234.640121) (xy 114.067382 -234.648246)
			(xy 114.116775 -234.664294) (xy 114.163049 -234.687872) (xy 114.205065 -234.718398) (xy 114.241788 -234.755121)
			(xy 114.272314 -234.797137) (xy 114.295892 -234.843411) (xy 114.31194 -234.892804) (xy 114.320065 -234.944099)
			(xy 114.320574 -234.970066) (xy 114.320065 -234.996033) (xy 121.178067 -234.996033) (xy 121.178067 -234.944099)
			(xy 121.186192 -234.892804) (xy 121.20224 -234.843411) (xy 121.225818 -234.797137) (xy 121.256344 -234.755121)
			(xy 121.293067 -234.718398) (xy 121.335083 -234.687872) (xy 121.381357 -234.664294) (xy 121.43075 -234.648246)
			(xy 121.482045 -234.640121) (xy 121.533979 -234.640121) (xy 121.585274 -234.648246) (xy 121.634667 -234.664294)
			(xy 121.680941 -234.687872) (xy 121.722957 -234.718398) (xy 121.75968 -234.755121) (xy 121.790206 -234.797137)
			(xy 121.813784 -234.843411) (xy 121.829832 -234.892804) (xy 121.837957 -234.944099) (xy 121.838466 -234.970066)
			(xy 121.837957 -234.996033) (xy 122.117867 -234.996033) (xy 122.117867 -234.944099) (xy 122.125992 -234.892804)
			(xy 122.14204 -234.843411) (xy 122.165618 -234.797137) (xy 122.196144 -234.755121) (xy 122.232867 -234.718398)
			(xy 122.274883 -234.687872) (xy 122.321157 -234.664294) (xy 122.37055 -234.648246) (xy 122.421845 -234.640121)
			(xy 122.473779 -234.640121) (xy 122.525074 -234.648246) (xy 122.574467 -234.664294) (xy 122.620741 -234.687872)
			(xy 122.662757 -234.718398) (xy 122.69948 -234.755121) (xy 122.730006 -234.797137) (xy 122.753584 -234.843411)
			(xy 122.769632 -234.892804) (xy 122.777757 -234.944099) (xy 122.778266 -234.970066) (xy 122.777757 -234.996033)
			(xy 123.057667 -234.996033) (xy 123.057667 -234.944099) (xy 123.065792 -234.892804) (xy 123.08184 -234.843411)
			(xy 123.105418 -234.797137) (xy 123.135944 -234.755121) (xy 123.172667 -234.718398) (xy 123.214683 -234.687872)
			(xy 123.260957 -234.664294) (xy 123.31035 -234.648246) (xy 123.361645 -234.640121) (xy 123.413579 -234.640121)
			(xy 123.464874 -234.648246) (xy 123.514267 -234.664294) (xy 123.560541 -234.687872) (xy 123.602557 -234.718398)
			(xy 123.63928 -234.755121) (xy 123.669806 -234.797137) (xy 123.693384 -234.843411) (xy 123.709432 -234.892804)
			(xy 123.717557 -234.944099) (xy 123.718066 -234.970066) (xy 123.717557 -234.996033) (xy 123.997467 -234.996033)
			(xy 123.997467 -234.944099) (xy 124.005592 -234.892804) (xy 124.02164 -234.843411) (xy 124.045218 -234.797137)
			(xy 124.075744 -234.755121) (xy 124.112467 -234.718398) (xy 124.154483 -234.687872) (xy 124.200757 -234.664294)
			(xy 124.25015 -234.648246) (xy 124.301445 -234.640121) (xy 124.353379 -234.640121) (xy 124.404674 -234.648246)
			(xy 124.454067 -234.664294) (xy 124.500341 -234.687872) (xy 124.542357 -234.718398) (xy 124.57908 -234.755121)
			(xy 124.609606 -234.797137) (xy 124.633184 -234.843411) (xy 124.649232 -234.892804) (xy 124.657357 -234.944099)
			(xy 124.657866 -234.970066) (xy 124.657357 -234.996033) (xy 124.937521 -234.996033) (xy 124.937521 -234.944099)
			(xy 124.945646 -234.892804) (xy 124.961694 -234.843411) (xy 124.985272 -234.797137) (xy 125.015798 -234.755121)
			(xy 125.052521 -234.718398) (xy 125.094537 -234.687872) (xy 125.140811 -234.664294) (xy 125.190204 -234.648246)
			(xy 125.241499 -234.640121) (xy 125.293433 -234.640121) (xy 125.344728 -234.648246) (xy 125.394121 -234.664294)
			(xy 125.440395 -234.687872) (xy 125.482411 -234.718398) (xy 125.519134 -234.755121) (xy 125.54966 -234.797137)
			(xy 125.573238 -234.843411) (xy 125.589286 -234.892804) (xy 125.597411 -234.944099) (xy 125.59792 -234.970066)
			(xy 125.597411 -234.996033) (xy 125.877067 -234.996033) (xy 125.877067 -234.944099) (xy 125.885192 -234.892804)
			(xy 125.90124 -234.843411) (xy 125.924818 -234.797137) (xy 125.955344 -234.755121) (xy 125.992067 -234.718398)
			(xy 126.034083 -234.687872) (xy 126.080357 -234.664294) (xy 126.12975 -234.648246) (xy 126.181045 -234.640121)
			(xy 126.232979 -234.640121) (xy 126.284274 -234.648246) (xy 126.333667 -234.664294) (xy 126.379941 -234.687872)
			(xy 126.421957 -234.718398) (xy 126.45868 -234.755121) (xy 126.489206 -234.797137) (xy 126.512784 -234.843411)
			(xy 126.528832 -234.892804) (xy 126.536957 -234.944099) (xy 126.537466 -234.970066) (xy 126.536957 -234.996033)
			(xy 126.816867 -234.996033) (xy 126.816867 -234.944099) (xy 126.824992 -234.892804) (xy 126.84104 -234.843411)
			(xy 126.864618 -234.797137) (xy 126.895144 -234.755121) (xy 126.931867 -234.718398) (xy 126.973883 -234.687872)
			(xy 127.020157 -234.664294) (xy 127.06955 -234.648246) (xy 127.120845 -234.640121) (xy 127.172779 -234.640121)
			(xy 127.224074 -234.648246) (xy 127.273467 -234.664294) (xy 127.319741 -234.687872) (xy 127.361757 -234.718398)
			(xy 127.39848 -234.755121) (xy 127.429006 -234.797137) (xy 127.452584 -234.843411) (xy 127.468632 -234.892804)
			(xy 127.476757 -234.944099) (xy 127.477266 -234.970066) (xy 127.476757 -234.996033) (xy 127.756667 -234.996033)
			(xy 127.756667 -234.944099) (xy 127.764792 -234.892804) (xy 127.78084 -234.843411) (xy 127.804418 -234.797137)
			(xy 127.834944 -234.755121) (xy 127.871667 -234.718398) (xy 127.913683 -234.687872) (xy 127.959957 -234.664294)
			(xy 128.00935 -234.648246) (xy 128.060645 -234.640121) (xy 128.112579 -234.640121) (xy 128.163874 -234.648246)
			(xy 128.213267 -234.664294) (xy 128.259541 -234.687872) (xy 128.301557 -234.718398) (xy 128.33828 -234.755121)
			(xy 128.368806 -234.797137) (xy 128.392384 -234.843411) (xy 128.408432 -234.892804) (xy 128.416557 -234.944099)
			(xy 128.417066 -234.970066) (xy 128.416557 -234.996033) (xy 128.696467 -234.996033) (xy 128.696467 -234.944099)
			(xy 128.704592 -234.892804) (xy 128.72064 -234.843411) (xy 128.744218 -234.797137) (xy 128.774744 -234.755121)
			(xy 128.811467 -234.718398) (xy 128.853483 -234.687872) (xy 128.899757 -234.664294) (xy 128.94915 -234.648246)
			(xy 129.000445 -234.640121) (xy 129.052379 -234.640121) (xy 129.103674 -234.648246) (xy 129.153067 -234.664294)
			(xy 129.199341 -234.687872) (xy 129.241357 -234.718398) (xy 129.27808 -234.755121) (xy 129.308606 -234.797137)
			(xy 129.332184 -234.843411) (xy 129.348232 -234.892804) (xy 129.356357 -234.944099) (xy 129.356866 -234.970066)
			(xy 129.356357 -234.996033) (xy 129.636267 -234.996033) (xy 129.636267 -234.944099) (xy 129.644392 -234.892804)
			(xy 129.66044 -234.843411) (xy 129.684018 -234.797137) (xy 129.714544 -234.755121) (xy 129.751267 -234.718398)
			(xy 129.793283 -234.687872) (xy 129.839557 -234.664294) (xy 129.88895 -234.648246) (xy 129.940245 -234.640121)
			(xy 129.992179 -234.640121) (xy 130.043474 -234.648246) (xy 130.092867 -234.664294) (xy 130.139141 -234.687872)
			(xy 130.181157 -234.718398) (xy 130.21788 -234.755121) (xy 130.248406 -234.797137) (xy 130.271984 -234.843411)
			(xy 130.288032 -234.892804) (xy 130.296157 -234.944099) (xy 130.296666 -234.970066) (xy 130.296157 -234.996033)
			(xy 130.576067 -234.996033) (xy 130.576067 -234.944099) (xy 130.584192 -234.892804) (xy 130.60024 -234.843411)
			(xy 130.623818 -234.797137) (xy 130.654344 -234.755121) (xy 130.691067 -234.718398) (xy 130.733083 -234.687872)
			(xy 130.779357 -234.664294) (xy 130.82875 -234.648246) (xy 130.880045 -234.640121) (xy 130.931979 -234.640121)
			(xy 130.983274 -234.648246) (xy 131.032667 -234.664294) (xy 131.078941 -234.687872) (xy 131.120957 -234.718398)
			(xy 131.15768 -234.755121) (xy 131.188206 -234.797137) (xy 131.211784 -234.843411) (xy 131.227832 -234.892804)
			(xy 131.235957 -234.944099) (xy 131.236466 -234.970066) (xy 131.235957 -234.996033) (xy 131.227832 -235.047328)
			(xy 131.211784 -235.096721) (xy 131.188206 -235.142995) (xy 131.15768 -235.185011) (xy 131.120957 -235.221734)
			(xy 131.078941 -235.25226) (xy 131.032667 -235.275838) (xy 130.983274 -235.291886) (xy 130.931979 -235.300011)
			(xy 130.880045 -235.300011) (xy 130.82875 -235.291886) (xy 130.779357 -235.275838) (xy 130.733083 -235.25226)
			(xy 130.691067 -235.221734) (xy 130.654344 -235.185011) (xy 130.623818 -235.142995) (xy 130.60024 -235.096721)
			(xy 130.584192 -235.047328) (xy 130.576067 -234.996033) (xy 130.296157 -234.996033) (xy 130.288032 -235.047328)
			(xy 130.271984 -235.096721) (xy 130.248406 -235.142995) (xy 130.21788 -235.185011) (xy 130.181157 -235.221734)
			(xy 130.139141 -235.25226) (xy 130.092867 -235.275838) (xy 130.043474 -235.291886) (xy 129.992179 -235.300011)
			(xy 129.940245 -235.300011) (xy 129.88895 -235.291886) (xy 129.839557 -235.275838) (xy 129.793283 -235.25226)
			(xy 129.751267 -235.221734) (xy 129.714544 -235.185011) (xy 129.684018 -235.142995) (xy 129.66044 -235.096721)
			(xy 129.644392 -235.047328) (xy 129.636267 -234.996033) (xy 129.356357 -234.996033) (xy 129.348232 -235.047328)
			(xy 129.332184 -235.096721) (xy 129.308606 -235.142995) (xy 129.27808 -235.185011) (xy 129.241357 -235.221734)
			(xy 129.199341 -235.25226) (xy 129.153067 -235.275838) (xy 129.103674 -235.291886) (xy 129.052379 -235.300011)
			(xy 129.000445 -235.300011) (xy 128.94915 -235.291886) (xy 128.899757 -235.275838) (xy 128.853483 -235.25226)
			(xy 128.811467 -235.221734) (xy 128.774744 -235.185011) (xy 128.744218 -235.142995) (xy 128.72064 -235.096721)
			(xy 128.704592 -235.047328) (xy 128.696467 -234.996033) (xy 128.416557 -234.996033) (xy 128.408432 -235.047328)
			(xy 128.392384 -235.096721) (xy 128.368806 -235.142995) (xy 128.33828 -235.185011) (xy 128.301557 -235.221734)
			(xy 128.259541 -235.25226) (xy 128.213267 -235.275838) (xy 128.163874 -235.291886) (xy 128.112579 -235.300011)
			(xy 128.060645 -235.300011) (xy 128.00935 -235.291886) (xy 127.959957 -235.275838) (xy 127.913683 -235.25226)
			(xy 127.871667 -235.221734) (xy 127.834944 -235.185011) (xy 127.804418 -235.142995) (xy 127.78084 -235.096721)
			(xy 127.764792 -235.047328) (xy 127.756667 -234.996033) (xy 127.476757 -234.996033) (xy 127.468632 -235.047328)
			(xy 127.452584 -235.096721) (xy 127.429006 -235.142995) (xy 127.39848 -235.185011) (xy 127.361757 -235.221734)
			(xy 127.319741 -235.25226) (xy 127.273467 -235.275838) (xy 127.224074 -235.291886) (xy 127.172779 -235.300011)
			(xy 127.120845 -235.300011) (xy 127.06955 -235.291886) (xy 127.020157 -235.275838) (xy 126.973883 -235.25226)
			(xy 126.931867 -235.221734) (xy 126.895144 -235.185011) (xy 126.864618 -235.142995) (xy 126.84104 -235.096721)
			(xy 126.824992 -235.047328) (xy 126.816867 -234.996033) (xy 126.536957 -234.996033) (xy 126.528832 -235.047328)
			(xy 126.512784 -235.096721) (xy 126.489206 -235.142995) (xy 126.45868 -235.185011) (xy 126.421957 -235.221734)
			(xy 126.379941 -235.25226) (xy 126.333667 -235.275838) (xy 126.284274 -235.291886) (xy 126.232979 -235.300011)
			(xy 126.181045 -235.300011) (xy 126.12975 -235.291886) (xy 126.080357 -235.275838) (xy 126.034083 -235.25226)
			(xy 125.992067 -235.221734) (xy 125.955344 -235.185011) (xy 125.924818 -235.142995) (xy 125.90124 -235.096721)
			(xy 125.885192 -235.047328) (xy 125.877067 -234.996033) (xy 125.597411 -234.996033) (xy 125.589286 -235.047328)
			(xy 125.573238 -235.096721) (xy 125.54966 -235.142995) (xy 125.519134 -235.185011) (xy 125.482411 -235.221734)
			(xy 125.440395 -235.25226) (xy 125.394121 -235.275838) (xy 125.344728 -235.291886) (xy 125.293433 -235.300011)
			(xy 125.241499 -235.300011) (xy 125.190204 -235.291886) (xy 125.140811 -235.275838) (xy 125.094537 -235.25226)
			(xy 125.052521 -235.221734) (xy 125.015798 -235.185011) (xy 124.985272 -235.142995) (xy 124.961694 -235.096721)
			(xy 124.945646 -235.047328) (xy 124.937521 -234.996033) (xy 124.657357 -234.996033) (xy 124.649232 -235.047328)
			(xy 124.633184 -235.096721) (xy 124.609606 -235.142995) (xy 124.57908 -235.185011) (xy 124.542357 -235.221734)
			(xy 124.500341 -235.25226) (xy 124.454067 -235.275838) (xy 124.404674 -235.291886) (xy 124.353379 -235.300011)
			(xy 124.301445 -235.300011) (xy 124.25015 -235.291886) (xy 124.200757 -235.275838) (xy 124.154483 -235.25226)
			(xy 124.112467 -235.221734) (xy 124.075744 -235.185011) (xy 124.045218 -235.142995) (xy 124.02164 -235.096721)
			(xy 124.005592 -235.047328) (xy 123.997467 -234.996033) (xy 123.717557 -234.996033) (xy 123.709432 -235.047328)
			(xy 123.693384 -235.096721) (xy 123.669806 -235.142995) (xy 123.63928 -235.185011) (xy 123.602557 -235.221734)
			(xy 123.560541 -235.25226) (xy 123.514267 -235.275838) (xy 123.464874 -235.291886) (xy 123.413579 -235.300011)
			(xy 123.361645 -235.300011) (xy 123.31035 -235.291886) (xy 123.260957 -235.275838) (xy 123.214683 -235.25226)
			(xy 123.172667 -235.221734) (xy 123.135944 -235.185011) (xy 123.105418 -235.142995) (xy 123.08184 -235.096721)
			(xy 123.065792 -235.047328) (xy 123.057667 -234.996033) (xy 122.777757 -234.996033) (xy 122.769632 -235.047328)
			(xy 122.753584 -235.096721) (xy 122.730006 -235.142995) (xy 122.69948 -235.185011) (xy 122.662757 -235.221734)
			(xy 122.620741 -235.25226) (xy 122.574467 -235.275838) (xy 122.525074 -235.291886) (xy 122.473779 -235.300011)
			(xy 122.421845 -235.300011) (xy 122.37055 -235.291886) (xy 122.321157 -235.275838) (xy 122.274883 -235.25226)
			(xy 122.232867 -235.221734) (xy 122.196144 -235.185011) (xy 122.165618 -235.142995) (xy 122.14204 -235.096721)
			(xy 122.125992 -235.047328) (xy 122.117867 -234.996033) (xy 121.837957 -234.996033) (xy 121.829832 -235.047328)
			(xy 121.813784 -235.096721) (xy 121.790206 -235.142995) (xy 121.75968 -235.185011) (xy 121.722957 -235.221734)
			(xy 121.680941 -235.25226) (xy 121.634667 -235.275838) (xy 121.585274 -235.291886) (xy 121.533979 -235.300011)
			(xy 121.482045 -235.300011) (xy 121.43075 -235.291886) (xy 121.381357 -235.275838) (xy 121.335083 -235.25226)
			(xy 121.293067 -235.221734) (xy 121.256344 -235.185011) (xy 121.225818 -235.142995) (xy 121.20224 -235.096721)
			(xy 121.186192 -235.047328) (xy 121.178067 -234.996033) (xy 114.320065 -234.996033) (xy 114.31194 -235.047328)
			(xy 114.295892 -235.096721) (xy 114.272314 -235.142995) (xy 114.241788 -235.185011) (xy 114.205065 -235.221734)
			(xy 114.163049 -235.25226) (xy 114.116775 -235.275838) (xy 114.067382 -235.291886) (xy 114.016087 -235.300011)
			(xy 113.964153 -235.300011) (xy 113.912858 -235.291886) (xy 113.863465 -235.275838) (xy 113.817191 -235.25226)
			(xy 113.775175 -235.221734) (xy 113.738452 -235.185011) (xy 113.707926 -235.142995) (xy 113.684348 -235.096721)
			(xy 113.6683 -235.047328) (xy 113.660175 -234.996033) (xy 113.380011 -234.996033) (xy 113.371886 -235.047328)
			(xy 113.355838 -235.096721) (xy 113.33226 -235.142995) (xy 113.301734 -235.185011) (xy 113.265011 -235.221734)
			(xy 113.222995 -235.25226) (xy 113.176721 -235.275838) (xy 113.127328 -235.291886) (xy 113.076033 -235.300011)
			(xy 113.024099 -235.300011) (xy 112.972804 -235.291886) (xy 112.923411 -235.275838) (xy 112.877137 -235.25226)
			(xy 112.835121 -235.221734) (xy 112.798398 -235.185011) (xy 112.767872 -235.142995) (xy 112.744294 -235.096721)
			(xy 112.728246 -235.047328) (xy 112.720121 -234.996033) (xy 112.440211 -234.996033) (xy 112.432086 -235.047328)
			(xy 112.416038 -235.096721) (xy 112.39246 -235.142995) (xy 112.361934 -235.185011) (xy 112.325211 -235.221734)
			(xy 112.283195 -235.25226) (xy 112.236921 -235.275838) (xy 112.187528 -235.291886) (xy 112.136233 -235.300011)
			(xy 112.084299 -235.300011) (xy 112.033004 -235.291886) (xy 111.983611 -235.275838) (xy 111.937337 -235.25226)
			(xy 111.895321 -235.221734) (xy 111.858598 -235.185011) (xy 111.828072 -235.142995) (xy 111.804494 -235.096721)
			(xy 111.788446 -235.047328) (xy 111.780321 -234.996033) (xy 111.500411 -234.996033) (xy 111.492286 -235.047328)
			(xy 111.476238 -235.096721) (xy 111.45266 -235.142995) (xy 111.422134 -235.185011) (xy 111.385411 -235.221734)
			(xy 111.343395 -235.25226) (xy 111.297121 -235.275838) (xy 111.247728 -235.291886) (xy 111.196433 -235.300011)
			(xy 111.144499 -235.300011) (xy 111.093204 -235.291886) (xy 111.043811 -235.275838) (xy 110.997537 -235.25226)
			(xy 110.955521 -235.221734) (xy 110.918798 -235.185011) (xy 110.888272 -235.142995) (xy 110.864694 -235.096721)
			(xy 110.848646 -235.047328) (xy 110.840521 -234.996033) (xy 110.560865 -234.996033) (xy 110.55274 -235.047328)
			(xy 110.536692 -235.096721) (xy 110.513114 -235.142995) (xy 110.482588 -235.185011) (xy 110.445865 -235.221734)
			(xy 110.403849 -235.25226) (xy 110.357575 -235.275838) (xy 110.308182 -235.291886) (xy 110.256887 -235.300011)
			(xy 110.204953 -235.300011) (xy 110.153658 -235.291886) (xy 110.104265 -235.275838) (xy 110.057991 -235.25226)
			(xy 110.015975 -235.221734) (xy 109.979252 -235.185011) (xy 109.948726 -235.142995) (xy 109.925148 -235.096721)
			(xy 109.9091 -235.047328) (xy 109.900975 -234.996033) (xy 109.620811 -234.996033) (xy 109.612686 -235.047328)
			(xy 109.596638 -235.096721) (xy 109.57306 -235.142995) (xy 109.542534 -235.185011) (xy 109.505811 -235.221734)
			(xy 109.463795 -235.25226) (xy 109.417521 -235.275838) (xy 109.368128 -235.291886) (xy 109.316833 -235.300011)
			(xy 109.264899 -235.300011) (xy 109.213604 -235.291886) (xy 109.164211 -235.275838) (xy 109.117937 -235.25226)
			(xy 109.075921 -235.221734) (xy 109.039198 -235.185011) (xy 109.008672 -235.142995) (xy 108.985094 -235.096721)
			(xy 108.969046 -235.047328) (xy 108.960921 -234.996033) (xy 105.414572 -234.996033) (xy 105.414572 -235.457551)
			(xy 105.900221 -235.457551) (xy 105.900221 -235.405617) (xy 105.908346 -235.354322) (xy 105.924394 -235.304929)
			(xy 105.947972 -235.258655) (xy 105.978498 -235.216639) (xy 106.015221 -235.179916) (xy 106.057237 -235.14939)
			(xy 106.103511 -235.125812) (xy 106.152904 -235.109764) (xy 106.204199 -235.101639) (xy 106.256133 -235.101639)
			(xy 106.307428 -235.109764) (xy 106.356821 -235.125812) (xy 106.403095 -235.14939) (xy 106.445111 -235.179916)
			(xy 106.481834 -235.216639) (xy 106.51236 -235.258655) (xy 106.535938 -235.304929) (xy 106.551986 -235.354322)
			(xy 106.560111 -235.405617) (xy 106.56062 -235.431584) (xy 106.560111 -235.457551) (xy 106.551986 -235.508846)
			(xy 106.547462 -235.52277) (xy 106.966004 -235.52277) (xy 106.966527 -235.496804) (xy 106.974655 -235.445512)
			(xy 106.990705 -235.396123) (xy 107.014283 -235.349851) (xy 107.044808 -235.307838) (xy 107.081529 -235.271116)
			(xy 107.123541 -235.240589) (xy 107.169811 -235.21701) (xy 107.2192 -235.200958) (xy 107.270492 -235.192828)
			(xy 107.296458 -235.192316) (xy 107.323755 -235.192891) (xy 107.377606 -235.201865) (xy 107.429247 -235.219576)
			(xy 107.477271 -235.24554) (xy 107.520369 -235.279051) (xy 107.539282 -235.298742) (xy 107.549115 -235.308722)
			(xy 107.572999 -235.323348) (xy 107.599955 -235.330947) (xy 107.627961 -235.330947) (xy 107.654917 -235.323348)
			(xy 107.678801 -235.308722) (xy 107.688634 -235.298742) (xy 107.707557 -235.279061) (xy 107.750654 -235.24555)
			(xy 107.798676 -235.219583) (xy 107.850313 -235.201866) (xy 107.904162 -235.192881) (xy 107.931458 -235.192316)
			(xy 107.957425 -235.192867) (xy 108.008719 -235.200985) (xy 108.058113 -235.217028) (xy 108.104388 -235.240599)
			(xy 108.146407 -235.27112) (xy 108.183133 -235.307839) (xy 108.213663 -235.34985) (xy 108.237245 -235.396121)
			(xy 108.253298 -235.44551) (xy 108.261427 -235.496803) (xy 108.261912 -235.52277) (xy 108.261465 -235.5464)
			(xy 108.254711 -235.593175) (xy 108.241379 -235.638516) (xy 108.23194 -235.660184) (xy 108.226004 -235.674401)
			(xy 108.222138 -235.704955) (xy 108.227522 -235.735277) (xy 108.241671 -235.762632) (xy 108.263308 -235.784548)
			(xy 108.276644 -235.792264) (xy 108.299001 -235.804683) (xy 108.305903 -235.809849) (xy 109.431075 -235.809849)
			(xy 109.431075 -235.757915) (xy 109.4392 -235.70662) (xy 109.455248 -235.657227) (xy 109.478826 -235.610953)
			(xy 109.509352 -235.568937) (xy 109.546075 -235.532214) (xy 109.588091 -235.501688) (xy 109.634365 -235.47811)
			(xy 109.683758 -235.462062) (xy 109.735053 -235.453937) (xy 109.786987 -235.453937) (xy 109.838282 -235.462062)
			(xy 109.887675 -235.47811) (xy 109.933949 -235.501688) (xy 109.975965 -235.532214) (xy 110.012688 -235.568937)
			(xy 110.043214 -235.610953) (xy 110.066792 -235.657227) (xy 110.08284 -235.70662) (xy 110.090965 -235.757915)
			(xy 110.091474 -235.783882) (xy 110.090965 -235.809849) (xy 110.370875 -235.809849) (xy 110.370875 -235.757915)
			(xy 110.379 -235.70662) (xy 110.395048 -235.657227) (xy 110.418626 -235.610953) (xy 110.449152 -235.568937)
			(xy 110.485875 -235.532214) (xy 110.527891 -235.501688) (xy 110.574165 -235.47811) (xy 110.623558 -235.462062)
			(xy 110.674853 -235.453937) (xy 110.726787 -235.453937) (xy 110.778082 -235.462062) (xy 110.827475 -235.47811)
			(xy 110.873749 -235.501688) (xy 110.915765 -235.532214) (xy 110.952488 -235.568937) (xy 110.983014 -235.610953)
			(xy 111.006592 -235.657227) (xy 111.02264 -235.70662) (xy 111.030765 -235.757915) (xy 111.031274 -235.783882)
			(xy 111.030765 -235.809849) (xy 111.310675 -235.809849) (xy 111.310675 -235.757915) (xy 111.3188 -235.70662)
			(xy 111.334848 -235.657227) (xy 111.358426 -235.610953) (xy 111.388952 -235.568937) (xy 111.425675 -235.532214)
			(xy 111.467691 -235.501688) (xy 111.513965 -235.47811) (xy 111.563358 -235.462062) (xy 111.614653 -235.453937)
			(xy 111.666587 -235.453937) (xy 111.717882 -235.462062) (xy 111.767275 -235.47811) (xy 111.813549 -235.501688)
			(xy 111.855565 -235.532214) (xy 111.892288 -235.568937) (xy 111.922814 -235.610953) (xy 111.946392 -235.657227)
			(xy 111.96244 -235.70662) (xy 111.970565 -235.757915) (xy 111.971074 -235.783882) (xy 111.970565 -235.809849)
			(xy 112.250475 -235.809849) (xy 112.250475 -235.757915) (xy 112.2586 -235.70662) (xy 112.274648 -235.657227)
			(xy 112.298226 -235.610953) (xy 112.328752 -235.568937) (xy 112.365475 -235.532214) (xy 112.407491 -235.501688)
			(xy 112.453765 -235.47811) (xy 112.503158 -235.462062) (xy 112.554453 -235.453937) (xy 112.606387 -235.453937)
			(xy 112.657682 -235.462062) (xy 112.707075 -235.47811) (xy 112.753349 -235.501688) (xy 112.795365 -235.532214)
			(xy 112.832088 -235.568937) (xy 112.862614 -235.610953) (xy 112.886192 -235.657227) (xy 112.90224 -235.70662)
			(xy 112.910365 -235.757915) (xy 112.910874 -235.783882) (xy 112.910365 -235.809849) (xy 113.190275 -235.809849)
			(xy 113.190275 -235.757915) (xy 113.1984 -235.70662) (xy 113.214448 -235.657227) (xy 113.238026 -235.610953)
			(xy 113.268552 -235.568937) (xy 113.305275 -235.532214) (xy 113.347291 -235.501688) (xy 113.393565 -235.47811)
			(xy 113.442958 -235.462062) (xy 113.494253 -235.453937) (xy 113.546187 -235.453937) (xy 113.597482 -235.462062)
			(xy 113.646875 -235.47811) (xy 113.693149 -235.501688) (xy 113.735165 -235.532214) (xy 113.771888 -235.568937)
			(xy 113.802414 -235.610953) (xy 113.825992 -235.657227) (xy 113.84204 -235.70662) (xy 113.850165 -235.757915)
			(xy 113.850674 -235.783882) (xy 113.850165 -235.809849) (xy 114.130075 -235.809849) (xy 114.130075 -235.757915)
			(xy 114.1382 -235.70662) (xy 114.154248 -235.657227) (xy 114.177826 -235.610953) (xy 114.208352 -235.568937)
			(xy 114.245075 -235.532214) (xy 114.287091 -235.501688) (xy 114.333365 -235.47811) (xy 114.382758 -235.462062)
			(xy 114.434053 -235.453937) (xy 114.485987 -235.453937) (xy 114.537282 -235.462062) (xy 114.586675 -235.47811)
			(xy 114.632949 -235.501688) (xy 114.674965 -235.532214) (xy 114.711688 -235.568937) (xy 114.742214 -235.610953)
			(xy 114.765792 -235.657227) (xy 114.78184 -235.70662) (xy 114.789965 -235.757915) (xy 114.790474 -235.783882)
			(xy 114.789965 -235.809849) (xy 114.787317 -235.826568) (xy 116.265175 -235.826568) (xy 116.265175 -235.774632)
			(xy 116.2733 -235.723336) (xy 116.28935 -235.673942) (xy 116.312931 -235.627668) (xy 116.34346 -235.585653)
			(xy 116.380187 -235.548931) (xy 116.422206 -235.518408) (xy 116.468483 -235.494834) (xy 116.517879 -235.47879)
			(xy 116.569176 -235.470671) (xy 116.595144 -235.470192) (xy 116.595398 -235.470192) (xy 116.619924 -235.470647)
			(xy 116.668437 -235.477909) (xy 116.715344 -235.49226) (xy 116.759616 -235.513384) (xy 116.80028 -235.540818)
			(xy 116.818664 -235.55706) (xy 116.830153 -235.566863) (xy 116.85739 -235.579877) (xy 116.887244 -235.584345)
			(xy 116.917098 -235.579877) (xy 116.944335 -235.566863) (xy 116.955824 -235.55706) (xy 116.974248 -235.540825)
			(xy 117.014946 -235.513351) (xy 117.059264 -235.492207) (xy 117.106225 -235.477859) (xy 117.154792 -235.470624)
			(xy 117.179344 -235.470192) (xy 117.203896 -235.47063) (xy 117.252463 -235.47787) (xy 117.299426 -235.492214)
			(xy 117.34375 -235.513347) (xy 117.38446 -235.540803) (xy 117.402864 -235.55706) (xy 117.414353 -235.566863)
			(xy 117.44159 -235.579877) (xy 117.471444 -235.584345) (xy 117.501298 -235.579877) (xy 117.528535 -235.566863)
			(xy 117.540024 -235.55706) (xy 117.558448 -235.540825) (xy 117.599146 -235.513351) (xy 117.643464 -235.492207)
			(xy 117.690425 -235.477859) (xy 117.738992 -235.470624) (xy 117.763544 -235.470192) (xy 117.788096 -235.47063)
			(xy 117.836663 -235.47787) (xy 117.883626 -235.492214) (xy 117.92795 -235.513347) (xy 117.96866 -235.540803)
			(xy 117.987064 -235.55706) (xy 117.998553 -235.566863) (xy 118.02579 -235.579877) (xy 118.055644 -235.584345)
			(xy 118.085498 -235.579877) (xy 118.112735 -235.566863) (xy 118.124224 -235.55706) (xy 118.142648 -235.540825)
			(xy 118.183346 -235.513351) (xy 118.227664 -235.492207) (xy 118.274625 -235.477859) (xy 118.323192 -235.470624)
			(xy 118.347744 -235.470192) (xy 118.372296 -235.47063) (xy 118.420863 -235.47787) (xy 118.467826 -235.492214)
			(xy 118.51215 -235.513347) (xy 118.55286 -235.540803) (xy 118.571264 -235.55706) (xy 118.582753 -235.566863)
			(xy 118.60999 -235.579877) (xy 118.639844 -235.584345) (xy 118.669698 -235.579877) (xy 118.696935 -235.566863)
			(xy 118.708424 -235.55706) (xy 118.726848 -235.540825) (xy 118.767546 -235.513351) (xy 118.811864 -235.492207)
			(xy 118.858825 -235.477859) (xy 118.907392 -235.470624) (xy 118.931944 -235.470192) (xy 118.956496 -235.47063)
			(xy 119.005063 -235.47787) (xy 119.052026 -235.492214) (xy 119.09635 -235.513347) (xy 119.13706 -235.540803)
			(xy 119.155464 -235.55706) (xy 119.166953 -235.566863) (xy 119.19419 -235.579877) (xy 119.224044 -235.584345)
			(xy 119.253898 -235.579877) (xy 119.281135 -235.566863) (xy 119.292624 -235.55706) (xy 119.311028 -235.540841)
			(xy 119.35168 -235.513389) (xy 119.395946 -235.492253) (xy 119.442851 -235.477899) (xy 119.491364 -235.470641)
			(xy 119.51589 -235.470192) (xy 119.516144 -235.470192) (xy 119.542113 -235.470613) (xy 119.593409 -235.478744)
			(xy 119.642803 -235.494798) (xy 119.689077 -235.518382) (xy 119.731093 -235.548913) (xy 119.767816 -235.585641)
			(xy 119.798341 -235.62766) (xy 119.821919 -235.673938) (xy 119.837967 -235.723333) (xy 119.846091 -235.774631)
			(xy 119.846091 -235.809849) (xy 121.648221 -235.809849) (xy 121.648221 -235.757915) (xy 121.656346 -235.70662)
			(xy 121.672394 -235.657227) (xy 121.695972 -235.610953) (xy 121.726498 -235.568937) (xy 121.763221 -235.532214)
			(xy 121.805237 -235.501688) (xy 121.851511 -235.47811) (xy 121.900904 -235.462062) (xy 121.952199 -235.453937)
			(xy 122.004133 -235.453937) (xy 122.055428 -235.462062) (xy 122.104821 -235.47811) (xy 122.151095 -235.501688)
			(xy 122.193111 -235.532214) (xy 122.229834 -235.568937) (xy 122.26036 -235.610953) (xy 122.283938 -235.657227)
			(xy 122.299986 -235.70662) (xy 122.308111 -235.757915) (xy 122.30862 -235.783882) (xy 122.308111 -235.809849)
			(xy 122.588021 -235.809849) (xy 122.588021 -235.757915) (xy 122.596146 -235.70662) (xy 122.612194 -235.657227)
			(xy 122.635772 -235.610953) (xy 122.666298 -235.568937) (xy 122.703021 -235.532214) (xy 122.745037 -235.501688)
			(xy 122.791311 -235.47811) (xy 122.840704 -235.462062) (xy 122.891999 -235.453937) (xy 122.943933 -235.453937)
			(xy 122.995228 -235.462062) (xy 123.044621 -235.47811) (xy 123.090895 -235.501688) (xy 123.132911 -235.532214)
			(xy 123.169634 -235.568937) (xy 123.20016 -235.610953) (xy 123.223738 -235.657227) (xy 123.239786 -235.70662)
			(xy 123.247911 -235.757915) (xy 123.24842 -235.783882) (xy 123.247911 -235.809849) (xy 123.527821 -235.809849)
			(xy 123.527821 -235.757915) (xy 123.535946 -235.70662) (xy 123.551994 -235.657227) (xy 123.575572 -235.610953)
			(xy 123.606098 -235.568937) (xy 123.642821 -235.532214) (xy 123.684837 -235.501688) (xy 123.731111 -235.47811)
			(xy 123.780504 -235.462062) (xy 123.831799 -235.453937) (xy 123.883733 -235.453937) (xy 123.935028 -235.462062)
			(xy 123.984421 -235.47811) (xy 124.030695 -235.501688) (xy 124.072711 -235.532214) (xy 124.109434 -235.568937)
			(xy 124.13996 -235.610953) (xy 124.163538 -235.657227) (xy 124.179586 -235.70662) (xy 124.187711 -235.757915)
			(xy 124.18822 -235.783882) (xy 124.187711 -235.809849) (xy 124.467621 -235.809849) (xy 124.467621 -235.757915)
			(xy 124.475746 -235.70662) (xy 124.491794 -235.657227) (xy 124.515372 -235.610953) (xy 124.545898 -235.568937)
			(xy 124.582621 -235.532214) (xy 124.624637 -235.501688) (xy 124.670911 -235.47811) (xy 124.720304 -235.462062)
			(xy 124.771599 -235.453937) (xy 124.823533 -235.453937) (xy 124.874828 -235.462062) (xy 124.924221 -235.47811)
			(xy 124.970495 -235.501688) (xy 125.012511 -235.532214) (xy 125.049234 -235.568937) (xy 125.07976 -235.610953)
			(xy 125.103338 -235.657227) (xy 125.119386 -235.70662) (xy 125.127511 -235.757915) (xy 125.12802 -235.783882)
			(xy 125.127511 -235.809849) (xy 125.407167 -235.809849) (xy 125.407167 -235.757915) (xy 125.415292 -235.70662)
			(xy 125.43134 -235.657227) (xy 125.454918 -235.610953) (xy 125.485444 -235.568937) (xy 125.522167 -235.532214)
			(xy 125.564183 -235.501688) (xy 125.610457 -235.47811) (xy 125.65985 -235.462062) (xy 125.711145 -235.453937)
			(xy 125.763079 -235.453937) (xy 125.814374 -235.462062) (xy 125.863767 -235.47811) (xy 125.910041 -235.501688)
			(xy 125.952057 -235.532214) (xy 125.98878 -235.568937) (xy 126.019306 -235.610953) (xy 126.042884 -235.657227)
			(xy 126.058932 -235.70662) (xy 126.067057 -235.757915) (xy 126.067566 -235.783882) (xy 126.067057 -235.809849)
			(xy 126.347221 -235.809849) (xy 126.347221 -235.757915) (xy 126.355346 -235.70662) (xy 126.371394 -235.657227)
			(xy 126.394972 -235.610953) (xy 126.425498 -235.568937) (xy 126.462221 -235.532214) (xy 126.504237 -235.501688)
			(xy 126.550511 -235.47811) (xy 126.599904 -235.462062) (xy 126.651199 -235.453937) (xy 126.703133 -235.453937)
			(xy 126.754428 -235.462062) (xy 126.803821 -235.47811) (xy 126.850095 -235.501688) (xy 126.892111 -235.532214)
			(xy 126.928834 -235.568937) (xy 126.95936 -235.610953) (xy 126.982938 -235.657227) (xy 126.998986 -235.70662)
			(xy 127.007111 -235.757915) (xy 127.00762 -235.783882) (xy 127.007111 -235.809849) (xy 127.287021 -235.809849)
			(xy 127.287021 -235.757915) (xy 127.295146 -235.70662) (xy 127.311194 -235.657227) (xy 127.334772 -235.610953)
			(xy 127.365298 -235.568937) (xy 127.402021 -235.532214) (xy 127.444037 -235.501688) (xy 127.490311 -235.47811)
			(xy 127.539704 -235.462062) (xy 127.590999 -235.453937) (xy 127.642933 -235.453937) (xy 127.694228 -235.462062)
			(xy 127.743621 -235.47811) (xy 127.789895 -235.501688) (xy 127.831911 -235.532214) (xy 127.868634 -235.568937)
			(xy 127.89916 -235.610953) (xy 127.922738 -235.657227) (xy 127.938786 -235.70662) (xy 127.946911 -235.757915)
			(xy 127.94742 -235.783882) (xy 127.946911 -235.809849) (xy 128.226821 -235.809849) (xy 128.226821 -235.757915)
			(xy 128.234946 -235.70662) (xy 128.250994 -235.657227) (xy 128.274572 -235.610953) (xy 128.305098 -235.568937)
			(xy 128.341821 -235.532214) (xy 128.383837 -235.501688) (xy 128.430111 -235.47811) (xy 128.479504 -235.462062)
			(xy 128.530799 -235.453937) (xy 128.582733 -235.453937) (xy 128.634028 -235.462062) (xy 128.683421 -235.47811)
			(xy 128.729695 -235.501688) (xy 128.771711 -235.532214) (xy 128.808434 -235.568937) (xy 128.83896 -235.610953)
			(xy 128.862538 -235.657227) (xy 128.878586 -235.70662) (xy 128.886711 -235.757915) (xy 128.88722 -235.783882)
			(xy 128.886711 -235.809849) (xy 129.166621 -235.809849) (xy 129.166621 -235.757915) (xy 129.174746 -235.70662)
			(xy 129.190794 -235.657227) (xy 129.214372 -235.610953) (xy 129.244898 -235.568937) (xy 129.281621 -235.532214)
			(xy 129.323637 -235.501688) (xy 129.369911 -235.47811) (xy 129.419304 -235.462062) (xy 129.470599 -235.453937)
			(xy 129.522533 -235.453937) (xy 129.573828 -235.462062) (xy 129.623221 -235.47811) (xy 129.669495 -235.501688)
			(xy 129.711511 -235.532214) (xy 129.748234 -235.568937) (xy 129.77876 -235.610953) (xy 129.802338 -235.657227)
			(xy 129.818386 -235.70662) (xy 129.826511 -235.757915) (xy 129.82702 -235.783882) (xy 129.826511 -235.809849)
			(xy 130.106421 -235.809849) (xy 130.106421 -235.757915) (xy 130.114546 -235.70662) (xy 130.130594 -235.657227)
			(xy 130.154172 -235.610953) (xy 130.184698 -235.568937) (xy 130.221421 -235.532214) (xy 130.263437 -235.501688)
			(xy 130.309711 -235.47811) (xy 130.359104 -235.462062) (xy 130.410399 -235.453937) (xy 130.462333 -235.453937)
			(xy 130.513628 -235.462062) (xy 130.563021 -235.47811) (xy 130.609295 -235.501688) (xy 130.651311 -235.532214)
			(xy 130.688034 -235.568937) (xy 130.71856 -235.610953) (xy 130.742138 -235.657227) (xy 130.758186 -235.70662)
			(xy 130.766311 -235.757915) (xy 130.76682 -235.783882) (xy 130.766311 -235.809849) (xy 130.758186 -235.861144)
			(xy 130.742138 -235.910537) (xy 130.71856 -235.956811) (xy 130.688034 -235.998827) (xy 130.651311 -236.03555)
			(xy 130.609295 -236.066076) (xy 130.563021 -236.089654) (xy 130.513628 -236.105702) (xy 130.462333 -236.113827)
			(xy 130.410399 -236.113827) (xy 130.359104 -236.105702) (xy 130.309711 -236.089654) (xy 130.263437 -236.066076)
			(xy 130.221421 -236.03555) (xy 130.184698 -235.998827) (xy 130.154172 -235.956811) (xy 130.130594 -235.910537)
			(xy 130.114546 -235.861144) (xy 130.106421 -235.809849) (xy 129.826511 -235.809849) (xy 129.818386 -235.861144)
			(xy 129.802338 -235.910537) (xy 129.77876 -235.956811) (xy 129.748234 -235.998827) (xy 129.711511 -236.03555)
			(xy 129.669495 -236.066076) (xy 129.623221 -236.089654) (xy 129.573828 -236.105702) (xy 129.522533 -236.113827)
			(xy 129.470599 -236.113827) (xy 129.419304 -236.105702) (xy 129.369911 -236.089654) (xy 129.323637 -236.066076)
			(xy 129.281621 -236.03555) (xy 129.244898 -235.998827) (xy 129.214372 -235.956811) (xy 129.190794 -235.910537)
			(xy 129.174746 -235.861144) (xy 129.166621 -235.809849) (xy 128.886711 -235.809849) (xy 128.878586 -235.861144)
			(xy 128.862538 -235.910537) (xy 128.83896 -235.956811) (xy 128.808434 -235.998827) (xy 128.771711 -236.03555)
			(xy 128.729695 -236.066076) (xy 128.683421 -236.089654) (xy 128.634028 -236.105702) (xy 128.582733 -236.113827)
			(xy 128.530799 -236.113827) (xy 128.479504 -236.105702) (xy 128.430111 -236.089654) (xy 128.383837 -236.066076)
			(xy 128.341821 -236.03555) (xy 128.305098 -235.998827) (xy 128.274572 -235.956811) (xy 128.250994 -235.910537)
			(xy 128.234946 -235.861144) (xy 128.226821 -235.809849) (xy 127.946911 -235.809849) (xy 127.938786 -235.861144)
			(xy 127.922738 -235.910537) (xy 127.89916 -235.956811) (xy 127.868634 -235.998827) (xy 127.831911 -236.03555)
			(xy 127.789895 -236.066076) (xy 127.743621 -236.089654) (xy 127.694228 -236.105702) (xy 127.642933 -236.113827)
			(xy 127.590999 -236.113827) (xy 127.539704 -236.105702) (xy 127.490311 -236.089654) (xy 127.444037 -236.066076)
			(xy 127.402021 -236.03555) (xy 127.365298 -235.998827) (xy 127.334772 -235.956811) (xy 127.311194 -235.910537)
			(xy 127.295146 -235.861144) (xy 127.287021 -235.809849) (xy 127.007111 -235.809849) (xy 126.998986 -235.861144)
			(xy 126.982938 -235.910537) (xy 126.95936 -235.956811) (xy 126.928834 -235.998827) (xy 126.892111 -236.03555)
			(xy 126.850095 -236.066076) (xy 126.803821 -236.089654) (xy 126.754428 -236.105702) (xy 126.703133 -236.113827)
			(xy 126.651199 -236.113827) (xy 126.599904 -236.105702) (xy 126.550511 -236.089654) (xy 126.504237 -236.066076)
			(xy 126.462221 -236.03555) (xy 126.425498 -235.998827) (xy 126.394972 -235.956811) (xy 126.371394 -235.910537)
			(xy 126.355346 -235.861144) (xy 126.347221 -235.809849) (xy 126.067057 -235.809849) (xy 126.058932 -235.861144)
			(xy 126.042884 -235.910537) (xy 126.019306 -235.956811) (xy 125.98878 -235.998827) (xy 125.952057 -236.03555)
			(xy 125.910041 -236.066076) (xy 125.863767 -236.089654) (xy 125.814374 -236.105702) (xy 125.763079 -236.113827)
			(xy 125.711145 -236.113827) (xy 125.65985 -236.105702) (xy 125.610457 -236.089654) (xy 125.564183 -236.066076)
			(xy 125.522167 -236.03555) (xy 125.485444 -235.998827) (xy 125.454918 -235.956811) (xy 125.43134 -235.910537)
			(xy 125.415292 -235.861144) (xy 125.407167 -235.809849) (xy 125.127511 -235.809849) (xy 125.119386 -235.861144)
			(xy 125.103338 -235.910537) (xy 125.07976 -235.956811) (xy 125.049234 -235.998827) (xy 125.012511 -236.03555)
			(xy 124.970495 -236.066076) (xy 124.924221 -236.089654) (xy 124.874828 -236.105702) (xy 124.823533 -236.113827)
			(xy 124.771599 -236.113827) (xy 124.720304 -236.105702) (xy 124.670911 -236.089654) (xy 124.624637 -236.066076)
			(xy 124.582621 -236.03555) (xy 124.545898 -235.998827) (xy 124.515372 -235.956811) (xy 124.491794 -235.910537)
			(xy 124.475746 -235.861144) (xy 124.467621 -235.809849) (xy 124.187711 -235.809849) (xy 124.179586 -235.861144)
			(xy 124.163538 -235.910537) (xy 124.13996 -235.956811) (xy 124.109434 -235.998827) (xy 124.072711 -236.03555)
			(xy 124.030695 -236.066076) (xy 123.984421 -236.089654) (xy 123.935028 -236.105702) (xy 123.883733 -236.113827)
			(xy 123.831799 -236.113827) (xy 123.780504 -236.105702) (xy 123.731111 -236.089654) (xy 123.684837 -236.066076)
			(xy 123.642821 -236.03555) (xy 123.606098 -235.998827) (xy 123.575572 -235.956811) (xy 123.551994 -235.910537)
			(xy 123.535946 -235.861144) (xy 123.527821 -235.809849) (xy 123.247911 -235.809849) (xy 123.239786 -235.861144)
			(xy 123.223738 -235.910537) (xy 123.20016 -235.956811) (xy 123.169634 -235.998827) (xy 123.132911 -236.03555)
			(xy 123.090895 -236.066076) (xy 123.044621 -236.089654) (xy 122.995228 -236.105702) (xy 122.943933 -236.113827)
			(xy 122.891999 -236.113827) (xy 122.840704 -236.105702) (xy 122.791311 -236.089654) (xy 122.745037 -236.066076)
			(xy 122.703021 -236.03555) (xy 122.666298 -235.998827) (xy 122.635772 -235.956811) (xy 122.612194 -235.910537)
			(xy 122.596146 -235.861144) (xy 122.588021 -235.809849) (xy 122.308111 -235.809849) (xy 122.299986 -235.861144)
			(xy 122.283938 -235.910537) (xy 122.26036 -235.956811) (xy 122.229834 -235.998827) (xy 122.193111 -236.03555)
			(xy 122.151095 -236.066076) (xy 122.104821 -236.089654) (xy 122.055428 -236.105702) (xy 122.004133 -236.113827)
			(xy 121.952199 -236.113827) (xy 121.900904 -236.105702) (xy 121.851511 -236.089654) (xy 121.805237 -236.066076)
			(xy 121.763221 -236.03555) (xy 121.726498 -235.998827) (xy 121.695972 -235.956811) (xy 121.672394 -235.910537)
			(xy 121.656346 -235.861144) (xy 121.648221 -235.809849) (xy 119.846091 -235.809849) (xy 119.846091 -235.826569)
			(xy 119.837967 -235.877867) (xy 119.821919 -235.927262) (xy 119.798341 -235.97354) (xy 119.767816 -236.015559)
			(xy 119.731093 -236.052287) (xy 119.689077 -236.082818) (xy 119.642803 -236.106402) (xy 119.593409 -236.122456)
			(xy 119.542113 -236.130587) (xy 119.516144 -236.1311) (xy 119.51589 -236.1311) (xy 119.491363 -236.130654)
			(xy 119.44285 -236.12339) (xy 119.395943 -236.109037) (xy 119.351671 -236.087911) (xy 119.311007 -236.060475)
			(xy 119.292624 -236.044232) (xy 119.281135 -236.034429) (xy 119.253898 -236.021415) (xy 119.224044 -236.016947)
			(xy 119.19419 -236.021415) (xy 119.166953 -236.034429) (xy 119.155464 -236.044232) (xy 119.137043 -236.060471)
			(xy 119.096344 -236.087945) (xy 119.052026 -236.109088) (xy 119.005064 -236.123435) (xy 118.956496 -236.130669)
			(xy 118.931944 -236.1311) (xy 118.907391 -236.130671) (xy 118.858824 -236.123429) (xy 118.811861 -236.109083)
			(xy 118.767538 -236.087949) (xy 118.726827 -236.06049) (xy 118.708424 -236.044232) (xy 118.696935 -236.034429)
			(xy 118.669698 -236.021415) (xy 118.639844 -236.016947) (xy 118.60999 -236.021415) (xy 118.582753 -236.034429)
			(xy 118.571264 -236.044232) (xy 118.552843 -236.060471) (xy 118.512144 -236.087945) (xy 118.467826 -236.109088)
			(xy 118.420864 -236.123435) (xy 118.372296 -236.130669) (xy 118.347744 -236.1311) (xy 118.323191 -236.130671)
			(xy 118.274624 -236.123429) (xy 118.227661 -236.109083) (xy 118.183338 -236.087949) (xy 118.142627 -236.06049)
			(xy 118.124224 -236.044232) (xy 118.112735 -236.034429) (xy 118.085498 -236.021415) (xy 118.055644 -236.016947)
			(xy 118.02579 -236.021415) (xy 117.998553 -236.034429) (xy 117.987064 -236.044232) (xy 117.968643 -236.060471)
			(xy 117.927944 -236.087945) (xy 117.883626 -236.109088) (xy 117.836664 -236.123435) (xy 117.788096 -236.130669)
			(xy 117.763544 -236.1311) (xy 117.738991 -236.130671) (xy 117.690424 -236.123429) (xy 117.643461 -236.109083)
			(xy 117.599138 -236.087949) (xy 117.558427 -236.06049) (xy 117.540024 -236.044232) (xy 117.528535 -236.034429)
			(xy 117.501298 -236.021415) (xy 117.471444 -236.016947) (xy 117.44159 -236.021415) (xy 117.414353 -236.034429)
			(xy 117.402864 -236.044232) (xy 117.384443 -236.060471) (xy 117.343744 -236.087945) (xy 117.299426 -236.109088)
			(xy 117.252464 -236.123435) (xy 117.203896 -236.130669) (xy 117.179344 -236.1311) (xy 117.154791 -236.130671)
			(xy 117.106224 -236.123429) (xy 117.059261 -236.109083) (xy 117.014938 -236.087949) (xy 116.974227 -236.06049)
			(xy 116.955824 -236.044232) (xy 116.944335 -236.034429) (xy 116.917098 -236.021415) (xy 116.887244 -236.016947)
			(xy 116.85739 -236.021415) (xy 116.830153 -236.034429) (xy 116.818664 -236.044232) (xy 116.800263 -236.060456)
			(xy 116.759611 -236.087907) (xy 116.715344 -236.109042) (xy 116.668438 -236.123396) (xy 116.619925 -236.130652)
			(xy 116.595398 -236.1311) (xy 116.595144 -236.1311) (xy 116.569176 -236.130529) (xy 116.517879 -236.12241)
			(xy 116.468483 -236.106366) (xy 116.422206 -236.082792) (xy 116.380187 -236.052269) (xy 116.34346 -236.015547)
			(xy 116.312931 -235.973532) (xy 116.28935 -235.927258) (xy 116.2733 -235.877864) (xy 116.265175 -235.826568)
			(xy 114.787317 -235.826568) (xy 114.78184 -235.861144) (xy 114.765792 -235.910537) (xy 114.742214 -235.956811)
			(xy 114.711688 -235.998827) (xy 114.674965 -236.03555) (xy 114.632949 -236.066076) (xy 114.586675 -236.089654)
			(xy 114.537282 -236.105702) (xy 114.485987 -236.113827) (xy 114.434053 -236.113827) (xy 114.382758 -236.105702)
			(xy 114.333365 -236.089654) (xy 114.287091 -236.066076) (xy 114.245075 -236.03555) (xy 114.208352 -235.998827)
			(xy 114.177826 -235.956811) (xy 114.154248 -235.910537) (xy 114.1382 -235.861144) (xy 114.130075 -235.809849)
			(xy 113.850165 -235.809849) (xy 113.84204 -235.861144) (xy 113.825992 -235.910537) (xy 113.802414 -235.956811)
			(xy 113.771888 -235.998827) (xy 113.735165 -236.03555) (xy 113.693149 -236.066076) (xy 113.646875 -236.089654)
			(xy 113.597482 -236.105702) (xy 113.546187 -236.113827) (xy 113.494253 -236.113827) (xy 113.442958 -236.105702)
			(xy 113.393565 -236.089654) (xy 113.347291 -236.066076) (xy 113.305275 -236.03555) (xy 113.268552 -235.998827)
			(xy 113.238026 -235.956811) (xy 113.214448 -235.910537) (xy 113.1984 -235.861144) (xy 113.190275 -235.809849)
			(xy 112.910365 -235.809849) (xy 112.90224 -235.861144) (xy 112.886192 -235.910537) (xy 112.862614 -235.956811)
			(xy 112.832088 -235.998827) (xy 112.795365 -236.03555) (xy 112.753349 -236.066076) (xy 112.707075 -236.089654)
			(xy 112.657682 -236.105702) (xy 112.606387 -236.113827) (xy 112.554453 -236.113827) (xy 112.503158 -236.105702)
			(xy 112.453765 -236.089654) (xy 112.407491 -236.066076) (xy 112.365475 -236.03555) (xy 112.328752 -235.998827)
			(xy 112.298226 -235.956811) (xy 112.274648 -235.910537) (xy 112.2586 -235.861144) (xy 112.250475 -235.809849)
			(xy 111.970565 -235.809849) (xy 111.96244 -235.861144) (xy 111.946392 -235.910537) (xy 111.922814 -235.956811)
			(xy 111.892288 -235.998827) (xy 111.855565 -236.03555) (xy 111.813549 -236.066076) (xy 111.767275 -236.089654)
			(xy 111.717882 -236.105702) (xy 111.666587 -236.113827) (xy 111.614653 -236.113827) (xy 111.563358 -236.105702)
			(xy 111.513965 -236.089654) (xy 111.467691 -236.066076) (xy 111.425675 -236.03555) (xy 111.388952 -235.998827)
			(xy 111.358426 -235.956811) (xy 111.334848 -235.910537) (xy 111.3188 -235.861144) (xy 111.310675 -235.809849)
			(xy 111.030765 -235.809849) (xy 111.02264 -235.861144) (xy 111.006592 -235.910537) (xy 110.983014 -235.956811)
			(xy 110.952488 -235.998827) (xy 110.915765 -236.03555) (xy 110.873749 -236.066076) (xy 110.827475 -236.089654)
			(xy 110.778082 -236.105702) (xy 110.726787 -236.113827) (xy 110.674853 -236.113827) (xy 110.623558 -236.105702)
			(xy 110.574165 -236.089654) (xy 110.527891 -236.066076) (xy 110.485875 -236.03555) (xy 110.449152 -235.998827)
			(xy 110.418626 -235.956811) (xy 110.395048 -235.910537) (xy 110.379 -235.861144) (xy 110.370875 -235.809849)
			(xy 110.090965 -235.809849) (xy 110.08284 -235.861144) (xy 110.066792 -235.910537) (xy 110.043214 -235.956811)
			(xy 110.012688 -235.998827) (xy 109.975965 -236.03555) (xy 109.933949 -236.066076) (xy 109.887675 -236.089654)
			(xy 109.838282 -236.105702) (xy 109.786987 -236.113827) (xy 109.735053 -236.113827) (xy 109.683758 -236.105702)
			(xy 109.634365 -236.089654) (xy 109.588091 -236.066076) (xy 109.546075 -236.03555) (xy 109.509352 -235.998827)
			(xy 109.478826 -235.956811) (xy 109.455248 -235.910537) (xy 109.4392 -235.861144) (xy 109.431075 -235.809849)
			(xy 108.305903 -235.809849) (xy 108.339942 -235.835327) (xy 108.375673 -235.871914) (xy 108.405338 -235.91357)
			(xy 108.42823 -235.9593) (xy 108.443801 -236.008011) (xy 108.45168 -236.05854) (xy 108.452158 -236.08411)
			(xy 108.451654 -236.110077) (xy 108.443528 -236.161372) (xy 108.427479 -236.210765) (xy 108.4039 -236.257038)
			(xy 108.373373 -236.299054) (xy 108.336649 -236.335777) (xy 108.294633 -236.366303) (xy 108.248359 -236.389881)
			(xy 108.198966 -236.40593) (xy 108.147671 -236.414054) (xy 108.121704 -236.414564) (xy 108.094406 -236.41402)
			(xy 108.040553 -236.405039) (xy 107.988911 -236.387322) (xy 107.940888 -236.36135) (xy 107.897791 -236.327832)
			(xy 107.87888 -236.308138) (xy 107.869047 -236.298158) (xy 107.845163 -236.283532) (xy 107.818207 -236.275933)
			(xy 107.790201 -236.275933) (xy 107.763245 -236.283532) (xy 107.739361 -236.298158) (xy 107.729528 -236.308138)
			(xy 107.710619 -236.327834) (xy 107.667519 -236.361343) (xy 107.619494 -236.387309) (xy 107.567853 -236.405022)
			(xy 107.514001 -236.414002) (xy 107.486704 -236.414564) (xy 107.460737 -236.414041) (xy 107.409443 -236.405918)
			(xy 107.360052 -236.38987) (xy 107.313779 -236.366294) (xy 107.271763 -236.335769) (xy 107.23504 -236.299048)
			(xy 107.204513 -236.257033) (xy 107.180935 -236.210761) (xy 107.164886 -236.16137) (xy 107.15676 -236.110077)
			(xy 107.15625 -236.08411) (xy 107.156693 -236.06048) (xy 107.163449 -236.013704) (xy 107.176783 -235.968364)
			(xy 107.186222 -235.946696) (xy 107.192197 -235.932493) (xy 107.196062 -235.901931) (xy 107.190671 -235.871601)
			(xy 107.176511 -235.844243) (xy 107.154861 -235.822329) (xy 107.141518 -235.814616) (xy 107.119144 -235.802227)
			(xy 107.078204 -235.771577) (xy 107.042476 -235.734984) (xy 107.012813 -235.693323) (xy 106.989924 -235.647588)
			(xy 106.974356 -235.598873) (xy 106.96648 -235.548341) (xy 106.966004 -235.52277) (xy 106.547462 -235.52277)
			(xy 106.535938 -235.558239) (xy 106.51236 -235.604513) (xy 106.481834 -235.646529) (xy 106.445111 -235.683252)
			(xy 106.403095 -235.713778) (xy 106.356821 -235.737356) (xy 106.307428 -235.753404) (xy 106.256133 -235.761529)
			(xy 106.204199 -235.761529) (xy 106.152904 -235.753404) (xy 106.103511 -235.737356) (xy 106.057237 -235.713778)
			(xy 106.015221 -235.683252) (xy 105.978498 -235.646529) (xy 105.947972 -235.604513) (xy 105.924394 -235.558239)
			(xy 105.908346 -235.508846) (xy 105.900221 -235.457551) (xy 105.414572 -235.457551) (xy 105.414572 -236.00029)
			(xy 104.974136 -236.44098) (xy 103.215186 -236.44098) (xy 103.20782 -236.48289) (xy 103.202897 -236.508108)
			(xy 103.186348 -236.556747) (xy 103.162475 -236.602241) (xy 103.146571 -236.623665) (xy 108.960921 -236.623665)
			(xy 108.960921 -236.571731) (xy 108.969046 -236.520436) (xy 108.985094 -236.471043) (xy 109.008672 -236.424769)
			(xy 109.039198 -236.382753) (xy 109.075921 -236.34603) (xy 109.117937 -236.315504) (xy 109.164211 -236.291926)
			(xy 109.213604 -236.275878) (xy 109.264899 -236.267753) (xy 109.316833 -236.267753) (xy 109.368128 -236.275878)
			(xy 109.417521 -236.291926) (xy 109.463795 -236.315504) (xy 109.505811 -236.34603) (xy 109.542534 -236.382753)
			(xy 109.57306 -236.424769) (xy 109.596638 -236.471043) (xy 109.612686 -236.520436) (xy 109.620811 -236.571731)
			(xy 109.62132 -236.597698) (xy 109.620811 -236.623665) (xy 109.900975 -236.623665) (xy 109.900975 -236.571731)
			(xy 109.9091 -236.520436) (xy 109.925148 -236.471043) (xy 109.948726 -236.424769) (xy 109.979252 -236.382753)
			(xy 110.015975 -236.34603) (xy 110.057991 -236.315504) (xy 110.104265 -236.291926) (xy 110.153658 -236.275878)
			(xy 110.204953 -236.267753) (xy 110.256887 -236.267753) (xy 110.308182 -236.275878) (xy 110.357575 -236.291926)
			(xy 110.403849 -236.315504) (xy 110.445865 -236.34603) (xy 110.482588 -236.382753) (xy 110.513114 -236.424769)
			(xy 110.536692 -236.471043) (xy 110.55274 -236.520436) (xy 110.560865 -236.571731) (xy 110.561374 -236.597698)
			(xy 110.560865 -236.623665) (xy 110.840521 -236.623665) (xy 110.840521 -236.571731) (xy 110.848646 -236.520436)
			(xy 110.864694 -236.471043) (xy 110.888272 -236.424769) (xy 110.918798 -236.382753) (xy 110.955521 -236.34603)
			(xy 110.997537 -236.315504) (xy 111.043811 -236.291926) (xy 111.093204 -236.275878) (xy 111.144499 -236.267753)
			(xy 111.196433 -236.267753) (xy 111.247728 -236.275878) (xy 111.297121 -236.291926) (xy 111.343395 -236.315504)
			(xy 111.385411 -236.34603) (xy 111.422134 -236.382753) (xy 111.45266 -236.424769) (xy 111.476238 -236.471043)
			(xy 111.492286 -236.520436) (xy 111.500411 -236.571731) (xy 111.50092 -236.597698) (xy 111.500411 -236.623665)
			(xy 111.780321 -236.623665) (xy 111.780321 -236.571731) (xy 111.788446 -236.520436) (xy 111.804494 -236.471043)
			(xy 111.828072 -236.424769) (xy 111.858598 -236.382753) (xy 111.895321 -236.34603) (xy 111.937337 -236.315504)
			(xy 111.983611 -236.291926) (xy 112.033004 -236.275878) (xy 112.084299 -236.267753) (xy 112.136233 -236.267753)
			(xy 112.187528 -236.275878) (xy 112.236921 -236.291926) (xy 112.283195 -236.315504) (xy 112.325211 -236.34603)
			(xy 112.361934 -236.382753) (xy 112.39246 -236.424769) (xy 112.416038 -236.471043) (xy 112.432086 -236.520436)
			(xy 112.440211 -236.571731) (xy 112.44072 -236.597698) (xy 112.440211 -236.623665) (xy 112.720121 -236.623665)
			(xy 112.720121 -236.571731) (xy 112.728246 -236.520436) (xy 112.744294 -236.471043) (xy 112.767872 -236.424769)
			(xy 112.798398 -236.382753) (xy 112.835121 -236.34603) (xy 112.877137 -236.315504) (xy 112.923411 -236.291926)
			(xy 112.972804 -236.275878) (xy 113.024099 -236.267753) (xy 113.076033 -236.267753) (xy 113.127328 -236.275878)
			(xy 113.176721 -236.291926) (xy 113.222995 -236.315504) (xy 113.265011 -236.34603) (xy 113.301734 -236.382753)
			(xy 113.33226 -236.424769) (xy 113.355838 -236.471043) (xy 113.371886 -236.520436) (xy 113.380011 -236.571731)
			(xy 113.38052 -236.597698) (xy 113.380011 -236.623665) (xy 113.660175 -236.623665) (xy 113.660175 -236.571731)
			(xy 113.6683 -236.520436) (xy 113.684348 -236.471043) (xy 113.707926 -236.424769) (xy 113.738452 -236.382753)
			(xy 113.775175 -236.34603) (xy 113.817191 -236.315504) (xy 113.863465 -236.291926) (xy 113.912858 -236.275878)
			(xy 113.964153 -236.267753) (xy 114.016087 -236.267753) (xy 114.067382 -236.275878) (xy 114.116775 -236.291926)
			(xy 114.163049 -236.315504) (xy 114.205065 -236.34603) (xy 114.241788 -236.382753) (xy 114.272314 -236.424769)
			(xy 114.295892 -236.471043) (xy 114.31194 -236.520436) (xy 114.320065 -236.571731) (xy 114.320574 -236.597698)
			(xy 114.320065 -236.623665) (xy 114.31194 -236.67496) (xy 114.295892 -236.724353) (xy 114.272314 -236.770627)
			(xy 114.241788 -236.812643) (xy 114.205065 -236.849366) (xy 114.163049 -236.879892) (xy 114.116775 -236.90347)
			(xy 114.067382 -236.919518) (xy 114.016087 -236.927643) (xy 113.964153 -236.927643) (xy 113.912858 -236.919518)
			(xy 113.863465 -236.90347) (xy 113.817191 -236.879892) (xy 113.775175 -236.849366) (xy 113.738452 -236.812643)
			(xy 113.707926 -236.770627) (xy 113.684348 -236.724353) (xy 113.6683 -236.67496) (xy 113.660175 -236.623665)
			(xy 113.380011 -236.623665) (xy 113.371886 -236.67496) (xy 113.355838 -236.724353) (xy 113.33226 -236.770627)
			(xy 113.301734 -236.812643) (xy 113.265011 -236.849366) (xy 113.222995 -236.879892) (xy 113.176721 -236.90347)
			(xy 113.127328 -236.919518) (xy 113.076033 -236.927643) (xy 113.024099 -236.927643) (xy 112.972804 -236.919518)
			(xy 112.923411 -236.90347) (xy 112.877137 -236.879892) (xy 112.835121 -236.849366) (xy 112.798398 -236.812643)
			(xy 112.767872 -236.770627) (xy 112.744294 -236.724353) (xy 112.728246 -236.67496) (xy 112.720121 -236.623665)
			(xy 112.440211 -236.623665) (xy 112.432086 -236.67496) (xy 112.416038 -236.724353) (xy 112.39246 -236.770627)
			(xy 112.361934 -236.812643) (xy 112.325211 -236.849366) (xy 112.283195 -236.879892) (xy 112.236921 -236.90347)
			(xy 112.187528 -236.919518) (xy 112.136233 -236.927643) (xy 112.084299 -236.927643) (xy 112.033004 -236.919518)
			(xy 111.983611 -236.90347) (xy 111.937337 -236.879892) (xy 111.895321 -236.849366) (xy 111.858598 -236.812643)
			(xy 111.828072 -236.770627) (xy 111.804494 -236.724353) (xy 111.788446 -236.67496) (xy 111.780321 -236.623665)
			(xy 111.500411 -236.623665) (xy 111.492286 -236.67496) (xy 111.476238 -236.724353) (xy 111.45266 -236.770627)
			(xy 111.422134 -236.812643) (xy 111.385411 -236.849366) (xy 111.343395 -236.879892) (xy 111.297121 -236.90347)
			(xy 111.247728 -236.919518) (xy 111.196433 -236.927643) (xy 111.144499 -236.927643) (xy 111.093204 -236.919518)
			(xy 111.043811 -236.90347) (xy 110.997537 -236.879892) (xy 110.955521 -236.849366) (xy 110.918798 -236.812643)
			(xy 110.888272 -236.770627) (xy 110.864694 -236.724353) (xy 110.848646 -236.67496) (xy 110.840521 -236.623665)
			(xy 110.560865 -236.623665) (xy 110.55274 -236.67496) (xy 110.536692 -236.724353) (xy 110.513114 -236.770627)
			(xy 110.482588 -236.812643) (xy 110.445865 -236.849366) (xy 110.403849 -236.879892) (xy 110.357575 -236.90347)
			(xy 110.308182 -236.919518) (xy 110.256887 -236.927643) (xy 110.204953 -236.927643) (xy 110.153658 -236.919518)
			(xy 110.104265 -236.90347) (xy 110.057991 -236.879892) (xy 110.015975 -236.849366) (xy 109.979252 -236.812643)
			(xy 109.948726 -236.770627) (xy 109.925148 -236.724353) (xy 109.9091 -236.67496) (xy 109.900975 -236.623665)
			(xy 109.620811 -236.623665) (xy 109.612686 -236.67496) (xy 109.596638 -236.724353) (xy 109.57306 -236.770627)
			(xy 109.542534 -236.812643) (xy 109.505811 -236.849366) (xy 109.463795 -236.879892) (xy 109.417521 -236.90347)
			(xy 109.368128 -236.919518) (xy 109.316833 -236.927643) (xy 109.264899 -236.927643) (xy 109.213604 -236.919518)
			(xy 109.164211 -236.90347) (xy 109.117937 -236.879892) (xy 109.075921 -236.849366) (xy 109.039198 -236.812643)
			(xy 109.008672 -236.770627) (xy 108.985094 -236.724353) (xy 108.969046 -236.67496) (xy 108.960921 -236.623665)
			(xy 103.146571 -236.623665) (xy 103.131851 -236.643495) (xy 103.095213 -236.679514) (xy 103.053445 -236.709431)
			(xy 103.007552 -236.732527) (xy 102.958637 -236.748246) (xy 102.907881 -236.756208) (xy 102.882192 -236.756702)
			(xy 102.856227 -236.756152) (xy 102.804936 -236.748028) (xy 102.755548 -236.731981) (xy 102.709277 -236.708407)
			(xy 102.667263 -236.677885) (xy 102.630541 -236.641167) (xy 102.600014 -236.599157) (xy 102.576434 -236.552889)
			(xy 102.560381 -236.503503) (xy 102.552251 -236.452213) (xy 102.551738 -236.426248) (xy 102.551998 -236.407931)
			(xy 102.556068 -236.371524) (xy 102.559866 -236.353604) (xy 102.565962 -236.326426) (xy 102.340156 -236.10062)
			(xy 102.313232 -236.106716) (xy 102.295861 -236.110275) (xy 102.260605 -236.114091) (xy 102.242874 -236.114336)
			(xy 102.242366 -236.114336) (xy 102.216397 -236.113876) (xy 102.165099 -236.105746) (xy 102.115704 -236.089692)
			(xy 102.069429 -236.066108) (xy 102.027413 -236.035576) (xy 101.99069 -235.998847) (xy 101.960165 -235.956826)
			(xy 101.936588 -235.910547) (xy 101.920542 -235.86115) (xy 101.91242 -235.809851) (xy 101.911912 -235.783882)
			(xy 101.911912 -235.783374) (xy 101.912145 -235.765643) (xy 101.915968 -235.730387) (xy 101.919532 -235.713016)
			(xy 101.925628 -235.686092) (xy 101.78288 -235.54309) (xy 101.78288 -235.303568) (xy 101.737414 -235.298742)
			(xy 101.712091 -235.295654) (xy 101.662788 -235.282554) (xy 101.616083 -235.262035) (xy 101.573084 -235.234583)
			(xy 101.534814 -235.200852) (xy 101.50218 -235.161641) (xy 101.475959 -235.117882) (xy 101.456771 -235.070614)
			(xy 101.445073 -235.020959) (xy 101.441143 -234.970096) (xy 101.162865 -234.970096) (xy 101.162357 -234.996033)
			(xy 101.154232 -235.047328) (xy 101.138184 -235.096721) (xy 101.114606 -235.142995) (xy 101.08408 -235.185011)
			(xy 101.047357 -235.221734) (xy 101.005341 -235.25226) (xy 100.959067 -235.275838) (xy 100.909674 -235.291886)
			(xy 100.858379 -235.300011) (xy 100.806445 -235.300011) (xy 100.75515 -235.291886) (xy 100.705757 -235.275838)
			(xy 100.659483 -235.25226) (xy 100.617467 -235.221734) (xy 100.580744 -235.185011) (xy 100.550218 -235.142995)
			(xy 100.52664 -235.096721) (xy 100.510592 -235.047328) (xy 100.502467 -234.996033) (xy 100.222557 -234.996033)
			(xy 100.214432 -235.047328) (xy 100.198384 -235.096721) (xy 100.174806 -235.142995) (xy 100.14428 -235.185011)
			(xy 100.107557 -235.221734) (xy 100.065541 -235.25226) (xy 100.019267 -235.275838) (xy 99.969874 -235.291886)
			(xy 99.918579 -235.300011) (xy 99.866645 -235.300011) (xy 99.81535 -235.291886) (xy 99.765957 -235.275838)
			(xy 99.719683 -235.25226) (xy 99.677667 -235.221734) (xy 99.640944 -235.185011) (xy 99.610418 -235.142995)
			(xy 99.58684 -235.096721) (xy 99.570792 -235.047328) (xy 99.562667 -234.996033) (xy 99.282757 -234.996033)
			(xy 99.274632 -235.047328) (xy 99.258584 -235.096721) (xy 99.235006 -235.142995) (xy 99.20448 -235.185011)
			(xy 99.167757 -235.221734) (xy 99.125741 -235.25226) (xy 99.079467 -235.275838) (xy 99.030074 -235.291886)
			(xy 98.978779 -235.300011) (xy 98.926845 -235.300011) (xy 98.87555 -235.291886) (xy 98.826157 -235.275838)
			(xy 98.779883 -235.25226) (xy 98.737867 -235.221734) (xy 98.701144 -235.185011) (xy 98.670618 -235.142995)
			(xy 98.64704 -235.096721) (xy 98.630992 -235.047328) (xy 98.622867 -234.996033) (xy 98.342957 -234.996033)
			(xy 98.334832 -235.047328) (xy 98.318784 -235.096721) (xy 98.295206 -235.142995) (xy 98.26468 -235.185011)
			(xy 98.227957 -235.221734) (xy 98.185941 -235.25226) (xy 98.139667 -235.275838) (xy 98.090274 -235.291886)
			(xy 98.038979 -235.300011) (xy 97.987045 -235.300011) (xy 97.93575 -235.291886) (xy 97.886357 -235.275838)
			(xy 97.840083 -235.25226) (xy 97.798067 -235.221734) (xy 97.761344 -235.185011) (xy 97.730818 -235.142995)
			(xy 97.70724 -235.096721) (xy 97.691192 -235.047328) (xy 97.683067 -234.996033) (xy 97.403411 -234.996033)
			(xy 97.395286 -235.047328) (xy 97.379238 -235.096721) (xy 97.35566 -235.142995) (xy 97.325134 -235.185011)
			(xy 97.288411 -235.221734) (xy 97.246395 -235.25226) (xy 97.200121 -235.275838) (xy 97.150728 -235.291886)
			(xy 97.099433 -235.300011) (xy 97.047499 -235.300011) (xy 96.996204 -235.291886) (xy 96.946811 -235.275838)
			(xy 96.900537 -235.25226) (xy 96.858521 -235.221734) (xy 96.821798 -235.185011) (xy 96.791272 -235.142995)
			(xy 96.767694 -235.096721) (xy 96.751646 -235.047328) (xy 96.743521 -234.996033) (xy 96.463357 -234.996033)
			(xy 96.455232 -235.047328) (xy 96.439184 -235.096721) (xy 96.415606 -235.142995) (xy 96.38508 -235.185011)
			(xy 96.348357 -235.221734) (xy 96.306341 -235.25226) (xy 96.260067 -235.275838) (xy 96.210674 -235.291886)
			(xy 96.159379 -235.300011) (xy 96.107445 -235.300011) (xy 96.05615 -235.291886) (xy 96.006757 -235.275838)
			(xy 95.960483 -235.25226) (xy 95.918467 -235.221734) (xy 95.881744 -235.185011) (xy 95.851218 -235.142995)
			(xy 95.82764 -235.096721) (xy 95.811592 -235.047328) (xy 95.803467 -234.996033) (xy 95.523557 -234.996033)
			(xy 95.515432 -235.047328) (xy 95.499384 -235.096721) (xy 95.475806 -235.142995) (xy 95.44528 -235.185011)
			(xy 95.408557 -235.221734) (xy 95.366541 -235.25226) (xy 95.320267 -235.275838) (xy 95.270874 -235.291886)
			(xy 95.219579 -235.300011) (xy 95.167645 -235.300011) (xy 95.11635 -235.291886) (xy 95.066957 -235.275838)
			(xy 95.020683 -235.25226) (xy 94.978667 -235.221734) (xy 94.941944 -235.185011) (xy 94.911418 -235.142995)
			(xy 94.88784 -235.096721) (xy 94.871792 -235.047328) (xy 94.863667 -234.996033) (xy 94.583757 -234.996033)
			(xy 94.575632 -235.047328) (xy 94.559584 -235.096721) (xy 94.536006 -235.142995) (xy 94.50548 -235.185011)
			(xy 94.468757 -235.221734) (xy 94.426741 -235.25226) (xy 94.380467 -235.275838) (xy 94.331074 -235.291886)
			(xy 94.279779 -235.300011) (xy 94.227845 -235.300011) (xy 94.17655 -235.291886) (xy 94.127157 -235.275838)
			(xy 94.080883 -235.25226) (xy 94.038867 -235.221734) (xy 94.002144 -235.185011) (xy 93.971618 -235.142995)
			(xy 93.94804 -235.096721) (xy 93.931992 -235.047328) (xy 93.923867 -234.996033) (xy 93.643957 -234.996033)
			(xy 93.635832 -235.047328) (xy 93.619784 -235.096721) (xy 93.596206 -235.142995) (xy 93.56568 -235.185011)
			(xy 93.528957 -235.221734) (xy 93.486941 -235.25226) (xy 93.440667 -235.275838) (xy 93.391274 -235.291886)
			(xy 93.339979 -235.300011) (xy 93.288045 -235.300011) (xy 93.23675 -235.291886) (xy 93.187357 -235.275838)
			(xy 93.141083 -235.25226) (xy 93.099067 -235.221734) (xy 93.062344 -235.185011) (xy 93.031818 -235.142995)
			(xy 93.00824 -235.096721) (xy 92.992192 -235.047328) (xy 92.984067 -234.996033) (xy 92.704157 -234.996033)
			(xy 92.696032 -235.047328) (xy 92.679984 -235.096721) (xy 92.656406 -235.142995) (xy 92.62588 -235.185011)
			(xy 92.589157 -235.221734) (xy 92.547141 -235.25226) (xy 92.500867 -235.275838) (xy 92.451474 -235.291886)
			(xy 92.400179 -235.300011) (xy 92.348245 -235.300011) (xy 92.29695 -235.291886) (xy 92.247557 -235.275838)
			(xy 92.201283 -235.25226) (xy 92.159267 -235.221734) (xy 92.122544 -235.185011) (xy 92.092018 -235.142995)
			(xy 92.06844 -235.096721) (xy 92.052392 -235.047328) (xy 92.044267 -234.996033) (xy 91.764784 -234.996033)
			(xy 91.764784 -234.996613) (xy 91.756313 -235.048987) (xy 91.739588 -235.099336) (xy 91.715036 -235.146367)
			(xy 91.683288 -235.188875) (xy 91.645159 -235.225766) (xy 91.601628 -235.256095) (xy 91.577922 -235.268008)
			(xy 91.565222 -235.274104) (xy 91.53525 -235.31957) (xy 91.53525 -235.447332) (xy 91.535677 -235.456356)
			(xy 91.542131 -235.473215) (xy 91.554123 -235.486707) (xy 91.56192 -235.491274) (xy 91.604846 -235.511848)
			(xy 91.645232 -235.531406) (xy 91.650455 -235.533746) (xy 91.661609 -235.536301) (xy 91.66733 -235.536486)
			(xy 91.69781 -235.525564) (xy 91.70416 -235.520738) (xy 91.725908 -235.504858) (xy 91.773477 -235.479626)
			(xy 91.824504 -235.462429) (xy 91.877642 -235.453722) (xy 91.904566 -235.453174) (xy 91.930558 -235.453655)
			(xy 91.981904 -235.461782) (xy 92.031346 -235.477842) (xy 92.077666 -235.501439) (xy 92.119725 -235.531993)
			(xy 92.156485 -235.56875) (xy 92.187043 -235.610805) (xy 92.210645 -235.657123) (xy 92.22671 -235.706563)
			(xy 92.234843 -235.757908) (xy 92.234843 -235.809849) (xy 92.514421 -235.809849) (xy 92.514421 -235.757915)
			(xy 92.522546 -235.70662) (xy 92.538594 -235.657227) (xy 92.562172 -235.610953) (xy 92.592698 -235.568937)
			(xy 92.629421 -235.532214) (xy 92.671437 -235.501688) (xy 92.717711 -235.47811) (xy 92.767104 -235.462062)
			(xy 92.818399 -235.453937) (xy 92.870333 -235.453937) (xy 92.921628 -235.462062) (xy 92.971021 -235.47811)
			(xy 93.017295 -235.501688) (xy 93.059311 -235.532214) (xy 93.096034 -235.568937) (xy 93.12656 -235.610953)
			(xy 93.150138 -235.657227) (xy 93.166186 -235.70662) (xy 93.174311 -235.757915) (xy 93.17482 -235.783882)
			(xy 93.174311 -235.809849) (xy 93.454221 -235.809849) (xy 93.454221 -235.757915) (xy 93.462346 -235.70662)
			(xy 93.478394 -235.657227) (xy 93.501972 -235.610953) (xy 93.532498 -235.568937) (xy 93.569221 -235.532214)
			(xy 93.611237 -235.501688) (xy 93.657511 -235.47811) (xy 93.706904 -235.462062) (xy 93.758199 -235.453937)
			(xy 93.810133 -235.453937) (xy 93.861428 -235.462062) (xy 93.910821 -235.47811) (xy 93.957095 -235.501688)
			(xy 93.999111 -235.532214) (xy 94.035834 -235.568937) (xy 94.06636 -235.610953) (xy 94.089938 -235.657227)
			(xy 94.105986 -235.70662) (xy 94.114111 -235.757915) (xy 94.11462 -235.783882) (xy 94.114111 -235.809849)
			(xy 94.394021 -235.809849) (xy 94.394021 -235.757915) (xy 94.402146 -235.70662) (xy 94.418194 -235.657227)
			(xy 94.441772 -235.610953) (xy 94.472298 -235.568937) (xy 94.509021 -235.532214) (xy 94.551037 -235.501688)
			(xy 94.597311 -235.47811) (xy 94.646704 -235.462062) (xy 94.697999 -235.453937) (xy 94.749933 -235.453937)
			(xy 94.801228 -235.462062) (xy 94.850621 -235.47811) (xy 94.896895 -235.501688) (xy 94.938911 -235.532214)
			(xy 94.975634 -235.568937) (xy 95.00616 -235.610953) (xy 95.029738 -235.657227) (xy 95.045786 -235.70662)
			(xy 95.053911 -235.757915) (xy 95.05442 -235.783882) (xy 95.053911 -235.809849) (xy 95.333821 -235.809849)
			(xy 95.333821 -235.757915) (xy 95.341946 -235.70662) (xy 95.357994 -235.657227) (xy 95.381572 -235.610953)
			(xy 95.412098 -235.568937) (xy 95.448821 -235.532214) (xy 95.490837 -235.501688) (xy 95.537111 -235.47811)
			(xy 95.586504 -235.462062) (xy 95.637799 -235.453937) (xy 95.689733 -235.453937) (xy 95.741028 -235.462062)
			(xy 95.790421 -235.47811) (xy 95.836695 -235.501688) (xy 95.878711 -235.532214) (xy 95.915434 -235.568937)
			(xy 95.94596 -235.610953) (xy 95.969538 -235.657227) (xy 95.985586 -235.70662) (xy 95.993711 -235.757915)
			(xy 95.99422 -235.783882) (xy 95.993711 -235.809849) (xy 96.273621 -235.809849) (xy 96.273621 -235.757915)
			(xy 96.281746 -235.70662) (xy 96.297794 -235.657227) (xy 96.321372 -235.610953) (xy 96.351898 -235.568937)
			(xy 96.388621 -235.532214) (xy 96.430637 -235.501688) (xy 96.476911 -235.47811) (xy 96.526304 -235.462062)
			(xy 96.577599 -235.453937) (xy 96.629533 -235.453937) (xy 96.680828 -235.462062) (xy 96.730221 -235.47811)
			(xy 96.776495 -235.501688) (xy 96.818511 -235.532214) (xy 96.855234 -235.568937) (xy 96.88576 -235.610953)
			(xy 96.909338 -235.657227) (xy 96.925386 -235.70662) (xy 96.933511 -235.757915) (xy 96.93402 -235.783882)
			(xy 96.933511 -235.809849) (xy 97.213167 -235.809849) (xy 97.213167 -235.757915) (xy 97.221292 -235.70662)
			(xy 97.23734 -235.657227) (xy 97.260918 -235.610953) (xy 97.291444 -235.568937) (xy 97.328167 -235.532214)
			(xy 97.370183 -235.501688) (xy 97.416457 -235.47811) (xy 97.46585 -235.462062) (xy 97.517145 -235.453937)
			(xy 97.569079 -235.453937) (xy 97.620374 -235.462062) (xy 97.669767 -235.47811) (xy 97.716041 -235.501688)
			(xy 97.758057 -235.532214) (xy 97.79478 -235.568937) (xy 97.825306 -235.610953) (xy 97.848884 -235.657227)
			(xy 97.864932 -235.70662) (xy 97.873057 -235.757915) (xy 97.873566 -235.783882) (xy 97.873057 -235.809849)
			(xy 98.153221 -235.809849) (xy 98.153221 -235.757915) (xy 98.161346 -235.70662) (xy 98.177394 -235.657227)
			(xy 98.200972 -235.610953) (xy 98.231498 -235.568937) (xy 98.268221 -235.532214) (xy 98.310237 -235.501688)
			(xy 98.356511 -235.47811) (xy 98.405904 -235.462062) (xy 98.457199 -235.453937) (xy 98.509133 -235.453937)
			(xy 98.560428 -235.462062) (xy 98.609821 -235.47811) (xy 98.656095 -235.501688) (xy 98.698111 -235.532214)
			(xy 98.734834 -235.568937) (xy 98.76536 -235.610953) (xy 98.788938 -235.657227) (xy 98.804986 -235.70662)
			(xy 98.813111 -235.757915) (xy 98.81362 -235.783882) (xy 98.813111 -235.809849) (xy 99.093021 -235.809849)
			(xy 99.093021 -235.757915) (xy 99.101146 -235.70662) (xy 99.117194 -235.657227) (xy 99.140772 -235.610953)
			(xy 99.171298 -235.568937) (xy 99.208021 -235.532214) (xy 99.250037 -235.501688) (xy 99.296311 -235.47811)
			(xy 99.345704 -235.462062) (xy 99.396999 -235.453937) (xy 99.448933 -235.453937) (xy 99.500228 -235.462062)
			(xy 99.549621 -235.47811) (xy 99.595895 -235.501688) (xy 99.637911 -235.532214) (xy 99.674634 -235.568937)
			(xy 99.70516 -235.610953) (xy 99.728738 -235.657227) (xy 99.744786 -235.70662) (xy 99.752911 -235.757915)
			(xy 99.75342 -235.783882) (xy 99.752911 -235.809849) (xy 100.032821 -235.809849) (xy 100.032821 -235.757915)
			(xy 100.040946 -235.70662) (xy 100.056994 -235.657227) (xy 100.080572 -235.610953) (xy 100.111098 -235.568937)
			(xy 100.147821 -235.532214) (xy 100.189837 -235.501688) (xy 100.236111 -235.47811) (xy 100.285504 -235.462062)
			(xy 100.336799 -235.453937) (xy 100.388733 -235.453937) (xy 100.440028 -235.462062) (xy 100.489421 -235.47811)
			(xy 100.535695 -235.501688) (xy 100.577711 -235.532214) (xy 100.614434 -235.568937) (xy 100.64496 -235.610953)
			(xy 100.668538 -235.657227) (xy 100.684586 -235.70662) (xy 100.692711 -235.757915) (xy 100.69322 -235.783882)
			(xy 100.692711 -235.809849) (xy 100.972621 -235.809849) (xy 100.972621 -235.757915) (xy 100.980746 -235.70662)
			(xy 100.996794 -235.657227) (xy 101.020372 -235.610953) (xy 101.050898 -235.568937) (xy 101.087621 -235.532214)
			(xy 101.129637 -235.501688) (xy 101.175911 -235.47811) (xy 101.225304 -235.462062) (xy 101.276599 -235.453937)
			(xy 101.328533 -235.453937) (xy 101.379828 -235.462062) (xy 101.429221 -235.47811) (xy 101.475495 -235.501688)
			(xy 101.517511 -235.532214) (xy 101.554234 -235.568937) (xy 101.58476 -235.610953) (xy 101.608338 -235.657227)
			(xy 101.624386 -235.70662) (xy 101.632511 -235.757915) (xy 101.63302 -235.783882) (xy 101.632511 -235.809849)
			(xy 101.624386 -235.861144) (xy 101.608338 -235.910537) (xy 101.58476 -235.956811) (xy 101.554234 -235.998827)
			(xy 101.517511 -236.03555) (xy 101.475495 -236.066076) (xy 101.429221 -236.089654) (xy 101.379828 -236.105702)
			(xy 101.328533 -236.113827) (xy 101.276599 -236.113827) (xy 101.225304 -236.105702) (xy 101.175911 -236.089654)
			(xy 101.129637 -236.066076) (xy 101.087621 -236.03555) (xy 101.050898 -235.998827) (xy 101.020372 -235.956811)
			(xy 100.996794 -235.910537) (xy 100.980746 -235.861144) (xy 100.972621 -235.809849) (xy 100.692711 -235.809849)
			(xy 100.684586 -235.861144) (xy 100.668538 -235.910537) (xy 100.64496 -235.956811) (xy 100.614434 -235.998827)
			(xy 100.577711 -236.03555) (xy 100.535695 -236.066076) (xy 100.489421 -236.089654) (xy 100.440028 -236.105702)
			(xy 100.388733 -236.113827) (xy 100.336799 -236.113827) (xy 100.285504 -236.105702) (xy 100.236111 -236.089654)
			(xy 100.189837 -236.066076) (xy 100.147821 -236.03555) (xy 100.111098 -235.998827) (xy 100.080572 -235.956811)
			(xy 100.056994 -235.910537) (xy 100.040946 -235.861144) (xy 100.032821 -235.809849) (xy 99.752911 -235.809849)
			(xy 99.744786 -235.861144) (xy 99.728738 -235.910537) (xy 99.70516 -235.956811) (xy 99.674634 -235.998827)
			(xy 99.637911 -236.03555) (xy 99.595895 -236.066076) (xy 99.549621 -236.089654) (xy 99.500228 -236.105702)
			(xy 99.448933 -236.113827) (xy 99.396999 -236.113827) (xy 99.345704 -236.105702) (xy 99.296311 -236.089654)
			(xy 99.250037 -236.066076) (xy 99.208021 -236.03555) (xy 99.171298 -235.998827) (xy 99.140772 -235.956811)
			(xy 99.117194 -235.910537) (xy 99.101146 -235.861144) (xy 99.093021 -235.809849) (xy 98.813111 -235.809849)
			(xy 98.804986 -235.861144) (xy 98.788938 -235.910537) (xy 98.76536 -235.956811) (xy 98.734834 -235.998827)
			(xy 98.698111 -236.03555) (xy 98.656095 -236.066076) (xy 98.609821 -236.089654) (xy 98.560428 -236.105702)
			(xy 98.509133 -236.113827) (xy 98.457199 -236.113827) (xy 98.405904 -236.105702) (xy 98.356511 -236.089654)
			(xy 98.310237 -236.066076) (xy 98.268221 -236.03555) (xy 98.231498 -235.998827) (xy 98.200972 -235.956811)
			(xy 98.177394 -235.910537) (xy 98.161346 -235.861144) (xy 98.153221 -235.809849) (xy 97.873057 -235.809849)
			(xy 97.864932 -235.861144) (xy 97.848884 -235.910537) (xy 97.825306 -235.956811) (xy 97.79478 -235.998827)
			(xy 97.758057 -236.03555) (xy 97.716041 -236.066076) (xy 97.669767 -236.089654) (xy 97.620374 -236.105702)
			(xy 97.569079 -236.113827) (xy 97.517145 -236.113827) (xy 97.46585 -236.105702) (xy 97.416457 -236.089654)
			(xy 97.370183 -236.066076) (xy 97.328167 -236.03555) (xy 97.291444 -235.998827) (xy 97.260918 -235.956811)
			(xy 97.23734 -235.910537) (xy 97.221292 -235.861144) (xy 97.213167 -235.809849) (xy 96.933511 -235.809849)
			(xy 96.925386 -235.861144) (xy 96.909338 -235.910537) (xy 96.88576 -235.956811) (xy 96.855234 -235.998827)
			(xy 96.818511 -236.03555) (xy 96.776495 -236.066076) (xy 96.730221 -236.089654) (xy 96.680828 -236.105702)
			(xy 96.629533 -236.113827) (xy 96.577599 -236.113827) (xy 96.526304 -236.105702) (xy 96.476911 -236.089654)
			(xy 96.430637 -236.066076) (xy 96.388621 -236.03555) (xy 96.351898 -235.998827) (xy 96.321372 -235.956811)
			(xy 96.297794 -235.910537) (xy 96.281746 -235.861144) (xy 96.273621 -235.809849) (xy 95.993711 -235.809849)
			(xy 95.985586 -235.861144) (xy 95.969538 -235.910537) (xy 95.94596 -235.956811) (xy 95.915434 -235.998827)
			(xy 95.878711 -236.03555) (xy 95.836695 -236.066076) (xy 95.790421 -236.089654) (xy 95.741028 -236.105702)
			(xy 95.689733 -236.113827) (xy 95.637799 -236.113827) (xy 95.586504 -236.105702) (xy 95.537111 -236.089654)
			(xy 95.490837 -236.066076) (xy 95.448821 -236.03555) (xy 95.412098 -235.998827) (xy 95.381572 -235.956811)
			(xy 95.357994 -235.910537) (xy 95.341946 -235.861144) (xy 95.333821 -235.809849) (xy 95.053911 -235.809849)
			(xy 95.045786 -235.861144) (xy 95.029738 -235.910537) (xy 95.00616 -235.956811) (xy 94.975634 -235.998827)
			(xy 94.938911 -236.03555) (xy 94.896895 -236.066076) (xy 94.850621 -236.089654) (xy 94.801228 -236.105702)
			(xy 94.749933 -236.113827) (xy 94.697999 -236.113827) (xy 94.646704 -236.105702) (xy 94.597311 -236.089654)
			(xy 94.551037 -236.066076) (xy 94.509021 -236.03555) (xy 94.472298 -235.998827) (xy 94.441772 -235.956811)
			(xy 94.418194 -235.910537) (xy 94.402146 -235.861144) (xy 94.394021 -235.809849) (xy 94.114111 -235.809849)
			(xy 94.105986 -235.861144) (xy 94.089938 -235.910537) (xy 94.06636 -235.956811) (xy 94.035834 -235.998827)
			(xy 93.999111 -236.03555) (xy 93.957095 -236.066076) (xy 93.910821 -236.089654) (xy 93.861428 -236.105702)
			(xy 93.810133 -236.113827) (xy 93.758199 -236.113827) (xy 93.706904 -236.105702) (xy 93.657511 -236.089654)
			(xy 93.611237 -236.066076) (xy 93.569221 -236.03555) (xy 93.532498 -235.998827) (xy 93.501972 -235.956811)
			(xy 93.478394 -235.910537) (xy 93.462346 -235.861144) (xy 93.454221 -235.809849) (xy 93.174311 -235.809849)
			(xy 93.166186 -235.861144) (xy 93.150138 -235.910537) (xy 93.12656 -235.956811) (xy 93.096034 -235.998827)
			(xy 93.059311 -236.03555) (xy 93.017295 -236.066076) (xy 92.971021 -236.089654) (xy 92.921628 -236.105702)
			(xy 92.870333 -236.113827) (xy 92.818399 -236.113827) (xy 92.767104 -236.105702) (xy 92.717711 -236.089654)
			(xy 92.671437 -236.066076) (xy 92.629421 -236.03555) (xy 92.592698 -235.998827) (xy 92.562172 -235.956811)
			(xy 92.538594 -235.910537) (xy 92.522546 -235.861144) (xy 92.514421 -235.809849) (xy 92.234843 -235.809849)
			(xy 92.234843 -235.809892) (xy 92.22671 -235.861237) (xy 92.210645 -235.910677) (xy 92.187043 -235.956995)
			(xy 92.156485 -235.99905) (xy 92.119725 -236.035807) (xy 92.077666 -236.066361) (xy 92.031346 -236.089958)
			(xy 91.981904 -236.106018) (xy 91.930558 -236.114145) (xy 91.904566 -236.11459) (xy 91.877643 -236.114059)
			(xy 91.824507 -236.105338) (xy 91.773484 -236.08813) (xy 91.725919 -236.062891) (xy 91.70416 -236.047026)
			(xy 91.69781 -236.0422) (xy 91.66733 -236.031278) (xy 91.661602 -236.031394) (xy 91.65044 -236.033968)
			(xy 91.645232 -236.036358) (xy 91.604846 -236.055916) (xy 91.56192 -236.07649) (xy 91.554123 -236.081048)
			(xy 91.542158 -236.094559) (xy 91.535698 -236.111411) (xy 91.53525 -236.120432) (xy 91.53525 -236.248448)
			(xy 91.565222 -236.293914) (xy 91.577922 -236.30001) (xy 91.601604 -236.311976) (xy 91.64514 -236.342302)
			(xy 91.683274 -236.37919) (xy 91.715027 -236.421696) (xy 91.739585 -236.468727) (xy 91.756317 -236.519076)
			(xy 91.764794 -236.571451) (xy 91.764797 -236.623919) (xy 92.044267 -236.623919) (xy 92.044267 -236.571985)
			(xy 92.052392 -236.52069) (xy 92.06844 -236.471297) (xy 92.092018 -236.425023) (xy 92.122544 -236.383007)
			(xy 92.159267 -236.346284) (xy 92.201283 -236.315758) (xy 92.247557 -236.29218) (xy 92.29695 -236.276132)
			(xy 92.348245 -236.268007) (xy 92.400179 -236.268007) (xy 92.451474 -236.276132) (xy 92.500867 -236.29218)
			(xy 92.547141 -236.315758) (xy 92.589157 -236.346284) (xy 92.62588 -236.383007) (xy 92.656406 -236.425023)
			(xy 92.679984 -236.471297) (xy 92.696032 -236.52069) (xy 92.704157 -236.571985) (xy 92.704666 -236.597952)
			(xy 92.704157 -236.623919) (xy 92.984067 -236.623919) (xy 92.984067 -236.571985) (xy 92.992192 -236.52069)
			(xy 93.00824 -236.471297) (xy 93.031818 -236.425023) (xy 93.062344 -236.383007) (xy 93.099067 -236.346284)
			(xy 93.141083 -236.315758) (xy 93.187357 -236.29218) (xy 93.23675 -236.276132) (xy 93.288045 -236.268007)
			(xy 93.339979 -236.268007) (xy 93.391274 -236.276132) (xy 93.440667 -236.29218) (xy 93.486941 -236.315758)
			(xy 93.528957 -236.346284) (xy 93.56568 -236.383007) (xy 93.596206 -236.425023) (xy 93.619784 -236.471297)
			(xy 93.635832 -236.52069) (xy 93.643957 -236.571985) (xy 93.644466 -236.597952) (xy 93.643957 -236.623919)
			(xy 93.924121 -236.623919) (xy 93.924121 -236.571985) (xy 93.932246 -236.52069) (xy 93.948294 -236.471297)
			(xy 93.971872 -236.425023) (xy 94.002398 -236.383007) (xy 94.039121 -236.346284) (xy 94.081137 -236.315758)
			(xy 94.127411 -236.29218) (xy 94.176804 -236.276132) (xy 94.228099 -236.268007) (xy 94.280033 -236.268007)
			(xy 94.331328 -236.276132) (xy 94.380721 -236.29218) (xy 94.426995 -236.315758) (xy 94.469011 -236.346284)
			(xy 94.505734 -236.383007) (xy 94.53626 -236.425023) (xy 94.559838 -236.471297) (xy 94.575886 -236.52069)
			(xy 94.584011 -236.571985) (xy 94.58452 -236.597952) (xy 94.584011 -236.623919) (xy 94.863667 -236.623919)
			(xy 94.863667 -236.571985) (xy 94.871792 -236.52069) (xy 94.88784 -236.471297) (xy 94.911418 -236.425023)
			(xy 94.941944 -236.383007) (xy 94.978667 -236.346284) (xy 95.020683 -236.315758) (xy 95.066957 -236.29218)
			(xy 95.11635 -236.276132) (xy 95.167645 -236.268007) (xy 95.219579 -236.268007) (xy 95.270874 -236.276132)
			(xy 95.320267 -236.29218) (xy 95.366541 -236.315758) (xy 95.408557 -236.346284) (xy 95.44528 -236.383007)
			(xy 95.475806 -236.425023) (xy 95.499384 -236.471297) (xy 95.515432 -236.52069) (xy 95.523557 -236.571985)
			(xy 95.524066 -236.597952) (xy 95.523557 -236.623919) (xy 95.803467 -236.623919) (xy 95.803467 -236.571985)
			(xy 95.811592 -236.52069) (xy 95.82764 -236.471297) (xy 95.851218 -236.425023) (xy 95.881744 -236.383007)
			(xy 95.918467 -236.346284) (xy 95.960483 -236.315758) (xy 96.006757 -236.29218) (xy 96.05615 -236.276132)
			(xy 96.107445 -236.268007) (xy 96.159379 -236.268007) (xy 96.210674 -236.276132) (xy 96.260067 -236.29218)
			(xy 96.306341 -236.315758) (xy 96.348357 -236.346284) (xy 96.38508 -236.383007) (xy 96.415606 -236.425023)
			(xy 96.439184 -236.471297) (xy 96.455232 -236.52069) (xy 96.463357 -236.571985) (xy 96.463866 -236.597952)
			(xy 96.463357 -236.623919) (xy 96.743267 -236.623919) (xy 96.743267 -236.571985) (xy 96.751392 -236.52069)
			(xy 96.76744 -236.471297) (xy 96.791018 -236.425023) (xy 96.821544 -236.383007) (xy 96.858267 -236.346284)
			(xy 96.900283 -236.315758) (xy 96.946557 -236.29218) (xy 96.99595 -236.276132) (xy 97.047245 -236.268007)
			(xy 97.099179 -236.268007) (xy 97.150474 -236.276132) (xy 97.199867 -236.29218) (xy 97.246141 -236.315758)
			(xy 97.288157 -236.346284) (xy 97.32488 -236.383007) (xy 97.355406 -236.425023) (xy 97.378984 -236.471297)
			(xy 97.395032 -236.52069) (xy 97.403157 -236.571985) (xy 97.403666 -236.597952) (xy 97.403157 -236.623919)
			(xy 97.683067 -236.623919) (xy 97.683067 -236.571985) (xy 97.691192 -236.52069) (xy 97.70724 -236.471297)
			(xy 97.730818 -236.425023) (xy 97.761344 -236.383007) (xy 97.798067 -236.346284) (xy 97.840083 -236.315758)
			(xy 97.886357 -236.29218) (xy 97.93575 -236.276132) (xy 97.987045 -236.268007) (xy 98.038979 -236.268007)
			(xy 98.090274 -236.276132) (xy 98.139667 -236.29218) (xy 98.185941 -236.315758) (xy 98.227957 -236.346284)
			(xy 98.26468 -236.383007) (xy 98.295206 -236.425023) (xy 98.318784 -236.471297) (xy 98.334832 -236.52069)
			(xy 98.342957 -236.571985) (xy 98.343466 -236.597952) (xy 98.342957 -236.623919) (xy 98.622867 -236.623919)
			(xy 98.622867 -236.571985) (xy 98.630992 -236.52069) (xy 98.64704 -236.471297) (xy 98.670618 -236.425023)
			(xy 98.701144 -236.383007) (xy 98.737867 -236.346284) (xy 98.779883 -236.315758) (xy 98.826157 -236.29218)
			(xy 98.87555 -236.276132) (xy 98.926845 -236.268007) (xy 98.978779 -236.268007) (xy 99.030074 -236.276132)
			(xy 99.079467 -236.29218) (xy 99.125741 -236.315758) (xy 99.167757 -236.346284) (xy 99.20448 -236.383007)
			(xy 99.235006 -236.425023) (xy 99.258584 -236.471297) (xy 99.274632 -236.52069) (xy 99.282757 -236.571985)
			(xy 99.283266 -236.597952) (xy 99.282757 -236.623919) (xy 99.562667 -236.623919) (xy 99.562667 -236.571985)
			(xy 99.570792 -236.52069) (xy 99.58684 -236.471297) (xy 99.610418 -236.425023) (xy 99.640944 -236.383007)
			(xy 99.677667 -236.346284) (xy 99.719683 -236.315758) (xy 99.765957 -236.29218) (xy 99.81535 -236.276132)
			(xy 99.866645 -236.268007) (xy 99.918579 -236.268007) (xy 99.969874 -236.276132) (xy 100.019267 -236.29218)
			(xy 100.065541 -236.315758) (xy 100.107557 -236.346284) (xy 100.14428 -236.383007) (xy 100.174806 -236.425023)
			(xy 100.198384 -236.471297) (xy 100.214432 -236.52069) (xy 100.222557 -236.571985) (xy 100.223066 -236.597952)
			(xy 100.222557 -236.623919) (xy 100.502721 -236.623919) (xy 100.502721 -236.571985) (xy 100.510846 -236.52069)
			(xy 100.526894 -236.471297) (xy 100.550472 -236.425023) (xy 100.580998 -236.383007) (xy 100.617721 -236.346284)
			(xy 100.659737 -236.315758) (xy 100.706011 -236.29218) (xy 100.755404 -236.276132) (xy 100.806699 -236.268007)
			(xy 100.858633 -236.268007) (xy 100.909928 -236.276132) (xy 100.959321 -236.29218) (xy 101.005595 -236.315758)
			(xy 101.047611 -236.346284) (xy 101.084334 -236.383007) (xy 101.11486 -236.425023) (xy 101.138438 -236.471297)
			(xy 101.154486 -236.52069) (xy 101.162611 -236.571985) (xy 101.16312 -236.597952) (xy 101.162611 -236.623919)
			(xy 101.442267 -236.623919) (xy 101.442267 -236.571985) (xy 101.450392 -236.52069) (xy 101.46644 -236.471297)
			(xy 101.490018 -236.425023) (xy 101.520544 -236.383007) (xy 101.557267 -236.346284) (xy 101.599283 -236.315758)
			(xy 101.645557 -236.29218) (xy 101.69495 -236.276132) (xy 101.746245 -236.268007) (xy 101.798179 -236.268007)
			(xy 101.849474 -236.276132) (xy 101.898867 -236.29218) (xy 101.945141 -236.315758) (xy 101.987157 -236.346284)
			(xy 102.02388 -236.383007) (xy 102.054406 -236.425023) (xy 102.077984 -236.471297) (xy 102.094032 -236.52069)
			(xy 102.102157 -236.571985) (xy 102.102666 -236.597952) (xy 102.102157 -236.623919) (xy 102.094032 -236.675214)
			(xy 102.077984 -236.724607) (xy 102.054406 -236.770881) (xy 102.02388 -236.812897) (xy 101.987157 -236.84962)
			(xy 101.945141 -236.880146) (xy 101.898867 -236.903724) (xy 101.849474 -236.919772) (xy 101.798179 -236.927897)
			(xy 101.746245 -236.927897) (xy 101.69495 -236.919772) (xy 101.645557 -236.903724) (xy 101.599283 -236.880146)
			(xy 101.557267 -236.84962) (xy 101.520544 -236.812897) (xy 101.490018 -236.770881) (xy 101.46644 -236.724607)
			(xy 101.450392 -236.675214) (xy 101.442267 -236.623919) (xy 101.162611 -236.623919) (xy 101.154486 -236.675214)
			(xy 101.138438 -236.724607) (xy 101.11486 -236.770881) (xy 101.084334 -236.812897) (xy 101.047611 -236.84962)
			(xy 101.005595 -236.880146) (xy 100.959321 -236.903724) (xy 100.909928 -236.919772) (xy 100.858633 -236.927897)
			(xy 100.806699 -236.927897) (xy 100.755404 -236.919772) (xy 100.706011 -236.903724) (xy 100.659737 -236.880146)
			(xy 100.617721 -236.84962) (xy 100.580998 -236.812897) (xy 100.550472 -236.770881) (xy 100.526894 -236.724607)
			(xy 100.510846 -236.675214) (xy 100.502721 -236.623919) (xy 100.222557 -236.623919) (xy 100.214432 -236.675214)
			(xy 100.198384 -236.724607) (xy 100.174806 -236.770881) (xy 100.14428 -236.812897) (xy 100.107557 -236.84962)
			(xy 100.065541 -236.880146) (xy 100.019267 -236.903724) (xy 99.969874 -236.919772) (xy 99.918579 -236.927897)
			(xy 99.866645 -236.927897) (xy 99.81535 -236.919772) (xy 99.765957 -236.903724) (xy 99.719683 -236.880146)
			(xy 99.677667 -236.84962) (xy 99.640944 -236.812897) (xy 99.610418 -236.770881) (xy 99.58684 -236.724607)
			(xy 99.570792 -236.675214) (xy 99.562667 -236.623919) (xy 99.282757 -236.623919) (xy 99.274632 -236.675214)
			(xy 99.258584 -236.724607) (xy 99.235006 -236.770881) (xy 99.20448 -236.812897) (xy 99.167757 -236.84962)
			(xy 99.125741 -236.880146) (xy 99.079467 -236.903724) (xy 99.030074 -236.919772) (xy 98.978779 -236.927897)
			(xy 98.926845 -236.927897) (xy 98.87555 -236.919772) (xy 98.826157 -236.903724) (xy 98.779883 -236.880146)
			(xy 98.737867 -236.84962) (xy 98.701144 -236.812897) (xy 98.670618 -236.770881) (xy 98.64704 -236.724607)
			(xy 98.630992 -236.675214) (xy 98.622867 -236.623919) (xy 98.342957 -236.623919) (xy 98.334832 -236.675214)
			(xy 98.318784 -236.724607) (xy 98.295206 -236.770881) (xy 98.26468 -236.812897) (xy 98.227957 -236.84962)
			(xy 98.185941 -236.880146) (xy 98.139667 -236.903724) (xy 98.090274 -236.919772) (xy 98.038979 -236.927897)
			(xy 97.987045 -236.927897) (xy 97.93575 -236.919772) (xy 97.886357 -236.903724) (xy 97.840083 -236.880146)
			(xy 97.798067 -236.84962) (xy 97.761344 -236.812897) (xy 97.730818 -236.770881) (xy 97.70724 -236.724607)
			(xy 97.691192 -236.675214) (xy 97.683067 -236.623919) (xy 97.403157 -236.623919) (xy 97.395032 -236.675214)
			(xy 97.378984 -236.724607) (xy 97.355406 -236.770881) (xy 97.32488 -236.812897) (xy 97.288157 -236.84962)
			(xy 97.246141 -236.880146) (xy 97.199867 -236.903724) (xy 97.150474 -236.919772) (xy 97.099179 -236.927897)
			(xy 97.047245 -236.927897) (xy 96.99595 -236.919772) (xy 96.946557 -236.903724) (xy 96.900283 -236.880146)
			(xy 96.858267 -236.84962) (xy 96.821544 -236.812897) (xy 96.791018 -236.770881) (xy 96.76744 -236.724607)
			(xy 96.751392 -236.675214) (xy 96.743267 -236.623919) (xy 96.463357 -236.623919) (xy 96.455232 -236.675214)
			(xy 96.439184 -236.724607) (xy 96.415606 -236.770881) (xy 96.38508 -236.812897) (xy 96.348357 -236.84962)
			(xy 96.306341 -236.880146) (xy 96.260067 -236.903724) (xy 96.210674 -236.919772) (xy 96.159379 -236.927897)
			(xy 96.107445 -236.927897) (xy 96.05615 -236.919772) (xy 96.006757 -236.903724) (xy 95.960483 -236.880146)
			(xy 95.918467 -236.84962) (xy 95.881744 -236.812897) (xy 95.851218 -236.770881) (xy 95.82764 -236.724607)
			(xy 95.811592 -236.675214) (xy 95.803467 -236.623919) (xy 95.523557 -236.623919) (xy 95.515432 -236.675214)
			(xy 95.499384 -236.724607) (xy 95.475806 -236.770881) (xy 95.44528 -236.812897) (xy 95.408557 -236.84962)
			(xy 95.366541 -236.880146) (xy 95.320267 -236.903724) (xy 95.270874 -236.919772) (xy 95.219579 -236.927897)
			(xy 95.167645 -236.927897) (xy 95.11635 -236.919772) (xy 95.066957 -236.903724) (xy 95.020683 -236.880146)
			(xy 94.978667 -236.84962) (xy 94.941944 -236.812897) (xy 94.911418 -236.770881) (xy 94.88784 -236.724607)
			(xy 94.871792 -236.675214) (xy 94.863667 -236.623919) (xy 94.584011 -236.623919) (xy 94.575886 -236.675214)
			(xy 94.559838 -236.724607) (xy 94.53626 -236.770881) (xy 94.505734 -236.812897) (xy 94.469011 -236.84962)
			(xy 94.426995 -236.880146) (xy 94.380721 -236.903724) (xy 94.331328 -236.919772) (xy 94.280033 -236.927897)
			(xy 94.228099 -236.927897) (xy 94.176804 -236.919772) (xy 94.127411 -236.903724) (xy 94.081137 -236.880146)
			(xy 94.039121 -236.84962) (xy 94.002398 -236.812897) (xy 93.971872 -236.770881) (xy 93.948294 -236.724607)
			(xy 93.932246 -236.675214) (xy 93.924121 -236.623919) (xy 93.643957 -236.623919) (xy 93.635832 -236.675214)
			(xy 93.619784 -236.724607) (xy 93.596206 -236.770881) (xy 93.56568 -236.812897) (xy 93.528957 -236.84962)
			(xy 93.486941 -236.880146) (xy 93.440667 -236.903724) (xy 93.391274 -236.919772) (xy 93.339979 -236.927897)
			(xy 93.288045 -236.927897) (xy 93.23675 -236.919772) (xy 93.187357 -236.903724) (xy 93.141083 -236.880146)
			(xy 93.099067 -236.84962) (xy 93.062344 -236.812897) (xy 93.031818 -236.770881) (xy 93.00824 -236.724607)
			(xy 92.992192 -236.675214) (xy 92.984067 -236.623919) (xy 92.704157 -236.623919) (xy 92.696032 -236.675214)
			(xy 92.679984 -236.724607) (xy 92.656406 -236.770881) (xy 92.62588 -236.812897) (xy 92.589157 -236.84962)
			(xy 92.547141 -236.880146) (xy 92.500867 -236.903724) (xy 92.451474 -236.919772) (xy 92.400179 -236.927897)
			(xy 92.348245 -236.927897) (xy 92.29695 -236.919772) (xy 92.247557 -236.903724) (xy 92.201283 -236.880146)
			(xy 92.159267 -236.84962) (xy 92.122544 -236.812897) (xy 92.092018 -236.770881) (xy 92.06844 -236.724607)
			(xy 92.052392 -236.675214) (xy 92.044267 -236.623919) (xy 91.764797 -236.623919) (xy 91.764797 -236.624508)
			(xy 91.756327 -236.676884) (xy 91.739602 -236.727235) (xy 91.71505 -236.774269) (xy 91.683301 -236.816778)
			(xy 91.645172 -236.853672) (xy 91.60164 -236.884003) (xy 91.577922 -236.895894) (xy 91.565222 -236.90199)
			(xy 91.53525 -236.947456) (xy 91.53525 -237.07471) (xy 91.535711 -237.083891) (xy 91.542362 -237.101012)
			(xy 91.554679 -237.114638) (xy 91.562682 -237.11916) (xy 91.648026 -237.160308) (xy 91.65248 -237.161971)
			(xy 91.661815 -237.163757) (xy 91.666568 -237.163864) (xy 91.69781 -237.152942) (xy 91.70416 -237.148116)
			(xy 91.725894 -237.132289) (xy 91.773415 -237.107146) (xy 91.824374 -237.090008) (xy 91.877431 -237.081326)
			(xy 91.904312 -237.080806) (xy 91.930297 -237.081316) (xy 91.981628 -237.089448) (xy 92.031055 -237.105509)
			(xy 92.077361 -237.129105) (xy 92.119406 -237.159654) (xy 92.156154 -237.196403) (xy 92.186701 -237.238449)
			(xy 92.210295 -237.284756) (xy 92.226355 -237.334183) (xy 92.234485 -237.385515) (xy 92.234485 -237.437481)
			(xy 92.514421 -237.437481) (xy 92.514421 -237.385547) (xy 92.522546 -237.334252) (xy 92.538594 -237.284859)
			(xy 92.562172 -237.238585) (xy 92.592698 -237.196569) (xy 92.629421 -237.159846) (xy 92.671437 -237.12932)
			(xy 92.717711 -237.105742) (xy 92.767104 -237.089694) (xy 92.818399 -237.081569) (xy 92.870333 -237.081569)
			(xy 92.921628 -237.089694) (xy 92.971021 -237.105742) (xy 93.017295 -237.12932) (xy 93.059311 -237.159846)
			(xy 93.096034 -237.196569) (xy 93.12656 -237.238585) (xy 93.150138 -237.284859) (xy 93.166186 -237.334252)
			(xy 93.174311 -237.385547) (xy 93.17482 -237.411514) (xy 93.174311 -237.437481) (xy 93.454221 -237.437481)
			(xy 93.454221 -237.385547) (xy 93.462346 -237.334252) (xy 93.478394 -237.284859) (xy 93.501972 -237.238585)
			(xy 93.532498 -237.196569) (xy 93.569221 -237.159846) (xy 93.611237 -237.12932) (xy 93.657511 -237.105742)
			(xy 93.706904 -237.089694) (xy 93.758199 -237.081569) (xy 93.810133 -237.081569) (xy 93.861428 -237.089694)
			(xy 93.910821 -237.105742) (xy 93.957095 -237.12932) (xy 93.999111 -237.159846) (xy 94.035834 -237.196569)
			(xy 94.06636 -237.238585) (xy 94.089938 -237.284859) (xy 94.105986 -237.334252) (xy 94.114111 -237.385547)
			(xy 94.11462 -237.411514) (xy 94.114111 -237.437481) (xy 94.394021 -237.437481) (xy 94.394021 -237.385547)
			(xy 94.402146 -237.334252) (xy 94.418194 -237.284859) (xy 94.441772 -237.238585) (xy 94.472298 -237.196569)
			(xy 94.509021 -237.159846) (xy 94.551037 -237.12932) (xy 94.597311 -237.105742) (xy 94.646704 -237.089694)
			(xy 94.697999 -237.081569) (xy 94.749933 -237.081569) (xy 94.801228 -237.089694) (xy 94.850621 -237.105742)
			(xy 94.896895 -237.12932) (xy 94.938911 -237.159846) (xy 94.975634 -237.196569) (xy 95.00616 -237.238585)
			(xy 95.029738 -237.284859) (xy 95.045786 -237.334252) (xy 95.053911 -237.385547) (xy 95.05442 -237.411514)
			(xy 95.053911 -237.437481) (xy 95.333821 -237.437481) (xy 95.333821 -237.385547) (xy 95.341946 -237.334252)
			(xy 95.357994 -237.284859) (xy 95.381572 -237.238585) (xy 95.412098 -237.196569) (xy 95.448821 -237.159846)
			(xy 95.490837 -237.12932) (xy 95.537111 -237.105742) (xy 95.586504 -237.089694) (xy 95.637799 -237.081569)
			(xy 95.689733 -237.081569) (xy 95.741028 -237.089694) (xy 95.790421 -237.105742) (xy 95.836695 -237.12932)
			(xy 95.878711 -237.159846) (xy 95.915434 -237.196569) (xy 95.94596 -237.238585) (xy 95.969538 -237.284859)
			(xy 95.985586 -237.334252) (xy 95.993711 -237.385547) (xy 95.99422 -237.411514) (xy 95.993711 -237.437481)
			(xy 96.273621 -237.437481) (xy 96.273621 -237.385547) (xy 96.281746 -237.334252) (xy 96.297794 -237.284859)
			(xy 96.321372 -237.238585) (xy 96.351898 -237.196569) (xy 96.388621 -237.159846) (xy 96.430637 -237.12932)
			(xy 96.476911 -237.105742) (xy 96.526304 -237.089694) (xy 96.577599 -237.081569) (xy 96.629533 -237.081569)
			(xy 96.680828 -237.089694) (xy 96.730221 -237.105742) (xy 96.776495 -237.12932) (xy 96.818511 -237.159846)
			(xy 96.855234 -237.196569) (xy 96.88576 -237.238585) (xy 96.909338 -237.284859) (xy 96.925386 -237.334252)
			(xy 96.933511 -237.385547) (xy 96.93402 -237.411514) (xy 96.933511 -237.437481) (xy 97.213421 -237.437481)
			(xy 97.213421 -237.385547) (xy 97.221546 -237.334252) (xy 97.237594 -237.284859) (xy 97.261172 -237.238585)
			(xy 97.291698 -237.196569) (xy 97.328421 -237.159846) (xy 97.370437 -237.12932) (xy 97.416711 -237.105742)
			(xy 97.466104 -237.089694) (xy 97.517399 -237.081569) (xy 97.569333 -237.081569) (xy 97.620628 -237.089694)
			(xy 97.670021 -237.105742) (xy 97.716295 -237.12932) (xy 97.758311 -237.159846) (xy 97.795034 -237.196569)
			(xy 97.82556 -237.238585) (xy 97.849138 -237.284859) (xy 97.865186 -237.334252) (xy 97.873311 -237.385547)
			(xy 97.87382 -237.411514) (xy 97.873311 -237.437481) (xy 98.152967 -237.437481) (xy 98.152967 -237.385547)
			(xy 98.161092 -237.334252) (xy 98.17714 -237.284859) (xy 98.200718 -237.238585) (xy 98.231244 -237.196569)
			(xy 98.267967 -237.159846) (xy 98.309983 -237.12932) (xy 98.356257 -237.105742) (xy 98.40565 -237.089694)
			(xy 98.456945 -237.081569) (xy 98.508879 -237.081569) (xy 98.560174 -237.089694) (xy 98.609567 -237.105742)
			(xy 98.655841 -237.12932) (xy 98.697857 -237.159846) (xy 98.73458 -237.196569) (xy 98.765106 -237.238585)
			(xy 98.788684 -237.284859) (xy 98.804732 -237.334252) (xy 98.812857 -237.385547) (xy 98.813366 -237.411514)
			(xy 98.812857 -237.437481) (xy 99.093021 -237.437481) (xy 99.093021 -237.385547) (xy 99.101146 -237.334252)
			(xy 99.117194 -237.284859) (xy 99.140772 -237.238585) (xy 99.171298 -237.196569) (xy 99.208021 -237.159846)
			(xy 99.250037 -237.12932) (xy 99.296311 -237.105742) (xy 99.345704 -237.089694) (xy 99.396999 -237.081569)
			(xy 99.448933 -237.081569) (xy 99.500228 -237.089694) (xy 99.549621 -237.105742) (xy 99.595895 -237.12932)
			(xy 99.637911 -237.159846) (xy 99.674634 -237.196569) (xy 99.70516 -237.238585) (xy 99.728738 -237.284859)
			(xy 99.744786 -237.334252) (xy 99.752911 -237.385547) (xy 99.75342 -237.411514) (xy 99.752911 -237.437481)
			(xy 100.032821 -237.437481) (xy 100.032821 -237.385547) (xy 100.040946 -237.334252) (xy 100.056994 -237.284859)
			(xy 100.080572 -237.238585) (xy 100.111098 -237.196569) (xy 100.147821 -237.159846) (xy 100.189837 -237.12932)
			(xy 100.236111 -237.105742) (xy 100.285504 -237.089694) (xy 100.336799 -237.081569) (xy 100.388733 -237.081569)
			(xy 100.440028 -237.089694) (xy 100.489421 -237.105742) (xy 100.535695 -237.12932) (xy 100.577711 -237.159846)
			(xy 100.614434 -237.196569) (xy 100.64496 -237.238585) (xy 100.668538 -237.284859) (xy 100.684586 -237.334252)
			(xy 100.692711 -237.385547) (xy 100.69322 -237.411514) (xy 100.692711 -237.437481) (xy 100.972621 -237.437481)
			(xy 100.972621 -237.385547) (xy 100.980746 -237.334252) (xy 100.996794 -237.284859) (xy 101.020372 -237.238585)
			(xy 101.050898 -237.196569) (xy 101.087621 -237.159846) (xy 101.129637 -237.12932) (xy 101.175911 -237.105742)
			(xy 101.225304 -237.089694) (xy 101.276599 -237.081569) (xy 101.328533 -237.081569) (xy 101.379828 -237.089694)
			(xy 101.429221 -237.105742) (xy 101.475495 -237.12932) (xy 101.517511 -237.159846) (xy 101.554234 -237.196569)
			(xy 101.58476 -237.238585) (xy 101.608338 -237.284859) (xy 101.624386 -237.334252) (xy 101.632511 -237.385547)
			(xy 101.63302 -237.411514) (xy 101.632511 -237.437464) (xy 101.912469 -237.437464) (xy 101.912469 -237.385536)
			(xy 101.920592 -237.334246) (xy 101.936638 -237.284858) (xy 101.960212 -237.238589) (xy 101.990733 -237.196576)
			(xy 102.02745 -237.159855) (xy 102.06946 -237.129329) (xy 102.115727 -237.105751) (xy 102.165113 -237.0897)
			(xy 102.216402 -237.081572) (xy 102.242366 -237.08106) (xy 102.266771 -237.081436) (xy 102.31505 -237.088625)
			(xy 102.361746 -237.102836) (xy 102.405844 -237.12376) (xy 102.446385 -237.150942) (xy 102.482487 -237.183792)
			(xy 102.513366 -237.221594) (xy 102.538349 -237.263526) (xy 102.556892 -237.308677) (xy 102.563168 -237.332266)
			(xy 102.566805 -237.345321) (xy 102.579982 -237.368994) (xy 102.598929 -237.38836) (xy 102.622306 -237.402054)
			(xy 102.648464 -237.409108) (xy 102.675557 -237.409025) (xy 102.701672 -237.40181) (xy 102.713536 -237.395258)
			(xy 102.739256 -237.38076) (xy 102.794576 -237.36015) (xy 102.852675 -237.349679) (xy 102.882192 -237.34903)
			(xy 102.908158 -237.349563) (xy 102.959451 -237.357685) (xy 103.008843 -237.373732) (xy 103.055115 -237.397307)
			(xy 103.097131 -237.427831) (xy 103.107036 -237.437735) (xy 109.431075 -237.437735) (xy 109.431075 -237.385801)
			(xy 109.4392 -237.334506) (xy 109.455248 -237.285113) (xy 109.478826 -237.238839) (xy 109.509352 -237.196823)
			(xy 109.546075 -237.1601) (xy 109.588091 -237.129574) (xy 109.634365 -237.105996) (xy 109.683758 -237.089948)
			(xy 109.735053 -237.081823) (xy 109.786987 -237.081823) (xy 109.838282 -237.089948) (xy 109.887675 -237.105996)
			(xy 109.933949 -237.129574) (xy 109.975965 -237.1601) (xy 110.012688 -237.196823) (xy 110.043214 -237.238839)
			(xy 110.066792 -237.285113) (xy 110.08284 -237.334506) (xy 110.090965 -237.385801) (xy 110.091474 -237.411768)
			(xy 110.090965 -237.437735) (xy 110.370875 -237.437735) (xy 110.370875 -237.385801) (xy 110.379 -237.334506)
			(xy 110.395048 -237.285113) (xy 110.418626 -237.238839) (xy 110.449152 -237.196823) (xy 110.485875 -237.1601)
			(xy 110.527891 -237.129574) (xy 110.574165 -237.105996) (xy 110.623558 -237.089948) (xy 110.674853 -237.081823)
			(xy 110.726787 -237.081823) (xy 110.778082 -237.089948) (xy 110.827475 -237.105996) (xy 110.873749 -237.129574)
			(xy 110.915765 -237.1601) (xy 110.952488 -237.196823) (xy 110.983014 -237.238839) (xy 111.006592 -237.285113)
			(xy 111.02264 -237.334506) (xy 111.030765 -237.385801) (xy 111.031274 -237.411768) (xy 111.030765 -237.437735)
			(xy 111.310675 -237.437735) (xy 111.310675 -237.385801) (xy 111.3188 -237.334506) (xy 111.334848 -237.285113)
			(xy 111.358426 -237.238839) (xy 111.388952 -237.196823) (xy 111.425675 -237.1601) (xy 111.467691 -237.129574)
			(xy 111.513965 -237.105996) (xy 111.563358 -237.089948) (xy 111.614653 -237.081823) (xy 111.666587 -237.081823)
			(xy 111.717882 -237.089948) (xy 111.767275 -237.105996) (xy 111.813549 -237.129574) (xy 111.855565 -237.1601)
			(xy 111.892288 -237.196823) (xy 111.922814 -237.238839) (xy 111.946392 -237.285113) (xy 111.96244 -237.334506)
			(xy 111.970565 -237.385801) (xy 111.971074 -237.411768) (xy 111.970565 -237.437735) (xy 112.250475 -237.437735)
			(xy 112.250475 -237.385801) (xy 112.2586 -237.334506) (xy 112.274648 -237.285113) (xy 112.298226 -237.238839)
			(xy 112.328752 -237.196823) (xy 112.365475 -237.1601) (xy 112.407491 -237.129574) (xy 112.453765 -237.105996)
			(xy 112.503158 -237.089948) (xy 112.554453 -237.081823) (xy 112.606387 -237.081823) (xy 112.657682 -237.089948)
			(xy 112.707075 -237.105996) (xy 112.753349 -237.129574) (xy 112.795365 -237.1601) (xy 112.832088 -237.196823)
			(xy 112.862614 -237.238839) (xy 112.886192 -237.285113) (xy 112.90224 -237.334506) (xy 112.910365 -237.385801)
			(xy 112.910874 -237.411768) (xy 112.910365 -237.437735) (xy 113.190275 -237.437735) (xy 113.190275 -237.385801)
			(xy 113.1984 -237.334506) (xy 113.214448 -237.285113) (xy 113.238026 -237.238839) (xy 113.268552 -237.196823)
			(xy 113.305275 -237.1601) (xy 113.347291 -237.129574) (xy 113.393565 -237.105996) (xy 113.442958 -237.089948)
			(xy 113.494253 -237.081823) (xy 113.546187 -237.081823) (xy 113.597482 -237.089948) (xy 113.646875 -237.105996)
			(xy 113.693149 -237.129574) (xy 113.720418 -237.149386) (xy 115.011708 -237.149386) (xy 115.011708 -237.149132)
			(xy 115.012177 -237.124606) (xy 115.019435 -237.076094) (xy 115.033783 -237.029187) (xy 115.054904 -236.984915)
			(xy 115.082335 -236.94425) (xy 115.098576 -236.925866) (xy 115.108393 -236.914388) (xy 115.121405 -236.887147)
			(xy 115.125871 -236.85729) (xy 115.121399 -236.827434) (xy 115.108381 -236.800195) (xy 115.098576 -236.788706)
			(xy 115.08231 -236.770341) (xy 115.054868 -236.729677) (xy 115.033743 -236.685401) (xy 115.019399 -236.638488)
			(xy 115.012151 -236.589969) (xy 115.011708 -236.56544) (xy 115.011708 -236.565186) (xy 115.012217 -236.539219)
			(xy 115.020342 -236.487924) (xy 115.03639 -236.438531) (xy 115.059968 -236.392257) (xy 115.090494 -236.350241)
			(xy 115.127217 -236.313518) (xy 115.169233 -236.282992) (xy 115.215507 -236.259414) (xy 115.2649 -236.243366)
			(xy 115.316195 -236.235241) (xy 115.368129 -236.235241) (xy 115.419424 -236.243366) (xy 115.468817 -236.259414)
			(xy 115.505227 -236.277966) (xy 120.646459 -236.277966) (xy 120.646459 -236.226034) (xy 120.654583 -236.17474)
			(xy 120.670631 -236.125349) (xy 120.694208 -236.079076) (xy 120.724732 -236.037061) (xy 120.761454 -236.000339)
			(xy 120.803468 -235.969813) (xy 120.84974 -235.946235) (xy 120.89913 -235.930185) (xy 120.950424 -235.92206)
			(xy 120.97639 -235.92155) (xy 121.002115 -235.922104) (xy 121.052941 -235.930091) (xy 121.101915 -235.945858)
			(xy 121.147855 -235.969023) (xy 121.18965 -235.999028) (xy 121.22629 -236.035147) (xy 121.25689 -236.076507)
			(xy 121.280711 -236.12211) (xy 121.297178 -236.170854) (xy 121.302018 -236.196124) (xy 121.304804 -236.209847)
			(xy 121.316774 -236.235149) (xy 121.335172 -236.256244) (xy 121.358613 -236.271542) (xy 121.385329 -236.27989)
			(xy 121.413309 -236.280661) (xy 121.426986 -236.277658) (xy 121.446905 -236.272909) (xy 121.487537 -236.267819)
			(xy 121.508012 -236.267498) (xy 121.533975 -236.268104) (xy 121.585261 -236.276229) (xy 121.634645 -236.292276)
			(xy 121.68091 -236.315851) (xy 121.722918 -236.346373) (xy 121.759635 -236.383091) (xy 121.790155 -236.4251)
			(xy 121.813729 -236.471366) (xy 121.829774 -236.520751) (xy 121.837897 -236.572037) (xy 121.837897 -236.623919)
			(xy 122.118121 -236.623919) (xy 122.118121 -236.571985) (xy 122.126246 -236.52069) (xy 122.142294 -236.471297)
			(xy 122.165872 -236.425023) (xy 122.196398 -236.383007) (xy 122.233121 -236.346284) (xy 122.275137 -236.315758)
			(xy 122.321411 -236.29218) (xy 122.370804 -236.276132) (xy 122.422099 -236.268007) (xy 122.474033 -236.268007)
			(xy 122.525328 -236.276132) (xy 122.574721 -236.29218) (xy 122.620995 -236.315758) (xy 122.663011 -236.346284)
			(xy 122.699734 -236.383007) (xy 122.73026 -236.425023) (xy 122.753838 -236.471297) (xy 122.769886 -236.52069)
			(xy 122.778011 -236.571985) (xy 122.77852 -236.597952) (xy 122.778011 -236.623919) (xy 123.057667 -236.623919)
			(xy 123.057667 -236.571985) (xy 123.065792 -236.52069) (xy 123.08184 -236.471297) (xy 123.105418 -236.425023)
			(xy 123.135944 -236.383007) (xy 123.172667 -236.346284) (xy 123.214683 -236.315758) (xy 123.260957 -236.29218)
			(xy 123.31035 -236.276132) (xy 123.361645 -236.268007) (xy 123.413579 -236.268007) (xy 123.464874 -236.276132)
			(xy 123.514267 -236.29218) (xy 123.560541 -236.315758) (xy 123.602557 -236.346284) (xy 123.63928 -236.383007)
			(xy 123.669806 -236.425023) (xy 123.693384 -236.471297) (xy 123.709432 -236.52069) (xy 123.717557 -236.571985)
			(xy 123.718066 -236.597952) (xy 123.717557 -236.623919) (xy 123.997467 -236.623919) (xy 123.997467 -236.571985)
			(xy 124.005592 -236.52069) (xy 124.02164 -236.471297) (xy 124.045218 -236.425023) (xy 124.075744 -236.383007)
			(xy 124.112467 -236.346284) (xy 124.154483 -236.315758) (xy 124.200757 -236.29218) (xy 124.25015 -236.276132)
			(xy 124.301445 -236.268007) (xy 124.353379 -236.268007) (xy 124.404674 -236.276132) (xy 124.454067 -236.29218)
			(xy 124.500341 -236.315758) (xy 124.542357 -236.346284) (xy 124.57908 -236.383007) (xy 124.609606 -236.425023)
			(xy 124.633184 -236.471297) (xy 124.649232 -236.52069) (xy 124.657357 -236.571985) (xy 124.657866 -236.597952)
			(xy 124.657357 -236.623919) (xy 124.937267 -236.623919) (xy 124.937267 -236.571985) (xy 124.945392 -236.52069)
			(xy 124.96144 -236.471297) (xy 124.985018 -236.425023) (xy 125.015544 -236.383007) (xy 125.052267 -236.346284)
			(xy 125.094283 -236.315758) (xy 125.140557 -236.29218) (xy 125.18995 -236.276132) (xy 125.241245 -236.268007)
			(xy 125.293179 -236.268007) (xy 125.344474 -236.276132) (xy 125.393867 -236.29218) (xy 125.440141 -236.315758)
			(xy 125.482157 -236.346284) (xy 125.51888 -236.383007) (xy 125.549406 -236.425023) (xy 125.572984 -236.471297)
			(xy 125.589032 -236.52069) (xy 125.597157 -236.571985) (xy 125.597666 -236.597952) (xy 125.597157 -236.623919)
			(xy 125.877067 -236.623919) (xy 125.877067 -236.571985) (xy 125.885192 -236.52069) (xy 125.90124 -236.471297)
			(xy 125.924818 -236.425023) (xy 125.955344 -236.383007) (xy 125.992067 -236.346284) (xy 126.034083 -236.315758)
			(xy 126.080357 -236.29218) (xy 126.12975 -236.276132) (xy 126.181045 -236.268007) (xy 126.232979 -236.268007)
			(xy 126.284274 -236.276132) (xy 126.333667 -236.29218) (xy 126.379941 -236.315758) (xy 126.421957 -236.346284)
			(xy 126.45868 -236.383007) (xy 126.489206 -236.425023) (xy 126.512784 -236.471297) (xy 126.528832 -236.52069)
			(xy 126.536957 -236.571985) (xy 126.537466 -236.597952) (xy 126.536957 -236.623919) (xy 126.816867 -236.623919)
			(xy 126.816867 -236.571985) (xy 126.824992 -236.52069) (xy 126.84104 -236.471297) (xy 126.864618 -236.425023)
			(xy 126.895144 -236.383007) (xy 126.931867 -236.346284) (xy 126.973883 -236.315758) (xy 127.020157 -236.29218)
			(xy 127.06955 -236.276132) (xy 127.120845 -236.268007) (xy 127.172779 -236.268007) (xy 127.224074 -236.276132)
			(xy 127.273467 -236.29218) (xy 127.319741 -236.315758) (xy 127.361757 -236.346284) (xy 127.39848 -236.383007)
			(xy 127.429006 -236.425023) (xy 127.452584 -236.471297) (xy 127.468632 -236.52069) (xy 127.476757 -236.571985)
			(xy 127.477266 -236.597952) (xy 127.476757 -236.623919) (xy 127.756667 -236.623919) (xy 127.756667 -236.571985)
			(xy 127.764792 -236.52069) (xy 127.78084 -236.471297) (xy 127.804418 -236.425023) (xy 127.834944 -236.383007)
			(xy 127.871667 -236.346284) (xy 127.913683 -236.315758) (xy 127.959957 -236.29218) (xy 128.00935 -236.276132)
			(xy 128.060645 -236.268007) (xy 128.112579 -236.268007) (xy 128.163874 -236.276132) (xy 128.213267 -236.29218)
			(xy 128.259541 -236.315758) (xy 128.301557 -236.346284) (xy 128.33828 -236.383007) (xy 128.368806 -236.425023)
			(xy 128.392384 -236.471297) (xy 128.408432 -236.52069) (xy 128.416557 -236.571985) (xy 128.417066 -236.597952)
			(xy 128.416557 -236.623919) (xy 128.696721 -236.623919) (xy 128.696721 -236.571985) (xy 128.704846 -236.52069)
			(xy 128.720894 -236.471297) (xy 128.744472 -236.425023) (xy 128.774998 -236.383007) (xy 128.811721 -236.346284)
			(xy 128.853737 -236.315758) (xy 128.900011 -236.29218) (xy 128.949404 -236.276132) (xy 129.000699 -236.268007)
			(xy 129.052633 -236.268007) (xy 129.103928 -236.276132) (xy 129.153321 -236.29218) (xy 129.199595 -236.315758)
			(xy 129.241611 -236.346284) (xy 129.278334 -236.383007) (xy 129.30886 -236.425023) (xy 129.332438 -236.471297)
			(xy 129.348486 -236.52069) (xy 129.356611 -236.571985) (xy 129.35712 -236.597952) (xy 129.356611 -236.623919)
			(xy 129.636267 -236.623919) (xy 129.636267 -236.571985) (xy 129.644392 -236.52069) (xy 129.66044 -236.471297)
			(xy 129.684018 -236.425023) (xy 129.714544 -236.383007) (xy 129.751267 -236.346284) (xy 129.793283 -236.315758)
			(xy 129.839557 -236.29218) (xy 129.88895 -236.276132) (xy 129.940245 -236.268007) (xy 129.992179 -236.268007)
			(xy 130.043474 -236.276132) (xy 130.092867 -236.29218) (xy 130.139141 -236.315758) (xy 130.181157 -236.346284)
			(xy 130.21788 -236.383007) (xy 130.248406 -236.425023) (xy 130.271984 -236.471297) (xy 130.288032 -236.52069)
			(xy 130.296157 -236.571985) (xy 130.296666 -236.597952) (xy 130.296157 -236.623919) (xy 130.576067 -236.623919)
			(xy 130.576067 -236.571985) (xy 130.584192 -236.52069) (xy 130.60024 -236.471297) (xy 130.623818 -236.425023)
			(xy 130.654344 -236.383007) (xy 130.691067 -236.346284) (xy 130.733083 -236.315758) (xy 130.779357 -236.29218)
			(xy 130.82875 -236.276132) (xy 130.880045 -236.268007) (xy 130.931979 -236.268007) (xy 130.983274 -236.276132)
			(xy 131.032667 -236.29218) (xy 131.078941 -236.315758) (xy 131.120957 -236.346284) (xy 131.15768 -236.383007)
			(xy 131.188206 -236.425023) (xy 131.211784 -236.471297) (xy 131.227832 -236.52069) (xy 131.235957 -236.571985)
			(xy 131.236466 -236.597952) (xy 131.235957 -236.623919) (xy 131.227832 -236.675214) (xy 131.211784 -236.724607)
			(xy 131.188206 -236.770881) (xy 131.15768 -236.812897) (xy 131.120957 -236.84962) (xy 131.078941 -236.880146)
			(xy 131.032667 -236.903724) (xy 130.983274 -236.919772) (xy 130.931979 -236.927897) (xy 130.880045 -236.927897)
			(xy 130.82875 -236.919772) (xy 130.779357 -236.903724) (xy 130.733083 -236.880146) (xy 130.691067 -236.84962)
			(xy 130.654344 -236.812897) (xy 130.623818 -236.770881) (xy 130.60024 -236.724607) (xy 130.584192 -236.675214)
			(xy 130.576067 -236.623919) (xy 130.296157 -236.623919) (xy 130.288032 -236.675214) (xy 130.271984 -236.724607)
			(xy 130.248406 -236.770881) (xy 130.21788 -236.812897) (xy 130.181157 -236.84962) (xy 130.139141 -236.880146)
			(xy 130.092867 -236.903724) (xy 130.043474 -236.919772) (xy 129.992179 -236.927897) (xy 129.940245 -236.927897)
			(xy 129.88895 -236.919772) (xy 129.839557 -236.903724) (xy 129.793283 -236.880146) (xy 129.751267 -236.84962)
			(xy 129.714544 -236.812897) (xy 129.684018 -236.770881) (xy 129.66044 -236.724607) (xy 129.644392 -236.675214)
			(xy 129.636267 -236.623919) (xy 129.356611 -236.623919) (xy 129.348486 -236.675214) (xy 129.332438 -236.724607)
			(xy 129.30886 -236.770881) (xy 129.278334 -236.812897) (xy 129.241611 -236.84962) (xy 129.199595 -236.880146)
			(xy 129.153321 -236.903724) (xy 129.103928 -236.919772) (xy 129.052633 -236.927897) (xy 129.000699 -236.927897)
			(xy 128.949404 -236.919772) (xy 128.900011 -236.903724) (xy 128.853737 -236.880146) (xy 128.811721 -236.84962)
			(xy 128.774998 -236.812897) (xy 128.744472 -236.770881) (xy 128.720894 -236.724607) (xy 128.704846 -236.675214)
			(xy 128.696721 -236.623919) (xy 128.416557 -236.623919) (xy 128.408432 -236.675214) (xy 128.392384 -236.724607)
			(xy 128.368806 -236.770881) (xy 128.33828 -236.812897) (xy 128.301557 -236.84962) (xy 128.259541 -236.880146)
			(xy 128.213267 -236.903724) (xy 128.163874 -236.919772) (xy 128.112579 -236.927897) (xy 128.060645 -236.927897)
			(xy 128.00935 -236.919772) (xy 127.959957 -236.903724) (xy 127.913683 -236.880146) (xy 127.871667 -236.84962)
			(xy 127.834944 -236.812897) (xy 127.804418 -236.770881) (xy 127.78084 -236.724607) (xy 127.764792 -236.675214)
			(xy 127.756667 -236.623919) (xy 127.476757 -236.623919) (xy 127.468632 -236.675214) (xy 127.452584 -236.724607)
			(xy 127.429006 -236.770881) (xy 127.39848 -236.812897) (xy 127.361757 -236.84962) (xy 127.319741 -236.880146)
			(xy 127.273467 -236.903724) (xy 127.224074 -236.919772) (xy 127.172779 -236.927897) (xy 127.120845 -236.927897)
			(xy 127.06955 -236.919772) (xy 127.020157 -236.903724) (xy 126.973883 -236.880146) (xy 126.931867 -236.84962)
			(xy 126.895144 -236.812897) (xy 126.864618 -236.770881) (xy 126.84104 -236.724607) (xy 126.824992 -236.675214)
			(xy 126.816867 -236.623919) (xy 126.536957 -236.623919) (xy 126.528832 -236.675214) (xy 126.512784 -236.724607)
			(xy 126.489206 -236.770881) (xy 126.45868 -236.812897) (xy 126.421957 -236.84962) (xy 126.379941 -236.880146)
			(xy 126.333667 -236.903724) (xy 126.284274 -236.919772) (xy 126.232979 -236.927897) (xy 126.181045 -236.927897)
			(xy 126.12975 -236.919772) (xy 126.080357 -236.903724) (xy 126.034083 -236.880146) (xy 125.992067 -236.84962)
			(xy 125.955344 -236.812897) (xy 125.924818 -236.770881) (xy 125.90124 -236.724607) (xy 125.885192 -236.675214)
			(xy 125.877067 -236.623919) (xy 125.597157 -236.623919) (xy 125.589032 -236.675214) (xy 125.572984 -236.724607)
			(xy 125.549406 -236.770881) (xy 125.51888 -236.812897) (xy 125.482157 -236.84962) (xy 125.440141 -236.880146)
			(xy 125.393867 -236.903724) (xy 125.344474 -236.919772) (xy 125.293179 -236.927897) (xy 125.241245 -236.927897)
			(xy 125.18995 -236.919772) (xy 125.140557 -236.903724) (xy 125.094283 -236.880146) (xy 125.052267 -236.84962)
			(xy 125.015544 -236.812897) (xy 124.985018 -236.770881) (xy 124.96144 -236.724607) (xy 124.945392 -236.675214)
			(xy 124.937267 -236.623919) (xy 124.657357 -236.623919) (xy 124.649232 -236.675214) (xy 124.633184 -236.724607)
			(xy 124.609606 -236.770881) (xy 124.57908 -236.812897) (xy 124.542357 -236.84962) (xy 124.500341 -236.880146)
			(xy 124.454067 -236.903724) (xy 124.404674 -236.919772) (xy 124.353379 -236.927897) (xy 124.301445 -236.927897)
			(xy 124.25015 -236.919772) (xy 124.200757 -236.903724) (xy 124.154483 -236.880146) (xy 124.112467 -236.84962)
			(xy 124.075744 -236.812897) (xy 124.045218 -236.770881) (xy 124.02164 -236.724607) (xy 124.005592 -236.675214)
			(xy 123.997467 -236.623919) (xy 123.717557 -236.623919) (xy 123.709432 -236.675214) (xy 123.693384 -236.724607)
			(xy 123.669806 -236.770881) (xy 123.63928 -236.812897) (xy 123.602557 -236.84962) (xy 123.560541 -236.880146)
			(xy 123.514267 -236.903724) (xy 123.464874 -236.919772) (xy 123.413579 -236.927897) (xy 123.361645 -236.927897)
			(xy 123.31035 -236.919772) (xy 123.260957 -236.903724) (xy 123.214683 -236.880146) (xy 123.172667 -236.84962)
			(xy 123.135944 -236.812897) (xy 123.105418 -236.770881) (xy 123.08184 -236.724607) (xy 123.065792 -236.675214)
			(xy 123.057667 -236.623919) (xy 122.778011 -236.623919) (xy 122.769886 -236.675214) (xy 122.753838 -236.724607)
			(xy 122.73026 -236.770881) (xy 122.699734 -236.812897) (xy 122.663011 -236.84962) (xy 122.620995 -236.880146)
			(xy 122.574721 -236.903724) (xy 122.525328 -236.919772) (xy 122.474033 -236.927897) (xy 122.422099 -236.927897)
			(xy 122.370804 -236.919772) (xy 122.321411 -236.903724) (xy 122.275137 -236.880146) (xy 122.233121 -236.84962)
			(xy 122.196398 -236.812897) (xy 122.165872 -236.770881) (xy 122.142294 -236.724607) (xy 122.126246 -236.675214)
			(xy 122.118121 -236.623919) (xy 121.837897 -236.623919) (xy 121.837897 -236.623963) (xy 121.829774 -236.675249)
			(xy 121.813729 -236.724634) (xy 121.790155 -236.7709) (xy 121.759635 -236.812909) (xy 121.722918 -236.849627)
			(xy 121.68091 -236.880149) (xy 121.634645 -236.903724) (xy 121.585261 -236.919771) (xy 121.533975 -236.927896)
			(xy 121.508012 -236.928406) (xy 121.482285 -236.927886) (xy 121.431456 -236.919898) (xy 121.382479 -236.90413)
			(xy 121.336537 -236.880961) (xy 121.294741 -236.850952) (xy 121.258101 -236.814828) (xy 121.227502 -236.773462)
			(xy 121.203683 -236.727853) (xy 121.187221 -236.679105) (xy 121.182384 -236.653832) (xy 121.179559 -236.640117)
			(xy 121.167602 -236.614813) (xy 121.149213 -236.593715) (xy 121.125779 -236.578415) (xy 121.099067 -236.570064)
			(xy 121.07109 -236.569294) (xy 121.057416 -236.572298) (xy 121.037497 -236.577046) (xy 120.996865 -236.582137)
			(xy 120.97639 -236.582458) (xy 120.950424 -236.58194) (xy 120.89913 -236.573815) (xy 120.84974 -236.557765)
			(xy 120.803468 -236.534187) (xy 120.761454 -236.503661) (xy 120.724732 -236.466939) (xy 120.694208 -236.424924)
			(xy 120.670631 -236.378651) (xy 120.654583 -236.32926) (xy 120.646459 -236.277966) (xy 115.505227 -236.277966)
			(xy 115.515091 -236.282992) (xy 115.557107 -236.313518) (xy 115.59383 -236.350241) (xy 115.624356 -236.392257)
			(xy 115.647934 -236.438531) (xy 115.663982 -236.487924) (xy 115.672107 -236.539219) (xy 115.672616 -236.565186)
			(xy 115.672616 -236.56544) (xy 115.672184 -236.589967) (xy 115.664916 -236.638481) (xy 115.650559 -236.685388)
			(xy 115.62943 -236.729659) (xy 115.601992 -236.770323) (xy 115.585748 -236.788706) (xy 115.575956 -236.800205)
			(xy 115.562938 -236.827438) (xy 115.558466 -236.85729) (xy 115.562932 -236.887142) (xy 115.575945 -236.914378)
			(xy 115.585748 -236.925866) (xy 115.601988 -236.944252) (xy 115.629437 -236.984909) (xy 115.650568 -237.029179)
			(xy 115.664918 -237.076089) (xy 115.67217 -237.124604) (xy 115.672616 -237.149132) (xy 115.672616 -237.149386)
			(xy 115.672107 -237.175353) (xy 115.663982 -237.226648) (xy 115.647934 -237.276041) (xy 115.624356 -237.322315)
			(xy 115.59383 -237.364331) (xy 115.557107 -237.401054) (xy 115.515091 -237.43158) (xy 115.486062 -237.446371)
			(xy 120.646445 -237.446371) (xy 120.646445 -237.394437) (xy 120.65457 -237.343142) (xy 120.670618 -237.293749)
			(xy 120.694196 -237.247475) (xy 120.724722 -237.205459) (xy 120.761445 -237.168736) (xy 120.803461 -237.13821)
			(xy 120.849735 -237.114632) (xy 120.899128 -237.098584) (xy 120.950423 -237.090459) (xy 121.002357 -237.090459)
			(xy 121.053652 -237.098584) (xy 121.103045 -237.114632) (xy 121.149319 -237.13821) (xy 121.191335 -237.168736)
			(xy 121.228058 -237.205459) (xy 121.258584 -237.247475) (xy 121.282162 -237.293749) (xy 121.29821 -237.343142)
			(xy 121.306335 -237.394437) (xy 121.306844 -237.420404) (xy 121.306509 -237.437481) (xy 121.648221 -237.437481)
			(xy 121.648221 -237.385547) (xy 121.656346 -237.334252) (xy 121.672394 -237.284859) (xy 121.695972 -237.238585)
			(xy 121.726498 -237.196569) (xy 121.763221 -237.159846) (xy 121.805237 -237.12932) (xy 121.851511 -237.105742)
			(xy 121.900904 -237.089694) (xy 121.952199 -237.081569) (xy 122.004133 -237.081569) (xy 122.055428 -237.089694)
			(xy 122.104821 -237.105742) (xy 122.151095 -237.12932) (xy 122.193111 -237.159846) (xy 122.229834 -237.196569)
			(xy 122.26036 -237.238585) (xy 122.283938 -237.284859) (xy 122.299986 -237.334252) (xy 122.308111 -237.385547)
			(xy 122.30862 -237.411514) (xy 122.308111 -237.437481) (xy 122.588021 -237.437481) (xy 122.588021 -237.385547)
			(xy 122.596146 -237.334252) (xy 122.612194 -237.284859) (xy 122.635772 -237.238585) (xy 122.666298 -237.196569)
			(xy 122.703021 -237.159846) (xy 122.745037 -237.12932) (xy 122.791311 -237.105742) (xy 122.840704 -237.089694)
			(xy 122.891999 -237.081569) (xy 122.943933 -237.081569) (xy 122.995228 -237.089694) (xy 123.044621 -237.105742)
			(xy 123.090895 -237.12932) (xy 123.132911 -237.159846) (xy 123.169634 -237.196569) (xy 123.20016 -237.238585)
			(xy 123.223738 -237.284859) (xy 123.239786 -237.334252) (xy 123.247911 -237.385547) (xy 123.24842 -237.411514)
			(xy 123.247911 -237.437481) (xy 123.527821 -237.437481) (xy 123.527821 -237.385547) (xy 123.535946 -237.334252)
			(xy 123.551994 -237.284859) (xy 123.575572 -237.238585) (xy 123.606098 -237.196569) (xy 123.642821 -237.159846)
			(xy 123.684837 -237.12932) (xy 123.731111 -237.105742) (xy 123.780504 -237.089694) (xy 123.831799 -237.081569)
			(xy 123.883733 -237.081569) (xy 123.935028 -237.089694) (xy 123.984421 -237.105742) (xy 124.030695 -237.12932)
			(xy 124.072711 -237.159846) (xy 124.109434 -237.196569) (xy 124.13996 -237.238585) (xy 124.163538 -237.284859)
			(xy 124.179586 -237.334252) (xy 124.187711 -237.385547) (xy 124.18822 -237.411514) (xy 124.187711 -237.437481)
			(xy 124.467621 -237.437481) (xy 124.467621 -237.385547) (xy 124.475746 -237.334252) (xy 124.491794 -237.284859)
			(xy 124.515372 -237.238585) (xy 124.545898 -237.196569) (xy 124.582621 -237.159846) (xy 124.624637 -237.12932)
			(xy 124.670911 -237.105742) (xy 124.720304 -237.089694) (xy 124.771599 -237.081569) (xy 124.823533 -237.081569)
			(xy 124.874828 -237.089694) (xy 124.924221 -237.105742) (xy 124.970495 -237.12932) (xy 125.012511 -237.159846)
			(xy 125.049234 -237.196569) (xy 125.07976 -237.238585) (xy 125.103338 -237.284859) (xy 125.119386 -237.334252)
			(xy 125.127511 -237.385547) (xy 125.12802 -237.411514) (xy 125.127511 -237.437481) (xy 125.407421 -237.437481)
			(xy 125.407421 -237.385547) (xy 125.415546 -237.334252) (xy 125.431594 -237.284859) (xy 125.455172 -237.238585)
			(xy 125.485698 -237.196569) (xy 125.522421 -237.159846) (xy 125.564437 -237.12932) (xy 125.610711 -237.105742)
			(xy 125.660104 -237.089694) (xy 125.711399 -237.081569) (xy 125.763333 -237.081569) (xy 125.814628 -237.089694)
			(xy 125.864021 -237.105742) (xy 125.910295 -237.12932) (xy 125.952311 -237.159846) (xy 125.989034 -237.196569)
			(xy 126.01956 -237.238585) (xy 126.043138 -237.284859) (xy 126.059186 -237.334252) (xy 126.067311 -237.385547)
			(xy 126.06782 -237.411514) (xy 126.067311 -237.437481) (xy 126.347221 -237.437481) (xy 126.347221 -237.385547)
			(xy 126.355346 -237.334252) (xy 126.371394 -237.284859) (xy 126.394972 -237.238585) (xy 126.425498 -237.196569)
			(xy 126.462221 -237.159846) (xy 126.504237 -237.12932) (xy 126.550511 -237.105742) (xy 126.599904 -237.089694)
			(xy 126.651199 -237.081569) (xy 126.703133 -237.081569) (xy 126.754428 -237.089694) (xy 126.803821 -237.105742)
			(xy 126.850095 -237.12932) (xy 126.892111 -237.159846) (xy 126.928834 -237.196569) (xy 126.95936 -237.238585)
			(xy 126.982938 -237.284859) (xy 126.998986 -237.334252) (xy 127.007111 -237.385547) (xy 127.00762 -237.411514)
			(xy 127.007111 -237.437481) (xy 127.287021 -237.437481) (xy 127.287021 -237.385547) (xy 127.295146 -237.334252)
			(xy 127.311194 -237.284859) (xy 127.334772 -237.238585) (xy 127.365298 -237.196569) (xy 127.402021 -237.159846)
			(xy 127.444037 -237.12932) (xy 127.490311 -237.105742) (xy 127.539704 -237.089694) (xy 127.590999 -237.081569)
			(xy 127.642933 -237.081569) (xy 127.694228 -237.089694) (xy 127.743621 -237.105742) (xy 127.789895 -237.12932)
			(xy 127.831911 -237.159846) (xy 127.868634 -237.196569) (xy 127.89916 -237.238585) (xy 127.922738 -237.284859)
			(xy 127.938786 -237.334252) (xy 127.946911 -237.385547) (xy 127.94742 -237.411514) (xy 127.946911 -237.437481)
			(xy 128.226821 -237.437481) (xy 128.226821 -237.385547) (xy 128.234946 -237.334252) (xy 128.250994 -237.284859)
			(xy 128.274572 -237.238585) (xy 128.305098 -237.196569) (xy 128.341821 -237.159846) (xy 128.383837 -237.12932)
			(xy 128.430111 -237.105742) (xy 128.479504 -237.089694) (xy 128.530799 -237.081569) (xy 128.582733 -237.081569)
			(xy 128.634028 -237.089694) (xy 128.683421 -237.105742) (xy 128.729695 -237.12932) (xy 128.771711 -237.159846)
			(xy 128.808434 -237.196569) (xy 128.83896 -237.238585) (xy 128.862538 -237.284859) (xy 128.878586 -237.334252)
			(xy 128.886711 -237.385547) (xy 128.88722 -237.411514) (xy 128.886711 -237.437481) (xy 129.166621 -237.437481)
			(xy 129.166621 -237.385547) (xy 129.174746 -237.334252) (xy 129.190794 -237.284859) (xy 129.214372 -237.238585)
			(xy 129.244898 -237.196569) (xy 129.281621 -237.159846) (xy 129.323637 -237.12932) (xy 129.369911 -237.105742)
			(xy 129.419304 -237.089694) (xy 129.470599 -237.081569) (xy 129.522533 -237.081569) (xy 129.573828 -237.089694)
			(xy 129.623221 -237.105742) (xy 129.669495 -237.12932) (xy 129.711511 -237.159846) (xy 129.748234 -237.196569)
			(xy 129.77876 -237.238585) (xy 129.802338 -237.284859) (xy 129.818386 -237.334252) (xy 129.826511 -237.385547)
			(xy 129.82702 -237.411514) (xy 129.826511 -237.437481) (xy 130.106421 -237.437481) (xy 130.106421 -237.385547)
			(xy 130.114546 -237.334252) (xy 130.130594 -237.284859) (xy 130.154172 -237.238585) (xy 130.184698 -237.196569)
			(xy 130.221421 -237.159846) (xy 130.263437 -237.12932) (xy 130.309711 -237.105742) (xy 130.359104 -237.089694)
			(xy 130.410399 -237.081569) (xy 130.462333 -237.081569) (xy 130.513628 -237.089694) (xy 130.563021 -237.105742)
			(xy 130.609295 -237.12932) (xy 130.651311 -237.159846) (xy 130.688034 -237.196569) (xy 130.71856 -237.238585)
			(xy 130.742138 -237.284859) (xy 130.758186 -237.334252) (xy 130.766311 -237.385547) (xy 130.76682 -237.411514)
			(xy 130.766311 -237.437481) (xy 130.758186 -237.488776) (xy 130.742138 -237.538169) (xy 130.71856 -237.584443)
			(xy 130.688034 -237.626459) (xy 130.651311 -237.663182) (xy 130.609295 -237.693708) (xy 130.563021 -237.717286)
			(xy 130.513628 -237.733334) (xy 130.462333 -237.741459) (xy 130.410399 -237.741459) (xy 130.359104 -237.733334)
			(xy 130.309711 -237.717286) (xy 130.263437 -237.693708) (xy 130.221421 -237.663182) (xy 130.184698 -237.626459)
			(xy 130.154172 -237.584443) (xy 130.130594 -237.538169) (xy 130.114546 -237.488776) (xy 130.106421 -237.437481)
			(xy 129.826511 -237.437481) (xy 129.818386 -237.488776) (xy 129.802338 -237.538169) (xy 129.77876 -237.584443)
			(xy 129.748234 -237.626459) (xy 129.711511 -237.663182) (xy 129.669495 -237.693708) (xy 129.623221 -237.717286)
			(xy 129.573828 -237.733334) (xy 129.522533 -237.741459) (xy 129.470599 -237.741459) (xy 129.419304 -237.733334)
			(xy 129.369911 -237.717286) (xy 129.323637 -237.693708) (xy 129.281621 -237.663182) (xy 129.244898 -237.626459)
			(xy 129.214372 -237.584443) (xy 129.190794 -237.538169) (xy 129.174746 -237.488776) (xy 129.166621 -237.437481)
			(xy 128.886711 -237.437481) (xy 128.878586 -237.488776) (xy 128.862538 -237.538169) (xy 128.83896 -237.584443)
			(xy 128.808434 -237.626459) (xy 128.771711 -237.663182) (xy 128.729695 -237.693708) (xy 128.683421 -237.717286)
			(xy 128.634028 -237.733334) (xy 128.582733 -237.741459) (xy 128.530799 -237.741459) (xy 128.479504 -237.733334)
			(xy 128.430111 -237.717286) (xy 128.383837 -237.693708) (xy 128.341821 -237.663182) (xy 128.305098 -237.626459)
			(xy 128.274572 -237.584443) (xy 128.250994 -237.538169) (xy 128.234946 -237.488776) (xy 128.226821 -237.437481)
			(xy 127.946911 -237.437481) (xy 127.938786 -237.488776) (xy 127.922738 -237.538169) (xy 127.89916 -237.584443)
			(xy 127.868634 -237.626459) (xy 127.831911 -237.663182) (xy 127.789895 -237.693708) (xy 127.743621 -237.717286)
			(xy 127.694228 -237.733334) (xy 127.642933 -237.741459) (xy 127.590999 -237.741459) (xy 127.539704 -237.733334)
			(xy 127.490311 -237.717286) (xy 127.444037 -237.693708) (xy 127.402021 -237.663182) (xy 127.365298 -237.626459)
			(xy 127.334772 -237.584443) (xy 127.311194 -237.538169) (xy 127.295146 -237.488776) (xy 127.287021 -237.437481)
			(xy 127.007111 -237.437481) (xy 126.998986 -237.488776) (xy 126.982938 -237.538169) (xy 126.95936 -237.584443)
			(xy 126.928834 -237.626459) (xy 126.892111 -237.663182) (xy 126.850095 -237.693708) (xy 126.803821 -237.717286)
			(xy 126.754428 -237.733334) (xy 126.703133 -237.741459) (xy 126.651199 -237.741459) (xy 126.599904 -237.733334)
			(xy 126.550511 -237.717286) (xy 126.504237 -237.693708) (xy 126.462221 -237.663182) (xy 126.425498 -237.626459)
			(xy 126.394972 -237.584443) (xy 126.371394 -237.538169) (xy 126.355346 -237.488776) (xy 126.347221 -237.437481)
			(xy 126.067311 -237.437481) (xy 126.059186 -237.488776) (xy 126.043138 -237.538169) (xy 126.01956 -237.584443)
			(xy 125.989034 -237.626459) (xy 125.952311 -237.663182) (xy 125.910295 -237.693708) (xy 125.864021 -237.717286)
			(xy 125.814628 -237.733334) (xy 125.763333 -237.741459) (xy 125.711399 -237.741459) (xy 125.660104 -237.733334)
			(xy 125.610711 -237.717286) (xy 125.564437 -237.693708) (xy 125.522421 -237.663182) (xy 125.485698 -237.626459)
			(xy 125.455172 -237.584443) (xy 125.431594 -237.538169) (xy 125.415546 -237.488776) (xy 125.407421 -237.437481)
			(xy 125.127511 -237.437481) (xy 125.119386 -237.488776) (xy 125.103338 -237.538169) (xy 125.07976 -237.584443)
			(xy 125.049234 -237.626459) (xy 125.012511 -237.663182) (xy 124.970495 -237.693708) (xy 124.924221 -237.717286)
			(xy 124.874828 -237.733334) (xy 124.823533 -237.741459) (xy 124.771599 -237.741459) (xy 124.720304 -237.733334)
			(xy 124.670911 -237.717286) (xy 124.624637 -237.693708) (xy 124.582621 -237.663182) (xy 124.545898 -237.626459)
			(xy 124.515372 -237.584443) (xy 124.491794 -237.538169) (xy 124.475746 -237.488776) (xy 124.467621 -237.437481)
			(xy 124.187711 -237.437481) (xy 124.179586 -237.488776) (xy 124.163538 -237.538169) (xy 124.13996 -237.584443)
			(xy 124.109434 -237.626459) (xy 124.072711 -237.663182) (xy 124.030695 -237.693708) (xy 123.984421 -237.717286)
			(xy 123.935028 -237.733334) (xy 123.883733 -237.741459) (xy 123.831799 -237.741459) (xy 123.780504 -237.733334)
			(xy 123.731111 -237.717286) (xy 123.684837 -237.693708) (xy 123.642821 -237.663182) (xy 123.606098 -237.626459)
			(xy 123.575572 -237.584443) (xy 123.551994 -237.538169) (xy 123.535946 -237.488776) (xy 123.527821 -237.437481)
			(xy 123.247911 -237.437481) (xy 123.239786 -237.488776) (xy 123.223738 -237.538169) (xy 123.20016 -237.584443)
			(xy 123.169634 -237.626459) (xy 123.132911 -237.663182) (xy 123.090895 -237.693708) (xy 123.044621 -237.717286)
			(xy 122.995228 -237.733334) (xy 122.943933 -237.741459) (xy 122.891999 -237.741459) (xy 122.840704 -237.733334)
			(xy 122.791311 -237.717286) (xy 122.745037 -237.693708) (xy 122.703021 -237.663182) (xy 122.666298 -237.626459)
			(xy 122.635772 -237.584443) (xy 122.612194 -237.538169) (xy 122.596146 -237.488776) (xy 122.588021 -237.437481)
			(xy 122.308111 -237.437481) (xy 122.299986 -237.488776) (xy 122.283938 -237.538169) (xy 122.26036 -237.584443)
			(xy 122.229834 -237.626459) (xy 122.193111 -237.663182) (xy 122.151095 -237.693708) (xy 122.104821 -237.717286)
			(xy 122.055428 -237.733334) (xy 122.004133 -237.741459) (xy 121.952199 -237.741459) (xy 121.900904 -237.733334)
			(xy 121.851511 -237.717286) (xy 121.805237 -237.693708) (xy 121.763221 -237.663182) (xy 121.726498 -237.626459)
			(xy 121.695972 -237.584443) (xy 121.672394 -237.538169) (xy 121.656346 -237.488776) (xy 121.648221 -237.437481)
			(xy 121.306509 -237.437481) (xy 121.306335 -237.446371) (xy 121.29821 -237.497666) (xy 121.282162 -237.547059)
			(xy 121.258584 -237.593333) (xy 121.228058 -237.635349) (xy 121.191335 -237.672072) (xy 121.149319 -237.702598)
			(xy 121.103045 -237.726176) (xy 121.053652 -237.742224) (xy 121.002357 -237.750349) (xy 120.950423 -237.750349)
			(xy 120.899128 -237.742224) (xy 120.849735 -237.726176) (xy 120.803461 -237.702598) (xy 120.761445 -237.672072)
			(xy 120.724722 -237.635349) (xy 120.694196 -237.593333) (xy 120.670618 -237.547059) (xy 120.65457 -237.497666)
			(xy 120.646445 -237.446371) (xy 115.486062 -237.446371) (xy 115.468817 -237.455158) (xy 115.419424 -237.471206)
			(xy 115.368129 -237.479331) (xy 115.316195 -237.479331) (xy 115.2649 -237.471206) (xy 115.215507 -237.455158)
			(xy 115.169233 -237.43158) (xy 115.127217 -237.401054) (xy 115.090494 -237.364331) (xy 115.059968 -237.322315)
			(xy 115.03639 -237.276041) (xy 115.020342 -237.226648) (xy 115.012217 -237.175353) (xy 115.011708 -237.149386)
			(xy 113.720418 -237.149386) (xy 113.735165 -237.1601) (xy 113.771888 -237.196823) (xy 113.802414 -237.238839)
			(xy 113.825992 -237.285113) (xy 113.84204 -237.334506) (xy 113.850165 -237.385801) (xy 113.850674 -237.411768)
			(xy 113.850165 -237.437735) (xy 113.84204 -237.48903) (xy 113.825992 -237.538423) (xy 113.802414 -237.584697)
			(xy 113.771888 -237.626713) (xy 113.735165 -237.663436) (xy 113.693149 -237.693962) (xy 113.646875 -237.71754)
			(xy 113.597482 -237.733588) (xy 113.546187 -237.741713) (xy 113.494253 -237.741713) (xy 113.442958 -237.733588)
			(xy 113.393565 -237.71754) (xy 113.347291 -237.693962) (xy 113.305275 -237.663436) (xy 113.268552 -237.626713)
			(xy 113.238026 -237.584697) (xy 113.214448 -237.538423) (xy 113.1984 -237.48903) (xy 113.190275 -237.437735)
			(xy 112.910365 -237.437735) (xy 112.90224 -237.48903) (xy 112.886192 -237.538423) (xy 112.862614 -237.584697)
			(xy 112.832088 -237.626713) (xy 112.795365 -237.663436) (xy 112.753349 -237.693962) (xy 112.707075 -237.71754)
			(xy 112.657682 -237.733588) (xy 112.606387 -237.741713) (xy 112.554453 -237.741713) (xy 112.503158 -237.733588)
			(xy 112.453765 -237.71754) (xy 112.407491 -237.693962) (xy 112.365475 -237.663436) (xy 112.328752 -237.626713)
			(xy 112.298226 -237.584697) (xy 112.274648 -237.538423) (xy 112.2586 -237.48903) (xy 112.250475 -237.437735)
			(xy 111.970565 -237.437735) (xy 111.96244 -237.48903) (xy 111.946392 -237.538423) (xy 111.922814 -237.584697)
			(xy 111.892288 -237.626713) (xy 111.855565 -237.663436) (xy 111.813549 -237.693962) (xy 111.767275 -237.71754)
			(xy 111.717882 -237.733588) (xy 111.666587 -237.741713) (xy 111.614653 -237.741713) (xy 111.563358 -237.733588)
			(xy 111.513965 -237.71754) (xy 111.467691 -237.693962) (xy 111.425675 -237.663436) (xy 111.388952 -237.626713)
			(xy 111.358426 -237.584697) (xy 111.334848 -237.538423) (xy 111.3188 -237.48903) (xy 111.310675 -237.437735)
			(xy 111.030765 -237.437735) (xy 111.02264 -237.48903) (xy 111.006592 -237.538423) (xy 110.983014 -237.584697)
			(xy 110.952488 -237.626713) (xy 110.915765 -237.663436) (xy 110.873749 -237.693962) (xy 110.827475 -237.71754)
			(xy 110.778082 -237.733588) (xy 110.726787 -237.741713) (xy 110.674853 -237.741713) (xy 110.623558 -237.733588)
			(xy 110.574165 -237.71754) (xy 110.527891 -237.693962) (xy 110.485875 -237.663436) (xy 110.449152 -237.626713)
			(xy 110.418626 -237.584697) (xy 110.395048 -237.538423) (xy 110.379 -237.48903) (xy 110.370875 -237.437735)
			(xy 110.090965 -237.437735) (xy 110.08284 -237.48903) (xy 110.066792 -237.538423) (xy 110.043214 -237.584697)
			(xy 110.012688 -237.626713) (xy 109.975965 -237.663436) (xy 109.933949 -237.693962) (xy 109.887675 -237.71754)
			(xy 109.838282 -237.733588) (xy 109.786987 -237.741713) (xy 109.735053 -237.741713) (xy 109.683758 -237.733588)
			(xy 109.634365 -237.71754) (xy 109.588091 -237.693962) (xy 109.546075 -237.663436) (xy 109.509352 -237.626713)
			(xy 109.478826 -237.584697) (xy 109.455248 -237.538423) (xy 109.4392 -237.48903) (xy 109.431075 -237.437735)
			(xy 103.107036 -237.437735) (xy 103.133854 -237.464551) (xy 103.16438 -237.506564) (xy 103.187959 -237.552835)
			(xy 103.204009 -237.602225) (xy 103.212136 -237.653518) (xy 103.212646 -237.679484) (xy 103.212646 -237.679738)
			(xy 103.212205 -237.704265) (xy 103.204938 -237.752778) (xy 103.190583 -237.799684) (xy 103.169456 -237.843956)
			(xy 103.14202 -237.88462) (xy 103.137827 -237.889366) (xy 108.350335 -237.889366) (xy 108.350335 -237.837434)
			(xy 108.358458 -237.78614) (xy 108.374505 -237.736749) (xy 108.39808 -237.690476) (xy 108.428602 -237.64846)
			(xy 108.465321 -237.611735) (xy 108.507333 -237.581206) (xy 108.553603 -237.557624) (xy 108.602992 -237.54157)
			(xy 108.654284 -237.533439) (xy 108.68025 -237.532926) (xy 108.705052 -237.53337) (xy 108.754102 -237.540764)
			(xy 108.801495 -237.555408) (xy 108.846166 -237.576973) (xy 108.887111 -237.604974) (xy 108.923409 -237.638783)
			(xy 108.954245 -237.677638) (xy 108.978925 -237.720666) (xy 108.996895 -237.766901) (xy 109.00775 -237.815303)
			(xy 109.009942 -237.840012) (xy 109.011363 -237.853971) (xy 109.020864 -237.880362) (xy 109.037185 -237.903174)
			(xy 109.059097 -237.920685) (xy 109.084946 -237.931575) (xy 109.112782 -237.935023) (xy 109.140507 -237.930769)
			(xy 109.153452 -237.925356) (xy 109.175111 -237.91589) (xy 109.22045 -237.90253) (xy 109.267233 -237.895786)
			(xy 109.290866 -237.895384) (xy 109.31684 -237.895788) (xy 109.368149 -237.90391) (xy 109.417556 -237.919959)
			(xy 109.463844 -237.943539) (xy 109.505872 -237.974071) (xy 109.542607 -238.010802) (xy 109.573143 -238.052827)
			(xy 109.596728 -238.099113) (xy 109.612782 -238.148518) (xy 109.620909 -238.199826) (xy 109.620909 -238.251774)
			(xy 109.620904 -238.251805) (xy 109.900721 -238.251805) (xy 109.900721 -238.199871) (xy 109.908846 -238.148576)
			(xy 109.924894 -238.099183) (xy 109.948472 -238.052909) (xy 109.978998 -238.010893) (xy 110.015721 -237.97417)
			(xy 110.057737 -237.943644) (xy 110.104011 -237.920066) (xy 110.153404 -237.904018) (xy 110.204699 -237.895893)
			(xy 110.256633 -237.895893) (xy 110.307928 -237.904018) (xy 110.357321 -237.920066) (xy 110.403595 -237.943644)
			(xy 110.445611 -237.97417) (xy 110.482334 -238.010893) (xy 110.51286 -238.052909) (xy 110.536438 -238.099183)
			(xy 110.552486 -238.148576) (xy 110.560611 -238.199871) (xy 110.56112 -238.225838) (xy 110.560611 -238.251805)
			(xy 110.840521 -238.251805) (xy 110.840521 -238.199871) (xy 110.848646 -238.148576) (xy 110.864694 -238.099183)
			(xy 110.888272 -238.052909) (xy 110.918798 -238.010893) (xy 110.955521 -237.97417) (xy 110.997537 -237.943644)
			(xy 111.043811 -237.920066) (xy 111.093204 -237.904018) (xy 111.144499 -237.895893) (xy 111.196433 -237.895893)
			(xy 111.247728 -237.904018) (xy 111.297121 -237.920066) (xy 111.343395 -237.943644) (xy 111.385411 -237.97417)
			(xy 111.422134 -238.010893) (xy 111.45266 -238.052909) (xy 111.476238 -238.099183) (xy 111.492286 -238.148576)
			(xy 111.500411 -238.199871) (xy 111.50092 -238.225838) (xy 111.500411 -238.251805) (xy 111.780321 -238.251805)
			(xy 111.780321 -238.199871) (xy 111.788446 -238.148576) (xy 111.804494 -238.099183) (xy 111.828072 -238.052909)
			(xy 111.858598 -238.010893) (xy 111.895321 -237.97417) (xy 111.937337 -237.943644) (xy 111.983611 -237.920066)
			(xy 112.033004 -237.904018) (xy 112.084299 -237.895893) (xy 112.136233 -237.895893) (xy 112.187528 -237.904018)
			(xy 112.236921 -237.920066) (xy 112.283195 -237.943644) (xy 112.325211 -237.97417) (xy 112.361934 -238.010893)
			(xy 112.39246 -238.052909) (xy 112.416038 -238.099183) (xy 112.432086 -238.148576) (xy 112.440211 -238.199871)
			(xy 112.44072 -238.225838) (xy 112.440211 -238.251805) (xy 112.720121 -238.251805) (xy 112.720121 -238.199871)
			(xy 112.728246 -238.148576) (xy 112.744294 -238.099183) (xy 112.767872 -238.052909) (xy 112.798398 -238.010893)
			(xy 112.835121 -237.97417) (xy 112.877137 -237.943644) (xy 112.923411 -237.920066) (xy 112.972804 -237.904018)
			(xy 113.024099 -237.895893) (xy 113.076033 -237.895893) (xy 113.127328 -237.904018) (xy 113.176721 -237.920066)
			(xy 113.222995 -237.943644) (xy 113.265011 -237.97417) (xy 113.301734 -238.010893) (xy 113.33226 -238.052909)
			(xy 113.355838 -238.099183) (xy 113.371886 -238.148576) (xy 113.380011 -238.199871) (xy 113.38052 -238.225838)
			(xy 113.380011 -238.251805) (xy 113.659921 -238.251805) (xy 113.659921 -238.199871) (xy 113.668046 -238.148576)
			(xy 113.684094 -238.099183) (xy 113.707672 -238.052909) (xy 113.738198 -238.010893) (xy 113.774921 -237.97417)
			(xy 113.816937 -237.943644) (xy 113.863211 -237.920066) (xy 113.912604 -237.904018) (xy 113.963899 -237.895893)
			(xy 114.015833 -237.895893) (xy 114.067128 -237.904018) (xy 114.116521 -237.920066) (xy 114.162795 -237.943644)
			(xy 114.204811 -237.97417) (xy 114.241534 -238.010893) (xy 114.27206 -238.052909) (xy 114.295638 -238.099183)
			(xy 114.311686 -238.148576) (xy 114.319811 -238.199871) (xy 114.32032 -238.225838) (xy 114.319816 -238.251551)
			(xy 121.178067 -238.251551) (xy 121.178067 -238.199617) (xy 121.186192 -238.148322) (xy 121.20224 -238.098929)
			(xy 121.225818 -238.052655) (xy 121.256344 -238.010639) (xy 121.293067 -237.973916) (xy 121.335083 -237.94339)
			(xy 121.381357 -237.919812) (xy 121.43075 -237.903764) (xy 121.482045 -237.895639) (xy 121.533979 -237.895639)
			(xy 121.585274 -237.903764) (xy 121.634667 -237.919812) (xy 121.680941 -237.94339) (xy 121.722957 -237.973916)
			(xy 121.75968 -238.010639) (xy 121.790206 -238.052655) (xy 121.813784 -238.098929) (xy 121.829832 -238.148322)
			(xy 121.837957 -238.199617) (xy 121.838466 -238.225584) (xy 121.837957 -238.251551) (xy 122.117867 -238.251551)
			(xy 122.117867 -238.199617) (xy 122.125992 -238.148322) (xy 122.14204 -238.098929) (xy 122.165618 -238.052655)
			(xy 122.196144 -238.010639) (xy 122.232867 -237.973916) (xy 122.274883 -237.94339) (xy 122.321157 -237.919812)
			(xy 122.37055 -237.903764) (xy 122.421845 -237.895639) (xy 122.473779 -237.895639) (xy 122.525074 -237.903764)
			(xy 122.574467 -237.919812) (xy 122.620741 -237.94339) (xy 122.662757 -237.973916) (xy 122.69948 -238.010639)
			(xy 122.730006 -238.052655) (xy 122.753584 -238.098929) (xy 122.769632 -238.148322) (xy 122.777757 -238.199617)
			(xy 122.778266 -238.225584) (xy 122.777757 -238.251551) (xy 123.057667 -238.251551) (xy 123.057667 -238.199617)
			(xy 123.065792 -238.148322) (xy 123.08184 -238.098929) (xy 123.105418 -238.052655) (xy 123.135944 -238.010639)
			(xy 123.172667 -237.973916) (xy 123.214683 -237.94339) (xy 123.260957 -237.919812) (xy 123.31035 -237.903764)
			(xy 123.361645 -237.895639) (xy 123.413579 -237.895639) (xy 123.464874 -237.903764) (xy 123.514267 -237.919812)
			(xy 123.560541 -237.94339) (xy 123.602557 -237.973916) (xy 123.63928 -238.010639) (xy 123.669806 -238.052655)
			(xy 123.693384 -238.098929) (xy 123.709432 -238.148322) (xy 123.717557 -238.199617) (xy 123.718066 -238.225584)
			(xy 123.717557 -238.251551) (xy 123.997467 -238.251551) (xy 123.997467 -238.199617) (xy 124.005592 -238.148322)
			(xy 124.02164 -238.098929) (xy 124.045218 -238.052655) (xy 124.075744 -238.010639) (xy 124.112467 -237.973916)
			(xy 124.154483 -237.94339) (xy 124.200757 -237.919812) (xy 124.25015 -237.903764) (xy 124.301445 -237.895639)
			(xy 124.353379 -237.895639) (xy 124.404674 -237.903764) (xy 124.454067 -237.919812) (xy 124.500341 -237.94339)
			(xy 124.542357 -237.973916) (xy 124.57908 -238.010639) (xy 124.609606 -238.052655) (xy 124.633184 -238.098929)
			(xy 124.649232 -238.148322) (xy 124.657357 -238.199617) (xy 124.657866 -238.225584) (xy 124.657357 -238.251551)
			(xy 124.937267 -238.251551) (xy 124.937267 -238.199617) (xy 124.945392 -238.148322) (xy 124.96144 -238.098929)
			(xy 124.985018 -238.052655) (xy 125.015544 -238.010639) (xy 125.052267 -237.973916) (xy 125.094283 -237.94339)
			(xy 125.140557 -237.919812) (xy 125.18995 -237.903764) (xy 125.241245 -237.895639) (xy 125.293179 -237.895639)
			(xy 125.344474 -237.903764) (xy 125.393867 -237.919812) (xy 125.440141 -237.94339) (xy 125.482157 -237.973916)
			(xy 125.51888 -238.010639) (xy 125.549406 -238.052655) (xy 125.572984 -238.098929) (xy 125.589032 -238.148322)
			(xy 125.597157 -238.199617) (xy 125.597666 -238.225584) (xy 125.597157 -238.251551) (xy 125.877321 -238.251551)
			(xy 125.877321 -238.199617) (xy 125.885446 -238.148322) (xy 125.901494 -238.098929) (xy 125.925072 -238.052655)
			(xy 125.955598 -238.010639) (xy 125.992321 -237.973916) (xy 126.034337 -237.94339) (xy 126.080611 -237.919812)
			(xy 126.130004 -237.903764) (xy 126.181299 -237.895639) (xy 126.233233 -237.895639) (xy 126.284528 -237.903764)
			(xy 126.333921 -237.919812) (xy 126.380195 -237.94339) (xy 126.422211 -237.973916) (xy 126.458934 -238.010639)
			(xy 126.48946 -238.052655) (xy 126.513038 -238.098929) (xy 126.529086 -238.148322) (xy 126.537211 -238.199617)
			(xy 126.53772 -238.225584) (xy 126.537211 -238.251551) (xy 126.816867 -238.251551) (xy 126.816867 -238.199617)
			(xy 126.824992 -238.148322) (xy 126.84104 -238.098929) (xy 126.864618 -238.052655) (xy 126.895144 -238.010639)
			(xy 126.931867 -237.973916) (xy 126.973883 -237.94339) (xy 127.020157 -237.919812) (xy 127.06955 -237.903764)
			(xy 127.120845 -237.895639) (xy 127.172779 -237.895639) (xy 127.224074 -237.903764) (xy 127.273467 -237.919812)
			(xy 127.319741 -237.94339) (xy 127.361757 -237.973916) (xy 127.39848 -238.010639) (xy 127.429006 -238.052655)
			(xy 127.452584 -238.098929) (xy 127.468632 -238.148322) (xy 127.476757 -238.199617) (xy 127.477266 -238.225584)
			(xy 127.476757 -238.251551) (xy 127.756667 -238.251551) (xy 127.756667 -238.199617) (xy 127.764792 -238.148322)
			(xy 127.78084 -238.098929) (xy 127.804418 -238.052655) (xy 127.834944 -238.010639) (xy 127.871667 -237.973916)
			(xy 127.913683 -237.94339) (xy 127.959957 -237.919812) (xy 128.00935 -237.903764) (xy 128.060645 -237.895639)
			(xy 128.112579 -237.895639) (xy 128.163874 -237.903764) (xy 128.213267 -237.919812) (xy 128.259541 -237.94339)
			(xy 128.301557 -237.973916) (xy 128.33828 -238.010639) (xy 128.368806 -238.052655) (xy 128.392384 -238.098929)
			(xy 128.408432 -238.148322) (xy 128.416557 -238.199617) (xy 128.417066 -238.225584) (xy 128.416557 -238.251551)
			(xy 128.696467 -238.251551) (xy 128.696467 -238.199617) (xy 128.704592 -238.148322) (xy 128.72064 -238.098929)
			(xy 128.744218 -238.052655) (xy 128.774744 -238.010639) (xy 128.811467 -237.973916) (xy 128.853483 -237.94339)
			(xy 128.899757 -237.919812) (xy 128.94915 -237.903764) (xy 129.000445 -237.895639) (xy 129.052379 -237.895639)
			(xy 129.103674 -237.903764) (xy 129.153067 -237.919812) (xy 129.199341 -237.94339) (xy 129.241357 -237.973916)
			(xy 129.27808 -238.010639) (xy 129.308606 -238.052655) (xy 129.332184 -238.098929) (xy 129.348232 -238.148322)
			(xy 129.356357 -238.199617) (xy 129.356866 -238.225584) (xy 129.356357 -238.251551) (xy 129.636267 -238.251551)
			(xy 129.636267 -238.199617) (xy 129.644392 -238.148322) (xy 129.66044 -238.098929) (xy 129.684018 -238.052655)
			(xy 129.714544 -238.010639) (xy 129.751267 -237.973916) (xy 129.793283 -237.94339) (xy 129.839557 -237.919812)
			(xy 129.88895 -237.903764) (xy 129.940245 -237.895639) (xy 129.992179 -237.895639) (xy 130.043474 -237.903764)
			(xy 130.092867 -237.919812) (xy 130.139141 -237.94339) (xy 130.181157 -237.973916) (xy 130.21788 -238.010639)
			(xy 130.248406 -238.052655) (xy 130.271984 -238.098929) (xy 130.288032 -238.148322) (xy 130.296157 -238.199617)
			(xy 130.296666 -238.225584) (xy 130.296157 -238.251551) (xy 130.576067 -238.251551) (xy 130.576067 -238.199617)
			(xy 130.584192 -238.148322) (xy 130.60024 -238.098929) (xy 130.623818 -238.052655) (xy 130.654344 -238.010639)
			(xy 130.691067 -237.973916) (xy 130.733083 -237.94339) (xy 130.779357 -237.919812) (xy 130.82875 -237.903764)
			(xy 130.880045 -237.895639) (xy 130.931979 -237.895639) (xy 130.983274 -237.903764) (xy 131.032667 -237.919812)
			(xy 131.078941 -237.94339) (xy 131.120957 -237.973916) (xy 131.15768 -238.010639) (xy 131.188206 -238.052655)
			(xy 131.211784 -238.098929) (xy 131.227832 -238.148322) (xy 131.235957 -238.199617) (xy 131.236466 -238.225584)
			(xy 131.235957 -238.251551) (xy 131.227832 -238.302846) (xy 131.211784 -238.352239) (xy 131.188206 -238.398513)
			(xy 131.15768 -238.440529) (xy 131.120957 -238.477252) (xy 131.078941 -238.507778) (xy 131.032667 -238.531356)
			(xy 130.983274 -238.547404) (xy 130.931979 -238.555529) (xy 130.880045 -238.555529) (xy 130.82875 -238.547404)
			(xy 130.779357 -238.531356) (xy 130.733083 -238.507778) (xy 130.691067 -238.477252) (xy 130.654344 -238.440529)
			(xy 130.623818 -238.398513) (xy 130.60024 -238.352239) (xy 130.584192 -238.302846) (xy 130.576067 -238.251551)
			(xy 130.296157 -238.251551) (xy 130.288032 -238.302846) (xy 130.271984 -238.352239) (xy 130.248406 -238.398513)
			(xy 130.21788 -238.440529) (xy 130.181157 -238.477252) (xy 130.139141 -238.507778) (xy 130.092867 -238.531356)
			(xy 130.043474 -238.547404) (xy 129.992179 -238.555529) (xy 129.940245 -238.555529) (xy 129.88895 -238.547404)
			(xy 129.839557 -238.531356) (xy 129.793283 -238.507778) (xy 129.751267 -238.477252) (xy 129.714544 -238.440529)
			(xy 129.684018 -238.398513) (xy 129.66044 -238.352239) (xy 129.644392 -238.302846) (xy 129.636267 -238.251551)
			(xy 129.356357 -238.251551) (xy 129.348232 -238.302846) (xy 129.332184 -238.352239) (xy 129.308606 -238.398513)
			(xy 129.27808 -238.440529) (xy 129.241357 -238.477252) (xy 129.199341 -238.507778) (xy 129.153067 -238.531356)
			(xy 129.103674 -238.547404) (xy 129.052379 -238.555529) (xy 129.000445 -238.555529) (xy 128.94915 -238.547404)
			(xy 128.899757 -238.531356) (xy 128.853483 -238.507778) (xy 128.811467 -238.477252) (xy 128.774744 -238.440529)
			(xy 128.744218 -238.398513) (xy 128.72064 -238.352239) (xy 128.704592 -238.302846) (xy 128.696467 -238.251551)
			(xy 128.416557 -238.251551) (xy 128.408432 -238.302846) (xy 128.392384 -238.352239) (xy 128.368806 -238.398513)
			(xy 128.33828 -238.440529) (xy 128.301557 -238.477252) (xy 128.259541 -238.507778) (xy 128.213267 -238.531356)
			(xy 128.163874 -238.547404) (xy 128.112579 -238.555529) (xy 128.060645 -238.555529) (xy 128.00935 -238.547404)
			(xy 127.959957 -238.531356) (xy 127.913683 -238.507778) (xy 127.871667 -238.477252) (xy 127.834944 -238.440529)
			(xy 127.804418 -238.398513) (xy 127.78084 -238.352239) (xy 127.764792 -238.302846) (xy 127.756667 -238.251551)
			(xy 127.476757 -238.251551) (xy 127.468632 -238.302846) (xy 127.452584 -238.352239) (xy 127.429006 -238.398513)
			(xy 127.39848 -238.440529) (xy 127.361757 -238.477252) (xy 127.319741 -238.507778) (xy 127.273467 -238.531356)
			(xy 127.224074 -238.547404) (xy 127.172779 -238.555529) (xy 127.120845 -238.555529) (xy 127.06955 -238.547404)
			(xy 127.020157 -238.531356) (xy 126.973883 -238.507778) (xy 126.931867 -238.477252) (xy 126.895144 -238.440529)
			(xy 126.864618 -238.398513) (xy 126.84104 -238.352239) (xy 126.824992 -238.302846) (xy 126.816867 -238.251551)
			(xy 126.537211 -238.251551) (xy 126.529086 -238.302846) (xy 126.513038 -238.352239) (xy 126.48946 -238.398513)
			(xy 126.458934 -238.440529) (xy 126.422211 -238.477252) (xy 126.380195 -238.507778) (xy 126.333921 -238.531356)
			(xy 126.284528 -238.547404) (xy 126.233233 -238.555529) (xy 126.181299 -238.555529) (xy 126.130004 -238.547404)
			(xy 126.080611 -238.531356) (xy 126.034337 -238.507778) (xy 125.992321 -238.477252) (xy 125.955598 -238.440529)
			(xy 125.925072 -238.398513) (xy 125.901494 -238.352239) (xy 125.885446 -238.302846) (xy 125.877321 -238.251551)
			(xy 125.597157 -238.251551) (xy 125.589032 -238.302846) (xy 125.572984 -238.352239) (xy 125.549406 -238.398513)
			(xy 125.51888 -238.440529) (xy 125.482157 -238.477252) (xy 125.440141 -238.507778) (xy 125.393867 -238.531356)
			(xy 125.344474 -238.547404) (xy 125.293179 -238.555529) (xy 125.241245 -238.555529) (xy 125.18995 -238.547404)
			(xy 125.140557 -238.531356) (xy 125.094283 -238.507778) (xy 125.052267 -238.477252) (xy 125.015544 -238.440529)
			(xy 124.985018 -238.398513) (xy 124.96144 -238.352239) (xy 124.945392 -238.302846) (xy 124.937267 -238.251551)
			(xy 124.657357 -238.251551) (xy 124.649232 -238.302846) (xy 124.633184 -238.352239) (xy 124.609606 -238.398513)
			(xy 124.57908 -238.440529) (xy 124.542357 -238.477252) (xy 124.500341 -238.507778) (xy 124.454067 -238.531356)
			(xy 124.404674 -238.547404) (xy 124.353379 -238.555529) (xy 124.301445 -238.555529) (xy 124.25015 -238.547404)
			(xy 124.200757 -238.531356) (xy 124.154483 -238.507778) (xy 124.112467 -238.477252) (xy 124.075744 -238.440529)
			(xy 124.045218 -238.398513) (xy 124.02164 -238.352239) (xy 124.005592 -238.302846) (xy 123.997467 -238.251551)
			(xy 123.717557 -238.251551) (xy 123.709432 -238.302846) (xy 123.693384 -238.352239) (xy 123.669806 -238.398513)
			(xy 123.63928 -238.440529) (xy 123.602557 -238.477252) (xy 123.560541 -238.507778) (xy 123.514267 -238.531356)
			(xy 123.464874 -238.547404) (xy 123.413579 -238.555529) (xy 123.361645 -238.555529) (xy 123.31035 -238.547404)
			(xy 123.260957 -238.531356) (xy 123.214683 -238.507778) (xy 123.172667 -238.477252) (xy 123.135944 -238.440529)
			(xy 123.105418 -238.398513) (xy 123.08184 -238.352239) (xy 123.065792 -238.302846) (xy 123.057667 -238.251551)
			(xy 122.777757 -238.251551) (xy 122.769632 -238.302846) (xy 122.753584 -238.352239) (xy 122.730006 -238.398513)
			(xy 122.69948 -238.440529) (xy 122.662757 -238.477252) (xy 122.620741 -238.507778) (xy 122.574467 -238.531356)
			(xy 122.525074 -238.547404) (xy 122.473779 -238.555529) (xy 122.421845 -238.555529) (xy 122.37055 -238.547404)
			(xy 122.321157 -238.531356) (xy 122.274883 -238.507778) (xy 122.232867 -238.477252) (xy 122.196144 -238.440529)
			(xy 122.165618 -238.398513) (xy 122.14204 -238.352239) (xy 122.125992 -238.302846) (xy 122.117867 -238.251551)
			(xy 121.837957 -238.251551) (xy 121.829832 -238.302846) (xy 121.813784 -238.352239) (xy 121.790206 -238.398513)
			(xy 121.75968 -238.440529) (xy 121.722957 -238.477252) (xy 121.680941 -238.507778) (xy 121.634667 -238.531356)
			(xy 121.585274 -238.547404) (xy 121.533979 -238.555529) (xy 121.482045 -238.555529) (xy 121.43075 -238.547404)
			(xy 121.381357 -238.531356) (xy 121.335083 -238.507778) (xy 121.293067 -238.477252) (xy 121.256344 -238.440529)
			(xy 121.225818 -238.398513) (xy 121.20224 -238.352239) (xy 121.186192 -238.302846) (xy 121.178067 -238.251551)
			(xy 114.319816 -238.251551) (xy 114.319811 -238.251805) (xy 114.311686 -238.3031) (xy 114.295638 -238.352493)
			(xy 114.27206 -238.398767) (xy 114.241534 -238.440783) (xy 114.204811 -238.477506) (xy 114.162795 -238.508032)
			(xy 114.116521 -238.53161) (xy 114.067128 -238.547658) (xy 114.015833 -238.555783) (xy 113.963899 -238.555783)
			(xy 113.912604 -238.547658) (xy 113.863211 -238.53161) (xy 113.816937 -238.508032) (xy 113.774921 -238.477506)
			(xy 113.738198 -238.440783) (xy 113.707672 -238.398767) (xy 113.684094 -238.352493) (xy 113.668046 -238.3031)
			(xy 113.659921 -238.251805) (xy 113.380011 -238.251805) (xy 113.371886 -238.3031) (xy 113.355838 -238.352493)
			(xy 113.33226 -238.398767) (xy 113.301734 -238.440783) (xy 113.265011 -238.477506) (xy 113.222995 -238.508032)
			(xy 113.176721 -238.53161) (xy 113.127328 -238.547658) (xy 113.076033 -238.555783) (xy 113.024099 -238.555783)
			(xy 112.972804 -238.547658) (xy 112.923411 -238.53161) (xy 112.877137 -238.508032) (xy 112.835121 -238.477506)
			(xy 112.798398 -238.440783) (xy 112.767872 -238.398767) (xy 112.744294 -238.352493) (xy 112.728246 -238.3031)
			(xy 112.720121 -238.251805) (xy 112.440211 -238.251805) (xy 112.432086 -238.3031) (xy 112.416038 -238.352493)
			(xy 112.39246 -238.398767) (xy 112.361934 -238.440783) (xy 112.325211 -238.477506) (xy 112.283195 -238.508032)
			(xy 112.236921 -238.53161) (xy 112.187528 -238.547658) (xy 112.136233 -238.555783) (xy 112.084299 -238.555783)
			(xy 112.033004 -238.547658) (xy 111.983611 -238.53161) (xy 111.937337 -238.508032) (xy 111.895321 -238.477506)
			(xy 111.858598 -238.440783) (xy 111.828072 -238.398767) (xy 111.804494 -238.352493) (xy 111.788446 -238.3031)
			(xy 111.780321 -238.251805) (xy 111.500411 -238.251805) (xy 111.492286 -238.3031) (xy 111.476238 -238.352493)
			(xy 111.45266 -238.398767) (xy 111.422134 -238.440783) (xy 111.385411 -238.477506) (xy 111.343395 -238.508032)
			(xy 111.297121 -238.53161) (xy 111.247728 -238.547658) (xy 111.196433 -238.555783) (xy 111.144499 -238.555783)
			(xy 111.093204 -238.547658) (xy 111.043811 -238.53161) (xy 110.997537 -238.508032) (xy 110.955521 -238.477506)
			(xy 110.918798 -238.440783) (xy 110.888272 -238.398767) (xy 110.864694 -238.352493) (xy 110.848646 -238.3031)
			(xy 110.840521 -238.251805) (xy 110.560611 -238.251805) (xy 110.552486 -238.3031) (xy 110.536438 -238.352493)
			(xy 110.51286 -238.398767) (xy 110.482334 -238.440783) (xy 110.445611 -238.477506) (xy 110.403595 -238.508032)
			(xy 110.357321 -238.53161) (xy 110.307928 -238.547658) (xy 110.256633 -238.555783) (xy 110.204699 -238.555783)
			(xy 110.153404 -238.547658) (xy 110.104011 -238.53161) (xy 110.057737 -238.508032) (xy 110.015721 -238.477506)
			(xy 109.978998 -238.440783) (xy 109.948472 -238.398767) (xy 109.924894 -238.352493) (xy 109.908846 -238.3031)
			(xy 109.900721 -238.251805) (xy 109.620904 -238.251805) (xy 109.612782 -238.303082) (xy 109.596728 -238.352487)
			(xy 109.573143 -238.398773) (xy 109.542607 -238.440798) (xy 109.505872 -238.477529) (xy 109.463844 -238.508061)
			(xy 109.417556 -238.531641) (xy 109.368149 -238.54769) (xy 109.31684 -238.555812) (xy 109.290866 -238.556292)
			(xy 109.266065 -238.555817) (xy 109.217017 -238.548426) (xy 109.169626 -238.533785) (xy 109.124956 -238.512223)
			(xy 109.084012 -238.484225) (xy 109.047713 -238.45042) (xy 109.016877 -238.411569) (xy 108.992196 -238.368544)
			(xy 108.974225 -238.322312) (xy 108.963367 -238.273914) (xy 108.961174 -238.249206) (xy 108.959718 -238.235251)
			(xy 108.950223 -238.208863) (xy 108.933908 -238.186053) (xy 108.912003 -238.168542) (xy 108.88616 -238.15765)
			(xy 108.858328 -238.1542) (xy 108.830608 -238.158451) (xy 108.817664 -238.163862) (xy 108.796017 -238.173356)
			(xy 108.750672 -238.186705) (xy 108.703885 -238.193438) (xy 108.68025 -238.193834) (xy 108.654284 -238.193361)
			(xy 108.602992 -238.18523) (xy 108.553603 -238.169176) (xy 108.507333 -238.145594) (xy 108.465321 -238.115065)
			(xy 108.428602 -238.07834) (xy 108.39808 -238.036324) (xy 108.374505 -237.990051) (xy 108.358458 -237.94066)
			(xy 108.350335 -237.889366) (xy 103.137827 -237.889366) (xy 103.125778 -237.903004) (xy 103.115994 -237.914507)
			(xy 103.102985 -237.94174) (xy 103.098515 -237.971588) (xy 103.102978 -238.001437) (xy 103.115981 -238.028673)
			(xy 103.125778 -238.040164) (xy 103.142022 -238.058547) (xy 103.169469 -238.099205) (xy 103.190599 -238.143476)
			(xy 103.204948 -238.190386) (xy 103.2122 -238.238902) (xy 103.212646 -238.26343) (xy 103.212646 -238.263684)
			(xy 103.212137 -238.289651) (xy 103.204012 -238.340946) (xy 103.187964 -238.390339) (xy 103.164386 -238.436613)
			(xy 103.13386 -238.478629) (xy 103.097137 -238.515352) (xy 103.055121 -238.545878) (xy 103.008847 -238.569456)
			(xy 102.959454 -238.585504) (xy 102.908159 -238.593629) (xy 102.856225 -238.593629) (xy 102.80493 -238.585504)
			(xy 102.755537 -238.569456) (xy 102.709263 -238.545878) (xy 102.667247 -238.515352) (xy 102.630524 -238.478629)
			(xy 102.599998 -238.436613) (xy 102.57642 -238.390339) (xy 102.560372 -238.340946) (xy 102.552247 -238.289651)
			(xy 102.551738 -238.263684) (xy 102.551738 -238.26343) (xy 102.552224 -238.238905) (xy 102.559481 -238.190394)
			(xy 102.573825 -238.143488) (xy 102.594942 -238.099216) (xy 102.622368 -238.058549) (xy 102.638606 -238.040164)
			(xy 102.648423 -238.028686) (xy 102.661431 -238.001444) (xy 102.665895 -237.971588) (xy 102.661424 -237.941733)
			(xy 102.64841 -237.914494) (xy 102.638606 -237.903004) (xy 102.620396 -237.882288) (xy 102.590417 -237.835996)
			(xy 102.568524 -237.785375) (xy 102.56139 -237.758732) (xy 102.557675 -237.745702) (xy 102.544507 -237.722039)
			(xy 102.525575 -237.702678) (xy 102.502212 -237.688984) (xy 102.476069 -237.681925) (xy 102.448989 -237.681997)
			(xy 102.422884 -237.689197) (xy 102.411022 -237.69574) (xy 102.385311 -237.710254) (xy 102.329986 -237.730858)
			(xy 102.271884 -237.741323) (xy 102.242366 -237.741968) (xy 102.216402 -237.741428) (xy 102.165113 -237.7333)
			(xy 102.115727 -237.717249) (xy 102.06946 -237.693671) (xy 102.02745 -237.663145) (xy 101.990733 -237.626424)
			(xy 101.960212 -237.584411) (xy 101.936638 -237.538142) (xy 101.920592 -237.488754) (xy 101.912469 -237.437464)
			(xy 101.632511 -237.437464) (xy 101.632511 -237.437481) (xy 101.624386 -237.488776) (xy 101.608338 -237.538169)
			(xy 101.58476 -237.584443) (xy 101.554234 -237.626459) (xy 101.517511 -237.663182) (xy 101.475495 -237.693708)
			(xy 101.429221 -237.717286) (xy 101.379828 -237.733334) (xy 101.328533 -237.741459) (xy 101.276599 -237.741459)
			(xy 101.225304 -237.733334) (xy 101.175911 -237.717286) (xy 101.129637 -237.693708) (xy 101.087621 -237.663182)
			(xy 101.050898 -237.626459) (xy 101.020372 -237.584443) (xy 100.996794 -237.538169) (xy 100.980746 -237.488776)
			(xy 100.972621 -237.437481) (xy 100.692711 -237.437481) (xy 100.684586 -237.488776) (xy 100.668538 -237.538169)
			(xy 100.64496 -237.584443) (xy 100.614434 -237.626459) (xy 100.577711 -237.663182) (xy 100.535695 -237.693708)
			(xy 100.489421 -237.717286) (xy 100.440028 -237.733334) (xy 100.388733 -237.741459) (xy 100.336799 -237.741459)
			(xy 100.285504 -237.733334) (xy 100.236111 -237.717286) (xy 100.189837 -237.693708) (xy 100.147821 -237.663182)
			(xy 100.111098 -237.626459) (xy 100.080572 -237.584443) (xy 100.056994 -237.538169) (xy 100.040946 -237.488776)
			(xy 100.032821 -237.437481) (xy 99.752911 -237.437481) (xy 99.744786 -237.488776) (xy 99.728738 -237.538169)
			(xy 99.70516 -237.584443) (xy 99.674634 -237.626459) (xy 99.637911 -237.663182) (xy 99.595895 -237.693708)
			(xy 99.549621 -237.717286) (xy 99.500228 -237.733334) (xy 99.448933 -237.741459) (xy 99.396999 -237.741459)
			(xy 99.345704 -237.733334) (xy 99.296311 -237.717286) (xy 99.250037 -237.693708) (xy 99.208021 -237.663182)
			(xy 99.171298 -237.626459) (xy 99.140772 -237.584443) (xy 99.117194 -237.538169) (xy 99.101146 -237.488776)
			(xy 99.093021 -237.437481) (xy 98.812857 -237.437481) (xy 98.804732 -237.488776) (xy 98.788684 -237.538169)
			(xy 98.765106 -237.584443) (xy 98.73458 -237.626459) (xy 98.697857 -237.663182) (xy 98.655841 -237.693708)
			(xy 98.609567 -237.717286) (xy 98.560174 -237.733334) (xy 98.508879 -237.741459) (xy 98.456945 -237.741459)
			(xy 98.40565 -237.733334) (xy 98.356257 -237.717286) (xy 98.309983 -237.693708) (xy 98.267967 -237.663182)
			(xy 98.231244 -237.626459) (xy 98.200718 -237.584443) (xy 98.17714 -237.538169) (xy 98.161092 -237.488776)
			(xy 98.152967 -237.437481) (xy 97.873311 -237.437481) (xy 97.865186 -237.488776) (xy 97.849138 -237.538169)
			(xy 97.82556 -237.584443) (xy 97.795034 -237.626459) (xy 97.758311 -237.663182) (xy 97.716295 -237.693708)
			(xy 97.670021 -237.717286) (xy 97.620628 -237.733334) (xy 97.569333 -237.741459) (xy 97.517399 -237.741459)
			(xy 97.466104 -237.733334) (xy 97.416711 -237.717286) (xy 97.370437 -237.693708) (xy 97.328421 -237.663182)
			(xy 97.291698 -237.626459) (xy 97.261172 -237.584443) (xy 97.237594 -237.538169) (xy 97.221546 -237.488776)
			(xy 97.213421 -237.437481) (xy 96.933511 -237.437481) (xy 96.925386 -237.488776) (xy 96.909338 -237.538169)
			(xy 96.88576 -237.584443) (xy 96.855234 -237.626459) (xy 96.818511 -237.663182) (xy 96.776495 -237.693708)
			(xy 96.730221 -237.717286) (xy 96.680828 -237.733334) (xy 96.629533 -237.741459) (xy 96.577599 -237.741459)
			(xy 96.526304 -237.733334) (xy 96.476911 -237.717286) (xy 96.430637 -237.693708) (xy 96.388621 -237.663182)
			(xy 96.351898 -237.626459) (xy 96.321372 -237.584443) (xy 96.297794 -237.538169) (xy 96.281746 -237.488776)
			(xy 96.273621 -237.437481) (xy 95.993711 -237.437481) (xy 95.985586 -237.488776) (xy 95.969538 -237.538169)
			(xy 95.94596 -237.584443) (xy 95.915434 -237.626459) (xy 95.878711 -237.663182) (xy 95.836695 -237.693708)
			(xy 95.790421 -237.717286) (xy 95.741028 -237.733334) (xy 95.689733 -237.741459) (xy 95.637799 -237.741459)
			(xy 95.586504 -237.733334) (xy 95.537111 -237.717286) (xy 95.490837 -237.693708) (xy 95.448821 -237.663182)
			(xy 95.412098 -237.626459) (xy 95.381572 -237.584443) (xy 95.357994 -237.538169) (xy 95.341946 -237.488776)
			(xy 95.333821 -237.437481) (xy 95.053911 -237.437481) (xy 95.045786 -237.488776) (xy 95.029738 -237.538169)
			(xy 95.00616 -237.584443) (xy 94.975634 -237.626459) (xy 94.938911 -237.663182) (xy 94.896895 -237.693708)
			(xy 94.850621 -237.717286) (xy 94.801228 -237.733334) (xy 94.749933 -237.741459) (xy 94.697999 -237.741459)
			(xy 94.646704 -237.733334) (xy 94.597311 -237.717286) (xy 94.551037 -237.693708) (xy 94.509021 -237.663182)
			(xy 94.472298 -237.626459) (xy 94.441772 -237.584443) (xy 94.418194 -237.538169) (xy 94.402146 -237.488776)
			(xy 94.394021 -237.437481) (xy 94.114111 -237.437481) (xy 94.105986 -237.488776) (xy 94.089938 -237.538169)
			(xy 94.06636 -237.584443) (xy 94.035834 -237.626459) (xy 93.999111 -237.663182) (xy 93.957095 -237.693708)
			(xy 93.910821 -237.717286) (xy 93.861428 -237.733334) (xy 93.810133 -237.741459) (xy 93.758199 -237.741459)
			(xy 93.706904 -237.733334) (xy 93.657511 -237.717286) (xy 93.611237 -237.693708) (xy 93.569221 -237.663182)
			(xy 93.532498 -237.626459) (xy 93.501972 -237.584443) (xy 93.478394 -237.538169) (xy 93.462346 -237.488776)
			(xy 93.454221 -237.437481) (xy 93.174311 -237.437481) (xy 93.166186 -237.488776) (xy 93.150138 -237.538169)
			(xy 93.12656 -237.584443) (xy 93.096034 -237.626459) (xy 93.059311 -237.663182) (xy 93.017295 -237.693708)
			(xy 92.971021 -237.717286) (xy 92.921628 -237.733334) (xy 92.870333 -237.741459) (xy 92.818399 -237.741459)
			(xy 92.767104 -237.733334) (xy 92.717711 -237.717286) (xy 92.671437 -237.693708) (xy 92.629421 -237.663182)
			(xy 92.592698 -237.626459) (xy 92.562172 -237.584443) (xy 92.538594 -237.538169) (xy 92.522546 -237.488776)
			(xy 92.514421 -237.437481) (xy 92.234485 -237.437481) (xy 92.234485 -237.437485) (xy 92.226355 -237.488817)
			(xy 92.210295 -237.538244) (xy 92.186701 -237.584551) (xy 92.156154 -237.626597) (xy 92.119406 -237.663346)
			(xy 92.077361 -237.693895) (xy 92.031055 -237.717491) (xy 91.981628 -237.733552) (xy 91.930297 -237.741684)
			(xy 91.904312 -237.742222) (xy 91.877431 -237.7417) (xy 91.824373 -237.733019) (xy 91.773415 -237.715882)
			(xy 91.725893 -237.690741) (xy 91.70416 -237.674912) (xy 91.69781 -237.670086) (xy 91.666568 -237.659164)
			(xy 91.661817 -237.659278) (xy 91.652485 -237.661073) (xy 91.648026 -237.66272) (xy 91.562682 -237.703868)
			(xy 91.554672 -237.708381) (xy 91.542346 -237.722) (xy 91.535727 -237.739134) (xy 91.53525 -237.748318)
			(xy 91.53525 -237.875826) (xy 91.565222 -237.921292) (xy 91.577922 -237.927388) (xy 91.601628 -237.939359)
			(xy 91.645211 -237.969701) (xy 91.683386 -238.006615) (xy 91.715175 -238.049154) (xy 91.73976 -238.096225)
			(xy 91.756509 -238.146619) (xy 91.764994 -238.199041) (xy 91.764995 -238.251551) (xy 92.044267 -238.251551)
			(xy 92.044267 -238.199617) (xy 92.052392 -238.148322) (xy 92.06844 -238.098929) (xy 92.092018 -238.052655)
			(xy 92.122544 -238.010639) (xy 92.159267 -237.973916) (xy 92.201283 -237.94339) (xy 92.247557 -237.919812)
			(xy 92.29695 -237.903764) (xy 92.348245 -237.895639) (xy 92.400179 -237.895639) (xy 92.451474 -237.903764)
			(xy 92.500867 -237.919812) (xy 92.547141 -237.94339) (xy 92.589157 -237.973916) (xy 92.62588 -238.010639)
			(xy 92.656406 -238.052655) (xy 92.679984 -238.098929) (xy 92.696032 -238.148322) (xy 92.704157 -238.199617)
			(xy 92.704666 -238.225584) (xy 92.704157 -238.251551) (xy 92.984067 -238.251551) (xy 92.984067 -238.199617)
			(xy 92.992192 -238.148322) (xy 93.00824 -238.098929) (xy 93.031818 -238.052655) (xy 93.062344 -238.010639)
			(xy 93.099067 -237.973916) (xy 93.141083 -237.94339) (xy 93.187357 -237.919812) (xy 93.23675 -237.903764)
			(xy 93.288045 -237.895639) (xy 93.339979 -237.895639) (xy 93.391274 -237.903764) (xy 93.440667 -237.919812)
			(xy 93.486941 -237.94339) (xy 93.528957 -237.973916) (xy 93.56568 -238.010639) (xy 93.596206 -238.052655)
			(xy 93.619784 -238.098929) (xy 93.635832 -238.148322) (xy 93.643957 -238.199617) (xy 93.644466 -238.225584)
			(xy 93.643957 -238.251551) (xy 93.923867 -238.251551) (xy 93.923867 -238.199617) (xy 93.931992 -238.148322)
			(xy 93.94804 -238.098929) (xy 93.971618 -238.052655) (xy 94.002144 -238.010639) (xy 94.038867 -237.973916)
			(xy 94.080883 -237.94339) (xy 94.127157 -237.919812) (xy 94.17655 -237.903764) (xy 94.227845 -237.895639)
			(xy 94.279779 -237.895639) (xy 94.331074 -237.903764) (xy 94.380467 -237.919812) (xy 94.426741 -237.94339)
			(xy 94.468757 -237.973916) (xy 94.50548 -238.010639) (xy 94.536006 -238.052655) (xy 94.559584 -238.098929)
			(xy 94.575632 -238.148322) (xy 94.583757 -238.199617) (xy 94.584266 -238.225584) (xy 94.583757 -238.251551)
			(xy 94.863667 -238.251551) (xy 94.863667 -238.199617) (xy 94.871792 -238.148322) (xy 94.88784 -238.098929)
			(xy 94.911418 -238.052655) (xy 94.941944 -238.010639) (xy 94.978667 -237.973916) (xy 95.020683 -237.94339)
			(xy 95.066957 -237.919812) (xy 95.11635 -237.903764) (xy 95.167645 -237.895639) (xy 95.219579 -237.895639)
			(xy 95.270874 -237.903764) (xy 95.320267 -237.919812) (xy 95.366541 -237.94339) (xy 95.408557 -237.973916)
			(xy 95.44528 -238.010639) (xy 95.475806 -238.052655) (xy 95.499384 -238.098929) (xy 95.515432 -238.148322)
			(xy 95.523557 -238.199617) (xy 95.524066 -238.225584) (xy 95.523557 -238.251551) (xy 95.803467 -238.251551)
			(xy 95.803467 -238.199617) (xy 95.811592 -238.148322) (xy 95.82764 -238.098929) (xy 95.851218 -238.052655)
			(xy 95.881744 -238.010639) (xy 95.918467 -237.973916) (xy 95.960483 -237.94339) (xy 96.006757 -237.919812)
			(xy 96.05615 -237.903764) (xy 96.107445 -237.895639) (xy 96.159379 -237.895639) (xy 96.210674 -237.903764)
			(xy 96.260067 -237.919812) (xy 96.306341 -237.94339) (xy 96.348357 -237.973916) (xy 96.38508 -238.010639)
			(xy 96.415606 -238.052655) (xy 96.439184 -238.098929) (xy 96.455232 -238.148322) (xy 96.463357 -238.199617)
			(xy 96.463866 -238.225584) (xy 96.463357 -238.251551) (xy 96.743267 -238.251551) (xy 96.743267 -238.199617)
			(xy 96.751392 -238.148322) (xy 96.76744 -238.098929) (xy 96.791018 -238.052655) (xy 96.821544 -238.010639)
			(xy 96.858267 -237.973916) (xy 96.900283 -237.94339) (xy 96.946557 -237.919812) (xy 96.99595 -237.903764)
			(xy 97.047245 -237.895639) (xy 97.099179 -237.895639) (xy 97.150474 -237.903764) (xy 97.199867 -237.919812)
			(xy 97.246141 -237.94339) (xy 97.288157 -237.973916) (xy 97.32488 -238.010639) (xy 97.355406 -238.052655)
			(xy 97.378984 -238.098929) (xy 97.395032 -238.148322) (xy 97.403157 -238.199617) (xy 97.403666 -238.225584)
			(xy 97.403157 -238.251551) (xy 97.683321 -238.251551) (xy 97.683321 -238.199617) (xy 97.691446 -238.148322)
			(xy 97.707494 -238.098929) (xy 97.731072 -238.052655) (xy 97.761598 -238.010639) (xy 97.798321 -237.973916)
			(xy 97.840337 -237.94339) (xy 97.886611 -237.919812) (xy 97.936004 -237.903764) (xy 97.987299 -237.895639)
			(xy 98.039233 -237.895639) (xy 98.090528 -237.903764) (xy 98.139921 -237.919812) (xy 98.186195 -237.94339)
			(xy 98.228211 -237.973916) (xy 98.264934 -238.010639) (xy 98.29546 -238.052655) (xy 98.319038 -238.098929)
			(xy 98.335086 -238.148322) (xy 98.343211 -238.199617) (xy 98.34372 -238.225584) (xy 98.343211 -238.251551)
			(xy 98.622867 -238.251551) (xy 98.622867 -238.199617) (xy 98.630992 -238.148322) (xy 98.64704 -238.098929)
			(xy 98.670618 -238.052655) (xy 98.701144 -238.010639) (xy 98.737867 -237.973916) (xy 98.779883 -237.94339)
			(xy 98.826157 -237.919812) (xy 98.87555 -237.903764) (xy 98.926845 -237.895639) (xy 98.978779 -237.895639)
			(xy 99.030074 -237.903764) (xy 99.079467 -237.919812) (xy 99.125741 -237.94339) (xy 99.167757 -237.973916)
			(xy 99.20448 -238.010639) (xy 99.235006 -238.052655) (xy 99.258584 -238.098929) (xy 99.274632 -238.148322)
			(xy 99.282757 -238.199617) (xy 99.283266 -238.225584) (xy 99.282757 -238.251551) (xy 99.562667 -238.251551)
			(xy 99.562667 -238.199617) (xy 99.570792 -238.148322) (xy 99.58684 -238.098929) (xy 99.610418 -238.052655)
			(xy 99.640944 -238.010639) (xy 99.677667 -237.973916) (xy 99.719683 -237.94339) (xy 99.765957 -237.919812)
			(xy 99.81535 -237.903764) (xy 99.866645 -237.895639) (xy 99.918579 -237.895639) (xy 99.969874 -237.903764)
			(xy 100.019267 -237.919812) (xy 100.065541 -237.94339) (xy 100.107557 -237.973916) (xy 100.14428 -238.010639)
			(xy 100.174806 -238.052655) (xy 100.198384 -238.098929) (xy 100.214432 -238.148322) (xy 100.222557 -238.199617)
			(xy 100.223066 -238.225584) (xy 100.222557 -238.251551) (xy 100.502467 -238.251551) (xy 100.502467 -238.199617)
			(xy 100.510592 -238.148322) (xy 100.52664 -238.098929) (xy 100.550218 -238.052655) (xy 100.580744 -238.010639)
			(xy 100.617467 -237.973916) (xy 100.659483 -237.94339) (xy 100.705757 -237.919812) (xy 100.75515 -237.903764)
			(xy 100.806445 -237.895639) (xy 100.858379 -237.895639) (xy 100.909674 -237.903764) (xy 100.959067 -237.919812)
			(xy 101.005341 -237.94339) (xy 101.047357 -237.973916) (xy 101.08408 -238.010639) (xy 101.114606 -238.052655)
			(xy 101.138184 -238.098929) (xy 101.154232 -238.148322) (xy 101.162357 -238.199617) (xy 101.162866 -238.225584)
			(xy 101.162357 -238.251551) (xy 101.442267 -238.251551) (xy 101.442267 -238.199617) (xy 101.450392 -238.148322)
			(xy 101.46644 -238.098929) (xy 101.490018 -238.052655) (xy 101.520544 -238.010639) (xy 101.557267 -237.973916)
			(xy 101.599283 -237.94339) (xy 101.645557 -237.919812) (xy 101.69495 -237.903764) (xy 101.746245 -237.895639)
			(xy 101.798179 -237.895639) (xy 101.849474 -237.903764) (xy 101.898867 -237.919812) (xy 101.945141 -237.94339)
			(xy 101.987157 -237.973916) (xy 102.02388 -238.010639) (xy 102.054406 -238.052655) (xy 102.077984 -238.098929)
			(xy 102.094032 -238.148322) (xy 102.102157 -238.199617) (xy 102.102666 -238.225584) (xy 102.102157 -238.251551)
			(xy 102.094032 -238.302846) (xy 102.077984 -238.352239) (xy 102.054406 -238.398513) (xy 102.02388 -238.440529)
			(xy 101.987157 -238.477252) (xy 101.945141 -238.507778) (xy 101.898867 -238.531356) (xy 101.849474 -238.547404)
			(xy 101.798179 -238.555529) (xy 101.746245 -238.555529) (xy 101.69495 -238.547404) (xy 101.645557 -238.531356)
			(xy 101.599283 -238.507778) (xy 101.557267 -238.477252) (xy 101.520544 -238.440529) (xy 101.490018 -238.398513)
			(xy 101.46644 -238.352239) (xy 101.450392 -238.302846) (xy 101.442267 -238.251551) (xy 101.162357 -238.251551)
			(xy 101.154232 -238.302846) (xy 101.138184 -238.352239) (xy 101.114606 -238.398513) (xy 101.08408 -238.440529)
			(xy 101.047357 -238.477252) (xy 101.005341 -238.507778) (xy 100.959067 -238.531356) (xy 100.909674 -238.547404)
			(xy 100.858379 -238.555529) (xy 100.806445 -238.555529) (xy 100.75515 -238.547404) (xy 100.705757 -238.531356)
			(xy 100.659483 -238.507778) (xy 100.617467 -238.477252) (xy 100.580744 -238.440529) (xy 100.550218 -238.398513)
			(xy 100.52664 -238.352239) (xy 100.510592 -238.302846) (xy 100.502467 -238.251551) (xy 100.222557 -238.251551)
			(xy 100.214432 -238.302846) (xy 100.198384 -238.352239) (xy 100.174806 -238.398513) (xy 100.14428 -238.440529)
			(xy 100.107557 -238.477252) (xy 100.065541 -238.507778) (xy 100.019267 -238.531356) (xy 99.969874 -238.547404)
			(xy 99.918579 -238.555529) (xy 99.866645 -238.555529) (xy 99.81535 -238.547404) (xy 99.765957 -238.531356)
			(xy 99.719683 -238.507778) (xy 99.677667 -238.477252) (xy 99.640944 -238.440529) (xy 99.610418 -238.398513)
			(xy 99.58684 -238.352239) (xy 99.570792 -238.302846) (xy 99.562667 -238.251551) (xy 99.282757 -238.251551)
			(xy 99.274632 -238.302846) (xy 99.258584 -238.352239) (xy 99.235006 -238.398513) (xy 99.20448 -238.440529)
			(xy 99.167757 -238.477252) (xy 99.125741 -238.507778) (xy 99.079467 -238.531356) (xy 99.030074 -238.547404)
			(xy 98.978779 -238.555529) (xy 98.926845 -238.555529) (xy 98.87555 -238.547404) (xy 98.826157 -238.531356)
			(xy 98.779883 -238.507778) (xy 98.737867 -238.477252) (xy 98.701144 -238.440529) (xy 98.670618 -238.398513)
			(xy 98.64704 -238.352239) (xy 98.630992 -238.302846) (xy 98.622867 -238.251551) (xy 98.343211 -238.251551)
			(xy 98.335086 -238.302846) (xy 98.319038 -238.352239) (xy 98.29546 -238.398513) (xy 98.264934 -238.440529)
			(xy 98.228211 -238.477252) (xy 98.186195 -238.507778) (xy 98.139921 -238.531356) (xy 98.090528 -238.547404)
			(xy 98.039233 -238.555529) (xy 97.987299 -238.555529) (xy 97.936004 -238.547404) (xy 97.886611 -238.531356)
			(xy 97.840337 -238.507778) (xy 97.798321 -238.477252) (xy 97.761598 -238.440529) (xy 97.731072 -238.398513)
			(xy 97.707494 -238.352239) (xy 97.691446 -238.302846) (xy 97.683321 -238.251551) (xy 97.403157 -238.251551)
			(xy 97.395032 -238.302846) (xy 97.378984 -238.352239) (xy 97.355406 -238.398513) (xy 97.32488 -238.440529)
			(xy 97.288157 -238.477252) (xy 97.246141 -238.507778) (xy 97.199867 -238.531356) (xy 97.150474 -238.547404)
			(xy 97.099179 -238.555529) (xy 97.047245 -238.555529) (xy 96.99595 -238.547404) (xy 96.946557 -238.531356)
			(xy 96.900283 -238.507778) (xy 96.858267 -238.477252) (xy 96.821544 -238.440529) (xy 96.791018 -238.398513)
			(xy 96.76744 -238.352239) (xy 96.751392 -238.302846) (xy 96.743267 -238.251551) (xy 96.463357 -238.251551)
			(xy 96.455232 -238.302846) (xy 96.439184 -238.352239) (xy 96.415606 -238.398513) (xy 96.38508 -238.440529)
			(xy 96.348357 -238.477252) (xy 96.306341 -238.507778) (xy 96.260067 -238.531356) (xy 96.210674 -238.547404)
			(xy 96.159379 -238.555529) (xy 96.107445 -238.555529) (xy 96.05615 -238.547404) (xy 96.006757 -238.531356)
			(xy 95.960483 -238.507778) (xy 95.918467 -238.477252) (xy 95.881744 -238.440529) (xy 95.851218 -238.398513)
			(xy 95.82764 -238.352239) (xy 95.811592 -238.302846) (xy 95.803467 -238.251551) (xy 95.523557 -238.251551)
			(xy 95.515432 -238.302846) (xy 95.499384 -238.352239) (xy 95.475806 -238.398513) (xy 95.44528 -238.440529)
			(xy 95.408557 -238.477252) (xy 95.366541 -238.507778) (xy 95.320267 -238.531356) (xy 95.270874 -238.547404)
			(xy 95.219579 -238.555529) (xy 95.167645 -238.555529) (xy 95.11635 -238.547404) (xy 95.066957 -238.531356)
			(xy 95.020683 -238.507778) (xy 94.978667 -238.477252) (xy 94.941944 -238.440529) (xy 94.911418 -238.398513)
			(xy 94.88784 -238.352239) (xy 94.871792 -238.302846) (xy 94.863667 -238.251551) (xy 94.583757 -238.251551)
			(xy 94.575632 -238.302846) (xy 94.559584 -238.352239) (xy 94.536006 -238.398513) (xy 94.50548 -238.440529)
			(xy 94.468757 -238.477252) (xy 94.426741 -238.507778) (xy 94.380467 -238.531356) (xy 94.331074 -238.547404)
			(xy 94.279779 -238.555529) (xy 94.227845 -238.555529) (xy 94.17655 -238.547404) (xy 94.127157 -238.531356)
			(xy 94.080883 -238.507778) (xy 94.038867 -238.477252) (xy 94.002144 -238.440529) (xy 93.971618 -238.398513)
			(xy 93.94804 -238.352239) (xy 93.931992 -238.302846) (xy 93.923867 -238.251551) (xy 93.643957 -238.251551)
			(xy 93.635832 -238.302846) (xy 93.619784 -238.352239) (xy 93.596206 -238.398513) (xy 93.56568 -238.440529)
			(xy 93.528957 -238.477252) (xy 93.486941 -238.507778) (xy 93.440667 -238.531356) (xy 93.391274 -238.547404)
			(xy 93.339979 -238.555529) (xy 93.288045 -238.555529) (xy 93.23675 -238.547404) (xy 93.187357 -238.531356)
			(xy 93.141083 -238.507778) (xy 93.099067 -238.477252) (xy 93.062344 -238.440529) (xy 93.031818 -238.398513)
			(xy 93.00824 -238.352239) (xy 92.992192 -238.302846) (xy 92.984067 -238.251551) (xy 92.704157 -238.251551)
			(xy 92.696032 -238.302846) (xy 92.679984 -238.352239) (xy 92.656406 -238.398513) (xy 92.62588 -238.440529)
			(xy 92.589157 -238.477252) (xy 92.547141 -238.507778) (xy 92.500867 -238.531356) (xy 92.451474 -238.547404)
			(xy 92.400179 -238.555529) (xy 92.348245 -238.555529) (xy 92.29695 -238.547404) (xy 92.247557 -238.531356)
			(xy 92.201283 -238.507778) (xy 92.159267 -238.477252) (xy 92.122544 -238.440529) (xy 92.092018 -238.398513)
			(xy 92.06844 -238.352239) (xy 92.052392 -238.302846) (xy 92.044267 -238.251551) (xy 91.764995 -238.251551)
			(xy 91.764995 -238.252145) (xy 91.756513 -238.304568) (xy 91.739765 -238.354962) (xy 91.715182 -238.402034)
			(xy 91.683396 -238.444574) (xy 91.645222 -238.48149) (xy 91.60164 -238.511834) (xy 91.577922 -238.52378)
			(xy 91.565222 -238.529876) (xy 91.53525 -238.575342) (xy 91.53525 -238.70285) (xy 91.53568 -238.711872)
			(xy 91.542138 -238.728726) (xy 91.554131 -238.742213) (xy 91.56192 -238.746792) (xy 91.604846 -238.767366)
			(xy 91.645232 -238.786924) (xy 91.650455 -238.789264) (xy 91.661609 -238.791818) (xy 91.66733 -238.792004)
			(xy 91.69781 -238.781082) (xy 91.70416 -238.776256) (xy 91.725908 -238.760375) (xy 91.773477 -238.735142)
			(xy 91.824504 -238.717944) (xy 91.877642 -238.709236) (xy 91.904566 -238.708692) (xy 91.930557 -238.709173)
			(xy 91.9819 -238.7173) (xy 92.031339 -238.733359) (xy 92.077657 -238.756955) (xy 92.119713 -238.787506)
			(xy 92.156471 -238.824261) (xy 92.187027 -238.866314) (xy 92.210628 -238.91263) (xy 92.226692 -238.962067)
			(xy 92.234825 -239.013409) (xy 92.234825 -239.065367) (xy 92.514421 -239.065367) (xy 92.514421 -239.013433)
			(xy 92.522546 -238.962138) (xy 92.538594 -238.912745) (xy 92.562172 -238.866471) (xy 92.592698 -238.824455)
			(xy 92.629421 -238.787732) (xy 92.671437 -238.757206) (xy 92.717711 -238.733628) (xy 92.767104 -238.71758)
			(xy 92.818399 -238.709455) (xy 92.870333 -238.709455) (xy 92.921628 -238.71758) (xy 92.971021 -238.733628)
			(xy 93.017295 -238.757206) (xy 93.059311 -238.787732) (xy 93.096034 -238.824455) (xy 93.12656 -238.866471)
			(xy 93.150138 -238.912745) (xy 93.166186 -238.962138) (xy 93.174311 -239.013433) (xy 93.17482 -239.0394)
			(xy 93.174311 -239.065367) (xy 93.454221 -239.065367) (xy 93.454221 -239.013433) (xy 93.462346 -238.962138)
			(xy 93.478394 -238.912745) (xy 93.501972 -238.866471) (xy 93.532498 -238.824455) (xy 93.569221 -238.787732)
			(xy 93.611237 -238.757206) (xy 93.657511 -238.733628) (xy 93.706904 -238.71758) (xy 93.758199 -238.709455)
			(xy 93.810133 -238.709455) (xy 93.861428 -238.71758) (xy 93.910821 -238.733628) (xy 93.957095 -238.757206)
			(xy 93.999111 -238.787732) (xy 94.035834 -238.824455) (xy 94.06636 -238.866471) (xy 94.089938 -238.912745)
			(xy 94.105986 -238.962138) (xy 94.114111 -239.013433) (xy 94.11462 -239.0394) (xy 94.114111 -239.065367)
			(xy 94.393767 -239.065367) (xy 94.393767 -239.013433) (xy 94.401892 -238.962138) (xy 94.41794 -238.912745)
			(xy 94.441518 -238.866471) (xy 94.472044 -238.824455) (xy 94.508767 -238.787732) (xy 94.550783 -238.757206)
			(xy 94.597057 -238.733628) (xy 94.64645 -238.71758) (xy 94.697745 -238.709455) (xy 94.749679 -238.709455)
			(xy 94.800974 -238.71758) (xy 94.850367 -238.733628) (xy 94.896641 -238.757206) (xy 94.938657 -238.787732)
			(xy 94.97538 -238.824455) (xy 95.005906 -238.866471) (xy 95.029484 -238.912745) (xy 95.045532 -238.962138)
			(xy 95.053657 -239.013433) (xy 95.054166 -239.0394) (xy 95.053657 -239.065367) (xy 95.333821 -239.065367)
			(xy 95.333821 -239.013433) (xy 95.341946 -238.962138) (xy 95.357994 -238.912745) (xy 95.381572 -238.866471)
			(xy 95.412098 -238.824455) (xy 95.448821 -238.787732) (xy 95.490837 -238.757206) (xy 95.537111 -238.733628)
			(xy 95.586504 -238.71758) (xy 95.637799 -238.709455) (xy 95.689733 -238.709455) (xy 95.741028 -238.71758)
			(xy 95.790421 -238.733628) (xy 95.836695 -238.757206) (xy 95.878711 -238.787732) (xy 95.915434 -238.824455)
			(xy 95.94596 -238.866471) (xy 95.969538 -238.912745) (xy 95.985586 -238.962138) (xy 95.993711 -239.013433)
			(xy 95.99422 -239.0394) (xy 95.993711 -239.065367) (xy 96.273621 -239.065367) (xy 96.273621 -239.013433)
			(xy 96.281746 -238.962138) (xy 96.297794 -238.912745) (xy 96.321372 -238.866471) (xy 96.351898 -238.824455)
			(xy 96.388621 -238.787732) (xy 96.430637 -238.757206) (xy 96.476911 -238.733628) (xy 96.526304 -238.71758)
			(xy 96.577599 -238.709455) (xy 96.629533 -238.709455) (xy 96.680828 -238.71758) (xy 96.730221 -238.733628)
			(xy 96.776495 -238.757206) (xy 96.818511 -238.787732) (xy 96.855234 -238.824455) (xy 96.88576 -238.866471)
			(xy 96.909338 -238.912745) (xy 96.925386 -238.962138) (xy 96.933511 -239.013433) (xy 96.93402 -239.0394)
			(xy 96.933511 -239.065367) (xy 97.213421 -239.065367) (xy 97.213421 -239.013433) (xy 97.221546 -238.962138)
			(xy 97.237594 -238.912745) (xy 97.261172 -238.866471) (xy 97.291698 -238.824455) (xy 97.328421 -238.787732)
			(xy 97.370437 -238.757206) (xy 97.416711 -238.733628) (xy 97.466104 -238.71758) (xy 97.517399 -238.709455)
			(xy 97.569333 -238.709455) (xy 97.620628 -238.71758) (xy 97.670021 -238.733628) (xy 97.716295 -238.757206)
			(xy 97.758311 -238.787732) (xy 97.795034 -238.824455) (xy 97.82556 -238.866471) (xy 97.849138 -238.912745)
			(xy 97.865186 -238.962138) (xy 97.873311 -239.013433) (xy 97.87382 -239.0394) (xy 97.873311 -239.065367)
			(xy 98.153221 -239.065367) (xy 98.153221 -239.013433) (xy 98.161346 -238.962138) (xy 98.177394 -238.912745)
			(xy 98.200972 -238.866471) (xy 98.231498 -238.824455) (xy 98.268221 -238.787732) (xy 98.310237 -238.757206)
			(xy 98.356511 -238.733628) (xy 98.405904 -238.71758) (xy 98.457199 -238.709455) (xy 98.509133 -238.709455)
			(xy 98.560428 -238.71758) (xy 98.609821 -238.733628) (xy 98.656095 -238.757206) (xy 98.698111 -238.787732)
			(xy 98.734834 -238.824455) (xy 98.76536 -238.866471) (xy 98.788938 -238.912745) (xy 98.804986 -238.962138)
			(xy 98.813111 -239.013433) (xy 98.81362 -239.0394) (xy 98.813111 -239.065367) (xy 99.093021 -239.065367)
			(xy 99.093021 -239.013433) (xy 99.101146 -238.962138) (xy 99.117194 -238.912745) (xy 99.140772 -238.866471)
			(xy 99.171298 -238.824455) (xy 99.208021 -238.787732) (xy 99.250037 -238.757206) (xy 99.296311 -238.733628)
			(xy 99.345704 -238.71758) (xy 99.396999 -238.709455) (xy 99.448933 -238.709455) (xy 99.500228 -238.71758)
			(xy 99.549621 -238.733628) (xy 99.595895 -238.757206) (xy 99.637911 -238.787732) (xy 99.674634 -238.824455)
			(xy 99.70516 -238.866471) (xy 99.728738 -238.912745) (xy 99.744786 -238.962138) (xy 99.752911 -239.013433)
			(xy 99.75342 -239.0394) (xy 99.752911 -239.065367) (xy 100.032821 -239.065367) (xy 100.032821 -239.013433)
			(xy 100.040946 -238.962138) (xy 100.056994 -238.912745) (xy 100.080572 -238.866471) (xy 100.111098 -238.824455)
			(xy 100.147821 -238.787732) (xy 100.189837 -238.757206) (xy 100.236111 -238.733628) (xy 100.285504 -238.71758)
			(xy 100.336799 -238.709455) (xy 100.388733 -238.709455) (xy 100.440028 -238.71758) (xy 100.489421 -238.733628)
			(xy 100.535695 -238.757206) (xy 100.577711 -238.787732) (xy 100.614434 -238.824455) (xy 100.64496 -238.866471)
			(xy 100.668538 -238.912745) (xy 100.684586 -238.962138) (xy 100.692711 -239.013433) (xy 100.69322 -239.0394)
			(xy 100.692711 -239.065367) (xy 100.972367 -239.065367) (xy 100.972367 -239.013433) (xy 100.980492 -238.962138)
			(xy 100.99654 -238.912745) (xy 101.020118 -238.866471) (xy 101.050644 -238.824455) (xy 101.087367 -238.787732)
			(xy 101.129383 -238.757206) (xy 101.175657 -238.733628) (xy 101.22505 -238.71758) (xy 101.276345 -238.709455)
			(xy 101.328279 -238.709455) (xy 101.379574 -238.71758) (xy 101.428967 -238.733628) (xy 101.475241 -238.757206)
			(xy 101.517257 -238.787732) (xy 101.55398 -238.824455) (xy 101.584506 -238.866471) (xy 101.608084 -238.912745)
			(xy 101.624132 -238.962138) (xy 101.632257 -239.013433) (xy 101.632766 -239.0394) (xy 101.632257 -239.065367)
			(xy 101.912421 -239.065367) (xy 101.912421 -239.013433) (xy 101.920546 -238.962138) (xy 101.936594 -238.912745)
			(xy 101.960172 -238.866471) (xy 101.990698 -238.824455) (xy 102.027421 -238.787732) (xy 102.069437 -238.757206)
			(xy 102.115711 -238.733628) (xy 102.165104 -238.71758) (xy 102.216399 -238.709455) (xy 102.268333 -238.709455)
			(xy 102.319628 -238.71758) (xy 102.369021 -238.733628) (xy 102.415295 -238.757206) (xy 102.457311 -238.787732)
			(xy 102.494034 -238.824455) (xy 102.52456 -238.866471) (xy 102.548138 -238.912745) (xy 102.564186 -238.962138)
			(xy 102.572311 -239.013433) (xy 102.57282 -239.0394) (xy 102.572311 -239.065367) (xy 102.564186 -239.116662)
			(xy 102.548138 -239.166055) (xy 102.52456 -239.212329) (xy 102.494034 -239.254345) (xy 102.457311 -239.291068)
			(xy 102.419043 -239.318871) (xy 104.849621 -239.318871) (xy 104.849621 -239.266929) (xy 104.857747 -239.215626)
			(xy 104.873798 -239.166227) (xy 104.897381 -239.119947) (xy 104.927912 -239.077925) (xy 104.964642 -239.041198)
			(xy 105.006665 -239.010669) (xy 105.052947 -238.98709) (xy 105.102348 -238.971042) (xy 105.153651 -238.962919)
			(xy 105.179622 -238.962438) (xy 105.179876 -238.962438) (xy 105.204401 -238.96292) (xy 105.252912 -238.970178)
			(xy 105.299818 -238.984523) (xy 105.34409 -239.005641) (xy 105.384757 -239.033068) (xy 105.403142 -239.049306)
			(xy 105.414631 -239.059109) (xy 105.441868 -239.072123) (xy 105.471722 -239.076591) (xy 105.501576 -239.072123)
			(xy 105.528813 -239.059109) (xy 105.540302 -239.049306) (xy 105.558687 -239.033025) (xy 105.599397 -239.00556)
			(xy 105.643725 -238.984426) (xy 105.690694 -238.970088) (xy 105.739267 -238.962864) (xy 105.763822 -238.962438)
			(xy 105.788373 -238.962903) (xy 105.836938 -238.970139) (xy 105.8839 -238.984477) (xy 105.928224 -239.005603)
			(xy 105.968937 -239.033052) (xy 105.987342 -239.049306) (xy 105.998831 -239.059109) (xy 106.026068 -239.072123)
			(xy 106.055922 -239.076591) (xy 106.085776 -239.072123) (xy 106.113013 -239.059109) (xy 106.124502 -239.049306)
			(xy 106.142868 -239.033041) (xy 106.183531 -239.005598) (xy 106.227806 -238.984472) (xy 106.27472 -238.970128)
			(xy 106.323239 -238.962881) (xy 106.347768 -238.962438) (xy 106.348022 -238.962438) (xy 106.373987 -238.962965)
			(xy 106.425279 -238.971092) (xy 106.474667 -238.987142) (xy 106.520937 -239.01072) (xy 106.562949 -239.041246)
			(xy 106.599668 -239.077968) (xy 106.630191 -239.119982) (xy 106.653767 -239.166253) (xy 106.669813 -239.215643)
			(xy 106.677937 -239.266935) (xy 106.677937 -239.318865) (xy 106.669813 -239.370157) (xy 106.653767 -239.419547)
			(xy 106.630191 -239.465818) (xy 106.599668 -239.507832) (xy 106.562949 -239.544554) (xy 106.520937 -239.57508)
			(xy 106.474667 -239.598658) (xy 106.425279 -239.614708) (xy 106.373987 -239.622835) (xy 106.348022 -239.623346)
			(xy 106.347768 -239.623346) (xy 106.323241 -239.622902) (xy 106.274729 -239.615635) (xy 106.227822 -239.601281)
			(xy 106.18355 -239.580155) (xy 106.142886 -239.55272) (xy 106.124502 -239.536478) (xy 106.113013 -239.526675)
			(xy 106.085776 -239.513661) (xy 106.055922 -239.509193) (xy 106.026068 -239.513661) (xy 105.998831 -239.526675)
			(xy 105.987342 -239.536478) (xy 105.968937 -239.552735) (xy 105.928233 -239.580204) (xy 105.88391 -239.601344)
			(xy 105.836946 -239.615686) (xy 105.788375 -239.622917) (xy 105.763822 -239.623346) (xy 105.73927 -239.622919)
			(xy 105.690702 -239.615674) (xy 105.64374 -239.601327) (xy 105.599417 -239.580193) (xy 105.558706 -239.552736)
			(xy 105.540302 -239.536478) (xy 105.528813 -239.526675) (xy 105.501576 -239.513661) (xy 105.471722 -239.509193)
			(xy 105.441868 -239.513661) (xy 105.414631 -239.526675) (xy 105.403142 -239.536478) (xy 105.384757 -239.552719)
			(xy 105.344099 -239.580166) (xy 105.299828 -239.601297) (xy 105.252919 -239.615647) (xy 105.204403 -239.6229)
			(xy 105.179876 -239.623346) (xy 105.179622 -239.623346) (xy 105.153651 -239.622881) (xy 105.102348 -239.614758)
			(xy 105.052947 -239.59871) (xy 105.006665 -239.575131) (xy 104.964642 -239.544602) (xy 104.927912 -239.507875)
			(xy 104.897381 -239.465853) (xy 104.873798 -239.419573) (xy 104.857747 -239.370174) (xy 104.849621 -239.318871)
			(xy 102.419043 -239.318871) (xy 102.415295 -239.321594) (xy 102.369021 -239.345172) (xy 102.319628 -239.36122)
			(xy 102.268333 -239.369345) (xy 102.216399 -239.369345) (xy 102.165104 -239.36122) (xy 102.115711 -239.345172)
			(xy 102.069437 -239.321594) (xy 102.027421 -239.291068) (xy 101.990698 -239.254345) (xy 101.960172 -239.212329)
			(xy 101.936594 -239.166055) (xy 101.920546 -239.116662) (xy 101.912421 -239.065367) (xy 101.632257 -239.065367)
			(xy 101.624132 -239.116662) (xy 101.608084 -239.166055) (xy 101.584506 -239.212329) (xy 101.55398 -239.254345)
			(xy 101.517257 -239.291068) (xy 101.475241 -239.321594) (xy 101.428967 -239.345172) (xy 101.379574 -239.36122)
			(xy 101.328279 -239.369345) (xy 101.276345 -239.369345) (xy 101.22505 -239.36122) (xy 101.175657 -239.345172)
			(xy 101.129383 -239.321594) (xy 101.087367 -239.291068) (xy 101.050644 -239.254345) (xy 101.020118 -239.212329)
			(xy 100.99654 -239.166055) (xy 100.980492 -239.116662) (xy 100.972367 -239.065367) (xy 100.692711 -239.065367)
			(xy 100.684586 -239.116662) (xy 100.668538 -239.166055) (xy 100.64496 -239.212329) (xy 100.614434 -239.254345)
			(xy 100.577711 -239.291068) (xy 100.535695 -239.321594) (xy 100.489421 -239.345172) (xy 100.440028 -239.36122)
			(xy 100.388733 -239.369345) (xy 100.336799 -239.369345) (xy 100.285504 -239.36122) (xy 100.236111 -239.345172)
			(xy 100.189837 -239.321594) (xy 100.147821 -239.291068) (xy 100.111098 -239.254345) (xy 100.080572 -239.212329)
			(xy 100.056994 -239.166055) (xy 100.040946 -239.116662) (xy 100.032821 -239.065367) (xy 99.752911 -239.065367)
			(xy 99.744786 -239.116662) (xy 99.728738 -239.166055) (xy 99.70516 -239.212329) (xy 99.674634 -239.254345)
			(xy 99.637911 -239.291068) (xy 99.595895 -239.321594) (xy 99.549621 -239.345172) (xy 99.500228 -239.36122)
			(xy 99.448933 -239.369345) (xy 99.396999 -239.369345) (xy 99.345704 -239.36122) (xy 99.296311 -239.345172)
			(xy 99.250037 -239.321594) (xy 99.208021 -239.291068) (xy 99.171298 -239.254345) (xy 99.140772 -239.212329)
			(xy 99.117194 -239.166055) (xy 99.101146 -239.116662) (xy 99.093021 -239.065367) (xy 98.813111 -239.065367)
			(xy 98.804986 -239.116662) (xy 98.788938 -239.166055) (xy 98.76536 -239.212329) (xy 98.734834 -239.254345)
			(xy 98.698111 -239.291068) (xy 98.656095 -239.321594) (xy 98.609821 -239.345172) (xy 98.560428 -239.36122)
			(xy 98.509133 -239.369345) (xy 98.457199 -239.369345) (xy 98.405904 -239.36122) (xy 98.356511 -239.345172)
			(xy 98.310237 -239.321594) (xy 98.268221 -239.291068) (xy 98.231498 -239.254345) (xy 98.200972 -239.212329)
			(xy 98.177394 -239.166055) (xy 98.161346 -239.116662) (xy 98.153221 -239.065367) (xy 97.873311 -239.065367)
			(xy 97.865186 -239.116662) (xy 97.849138 -239.166055) (xy 97.82556 -239.212329) (xy 97.795034 -239.254345)
			(xy 97.758311 -239.291068) (xy 97.716295 -239.321594) (xy 97.670021 -239.345172) (xy 97.620628 -239.36122)
			(xy 97.569333 -239.369345) (xy 97.517399 -239.369345) (xy 97.466104 -239.36122) (xy 97.416711 -239.345172)
			(xy 97.370437 -239.321594) (xy 97.328421 -239.291068) (xy 97.291698 -239.254345) (xy 97.261172 -239.212329)
			(xy 97.237594 -239.166055) (xy 97.221546 -239.116662) (xy 97.213421 -239.065367) (xy 96.933511 -239.065367)
			(xy 96.925386 -239.116662) (xy 96.909338 -239.166055) (xy 96.88576 -239.212329) (xy 96.855234 -239.254345)
			(xy 96.818511 -239.291068) (xy 96.776495 -239.321594) (xy 96.730221 -239.345172) (xy 96.680828 -239.36122)
			(xy 96.629533 -239.369345) (xy 96.577599 -239.369345) (xy 96.526304 -239.36122) (xy 96.476911 -239.345172)
			(xy 96.430637 -239.321594) (xy 96.388621 -239.291068) (xy 96.351898 -239.254345) (xy 96.321372 -239.212329)
			(xy 96.297794 -239.166055) (xy 96.281746 -239.116662) (xy 96.273621 -239.065367) (xy 95.993711 -239.065367)
			(xy 95.985586 -239.116662) (xy 95.969538 -239.166055) (xy 95.94596 -239.212329) (xy 95.915434 -239.254345)
			(xy 95.878711 -239.291068) (xy 95.836695 -239.321594) (xy 95.790421 -239.345172) (xy 95.741028 -239.36122)
			(xy 95.689733 -239.369345) (xy 95.637799 -239.369345) (xy 95.586504 -239.36122) (xy 95.537111 -239.345172)
			(xy 95.490837 -239.321594) (xy 95.448821 -239.291068) (xy 95.412098 -239.254345) (xy 95.381572 -239.212329)
			(xy 95.357994 -239.166055) (xy 95.341946 -239.116662) (xy 95.333821 -239.065367) (xy 95.053657 -239.065367)
			(xy 95.045532 -239.116662) (xy 95.029484 -239.166055) (xy 95.005906 -239.212329) (xy 94.97538 -239.254345)
			(xy 94.938657 -239.291068) (xy 94.896641 -239.321594) (xy 94.850367 -239.345172) (xy 94.800974 -239.36122)
			(xy 94.749679 -239.369345) (xy 94.697745 -239.369345) (xy 94.64645 -239.36122) (xy 94.597057 -239.345172)
			(xy 94.550783 -239.321594) (xy 94.508767 -239.291068) (xy 94.472044 -239.254345) (xy 94.441518 -239.212329)
			(xy 94.41794 -239.166055) (xy 94.401892 -239.116662) (xy 94.393767 -239.065367) (xy 94.114111 -239.065367)
			(xy 94.105986 -239.116662) (xy 94.089938 -239.166055) (xy 94.06636 -239.212329) (xy 94.035834 -239.254345)
			(xy 93.999111 -239.291068) (xy 93.957095 -239.321594) (xy 93.910821 -239.345172) (xy 93.861428 -239.36122)
			(xy 93.810133 -239.369345) (xy 93.758199 -239.369345) (xy 93.706904 -239.36122) (xy 93.657511 -239.345172)
			(xy 93.611237 -239.321594) (xy 93.569221 -239.291068) (xy 93.532498 -239.254345) (xy 93.501972 -239.212329)
			(xy 93.478394 -239.166055) (xy 93.462346 -239.116662) (xy 93.454221 -239.065367) (xy 93.174311 -239.065367)
			(xy 93.166186 -239.116662) (xy 93.150138 -239.166055) (xy 93.12656 -239.212329) (xy 93.096034 -239.254345)
			(xy 93.059311 -239.291068) (xy 93.017295 -239.321594) (xy 92.971021 -239.345172) (xy 92.921628 -239.36122)
			(xy 92.870333 -239.369345) (xy 92.818399 -239.369345) (xy 92.767104 -239.36122) (xy 92.717711 -239.345172)
			(xy 92.671437 -239.321594) (xy 92.629421 -239.291068) (xy 92.592698 -239.254345) (xy 92.562172 -239.212329)
			(xy 92.538594 -239.166055) (xy 92.522546 -239.116662) (xy 92.514421 -239.065367) (xy 92.234825 -239.065367)
			(xy 92.234825 -239.065391) (xy 92.226692 -239.116733) (xy 92.210628 -239.16617) (xy 92.187027 -239.212486)
			(xy 92.156471 -239.254539) (xy 92.119713 -239.291294) (xy 92.077657 -239.321845) (xy 92.031339 -239.345441)
			(xy 91.9819 -239.3615) (xy 91.930557 -239.369627) (xy 91.904566 -239.370108) (xy 91.877643 -239.369577)
			(xy 91.824507 -239.360856) (xy 91.773483 -239.34365) (xy 91.725918 -239.318411) (xy 91.70416 -239.302544)
			(xy 91.69781 -239.297718) (xy 91.66733 -239.286796) (xy 91.661602 -239.286912) (xy 91.65044 -239.289487)
			(xy 91.645232 -239.291876) (xy 91.604846 -239.311434) (xy 91.56192 -239.332008) (xy 91.554125 -239.336567)
			(xy 91.542165 -239.350079) (xy 91.535711 -239.366931) (xy 91.53525 -239.37595) (xy 91.53525 -239.503712)
			(xy 91.565222 -239.549178) (xy 91.577922 -239.555274) (xy 91.601599 -239.56724) (xy 91.645124 -239.597564)
			(xy 91.683249 -239.63445) (xy 91.714993 -239.67695) (xy 91.739543 -239.723975) (xy 91.756267 -239.774317)
			(xy 91.764738 -239.826683) (xy 91.764737 -239.879183) (xy 92.044267 -239.879183) (xy 92.044267 -239.827249)
			(xy 92.052392 -239.775954) (xy 92.06844 -239.726561) (xy 92.092018 -239.680287) (xy 92.122544 -239.638271)
			(xy 92.159267 -239.601548) (xy 92.201283 -239.571022) (xy 92.247557 -239.547444) (xy 92.29695 -239.531396)
			(xy 92.348245 -239.523271) (xy 92.400179 -239.523271) (xy 92.451474 -239.531396) (xy 92.500867 -239.547444)
			(xy 92.547141 -239.571022) (xy 92.589157 -239.601548) (xy 92.62588 -239.638271) (xy 92.656406 -239.680287)
			(xy 92.679984 -239.726561) (xy 92.696032 -239.775954) (xy 92.704157 -239.827249) (xy 92.704666 -239.853216)
			(xy 92.704157 -239.879183) (xy 92.984067 -239.879183) (xy 92.984067 -239.827249) (xy 92.992192 -239.775954)
			(xy 93.00824 -239.726561) (xy 93.031818 -239.680287) (xy 93.062344 -239.638271) (xy 93.099067 -239.601548)
			(xy 93.141083 -239.571022) (xy 93.187357 -239.547444) (xy 93.23675 -239.531396) (xy 93.288045 -239.523271)
			(xy 93.339979 -239.523271) (xy 93.391274 -239.531396) (xy 93.440667 -239.547444) (xy 93.486941 -239.571022)
			(xy 93.528957 -239.601548) (xy 93.56568 -239.638271) (xy 93.596206 -239.680287) (xy 93.619784 -239.726561)
			(xy 93.635832 -239.775954) (xy 93.643957 -239.827249) (xy 93.644466 -239.853216) (xy 93.643957 -239.879183)
			(xy 93.923867 -239.879183) (xy 93.923867 -239.827249) (xy 93.931992 -239.775954) (xy 93.94804 -239.726561)
			(xy 93.971618 -239.680287) (xy 94.002144 -239.638271) (xy 94.038867 -239.601548) (xy 94.080883 -239.571022)
			(xy 94.127157 -239.547444) (xy 94.17655 -239.531396) (xy 94.227845 -239.523271) (xy 94.279779 -239.523271)
			(xy 94.331074 -239.531396) (xy 94.380467 -239.547444) (xy 94.426741 -239.571022) (xy 94.468757 -239.601548)
			(xy 94.50548 -239.638271) (xy 94.536006 -239.680287) (xy 94.559584 -239.726561) (xy 94.575632 -239.775954)
			(xy 94.583757 -239.827249) (xy 94.584266 -239.853216) (xy 94.583757 -239.879183) (xy 94.863667 -239.879183)
			(xy 94.863667 -239.827249) (xy 94.871792 -239.775954) (xy 94.88784 -239.726561) (xy 94.911418 -239.680287)
			(xy 94.941944 -239.638271) (xy 94.978667 -239.601548) (xy 95.020683 -239.571022) (xy 95.066957 -239.547444)
			(xy 95.11635 -239.531396) (xy 95.167645 -239.523271) (xy 95.219579 -239.523271) (xy 95.270874 -239.531396)
			(xy 95.320267 -239.547444) (xy 95.366541 -239.571022) (xy 95.408557 -239.601548) (xy 95.44528 -239.638271)
			(xy 95.475806 -239.680287) (xy 95.499384 -239.726561) (xy 95.515432 -239.775954) (xy 95.523557 -239.827249)
			(xy 95.524066 -239.853216) (xy 95.523557 -239.879183) (xy 95.803467 -239.879183) (xy 95.803467 -239.827249)
			(xy 95.811592 -239.775954) (xy 95.82764 -239.726561) (xy 95.851218 -239.680287) (xy 95.881744 -239.638271)
			(xy 95.918467 -239.601548) (xy 95.960483 -239.571022) (xy 96.006757 -239.547444) (xy 96.05615 -239.531396)
			(xy 96.107445 -239.523271) (xy 96.159379 -239.523271) (xy 96.210674 -239.531396) (xy 96.260067 -239.547444)
			(xy 96.306341 -239.571022) (xy 96.348357 -239.601548) (xy 96.38508 -239.638271) (xy 96.415606 -239.680287)
			(xy 96.439184 -239.726561) (xy 96.455232 -239.775954) (xy 96.463357 -239.827249) (xy 96.463866 -239.853216)
			(xy 96.463357 -239.879183) (xy 96.743521 -239.879183) (xy 96.743521 -239.827249) (xy 96.751646 -239.775954)
			(xy 96.767694 -239.726561) (xy 96.791272 -239.680287) (xy 96.821798 -239.638271) (xy 96.858521 -239.601548)
			(xy 96.900537 -239.571022) (xy 96.946811 -239.547444) (xy 96.996204 -239.531396) (xy 97.047499 -239.523271)
			(xy 97.099433 -239.523271) (xy 97.150728 -239.531396) (xy 97.200121 -239.547444) (xy 97.246395 -239.571022)
			(xy 97.288411 -239.601548) (xy 97.325134 -239.638271) (xy 97.35566 -239.680287) (xy 97.379238 -239.726561)
			(xy 97.395286 -239.775954) (xy 97.403411 -239.827249) (xy 97.40392 -239.853216) (xy 97.403411 -239.879183)
			(xy 97.683067 -239.879183) (xy 97.683067 -239.827249) (xy 97.691192 -239.775954) (xy 97.70724 -239.726561)
			(xy 97.730818 -239.680287) (xy 97.761344 -239.638271) (xy 97.798067 -239.601548) (xy 97.840083 -239.571022)
			(xy 97.886357 -239.547444) (xy 97.93575 -239.531396) (xy 97.987045 -239.523271) (xy 98.038979 -239.523271)
			(xy 98.090274 -239.531396) (xy 98.139667 -239.547444) (xy 98.185941 -239.571022) (xy 98.227957 -239.601548)
			(xy 98.26468 -239.638271) (xy 98.295206 -239.680287) (xy 98.318784 -239.726561) (xy 98.334832 -239.775954)
			(xy 98.342957 -239.827249) (xy 98.343466 -239.853216) (xy 98.342957 -239.879183) (xy 98.622867 -239.879183)
			(xy 98.622867 -239.827249) (xy 98.630992 -239.775954) (xy 98.64704 -239.726561) (xy 98.670618 -239.680287)
			(xy 98.701144 -239.638271) (xy 98.737867 -239.601548) (xy 98.779883 -239.571022) (xy 98.826157 -239.547444)
			(xy 98.87555 -239.531396) (xy 98.926845 -239.523271) (xy 98.978779 -239.523271) (xy 99.030074 -239.531396)
			(xy 99.079467 -239.547444) (xy 99.125741 -239.571022) (xy 99.167757 -239.601548) (xy 99.20448 -239.638271)
			(xy 99.235006 -239.680287) (xy 99.258584 -239.726561) (xy 99.274632 -239.775954) (xy 99.282757 -239.827249)
			(xy 99.283266 -239.853216) (xy 99.282757 -239.879183) (xy 99.562667 -239.879183) (xy 99.562667 -239.827249)
			(xy 99.570792 -239.775954) (xy 99.58684 -239.726561) (xy 99.610418 -239.680287) (xy 99.640944 -239.638271)
			(xy 99.677667 -239.601548) (xy 99.719683 -239.571022) (xy 99.765957 -239.547444) (xy 99.81535 -239.531396)
			(xy 99.866645 -239.523271) (xy 99.918579 -239.523271) (xy 99.969874 -239.531396) (xy 100.019267 -239.547444)
			(xy 100.065541 -239.571022) (xy 100.107557 -239.601548) (xy 100.14428 -239.638271) (xy 100.174806 -239.680287)
			(xy 100.198384 -239.726561) (xy 100.214432 -239.775954) (xy 100.222557 -239.827249) (xy 100.223066 -239.853216)
			(xy 100.222557 -239.879183) (xy 100.502467 -239.879183) (xy 100.502467 -239.827249) (xy 100.510592 -239.775954)
			(xy 100.52664 -239.726561) (xy 100.550218 -239.680287) (xy 100.580744 -239.638271) (xy 100.617467 -239.601548)
			(xy 100.659483 -239.571022) (xy 100.705757 -239.547444) (xy 100.75515 -239.531396) (xy 100.806445 -239.523271)
			(xy 100.858379 -239.523271) (xy 100.909674 -239.531396) (xy 100.959067 -239.547444) (xy 101.005341 -239.571022)
			(xy 101.047357 -239.601548) (xy 101.08408 -239.638271) (xy 101.114606 -239.680287) (xy 101.138184 -239.726561)
			(xy 101.154232 -239.775954) (xy 101.162357 -239.827249) (xy 101.162866 -239.853216) (xy 101.162357 -239.879183)
			(xy 101.442521 -239.879183) (xy 101.442521 -239.827249) (xy 101.450646 -239.775954) (xy 101.466694 -239.726561)
			(xy 101.490272 -239.680287) (xy 101.520798 -239.638271) (xy 101.557521 -239.601548) (xy 101.599537 -239.571022)
			(xy 101.645811 -239.547444) (xy 101.695204 -239.531396) (xy 101.746499 -239.523271) (xy 101.798433 -239.523271)
			(xy 101.849728 -239.531396) (xy 101.899121 -239.547444) (xy 101.945395 -239.571022) (xy 101.987411 -239.601548)
			(xy 102.024134 -239.638271) (xy 102.05466 -239.680287) (xy 102.078238 -239.726561) (xy 102.094286 -239.775954)
			(xy 102.102411 -239.827249) (xy 102.102552 -239.83442) (xy 108.349796 -239.83442) (xy 108.349796 -239.834166)
			(xy 108.350228 -239.809639) (xy 108.357496 -239.761125) (xy 108.371852 -239.714218) (xy 108.392981 -239.669946)
			(xy 108.42042 -239.629283) (xy 108.436664 -239.6109) (xy 108.446449 -239.599396) (xy 108.459466 -239.572165)
			(xy 108.463939 -239.542315) (xy 108.459475 -239.512464) (xy 108.446466 -239.485229) (xy 108.436664 -239.47374)
			(xy 108.420428 -239.455349) (xy 108.392979 -239.414694) (xy 108.371846 -239.370425) (xy 108.357495 -239.323517)
			(xy 108.350242 -239.275001) (xy 108.349796 -239.250474) (xy 108.349796 -239.25022) (xy 108.350305 -239.224253)
			(xy 108.35843 -239.172958) (xy 108.374478 -239.123565) (xy 108.398056 -239.077291) (xy 108.428582 -239.035275)
			(xy 108.465305 -238.998552) (xy 108.507321 -238.968026) (xy 108.553595 -238.944448) (xy 108.602988 -238.9284)
			(xy 108.654283 -238.920275) (xy 108.706217 -238.920275) (xy 108.757512 -238.9284) (xy 108.806905 -238.944448)
			(xy 108.853179 -238.968026) (xy 108.895195 -238.998552) (xy 108.931918 -239.035275) (xy 108.953965 -239.065621)
			(xy 109.431075 -239.065621) (xy 109.431075 -239.013687) (xy 109.4392 -238.962392) (xy 109.455248 -238.912999)
			(xy 109.478826 -238.866725) (xy 109.509352 -238.824709) (xy 109.546075 -238.787986) (xy 109.588091 -238.75746)
			(xy 109.634365 -238.733882) (xy 109.683758 -238.717834) (xy 109.735053 -238.709709) (xy 109.786987 -238.709709)
			(xy 109.838282 -238.717834) (xy 109.887675 -238.733882) (xy 109.933949 -238.75746) (xy 109.975965 -238.787986)
			(xy 110.012688 -238.824709) (xy 110.043214 -238.866725) (xy 110.066792 -238.912999) (xy 110.08284 -238.962392)
			(xy 110.090965 -239.013687) (xy 110.091474 -239.039654) (xy 110.090965 -239.065621) (xy 110.370875 -239.065621)
			(xy 110.370875 -239.013687) (xy 110.379 -238.962392) (xy 110.395048 -238.912999) (xy 110.418626 -238.866725)
			(xy 110.449152 -238.824709) (xy 110.485875 -238.787986) (xy 110.527891 -238.75746) (xy 110.574165 -238.733882)
			(xy 110.623558 -238.717834) (xy 110.674853 -238.709709) (xy 110.726787 -238.709709) (xy 110.778082 -238.717834)
			(xy 110.827475 -238.733882) (xy 110.873749 -238.75746) (xy 110.915765 -238.787986) (xy 110.952488 -238.824709)
			(xy 110.983014 -238.866725) (xy 111.006592 -238.912999) (xy 111.02264 -238.962392) (xy 111.030765 -239.013687)
			(xy 111.031274 -239.039654) (xy 111.030765 -239.065621) (xy 111.310675 -239.065621) (xy 111.310675 -239.013687)
			(xy 111.3188 -238.962392) (xy 111.334848 -238.912999) (xy 111.358426 -238.866725) (xy 111.388952 -238.824709)
			(xy 111.425675 -238.787986) (xy 111.467691 -238.75746) (xy 111.513965 -238.733882) (xy 111.563358 -238.717834)
			(xy 111.614653 -238.709709) (xy 111.666587 -238.709709) (xy 111.717882 -238.717834) (xy 111.767275 -238.733882)
			(xy 111.813549 -238.75746) (xy 111.855565 -238.787986) (xy 111.892288 -238.824709) (xy 111.922814 -238.866725)
			(xy 111.946392 -238.912999) (xy 111.96244 -238.962392) (xy 111.970565 -239.013687) (xy 111.971074 -239.039654)
			(xy 111.970565 -239.065621) (xy 112.250475 -239.065621) (xy 112.250475 -239.013687) (xy 112.2586 -238.962392)
			(xy 112.274648 -238.912999) (xy 112.298226 -238.866725) (xy 112.328752 -238.824709) (xy 112.365475 -238.787986)
			(xy 112.407491 -238.75746) (xy 112.453765 -238.733882) (xy 112.503158 -238.717834) (xy 112.554453 -238.709709)
			(xy 112.606387 -238.709709) (xy 112.657682 -238.717834) (xy 112.707075 -238.733882) (xy 112.753349 -238.75746)
			(xy 112.795365 -238.787986) (xy 112.832088 -238.824709) (xy 112.862614 -238.866725) (xy 112.886192 -238.912999)
			(xy 112.90224 -238.962392) (xy 112.910365 -239.013687) (xy 112.910874 -239.039654) (xy 112.910365 -239.065621)
			(xy 113.190021 -239.065621) (xy 113.190021 -239.013687) (xy 113.198146 -238.962392) (xy 113.214194 -238.912999)
			(xy 113.237772 -238.866725) (xy 113.268298 -238.824709) (xy 113.305021 -238.787986) (xy 113.347037 -238.75746)
			(xy 113.393311 -238.733882) (xy 113.442704 -238.717834) (xy 113.493999 -238.709709) (xy 113.545933 -238.709709)
			(xy 113.597228 -238.717834) (xy 113.646621 -238.733882) (xy 113.692895 -238.75746) (xy 113.734911 -238.787986)
			(xy 113.771634 -238.824709) (xy 113.80216 -238.866725) (xy 113.825738 -238.912999) (xy 113.841786 -238.962392)
			(xy 113.849911 -239.013687) (xy 113.85042 -239.039654) (xy 113.849911 -239.065621) (xy 114.130075 -239.065621)
			(xy 114.130075 -239.013687) (xy 114.1382 -238.962392) (xy 114.154248 -238.912999) (xy 114.177826 -238.866725)
			(xy 114.208352 -238.824709) (xy 114.245075 -238.787986) (xy 114.287091 -238.75746) (xy 114.333365 -238.733882)
			(xy 114.382758 -238.717834) (xy 114.434053 -238.709709) (xy 114.485987 -238.709709) (xy 114.537282 -238.717834)
			(xy 114.586675 -238.733882) (xy 114.632949 -238.75746) (xy 114.674965 -238.787986) (xy 114.711688 -238.824709)
			(xy 114.742214 -238.866725) (xy 114.765792 -238.912999) (xy 114.78184 -238.962392) (xy 114.789965 -239.013687)
			(xy 114.790474 -239.039654) (xy 114.789965 -239.065621) (xy 114.78184 -239.116916) (xy 114.765792 -239.166309)
			(xy 114.742214 -239.212583) (xy 114.711688 -239.254599) (xy 114.674965 -239.291322) (xy 114.632949 -239.321848)
			(xy 114.586675 -239.345426) (xy 114.537282 -239.361474) (xy 114.485987 -239.369599) (xy 114.434053 -239.369599)
			(xy 114.382758 -239.361474) (xy 114.333365 -239.345426) (xy 114.287091 -239.321848) (xy 114.245075 -239.291322)
			(xy 114.208352 -239.254599) (xy 114.177826 -239.212583) (xy 114.154248 -239.166309) (xy 114.1382 -239.116916)
			(xy 114.130075 -239.065621) (xy 113.849911 -239.065621) (xy 113.841786 -239.116916) (xy 113.825738 -239.166309)
			(xy 113.80216 -239.212583) (xy 113.771634 -239.254599) (xy 113.734911 -239.291322) (xy 113.692895 -239.321848)
			(xy 113.646621 -239.345426) (xy 113.597228 -239.361474) (xy 113.545933 -239.369599) (xy 113.493999 -239.369599)
			(xy 113.442704 -239.361474) (xy 113.393311 -239.345426) (xy 113.347037 -239.321848) (xy 113.305021 -239.291322)
			(xy 113.268298 -239.254599) (xy 113.237772 -239.212583) (xy 113.214194 -239.166309) (xy 113.198146 -239.116916)
			(xy 113.190021 -239.065621) (xy 112.910365 -239.065621) (xy 112.90224 -239.116916) (xy 112.886192 -239.166309)
			(xy 112.862614 -239.212583) (xy 112.832088 -239.254599) (xy 112.795365 -239.291322) (xy 112.753349 -239.321848)
			(xy 112.707075 -239.345426) (xy 112.657682 -239.361474) (xy 112.606387 -239.369599) (xy 112.554453 -239.369599)
			(xy 112.503158 -239.361474) (xy 112.453765 -239.345426) (xy 112.407491 -239.321848) (xy 112.365475 -239.291322)
			(xy 112.328752 -239.254599) (xy 112.298226 -239.212583) (xy 112.274648 -239.166309) (xy 112.2586 -239.116916)
			(xy 112.250475 -239.065621) (xy 111.970565 -239.065621) (xy 111.96244 -239.116916) (xy 111.946392 -239.166309)
			(xy 111.922814 -239.212583) (xy 111.892288 -239.254599) (xy 111.855565 -239.291322) (xy 111.813549 -239.321848)
			(xy 111.767275 -239.345426) (xy 111.717882 -239.361474) (xy 111.666587 -239.369599) (xy 111.614653 -239.369599)
			(xy 111.563358 -239.361474) (xy 111.513965 -239.345426) (xy 111.467691 -239.321848) (xy 111.425675 -239.291322)
			(xy 111.388952 -239.254599) (xy 111.358426 -239.212583) (xy 111.334848 -239.166309) (xy 111.3188 -239.116916)
			(xy 111.310675 -239.065621) (xy 111.030765 -239.065621) (xy 111.02264 -239.116916) (xy 111.006592 -239.166309)
			(xy 110.983014 -239.212583) (xy 110.952488 -239.254599) (xy 110.915765 -239.291322) (xy 110.873749 -239.321848)
			(xy 110.827475 -239.345426) (xy 110.778082 -239.361474) (xy 110.726787 -239.369599) (xy 110.674853 -239.369599)
			(xy 110.623558 -239.361474) (xy 110.574165 -239.345426) (xy 110.527891 -239.321848) (xy 110.485875 -239.291322)
			(xy 110.449152 -239.254599) (xy 110.418626 -239.212583) (xy 110.395048 -239.166309) (xy 110.379 -239.116916)
			(xy 110.370875 -239.065621) (xy 110.090965 -239.065621) (xy 110.08284 -239.116916) (xy 110.066792 -239.166309)
			(xy 110.043214 -239.212583) (xy 110.012688 -239.254599) (xy 109.975965 -239.291322) (xy 109.933949 -239.321848)
			(xy 109.887675 -239.345426) (xy 109.838282 -239.361474) (xy 109.786987 -239.369599) (xy 109.735053 -239.369599)
			(xy 109.683758 -239.361474) (xy 109.634365 -239.345426) (xy 109.588091 -239.321848) (xy 109.546075 -239.291322)
			(xy 109.509352 -239.254599) (xy 109.478826 -239.212583) (xy 109.455248 -239.166309) (xy 109.4392 -239.116916)
			(xy 109.431075 -239.065621) (xy 108.953965 -239.065621) (xy 108.962444 -239.077291) (xy 108.986022 -239.123565)
			(xy 109.00207 -239.172958) (xy 109.010195 -239.224253) (xy 109.010704 -239.25022) (xy 109.010298 -239.274274)
			(xy 109.003331 -239.321876) (xy 108.989532 -239.367963) (xy 108.969194 -239.411561) (xy 108.942747 -239.451748)
			(xy 108.91075 -239.487674) (xy 108.892594 -239.503458) (xy 108.884443 -239.511034) (xy 108.875083 -239.531198)
			(xy 108.875089 -239.553428) (xy 108.884459 -239.573587) (xy 108.892594 -239.581182) (xy 108.900058 -239.587531)
			(xy 108.914289 -239.601005) (xy 108.921042 -239.608106) (xy 108.930447 -239.617579) (xy 108.953109 -239.63167)
			(xy 108.97865 -239.639403) (xy 109.005323 -239.64025) (xy 109.031303 -239.634154) (xy 109.054815 -239.621531)
			(xy 109.064806 -239.612678) (xy 109.083279 -239.595911) (xy 109.124356 -239.567602) (xy 109.169221 -239.545787)
			(xy 109.216855 -239.530964) (xy 109.266176 -239.523469) (xy 109.29112 -239.523016) (xy 109.317084 -239.523587)
			(xy 109.368372 -239.531713) (xy 109.417757 -239.547762) (xy 109.464024 -239.571338) (xy 109.506033 -239.601862)
			(xy 109.542751 -239.638582) (xy 109.573272 -239.680593) (xy 109.596846 -239.726861) (xy 109.612892 -239.776248)
			(xy 109.621015 -239.827536) (xy 109.621015 -239.879437) (xy 109.900975 -239.879437) (xy 109.900975 -239.827503)
			(xy 109.9091 -239.776208) (xy 109.925148 -239.726815) (xy 109.948726 -239.680541) (xy 109.979252 -239.638525)
			(xy 110.015975 -239.601802) (xy 110.057991 -239.571276) (xy 110.104265 -239.547698) (xy 110.153658 -239.53165)
			(xy 110.204953 -239.523525) (xy 110.256887 -239.523525) (xy 110.308182 -239.53165) (xy 110.357575 -239.547698)
			(xy 110.403849 -239.571276) (xy 110.445865 -239.601802) (xy 110.482588 -239.638525) (xy 110.513114 -239.680541)
			(xy 110.536692 -239.726815) (xy 110.55274 -239.776208) (xy 110.560865 -239.827503) (xy 110.561374 -239.85347)
			(xy 110.560865 -239.879437) (xy 110.840775 -239.879437) (xy 110.840775 -239.827503) (xy 110.8489 -239.776208)
			(xy 110.864948 -239.726815) (xy 110.888526 -239.680541) (xy 110.919052 -239.638525) (xy 110.955775 -239.601802)
			(xy 110.997791 -239.571276) (xy 111.044065 -239.547698) (xy 111.093458 -239.53165) (xy 111.144753 -239.523525)
			(xy 111.196687 -239.523525) (xy 111.247982 -239.53165) (xy 111.297375 -239.547698) (xy 111.343649 -239.571276)
			(xy 111.385665 -239.601802) (xy 111.422388 -239.638525) (xy 111.452914 -239.680541) (xy 111.476492 -239.726815)
			(xy 111.49254 -239.776208) (xy 111.500665 -239.827503) (xy 111.501174 -239.85347) (xy 111.500665 -239.879437)
			(xy 111.780575 -239.879437) (xy 111.780575 -239.827503) (xy 111.7887 -239.776208) (xy 111.804748 -239.726815)
			(xy 111.828326 -239.680541) (xy 111.858852 -239.638525) (xy 111.895575 -239.601802) (xy 111.937591 -239.571276)
			(xy 111.983865 -239.547698) (xy 112.033258 -239.53165) (xy 112.084553 -239.523525) (xy 112.136487 -239.523525)
			(xy 112.187782 -239.53165) (xy 112.237175 -239.547698) (xy 112.283449 -239.571276) (xy 112.325465 -239.601802)
			(xy 112.362188 -239.638525) (xy 112.392714 -239.680541) (xy 112.416292 -239.726815) (xy 112.43234 -239.776208)
			(xy 112.440465 -239.827503) (xy 112.440974 -239.85347) (xy 112.440465 -239.879437) (xy 112.720121 -239.879437)
			(xy 112.720121 -239.827503) (xy 112.728246 -239.776208) (xy 112.744294 -239.726815) (xy 112.767872 -239.680541)
			(xy 112.798398 -239.638525) (xy 112.835121 -239.601802) (xy 112.877137 -239.571276) (xy 112.923411 -239.547698)
			(xy 112.972804 -239.53165) (xy 113.024099 -239.523525) (xy 113.076033 -239.523525) (xy 113.127328 -239.53165)
			(xy 113.176721 -239.547698) (xy 113.222995 -239.571276) (xy 113.265011 -239.601802) (xy 113.301734 -239.638525)
			(xy 113.33226 -239.680541) (xy 113.355838 -239.726815) (xy 113.371886 -239.776208) (xy 113.380011 -239.827503)
			(xy 113.38052 -239.85347) (xy 113.380011 -239.879437) (xy 113.660175 -239.879437) (xy 113.660175 -239.827503)
			(xy 113.6683 -239.776208) (xy 113.684348 -239.726815) (xy 113.707926 -239.680541) (xy 113.738452 -239.638525)
			(xy 113.775175 -239.601802) (xy 113.817191 -239.571276) (xy 113.863465 -239.547698) (xy 113.912858 -239.53165)
			(xy 113.964153 -239.523525) (xy 114.016087 -239.523525) (xy 114.067382 -239.53165) (xy 114.116775 -239.547698)
			(xy 114.163049 -239.571276) (xy 114.205065 -239.601802) (xy 114.241788 -239.638525) (xy 114.272314 -239.680541)
			(xy 114.295892 -239.726815) (xy 114.31194 -239.776208) (xy 114.320065 -239.827503) (xy 114.320574 -239.85347)
			(xy 114.320065 -239.879437) (xy 114.314804 -239.912652) (xy 114.880136 -239.912652) (xy 114.880136 -239.912398)
			(xy 114.880603 -239.887872) (xy 114.887865 -239.839361) (xy 114.902214 -239.792454) (xy 114.923335 -239.748183)
			(xy 114.950765 -239.707517) (xy 114.967004 -239.689132) (xy 114.976852 -239.677679) (xy 114.989857 -239.650428)
			(xy 114.994315 -239.620564) (xy 114.989836 -239.590704) (xy 114.976812 -239.563462) (xy 114.967004 -239.551972)
			(xy 114.950758 -239.533557) (xy 114.923288 -239.492856) (xy 114.902147 -239.448535) (xy 114.887801 -239.401573)
			(xy 114.880567 -239.353005) (xy 114.880136 -239.328452) (xy 114.880586 -239.3039) (xy 114.887826 -239.255334)
			(xy 114.902168 -239.208373) (xy 114.923297 -239.164049) (xy 114.950749 -239.123337) (xy 114.967004 -239.104932)
			(xy 114.976852 -239.093479) (xy 114.989857 -239.066228) (xy 114.994315 -239.036364) (xy 114.989836 -239.006504)
			(xy 114.976812 -238.979262) (xy 114.967004 -238.967772) (xy 114.950774 -238.949377) (xy 114.923326 -238.908722)
			(xy 114.902193 -238.864454) (xy 114.887841 -238.817547) (xy 114.880584 -238.769033) (xy 114.880136 -238.744506)
			(xy 114.880136 -238.744252) (xy 114.880645 -238.718285) (xy 114.88877 -238.66699) (xy 114.904818 -238.617597)
			(xy 114.928396 -238.571323) (xy 114.958922 -238.529307) (xy 114.995645 -238.492584) (xy 115.037661 -238.462058)
			(xy 115.083935 -238.43848) (xy 115.133328 -238.422432) (xy 115.184623 -238.414307) (xy 115.236557 -238.414307)
			(xy 115.287852 -238.422432) (xy 115.337245 -238.43848) (xy 115.383519 -238.462058) (xy 115.425535 -238.492584)
			(xy 115.462258 -238.529307) (xy 115.492784 -238.571323) (xy 115.516362 -238.617597) (xy 115.53241 -238.66699)
			(xy 115.540535 -238.718285) (xy 115.541044 -238.744252) (xy 115.541044 -238.744506) (xy 115.540584 -238.769032)
			(xy 115.533322 -238.817544) (xy 115.518971 -238.864451) (xy 115.497848 -238.908723) (xy 115.470417 -238.949388)
			(xy 115.454176 -238.967772) (xy 115.444423 -238.9793) (xy 115.431411 -239.006524) (xy 115.426936 -239.036364)
			(xy 115.43139 -239.066208) (xy 115.444384 -239.093441) (xy 115.454176 -239.104932) (xy 115.470421 -239.123348)
			(xy 115.497892 -239.164049) (xy 115.519033 -239.208369) (xy 115.533379 -239.255331) (xy 115.540613 -239.3039)
			(xy 115.541044 -239.328452) (xy 115.54097 -239.332566) (xy 117.084363 -239.332566) (xy 117.084363 -239.280634)
			(xy 117.092487 -239.22934) (xy 117.108535 -239.17995) (xy 117.132112 -239.133677) (xy 117.162637 -239.091663)
			(xy 117.199358 -239.05494) (xy 117.241372 -239.024415) (xy 117.287644 -239.000837) (xy 117.337035 -238.984789)
			(xy 117.388328 -238.976664) (xy 117.414294 -238.976154) (xy 117.414548 -238.976154) (xy 117.439075 -238.976589)
			(xy 117.487588 -238.983858) (xy 117.534495 -238.998214) (xy 117.578766 -239.019342) (xy 117.61943 -239.046779)
			(xy 117.637814 -239.063022) (xy 117.649303 -239.072825) (xy 117.67654 -239.085839) (xy 117.706394 -239.090307)
			(xy 117.736248 -239.085839) (xy 117.763485 -239.072825) (xy 117.774974 -239.063022) (xy 117.793373 -239.046757)
			(xy 117.834079 -239.019289) (xy 117.878403 -238.998151) (xy 117.925369 -238.98381) (xy 117.97394 -238.976582)
			(xy 117.998494 -238.976154) (xy 118.023047 -238.976572) (xy 118.071615 -238.983818) (xy 118.118577 -238.998168)
			(xy 118.1629 -239.019304) (xy 118.20361 -239.046763) (xy 118.222014 -239.063022) (xy 118.233503 -239.072825)
			(xy 118.26074 -239.085839) (xy 118.290594 -239.090307) (xy 118.320448 -239.085839) (xy 118.347685 -239.072825)
			(xy 118.359174 -239.063022) (xy 118.377553 -239.046773) (xy 118.418212 -239.019327) (xy 118.462484 -238.998198)
			(xy 118.509395 -238.98385) (xy 118.557912 -238.976599) (xy 118.58244 -238.976154) (xy 118.582694 -238.976154)
			(xy 118.608664 -238.97662) (xy 118.659965 -238.984745) (xy 118.709364 -239.000795) (xy 118.755643 -239.024374)
			(xy 118.797664 -239.054904) (xy 118.808127 -239.065367) (xy 121.648221 -239.065367) (xy 121.648221 -239.013433)
			(xy 121.656346 -238.962138) (xy 121.672394 -238.912745) (xy 121.695972 -238.866471) (xy 121.726498 -238.824455)
			(xy 121.763221 -238.787732) (xy 121.805237 -238.757206) (xy 121.851511 -238.733628) (xy 121.900904 -238.71758)
			(xy 121.952199 -238.709455) (xy 122.004133 -238.709455) (xy 122.055428 -238.71758) (xy 122.104821 -238.733628)
			(xy 122.151095 -238.757206) (xy 122.193111 -238.787732) (xy 122.229834 -238.824455) (xy 122.26036 -238.866471)
			(xy 122.283938 -238.912745) (xy 122.299986 -238.962138) (xy 122.308111 -239.013433) (xy 122.30862 -239.0394)
			(xy 122.308111 -239.065367) (xy 122.587767 -239.065367) (xy 122.587767 -239.013433) (xy 122.595892 -238.962138)
			(xy 122.61194 -238.912745) (xy 122.635518 -238.866471) (xy 122.666044 -238.824455) (xy 122.702767 -238.787732)
			(xy 122.744783 -238.757206) (xy 122.791057 -238.733628) (xy 122.84045 -238.71758) (xy 122.891745 -238.709455)
			(xy 122.943679 -238.709455) (xy 122.994974 -238.71758) (xy 123.044367 -238.733628) (xy 123.090641 -238.757206)
			(xy 123.132657 -238.787732) (xy 123.16938 -238.824455) (xy 123.199906 -238.866471) (xy 123.223484 -238.912745)
			(xy 123.239532 -238.962138) (xy 123.247657 -239.013433) (xy 123.248166 -239.0394) (xy 123.247657 -239.065367)
			(xy 123.527821 -239.065367) (xy 123.527821 -239.013433) (xy 123.535946 -238.962138) (xy 123.551994 -238.912745)
			(xy 123.575572 -238.866471) (xy 123.606098 -238.824455) (xy 123.642821 -238.787732) (xy 123.684837 -238.757206)
			(xy 123.731111 -238.733628) (xy 123.780504 -238.71758) (xy 123.831799 -238.709455) (xy 123.883733 -238.709455)
			(xy 123.935028 -238.71758) (xy 123.984421 -238.733628) (xy 124.030695 -238.757206) (xy 124.072711 -238.787732)
			(xy 124.109434 -238.824455) (xy 124.13996 -238.866471) (xy 124.163538 -238.912745) (xy 124.179586 -238.962138)
			(xy 124.187711 -239.013433) (xy 124.18822 -239.0394) (xy 124.187711 -239.065367) (xy 124.467621 -239.065367)
			(xy 124.467621 -239.013433) (xy 124.475746 -238.962138) (xy 124.491794 -238.912745) (xy 124.515372 -238.866471)
			(xy 124.545898 -238.824455) (xy 124.582621 -238.787732) (xy 124.624637 -238.757206) (xy 124.670911 -238.733628)
			(xy 124.720304 -238.71758) (xy 124.771599 -238.709455) (xy 124.823533 -238.709455) (xy 124.874828 -238.71758)
			(xy 124.924221 -238.733628) (xy 124.970495 -238.757206) (xy 125.012511 -238.787732) (xy 125.049234 -238.824455)
			(xy 125.07976 -238.866471) (xy 125.103338 -238.912745) (xy 125.119386 -238.962138) (xy 125.127511 -239.013433)
			(xy 125.12802 -239.0394) (xy 125.127511 -239.065367) (xy 125.407421 -239.065367) (xy 125.407421 -239.013433)
			(xy 125.415546 -238.962138) (xy 125.431594 -238.912745) (xy 125.455172 -238.866471) (xy 125.485698 -238.824455)
			(xy 125.522421 -238.787732) (xy 125.564437 -238.757206) (xy 125.610711 -238.733628) (xy 125.660104 -238.71758)
			(xy 125.711399 -238.709455) (xy 125.763333 -238.709455) (xy 125.814628 -238.71758) (xy 125.864021 -238.733628)
			(xy 125.910295 -238.757206) (xy 125.952311 -238.787732) (xy 125.989034 -238.824455) (xy 126.01956 -238.866471)
			(xy 126.043138 -238.912745) (xy 126.059186 -238.962138) (xy 126.067311 -239.013433) (xy 126.06782 -239.0394)
			(xy 126.067311 -239.065367) (xy 126.347221 -239.065367) (xy 126.347221 -239.013433) (xy 126.355346 -238.962138)
			(xy 126.371394 -238.912745) (xy 126.394972 -238.866471) (xy 126.425498 -238.824455) (xy 126.462221 -238.787732)
			(xy 126.504237 -238.757206) (xy 126.550511 -238.733628) (xy 126.599904 -238.71758) (xy 126.651199 -238.709455)
			(xy 126.703133 -238.709455) (xy 126.754428 -238.71758) (xy 126.803821 -238.733628) (xy 126.850095 -238.757206)
			(xy 126.892111 -238.787732) (xy 126.928834 -238.824455) (xy 126.95936 -238.866471) (xy 126.982938 -238.912745)
			(xy 126.998986 -238.962138) (xy 127.007111 -239.013433) (xy 127.00762 -239.0394) (xy 127.007111 -239.065367)
			(xy 127.287021 -239.065367) (xy 127.287021 -239.013433) (xy 127.295146 -238.962138) (xy 127.311194 -238.912745)
			(xy 127.334772 -238.866471) (xy 127.365298 -238.824455) (xy 127.402021 -238.787732) (xy 127.444037 -238.757206)
			(xy 127.490311 -238.733628) (xy 127.539704 -238.71758) (xy 127.590999 -238.709455) (xy 127.642933 -238.709455)
			(xy 127.694228 -238.71758) (xy 127.743621 -238.733628) (xy 127.789895 -238.757206) (xy 127.831911 -238.787732)
			(xy 127.868634 -238.824455) (xy 127.89916 -238.866471) (xy 127.922738 -238.912745) (xy 127.938786 -238.962138)
			(xy 127.946911 -239.013433) (xy 127.94742 -239.0394) (xy 127.946911 -239.065367) (xy 128.226821 -239.065367)
			(xy 128.226821 -239.013433) (xy 128.234946 -238.962138) (xy 128.250994 -238.912745) (xy 128.274572 -238.866471)
			(xy 128.305098 -238.824455) (xy 128.341821 -238.787732) (xy 128.383837 -238.757206) (xy 128.430111 -238.733628)
			(xy 128.479504 -238.71758) (xy 128.530799 -238.709455) (xy 128.582733 -238.709455) (xy 128.634028 -238.71758)
			(xy 128.683421 -238.733628) (xy 128.729695 -238.757206) (xy 128.771711 -238.787732) (xy 128.808434 -238.824455)
			(xy 128.83896 -238.866471) (xy 128.862538 -238.912745) (xy 128.878586 -238.962138) (xy 128.886711 -239.013433)
			(xy 128.88722 -239.0394) (xy 128.886711 -239.065367) (xy 129.166367 -239.065367) (xy 129.166367 -239.013433)
			(xy 129.174492 -238.962138) (xy 129.19054 -238.912745) (xy 129.214118 -238.866471) (xy 129.244644 -238.824455)
			(xy 129.281367 -238.787732) (xy 129.323383 -238.757206) (xy 129.369657 -238.733628) (xy 129.41905 -238.71758)
			(xy 129.470345 -238.709455) (xy 129.522279 -238.709455) (xy 129.573574 -238.71758) (xy 129.622967 -238.733628)
			(xy 129.669241 -238.757206) (xy 129.711257 -238.787732) (xy 129.74798 -238.824455) (xy 129.778506 -238.866471)
			(xy 129.802084 -238.912745) (xy 129.818132 -238.962138) (xy 129.826257 -239.013433) (xy 129.826766 -239.0394)
			(xy 129.826257 -239.065367) (xy 130.106421 -239.065367) (xy 130.106421 -239.013433) (xy 130.114546 -238.962138)
			(xy 130.130594 -238.912745) (xy 130.154172 -238.866471) (xy 130.184698 -238.824455) (xy 130.221421 -238.787732)
			(xy 130.263437 -238.757206) (xy 130.309711 -238.733628) (xy 130.359104 -238.71758) (xy 130.410399 -238.709455)
			(xy 130.462333 -238.709455) (xy 130.513628 -238.71758) (xy 130.563021 -238.733628) (xy 130.609295 -238.757206)
			(xy 130.651311 -238.787732) (xy 130.688034 -238.824455) (xy 130.71856 -238.866471) (xy 130.742138 -238.912745)
			(xy 130.758186 -238.962138) (xy 130.766311 -239.013433) (xy 130.76682 -239.0394) (xy 130.766311 -239.065367)
			(xy 130.758186 -239.116662) (xy 130.742138 -239.166055) (xy 130.71856 -239.212329) (xy 130.688034 -239.254345)
			(xy 130.651311 -239.291068) (xy 130.609295 -239.321594) (xy 130.563021 -239.345172) (xy 130.513628 -239.36122)
			(xy 130.462333 -239.369345) (xy 130.410399 -239.369345) (xy 130.359104 -239.36122) (xy 130.309711 -239.345172)
			(xy 130.263437 -239.321594) (xy 130.221421 -239.291068) (xy 130.184698 -239.254345) (xy 130.154172 -239.212329)
			(xy 130.130594 -239.166055) (xy 130.114546 -239.116662) (xy 130.106421 -239.065367) (xy 129.826257 -239.065367)
			(xy 129.818132 -239.116662) (xy 129.802084 -239.166055) (xy 129.778506 -239.212329) (xy 129.74798 -239.254345)
			(xy 129.711257 -239.291068) (xy 129.669241 -239.321594) (xy 129.622967 -239.345172) (xy 129.573574 -239.36122)
			(xy 129.522279 -239.369345) (xy 129.470345 -239.369345) (xy 129.41905 -239.36122) (xy 129.369657 -239.345172)
			(xy 129.323383 -239.321594) (xy 129.281367 -239.291068) (xy 129.244644 -239.254345) (xy 129.214118 -239.212329)
			(xy 129.19054 -239.166055) (xy 129.174492 -239.116662) (xy 129.166367 -239.065367) (xy 128.886711 -239.065367)
			(xy 128.878586 -239.116662) (xy 128.862538 -239.166055) (xy 128.83896 -239.212329) (xy 128.808434 -239.254345)
			(xy 128.771711 -239.291068) (xy 128.729695 -239.321594) (xy 128.683421 -239.345172) (xy 128.634028 -239.36122)
			(xy 128.582733 -239.369345) (xy 128.530799 -239.369345) (xy 128.479504 -239.36122) (xy 128.430111 -239.345172)
			(xy 128.383837 -239.321594) (xy 128.341821 -239.291068) (xy 128.305098 -239.254345) (xy 128.274572 -239.212329)
			(xy 128.250994 -239.166055) (xy 128.234946 -239.116662) (xy 128.226821 -239.065367) (xy 127.946911 -239.065367)
			(xy 127.938786 -239.116662) (xy 127.922738 -239.166055) (xy 127.89916 -239.212329) (xy 127.868634 -239.254345)
			(xy 127.831911 -239.291068) (xy 127.789895 -239.321594) (xy 127.743621 -239.345172) (xy 127.694228 -239.36122)
			(xy 127.642933 -239.369345) (xy 127.590999 -239.369345) (xy 127.539704 -239.36122) (xy 127.490311 -239.345172)
			(xy 127.444037 -239.321594) (xy 127.402021 -239.291068) (xy 127.365298 -239.254345) (xy 127.334772 -239.212329)
			(xy 127.311194 -239.166055) (xy 127.295146 -239.116662) (xy 127.287021 -239.065367) (xy 127.007111 -239.065367)
			(xy 126.998986 -239.116662) (xy 126.982938 -239.166055) (xy 126.95936 -239.212329) (xy 126.928834 -239.254345)
			(xy 126.892111 -239.291068) (xy 126.850095 -239.321594) (xy 126.803821 -239.345172) (xy 126.754428 -239.36122)
			(xy 126.703133 -239.369345) (xy 126.651199 -239.369345) (xy 126.599904 -239.36122) (xy 126.550511 -239.345172)
			(xy 126.504237 -239.321594) (xy 126.462221 -239.291068) (xy 126.425498 -239.254345) (xy 126.394972 -239.212329)
			(xy 126.371394 -239.166055) (xy 126.355346 -239.116662) (xy 126.347221 -239.065367) (xy 126.067311 -239.065367)
			(xy 126.059186 -239.116662) (xy 126.043138 -239.166055) (xy 126.01956 -239.212329) (xy 125.989034 -239.254345)
			(xy 125.952311 -239.291068) (xy 125.910295 -239.321594) (xy 125.864021 -239.345172) (xy 125.814628 -239.36122)
			(xy 125.763333 -239.369345) (xy 125.711399 -239.369345) (xy 125.660104 -239.36122) (xy 125.610711 -239.345172)
			(xy 125.564437 -239.321594) (xy 125.522421 -239.291068) (xy 125.485698 -239.254345) (xy 125.455172 -239.212329)
			(xy 125.431594 -239.166055) (xy 125.415546 -239.116662) (xy 125.407421 -239.065367) (xy 125.127511 -239.065367)
			(xy 125.119386 -239.116662) (xy 125.103338 -239.166055) (xy 125.07976 -239.212329) (xy 125.049234 -239.254345)
			(xy 125.012511 -239.291068) (xy 124.970495 -239.321594) (xy 124.924221 -239.345172) (xy 124.874828 -239.36122)
			(xy 124.823533 -239.369345) (xy 124.771599 -239.369345) (xy 124.720304 -239.36122) (xy 124.670911 -239.345172)
			(xy 124.624637 -239.321594) (xy 124.582621 -239.291068) (xy 124.545898 -239.254345) (xy 124.515372 -239.212329)
			(xy 124.491794 -239.166055) (xy 124.475746 -239.116662) (xy 124.467621 -239.065367) (xy 124.187711 -239.065367)
			(xy 124.179586 -239.116662) (xy 124.163538 -239.166055) (xy 124.13996 -239.212329) (xy 124.109434 -239.254345)
			(xy 124.072711 -239.291068) (xy 124.030695 -239.321594) (xy 123.984421 -239.345172) (xy 123.935028 -239.36122)
			(xy 123.883733 -239.369345) (xy 123.831799 -239.369345) (xy 123.780504 -239.36122) (xy 123.731111 -239.345172)
			(xy 123.684837 -239.321594) (xy 123.642821 -239.291068) (xy 123.606098 -239.254345) (xy 123.575572 -239.212329)
			(xy 123.551994 -239.166055) (xy 123.535946 -239.116662) (xy 123.527821 -239.065367) (xy 123.247657 -239.065367)
			(xy 123.239532 -239.116662) (xy 123.223484 -239.166055) (xy 123.199906 -239.212329) (xy 123.16938 -239.254345)
			(xy 123.132657 -239.291068) (xy 123.090641 -239.321594) (xy 123.044367 -239.345172) (xy 122.994974 -239.36122)
			(xy 122.943679 -239.369345) (xy 122.891745 -239.369345) (xy 122.84045 -239.36122) (xy 122.791057 -239.345172)
			(xy 122.744783 -239.321594) (xy 122.702767 -239.291068) (xy 122.666044 -239.254345) (xy 122.635518 -239.212329)
			(xy 122.61194 -239.166055) (xy 122.595892 -239.116662) (xy 122.587767 -239.065367) (xy 122.308111 -239.065367)
			(xy 122.299986 -239.116662) (xy 122.283938 -239.166055) (xy 122.26036 -239.212329) (xy 122.229834 -239.254345)
			(xy 122.193111 -239.291068) (xy 122.151095 -239.321594) (xy 122.104821 -239.345172) (xy 122.055428 -239.36122)
			(xy 122.004133 -239.369345) (xy 121.952199 -239.369345) (xy 121.900904 -239.36122) (xy 121.851511 -239.345172)
			(xy 121.805237 -239.321594) (xy 121.763221 -239.291068) (xy 121.726498 -239.254345) (xy 121.695972 -239.212329)
			(xy 121.672394 -239.166055) (xy 121.656346 -239.116662) (xy 121.648221 -239.065367) (xy 118.808127 -239.065367)
			(xy 118.834392 -239.091631) (xy 118.864922 -239.133651) (xy 118.888503 -239.179931) (xy 118.904554 -239.229329)
			(xy 118.912679 -239.28063) (xy 118.912679 -239.33257) (xy 118.904554 -239.383871) (xy 118.888503 -239.433269)
			(xy 118.864922 -239.479549) (xy 118.834392 -239.521569) (xy 118.797664 -239.558296) (xy 118.755643 -239.588826)
			(xy 118.709364 -239.612405) (xy 118.659965 -239.628455) (xy 118.608664 -239.63658) (xy 118.582694 -239.637062)
			(xy 118.58244 -239.637062) (xy 118.557915 -239.63657) (xy 118.509405 -239.629315) (xy 118.462499 -239.614972)
			(xy 118.418226 -239.593856) (xy 118.37756 -239.566431) (xy 118.359174 -239.550194) (xy 118.347685 -239.540391)
			(xy 118.320448 -239.527377) (xy 118.290594 -239.522909) (xy 118.26074 -239.527377) (xy 118.233503 -239.540391)
			(xy 118.222014 -239.550194) (xy 118.203622 -239.566467) (xy 118.162914 -239.593933) (xy 118.118588 -239.615069)
			(xy 118.071621 -239.629409) (xy 118.023048 -239.636635) (xy 117.998494 -239.637062) (xy 117.973943 -239.636587)
			(xy 117.925378 -239.629354) (xy 117.878417 -239.615018) (xy 117.834093 -239.593894) (xy 117.79338 -239.566447)
			(xy 117.774974 -239.550194) (xy 117.763485 -239.540391) (xy 117.736248 -239.527377) (xy 117.706394 -239.522909)
			(xy 117.67654 -239.527377) (xy 117.649303 -239.540391) (xy 117.637814 -239.550194) (xy 117.619442 -239.566451)
			(xy 117.57878 -239.593895) (xy 117.534507 -239.615023) (xy 117.487594 -239.629369) (xy 117.439076 -239.636618)
			(xy 117.414548 -239.637062) (xy 117.414294 -239.637062) (xy 117.388328 -239.636536) (xy 117.337035 -239.628411)
			(xy 117.287644 -239.612363) (xy 117.241372 -239.588785) (xy 117.199358 -239.55826) (xy 117.162637 -239.521537)
			(xy 117.132112 -239.479523) (xy 117.108535 -239.43325) (xy 117.092487 -239.38386) (xy 117.084363 -239.332566)
			(xy 115.54097 -239.332566) (xy 115.540601 -239.353004) (xy 115.533361 -239.401571) (xy 115.519017 -239.448532)
			(xy 115.497886 -239.492856) (xy 115.470432 -239.533568) (xy 115.454176 -239.551972) (xy 115.444423 -239.5635)
			(xy 115.431411 -239.590724) (xy 115.426936 -239.620564) (xy 115.43139 -239.650408) (xy 115.444384 -239.677641)
			(xy 115.454176 -239.689132) (xy 115.470405 -239.707528) (xy 115.497854 -239.748183) (xy 115.518987 -239.792451)
			(xy 115.53334 -239.839357) (xy 115.540596 -239.887871) (xy 115.541044 -239.912398) (xy 115.541044 -239.912652)
			(xy 115.540535 -239.938619) (xy 115.53241 -239.989914) (xy 115.516362 -240.039307) (xy 115.492784 -240.085581)
			(xy 115.462258 -240.127597) (xy 115.425535 -240.16432) (xy 115.383519 -240.194846) (xy 115.337245 -240.218424)
			(xy 115.287852 -240.234472) (xy 115.236557 -240.242597) (xy 115.184623 -240.242597) (xy 115.133328 -240.234472)
			(xy 115.083935 -240.218424) (xy 115.037661 -240.194846) (xy 114.995645 -240.16432) (xy 114.958922 -240.127597)
			(xy 114.928396 -240.085581) (xy 114.904818 -240.039307) (xy 114.88877 -239.989914) (xy 114.880645 -239.938619)
			(xy 114.880136 -239.912652) (xy 114.314804 -239.912652) (xy 114.31194 -239.930732) (xy 114.295892 -239.980125)
			(xy 114.272314 -240.026399) (xy 114.241788 -240.068415) (xy 114.205065 -240.105138) (xy 114.163049 -240.135664)
			(xy 114.116775 -240.159242) (xy 114.067382 -240.17529) (xy 114.016087 -240.183415) (xy 113.964153 -240.183415)
			(xy 113.912858 -240.17529) (xy 113.863465 -240.159242) (xy 113.817191 -240.135664) (xy 113.775175 -240.105138)
			(xy 113.738452 -240.068415) (xy 113.707926 -240.026399) (xy 113.684348 -239.980125) (xy 113.6683 -239.930732)
			(xy 113.660175 -239.879437) (xy 113.380011 -239.879437) (xy 113.371886 -239.930732) (xy 113.355838 -239.980125)
			(xy 113.33226 -240.026399) (xy 113.301734 -240.068415) (xy 113.265011 -240.105138) (xy 113.222995 -240.135664)
			(xy 113.176721 -240.159242) (xy 113.127328 -240.17529) (xy 113.076033 -240.183415) (xy 113.024099 -240.183415)
			(xy 112.972804 -240.17529) (xy 112.923411 -240.159242) (xy 112.877137 -240.135664) (xy 112.835121 -240.105138)
			(xy 112.798398 -240.068415) (xy 112.767872 -240.026399) (xy 112.744294 -239.980125) (xy 112.728246 -239.930732)
			(xy 112.720121 -239.879437) (xy 112.440465 -239.879437) (xy 112.43234 -239.930732) (xy 112.416292 -239.980125)
			(xy 112.392714 -240.026399) (xy 112.362188 -240.068415) (xy 112.325465 -240.105138) (xy 112.283449 -240.135664)
			(xy 112.237175 -240.159242) (xy 112.187782 -240.17529) (xy 112.136487 -240.183415) (xy 112.084553 -240.183415)
			(xy 112.033258 -240.17529) (xy 111.983865 -240.159242) (xy 111.937591 -240.135664) (xy 111.895575 -240.105138)
			(xy 111.858852 -240.068415) (xy 111.828326 -240.026399) (xy 111.804748 -239.980125) (xy 111.7887 -239.930732)
			(xy 111.780575 -239.879437) (xy 111.500665 -239.879437) (xy 111.49254 -239.930732) (xy 111.476492 -239.980125)
			(xy 111.452914 -240.026399) (xy 111.422388 -240.068415) (xy 111.385665 -240.105138) (xy 111.343649 -240.135664)
			(xy 111.297375 -240.159242) (xy 111.247982 -240.17529) (xy 111.196687 -240.183415) (xy 111.144753 -240.183415)
			(xy 111.093458 -240.17529) (xy 111.044065 -240.159242) (xy 110.997791 -240.135664) (xy 110.955775 -240.105138)
			(xy 110.919052 -240.068415) (xy 110.888526 -240.026399) (xy 110.864948 -239.980125) (xy 110.8489 -239.930732)
			(xy 110.840775 -239.879437) (xy 110.560865 -239.879437) (xy 110.55274 -239.930732) (xy 110.536692 -239.980125)
			(xy 110.513114 -240.026399) (xy 110.482588 -240.068415) (xy 110.445865 -240.105138) (xy 110.403849 -240.135664)
			(xy 110.357575 -240.159242) (xy 110.308182 -240.17529) (xy 110.256887 -240.183415) (xy 110.204953 -240.183415)
			(xy 110.153658 -240.17529) (xy 110.104265 -240.159242) (xy 110.057991 -240.135664) (xy 110.015975 -240.105138)
			(xy 109.979252 -240.068415) (xy 109.948726 -240.026399) (xy 109.925148 -239.980125) (xy 109.9091 -239.930732)
			(xy 109.900975 -239.879437) (xy 109.621015 -239.879437) (xy 109.621015 -239.879464) (xy 109.612892 -239.930752)
			(xy 109.596846 -239.980139) (xy 109.573272 -240.026407) (xy 109.542751 -240.068418) (xy 109.506033 -240.105138)
			(xy 109.464024 -240.135662) (xy 109.417757 -240.159238) (xy 109.368372 -240.175287) (xy 109.317084 -240.183413)
			(xy 109.29112 -240.183924) (xy 109.264126 -240.183382) (xy 109.210856 -240.174609) (xy 109.159722 -240.157292)
			(xy 109.112082 -240.131893) (xy 109.069205 -240.099087) (xy 109.050328 -240.079784) (xy 109.040952 -240.070277)
			(xy 109.018284 -240.056177) (xy 108.992734 -240.04844) (xy 108.966052 -240.047597) (xy 108.940064 -240.053706)
			(xy 108.916552 -240.066348) (xy 108.906564 -240.075212) (xy 108.888102 -240.091991) (xy 108.847022 -240.1203)
			(xy 108.802154 -240.142112) (xy 108.754518 -240.156932) (xy 108.705194 -240.164423) (xy 108.68025 -240.164874)
			(xy 108.654282 -240.164391) (xy 108.602988 -240.15626) (xy 108.553596 -240.140206) (xy 108.507323 -240.116623)
			(xy 108.465309 -240.086094) (xy 108.428587 -240.049368) (xy 108.398061 -240.007351) (xy 108.374483 -239.961076)
			(xy 108.358433 -239.911683) (xy 108.350307 -239.860388) (xy 108.349796 -239.83442) (xy 102.102552 -239.83442)
			(xy 102.10292 -239.853216) (xy 102.102411 -239.879183) (xy 102.094286 -239.930478) (xy 102.078238 -239.979871)
			(xy 102.05466 -240.026145) (xy 102.024134 -240.068161) (xy 101.987411 -240.104884) (xy 101.945395 -240.13541)
			(xy 101.899121 -240.158988) (xy 101.849728 -240.175036) (xy 101.798433 -240.183161) (xy 101.746499 -240.183161)
			(xy 101.695204 -240.175036) (xy 101.645811 -240.158988) (xy 101.599537 -240.13541) (xy 101.557521 -240.104884)
			(xy 101.520798 -240.068161) (xy 101.490272 -240.026145) (xy 101.466694 -239.979871) (xy 101.450646 -239.930478)
			(xy 101.442521 -239.879183) (xy 101.162357 -239.879183) (xy 101.154232 -239.930478) (xy 101.138184 -239.979871)
			(xy 101.114606 -240.026145) (xy 101.08408 -240.068161) (xy 101.047357 -240.104884) (xy 101.005341 -240.13541)
			(xy 100.959067 -240.158988) (xy 100.909674 -240.175036) (xy 100.858379 -240.183161) (xy 100.806445 -240.183161)
			(xy 100.75515 -240.175036) (xy 100.705757 -240.158988) (xy 100.659483 -240.13541) (xy 100.617467 -240.104884)
			(xy 100.580744 -240.068161) (xy 100.550218 -240.026145) (xy 100.52664 -239.979871) (xy 100.510592 -239.930478)
			(xy 100.502467 -239.879183) (xy 100.222557 -239.879183) (xy 100.214432 -239.930478) (xy 100.198384 -239.979871)
			(xy 100.174806 -240.026145) (xy 100.14428 -240.068161) (xy 100.107557 -240.104884) (xy 100.065541 -240.13541)
			(xy 100.019267 -240.158988) (xy 99.969874 -240.175036) (xy 99.918579 -240.183161) (xy 99.866645 -240.183161)
			(xy 99.81535 -240.175036) (xy 99.765957 -240.158988) (xy 99.719683 -240.13541) (xy 99.677667 -240.104884)
			(xy 99.640944 -240.068161) (xy 99.610418 -240.026145) (xy 99.58684 -239.979871) (xy 99.570792 -239.930478)
			(xy 99.562667 -239.879183) (xy 99.282757 -239.879183) (xy 99.274632 -239.930478) (xy 99.258584 -239.979871)
			(xy 99.235006 -240.026145) (xy 99.20448 -240.068161) (xy 99.167757 -240.104884) (xy 99.125741 -240.13541)
			(xy 99.079467 -240.158988) (xy 99.030074 -240.175036) (xy 98.978779 -240.183161) (xy 98.926845 -240.183161)
			(xy 98.87555 -240.175036) (xy 98.826157 -240.158988) (xy 98.779883 -240.13541) (xy 98.737867 -240.104884)
			(xy 98.701144 -240.068161) (xy 98.670618 -240.026145) (xy 98.64704 -239.979871) (xy 98.630992 -239.930478)
			(xy 98.622867 -239.879183) (xy 98.342957 -239.879183) (xy 98.334832 -239.930478) (xy 98.318784 -239.979871)
			(xy 98.295206 -240.026145) (xy 98.26468 -240.068161) (xy 98.227957 -240.104884) (xy 98.185941 -240.13541)
			(xy 98.139667 -240.158988) (xy 98.090274 -240.175036) (xy 98.038979 -240.183161) (xy 97.987045 -240.183161)
			(xy 97.93575 -240.175036) (xy 97.886357 -240.158988) (xy 97.840083 -240.13541) (xy 97.798067 -240.104884)
			(xy 97.761344 -240.068161) (xy 97.730818 -240.026145) (xy 97.70724 -239.979871) (xy 97.691192 -239.930478)
			(xy 97.683067 -239.879183) (xy 97.403411 -239.879183) (xy 97.395286 -239.930478) (xy 97.379238 -239.979871)
			(xy 97.35566 -240.026145) (xy 97.325134 -240.068161) (xy 97.288411 -240.104884) (xy 97.246395 -240.13541)
			(xy 97.200121 -240.158988) (xy 97.150728 -240.175036) (xy 97.099433 -240.183161) (xy 97.047499 -240.183161)
			(xy 96.996204 -240.175036) (xy 96.946811 -240.158988) (xy 96.900537 -240.13541) (xy 96.858521 -240.104884)
			(xy 96.821798 -240.068161) (xy 96.791272 -240.026145) (xy 96.767694 -239.979871) (xy 96.751646 -239.930478)
			(xy 96.743521 -239.879183) (xy 96.463357 -239.879183) (xy 96.455232 -239.930478) (xy 96.439184 -239.979871)
			(xy 96.415606 -240.026145) (xy 96.38508 -240.068161) (xy 96.348357 -240.104884) (xy 96.306341 -240.13541)
			(xy 96.260067 -240.158988) (xy 96.210674 -240.175036) (xy 96.159379 -240.183161) (xy 96.107445 -240.183161)
			(xy 96.05615 -240.175036) (xy 96.006757 -240.158988) (xy 95.960483 -240.13541) (xy 95.918467 -240.104884)
			(xy 95.881744 -240.068161) (xy 95.851218 -240.026145) (xy 95.82764 -239.979871) (xy 95.811592 -239.930478)
			(xy 95.803467 -239.879183) (xy 95.523557 -239.879183) (xy 95.515432 -239.930478) (xy 95.499384 -239.979871)
			(xy 95.475806 -240.026145) (xy 95.44528 -240.068161) (xy 95.408557 -240.104884) (xy 95.366541 -240.13541)
			(xy 95.320267 -240.158988) (xy 95.270874 -240.175036) (xy 95.219579 -240.183161) (xy 95.167645 -240.183161)
			(xy 95.11635 -240.175036) (xy 95.066957 -240.158988) (xy 95.020683 -240.13541) (xy 94.978667 -240.104884)
			(xy 94.941944 -240.068161) (xy 94.911418 -240.026145) (xy 94.88784 -239.979871) (xy 94.871792 -239.930478)
			(xy 94.863667 -239.879183) (xy 94.583757 -239.879183) (xy 94.575632 -239.930478) (xy 94.559584 -239.979871)
			(xy 94.536006 -240.026145) (xy 94.50548 -240.068161) (xy 94.468757 -240.104884) (xy 94.426741 -240.13541)
			(xy 94.380467 -240.158988) (xy 94.331074 -240.175036) (xy 94.279779 -240.183161) (xy 94.227845 -240.183161)
			(xy 94.17655 -240.175036) (xy 94.127157 -240.158988) (xy 94.080883 -240.13541) (xy 94.038867 -240.104884)
			(xy 94.002144 -240.068161) (xy 93.971618 -240.026145) (xy 93.94804 -239.979871) (xy 93.931992 -239.930478)
			(xy 93.923867 -239.879183) (xy 93.643957 -239.879183) (xy 93.635832 -239.930478) (xy 93.619784 -239.979871)
			(xy 93.596206 -240.026145) (xy 93.56568 -240.068161) (xy 93.528957 -240.104884) (xy 93.486941 -240.13541)
			(xy 93.440667 -240.158988) (xy 93.391274 -240.175036) (xy 93.339979 -240.183161) (xy 93.288045 -240.183161)
			(xy 93.23675 -240.175036) (xy 93.187357 -240.158988) (xy 93.141083 -240.13541) (xy 93.099067 -240.104884)
			(xy 93.062344 -240.068161) (xy 93.031818 -240.026145) (xy 93.00824 -239.979871) (xy 92.992192 -239.930478)
			(xy 92.984067 -239.879183) (xy 92.704157 -239.879183) (xy 92.696032 -239.930478) (xy 92.679984 -239.979871)
			(xy 92.656406 -240.026145) (xy 92.62588 -240.068161) (xy 92.589157 -240.104884) (xy 92.547141 -240.13541)
			(xy 92.500867 -240.158988) (xy 92.451474 -240.175036) (xy 92.400179 -240.183161) (xy 92.348245 -240.183161)
			(xy 92.29695 -240.175036) (xy 92.247557 -240.158988) (xy 92.201283 -240.13541) (xy 92.159267 -240.104884)
			(xy 92.122544 -240.068161) (xy 92.092018 -240.026145) (xy 92.06844 -239.979871) (xy 92.052392 -239.930478)
			(xy 92.044267 -239.879183) (xy 91.764737 -239.879183) (xy 91.764737 -239.879731) (xy 91.756264 -239.932097)
			(xy 91.739537 -239.982438) (xy 91.714986 -240.029461) (xy 91.683239 -240.071961) (xy 91.645114 -240.108845)
			(xy 91.601587 -240.139167) (xy 91.577922 -240.151158) (xy 91.565222 -240.157254) (xy 91.53525 -240.20272)
			(xy 91.53525 -240.330736) (xy 91.535678 -240.33976) (xy 91.542133 -240.356617) (xy 91.554125 -240.370109)
			(xy 91.56192 -240.374678) (xy 91.604846 -240.395252) (xy 91.645232 -240.41481) (xy 91.650455 -240.41715)
			(xy 91.661609 -240.419705) (xy 91.66733 -240.41989) (xy 91.69781 -240.408968) (xy 91.70416 -240.404142)
			(xy 91.725908 -240.388262) (xy 91.773477 -240.36303) (xy 91.824504 -240.345833) (xy 91.877642 -240.337125)
			(xy 91.904566 -240.336578) (xy 91.930558 -240.337059) (xy 91.981903 -240.345186) (xy 92.031344 -240.361246)
			(xy 92.077664 -240.384843) (xy 92.119722 -240.415396) (xy 92.156482 -240.452152) (xy 92.187039 -240.494207)
			(xy 92.210641 -240.540524) (xy 92.226706 -240.589964) (xy 92.234839 -240.641308) (xy 92.234839 -240.693253)
			(xy 92.514421 -240.693253) (xy 92.514421 -240.641319) (xy 92.522546 -240.590024) (xy 92.538594 -240.540631)
			(xy 92.562172 -240.494357) (xy 92.592698 -240.452341) (xy 92.629421 -240.415618) (xy 92.671437 -240.385092)
			(xy 92.717711 -240.361514) (xy 92.767104 -240.345466) (xy 92.818399 -240.337341) (xy 92.870333 -240.337341)
			(xy 92.921628 -240.345466) (xy 92.971021 -240.361514) (xy 93.017295 -240.385092) (xy 93.059311 -240.415618)
			(xy 93.096034 -240.452341) (xy 93.12656 -240.494357) (xy 93.150138 -240.540631) (xy 93.166186 -240.590024)
			(xy 93.174311 -240.641319) (xy 93.17482 -240.667286) (xy 93.174311 -240.693253) (xy 93.454221 -240.693253)
			(xy 93.454221 -240.641319) (xy 93.462346 -240.590024) (xy 93.478394 -240.540631) (xy 93.501972 -240.494357)
			(xy 93.532498 -240.452341) (xy 93.569221 -240.415618) (xy 93.611237 -240.385092) (xy 93.657511 -240.361514)
			(xy 93.706904 -240.345466) (xy 93.758199 -240.337341) (xy 93.810133 -240.337341) (xy 93.861428 -240.345466)
			(xy 93.910821 -240.361514) (xy 93.957095 -240.385092) (xy 93.999111 -240.415618) (xy 94.035834 -240.452341)
			(xy 94.06636 -240.494357) (xy 94.089938 -240.540631) (xy 94.105986 -240.590024) (xy 94.114111 -240.641319)
			(xy 94.11462 -240.667286) (xy 94.114111 -240.693253) (xy 94.394021 -240.693253) (xy 94.394021 -240.641319)
			(xy 94.402146 -240.590024) (xy 94.418194 -240.540631) (xy 94.441772 -240.494357) (xy 94.472298 -240.452341)
			(xy 94.509021 -240.415618) (xy 94.551037 -240.385092) (xy 94.597311 -240.361514) (xy 94.646704 -240.345466)
			(xy 94.697999 -240.337341) (xy 94.749933 -240.337341) (xy 94.801228 -240.345466) (xy 94.850621 -240.361514)
			(xy 94.896895 -240.385092) (xy 94.938911 -240.415618) (xy 94.975634 -240.452341) (xy 95.00616 -240.494357)
			(xy 95.029738 -240.540631) (xy 95.045786 -240.590024) (xy 95.053911 -240.641319) (xy 95.05442 -240.667286)
			(xy 95.053911 -240.693253) (xy 95.333821 -240.693253) (xy 95.333821 -240.641319) (xy 95.341946 -240.590024)
			(xy 95.357994 -240.540631) (xy 95.381572 -240.494357) (xy 95.412098 -240.452341) (xy 95.448821 -240.415618)
			(xy 95.490837 -240.385092) (xy 95.537111 -240.361514) (xy 95.586504 -240.345466) (xy 95.637799 -240.337341)
			(xy 95.689733 -240.337341) (xy 95.741028 -240.345466) (xy 95.790421 -240.361514) (xy 95.836695 -240.385092)
			(xy 95.878711 -240.415618) (xy 95.915434 -240.452341) (xy 95.94596 -240.494357) (xy 95.969538 -240.540631)
			(xy 95.985586 -240.590024) (xy 95.993711 -240.641319) (xy 95.99422 -240.667286) (xy 95.993711 -240.693253)
			(xy 96.273621 -240.693253) (xy 96.273621 -240.641319) (xy 96.281746 -240.590024) (xy 96.297794 -240.540631)
			(xy 96.321372 -240.494357) (xy 96.351898 -240.452341) (xy 96.388621 -240.415618) (xy 96.430637 -240.385092)
			(xy 96.476911 -240.361514) (xy 96.526304 -240.345466) (xy 96.577599 -240.337341) (xy 96.629533 -240.337341)
			(xy 96.680828 -240.345466) (xy 96.730221 -240.361514) (xy 96.776495 -240.385092) (xy 96.818511 -240.415618)
			(xy 96.855234 -240.452341) (xy 96.88576 -240.494357) (xy 96.909338 -240.540631) (xy 96.925386 -240.590024)
			(xy 96.933511 -240.641319) (xy 96.93402 -240.667286) (xy 96.933511 -240.693253) (xy 97.213167 -240.693253)
			(xy 97.213167 -240.641319) (xy 97.221292 -240.590024) (xy 97.23734 -240.540631) (xy 97.260918 -240.494357)
			(xy 97.291444 -240.452341) (xy 97.328167 -240.415618) (xy 97.370183 -240.385092) (xy 97.416457 -240.361514)
			(xy 97.46585 -240.345466) (xy 97.517145 -240.337341) (xy 97.569079 -240.337341) (xy 97.620374 -240.345466)
			(xy 97.669767 -240.361514) (xy 97.716041 -240.385092) (xy 97.758057 -240.415618) (xy 97.79478 -240.452341)
			(xy 97.825306 -240.494357) (xy 97.848884 -240.540631) (xy 97.864932 -240.590024) (xy 97.873057 -240.641319)
			(xy 97.873566 -240.667286) (xy 97.873057 -240.693253) (xy 98.153221 -240.693253) (xy 98.153221 -240.641319)
			(xy 98.161346 -240.590024) (xy 98.177394 -240.540631) (xy 98.200972 -240.494357) (xy 98.231498 -240.452341)
			(xy 98.268221 -240.415618) (xy 98.310237 -240.385092) (xy 98.356511 -240.361514) (xy 98.405904 -240.345466)
			(xy 98.457199 -240.337341) (xy 98.509133 -240.337341) (xy 98.560428 -240.345466) (xy 98.609821 -240.361514)
			(xy 98.656095 -240.385092) (xy 98.698111 -240.415618) (xy 98.734834 -240.452341) (xy 98.76536 -240.494357)
			(xy 98.788938 -240.540631) (xy 98.804986 -240.590024) (xy 98.813111 -240.641319) (xy 98.81362 -240.667286)
			(xy 98.813111 -240.693253) (xy 99.093021 -240.693253) (xy 99.093021 -240.641319) (xy 99.101146 -240.590024)
			(xy 99.117194 -240.540631) (xy 99.140772 -240.494357) (xy 99.171298 -240.452341) (xy 99.208021 -240.415618)
			(xy 99.250037 -240.385092) (xy 99.296311 -240.361514) (xy 99.345704 -240.345466) (xy 99.396999 -240.337341)
			(xy 99.448933 -240.337341) (xy 99.500228 -240.345466) (xy 99.549621 -240.361514) (xy 99.595895 -240.385092)
			(xy 99.637911 -240.415618) (xy 99.674634 -240.452341) (xy 99.70516 -240.494357) (xy 99.728738 -240.540631)
			(xy 99.744786 -240.590024) (xy 99.752911 -240.641319) (xy 99.75342 -240.667286) (xy 99.752911 -240.693253)
			(xy 100.032821 -240.693253) (xy 100.032821 -240.641319) (xy 100.040946 -240.590024) (xy 100.056994 -240.540631)
			(xy 100.080572 -240.494357) (xy 100.111098 -240.452341) (xy 100.147821 -240.415618) (xy 100.189837 -240.385092)
			(xy 100.236111 -240.361514) (xy 100.285504 -240.345466) (xy 100.336799 -240.337341) (xy 100.388733 -240.337341)
			(xy 100.440028 -240.345466) (xy 100.489421 -240.361514) (xy 100.535695 -240.385092) (xy 100.577711 -240.415618)
			(xy 100.614434 -240.452341) (xy 100.64496 -240.494357) (xy 100.668538 -240.540631) (xy 100.684586 -240.590024)
			(xy 100.692711 -240.641319) (xy 100.69322 -240.667286) (xy 100.692711 -240.693253) (xy 100.972621 -240.693253)
			(xy 100.972621 -240.641319) (xy 100.980746 -240.590024) (xy 100.996794 -240.540631) (xy 101.020372 -240.494357)
			(xy 101.050898 -240.452341) (xy 101.087621 -240.415618) (xy 101.129637 -240.385092) (xy 101.175911 -240.361514)
			(xy 101.225304 -240.345466) (xy 101.276599 -240.337341) (xy 101.328533 -240.337341) (xy 101.379828 -240.345466)
			(xy 101.429221 -240.361514) (xy 101.475495 -240.385092) (xy 101.517511 -240.415618) (xy 101.554234 -240.452341)
			(xy 101.58476 -240.494357) (xy 101.608338 -240.540631) (xy 101.624386 -240.590024) (xy 101.632511 -240.641319)
			(xy 101.63302 -240.667286) (xy 101.632511 -240.693253) (xy 101.632509 -240.693267) (xy 101.912441 -240.693267)
			(xy 101.912441 -240.641333) (xy 101.920565 -240.590039) (xy 101.936612 -240.540648) (xy 101.960188 -240.494374)
			(xy 101.990712 -240.452358) (xy 102.027432 -240.415634) (xy 102.069445 -240.385106) (xy 102.115716 -240.361525)
			(xy 102.165106 -240.345473) (xy 102.216399 -240.337344) (xy 102.242366 -240.336832) (xy 102.266068 -240.337242)
			(xy 102.312988 -240.344007) (xy 102.35846 -240.357403) (xy 102.401553 -240.377155) (xy 102.42169 -240.389664)
			(xy 102.434465 -240.397377) (xy 102.46314 -240.405608) (xy 102.49297 -240.405208) (xy 102.521414 -240.396212)
			(xy 102.546049 -240.379386) (xy 102.564776 -240.356163) (xy 102.576 -240.328522) (xy 102.5779 -240.313718)
			(xy 102.58098 -240.28676) (xy 102.594811 -240.234297) (xy 102.617028 -240.184799) (xy 102.647035 -240.139597)
			(xy 102.684025 -240.099905) (xy 102.727004 -240.066792) (xy 102.774815 -240.041146) (xy 102.826175 -240.023658)
			(xy 102.879702 -240.014797) (xy 102.90683 -240.014252) (xy 102.932798 -240.014728) (xy 102.984095 -240.022857)
			(xy 103.033489 -240.03891) (xy 103.079763 -240.062492) (xy 103.121779 -240.093022) (xy 103.158502 -240.129749)
			(xy 103.189027 -240.171768) (xy 103.212604 -240.218045) (xy 103.228652 -240.26744) (xy 103.236775 -240.318738)
			(xy 103.237284 -240.344706) (xy 103.237284 -240.34496) (xy 103.236812 -240.369486) (xy 103.229555 -240.417998)
			(xy 103.215208 -240.464905) (xy 103.194088 -240.509177) (xy 103.166657 -240.549842) (xy 103.150416 -240.568226)
			(xy 103.140607 -240.579711) (xy 103.127596 -240.60695) (xy 103.123129 -240.636804) (xy 103.127598 -240.666659)
			(xy 103.140612 -240.693897) (xy 103.150416 -240.705386) (xy 103.166677 -240.723755) (xy 103.19412 -240.764418)
			(xy 103.215246 -240.808692) (xy 103.229592 -240.855605) (xy 103.23684 -240.904123) (xy 103.237284 -240.928652)
			(xy 103.237284 -240.928906) (xy 103.23675 -240.954872) (xy 103.228626 -241.006164) (xy 103.212578 -241.055554)
			(xy 103.189003 -241.101826) (xy 103.158479 -241.143841) (xy 103.129576 -241.172746) (xy 108.095796 -241.172746)
			(xy 108.095796 -241.172492) (xy 108.096244 -241.147965) (xy 108.103508 -241.099452) (xy 108.11786 -241.052545)
			(xy 108.138986 -241.008274) (xy 108.166422 -240.967609) (xy 108.182664 -240.949226) (xy 108.192424 -240.937702)
			(xy 108.205444 -240.910478) (xy 108.209922 -240.880634) (xy 108.205464 -240.850787) (xy 108.192462 -240.823554)
			(xy 108.182664 -240.812066) (xy 108.166441 -240.793665) (xy 108.13899 -240.753012) (xy 108.117855 -240.708746)
			(xy 108.103501 -240.66184) (xy 108.096244 -240.613327) (xy 108.095796 -240.5888) (xy 108.095796 -240.588546)
			(xy 108.096305 -240.562579) (xy 108.10443 -240.511284) (xy 108.120478 -240.461891) (xy 108.144056 -240.415617)
			(xy 108.174582 -240.373601) (xy 108.211305 -240.336878) (xy 108.253321 -240.306352) (xy 108.299595 -240.282774)
			(xy 108.348988 -240.266726) (xy 108.400283 -240.258601) (xy 108.452217 -240.258601) (xy 108.503512 -240.266726)
			(xy 108.552905 -240.282774) (xy 108.599179 -240.306352) (xy 108.641195 -240.336878) (xy 108.677918 -240.373601)
			(xy 108.708444 -240.415617) (xy 108.732022 -240.461891) (xy 108.74807 -240.511284) (xy 108.756195 -240.562579)
			(xy 108.756704 -240.588546) (xy 108.756704 -240.5888) (xy 108.756251 -240.613327) (xy 108.748988 -240.661839)
			(xy 108.739299 -240.693507) (xy 109.430821 -240.693507) (xy 109.430821 -240.641573) (xy 109.438946 -240.590278)
			(xy 109.454994 -240.540885) (xy 109.478572 -240.494611) (xy 109.509098 -240.452595) (xy 109.545821 -240.415872)
			(xy 109.587837 -240.385346) (xy 109.634111 -240.361768) (xy 109.683504 -240.34572) (xy 109.734799 -240.337595)
			(xy 109.786733 -240.337595) (xy 109.838028 -240.34572) (xy 109.887421 -240.361768) (xy 109.933695 -240.385346)
			(xy 109.975711 -240.415872) (xy 110.012434 -240.452595) (xy 110.04296 -240.494611) (xy 110.066538 -240.540885)
			(xy 110.082586 -240.590278) (xy 110.090711 -240.641573) (xy 110.09122 -240.66754) (xy 110.090711 -240.693507)
			(xy 110.370875 -240.693507) (xy 110.370875 -240.641573) (xy 110.379 -240.590278) (xy 110.395048 -240.540885)
			(xy 110.418626 -240.494611) (xy 110.449152 -240.452595) (xy 110.485875 -240.415872) (xy 110.527891 -240.385346)
			(xy 110.574165 -240.361768) (xy 110.623558 -240.34572) (xy 110.674853 -240.337595) (xy 110.726787 -240.337595)
			(xy 110.778082 -240.34572) (xy 110.827475 -240.361768) (xy 110.873749 -240.385346) (xy 110.915765 -240.415872)
			(xy 110.952488 -240.452595) (xy 110.983014 -240.494611) (xy 111.006592 -240.540885) (xy 111.02264 -240.590278)
			(xy 111.030765 -240.641573) (xy 111.031274 -240.66754) (xy 111.030765 -240.693507) (xy 111.310421 -240.693507)
			(xy 111.310421 -240.641573) (xy 111.318546 -240.590278) (xy 111.334594 -240.540885) (xy 111.358172 -240.494611)
			(xy 111.388698 -240.452595) (xy 111.425421 -240.415872) (xy 111.467437 -240.385346) (xy 111.513711 -240.361768)
			(xy 111.563104 -240.34572) (xy 111.614399 -240.337595) (xy 111.666333 -240.337595) (xy 111.717628 -240.34572)
			(xy 111.767021 -240.361768) (xy 111.813295 -240.385346) (xy 111.855311 -240.415872) (xy 111.892034 -240.452595)
			(xy 111.92256 -240.494611) (xy 111.946138 -240.540885) (xy 111.962186 -240.590278) (xy 111.970311 -240.641573)
			(xy 111.97082 -240.66754) (xy 111.970311 -240.693507) (xy 112.250221 -240.693507) (xy 112.250221 -240.641573)
			(xy 112.258346 -240.590278) (xy 112.274394 -240.540885) (xy 112.297972 -240.494611) (xy 112.328498 -240.452595)
			(xy 112.365221 -240.415872) (xy 112.407237 -240.385346) (xy 112.453511 -240.361768) (xy 112.502904 -240.34572)
			(xy 112.554199 -240.337595) (xy 112.606133 -240.337595) (xy 112.657428 -240.34572) (xy 112.706821 -240.361768)
			(xy 112.753095 -240.385346) (xy 112.795111 -240.415872) (xy 112.831834 -240.452595) (xy 112.86236 -240.494611)
			(xy 112.885938 -240.540885) (xy 112.901986 -240.590278) (xy 112.910111 -240.641573) (xy 112.91062 -240.66754)
			(xy 112.910111 -240.693507) (xy 113.190275 -240.693507) (xy 113.190275 -240.641573) (xy 113.1984 -240.590278)
			(xy 113.214448 -240.540885) (xy 113.238026 -240.494611) (xy 113.268552 -240.452595) (xy 113.305275 -240.415872)
			(xy 113.347291 -240.385346) (xy 113.393565 -240.361768) (xy 113.442958 -240.34572) (xy 113.494253 -240.337595)
			(xy 113.546187 -240.337595) (xy 113.597482 -240.34572) (xy 113.646875 -240.361768) (xy 113.693149 -240.385346)
			(xy 113.735165 -240.415872) (xy 113.771888 -240.452595) (xy 113.802414 -240.494611) (xy 113.825992 -240.540885)
			(xy 113.84204 -240.590278) (xy 113.850165 -240.641573) (xy 113.850674 -240.66754) (xy 113.850165 -240.693507)
			(xy 114.130075 -240.693507) (xy 114.130075 -240.641573) (xy 114.1382 -240.590278) (xy 114.154248 -240.540885)
			(xy 114.177826 -240.494611) (xy 114.208352 -240.452595) (xy 114.245075 -240.415872) (xy 114.287091 -240.385346)
			(xy 114.333365 -240.361768) (xy 114.382758 -240.34572) (xy 114.434053 -240.337595) (xy 114.485987 -240.337595)
			(xy 114.537282 -240.34572) (xy 114.586675 -240.361768) (xy 114.632949 -240.385346) (xy 114.674965 -240.415872)
			(xy 114.711688 -240.452595) (xy 114.742214 -240.494611) (xy 114.765792 -240.540885) (xy 114.78184 -240.590278)
			(xy 114.789965 -240.641573) (xy 114.790474 -240.66754) (xy 114.789965 -240.693507) (xy 114.788244 -240.70437)
			(xy 120.619266 -240.70437) (xy 120.619266 -240.704116) (xy 120.619736 -240.67959) (xy 120.626996 -240.631079)
			(xy 120.641344 -240.584172) (xy 120.662464 -240.5399) (xy 120.689894 -240.499235) (xy 120.706134 -240.48085)
			(xy 120.71597 -240.469385) (xy 120.728986 -240.44214) (xy 120.733451 -240.412278) (xy 120.728973 -240.382417)
			(xy 120.715945 -240.355178) (xy 120.706134 -240.34369) (xy 120.68987 -240.325324) (xy 120.662426 -240.284661)
			(xy 120.641299 -240.240386) (xy 120.626955 -240.193472) (xy 120.619708 -240.144953) (xy 120.619266 -240.120424)
			(xy 120.619266 -240.12017) (xy 120.619728 -240.094201) (xy 120.627857 -240.042903) (xy 120.643911 -239.993508)
			(xy 120.667494 -239.947233) (xy 120.698026 -239.905217) (xy 120.734755 -239.868493) (xy 120.776776 -239.837968)
			(xy 120.823055 -239.814392) (xy 120.872452 -239.798345) (xy 120.923751 -239.790224) (xy 120.94972 -239.789716)
			(xy 120.978853 -239.790327) (xy 121.036214 -239.800552) (xy 121.063766 -239.810036) (xy 121.076632 -239.814262)
			(xy 121.103602 -239.816582) (xy 121.130235 -239.81174) (xy 121.154663 -239.800075) (xy 121.175171 -239.782407)
			(xy 121.19032 -239.759974) (xy 121.195084 -239.747298) (xy 121.203795 -239.723102) (xy 121.227622 -239.677533)
			(xy 121.25822 -239.636204) (xy 121.294851 -239.600115) (xy 121.336631 -239.570135) (xy 121.38255 -239.54699)
			(xy 121.431501 -239.531238) (xy 121.482301 -239.523258) (xy 121.508012 -239.522762) (xy 121.53398 -239.52324)
			(xy 121.585276 -239.531366) (xy 121.634669 -239.547417) (xy 121.680944 -239.570996) (xy 121.72296 -239.601524)
			(xy 121.759683 -239.638249) (xy 121.79021 -239.680266) (xy 121.813788 -239.726542) (xy 121.829836 -239.775936)
			(xy 121.837961 -239.827232) (xy 121.837961 -239.879168) (xy 121.837959 -239.879183) (xy 122.118121 -239.879183)
			(xy 122.118121 -239.827249) (xy 122.126246 -239.775954) (xy 122.142294 -239.726561) (xy 122.165872 -239.680287)
			(xy 122.196398 -239.638271) (xy 122.233121 -239.601548) (xy 122.275137 -239.571022) (xy 122.321411 -239.547444)
			(xy 122.370804 -239.531396) (xy 122.422099 -239.523271) (xy 122.474033 -239.523271) (xy 122.525328 -239.531396)
			(xy 122.574721 -239.547444) (xy 122.620995 -239.571022) (xy 122.663011 -239.601548) (xy 122.699734 -239.638271)
			(xy 122.73026 -239.680287) (xy 122.753838 -239.726561) (xy 122.769886 -239.775954) (xy 122.778011 -239.827249)
			(xy 122.77852 -239.853216) (xy 122.778011 -239.879183) (xy 123.057667 -239.879183) (xy 123.057667 -239.827249)
			(xy 123.065792 -239.775954) (xy 123.08184 -239.726561) (xy 123.105418 -239.680287) (xy 123.135944 -239.638271)
			(xy 123.172667 -239.601548) (xy 123.214683 -239.571022) (xy 123.260957 -239.547444) (xy 123.31035 -239.531396)
			(xy 123.361645 -239.523271) (xy 123.413579 -239.523271) (xy 123.464874 -239.531396) (xy 123.514267 -239.547444)
			(xy 123.560541 -239.571022) (xy 123.602557 -239.601548) (xy 123.63928 -239.638271) (xy 123.669806 -239.680287)
			(xy 123.693384 -239.726561) (xy 123.709432 -239.775954) (xy 123.717557 -239.827249) (xy 123.718066 -239.853216)
			(xy 123.717557 -239.879183) (xy 123.997467 -239.879183) (xy 123.997467 -239.827249) (xy 124.005592 -239.775954)
			(xy 124.02164 -239.726561) (xy 124.045218 -239.680287) (xy 124.075744 -239.638271) (xy 124.112467 -239.601548)
			(xy 124.154483 -239.571022) (xy 124.200757 -239.547444) (xy 124.25015 -239.531396) (xy 124.301445 -239.523271)
			(xy 124.353379 -239.523271) (xy 124.404674 -239.531396) (xy 124.454067 -239.547444) (xy 124.500341 -239.571022)
			(xy 124.542357 -239.601548) (xy 124.57908 -239.638271) (xy 124.609606 -239.680287) (xy 124.633184 -239.726561)
			(xy 124.649232 -239.775954) (xy 124.657357 -239.827249) (xy 124.657866 -239.853216) (xy 124.657357 -239.879183)
			(xy 124.937521 -239.879183) (xy 124.937521 -239.827249) (xy 124.945646 -239.775954) (xy 124.961694 -239.726561)
			(xy 124.985272 -239.680287) (xy 125.015798 -239.638271) (xy 125.052521 -239.601548) (xy 125.094537 -239.571022)
			(xy 125.140811 -239.547444) (xy 125.190204 -239.531396) (xy 125.241499 -239.523271) (xy 125.293433 -239.523271)
			(xy 125.344728 -239.531396) (xy 125.394121 -239.547444) (xy 125.440395 -239.571022) (xy 125.482411 -239.601548)
			(xy 125.519134 -239.638271) (xy 125.54966 -239.680287) (xy 125.573238 -239.726561) (xy 125.589286 -239.775954)
			(xy 125.597411 -239.827249) (xy 125.59792 -239.853216) (xy 125.597411 -239.879183) (xy 125.877067 -239.879183)
			(xy 125.877067 -239.827249) (xy 125.885192 -239.775954) (xy 125.90124 -239.726561) (xy 125.924818 -239.680287)
			(xy 125.955344 -239.638271) (xy 125.992067 -239.601548) (xy 126.034083 -239.571022) (xy 126.080357 -239.547444)
			(xy 126.12975 -239.531396) (xy 126.181045 -239.523271) (xy 126.232979 -239.523271) (xy 126.284274 -239.531396)
			(xy 126.333667 -239.547444) (xy 126.379941 -239.571022) (xy 126.421957 -239.601548) (xy 126.45868 -239.638271)
			(xy 126.489206 -239.680287) (xy 126.512784 -239.726561) (xy 126.528832 -239.775954) (xy 126.536957 -239.827249)
			(xy 126.537466 -239.853216) (xy 126.536957 -239.879183) (xy 126.816867 -239.879183) (xy 126.816867 -239.827249)
			(xy 126.824992 -239.775954) (xy 126.84104 -239.726561) (xy 126.864618 -239.680287) (xy 126.895144 -239.638271)
			(xy 126.931867 -239.601548) (xy 126.973883 -239.571022) (xy 127.020157 -239.547444) (xy 127.06955 -239.531396)
			(xy 127.120845 -239.523271) (xy 127.172779 -239.523271) (xy 127.224074 -239.531396) (xy 127.273467 -239.547444)
			(xy 127.319741 -239.571022) (xy 127.361757 -239.601548) (xy 127.39848 -239.638271) (xy 127.429006 -239.680287)
			(xy 127.452584 -239.726561) (xy 127.468632 -239.775954) (xy 127.476757 -239.827249) (xy 127.477266 -239.853216)
			(xy 127.476757 -239.879183) (xy 127.756667 -239.879183) (xy 127.756667 -239.827249) (xy 127.764792 -239.775954)
			(xy 127.78084 -239.726561) (xy 127.804418 -239.680287) (xy 127.834944 -239.638271) (xy 127.871667 -239.601548)
			(xy 127.913683 -239.571022) (xy 127.959957 -239.547444) (xy 128.00935 -239.531396) (xy 128.060645 -239.523271)
			(xy 128.112579 -239.523271) (xy 128.163874 -239.531396) (xy 128.213267 -239.547444) (xy 128.259541 -239.571022)
			(xy 128.301557 -239.601548) (xy 128.33828 -239.638271) (xy 128.368806 -239.680287) (xy 128.392384 -239.726561)
			(xy 128.408432 -239.775954) (xy 128.416557 -239.827249) (xy 128.417066 -239.853216) (xy 128.416557 -239.879183)
			(xy 128.696467 -239.879183) (xy 128.696467 -239.827249) (xy 128.704592 -239.775954) (xy 128.72064 -239.726561)
			(xy 128.744218 -239.680287) (xy 128.774744 -239.638271) (xy 128.811467 -239.601548) (xy 128.853483 -239.571022)
			(xy 128.899757 -239.547444) (xy 128.94915 -239.531396) (xy 129.000445 -239.523271) (xy 129.052379 -239.523271)
			(xy 129.103674 -239.531396) (xy 129.153067 -239.547444) (xy 129.199341 -239.571022) (xy 129.241357 -239.601548)
			(xy 129.27808 -239.638271) (xy 129.308606 -239.680287) (xy 129.332184 -239.726561) (xy 129.348232 -239.775954)
			(xy 129.356357 -239.827249) (xy 129.356866 -239.853216) (xy 129.356357 -239.879183) (xy 129.636267 -239.879183)
			(xy 129.636267 -239.827249) (xy 129.644392 -239.775954) (xy 129.66044 -239.726561) (xy 129.684018 -239.680287)
			(xy 129.714544 -239.638271) (xy 129.751267 -239.601548) (xy 129.793283 -239.571022) (xy 129.839557 -239.547444)
			(xy 129.88895 -239.531396) (xy 129.940245 -239.523271) (xy 129.992179 -239.523271) (xy 130.043474 -239.531396)
			(xy 130.092867 -239.547444) (xy 130.139141 -239.571022) (xy 130.181157 -239.601548) (xy 130.21788 -239.638271)
			(xy 130.248406 -239.680287) (xy 130.271984 -239.726561) (xy 130.288032 -239.775954) (xy 130.296157 -239.827249)
			(xy 130.296666 -239.853216) (xy 130.296157 -239.879183) (xy 130.576067 -239.879183) (xy 130.576067 -239.827249)
			(xy 130.584192 -239.775954) (xy 130.60024 -239.726561) (xy 130.623818 -239.680287) (xy 130.654344 -239.638271)
			(xy 130.691067 -239.601548) (xy 130.733083 -239.571022) (xy 130.779357 -239.547444) (xy 130.82875 -239.531396)
			(xy 130.880045 -239.523271) (xy 130.931979 -239.523271) (xy 130.983274 -239.531396) (xy 131.032667 -239.547444)
			(xy 131.078941 -239.571022) (xy 131.120957 -239.601548) (xy 131.15768 -239.638271) (xy 131.188206 -239.680287)
			(xy 131.211784 -239.726561) (xy 131.227832 -239.775954) (xy 131.235957 -239.827249) (xy 131.236466 -239.853216)
			(xy 131.235957 -239.879183) (xy 131.227832 -239.930478) (xy 131.211784 -239.979871) (xy 131.188206 -240.026145)
			(xy 131.15768 -240.068161) (xy 131.120957 -240.104884) (xy 131.078941 -240.13541) (xy 131.032667 -240.158988)
			(xy 130.983274 -240.175036) (xy 130.931979 -240.183161) (xy 130.880045 -240.183161) (xy 130.82875 -240.175036)
			(xy 130.779357 -240.158988) (xy 130.733083 -240.13541) (xy 130.691067 -240.104884) (xy 130.654344 -240.068161)
			(xy 130.623818 -240.026145) (xy 130.60024 -239.979871) (xy 130.584192 -239.930478) (xy 130.576067 -239.879183)
			(xy 130.296157 -239.879183) (xy 130.288032 -239.930478) (xy 130.271984 -239.979871) (xy 130.248406 -240.026145)
			(xy 130.21788 -240.068161) (xy 130.181157 -240.104884) (xy 130.139141 -240.13541) (xy 130.092867 -240.158988)
			(xy 130.043474 -240.175036) (xy 129.992179 -240.183161) (xy 129.940245 -240.183161) (xy 129.88895 -240.175036)
			(xy 129.839557 -240.158988) (xy 129.793283 -240.13541) (xy 129.751267 -240.104884) (xy 129.714544 -240.068161)
			(xy 129.684018 -240.026145) (xy 129.66044 -239.979871) (xy 129.644392 -239.930478) (xy 129.636267 -239.879183)
			(xy 129.356357 -239.879183) (xy 129.348232 -239.930478) (xy 129.332184 -239.979871) (xy 129.308606 -240.026145)
			(xy 129.27808 -240.068161) (xy 129.241357 -240.104884) (xy 129.199341 -240.13541) (xy 129.153067 -240.158988)
			(xy 129.103674 -240.175036) (xy 129.052379 -240.183161) (xy 129.000445 -240.183161) (xy 128.94915 -240.175036)
			(xy 128.899757 -240.158988) (xy 128.853483 -240.13541) (xy 128.811467 -240.104884) (xy 128.774744 -240.068161)
			(xy 128.744218 -240.026145) (xy 128.72064 -239.979871) (xy 128.704592 -239.930478) (xy 128.696467 -239.879183)
			(xy 128.416557 -239.879183) (xy 128.408432 -239.930478) (xy 128.392384 -239.979871) (xy 128.368806 -240.026145)
			(xy 128.33828 -240.068161) (xy 128.301557 -240.104884) (xy 128.259541 -240.13541) (xy 128.213267 -240.158988)
			(xy 128.163874 -240.175036) (xy 128.112579 -240.183161) (xy 128.060645 -240.183161) (xy 128.00935 -240.175036)
			(xy 127.959957 -240.158988) (xy 127.913683 -240.13541) (xy 127.871667 -240.104884) (xy 127.834944 -240.068161)
			(xy 127.804418 -240.026145) (xy 127.78084 -239.979871) (xy 127.764792 -239.930478) (xy 127.756667 -239.879183)
			(xy 127.476757 -239.879183) (xy 127.468632 -239.930478) (xy 127.452584 -239.979871) (xy 127.429006 -240.026145)
			(xy 127.39848 -240.068161) (xy 127.361757 -240.104884) (xy 127.319741 -240.13541) (xy 127.273467 -240.158988)
			(xy 127.224074 -240.175036) (xy 127.172779 -240.183161) (xy 127.120845 -240.183161) (xy 127.06955 -240.175036)
			(xy 127.020157 -240.158988) (xy 126.973883 -240.13541) (xy 126.931867 -240.104884) (xy 126.895144 -240.068161)
			(xy 126.864618 -240.026145) (xy 126.84104 -239.979871) (xy 126.824992 -239.930478) (xy 126.816867 -239.879183)
			(xy 126.536957 -239.879183) (xy 126.528832 -239.930478) (xy 126.512784 -239.979871) (xy 126.489206 -240.026145)
			(xy 126.45868 -240.068161) (xy 126.421957 -240.104884) (xy 126.379941 -240.13541) (xy 126.333667 -240.158988)
			(xy 126.284274 -240.175036) (xy 126.232979 -240.183161) (xy 126.181045 -240.183161) (xy 126.12975 -240.175036)
			(xy 126.080357 -240.158988) (xy 126.034083 -240.13541) (xy 125.992067 -240.104884) (xy 125.955344 -240.068161)
			(xy 125.924818 -240.026145) (xy 125.90124 -239.979871) (xy 125.885192 -239.930478) (xy 125.877067 -239.879183)
			(xy 125.597411 -239.879183) (xy 125.589286 -239.930478) (xy 125.573238 -239.979871) (xy 125.54966 -240.026145)
			(xy 125.519134 -240.068161) (xy 125.482411 -240.104884) (xy 125.440395 -240.13541) (xy 125.394121 -240.158988)
			(xy 125.344728 -240.175036) (xy 125.293433 -240.183161) (xy 125.241499 -240.183161) (xy 125.190204 -240.175036)
			(xy 125.140811 -240.158988) (xy 125.094537 -240.13541) (xy 125.052521 -240.104884) (xy 125.015798 -240.068161)
			(xy 124.985272 -240.026145) (xy 124.961694 -239.979871) (xy 124.945646 -239.930478) (xy 124.937521 -239.879183)
			(xy 124.657357 -239.879183) (xy 124.649232 -239.930478) (xy 124.633184 -239.979871) (xy 124.609606 -240.026145)
			(xy 124.57908 -240.068161) (xy 124.542357 -240.104884) (xy 124.500341 -240.13541) (xy 124.454067 -240.158988)
			(xy 124.404674 -240.175036) (xy 124.353379 -240.183161) (xy 124.301445 -240.183161) (xy 124.25015 -240.175036)
			(xy 124.200757 -240.158988) (xy 124.154483 -240.13541) (xy 124.112467 -240.104884) (xy 124.075744 -240.068161)
			(xy 124.045218 -240.026145) (xy 124.02164 -239.979871) (xy 124.005592 -239.930478) (xy 123.997467 -239.879183)
			(xy 123.717557 -239.879183) (xy 123.709432 -239.930478) (xy 123.693384 -239.979871) (xy 123.669806 -240.026145)
			(xy 123.63928 -240.068161) (xy 123.602557 -240.104884) (xy 123.560541 -240.13541) (xy 123.514267 -240.158988)
			(xy 123.464874 -240.175036) (xy 123.413579 -240.183161) (xy 123.361645 -240.183161) (xy 123.31035 -240.175036)
			(xy 123.260957 -240.158988) (xy 123.214683 -240.13541) (xy 123.172667 -240.104884) (xy 123.135944 -240.068161)
			(xy 123.105418 -240.026145) (xy 123.08184 -239.979871) (xy 123.065792 -239.930478) (xy 123.057667 -239.879183)
			(xy 122.778011 -239.879183) (xy 122.769886 -239.930478) (xy 122.753838 -239.979871) (xy 122.73026 -240.026145)
			(xy 122.699734 -240.068161) (xy 122.663011 -240.104884) (xy 122.620995 -240.13541) (xy 122.574721 -240.158988)
			(xy 122.525328 -240.175036) (xy 122.474033 -240.183161) (xy 122.422099 -240.183161) (xy 122.370804 -240.175036)
			(xy 122.321411 -240.158988) (xy 122.275137 -240.13541) (xy 122.233121 -240.104884) (xy 122.196398 -240.068161)
			(xy 122.165872 -240.026145) (xy 122.142294 -239.979871) (xy 122.126246 -239.930478) (xy 122.118121 -239.879183)
			(xy 121.837959 -239.879183) (xy 121.829836 -239.930464) (xy 121.813788 -239.979858) (xy 121.79021 -240.026134)
			(xy 121.759683 -240.068151) (xy 121.72296 -240.104876) (xy 121.680944 -240.135404) (xy 121.634669 -240.158983)
			(xy 121.585276 -240.175034) (xy 121.53398 -240.18316) (xy 121.508012 -240.18367) (xy 121.47888 -240.183045)
			(xy 121.421519 -240.172829) (xy 121.393966 -240.16335) (xy 121.38112 -240.159057) (xy 121.354141 -240.156751)
			(xy 121.327502 -240.161608) (xy 121.303071 -240.173285) (xy 121.282562 -240.190965) (xy 121.267412 -240.213408)
			(xy 121.262648 -240.226088) (xy 121.25497 -240.247696) (xy 121.234467 -240.288715) (xy 121.208492 -240.326507)
			(xy 121.193306 -240.34369) (xy 121.183533 -240.355203) (xy 121.170519 -240.382432) (xy 121.166046 -240.412278)
			(xy 121.170506 -240.442126) (xy 121.183508 -240.46936) (xy 121.193306 -240.48085) (xy 121.209548 -240.499235)
			(xy 121.236994 -240.539893) (xy 121.258124 -240.584164) (xy 121.272474 -240.631073) (xy 121.279727 -240.679589)
			(xy 121.279976 -240.693253) (xy 121.648221 -240.693253) (xy 121.648221 -240.641319) (xy 121.656346 -240.590024)
			(xy 121.672394 -240.540631) (xy 121.695972 -240.494357) (xy 121.726498 -240.452341) (xy 121.763221 -240.415618)
			(xy 121.805237 -240.385092) (xy 121.851511 -240.361514) (xy 121.900904 -240.345466) (xy 121.952199 -240.337341)
			(xy 122.004133 -240.337341) (xy 122.055428 -240.345466) (xy 122.104821 -240.361514) (xy 122.151095 -240.385092)
			(xy 122.193111 -240.415618) (xy 122.229834 -240.452341) (xy 122.26036 -240.494357) (xy 122.283938 -240.540631)
			(xy 122.299986 -240.590024) (xy 122.308111 -240.641319) (xy 122.30862 -240.667286) (xy 122.308111 -240.693253)
			(xy 122.587767 -240.693253) (xy 122.587767 -240.641319) (xy 122.595892 -240.590024) (xy 122.61194 -240.540631)
			(xy 122.635518 -240.494357) (xy 122.666044 -240.452341) (xy 122.702767 -240.415618) (xy 122.744783 -240.385092)
			(xy 122.791057 -240.361514) (xy 122.84045 -240.345466) (xy 122.891745 -240.337341) (xy 122.943679 -240.337341)
			(xy 122.994974 -240.345466) (xy 123.044367 -240.361514) (xy 123.090641 -240.385092) (xy 123.132657 -240.415618)
			(xy 123.16938 -240.452341) (xy 123.199906 -240.494357) (xy 123.223484 -240.540631) (xy 123.239532 -240.590024)
			(xy 123.247657 -240.641319) (xy 123.248166 -240.667286) (xy 123.247657 -240.693253) (xy 123.527821 -240.693253)
			(xy 123.527821 -240.641319) (xy 123.535946 -240.590024) (xy 123.551994 -240.540631) (xy 123.575572 -240.494357)
			(xy 123.606098 -240.452341) (xy 123.642821 -240.415618) (xy 123.684837 -240.385092) (xy 123.731111 -240.361514)
			(xy 123.780504 -240.345466) (xy 123.831799 -240.337341) (xy 123.883733 -240.337341) (xy 123.935028 -240.345466)
			(xy 123.984421 -240.361514) (xy 124.030695 -240.385092) (xy 124.072711 -240.415618) (xy 124.109434 -240.452341)
			(xy 124.13996 -240.494357) (xy 124.163538 -240.540631) (xy 124.179586 -240.590024) (xy 124.187711 -240.641319)
			(xy 124.18822 -240.667286) (xy 124.187711 -240.693253) (xy 124.467621 -240.693253) (xy 124.467621 -240.641319)
			(xy 124.475746 -240.590024) (xy 124.491794 -240.540631) (xy 124.515372 -240.494357) (xy 124.545898 -240.452341)
			(xy 124.582621 -240.415618) (xy 124.624637 -240.385092) (xy 124.670911 -240.361514) (xy 124.720304 -240.345466)
			(xy 124.771599 -240.337341) (xy 124.823533 -240.337341) (xy 124.874828 -240.345466) (xy 124.924221 -240.361514)
			(xy 124.970495 -240.385092) (xy 125.012511 -240.415618) (xy 125.049234 -240.452341) (xy 125.07976 -240.494357)
			(xy 125.103338 -240.540631) (xy 125.119386 -240.590024) (xy 125.127511 -240.641319) (xy 125.12802 -240.667286)
			(xy 125.127511 -240.693253) (xy 125.407167 -240.693253) (xy 125.407167 -240.641319) (xy 125.415292 -240.590024)
			(xy 125.43134 -240.540631) (xy 125.454918 -240.494357) (xy 125.485444 -240.452341) (xy 125.522167 -240.415618)
			(xy 125.564183 -240.385092) (xy 125.610457 -240.361514) (xy 125.65985 -240.345466) (xy 125.711145 -240.337341)
			(xy 125.763079 -240.337341) (xy 125.814374 -240.345466) (xy 125.863767 -240.361514) (xy 125.910041 -240.385092)
			(xy 125.952057 -240.415618) (xy 125.98878 -240.452341) (xy 126.019306 -240.494357) (xy 126.042884 -240.540631)
			(xy 126.058932 -240.590024) (xy 126.067057 -240.641319) (xy 126.067566 -240.667286) (xy 126.067057 -240.693253)
			(xy 126.347221 -240.693253) (xy 126.347221 -240.641319) (xy 126.355346 -240.590024) (xy 126.371394 -240.540631)
			(xy 126.394972 -240.494357) (xy 126.425498 -240.452341) (xy 126.462221 -240.415618) (xy 126.504237 -240.385092)
			(xy 126.550511 -240.361514) (xy 126.599904 -240.345466) (xy 126.651199 -240.337341) (xy 126.703133 -240.337341)
			(xy 126.754428 -240.345466) (xy 126.803821 -240.361514) (xy 126.850095 -240.385092) (xy 126.892111 -240.415618)
			(xy 126.928834 -240.452341) (xy 126.95936 -240.494357) (xy 126.982938 -240.540631) (xy 126.998986 -240.590024)
			(xy 127.007111 -240.641319) (xy 127.00762 -240.667286) (xy 127.007111 -240.693253) (xy 127.287021 -240.693253)
			(xy 127.287021 -240.641319) (xy 127.295146 -240.590024) (xy 127.311194 -240.540631) (xy 127.334772 -240.494357)
			(xy 127.365298 -240.452341) (xy 127.402021 -240.415618) (xy 127.444037 -240.385092) (xy 127.490311 -240.361514)
			(xy 127.539704 -240.345466) (xy 127.590999 -240.337341) (xy 127.642933 -240.337341) (xy 127.694228 -240.345466)
			(xy 127.743621 -240.361514) (xy 127.789895 -240.385092) (xy 127.831911 -240.415618) (xy 127.868634 -240.452341)
			(xy 127.89916 -240.494357) (xy 127.922738 -240.540631) (xy 127.938786 -240.590024) (xy 127.946911 -240.641319)
			(xy 127.94742 -240.667286) (xy 127.946911 -240.693253) (xy 128.226821 -240.693253) (xy 128.226821 -240.641319)
			(xy 128.234946 -240.590024) (xy 128.250994 -240.540631) (xy 128.274572 -240.494357) (xy 128.305098 -240.452341)
			(xy 128.341821 -240.415618) (xy 128.383837 -240.385092) (xy 128.430111 -240.361514) (xy 128.479504 -240.345466)
			(xy 128.530799 -240.337341) (xy 128.582733 -240.337341) (xy 128.634028 -240.345466) (xy 128.683421 -240.361514)
			(xy 128.729695 -240.385092) (xy 128.771711 -240.415618) (xy 128.808434 -240.452341) (xy 128.83896 -240.494357)
			(xy 128.862538 -240.540631) (xy 128.878586 -240.590024) (xy 128.886711 -240.641319) (xy 128.88722 -240.667286)
			(xy 128.886711 -240.693253) (xy 129.166621 -240.693253) (xy 129.166621 -240.641319) (xy 129.174746 -240.590024)
			(xy 129.190794 -240.540631) (xy 129.214372 -240.494357) (xy 129.244898 -240.452341) (xy 129.281621 -240.415618)
			(xy 129.323637 -240.385092) (xy 129.369911 -240.361514) (xy 129.419304 -240.345466) (xy 129.470599 -240.337341)
			(xy 129.522533 -240.337341) (xy 129.573828 -240.345466) (xy 129.623221 -240.361514) (xy 129.669495 -240.385092)
			(xy 129.711511 -240.415618) (xy 129.748234 -240.452341) (xy 129.77876 -240.494357) (xy 129.802338 -240.540631)
			(xy 129.818386 -240.590024) (xy 129.826511 -240.641319) (xy 129.82702 -240.667286) (xy 129.826511 -240.693253)
			(xy 130.106421 -240.693253) (xy 130.106421 -240.641319) (xy 130.114546 -240.590024) (xy 130.130594 -240.540631)
			(xy 130.154172 -240.494357) (xy 130.184698 -240.452341) (xy 130.221421 -240.415618) (xy 130.263437 -240.385092)
			(xy 130.309711 -240.361514) (xy 130.359104 -240.345466) (xy 130.410399 -240.337341) (xy 130.462333 -240.337341)
			(xy 130.513628 -240.345466) (xy 130.563021 -240.361514) (xy 130.609295 -240.385092) (xy 130.651311 -240.415618)
			(xy 130.688034 -240.452341) (xy 130.71856 -240.494357) (xy 130.742138 -240.540631) (xy 130.758186 -240.590024)
			(xy 130.766311 -240.641319) (xy 130.76682 -240.667286) (xy 130.766311 -240.693253) (xy 130.758186 -240.744548)
			(xy 130.742138 -240.793941) (xy 130.71856 -240.840215) (xy 130.688034 -240.882231) (xy 130.651311 -240.918954)
			(xy 130.609295 -240.94948) (xy 130.563021 -240.973058) (xy 130.513628 -240.989106) (xy 130.462333 -240.997231)
			(xy 130.410399 -240.997231) (xy 130.359104 -240.989106) (xy 130.309711 -240.973058) (xy 130.263437 -240.94948)
			(xy 130.221421 -240.918954) (xy 130.184698 -240.882231) (xy 130.154172 -240.840215) (xy 130.130594 -240.793941)
			(xy 130.114546 -240.744548) (xy 130.106421 -240.693253) (xy 129.826511 -240.693253) (xy 129.818386 -240.744548)
			(xy 129.802338 -240.793941) (xy 129.77876 -240.840215) (xy 129.748234 -240.882231) (xy 129.711511 -240.918954)
			(xy 129.669495 -240.94948) (xy 129.623221 -240.973058) (xy 129.573828 -240.989106) (xy 129.522533 -240.997231)
			(xy 129.470599 -240.997231) (xy 129.419304 -240.989106) (xy 129.369911 -240.973058) (xy 129.323637 -240.94948)
			(xy 129.281621 -240.918954) (xy 129.244898 -240.882231) (xy 129.214372 -240.840215) (xy 129.190794 -240.793941)
			(xy 129.174746 -240.744548) (xy 129.166621 -240.693253) (xy 128.886711 -240.693253) (xy 128.878586 -240.744548)
			(xy 128.862538 -240.793941) (xy 128.83896 -240.840215) (xy 128.808434 -240.882231) (xy 128.771711 -240.918954)
			(xy 128.729695 -240.94948) (xy 128.683421 -240.973058) (xy 128.634028 -240.989106) (xy 128.582733 -240.997231)
			(xy 128.530799 -240.997231) (xy 128.479504 -240.989106) (xy 128.430111 -240.973058) (xy 128.383837 -240.94948)
			(xy 128.341821 -240.918954) (xy 128.305098 -240.882231) (xy 128.274572 -240.840215) (xy 128.250994 -240.793941)
			(xy 128.234946 -240.744548) (xy 128.226821 -240.693253) (xy 127.946911 -240.693253) (xy 127.938786 -240.744548)
			(xy 127.922738 -240.793941) (xy 127.89916 -240.840215) (xy 127.868634 -240.882231) (xy 127.831911 -240.918954)
			(xy 127.789895 -240.94948) (xy 127.743621 -240.973058) (xy 127.694228 -240.989106) (xy 127.642933 -240.997231)
			(xy 127.590999 -240.997231) (xy 127.539704 -240.989106) (xy 127.490311 -240.973058) (xy 127.444037 -240.94948)
			(xy 127.402021 -240.918954) (xy 127.365298 -240.882231) (xy 127.334772 -240.840215) (xy 127.311194 -240.793941)
			(xy 127.295146 -240.744548) (xy 127.287021 -240.693253) (xy 127.007111 -240.693253) (xy 126.998986 -240.744548)
			(xy 126.982938 -240.793941) (xy 126.95936 -240.840215) (xy 126.928834 -240.882231) (xy 126.892111 -240.918954)
			(xy 126.850095 -240.94948) (xy 126.803821 -240.973058) (xy 126.754428 -240.989106) (xy 126.703133 -240.997231)
			(xy 126.651199 -240.997231) (xy 126.599904 -240.989106) (xy 126.550511 -240.973058) (xy 126.504237 -240.94948)
			(xy 126.462221 -240.918954) (xy 126.425498 -240.882231) (xy 126.394972 -240.840215) (xy 126.371394 -240.793941)
			(xy 126.355346 -240.744548) (xy 126.347221 -240.693253) (xy 126.067057 -240.693253) (xy 126.058932 -240.744548)
			(xy 126.042884 -240.793941) (xy 126.019306 -240.840215) (xy 125.98878 -240.882231) (xy 125.952057 -240.918954)
			(xy 125.910041 -240.94948) (xy 125.863767 -240.973058) (xy 125.814374 -240.989106) (xy 125.763079 -240.997231)
			(xy 125.711145 -240.997231) (xy 125.65985 -240.989106) (xy 125.610457 -240.973058) (xy 125.564183 -240.94948)
			(xy 125.522167 -240.918954) (xy 125.485444 -240.882231) (xy 125.454918 -240.840215) (xy 125.43134 -240.793941)
			(xy 125.415292 -240.744548) (xy 125.407167 -240.693253) (xy 125.127511 -240.693253) (xy 125.119386 -240.744548)
			(xy 125.103338 -240.793941) (xy 125.07976 -240.840215) (xy 125.049234 -240.882231) (xy 125.012511 -240.918954)
			(xy 124.970495 -240.94948) (xy 124.924221 -240.973058) (xy 124.874828 -240.989106) (xy 124.823533 -240.997231)
			(xy 124.771599 -240.997231) (xy 124.720304 -240.989106) (xy 124.670911 -240.973058) (xy 124.624637 -240.94948)
			(xy 124.582621 -240.918954) (xy 124.545898 -240.882231) (xy 124.515372 -240.840215) (xy 124.491794 -240.793941)
			(xy 124.475746 -240.744548) (xy 124.467621 -240.693253) (xy 124.187711 -240.693253) (xy 124.179586 -240.744548)
			(xy 124.163538 -240.793941) (xy 124.13996 -240.840215) (xy 124.109434 -240.882231) (xy 124.072711 -240.918954)
			(xy 124.030695 -240.94948) (xy 123.984421 -240.973058) (xy 123.935028 -240.989106) (xy 123.883733 -240.997231)
			(xy 123.831799 -240.997231) (xy 123.780504 -240.989106) (xy 123.731111 -240.973058) (xy 123.684837 -240.94948)
			(xy 123.642821 -240.918954) (xy 123.606098 -240.882231) (xy 123.575572 -240.840215) (xy 123.551994 -240.793941)
			(xy 123.535946 -240.744548) (xy 123.527821 -240.693253) (xy 123.247657 -240.693253) (xy 123.239532 -240.744548)
			(xy 123.223484 -240.793941) (xy 123.199906 -240.840215) (xy 123.16938 -240.882231) (xy 123.132657 -240.918954)
			(xy 123.090641 -240.94948) (xy 123.044367 -240.973058) (xy 122.994974 -240.989106) (xy 122.943679 -240.997231)
			(xy 122.891745 -240.997231) (xy 122.84045 -240.989106) (xy 122.791057 -240.973058) (xy 122.744783 -240.94948)
			(xy 122.702767 -240.918954) (xy 122.666044 -240.882231) (xy 122.635518 -240.840215) (xy 122.61194 -240.793941)
			(xy 122.595892 -240.744548) (xy 122.587767 -240.693253) (xy 122.308111 -240.693253) (xy 122.299986 -240.744548)
			(xy 122.283938 -240.793941) (xy 122.26036 -240.840215) (xy 122.229834 -240.882231) (xy 122.193111 -240.918954)
			(xy 122.151095 -240.94948) (xy 122.104821 -240.973058) (xy 122.055428 -240.989106) (xy 122.004133 -240.997231)
			(xy 121.952199 -240.997231) (xy 121.900904 -240.989106) (xy 121.851511 -240.973058) (xy 121.805237 -240.94948)
			(xy 121.763221 -240.918954) (xy 121.726498 -240.882231) (xy 121.695972 -240.840215) (xy 121.672394 -240.793941)
			(xy 121.656346 -240.744548) (xy 121.648221 -240.693253) (xy 121.279976 -240.693253) (xy 121.280174 -240.704116)
			(xy 121.280174 -240.70437) (xy 121.279665 -240.730337) (xy 121.27154 -240.781632) (xy 121.255492 -240.831025)
			(xy 121.231914 -240.877299) (xy 121.201388 -240.919315) (xy 121.164665 -240.956038) (xy 121.122649 -240.986564)
			(xy 121.076375 -241.010142) (xy 121.026982 -241.02619) (xy 120.975687 -241.034315) (xy 120.923753 -241.034315)
			(xy 120.872458 -241.02619) (xy 120.823065 -241.010142) (xy 120.776791 -240.986564) (xy 120.734775 -240.956038)
			(xy 120.698052 -240.919315) (xy 120.667526 -240.877299) (xy 120.643948 -240.831025) (xy 120.6279 -240.781632)
			(xy 120.619775 -240.730337) (xy 120.619266 -240.70437) (xy 114.788244 -240.70437) (xy 114.78184 -240.744802)
			(xy 114.765792 -240.794195) (xy 114.742214 -240.840469) (xy 114.711688 -240.882485) (xy 114.674965 -240.919208)
			(xy 114.632949 -240.949734) (xy 114.586675 -240.973312) (xy 114.537282 -240.98936) (xy 114.485987 -240.997485)
			(xy 114.434053 -240.997485) (xy 114.382758 -240.98936) (xy 114.333365 -240.973312) (xy 114.287091 -240.949734)
			(xy 114.245075 -240.919208) (xy 114.208352 -240.882485) (xy 114.177826 -240.840469) (xy 114.154248 -240.794195)
			(xy 114.1382 -240.744802) (xy 114.130075 -240.693507) (xy 113.850165 -240.693507) (xy 113.84204 -240.744802)
			(xy 113.825992 -240.794195) (xy 113.802414 -240.840469) (xy 113.771888 -240.882485) (xy 113.735165 -240.919208)
			(xy 113.693149 -240.949734) (xy 113.646875 -240.973312) (xy 113.597482 -240.98936) (xy 113.546187 -240.997485)
			(xy 113.494253 -240.997485) (xy 113.442958 -240.98936) (xy 113.393565 -240.973312) (xy 113.347291 -240.949734)
			(xy 113.305275 -240.919208) (xy 113.268552 -240.882485) (xy 113.238026 -240.840469) (xy 113.214448 -240.794195)
			(xy 113.1984 -240.744802) (xy 113.190275 -240.693507) (xy 112.910111 -240.693507) (xy 112.901986 -240.744802)
			(xy 112.885938 -240.794195) (xy 112.86236 -240.840469) (xy 112.831834 -240.882485) (xy 112.795111 -240.919208)
			(xy 112.753095 -240.949734) (xy 112.706821 -240.973312) (xy 112.657428 -240.98936) (xy 112.606133 -240.997485)
			(xy 112.554199 -240.997485) (xy 112.502904 -240.98936) (xy 112.453511 -240.973312) (xy 112.407237 -240.949734)
			(xy 112.365221 -240.919208) (xy 112.328498 -240.882485) (xy 112.297972 -240.840469) (xy 112.274394 -240.794195)
			(xy 112.258346 -240.744802) (xy 112.250221 -240.693507) (xy 111.970311 -240.693507) (xy 111.962186 -240.744802)
			(xy 111.946138 -240.794195) (xy 111.92256 -240.840469) (xy 111.892034 -240.882485) (xy 111.855311 -240.919208)
			(xy 111.813295 -240.949734) (xy 111.767021 -240.973312) (xy 111.717628 -240.98936) (xy 111.666333 -240.997485)
			(xy 111.614399 -240.997485) (xy 111.563104 -240.98936) (xy 111.513711 -240.973312) (xy 111.467437 -240.949734)
			(xy 111.425421 -240.919208) (xy 111.388698 -240.882485) (xy 111.358172 -240.840469) (xy 111.334594 -240.794195)
			(xy 111.318546 -240.744802) (xy 111.310421 -240.693507) (xy 111.030765 -240.693507) (xy 111.02264 -240.744802)
			(xy 111.006592 -240.794195) (xy 110.983014 -240.840469) (xy 110.952488 -240.882485) (xy 110.915765 -240.919208)
			(xy 110.873749 -240.949734) (xy 110.827475 -240.973312) (xy 110.778082 -240.98936) (xy 110.726787 -240.997485)
			(xy 110.674853 -240.997485) (xy 110.623558 -240.98936) (xy 110.574165 -240.973312) (xy 110.527891 -240.949734)
			(xy 110.485875 -240.919208) (xy 110.449152 -240.882485) (xy 110.418626 -240.840469) (xy 110.395048 -240.794195)
			(xy 110.379 -240.744802) (xy 110.370875 -240.693507) (xy 110.090711 -240.693507) (xy 110.082586 -240.744802)
			(xy 110.066538 -240.794195) (xy 110.04296 -240.840469) (xy 110.012434 -240.882485) (xy 109.975711 -240.919208)
			(xy 109.933695 -240.949734) (xy 109.887421 -240.973312) (xy 109.838028 -240.98936) (xy 109.786733 -240.997485)
			(xy 109.734799 -240.997485) (xy 109.683504 -240.98936) (xy 109.634111 -240.973312) (xy 109.587837 -240.949734)
			(xy 109.545821 -240.919208) (xy 109.509098 -240.882485) (xy 109.478572 -240.840469) (xy 109.454994 -240.794195)
			(xy 109.438946 -240.744802) (xy 109.430821 -240.693507) (xy 108.739299 -240.693507) (xy 108.734637 -240.708746)
			(xy 108.713512 -240.753018) (xy 108.686078 -240.793682) (xy 108.669836 -240.812066) (xy 108.659987 -240.823519)
			(xy 108.646977 -240.850769) (xy 108.642516 -240.880634) (xy 108.646997 -240.910496) (xy 108.660025 -240.937737)
			(xy 108.669836 -240.949226) (xy 108.686055 -240.96763) (xy 108.713507 -241.008282) (xy 108.734643 -241.052548)
			(xy 108.748998 -241.099453) (xy 108.756256 -241.147966) (xy 108.756704 -241.172492) (xy 108.756704 -241.172746)
			(xy 108.756195 -241.198713) (xy 108.74807 -241.250008) (xy 108.732022 -241.299401) (xy 108.708444 -241.345675)
			(xy 108.677918 -241.387691) (xy 108.641195 -241.424414) (xy 108.599179 -241.45494) (xy 108.552905 -241.478518)
			(xy 108.503512 -241.494566) (xy 108.452217 -241.502691) (xy 108.400283 -241.502691) (xy 108.348988 -241.494566)
			(xy 108.299595 -241.478518) (xy 108.253321 -241.45494) (xy 108.211305 -241.424414) (xy 108.174582 -241.387691)
			(xy 108.144056 -241.345675) (xy 108.120478 -241.299401) (xy 108.10443 -241.250008) (xy 108.096305 -241.198713)
			(xy 108.095796 -241.172746) (xy 103.129576 -241.172746) (xy 103.121759 -241.180563) (xy 103.079747 -241.21109)
			(xy 103.033477 -241.234669) (xy 102.984088 -241.25072) (xy 102.932796 -241.258849) (xy 102.90683 -241.25936)
			(xy 102.882071 -241.258943) (xy 102.833106 -241.251572) (xy 102.785789 -241.236977) (xy 102.74118 -241.215483)
			(xy 102.700279 -241.187572) (xy 102.664001 -241.153869) (xy 102.633159 -241.11513) (xy 102.608444 -241.072222)
			(xy 102.59041 -241.026106) (xy 102.584504 -241.002058) (xy 102.580927 -240.988358) (xy 102.567385 -240.963507)
			(xy 102.547539 -240.94333) (xy 102.522915 -240.929379) (xy 102.495406 -240.922726) (xy 102.467129 -240.923883)
			(xy 102.440256 -240.932761) (xy 102.428294 -240.940336) (xy 102.407636 -240.953885) (xy 102.363121 -240.97531)
			(xy 102.315914 -240.989877) (xy 102.267067 -240.997262) (xy 102.242366 -240.99774) (xy 102.216399 -240.997256)
			(xy 102.165106 -240.989127) (xy 102.115716 -240.973075) (xy 102.069445 -240.949494) (xy 102.027432 -240.918966)
			(xy 101.990712 -240.882242) (xy 101.960188 -240.840226) (xy 101.936612 -240.793952) (xy 101.920565 -240.744561)
			(xy 101.912441 -240.693267) (xy 101.632509 -240.693267) (xy 101.624386 -240.744548) (xy 101.608338 -240.793941)
			(xy 101.58476 -240.840215) (xy 101.554234 -240.882231) (xy 101.517511 -240.918954) (xy 101.475495 -240.94948)
			(xy 101.429221 -240.973058) (xy 101.379828 -240.989106) (xy 101.328533 -240.997231) (xy 101.276599 -240.997231)
			(xy 101.225304 -240.989106) (xy 101.175911 -240.973058) (xy 101.129637 -240.94948) (xy 101.087621 -240.918954)
			(xy 101.050898 -240.882231) (xy 101.020372 -240.840215) (xy 100.996794 -240.793941) (xy 100.980746 -240.744548)
			(xy 100.972621 -240.693253) (xy 100.692711 -240.693253) (xy 100.684586 -240.744548) (xy 100.668538 -240.793941)
			(xy 100.64496 -240.840215) (xy 100.614434 -240.882231) (xy 100.577711 -240.918954) (xy 100.535695 -240.94948)
			(xy 100.489421 -240.973058) (xy 100.440028 -240.989106) (xy 100.388733 -240.997231) (xy 100.336799 -240.997231)
			(xy 100.285504 -240.989106) (xy 100.236111 -240.973058) (xy 100.189837 -240.94948) (xy 100.147821 -240.918954)
			(xy 100.111098 -240.882231) (xy 100.080572 -240.840215) (xy 100.056994 -240.793941) (xy 100.040946 -240.744548)
			(xy 100.032821 -240.693253) (xy 99.752911 -240.693253) (xy 99.744786 -240.744548) (xy 99.728738 -240.793941)
			(xy 99.70516 -240.840215) (xy 99.674634 -240.882231) (xy 99.637911 -240.918954) (xy 99.595895 -240.94948)
			(xy 99.549621 -240.973058) (xy 99.500228 -240.989106) (xy 99.448933 -240.997231) (xy 99.396999 -240.997231)
			(xy 99.345704 -240.989106) (xy 99.296311 -240.973058) (xy 99.250037 -240.94948) (xy 99.208021 -240.918954)
			(xy 99.171298 -240.882231) (xy 99.140772 -240.840215) (xy 99.117194 -240.793941) (xy 99.101146 -240.744548)
			(xy 99.093021 -240.693253) (xy 98.813111 -240.693253) (xy 98.804986 -240.744548) (xy 98.788938 -240.793941)
			(xy 98.76536 -240.840215) (xy 98.734834 -240.882231) (xy 98.698111 -240.918954) (xy 98.656095 -240.94948)
			(xy 98.609821 -240.973058) (xy 98.560428 -240.989106) (xy 98.509133 -240.997231) (xy 98.457199 -240.997231)
			(xy 98.405904 -240.989106) (xy 98.356511 -240.973058) (xy 98.310237 -240.94948) (xy 98.268221 -240.918954)
			(xy 98.231498 -240.882231) (xy 98.200972 -240.840215) (xy 98.177394 -240.793941) (xy 98.161346 -240.744548)
			(xy 98.153221 -240.693253) (xy 97.873057 -240.693253) (xy 97.864932 -240.744548) (xy 97.848884 -240.793941)
			(xy 97.825306 -240.840215) (xy 97.79478 -240.882231) (xy 97.758057 -240.918954) (xy 97.716041 -240.94948)
			(xy 97.669767 -240.973058) (xy 97.620374 -240.989106) (xy 97.569079 -240.997231) (xy 97.517145 -240.997231)
			(xy 97.46585 -240.989106) (xy 97.416457 -240.973058) (xy 97.370183 -240.94948) (xy 97.328167 -240.918954)
			(xy 97.291444 -240.882231) (xy 97.260918 -240.840215) (xy 97.23734 -240.793941) (xy 97.221292 -240.744548)
			(xy 97.213167 -240.693253) (xy 96.933511 -240.693253) (xy 96.925386 -240.744548) (xy 96.909338 -240.793941)
			(xy 96.88576 -240.840215) (xy 96.855234 -240.882231) (xy 96.818511 -240.918954) (xy 96.776495 -240.94948)
			(xy 96.730221 -240.973058) (xy 96.680828 -240.989106) (xy 96.629533 -240.997231) (xy 96.577599 -240.997231)
			(xy 96.526304 -240.989106) (xy 96.476911 -240.973058) (xy 96.430637 -240.94948) (xy 96.388621 -240.918954)
			(xy 96.351898 -240.882231) (xy 96.321372 -240.840215) (xy 96.297794 -240.793941) (xy 96.281746 -240.744548)
			(xy 96.273621 -240.693253) (xy 95.993711 -240.693253) (xy 95.985586 -240.744548) (xy 95.969538 -240.793941)
			(xy 95.94596 -240.840215) (xy 95.915434 -240.882231) (xy 95.878711 -240.918954) (xy 95.836695 -240.94948)
			(xy 95.790421 -240.973058) (xy 95.741028 -240.989106) (xy 95.689733 -240.997231) (xy 95.637799 -240.997231)
			(xy 95.586504 -240.989106) (xy 95.537111 -240.973058) (xy 95.490837 -240.94948) (xy 95.448821 -240.918954)
			(xy 95.412098 -240.882231) (xy 95.381572 -240.840215) (xy 95.357994 -240.793941) (xy 95.341946 -240.744548)
			(xy 95.333821 -240.693253) (xy 95.053911 -240.693253) (xy 95.045786 -240.744548) (xy 95.029738 -240.793941)
			(xy 95.00616 -240.840215) (xy 94.975634 -240.882231) (xy 94.938911 -240.918954) (xy 94.896895 -240.94948)
			(xy 94.850621 -240.973058) (xy 94.801228 -240.989106) (xy 94.749933 -240.997231) (xy 94.697999 -240.997231)
			(xy 94.646704 -240.989106) (xy 94.597311 -240.973058) (xy 94.551037 -240.94948) (xy 94.509021 -240.918954)
			(xy 94.472298 -240.882231) (xy 94.441772 -240.840215) (xy 94.418194 -240.793941) (xy 94.402146 -240.744548)
			(xy 94.394021 -240.693253) (xy 94.114111 -240.693253) (xy 94.105986 -240.744548) (xy 94.089938 -240.793941)
			(xy 94.06636 -240.840215) (xy 94.035834 -240.882231) (xy 93.999111 -240.918954) (xy 93.957095 -240.94948)
			(xy 93.910821 -240.973058) (xy 93.861428 -240.989106) (xy 93.810133 -240.997231) (xy 93.758199 -240.997231)
			(xy 93.706904 -240.989106) (xy 93.657511 -240.973058) (xy 93.611237 -240.94948) (xy 93.569221 -240.918954)
			(xy 93.532498 -240.882231) (xy 93.501972 -240.840215) (xy 93.478394 -240.793941) (xy 93.462346 -240.744548)
			(xy 93.454221 -240.693253) (xy 93.174311 -240.693253) (xy 93.166186 -240.744548) (xy 93.150138 -240.793941)
			(xy 93.12656 -240.840215) (xy 93.096034 -240.882231) (xy 93.059311 -240.918954) (xy 93.017295 -240.94948)
			(xy 92.971021 -240.973058) (xy 92.921628 -240.989106) (xy 92.870333 -240.997231) (xy 92.818399 -240.997231)
			(xy 92.767104 -240.989106) (xy 92.717711 -240.973058) (xy 92.671437 -240.94948) (xy 92.629421 -240.918954)
			(xy 92.592698 -240.882231) (xy 92.562172 -240.840215) (xy 92.538594 -240.793941) (xy 92.522546 -240.744548)
			(xy 92.514421 -240.693253) (xy 92.234839 -240.693253) (xy 92.234839 -240.693292) (xy 92.226706 -240.744636)
			(xy 92.210641 -240.794076) (xy 92.187039 -240.840393) (xy 92.156482 -240.882448) (xy 92.119722 -240.919204)
			(xy 92.077664 -240.949757) (xy 92.031344 -240.973354) (xy 91.981903 -240.989414) (xy 91.930558 -240.997541)
			(xy 91.904566 -240.997994) (xy 91.877643 -240.997463) (xy 91.824507 -240.988742) (xy 91.773484 -240.971535)
			(xy 91.725919 -240.946295) (xy 91.70416 -240.93043) (xy 91.69781 -240.925604) (xy 91.66733 -240.914682)
			(xy 91.661602 -240.914798) (xy 91.65044 -240.917372) (xy 91.645232 -240.919762) (xy 91.604846 -240.93932)
			(xy 91.56192 -240.959894) (xy 91.554123 -240.964452) (xy 91.542159 -240.977964) (xy 91.535701 -240.994816)
			(xy 91.53525 -241.003836) (xy 91.53525 -241.131598) (xy 91.565222 -241.177064) (xy 91.577922 -241.18316)
			(xy 91.6016 -241.195126) (xy 91.645128 -241.225451) (xy 91.683254 -241.262337) (xy 91.715 -241.304838)
			(xy 91.739552 -241.351864) (xy 91.756278 -241.402208) (xy 91.76475 -241.454576) (xy 91.76475 -241.507069)
			(xy 92.044267 -241.507069) (xy 92.044267 -241.455135) (xy 92.052392 -241.40384) (xy 92.06844 -241.354447)
			(xy 92.092018 -241.308173) (xy 92.122544 -241.266157) (xy 92.159267 -241.229434) (xy 92.201283 -241.198908)
			(xy 92.247557 -241.17533) (xy 92.29695 -241.159282) (xy 92.348245 -241.151157) (xy 92.400179 -241.151157)
			(xy 92.451474 -241.159282) (xy 92.500867 -241.17533) (xy 92.547141 -241.198908) (xy 92.589157 -241.229434)
			(xy 92.62588 -241.266157) (xy 92.656406 -241.308173) (xy 92.679984 -241.354447) (xy 92.696032 -241.40384)
			(xy 92.704157 -241.455135) (xy 92.704666 -241.481102) (xy 92.704157 -241.507069) (xy 92.984067 -241.507069)
			(xy 92.984067 -241.455135) (xy 92.992192 -241.40384) (xy 93.00824 -241.354447) (xy 93.031818 -241.308173)
			(xy 93.062344 -241.266157) (xy 93.099067 -241.229434) (xy 93.141083 -241.198908) (xy 93.187357 -241.17533)
			(xy 93.23675 -241.159282) (xy 93.288045 -241.151157) (xy 93.339979 -241.151157) (xy 93.391274 -241.159282)
			(xy 93.440667 -241.17533) (xy 93.486941 -241.198908) (xy 93.528957 -241.229434) (xy 93.56568 -241.266157)
			(xy 93.596206 -241.308173) (xy 93.619784 -241.354447) (xy 93.635832 -241.40384) (xy 93.643957 -241.455135)
			(xy 93.644466 -241.481102) (xy 93.643957 -241.507069) (xy 93.924121 -241.507069) (xy 93.924121 -241.455135)
			(xy 93.932246 -241.40384) (xy 93.948294 -241.354447) (xy 93.971872 -241.308173) (xy 94.002398 -241.266157)
			(xy 94.039121 -241.229434) (xy 94.081137 -241.198908) (xy 94.127411 -241.17533) (xy 94.176804 -241.159282)
			(xy 94.228099 -241.151157) (xy 94.280033 -241.151157) (xy 94.331328 -241.159282) (xy 94.380721 -241.17533)
			(xy 94.426995 -241.198908) (xy 94.469011 -241.229434) (xy 94.505734 -241.266157) (xy 94.53626 -241.308173)
			(xy 94.559838 -241.354447) (xy 94.575886 -241.40384) (xy 94.584011 -241.455135) (xy 94.58452 -241.481102)
			(xy 94.584011 -241.507069) (xy 94.863667 -241.507069) (xy 94.863667 -241.455135) (xy 94.871792 -241.40384)
			(xy 94.88784 -241.354447) (xy 94.911418 -241.308173) (xy 94.941944 -241.266157) (xy 94.978667 -241.229434)
			(xy 95.020683 -241.198908) (xy 95.066957 -241.17533) (xy 95.11635 -241.159282) (xy 95.167645 -241.151157)
			(xy 95.219579 -241.151157) (xy 95.270874 -241.159282) (xy 95.320267 -241.17533) (xy 95.366541 -241.198908)
			(xy 95.408557 -241.229434) (xy 95.44528 -241.266157) (xy 95.475806 -241.308173) (xy 95.499384 -241.354447)
			(xy 95.515432 -241.40384) (xy 95.523557 -241.455135) (xy 95.524066 -241.481102) (xy 95.523557 -241.507069)
			(xy 95.803467 -241.507069) (xy 95.803467 -241.455135) (xy 95.811592 -241.40384) (xy 95.82764 -241.354447)
			(xy 95.851218 -241.308173) (xy 95.881744 -241.266157) (xy 95.918467 -241.229434) (xy 95.960483 -241.198908)
			(xy 96.006757 -241.17533) (xy 96.05615 -241.159282) (xy 96.107445 -241.151157) (xy 96.159379 -241.151157)
			(xy 96.210674 -241.159282) (xy 96.260067 -241.17533) (xy 96.306341 -241.198908) (xy 96.348357 -241.229434)
			(xy 96.38508 -241.266157) (xy 96.415606 -241.308173) (xy 96.439184 -241.354447) (xy 96.455232 -241.40384)
			(xy 96.463357 -241.455135) (xy 96.463866 -241.481102) (xy 96.463357 -241.507069) (xy 96.743267 -241.507069)
			(xy 96.743267 -241.455135) (xy 96.751392 -241.40384) (xy 96.76744 -241.354447) (xy 96.791018 -241.308173)
			(xy 96.821544 -241.266157) (xy 96.858267 -241.229434) (xy 96.900283 -241.198908) (xy 96.946557 -241.17533)
			(xy 96.99595 -241.159282) (xy 97.047245 -241.151157) (xy 97.099179 -241.151157) (xy 97.150474 -241.159282)
			(xy 97.199867 -241.17533) (xy 97.246141 -241.198908) (xy 97.288157 -241.229434) (xy 97.32488 -241.266157)
			(xy 97.355406 -241.308173) (xy 97.378984 -241.354447) (xy 97.395032 -241.40384) (xy 97.403157 -241.455135)
			(xy 97.403666 -241.481102) (xy 97.403157 -241.507069) (xy 97.683067 -241.507069) (xy 97.683067 -241.455135)
			(xy 97.691192 -241.40384) (xy 97.70724 -241.354447) (xy 97.730818 -241.308173) (xy 97.761344 -241.266157)
			(xy 97.798067 -241.229434) (xy 97.840083 -241.198908) (xy 97.886357 -241.17533) (xy 97.93575 -241.159282)
			(xy 97.987045 -241.151157) (xy 98.038979 -241.151157) (xy 98.090274 -241.159282) (xy 98.139667 -241.17533)
			(xy 98.185941 -241.198908) (xy 98.227957 -241.229434) (xy 98.26468 -241.266157) (xy 98.295206 -241.308173)
			(xy 98.318784 -241.354447) (xy 98.334832 -241.40384) (xy 98.342957 -241.455135) (xy 98.343466 -241.481102)
			(xy 98.342957 -241.507069) (xy 98.622867 -241.507069) (xy 98.622867 -241.455135) (xy 98.630992 -241.40384)
			(xy 98.64704 -241.354447) (xy 98.670618 -241.308173) (xy 98.701144 -241.266157) (xy 98.737867 -241.229434)
			(xy 98.779883 -241.198908) (xy 98.826157 -241.17533) (xy 98.87555 -241.159282) (xy 98.926845 -241.151157)
			(xy 98.978779 -241.151157) (xy 99.030074 -241.159282) (xy 99.079467 -241.17533) (xy 99.125741 -241.198908)
			(xy 99.167757 -241.229434) (xy 99.20448 -241.266157) (xy 99.235006 -241.308173) (xy 99.258584 -241.354447)
			(xy 99.274632 -241.40384) (xy 99.282757 -241.455135) (xy 99.283266 -241.481102) (xy 99.282757 -241.507069)
			(xy 99.562667 -241.507069) (xy 99.562667 -241.455135) (xy 99.570792 -241.40384) (xy 99.58684 -241.354447)
			(xy 99.610418 -241.308173) (xy 99.640944 -241.266157) (xy 99.677667 -241.229434) (xy 99.719683 -241.198908)
			(xy 99.765957 -241.17533) (xy 99.81535 -241.159282) (xy 99.866645 -241.151157) (xy 99.918579 -241.151157)
			(xy 99.969874 -241.159282) (xy 100.019267 -241.17533) (xy 100.065541 -241.198908) (xy 100.107557 -241.229434)
			(xy 100.14428 -241.266157) (xy 100.174806 -241.308173) (xy 100.198384 -241.354447) (xy 100.214432 -241.40384)
			(xy 100.222557 -241.455135) (xy 100.223066 -241.481102) (xy 100.222557 -241.507069) (xy 100.502721 -241.507069)
			(xy 100.502721 -241.455135) (xy 100.510846 -241.40384) (xy 100.526894 -241.354447) (xy 100.550472 -241.308173)
			(xy 100.580998 -241.266157) (xy 100.617721 -241.229434) (xy 100.659737 -241.198908) (xy 100.706011 -241.17533)
			(xy 100.755404 -241.159282) (xy 100.806699 -241.151157) (xy 100.858633 -241.151157) (xy 100.909928 -241.159282)
			(xy 100.959321 -241.17533) (xy 101.005595 -241.198908) (xy 101.047611 -241.229434) (xy 101.084334 -241.266157)
			(xy 101.11486 -241.308173) (xy 101.138438 -241.354447) (xy 101.154486 -241.40384) (xy 101.162611 -241.455135)
			(xy 101.16312 -241.481102) (xy 101.162611 -241.507069) (xy 101.442775 -241.507069) (xy 101.442775 -241.455135)
			(xy 101.4509 -241.40384) (xy 101.466948 -241.354447) (xy 101.490526 -241.308173) (xy 101.521052 -241.266157)
			(xy 101.557775 -241.229434) (xy 101.599791 -241.198908) (xy 101.646065 -241.17533) (xy 101.695458 -241.159282)
			(xy 101.746753 -241.151157) (xy 101.798687 -241.151157) (xy 101.849982 -241.159282) (xy 101.899375 -241.17533)
			(xy 101.945649 -241.198908) (xy 101.987665 -241.229434) (xy 102.024388 -241.266157) (xy 102.054914 -241.308173)
			(xy 102.078492 -241.354447) (xy 102.09454 -241.40384) (xy 102.102665 -241.455135) (xy 102.103174 -241.481102)
			(xy 102.102665 -241.507069) (xy 102.102625 -241.507323) (xy 108.961175 -241.507323) (xy 108.961175 -241.455389)
			(xy 108.9693 -241.404094) (xy 108.985348 -241.354701) (xy 109.008926 -241.308427) (xy 109.039452 -241.266411)
			(xy 109.076175 -241.229688) (xy 109.118191 -241.199162) (xy 109.164465 -241.175584) (xy 109.213858 -241.159536)
			(xy 109.265153 -241.151411) (xy 109.317087 -241.151411) (xy 109.368382 -241.159536) (xy 109.417775 -241.175584)
			(xy 109.464049 -241.199162) (xy 109.506065 -241.229688) (xy 109.542788 -241.266411) (xy 109.573314 -241.308427)
			(xy 109.596892 -241.354701) (xy 109.61294 -241.404094) (xy 109.621065 -241.455389) (xy 109.621574 -241.481356)
			(xy 109.621065 -241.507323) (xy 109.900975 -241.507323) (xy 109.900975 -241.455389) (xy 109.9091 -241.404094)
			(xy 109.925148 -241.354701) (xy 109.948726 -241.308427) (xy 109.979252 -241.266411) (xy 110.015975 -241.229688)
			(xy 110.057991 -241.199162) (xy 110.104265 -241.175584) (xy 110.153658 -241.159536) (xy 110.204953 -241.151411)
			(xy 110.256887 -241.151411) (xy 110.308182 -241.159536) (xy 110.357575 -241.175584) (xy 110.403849 -241.199162)
			(xy 110.445865 -241.229688) (xy 110.482588 -241.266411) (xy 110.513114 -241.308427) (xy 110.536692 -241.354701)
			(xy 110.55274 -241.404094) (xy 110.560865 -241.455389) (xy 110.561374 -241.481356) (xy 110.560865 -241.507323)
			(xy 110.840775 -241.507323) (xy 110.840775 -241.455389) (xy 110.8489 -241.404094) (xy 110.864948 -241.354701)
			(xy 110.888526 -241.308427) (xy 110.919052 -241.266411) (xy 110.955775 -241.229688) (xy 110.997791 -241.199162)
			(xy 111.044065 -241.175584) (xy 111.093458 -241.159536) (xy 111.144753 -241.151411) (xy 111.196687 -241.151411)
			(xy 111.247982 -241.159536) (xy 111.297375 -241.175584) (xy 111.343649 -241.199162) (xy 111.385665 -241.229688)
			(xy 111.422388 -241.266411) (xy 111.452914 -241.308427) (xy 111.476492 -241.354701) (xy 111.49254 -241.404094)
			(xy 111.500665 -241.455389) (xy 111.501174 -241.481356) (xy 111.500665 -241.507323) (xy 111.780575 -241.507323)
			(xy 111.780575 -241.455389) (xy 111.7887 -241.404094) (xy 111.804748 -241.354701) (xy 111.828326 -241.308427)
			(xy 111.858852 -241.266411) (xy 111.895575 -241.229688) (xy 111.937591 -241.199162) (xy 111.983865 -241.175584)
			(xy 112.033258 -241.159536) (xy 112.084553 -241.151411) (xy 112.136487 -241.151411) (xy 112.187782 -241.159536)
			(xy 112.237175 -241.175584) (xy 112.283449 -241.199162) (xy 112.325465 -241.229688) (xy 112.362188 -241.266411)
			(xy 112.392714 -241.308427) (xy 112.416292 -241.354701) (xy 112.43234 -241.404094) (xy 112.440465 -241.455389)
			(xy 112.440974 -241.481356) (xy 112.440465 -241.507323) (xy 112.720121 -241.507323) (xy 112.720121 -241.455389)
			(xy 112.728246 -241.404094) (xy 112.744294 -241.354701) (xy 112.767872 -241.308427) (xy 112.798398 -241.266411)
			(xy 112.835121 -241.229688) (xy 112.877137 -241.199162) (xy 112.923411 -241.175584) (xy 112.972804 -241.159536)
			(xy 113.024099 -241.151411) (xy 113.076033 -241.151411) (xy 113.127328 -241.159536) (xy 113.176721 -241.175584)
			(xy 113.222995 -241.199162) (xy 113.265011 -241.229688) (xy 113.301734 -241.266411) (xy 113.33226 -241.308427)
			(xy 113.355838 -241.354701) (xy 113.371886 -241.404094) (xy 113.380011 -241.455389) (xy 113.38052 -241.481356)
			(xy 113.380011 -241.507323) (xy 113.660175 -241.507323) (xy 113.660175 -241.455389) (xy 113.6683 -241.404094)
			(xy 113.684348 -241.354701) (xy 113.707926 -241.308427) (xy 113.738452 -241.266411) (xy 113.775175 -241.229688)
			(xy 113.817191 -241.199162) (xy 113.863465 -241.175584) (xy 113.912858 -241.159536) (xy 113.964153 -241.151411)
			(xy 114.016087 -241.151411) (xy 114.067382 -241.159536) (xy 114.116775 -241.175584) (xy 114.163049 -241.199162)
			(xy 114.205065 -241.229688) (xy 114.241788 -241.266411) (xy 114.272314 -241.308427) (xy 114.295892 -241.354701)
			(xy 114.31194 -241.404094) (xy 114.320065 -241.455389) (xy 114.320574 -241.481356) (xy 114.320065 -241.507323)
			(xy 114.31194 -241.558618) (xy 114.295892 -241.608011) (xy 114.272314 -241.654285) (xy 114.264162 -241.665506)
			(xy 115.092988 -241.665506) (xy 115.092988 -241.665252) (xy 115.093414 -241.640724) (xy 115.100684 -241.592211)
			(xy 115.115041 -241.545303) (xy 115.136172 -241.501032) (xy 115.163612 -241.460369) (xy 115.179856 -241.441986)
			(xy 115.189655 -241.430493) (xy 115.202672 -241.403258) (xy 115.207143 -241.373404) (xy 115.202675 -241.343551)
			(xy 115.18966 -241.316314) (xy 115.179856 -241.304826) (xy 115.163613 -241.286442) (xy 115.136165 -241.245785)
			(xy 115.115033 -241.201514) (xy 115.100684 -241.154604) (xy 115.093433 -241.106088) (xy 115.092988 -241.08156)
			(xy 115.092988 -241.081306) (xy 115.093497 -241.055339) (xy 115.101622 -241.004044) (xy 115.11767 -240.954651)
			(xy 115.141248 -240.908377) (xy 115.171774 -240.866361) (xy 115.208497 -240.829638) (xy 115.250513 -240.799112)
			(xy 115.296787 -240.775534) (xy 115.34618 -240.759486) (xy 115.397475 -240.751361) (xy 115.449409 -240.751361)
			(xy 115.500704 -240.759486) (xy 115.550097 -240.775534) (xy 115.596371 -240.799112) (xy 115.638387 -240.829638)
			(xy 115.67511 -240.866361) (xy 115.705636 -240.908377) (xy 115.729214 -240.954651) (xy 115.745262 -241.004044)
			(xy 115.753387 -241.055339) (xy 115.753896 -241.081306) (xy 115.753896 -241.08156) (xy 115.753421 -241.106086)
			(xy 115.746164 -241.154598) (xy 115.731818 -241.201505) (xy 115.710698 -241.245777) (xy 115.683268 -241.286442)
			(xy 115.667028 -241.304826) (xy 115.657218 -241.31631) (xy 115.644205 -241.343549) (xy 115.639737 -241.373404)
			(xy 115.644208 -241.403259) (xy 115.657223 -241.430497) (xy 115.667028 -241.441986) (xy 115.683291 -241.460353)
			(xy 115.710733 -241.501017) (xy 115.713621 -241.507069) (xy 121.178067 -241.507069) (xy 121.178067 -241.455135)
			(xy 121.186192 -241.40384) (xy 121.20224 -241.354447) (xy 121.225818 -241.308173) (xy 121.256344 -241.266157)
			(xy 121.293067 -241.229434) (xy 121.335083 -241.198908) (xy 121.381357 -241.17533) (xy 121.43075 -241.159282)
			(xy 121.482045 -241.151157) (xy 121.533979 -241.151157) (xy 121.585274 -241.159282) (xy 121.634667 -241.17533)
			(xy 121.680941 -241.198908) (xy 121.722957 -241.229434) (xy 121.75968 -241.266157) (xy 121.790206 -241.308173)
			(xy 121.813784 -241.354447) (xy 121.829832 -241.40384) (xy 121.837957 -241.455135) (xy 121.838466 -241.481102)
			(xy 121.837957 -241.507069) (xy 122.118121 -241.507069) (xy 122.118121 -241.455135) (xy 122.126246 -241.40384)
			(xy 122.142294 -241.354447) (xy 122.165872 -241.308173) (xy 122.196398 -241.266157) (xy 122.233121 -241.229434)
			(xy 122.275137 -241.198908) (xy 122.321411 -241.17533) (xy 122.370804 -241.159282) (xy 122.422099 -241.151157)
			(xy 122.474033 -241.151157) (xy 122.525328 -241.159282) (xy 122.574721 -241.17533) (xy 122.620995 -241.198908)
			(xy 122.663011 -241.229434) (xy 122.699734 -241.266157) (xy 122.73026 -241.308173) (xy 122.753838 -241.354447)
			(xy 122.769886 -241.40384) (xy 122.778011 -241.455135) (xy 122.77852 -241.481102) (xy 122.778011 -241.507069)
			(xy 123.057667 -241.507069) (xy 123.057667 -241.455135) (xy 123.065792 -241.40384) (xy 123.08184 -241.354447)
			(xy 123.105418 -241.308173) (xy 123.135944 -241.266157) (xy 123.172667 -241.229434) (xy 123.214683 -241.198908)
			(xy 123.260957 -241.17533) (xy 123.31035 -241.159282) (xy 123.361645 -241.151157) (xy 123.413579 -241.151157)
			(xy 123.464874 -241.159282) (xy 123.514267 -241.17533) (xy 123.560541 -241.198908) (xy 123.602557 -241.229434)
			(xy 123.63928 -241.266157) (xy 123.669806 -241.308173) (xy 123.693384 -241.354447) (xy 123.709432 -241.40384)
			(xy 123.717557 -241.455135) (xy 123.718066 -241.481102) (xy 123.717557 -241.507069) (xy 123.997467 -241.507069)
			(xy 123.997467 -241.455135) (xy 124.005592 -241.40384) (xy 124.02164 -241.354447) (xy 124.045218 -241.308173)
			(xy 124.075744 -241.266157) (xy 124.112467 -241.229434) (xy 124.154483 -241.198908) (xy 124.200757 -241.17533)
			(xy 124.25015 -241.159282) (xy 124.301445 -241.151157) (xy 124.353379 -241.151157) (xy 124.404674 -241.159282)
			(xy 124.454067 -241.17533) (xy 124.500341 -241.198908) (xy 124.542357 -241.229434) (xy 124.57908 -241.266157)
			(xy 124.609606 -241.308173) (xy 124.633184 -241.354447) (xy 124.649232 -241.40384) (xy 124.657357 -241.455135)
			(xy 124.657866 -241.481102) (xy 124.657357 -241.507069) (xy 124.937267 -241.507069) (xy 124.937267 -241.455135)
			(xy 124.945392 -241.40384) (xy 124.96144 -241.354447) (xy 124.985018 -241.308173) (xy 125.015544 -241.266157)
			(xy 125.052267 -241.229434) (xy 125.094283 -241.198908) (xy 125.140557 -241.17533) (xy 125.18995 -241.159282)
			(xy 125.241245 -241.151157) (xy 125.293179 -241.151157) (xy 125.344474 -241.159282) (xy 125.393867 -241.17533)
			(xy 125.440141 -241.198908) (xy 125.482157 -241.229434) (xy 125.51888 -241.266157) (xy 125.549406 -241.308173)
			(xy 125.572984 -241.354447) (xy 125.589032 -241.40384) (xy 125.597157 -241.455135) (xy 125.597666 -241.481102)
			(xy 125.597157 -241.507069) (xy 125.877067 -241.507069) (xy 125.877067 -241.455135) (xy 125.885192 -241.40384)
			(xy 125.90124 -241.354447) (xy 125.924818 -241.308173) (xy 125.955344 -241.266157) (xy 125.992067 -241.229434)
			(xy 126.034083 -241.198908) (xy 126.080357 -241.17533) (xy 126.12975 -241.159282) (xy 126.181045 -241.151157)
			(xy 126.232979 -241.151157) (xy 126.284274 -241.159282) (xy 126.333667 -241.17533) (xy 126.379941 -241.198908)
			(xy 126.421957 -241.229434) (xy 126.45868 -241.266157) (xy 126.489206 -241.308173) (xy 126.512784 -241.354447)
			(xy 126.528832 -241.40384) (xy 126.536957 -241.455135) (xy 126.537466 -241.481102) (xy 126.536957 -241.507069)
			(xy 126.816867 -241.507069) (xy 126.816867 -241.455135) (xy 126.824992 -241.40384) (xy 126.84104 -241.354447)
			(xy 126.864618 -241.308173) (xy 126.895144 -241.266157) (xy 126.931867 -241.229434) (xy 126.973883 -241.198908)
			(xy 127.020157 -241.17533) (xy 127.06955 -241.159282) (xy 127.120845 -241.151157) (xy 127.172779 -241.151157)
			(xy 127.224074 -241.159282) (xy 127.273467 -241.17533) (xy 127.319741 -241.198908) (xy 127.361757 -241.229434)
			(xy 127.39848 -241.266157) (xy 127.429006 -241.308173) (xy 127.452584 -241.354447) (xy 127.468632 -241.40384)
			(xy 127.476757 -241.455135) (xy 127.477266 -241.481102) (xy 127.476757 -241.507069) (xy 127.756667 -241.507069)
			(xy 127.756667 -241.455135) (xy 127.764792 -241.40384) (xy 127.78084 -241.354447) (xy 127.804418 -241.308173)
			(xy 127.834944 -241.266157) (xy 127.871667 -241.229434) (xy 127.913683 -241.198908) (xy 127.959957 -241.17533)
			(xy 128.00935 -241.159282) (xy 128.060645 -241.151157) (xy 128.112579 -241.151157) (xy 128.163874 -241.159282)
			(xy 128.213267 -241.17533) (xy 128.259541 -241.198908) (xy 128.301557 -241.229434) (xy 128.33828 -241.266157)
			(xy 128.368806 -241.308173) (xy 128.392384 -241.354447) (xy 128.408432 -241.40384) (xy 128.416557 -241.455135)
			(xy 128.417066 -241.481102) (xy 128.416557 -241.507069) (xy 128.696721 -241.507069) (xy 128.696721 -241.455135)
			(xy 128.704846 -241.40384) (xy 128.720894 -241.354447) (xy 128.744472 -241.308173) (xy 128.774998 -241.266157)
			(xy 128.811721 -241.229434) (xy 128.853737 -241.198908) (xy 128.900011 -241.17533) (xy 128.949404 -241.159282)
			(xy 129.000699 -241.151157) (xy 129.052633 -241.151157) (xy 129.103928 -241.159282) (xy 129.153321 -241.17533)
			(xy 129.199595 -241.198908) (xy 129.241611 -241.229434) (xy 129.278334 -241.266157) (xy 129.30886 -241.308173)
			(xy 129.332438 -241.354447) (xy 129.348486 -241.40384) (xy 129.356611 -241.455135) (xy 129.35712 -241.481102)
			(xy 129.356611 -241.507069) (xy 129.636267 -241.507069) (xy 129.636267 -241.455135) (xy 129.644392 -241.40384)
			(xy 129.66044 -241.354447) (xy 129.684018 -241.308173) (xy 129.714544 -241.266157) (xy 129.751267 -241.229434)
			(xy 129.793283 -241.198908) (xy 129.839557 -241.17533) (xy 129.88895 -241.159282) (xy 129.940245 -241.151157)
			(xy 129.992179 -241.151157) (xy 130.043474 -241.159282) (xy 130.092867 -241.17533) (xy 130.139141 -241.198908)
			(xy 130.181157 -241.229434) (xy 130.21788 -241.266157) (xy 130.248406 -241.308173) (xy 130.271984 -241.354447)
			(xy 130.288032 -241.40384) (xy 130.296157 -241.455135) (xy 130.296666 -241.481102) (xy 130.296157 -241.507069)
			(xy 130.576067 -241.507069) (xy 130.576067 -241.455135) (xy 130.584192 -241.40384) (xy 130.60024 -241.354447)
			(xy 130.623818 -241.308173) (xy 130.654344 -241.266157) (xy 130.691067 -241.229434) (xy 130.733083 -241.198908)
			(xy 130.779357 -241.17533) (xy 130.82875 -241.159282) (xy 130.880045 -241.151157) (xy 130.931979 -241.151157)
			(xy 130.983274 -241.159282) (xy 131.032667 -241.17533) (xy 131.078941 -241.198908) (xy 131.120957 -241.229434)
			(xy 131.15768 -241.266157) (xy 131.188206 -241.308173) (xy 131.211784 -241.354447) (xy 131.227832 -241.40384)
			(xy 131.235957 -241.455135) (xy 131.236466 -241.481102) (xy 131.235957 -241.507069) (xy 131.227832 -241.558364)
			(xy 131.211784 -241.607757) (xy 131.188206 -241.654031) (xy 131.15768 -241.696047) (xy 131.120957 -241.73277)
			(xy 131.078941 -241.763296) (xy 131.032667 -241.786874) (xy 130.983274 -241.802922) (xy 130.931979 -241.811047)
			(xy 130.880045 -241.811047) (xy 130.82875 -241.802922) (xy 130.779357 -241.786874) (xy 130.733083 -241.763296)
			(xy 130.691067 -241.73277) (xy 130.654344 -241.696047) (xy 130.623818 -241.654031) (xy 130.60024 -241.607757)
			(xy 130.584192 -241.558364) (xy 130.576067 -241.507069) (xy 130.296157 -241.507069) (xy 130.288032 -241.558364)
			(xy 130.271984 -241.607757) (xy 130.248406 -241.654031) (xy 130.21788 -241.696047) (xy 130.181157 -241.73277)
			(xy 130.139141 -241.763296) (xy 130.092867 -241.786874) (xy 130.043474 -241.802922) (xy 129.992179 -241.811047)
			(xy 129.940245 -241.811047) (xy 129.88895 -241.802922) (xy 129.839557 -241.786874) (xy 129.793283 -241.763296)
			(xy 129.751267 -241.73277) (xy 129.714544 -241.696047) (xy 129.684018 -241.654031) (xy 129.66044 -241.607757)
			(xy 129.644392 -241.558364) (xy 129.636267 -241.507069) (xy 129.356611 -241.507069) (xy 129.348486 -241.558364)
			(xy 129.332438 -241.607757) (xy 129.30886 -241.654031) (xy 129.278334 -241.696047) (xy 129.241611 -241.73277)
			(xy 129.199595 -241.763296) (xy 129.153321 -241.786874) (xy 129.103928 -241.802922) (xy 129.052633 -241.811047)
			(xy 129.000699 -241.811047) (xy 128.949404 -241.802922) (xy 128.900011 -241.786874) (xy 128.853737 -241.763296)
			(xy 128.811721 -241.73277) (xy 128.774998 -241.696047) (xy 128.744472 -241.654031) (xy 128.720894 -241.607757)
			(xy 128.704846 -241.558364) (xy 128.696721 -241.507069) (xy 128.416557 -241.507069) (xy 128.408432 -241.558364)
			(xy 128.392384 -241.607757) (xy 128.368806 -241.654031) (xy 128.33828 -241.696047) (xy 128.301557 -241.73277)
			(xy 128.259541 -241.763296) (xy 128.213267 -241.786874) (xy 128.163874 -241.802922) (xy 128.112579 -241.811047)
			(xy 128.060645 -241.811047) (xy 128.00935 -241.802922) (xy 127.959957 -241.786874) (xy 127.913683 -241.763296)
			(xy 127.871667 -241.73277) (xy 127.834944 -241.696047) (xy 127.804418 -241.654031) (xy 127.78084 -241.607757)
			(xy 127.764792 -241.558364) (xy 127.756667 -241.507069) (xy 127.476757 -241.507069) (xy 127.468632 -241.558364)
			(xy 127.452584 -241.607757) (xy 127.429006 -241.654031) (xy 127.39848 -241.696047) (xy 127.361757 -241.73277)
			(xy 127.319741 -241.763296) (xy 127.273467 -241.786874) (xy 127.224074 -241.802922) (xy 127.172779 -241.811047)
			(xy 127.120845 -241.811047) (xy 127.06955 -241.802922) (xy 127.020157 -241.786874) (xy 126.973883 -241.763296)
			(xy 126.931867 -241.73277) (xy 126.895144 -241.696047) (xy 126.864618 -241.654031) (xy 126.84104 -241.607757)
			(xy 126.824992 -241.558364) (xy 126.816867 -241.507069) (xy 126.536957 -241.507069) (xy 126.528832 -241.558364)
			(xy 126.512784 -241.607757) (xy 126.489206 -241.654031) (xy 126.45868 -241.696047) (xy 126.421957 -241.73277)
			(xy 126.379941 -241.763296) (xy 126.333667 -241.786874) (xy 126.284274 -241.802922) (xy 126.232979 -241.811047)
			(xy 126.181045 -241.811047) (xy 126.12975 -241.802922) (xy 126.080357 -241.786874) (xy 126.034083 -241.763296)
			(xy 125.992067 -241.73277) (xy 125.955344 -241.696047) (xy 125.924818 -241.654031) (xy 125.90124 -241.607757)
			(xy 125.885192 -241.558364) (xy 125.877067 -241.507069) (xy 125.597157 -241.507069) (xy 125.589032 -241.558364)
			(xy 125.572984 -241.607757) (xy 125.549406 -241.654031) (xy 125.51888 -241.696047) (xy 125.482157 -241.73277)
			(xy 125.440141 -241.763296) (xy 125.393867 -241.786874) (xy 125.344474 -241.802922) (xy 125.293179 -241.811047)
			(xy 125.241245 -241.811047) (xy 125.18995 -241.802922) (xy 125.140557 -241.786874) (xy 125.094283 -241.763296)
			(xy 125.052267 -241.73277) (xy 125.015544 -241.696047) (xy 124.985018 -241.654031) (xy 124.96144 -241.607757)
			(xy 124.945392 -241.558364) (xy 124.937267 -241.507069) (xy 124.657357 -241.507069) (xy 124.649232 -241.558364)
			(xy 124.633184 -241.607757) (xy 124.609606 -241.654031) (xy 124.57908 -241.696047) (xy 124.542357 -241.73277)
			(xy 124.500341 -241.763296) (xy 124.454067 -241.786874) (xy 124.404674 -241.802922) (xy 124.353379 -241.811047)
			(xy 124.301445 -241.811047) (xy 124.25015 -241.802922) (xy 124.200757 -241.786874) (xy 124.154483 -241.763296)
			(xy 124.112467 -241.73277) (xy 124.075744 -241.696047) (xy 124.045218 -241.654031) (xy 124.02164 -241.607757)
			(xy 124.005592 -241.558364) (xy 123.997467 -241.507069) (xy 123.717557 -241.507069) (xy 123.709432 -241.558364)
			(xy 123.693384 -241.607757) (xy 123.669806 -241.654031) (xy 123.63928 -241.696047) (xy 123.602557 -241.73277)
			(xy 123.560541 -241.763296) (xy 123.514267 -241.786874) (xy 123.464874 -241.802922) (xy 123.413579 -241.811047)
			(xy 123.361645 -241.811047) (xy 123.31035 -241.802922) (xy 123.260957 -241.786874) (xy 123.214683 -241.763296)
			(xy 123.172667 -241.73277) (xy 123.135944 -241.696047) (xy 123.105418 -241.654031) (xy 123.08184 -241.607757)
			(xy 123.065792 -241.558364) (xy 123.057667 -241.507069) (xy 122.778011 -241.507069) (xy 122.769886 -241.558364)
			(xy 122.753838 -241.607757) (xy 122.73026 -241.654031) (xy 122.699734 -241.696047) (xy 122.663011 -241.73277)
			(xy 122.620995 -241.763296) (xy 122.574721 -241.786874) (xy 122.525328 -241.802922) (xy 122.474033 -241.811047)
			(xy 122.422099 -241.811047) (xy 122.370804 -241.802922) (xy 122.321411 -241.786874) (xy 122.275137 -241.763296)
			(xy 122.233121 -241.73277) (xy 122.196398 -241.696047) (xy 122.165872 -241.654031) (xy 122.142294 -241.607757)
			(xy 122.126246 -241.558364) (xy 122.118121 -241.507069) (xy 121.837957 -241.507069) (xy 121.829832 -241.558364)
			(xy 121.813784 -241.607757) (xy 121.790206 -241.654031) (xy 121.75968 -241.696047) (xy 121.722957 -241.73277)
			(xy 121.680941 -241.763296) (xy 121.634667 -241.786874) (xy 121.585274 -241.802922) (xy 121.533979 -241.811047)
			(xy 121.482045 -241.811047) (xy 121.43075 -241.802922) (xy 121.381357 -241.786874) (xy 121.335083 -241.763296)
			(xy 121.293067 -241.73277) (xy 121.256344 -241.696047) (xy 121.225818 -241.654031) (xy 121.20224 -241.607757)
			(xy 121.186192 -241.558364) (xy 121.178067 -241.507069) (xy 115.713621 -241.507069) (xy 115.731859 -241.545292)
			(xy 115.746204 -241.592205) (xy 115.753452 -241.640723) (xy 115.753896 -241.665252) (xy 115.753896 -241.665506)
			(xy 115.753387 -241.691473) (xy 115.745262 -241.742768) (xy 115.729214 -241.792161) (xy 115.705636 -241.838435)
			(xy 115.67511 -241.880451) (xy 115.638387 -241.917174) (xy 115.596371 -241.9477) (xy 115.550097 -241.971278)
			(xy 115.500704 -241.987326) (xy 115.449409 -241.995451) (xy 115.397475 -241.995451) (xy 115.34618 -241.987326)
			(xy 115.296787 -241.971278) (xy 115.250513 -241.9477) (xy 115.208497 -241.917174) (xy 115.171774 -241.880451)
			(xy 115.141248 -241.838435) (xy 115.11767 -241.792161) (xy 115.101622 -241.742768) (xy 115.093497 -241.691473)
			(xy 115.092988 -241.665506) (xy 114.264162 -241.665506) (xy 114.241788 -241.696301) (xy 114.205065 -241.733024)
			(xy 114.163049 -241.76355) (xy 114.116775 -241.787128) (xy 114.067382 -241.803176) (xy 114.016087 -241.811301)
			(xy 113.964153 -241.811301) (xy 113.912858 -241.803176) (xy 113.863465 -241.787128) (xy 113.817191 -241.76355)
			(xy 113.775175 -241.733024) (xy 113.738452 -241.696301) (xy 113.707926 -241.654285) (xy 113.684348 -241.608011)
			(xy 113.6683 -241.558618) (xy 113.660175 -241.507323) (xy 113.380011 -241.507323) (xy 113.371886 -241.558618)
			(xy 113.355838 -241.608011) (xy 113.33226 -241.654285) (xy 113.301734 -241.696301) (xy 113.265011 -241.733024)
			(xy 113.222995 -241.76355) (xy 113.176721 -241.787128) (xy 113.127328 -241.803176) (xy 113.076033 -241.811301)
			(xy 113.024099 -241.811301) (xy 112.972804 -241.803176) (xy 112.923411 -241.787128) (xy 112.877137 -241.76355)
			(xy 112.835121 -241.733024) (xy 112.798398 -241.696301) (xy 112.767872 -241.654285) (xy 112.744294 -241.608011)
			(xy 112.728246 -241.558618) (xy 112.720121 -241.507323) (xy 112.440465 -241.507323) (xy 112.43234 -241.558618)
			(xy 112.416292 -241.608011) (xy 112.392714 -241.654285) (xy 112.362188 -241.696301) (xy 112.325465 -241.733024)
			(xy 112.283449 -241.76355) (xy 112.237175 -241.787128) (xy 112.187782 -241.803176) (xy 112.136487 -241.811301)
			(xy 112.084553 -241.811301) (xy 112.033258 -241.803176) (xy 111.983865 -241.787128) (xy 111.937591 -241.76355)
			(xy 111.895575 -241.733024) (xy 111.858852 -241.696301) (xy 111.828326 -241.654285) (xy 111.804748 -241.608011)
			(xy 111.7887 -241.558618) (xy 111.780575 -241.507323) (xy 111.500665 -241.507323) (xy 111.49254 -241.558618)
			(xy 111.476492 -241.608011) (xy 111.452914 -241.654285) (xy 111.422388 -241.696301) (xy 111.385665 -241.733024)
			(xy 111.343649 -241.76355) (xy 111.297375 -241.787128) (xy 111.247982 -241.803176) (xy 111.196687 -241.811301)
			(xy 111.144753 -241.811301) (xy 111.093458 -241.803176) (xy 111.044065 -241.787128) (xy 110.997791 -241.76355)
			(xy 110.955775 -241.733024) (xy 110.919052 -241.696301) (xy 110.888526 -241.654285) (xy 110.864948 -241.608011)
			(xy 110.8489 -241.558618) (xy 110.840775 -241.507323) (xy 110.560865 -241.507323) (xy 110.55274 -241.558618)
			(xy 110.536692 -241.608011) (xy 110.513114 -241.654285) (xy 110.482588 -241.696301) (xy 110.445865 -241.733024)
			(xy 110.403849 -241.76355) (xy 110.357575 -241.787128) (xy 110.308182 -241.803176) (xy 110.256887 -241.811301)
			(xy 110.204953 -241.811301) (xy 110.153658 -241.803176) (xy 110.104265 -241.787128) (xy 110.057991 -241.76355)
			(xy 110.015975 -241.733024) (xy 109.979252 -241.696301) (xy 109.948726 -241.654285) (xy 109.925148 -241.608011)
			(xy 109.9091 -241.558618) (xy 109.900975 -241.507323) (xy 109.621065 -241.507323) (xy 109.61294 -241.558618)
			(xy 109.596892 -241.608011) (xy 109.573314 -241.654285) (xy 109.542788 -241.696301) (xy 109.506065 -241.733024)
			(xy 109.464049 -241.76355) (xy 109.417775 -241.787128) (xy 109.368382 -241.803176) (xy 109.317087 -241.811301)
			(xy 109.265153 -241.811301) (xy 109.213858 -241.803176) (xy 109.164465 -241.787128) (xy 109.118191 -241.76355)
			(xy 109.076175 -241.733024) (xy 109.039452 -241.696301) (xy 109.008926 -241.654285) (xy 108.985348 -241.608011)
			(xy 108.9693 -241.558618) (xy 108.961175 -241.507323) (xy 102.102625 -241.507323) (xy 102.09454 -241.558364)
			(xy 102.078492 -241.607757) (xy 102.054914 -241.654031) (xy 102.024388 -241.696047) (xy 101.987665 -241.73277)
			(xy 101.945649 -241.763296) (xy 101.899375 -241.786874) (xy 101.849982 -241.802922) (xy 101.798687 -241.811047)
			(xy 101.746753 -241.811047) (xy 101.695458 -241.802922) (xy 101.646065 -241.786874) (xy 101.599791 -241.763296)
			(xy 101.557775 -241.73277) (xy 101.521052 -241.696047) (xy 101.490526 -241.654031) (xy 101.466948 -241.607757)
			(xy 101.4509 -241.558364) (xy 101.442775 -241.507069) (xy 101.162611 -241.507069) (xy 101.154486 -241.558364)
			(xy 101.138438 -241.607757) (xy 101.11486 -241.654031) (xy 101.084334 -241.696047) (xy 101.047611 -241.73277)
			(xy 101.005595 -241.763296) (xy 100.959321 -241.786874) (xy 100.909928 -241.802922) (xy 100.858633 -241.811047)
			(xy 100.806699 -241.811047) (xy 100.755404 -241.802922) (xy 100.706011 -241.786874) (xy 100.659737 -241.763296)
			(xy 100.617721 -241.73277) (xy 100.580998 -241.696047) (xy 100.550472 -241.654031) (xy 100.526894 -241.607757)
			(xy 100.510846 -241.558364) (xy 100.502721 -241.507069) (xy 100.222557 -241.507069) (xy 100.214432 -241.558364)
			(xy 100.198384 -241.607757) (xy 100.174806 -241.654031) (xy 100.14428 -241.696047) (xy 100.107557 -241.73277)
			(xy 100.065541 -241.763296) (xy 100.019267 -241.786874) (xy 99.969874 -241.802922) (xy 99.918579 -241.811047)
			(xy 99.866645 -241.811047) (xy 99.81535 -241.802922) (xy 99.765957 -241.786874) (xy 99.719683 -241.763296)
			(xy 99.677667 -241.73277) (xy 99.640944 -241.696047) (xy 99.610418 -241.654031) (xy 99.58684 -241.607757)
			(xy 99.570792 -241.558364) (xy 99.562667 -241.507069) (xy 99.282757 -241.507069) (xy 99.274632 -241.558364)
			(xy 99.258584 -241.607757) (xy 99.235006 -241.654031) (xy 99.20448 -241.696047) (xy 99.167757 -241.73277)
			(xy 99.125741 -241.763296) (xy 99.079467 -241.786874) (xy 99.030074 -241.802922) (xy 98.978779 -241.811047)
			(xy 98.926845 -241.811047) (xy 98.87555 -241.802922) (xy 98.826157 -241.786874) (xy 98.779883 -241.763296)
			(xy 98.737867 -241.73277) (xy 98.701144 -241.696047) (xy 98.670618 -241.654031) (xy 98.64704 -241.607757)
			(xy 98.630992 -241.558364) (xy 98.622867 -241.507069) (xy 98.342957 -241.507069) (xy 98.334832 -241.558364)
			(xy 98.318784 -241.607757) (xy 98.295206 -241.654031) (xy 98.26468 -241.696047) (xy 98.227957 -241.73277)
			(xy 98.185941 -241.763296) (xy 98.139667 -241.786874) (xy 98.090274 -241.802922) (xy 98.038979 -241.811047)
			(xy 97.987045 -241.811047) (xy 97.93575 -241.802922) (xy 97.886357 -241.786874) (xy 97.840083 -241.763296)
			(xy 97.798067 -241.73277) (xy 97.761344 -241.696047) (xy 97.730818 -241.654031) (xy 97.70724 -241.607757)
			(xy 97.691192 -241.558364) (xy 97.683067 -241.507069) (xy 97.403157 -241.507069) (xy 97.395032 -241.558364)
			(xy 97.378984 -241.607757) (xy 97.355406 -241.654031) (xy 97.32488 -241.696047) (xy 97.288157 -241.73277)
			(xy 97.246141 -241.763296) (xy 97.199867 -241.786874) (xy 97.150474 -241.802922) (xy 97.099179 -241.811047)
			(xy 97.047245 -241.811047) (xy 96.99595 -241.802922) (xy 96.946557 -241.786874) (xy 96.900283 -241.763296)
			(xy 96.858267 -241.73277) (xy 96.821544 -241.696047) (xy 96.791018 -241.654031) (xy 96.76744 -241.607757)
			(xy 96.751392 -241.558364) (xy 96.743267 -241.507069) (xy 96.463357 -241.507069) (xy 96.455232 -241.558364)
			(xy 96.439184 -241.607757) (xy 96.415606 -241.654031) (xy 96.38508 -241.696047) (xy 96.348357 -241.73277)
			(xy 96.306341 -241.763296) (xy 96.260067 -241.786874) (xy 96.210674 -241.802922) (xy 96.159379 -241.811047)
			(xy 96.107445 -241.811047) (xy 96.05615 -241.802922) (xy 96.006757 -241.786874) (xy 95.960483 -241.763296)
			(xy 95.918467 -241.73277) (xy 95.881744 -241.696047) (xy 95.851218 -241.654031) (xy 95.82764 -241.607757)
			(xy 95.811592 -241.558364) (xy 95.803467 -241.507069) (xy 95.523557 -241.507069) (xy 95.515432 -241.558364)
			(xy 95.499384 -241.607757) (xy 95.475806 -241.654031) (xy 95.44528 -241.696047) (xy 95.408557 -241.73277)
			(xy 95.366541 -241.763296) (xy 95.320267 -241.786874) (xy 95.270874 -241.802922) (xy 95.219579 -241.811047)
			(xy 95.167645 -241.811047) (xy 95.11635 -241.802922) (xy 95.066957 -241.786874) (xy 95.020683 -241.763296)
			(xy 94.978667 -241.73277) (xy 94.941944 -241.696047) (xy 94.911418 -241.654031) (xy 94.88784 -241.607757)
			(xy 94.871792 -241.558364) (xy 94.863667 -241.507069) (xy 94.584011 -241.507069) (xy 94.575886 -241.558364)
			(xy 94.559838 -241.607757) (xy 94.53626 -241.654031) (xy 94.505734 -241.696047) (xy 94.469011 -241.73277)
			(xy 94.426995 -241.763296) (xy 94.380721 -241.786874) (xy 94.331328 -241.802922) (xy 94.280033 -241.811047)
			(xy 94.228099 -241.811047) (xy 94.176804 -241.802922) (xy 94.127411 -241.786874) (xy 94.081137 -241.763296)
			(xy 94.039121 -241.73277) (xy 94.002398 -241.696047) (xy 93.971872 -241.654031) (xy 93.948294 -241.607757)
			(xy 93.932246 -241.558364) (xy 93.924121 -241.507069) (xy 93.643957 -241.507069) (xy 93.635832 -241.558364)
			(xy 93.619784 -241.607757) (xy 93.596206 -241.654031) (xy 93.56568 -241.696047) (xy 93.528957 -241.73277)
			(xy 93.486941 -241.763296) (xy 93.440667 -241.786874) (xy 93.391274 -241.802922) (xy 93.339979 -241.811047)
			(xy 93.288045 -241.811047) (xy 93.23675 -241.802922) (xy 93.187357 -241.786874) (xy 93.141083 -241.763296)
			(xy 93.099067 -241.73277) (xy 93.062344 -241.696047) (xy 93.031818 -241.654031) (xy 93.00824 -241.607757)
			(xy 92.992192 -241.558364) (xy 92.984067 -241.507069) (xy 92.704157 -241.507069) (xy 92.696032 -241.558364)
			(xy 92.679984 -241.607757) (xy 92.656406 -241.654031) (xy 92.62588 -241.696047) (xy 92.589157 -241.73277)
			(xy 92.547141 -241.763296) (xy 92.500867 -241.786874) (xy 92.451474 -241.802922) (xy 92.400179 -241.811047)
			(xy 92.348245 -241.811047) (xy 92.29695 -241.802922) (xy 92.247557 -241.786874) (xy 92.201283 -241.763296)
			(xy 92.159267 -241.73277) (xy 92.122544 -241.696047) (xy 92.092018 -241.654031) (xy 92.06844 -241.607757)
			(xy 92.052392 -241.558364) (xy 92.044267 -241.507069) (xy 91.76475 -241.507069) (xy 91.76475 -241.507625)
			(xy 91.756278 -241.559994) (xy 91.739551 -241.610337) (xy 91.714999 -241.657363) (xy 91.683253 -241.699865)
			(xy 91.645126 -241.736751) (xy 91.601598 -241.767074) (xy 91.577922 -241.779044) (xy 91.565222 -241.78514)
			(xy 91.53525 -241.830606) (xy 91.53525 -241.958368) (xy 91.535667 -241.967398) (xy 91.542107 -241.984274)
			(xy 91.554095 -241.997785) (xy 91.56192 -242.00231) (xy 91.604846 -242.022884) (xy 91.645232 -242.042442)
			(xy 91.650456 -242.044781) (xy 91.661609 -242.047334) (xy 91.66733 -242.047522) (xy 91.69781 -242.0366)
			(xy 91.70416 -242.031774) (xy 91.725907 -242.015892) (xy 91.773476 -241.990658) (xy 91.824503 -241.973459)
			(xy 91.877642 -241.96475) (xy 91.904566 -241.96421) (xy 91.930556 -241.964691) (xy 91.981895 -241.972817)
			(xy 92.031332 -241.988875) (xy 92.077647 -242.01247) (xy 92.119701 -242.04302) (xy 92.156458 -242.079773)
			(xy 92.187012 -242.121824) (xy 92.210612 -242.168137) (xy 92.226675 -242.217571) (xy 92.234807 -242.26891)
			(xy 92.234807 -242.320885) (xy 92.514421 -242.320885) (xy 92.514421 -242.268951) (xy 92.522546 -242.217656)
			(xy 92.538594 -242.168263) (xy 92.562172 -242.121989) (xy 92.592698 -242.079973) (xy 92.629421 -242.04325)
			(xy 92.671437 -242.012724) (xy 92.717711 -241.989146) (xy 92.767104 -241.973098) (xy 92.818399 -241.964973)
			(xy 92.870333 -241.964973) (xy 92.921628 -241.973098) (xy 92.971021 -241.989146) (xy 93.017295 -242.012724)
			(xy 93.059311 -242.04325) (xy 93.096034 -242.079973) (xy 93.12656 -242.121989) (xy 93.150138 -242.168263)
			(xy 93.166186 -242.217656) (xy 93.174311 -242.268951) (xy 93.17482 -242.294918) (xy 93.174311 -242.320885)
			(xy 93.454221 -242.320885) (xy 93.454221 -242.268951) (xy 93.462346 -242.217656) (xy 93.478394 -242.168263)
			(xy 93.501972 -242.121989) (xy 93.532498 -242.079973) (xy 93.569221 -242.04325) (xy 93.611237 -242.012724)
			(xy 93.657511 -241.989146) (xy 93.706904 -241.973098) (xy 93.758199 -241.964973) (xy 93.810133 -241.964973)
			(xy 93.861428 -241.973098) (xy 93.910821 -241.989146) (xy 93.957095 -242.012724) (xy 93.999111 -242.04325)
			(xy 94.035834 -242.079973) (xy 94.06636 -242.121989) (xy 94.089938 -242.168263) (xy 94.105986 -242.217656)
			(xy 94.114111 -242.268951) (xy 94.11462 -242.294918) (xy 94.114111 -242.320885) (xy 94.394021 -242.320885)
			(xy 94.394021 -242.268951) (xy 94.402146 -242.217656) (xy 94.418194 -242.168263) (xy 94.441772 -242.121989)
			(xy 94.472298 -242.079973) (xy 94.509021 -242.04325) (xy 94.551037 -242.012724) (xy 94.597311 -241.989146)
			(xy 94.646704 -241.973098) (xy 94.697999 -241.964973) (xy 94.749933 -241.964973) (xy 94.801228 -241.973098)
			(xy 94.850621 -241.989146) (xy 94.896895 -242.012724) (xy 94.938911 -242.04325) (xy 94.975634 -242.079973)
			(xy 95.00616 -242.121989) (xy 95.029738 -242.168263) (xy 95.045786 -242.217656) (xy 95.053911 -242.268951)
			(xy 95.05442 -242.294918) (xy 95.053911 -242.320885) (xy 95.333821 -242.320885) (xy 95.333821 -242.268951)
			(xy 95.341946 -242.217656) (xy 95.357994 -242.168263) (xy 95.381572 -242.121989) (xy 95.412098 -242.079973)
			(xy 95.448821 -242.04325) (xy 95.490837 -242.012724) (xy 95.537111 -241.989146) (xy 95.586504 -241.973098)
			(xy 95.637799 -241.964973) (xy 95.689733 -241.964973) (xy 95.741028 -241.973098) (xy 95.790421 -241.989146)
			(xy 95.836695 -242.012724) (xy 95.878711 -242.04325) (xy 95.915434 -242.079973) (xy 95.94596 -242.121989)
			(xy 95.969538 -242.168263) (xy 95.985586 -242.217656) (xy 95.993711 -242.268951) (xy 95.99422 -242.294918)
			(xy 95.993711 -242.320885) (xy 96.273621 -242.320885) (xy 96.273621 -242.268951) (xy 96.281746 -242.217656)
			(xy 96.297794 -242.168263) (xy 96.321372 -242.121989) (xy 96.351898 -242.079973) (xy 96.388621 -242.04325)
			(xy 96.430637 -242.012724) (xy 96.476911 -241.989146) (xy 96.526304 -241.973098) (xy 96.577599 -241.964973)
			(xy 96.629533 -241.964973) (xy 96.680828 -241.973098) (xy 96.730221 -241.989146) (xy 96.776495 -242.012724)
			(xy 96.818511 -242.04325) (xy 96.855234 -242.079973) (xy 96.88576 -242.121989) (xy 96.909338 -242.168263)
			(xy 96.925386 -242.217656) (xy 96.933511 -242.268951) (xy 96.93402 -242.294918) (xy 96.933511 -242.320885)
			(xy 97.213421 -242.320885) (xy 97.213421 -242.268951) (xy 97.221546 -242.217656) (xy 97.237594 -242.168263)
			(xy 97.261172 -242.121989) (xy 97.291698 -242.079973) (xy 97.328421 -242.04325) (xy 97.370437 -242.012724)
			(xy 97.416711 -241.989146) (xy 97.466104 -241.973098) (xy 97.517399 -241.964973) (xy 97.569333 -241.964973)
			(xy 97.620628 -241.973098) (xy 97.670021 -241.989146) (xy 97.716295 -242.012724) (xy 97.758311 -242.04325)
			(xy 97.795034 -242.079973) (xy 97.82556 -242.121989) (xy 97.849138 -242.168263) (xy 97.865186 -242.217656)
			(xy 97.873311 -242.268951) (xy 97.87382 -242.294918) (xy 97.873311 -242.320885) (xy 98.153221 -242.320885)
			(xy 98.153221 -242.268951) (xy 98.161346 -242.217656) (xy 98.177394 -242.168263) (xy 98.200972 -242.121989)
			(xy 98.231498 -242.079973) (xy 98.268221 -242.04325) (xy 98.310237 -242.012724) (xy 98.356511 -241.989146)
			(xy 98.405904 -241.973098) (xy 98.457199 -241.964973) (xy 98.509133 -241.964973) (xy 98.560428 -241.973098)
			(xy 98.609821 -241.989146) (xy 98.656095 -242.012724) (xy 98.698111 -242.04325) (xy 98.734834 -242.079973)
			(xy 98.76536 -242.121989) (xy 98.788938 -242.168263) (xy 98.804986 -242.217656) (xy 98.813111 -242.268951)
			(xy 98.81362 -242.294918) (xy 98.813111 -242.320885) (xy 99.093021 -242.320885) (xy 99.093021 -242.268951)
			(xy 99.101146 -242.217656) (xy 99.117194 -242.168263) (xy 99.140772 -242.121989) (xy 99.171298 -242.079973)
			(xy 99.208021 -242.04325) (xy 99.250037 -242.012724) (xy 99.296311 -241.989146) (xy 99.345704 -241.973098)
			(xy 99.396999 -241.964973) (xy 99.448933 -241.964973) (xy 99.500228 -241.973098) (xy 99.549621 -241.989146)
			(xy 99.595895 -242.012724) (xy 99.637911 -242.04325) (xy 99.674634 -242.079973) (xy 99.70516 -242.121989)
			(xy 99.728738 -242.168263) (xy 99.744786 -242.217656) (xy 99.752911 -242.268951) (xy 99.75342 -242.294918)
			(xy 99.752911 -242.320885) (xy 100.032821 -242.320885) (xy 100.032821 -242.268951) (xy 100.040946 -242.217656)
			(xy 100.056994 -242.168263) (xy 100.080572 -242.121989) (xy 100.111098 -242.079973) (xy 100.147821 -242.04325)
			(xy 100.189837 -242.012724) (xy 100.236111 -241.989146) (xy 100.285504 -241.973098) (xy 100.336799 -241.964973)
			(xy 100.388733 -241.964973) (xy 100.440028 -241.973098) (xy 100.489421 -241.989146) (xy 100.535695 -242.012724)
			(xy 100.577711 -242.04325) (xy 100.614434 -242.079973) (xy 100.64496 -242.121989) (xy 100.668538 -242.168263)
			(xy 100.684586 -242.217656) (xy 100.692711 -242.268951) (xy 100.69322 -242.294918) (xy 100.692711 -242.320885)
			(xy 100.972621 -242.320885) (xy 100.972621 -242.268951) (xy 100.980746 -242.217656) (xy 100.996794 -242.168263)
			(xy 101.020372 -242.121989) (xy 101.050898 -242.079973) (xy 101.087621 -242.04325) (xy 101.129637 -242.012724)
			(xy 101.175911 -241.989146) (xy 101.225304 -241.973098) (xy 101.276599 -241.964973) (xy 101.328533 -241.964973)
			(xy 101.379828 -241.973098) (xy 101.429221 -241.989146) (xy 101.475495 -242.012724) (xy 101.517511 -242.04325)
			(xy 101.554234 -242.079973) (xy 101.58476 -242.121989) (xy 101.608338 -242.168263) (xy 101.624386 -242.217656)
			(xy 101.632511 -242.268951) (xy 101.63302 -242.294918) (xy 101.632511 -242.320885) (xy 101.912421 -242.320885)
			(xy 101.912421 -242.268951) (xy 101.920546 -242.217656) (xy 101.936594 -242.168263) (xy 101.960172 -242.121989)
			(xy 101.990698 -242.079973) (xy 102.027421 -242.04325) (xy 102.069437 -242.012724) (xy 102.115711 -241.989146)
			(xy 102.165104 -241.973098) (xy 102.216399 -241.964973) (xy 102.268333 -241.964973) (xy 102.319628 -241.973098)
			(xy 102.369021 -241.989146) (xy 102.415295 -242.012724) (xy 102.457311 -242.04325) (xy 102.494034 -242.079973)
			(xy 102.52456 -242.121989) (xy 102.548138 -242.168263) (xy 102.564186 -242.217656) (xy 102.572311 -242.268951)
			(xy 102.57282 -242.294918) (xy 102.572311 -242.320885) (xy 102.564186 -242.37218) (xy 102.548138 -242.421573)
			(xy 102.52456 -242.467847) (xy 102.494034 -242.509863) (xy 102.457311 -242.546586) (xy 102.415295 -242.577112)
			(xy 102.369021 -242.60069) (xy 102.319628 -242.616738) (xy 102.268333 -242.624863) (xy 102.216399 -242.624863)
			(xy 102.165104 -242.616738) (xy 102.115711 -242.60069) (xy 102.069437 -242.577112) (xy 102.027421 -242.546586)
			(xy 101.990698 -242.509863) (xy 101.960172 -242.467847) (xy 101.936594 -242.421573) (xy 101.920546 -242.37218)
			(xy 101.912421 -242.320885) (xy 101.632511 -242.320885) (xy 101.624386 -242.37218) (xy 101.608338 -242.421573)
			(xy 101.58476 -242.467847) (xy 101.554234 -242.509863) (xy 101.517511 -242.546586) (xy 101.475495 -242.577112)
			(xy 101.429221 -242.60069) (xy 101.379828 -242.616738) (xy 101.328533 -242.624863) (xy 101.276599 -242.624863)
			(xy 101.225304 -242.616738) (xy 101.175911 -242.60069) (xy 101.129637 -242.577112) (xy 101.087621 -242.546586)
			(xy 101.050898 -242.509863) (xy 101.020372 -242.467847) (xy 100.996794 -242.421573) (xy 100.980746 -242.37218)
			(xy 100.972621 -242.320885) (xy 100.692711 -242.320885) (xy 100.684586 -242.37218) (xy 100.668538 -242.421573)
			(xy 100.64496 -242.467847) (xy 100.614434 -242.509863) (xy 100.577711 -242.546586) (xy 100.535695 -242.577112)
			(xy 100.489421 -242.60069) (xy 100.440028 -242.616738) (xy 100.388733 -242.624863) (xy 100.336799 -242.624863)
			(xy 100.285504 -242.616738) (xy 100.236111 -242.60069) (xy 100.189837 -242.577112) (xy 100.147821 -242.546586)
			(xy 100.111098 -242.509863) (xy 100.080572 -242.467847) (xy 100.056994 -242.421573) (xy 100.040946 -242.37218)
			(xy 100.032821 -242.320885) (xy 99.752911 -242.320885) (xy 99.744786 -242.37218) (xy 99.728738 -242.421573)
			(xy 99.70516 -242.467847) (xy 99.674634 -242.509863) (xy 99.637911 -242.546586) (xy 99.595895 -242.577112)
			(xy 99.549621 -242.60069) (xy 99.500228 -242.616738) (xy 99.448933 -242.624863) (xy 99.396999 -242.624863)
			(xy 99.345704 -242.616738) (xy 99.296311 -242.60069) (xy 99.250037 -242.577112) (xy 99.208021 -242.546586)
			(xy 99.171298 -242.509863) (xy 99.140772 -242.467847) (xy 99.117194 -242.421573) (xy 99.101146 -242.37218)
			(xy 99.093021 -242.320885) (xy 98.813111 -242.320885) (xy 98.804986 -242.37218) (xy 98.788938 -242.421573)
			(xy 98.76536 -242.467847) (xy 98.734834 -242.509863) (xy 98.698111 -242.546586) (xy 98.656095 -242.577112)
			(xy 98.609821 -242.60069) (xy 98.560428 -242.616738) (xy 98.509133 -242.624863) (xy 98.457199 -242.624863)
			(xy 98.405904 -242.616738) (xy 98.356511 -242.60069) (xy 98.310237 -242.577112) (xy 98.268221 -242.546586)
			(xy 98.231498 -242.509863) (xy 98.200972 -242.467847) (xy 98.177394 -242.421573) (xy 98.161346 -242.37218)
			(xy 98.153221 -242.320885) (xy 97.873311 -242.320885) (xy 97.865186 -242.37218) (xy 97.849138 -242.421573)
			(xy 97.82556 -242.467847) (xy 97.795034 -242.509863) (xy 97.758311 -242.546586) (xy 97.716295 -242.577112)
			(xy 97.670021 -242.60069) (xy 97.620628 -242.616738) (xy 97.569333 -242.624863) (xy 97.517399 -242.624863)
			(xy 97.466104 -242.616738) (xy 97.416711 -242.60069) (xy 97.370437 -242.577112) (xy 97.328421 -242.546586)
			(xy 97.291698 -242.509863) (xy 97.261172 -242.467847) (xy 97.237594 -242.421573) (xy 97.221546 -242.37218)
			(xy 97.213421 -242.320885) (xy 96.933511 -242.320885) (xy 96.925386 -242.37218) (xy 96.909338 -242.421573)
			(xy 96.88576 -242.467847) (xy 96.855234 -242.509863) (xy 96.818511 -242.546586) (xy 96.776495 -242.577112)
			(xy 96.730221 -242.60069) (xy 96.680828 -242.616738) (xy 96.629533 -242.624863) (xy 96.577599 -242.624863)
			(xy 96.526304 -242.616738) (xy 96.476911 -242.60069) (xy 96.430637 -242.577112) (xy 96.388621 -242.546586)
			(xy 96.351898 -242.509863) (xy 96.321372 -242.467847) (xy 96.297794 -242.421573) (xy 96.281746 -242.37218)
			(xy 96.273621 -242.320885) (xy 95.993711 -242.320885) (xy 95.985586 -242.37218) (xy 95.969538 -242.421573)
			(xy 95.94596 -242.467847) (xy 95.915434 -242.509863) (xy 95.878711 -242.546586) (xy 95.836695 -242.577112)
			(xy 95.790421 -242.60069) (xy 95.741028 -242.616738) (xy 95.689733 -242.624863) (xy 95.637799 -242.624863)
			(xy 95.586504 -242.616738) (xy 95.537111 -242.60069) (xy 95.490837 -242.577112) (xy 95.448821 -242.546586)
			(xy 95.412098 -242.509863) (xy 95.381572 -242.467847) (xy 95.357994 -242.421573) (xy 95.341946 -242.37218)
			(xy 95.333821 -242.320885) (xy 95.053911 -242.320885) (xy 95.045786 -242.37218) (xy 95.029738 -242.421573)
			(xy 95.00616 -242.467847) (xy 94.975634 -242.509863) (xy 94.938911 -242.546586) (xy 94.896895 -242.577112)
			(xy 94.850621 -242.60069) (xy 94.801228 -242.616738) (xy 94.749933 -242.624863) (xy 94.697999 -242.624863)
			(xy 94.646704 -242.616738) (xy 94.597311 -242.60069) (xy 94.551037 -242.577112) (xy 94.509021 -242.546586)
			(xy 94.472298 -242.509863) (xy 94.441772 -242.467847) (xy 94.418194 -242.421573) (xy 94.402146 -242.37218)
			(xy 94.394021 -242.320885) (xy 94.114111 -242.320885) (xy 94.105986 -242.37218) (xy 94.089938 -242.421573)
			(xy 94.06636 -242.467847) (xy 94.035834 -242.509863) (xy 93.999111 -242.546586) (xy 93.957095 -242.577112)
			(xy 93.910821 -242.60069) (xy 93.861428 -242.616738) (xy 93.810133 -242.624863) (xy 93.758199 -242.624863)
			(xy 93.706904 -242.616738) (xy 93.657511 -242.60069) (xy 93.611237 -242.577112) (xy 93.569221 -242.546586)
			(xy 93.532498 -242.509863) (xy 93.501972 -242.467847) (xy 93.478394 -242.421573) (xy 93.462346 -242.37218)
			(xy 93.454221 -242.320885) (xy 93.174311 -242.320885) (xy 93.166186 -242.37218) (xy 93.150138 -242.421573)
			(xy 93.12656 -242.467847) (xy 93.096034 -242.509863) (xy 93.059311 -242.546586) (xy 93.017295 -242.577112)
			(xy 92.971021 -242.60069) (xy 92.921628 -242.616738) (xy 92.870333 -242.624863) (xy 92.818399 -242.624863)
			(xy 92.767104 -242.616738) (xy 92.717711 -242.60069) (xy 92.671437 -242.577112) (xy 92.629421 -242.546586)
			(xy 92.592698 -242.509863) (xy 92.562172 -242.467847) (xy 92.538594 -242.421573) (xy 92.522546 -242.37218)
			(xy 92.514421 -242.320885) (xy 92.234807 -242.320885) (xy 92.234807 -242.32089) (xy 92.226675 -242.372229)
			(xy 92.210612 -242.421663) (xy 92.187012 -242.467976) (xy 92.156458 -242.510027) (xy 92.119701 -242.54678)
			(xy 92.077647 -242.57733) (xy 92.031332 -242.600925) (xy 91.981895 -242.616983) (xy 91.930556 -242.625109)
			(xy 91.904566 -242.625626) (xy 91.877643 -242.625095) (xy 91.824507 -242.616375) (xy 91.773483 -242.599169)
			(xy 91.725916 -242.573931) (xy 91.70416 -242.558062) (xy 91.69781 -242.553236) (xy 91.66733 -242.542314)
			(xy 91.661602 -242.54243) (xy 91.65044 -242.545005) (xy 91.645232 -242.547394) (xy 91.604846 -242.566952)
			(xy 91.56192 -242.587526) (xy 91.554127 -242.592086) (xy 91.542172 -242.605599) (xy 91.535723 -242.62245)
			(xy 91.53525 -242.631468) (xy 91.53525 -242.75923) (xy 91.565222 -242.804696) (xy 91.577922 -242.810792)
			(xy 91.601628 -242.822763) (xy 91.64521 -242.853105) (xy 91.683385 -242.890019) (xy 91.715173 -242.932558)
			(xy 91.739757 -242.979628) (xy 91.756506 -243.030021) (xy 91.76499 -243.082443) (xy 91.764991 -243.134955)
			(xy 92.044267 -243.134955) (xy 92.044267 -243.083021) (xy 92.052392 -243.031726) (xy 92.06844 -242.982333)
			(xy 92.092018 -242.936059) (xy 92.122544 -242.894043) (xy 92.159267 -242.85732) (xy 92.201283 -242.826794)
			(xy 92.247557 -242.803216) (xy 92.29695 -242.787168) (xy 92.348245 -242.779043) (xy 92.400179 -242.779043)
			(xy 92.451474 -242.787168) (xy 92.500867 -242.803216) (xy 92.547141 -242.826794) (xy 92.589157 -242.85732)
			(xy 92.62588 -242.894043) (xy 92.656406 -242.936059) (xy 92.679984 -242.982333) (xy 92.696032 -243.031726)
			(xy 92.704157 -243.083021) (xy 92.704666 -243.108988) (xy 92.704157 -243.134955) (xy 92.984067 -243.134955)
			(xy 92.984067 -243.083021) (xy 92.992192 -243.031726) (xy 93.00824 -242.982333) (xy 93.031818 -242.936059)
			(xy 93.062344 -242.894043) (xy 93.099067 -242.85732) (xy 93.141083 -242.826794) (xy 93.187357 -242.803216)
			(xy 93.23675 -242.787168) (xy 93.288045 -242.779043) (xy 93.339979 -242.779043) (xy 93.391274 -242.787168)
			(xy 93.440667 -242.803216) (xy 93.486941 -242.826794) (xy 93.528957 -242.85732) (xy 93.56568 -242.894043)
			(xy 93.596206 -242.936059) (xy 93.619784 -242.982333) (xy 93.635832 -243.031726) (xy 93.643957 -243.083021)
			(xy 93.644466 -243.108988) (xy 93.643957 -243.134955) (xy 93.923867 -243.134955) (xy 93.923867 -243.083021)
			(xy 93.931992 -243.031726) (xy 93.94804 -242.982333) (xy 93.971618 -242.936059) (xy 94.002144 -242.894043)
			(xy 94.038867 -242.85732) (xy 94.080883 -242.826794) (xy 94.127157 -242.803216) (xy 94.17655 -242.787168)
			(xy 94.227845 -242.779043) (xy 94.279779 -242.779043) (xy 94.331074 -242.787168) (xy 94.380467 -242.803216)
			(xy 94.426741 -242.826794) (xy 94.468757 -242.85732) (xy 94.50548 -242.894043) (xy 94.536006 -242.936059)
			(xy 94.559584 -242.982333) (xy 94.575632 -243.031726) (xy 94.583757 -243.083021) (xy 94.584266 -243.108988)
			(xy 94.583757 -243.134955) (xy 94.863667 -243.134955) (xy 94.863667 -243.083021) (xy 94.871792 -243.031726)
			(xy 94.88784 -242.982333) (xy 94.911418 -242.936059) (xy 94.941944 -242.894043) (xy 94.978667 -242.85732)
			(xy 95.020683 -242.826794) (xy 95.066957 -242.803216) (xy 95.11635 -242.787168) (xy 95.167645 -242.779043)
			(xy 95.219579 -242.779043) (xy 95.270874 -242.787168) (xy 95.320267 -242.803216) (xy 95.366541 -242.826794)
			(xy 95.408557 -242.85732) (xy 95.44528 -242.894043) (xy 95.475806 -242.936059) (xy 95.499384 -242.982333)
			(xy 95.515432 -243.031726) (xy 95.523557 -243.083021) (xy 95.524066 -243.108988) (xy 95.523557 -243.134955)
			(xy 95.803467 -243.134955) (xy 95.803467 -243.083021) (xy 95.811592 -243.031726) (xy 95.82764 -242.982333)
			(xy 95.851218 -242.936059) (xy 95.881744 -242.894043) (xy 95.918467 -242.85732) (xy 95.960483 -242.826794)
			(xy 96.006757 -242.803216) (xy 96.05615 -242.787168) (xy 96.107445 -242.779043) (xy 96.159379 -242.779043)
			(xy 96.210674 -242.787168) (xy 96.260067 -242.803216) (xy 96.306341 -242.826794) (xy 96.348357 -242.85732)
			(xy 96.38508 -242.894043) (xy 96.415606 -242.936059) (xy 96.439184 -242.982333) (xy 96.455232 -243.031726)
			(xy 96.463357 -243.083021) (xy 96.463866 -243.108988) (xy 96.463357 -243.134955) (xy 96.743267 -243.134955)
			(xy 96.743267 -243.083021) (xy 96.751392 -243.031726) (xy 96.76744 -242.982333) (xy 96.791018 -242.936059)
			(xy 96.821544 -242.894043) (xy 96.858267 -242.85732) (xy 96.900283 -242.826794) (xy 96.946557 -242.803216)
			(xy 96.99595 -242.787168) (xy 97.047245 -242.779043) (xy 97.099179 -242.779043) (xy 97.150474 -242.787168)
			(xy 97.199867 -242.803216) (xy 97.246141 -242.826794) (xy 97.288157 -242.85732) (xy 97.32488 -242.894043)
			(xy 97.355406 -242.936059) (xy 97.378984 -242.982333) (xy 97.395032 -243.031726) (xy 97.403157 -243.083021)
			(xy 97.403666 -243.108988) (xy 97.403157 -243.134955) (xy 97.683321 -243.134955) (xy 97.683321 -243.083021)
			(xy 97.691446 -243.031726) (xy 97.707494 -242.982333) (xy 97.731072 -242.936059) (xy 97.761598 -242.894043)
			(xy 97.798321 -242.85732) (xy 97.840337 -242.826794) (xy 97.886611 -242.803216) (xy 97.936004 -242.787168)
			(xy 97.987299 -242.779043) (xy 98.039233 -242.779043) (xy 98.090528 -242.787168) (xy 98.139921 -242.803216)
			(xy 98.186195 -242.826794) (xy 98.228211 -242.85732) (xy 98.264934 -242.894043) (xy 98.29546 -242.936059)
			(xy 98.319038 -242.982333) (xy 98.335086 -243.031726) (xy 98.343211 -243.083021) (xy 98.34372 -243.108988)
			(xy 98.343211 -243.134955) (xy 98.622867 -243.134955) (xy 98.622867 -243.083021) (xy 98.630992 -243.031726)
			(xy 98.64704 -242.982333) (xy 98.670618 -242.936059) (xy 98.701144 -242.894043) (xy 98.737867 -242.85732)
			(xy 98.779883 -242.826794) (xy 98.826157 -242.803216) (xy 98.87555 -242.787168) (xy 98.926845 -242.779043)
			(xy 98.978779 -242.779043) (xy 99.030074 -242.787168) (xy 99.079467 -242.803216) (xy 99.125741 -242.826794)
			(xy 99.167757 -242.85732) (xy 99.20448 -242.894043) (xy 99.235006 -242.936059) (xy 99.258584 -242.982333)
			(xy 99.274632 -243.031726) (xy 99.282757 -243.083021) (xy 99.283266 -243.108988) (xy 99.282757 -243.134955)
			(xy 99.562667 -243.134955) (xy 99.562667 -243.083021) (xy 99.570792 -243.031726) (xy 99.58684 -242.982333)
			(xy 99.610418 -242.936059) (xy 99.640944 -242.894043) (xy 99.677667 -242.85732) (xy 99.719683 -242.826794)
			(xy 99.765957 -242.803216) (xy 99.81535 -242.787168) (xy 99.866645 -242.779043) (xy 99.918579 -242.779043)
			(xy 99.969874 -242.787168) (xy 100.019267 -242.803216) (xy 100.065541 -242.826794) (xy 100.107557 -242.85732)
			(xy 100.14428 -242.894043) (xy 100.174806 -242.936059) (xy 100.198384 -242.982333) (xy 100.214432 -243.031726)
			(xy 100.222557 -243.083021) (xy 100.223066 -243.108988) (xy 100.222557 -243.134955) (xy 100.502467 -243.134955)
			(xy 100.502467 -243.083021) (xy 100.510592 -243.031726) (xy 100.52664 -242.982333) (xy 100.550218 -242.936059)
			(xy 100.580744 -242.894043) (xy 100.617467 -242.85732) (xy 100.659483 -242.826794) (xy 100.705757 -242.803216)
			(xy 100.75515 -242.787168) (xy 100.806445 -242.779043) (xy 100.858379 -242.779043) (xy 100.909674 -242.787168)
			(xy 100.959067 -242.803216) (xy 101.005341 -242.826794) (xy 101.047357 -242.85732) (xy 101.08408 -242.894043)
			(xy 101.114606 -242.936059) (xy 101.138184 -242.982333) (xy 101.154232 -243.031726) (xy 101.162357 -243.083021)
			(xy 101.162866 -243.108988) (xy 101.162357 -243.134955) (xy 101.442267 -243.134955) (xy 101.442267 -243.083021)
			(xy 101.450392 -243.031726) (xy 101.46644 -242.982333) (xy 101.490018 -242.936059) (xy 101.520544 -242.894043)
			(xy 101.557267 -242.85732) (xy 101.599283 -242.826794) (xy 101.645557 -242.803216) (xy 101.69495 -242.787168)
			(xy 101.746245 -242.779043) (xy 101.798179 -242.779043) (xy 101.849474 -242.787168) (xy 101.898867 -242.803216)
			(xy 101.945141 -242.826794) (xy 101.987157 -242.85732) (xy 102.02388 -242.894043) (xy 102.054406 -242.936059)
			(xy 102.077984 -242.982333) (xy 102.08615 -243.007468) (xy 103.653835 -243.007468) (xy 103.653835 -242.955532)
			(xy 103.66196 -242.904235) (xy 103.678009 -242.85484) (xy 103.701587 -242.808564) (xy 103.732114 -242.766546)
			(xy 103.768838 -242.729821) (xy 103.810855 -242.699292) (xy 103.857131 -242.675713) (xy 103.906525 -242.659662)
			(xy 103.957822 -242.651536) (xy 103.98379 -242.651026) (xy 103.984044 -242.651026) (xy 104.008571 -242.651471)
			(xy 104.057083 -242.658738) (xy 104.103989 -242.673092) (xy 104.148261 -242.694218) (xy 104.188926 -242.721653)
			(xy 104.20731 -242.737894) (xy 104.218799 -242.747697) (xy 104.246036 -242.760711) (xy 104.27589 -242.765179)
			(xy 104.305744 -242.760711) (xy 104.332981 -242.747697) (xy 104.34447 -242.737894) (xy 104.362847 -242.721642)
			(xy 104.403507 -242.694198) (xy 104.44778 -242.673069) (xy 104.494691 -242.658722) (xy 104.543208 -242.651471)
			(xy 104.567736 -242.651026) (xy 104.56799 -242.651026) (xy 104.593958 -242.651548) (xy 104.645255 -242.659671)
			(xy 104.69465 -242.675719) (xy 104.740927 -242.699297) (xy 104.782945 -242.729824) (xy 104.81967 -242.766548)
			(xy 104.850198 -242.808565) (xy 104.873777 -242.85484) (xy 104.889826 -242.904235) (xy 104.897951 -242.955532)
			(xy 104.897951 -243.007468) (xy 105.127035 -243.007468) (xy 105.127035 -242.955532) (xy 105.13516 -242.904235)
			(xy 105.151209 -242.85484) (xy 105.174787 -242.808564) (xy 105.205314 -242.766546) (xy 105.242038 -242.729821)
			(xy 105.284055 -242.699292) (xy 105.330331 -242.675713) (xy 105.379725 -242.659662) (xy 105.431022 -242.651536)
			(xy 105.45699 -242.651026) (xy 105.484288 -242.651577) (xy 105.53814 -242.660557) (xy 105.589781 -242.678273)
			(xy 105.637805 -242.704243) (xy 105.680902 -242.737759) (xy 105.699814 -242.757452) (xy 105.709647 -242.767432)
			(xy 105.733531 -242.782058) (xy 105.760487 -242.789657) (xy 105.788493 -242.789657) (xy 105.815449 -242.782058)
			(xy 105.839333 -242.767432) (xy 105.849166 -242.757452) (xy 105.868076 -242.737757) (xy 105.911176 -242.704248)
			(xy 105.959201 -242.678283) (xy 106.010842 -242.660569) (xy 106.064693 -242.651589) (xy 106.09199 -242.651026)
			(xy 106.117958 -242.651548) (xy 106.169255 -242.659671) (xy 106.21865 -242.675719) (xy 106.264927 -242.699297)
			(xy 106.306945 -242.729824) (xy 106.34367 -242.766548) (xy 106.374198 -242.808565) (xy 106.397777 -242.85484)
			(xy 106.413826 -242.904235) (xy 106.421951 -242.955532) (xy 106.421951 -243.007468) (xy 107.032035 -243.007468)
			(xy 107.032035 -242.955532) (xy 107.04016 -242.904235) (xy 107.056209 -242.85484) (xy 107.079787 -242.808564)
			(xy 107.110314 -242.766546) (xy 107.147038 -242.729821) (xy 107.189055 -242.699292) (xy 107.235331 -242.675713)
			(xy 107.284725 -242.659662) (xy 107.336022 -242.651536) (xy 107.36199 -242.651026) (xy 107.389288 -242.651577)
			(xy 107.44314 -242.660557) (xy 107.494781 -242.678273) (xy 107.542805 -242.704243) (xy 107.585902 -242.737759)
			(xy 107.604814 -242.757452) (xy 107.614647 -242.767432) (xy 107.638531 -242.782058) (xy 107.665487 -242.789657)
			(xy 107.693493 -242.789657) (xy 107.720449 -242.782058) (xy 107.744333 -242.767432) (xy 107.754166 -242.757452)
			(xy 107.771311 -242.739507) (xy 107.810027 -242.708455) (xy 107.852954 -242.683547) (xy 107.899125 -242.665344)
			(xy 107.9475 -242.654255) (xy 107.99699 -242.650531) (xy 108.04648 -242.654255) (xy 108.094855 -242.665344)
			(xy 108.141026 -242.683547) (xy 108.183953 -242.708455) (xy 108.222669 -242.739507) (xy 108.239814 -242.757452)
			(xy 108.249154 -242.767009) (xy 108.271709 -242.781321) (xy 108.297207 -242.789285) (xy 108.323899 -242.790354)
			(xy 108.349952 -242.784455) (xy 108.37358 -242.771993) (xy 108.393161 -242.753823) (xy 108.400596 -242.74272)
			(xy 108.408662 -242.730152) (xy 108.426721 -242.706365) (xy 108.436664 -242.695222) (xy 108.446427 -242.683701)
			(xy 108.459447 -242.656476) (xy 108.463924 -242.626631) (xy 108.459466 -242.596784) (xy 108.446462 -242.56955)
			(xy 108.436664 -242.558062) (xy 108.420439 -242.539663) (xy 108.392988 -242.49901) (xy 108.371853 -242.454743)
			(xy 108.3575 -242.407836) (xy 108.350244 -242.359323) (xy 108.349796 -242.334796) (xy 108.349796 -242.334542)
			(xy 108.350305 -242.308575) (xy 108.35843 -242.25728) (xy 108.374478 -242.207887) (xy 108.398056 -242.161613)
			(xy 108.428582 -242.119597) (xy 108.465305 -242.082874) (xy 108.507321 -242.052348) (xy 108.553595 -242.02877)
			(xy 108.602988 -242.012722) (xy 108.654283 -242.004597) (xy 108.706217 -242.004597) (xy 108.757512 -242.012722)
			(xy 108.806905 -242.02877) (xy 108.853179 -242.052348) (xy 108.895195 -242.082874) (xy 108.931918 -242.119597)
			(xy 108.962444 -242.161613) (xy 108.986022 -242.207887) (xy 109.00207 -242.25728) (xy 109.010195 -242.308575)
			(xy 109.010441 -242.321139) (xy 109.430821 -242.321139) (xy 109.430821 -242.269205) (xy 109.438946 -242.21791)
			(xy 109.454994 -242.168517) (xy 109.478572 -242.122243) (xy 109.509098 -242.080227) (xy 109.545821 -242.043504)
			(xy 109.587837 -242.012978) (xy 109.634111 -241.9894) (xy 109.683504 -241.973352) (xy 109.734799 -241.965227)
			(xy 109.786733 -241.965227) (xy 109.838028 -241.973352) (xy 109.887421 -241.9894) (xy 109.933695 -242.012978)
			(xy 109.975711 -242.043504) (xy 110.012434 -242.080227) (xy 110.04296 -242.122243) (xy 110.066538 -242.168517)
			(xy 110.082586 -242.21791) (xy 110.090711 -242.269205) (xy 110.09122 -242.295172) (xy 110.090711 -242.321139)
			(xy 110.370875 -242.321139) (xy 110.370875 -242.269205) (xy 110.379 -242.21791) (xy 110.395048 -242.168517)
			(xy 110.418626 -242.122243) (xy 110.449152 -242.080227) (xy 110.485875 -242.043504) (xy 110.527891 -242.012978)
			(xy 110.574165 -241.9894) (xy 110.623558 -241.973352) (xy 110.674853 -241.965227) (xy 110.726787 -241.965227)
			(xy 110.778082 -241.973352) (xy 110.827475 -241.9894) (xy 110.873749 -242.012978) (xy 110.915765 -242.043504)
			(xy 110.952488 -242.080227) (xy 110.983014 -242.122243) (xy 111.006592 -242.168517) (xy 111.02264 -242.21791)
			(xy 111.030765 -242.269205) (xy 111.031274 -242.295172) (xy 111.030765 -242.321139) (xy 111.310421 -242.321139)
			(xy 111.310421 -242.269205) (xy 111.318546 -242.21791) (xy 111.334594 -242.168517) (xy 111.358172 -242.122243)
			(xy 111.388698 -242.080227) (xy 111.425421 -242.043504) (xy 111.467437 -242.012978) (xy 111.513711 -241.9894)
			(xy 111.563104 -241.973352) (xy 111.614399 -241.965227) (xy 111.666333 -241.965227) (xy 111.717628 -241.973352)
			(xy 111.767021 -241.9894) (xy 111.813295 -242.012978) (xy 111.855311 -242.043504) (xy 111.892034 -242.080227)
			(xy 111.92256 -242.122243) (xy 111.946138 -242.168517) (xy 111.962186 -242.21791) (xy 111.970311 -242.269205)
			(xy 111.97082 -242.295172) (xy 111.970311 -242.321139) (xy 112.250221 -242.321139) (xy 112.250221 -242.269205)
			(xy 112.258346 -242.21791) (xy 112.274394 -242.168517) (xy 112.297972 -242.122243) (xy 112.328498 -242.080227)
			(xy 112.365221 -242.043504) (xy 112.407237 -242.012978) (xy 112.453511 -241.9894) (xy 112.502904 -241.973352)
			(xy 112.554199 -241.965227) (xy 112.606133 -241.965227) (xy 112.657428 -241.973352) (xy 112.706821 -241.9894)
			(xy 112.753095 -242.012978) (xy 112.795111 -242.043504) (xy 112.831834 -242.080227) (xy 112.86236 -242.122243)
			(xy 112.885938 -242.168517) (xy 112.901986 -242.21791) (xy 112.910111 -242.269205) (xy 112.91062 -242.295172)
			(xy 112.910111 -242.321139) (xy 113.190275 -242.321139) (xy 113.190275 -242.269205) (xy 113.1984 -242.21791)
			(xy 113.214448 -242.168517) (xy 113.238026 -242.122243) (xy 113.268552 -242.080227) (xy 113.305275 -242.043504)
			(xy 113.347291 -242.012978) (xy 113.393565 -241.9894) (xy 113.442958 -241.973352) (xy 113.494253 -241.965227)
			(xy 113.546187 -241.965227) (xy 113.597482 -241.973352) (xy 113.646875 -241.9894) (xy 113.693149 -242.012978)
			(xy 113.735165 -242.043504) (xy 113.771888 -242.080227) (xy 113.802414 -242.122243) (xy 113.825992 -242.168517)
			(xy 113.84204 -242.21791) (xy 113.850165 -242.269205) (xy 113.850674 -242.295172) (xy 113.850165 -242.321139)
			(xy 114.130075 -242.321139) (xy 114.130075 -242.269205) (xy 114.1382 -242.21791) (xy 114.154248 -242.168517)
			(xy 114.177826 -242.122243) (xy 114.208352 -242.080227) (xy 114.245075 -242.043504) (xy 114.287091 -242.012978)
			(xy 114.333365 -241.9894) (xy 114.382758 -241.973352) (xy 114.434053 -241.965227) (xy 114.485987 -241.965227)
			(xy 114.537282 -241.973352) (xy 114.586675 -241.9894) (xy 114.632949 -242.012978) (xy 114.674965 -242.043504)
			(xy 114.711688 -242.080227) (xy 114.742214 -242.122243) (xy 114.765792 -242.168517) (xy 114.78184 -242.21791)
			(xy 114.789965 -242.269205) (xy 114.790474 -242.295172) (xy 114.78997 -242.320885) (xy 121.648221 -242.320885)
			(xy 121.648221 -242.268951) (xy 121.656346 -242.217656) (xy 121.672394 -242.168263) (xy 121.695972 -242.121989)
			(xy 121.726498 -242.079973) (xy 121.763221 -242.04325) (xy 121.805237 -242.012724) (xy 121.851511 -241.989146)
			(xy 121.900904 -241.973098) (xy 121.952199 -241.964973) (xy 122.004133 -241.964973) (xy 122.055428 -241.973098)
			(xy 122.104821 -241.989146) (xy 122.151095 -242.012724) (xy 122.193111 -242.04325) (xy 122.229834 -242.079973)
			(xy 122.26036 -242.121989) (xy 122.283938 -242.168263) (xy 122.299986 -242.217656) (xy 122.308111 -242.268951)
			(xy 122.30862 -242.294918) (xy 122.308111 -242.320885) (xy 122.588021 -242.320885) (xy 122.588021 -242.268951)
			(xy 122.596146 -242.217656) (xy 122.612194 -242.168263) (xy 122.635772 -242.121989) (xy 122.666298 -242.079973)
			(xy 122.703021 -242.04325) (xy 122.745037 -242.012724) (xy 122.791311 -241.989146) (xy 122.840704 -241.973098)
			(xy 122.891999 -241.964973) (xy 122.943933 -241.964973) (xy 122.995228 -241.973098) (xy 123.044621 -241.989146)
			(xy 123.090895 -242.012724) (xy 123.132911 -242.04325) (xy 123.169634 -242.079973) (xy 123.20016 -242.121989)
			(xy 123.223738 -242.168263) (xy 123.239786 -242.217656) (xy 123.247911 -242.268951) (xy 123.24842 -242.294918)
			(xy 123.247911 -242.320885) (xy 123.527821 -242.320885) (xy 123.527821 -242.268951) (xy 123.535946 -242.217656)
			(xy 123.551994 -242.168263) (xy 123.575572 -242.121989) (xy 123.606098 -242.079973) (xy 123.642821 -242.04325)
			(xy 123.684837 -242.012724) (xy 123.731111 -241.989146) (xy 123.780504 -241.973098) (xy 123.831799 -241.964973)
			(xy 123.883733 -241.964973) (xy 123.935028 -241.973098) (xy 123.984421 -241.989146) (xy 124.030695 -242.012724)
			(xy 124.072711 -242.04325) (xy 124.109434 -242.079973) (xy 124.13996 -242.121989) (xy 124.163538 -242.168263)
			(xy 124.179586 -242.217656) (xy 124.187711 -242.268951) (xy 124.18822 -242.294918) (xy 124.187711 -242.320885)
			(xy 124.467621 -242.320885) (xy 124.467621 -242.268951) (xy 124.475746 -242.217656) (xy 124.491794 -242.168263)
			(xy 124.515372 -242.121989) (xy 124.545898 -242.079973) (xy 124.582621 -242.04325) (xy 124.624637 -242.012724)
			(xy 124.670911 -241.989146) (xy 124.720304 -241.973098) (xy 124.771599 -241.964973) (xy 124.823533 -241.964973)
			(xy 124.874828 -241.973098) (xy 124.924221 -241.989146) (xy 124.970495 -242.012724) (xy 125.012511 -242.04325)
			(xy 125.049234 -242.079973) (xy 125.07976 -242.121989) (xy 125.103338 -242.168263) (xy 125.119386 -242.217656)
			(xy 125.127511 -242.268951) (xy 125.12802 -242.294918) (xy 125.127511 -242.320885) (xy 125.407421 -242.320885)
			(xy 125.407421 -242.268951) (xy 125.415546 -242.217656) (xy 125.431594 -242.168263) (xy 125.455172 -242.121989)
			(xy 125.485698 -242.079973) (xy 125.522421 -242.04325) (xy 125.564437 -242.012724) (xy 125.610711 -241.989146)
			(xy 125.660104 -241.973098) (xy 125.711399 -241.964973) (xy 125.763333 -241.964973) (xy 125.814628 -241.973098)
			(xy 125.864021 -241.989146) (xy 125.910295 -242.012724) (xy 125.952311 -242.04325) (xy 125.989034 -242.079973)
			(xy 126.01956 -242.121989) (xy 126.043138 -242.168263) (xy 126.059186 -242.217656) (xy 126.067311 -242.268951)
			(xy 126.06782 -242.294918) (xy 126.067311 -242.320885) (xy 126.347221 -242.320885) (xy 126.347221 -242.268951)
			(xy 126.355346 -242.217656) (xy 126.371394 -242.168263) (xy 126.394972 -242.121989) (xy 126.425498 -242.079973)
			(xy 126.462221 -242.04325) (xy 126.504237 -242.012724) (xy 126.550511 -241.989146) (xy 126.599904 -241.973098)
			(xy 126.651199 -241.964973) (xy 126.703133 -241.964973) (xy 126.754428 -241.973098) (xy 126.803821 -241.989146)
			(xy 126.850095 -242.012724) (xy 126.892111 -242.04325) (xy 126.928834 -242.079973) (xy 126.95936 -242.121989)
			(xy 126.982938 -242.168263) (xy 126.998986 -242.217656) (xy 127.007111 -242.268951) (xy 127.00762 -242.294918)
			(xy 127.007111 -242.320885) (xy 127.287021 -242.320885) (xy 127.287021 -242.268951) (xy 127.295146 -242.217656)
			(xy 127.311194 -242.168263) (xy 127.334772 -242.121989) (xy 127.365298 -242.079973) (xy 127.402021 -242.04325)
			(xy 127.444037 -242.012724) (xy 127.490311 -241.989146) (xy 127.539704 -241.973098) (xy 127.590999 -241.964973)
			(xy 127.642933 -241.964973) (xy 127.694228 -241.973098) (xy 127.743621 -241.989146) (xy 127.789895 -242.012724)
			(xy 127.831911 -242.04325) (xy 127.868634 -242.079973) (xy 127.89916 -242.121989) (xy 127.922738 -242.168263)
			(xy 127.938786 -242.217656) (xy 127.946911 -242.268951) (xy 127.94742 -242.294918) (xy 127.946911 -242.320885)
			(xy 128.226821 -242.320885) (xy 128.226821 -242.268951) (xy 128.234946 -242.217656) (xy 128.250994 -242.168263)
			(xy 128.274572 -242.121989) (xy 128.305098 -242.079973) (xy 128.341821 -242.04325) (xy 128.383837 -242.012724)
			(xy 128.430111 -241.989146) (xy 128.479504 -241.973098) (xy 128.530799 -241.964973) (xy 128.582733 -241.964973)
			(xy 128.634028 -241.973098) (xy 128.683421 -241.989146) (xy 128.729695 -242.012724) (xy 128.771711 -242.04325)
			(xy 128.808434 -242.079973) (xy 128.83896 -242.121989) (xy 128.862538 -242.168263) (xy 128.878586 -242.217656)
			(xy 128.886711 -242.268951) (xy 128.88722 -242.294918) (xy 128.886711 -242.320885) (xy 129.166621 -242.320885)
			(xy 129.166621 -242.268951) (xy 129.174746 -242.217656) (xy 129.190794 -242.168263) (xy 129.214372 -242.121989)
			(xy 129.244898 -242.079973) (xy 129.281621 -242.04325) (xy 129.323637 -242.012724) (xy 129.369911 -241.989146)
			(xy 129.419304 -241.973098) (xy 129.470599 -241.964973) (xy 129.522533 -241.964973) (xy 129.573828 -241.973098)
			(xy 129.623221 -241.989146) (xy 129.669495 -242.012724) (xy 129.711511 -242.04325) (xy 129.748234 -242.079973)
			(xy 129.77876 -242.121989) (xy 129.802338 -242.168263) (xy 129.818386 -242.217656) (xy 129.826511 -242.268951)
			(xy 129.82702 -242.294918) (xy 129.826511 -242.320885) (xy 130.106421 -242.320885) (xy 130.106421 -242.268951)
			(xy 130.114546 -242.217656) (xy 130.130594 -242.168263) (xy 130.154172 -242.121989) (xy 130.184698 -242.079973)
			(xy 130.221421 -242.04325) (xy 130.263437 -242.012724) (xy 130.309711 -241.989146) (xy 130.359104 -241.973098)
			(xy 130.410399 -241.964973) (xy 130.462333 -241.964973) (xy 130.513628 -241.973098) (xy 130.563021 -241.989146)
			(xy 130.609295 -242.012724) (xy 130.651311 -242.04325) (xy 130.688034 -242.079973) (xy 130.71856 -242.121989)
			(xy 130.742138 -242.168263) (xy 130.758186 -242.217656) (xy 130.766311 -242.268951) (xy 130.76682 -242.294918)
			(xy 130.766311 -242.320885) (xy 130.758186 -242.37218) (xy 130.742138 -242.421573) (xy 130.71856 -242.467847)
			(xy 130.688034 -242.509863) (xy 130.651311 -242.546586) (xy 130.609295 -242.577112) (xy 130.563021 -242.60069)
			(xy 130.513628 -242.616738) (xy 130.462333 -242.624863) (xy 130.410399 -242.624863) (xy 130.359104 -242.616738)
			(xy 130.309711 -242.60069) (xy 130.263437 -242.577112) (xy 130.221421 -242.546586) (xy 130.184698 -242.509863)
			(xy 130.154172 -242.467847) (xy 130.130594 -242.421573) (xy 130.114546 -242.37218) (xy 130.106421 -242.320885)
			(xy 129.826511 -242.320885) (xy 129.818386 -242.37218) (xy 129.802338 -242.421573) (xy 129.77876 -242.467847)
			(xy 129.748234 -242.509863) (xy 129.711511 -242.546586) (xy 129.669495 -242.577112) (xy 129.623221 -242.60069)
			(xy 129.573828 -242.616738) (xy 129.522533 -242.624863) (xy 129.470599 -242.624863) (xy 129.419304 -242.616738)
			(xy 129.369911 -242.60069) (xy 129.323637 -242.577112) (xy 129.281621 -242.546586) (xy 129.244898 -242.509863)
			(xy 129.214372 -242.467847) (xy 129.190794 -242.421573) (xy 129.174746 -242.37218) (xy 129.166621 -242.320885)
			(xy 128.886711 -242.320885) (xy 128.878586 -242.37218) (xy 128.862538 -242.421573) (xy 128.83896 -242.467847)
			(xy 128.808434 -242.509863) (xy 128.771711 -242.546586) (xy 128.729695 -242.577112) (xy 128.683421 -242.60069)
			(xy 128.634028 -242.616738) (xy 128.582733 -242.624863) (xy 128.530799 -242.624863) (xy 128.479504 -242.616738)
			(xy 128.430111 -242.60069) (xy 128.383837 -242.577112) (xy 128.341821 -242.546586) (xy 128.305098 -242.509863)
			(xy 128.274572 -242.467847) (xy 128.250994 -242.421573) (xy 128.234946 -242.37218) (xy 128.226821 -242.320885)
			(xy 127.946911 -242.320885) (xy 127.938786 -242.37218) (xy 127.922738 -242.421573) (xy 127.89916 -242.467847)
			(xy 127.868634 -242.509863) (xy 127.831911 -242.546586) (xy 127.789895 -242.577112) (xy 127.743621 -242.60069)
			(xy 127.694228 -242.616738) (xy 127.642933 -242.624863) (xy 127.590999 -242.624863) (xy 127.539704 -242.616738)
			(xy 127.490311 -242.60069) (xy 127.444037 -242.577112) (xy 127.402021 -242.546586) (xy 127.365298 -242.509863)
			(xy 127.334772 -242.467847) (xy 127.311194 -242.421573) (xy 127.295146 -242.37218) (xy 127.287021 -242.320885)
			(xy 127.007111 -242.320885) (xy 126.998986 -242.37218) (xy 126.982938 -242.421573) (xy 126.95936 -242.467847)
			(xy 126.928834 -242.509863) (xy 126.892111 -242.546586) (xy 126.850095 -242.577112) (xy 126.803821 -242.60069)
			(xy 126.754428 -242.616738) (xy 126.703133 -242.624863) (xy 126.651199 -242.624863) (xy 126.599904 -242.616738)
			(xy 126.550511 -242.60069) (xy 126.504237 -242.577112) (xy 126.462221 -242.546586) (xy 126.425498 -242.509863)
			(xy 126.394972 -242.467847) (xy 126.371394 -242.421573) (xy 126.355346 -242.37218) (xy 126.347221 -242.320885)
			(xy 126.067311 -242.320885) (xy 126.059186 -242.37218) (xy 126.043138 -242.421573) (xy 126.01956 -242.467847)
			(xy 125.989034 -242.509863) (xy 125.952311 -242.546586) (xy 125.910295 -242.577112) (xy 125.864021 -242.60069)
			(xy 125.814628 -242.616738) (xy 125.763333 -242.624863) (xy 125.711399 -242.624863) (xy 125.660104 -242.616738)
			(xy 125.610711 -242.60069) (xy 125.564437 -242.577112) (xy 125.522421 -242.546586) (xy 125.485698 -242.509863)
			(xy 125.455172 -242.467847) (xy 125.431594 -242.421573) (xy 125.415546 -242.37218) (xy 125.407421 -242.320885)
			(xy 125.127511 -242.320885) (xy 125.119386 -242.37218) (xy 125.103338 -242.421573) (xy 125.07976 -242.467847)
			(xy 125.049234 -242.509863) (xy 125.012511 -242.546586) (xy 124.970495 -242.577112) (xy 124.924221 -242.60069)
			(xy 124.874828 -242.616738) (xy 124.823533 -242.624863) (xy 124.771599 -242.624863) (xy 124.720304 -242.616738)
			(xy 124.670911 -242.60069) (xy 124.624637 -242.577112) (xy 124.582621 -242.546586) (xy 124.545898 -242.509863)
			(xy 124.515372 -242.467847) (xy 124.491794 -242.421573) (xy 124.475746 -242.37218) (xy 124.467621 -242.320885)
			(xy 124.187711 -242.320885) (xy 124.179586 -242.37218) (xy 124.163538 -242.421573) (xy 124.13996 -242.467847)
			(xy 124.109434 -242.509863) (xy 124.072711 -242.546586) (xy 124.030695 -242.577112) (xy 123.984421 -242.60069)
			(xy 123.935028 -242.616738) (xy 123.883733 -242.624863) (xy 123.831799 -242.624863) (xy 123.780504 -242.616738)
			(xy 123.731111 -242.60069) (xy 123.684837 -242.577112) (xy 123.642821 -242.546586) (xy 123.606098 -242.509863)
			(xy 123.575572 -242.467847) (xy 123.551994 -242.421573) (xy 123.535946 -242.37218) (xy 123.527821 -242.320885)
			(xy 123.247911 -242.320885) (xy 123.239786 -242.37218) (xy 123.223738 -242.421573) (xy 123.20016 -242.467847)
			(xy 123.169634 -242.509863) (xy 123.132911 -242.546586) (xy 123.090895 -242.577112) (xy 123.044621 -242.60069)
			(xy 122.995228 -242.616738) (xy 122.943933 -242.624863) (xy 122.891999 -242.624863) (xy 122.840704 -242.616738)
			(xy 122.791311 -242.60069) (xy 122.745037 -242.577112) (xy 122.703021 -242.546586) (xy 122.666298 -242.509863)
			(xy 122.635772 -242.467847) (xy 122.612194 -242.421573) (xy 122.596146 -242.37218) (xy 122.588021 -242.320885)
			(xy 122.308111 -242.320885) (xy 122.299986 -242.37218) (xy 122.283938 -242.421573) (xy 122.26036 -242.467847)
			(xy 122.229834 -242.509863) (xy 122.193111 -242.546586) (xy 122.151095 -242.577112) (xy 122.104821 -242.60069)
			(xy 122.055428 -242.616738) (xy 122.004133 -242.624863) (xy 121.952199 -242.624863) (xy 121.900904 -242.616738)
			(xy 121.851511 -242.60069) (xy 121.805237 -242.577112) (xy 121.763221 -242.546586) (xy 121.726498 -242.509863)
			(xy 121.695972 -242.467847) (xy 121.672394 -242.421573) (xy 121.656346 -242.37218) (xy 121.648221 -242.320885)
			(xy 114.78997 -242.320885) (xy 114.789965 -242.321139) (xy 114.78184 -242.372434) (xy 114.765792 -242.421827)
			(xy 114.742214 -242.468101) (xy 114.711688 -242.510117) (xy 114.674965 -242.54684) (xy 114.632949 -242.577366)
			(xy 114.586675 -242.600944) (xy 114.537282 -242.616992) (xy 114.485987 -242.625117) (xy 114.434053 -242.625117)
			(xy 114.382758 -242.616992) (xy 114.333365 -242.600944) (xy 114.287091 -242.577366) (xy 114.245075 -242.54684)
			(xy 114.208352 -242.510117) (xy 114.177826 -242.468101) (xy 114.154248 -242.421827) (xy 114.1382 -242.372434)
			(xy 114.130075 -242.321139) (xy 113.850165 -242.321139) (xy 113.84204 -242.372434) (xy 113.825992 -242.421827)
			(xy 113.802414 -242.468101) (xy 113.771888 -242.510117) (xy 113.735165 -242.54684) (xy 113.693149 -242.577366)
			(xy 113.646875 -242.600944) (xy 113.597482 -242.616992) (xy 113.546187 -242.625117) (xy 113.494253 -242.625117)
			(xy 113.442958 -242.616992) (xy 113.393565 -242.600944) (xy 113.347291 -242.577366) (xy 113.305275 -242.54684)
			(xy 113.268552 -242.510117) (xy 113.238026 -242.468101) (xy 113.214448 -242.421827) (xy 113.1984 -242.372434)
			(xy 113.190275 -242.321139) (xy 112.910111 -242.321139) (xy 112.901986 -242.372434) (xy 112.885938 -242.421827)
			(xy 112.86236 -242.468101) (xy 112.831834 -242.510117) (xy 112.795111 -242.54684) (xy 112.753095 -242.577366)
			(xy 112.706821 -242.600944) (xy 112.657428 -242.616992) (xy 112.606133 -242.625117) (xy 112.554199 -242.625117)
			(xy 112.502904 -242.616992) (xy 112.453511 -242.600944) (xy 112.407237 -242.577366) (xy 112.365221 -242.54684)
			(xy 112.328498 -242.510117) (xy 112.297972 -242.468101) (xy 112.274394 -242.421827) (xy 112.258346 -242.372434)
			(xy 112.250221 -242.321139) (xy 111.970311 -242.321139) (xy 111.962186 -242.372434) (xy 111.946138 -242.421827)
			(xy 111.92256 -242.468101) (xy 111.892034 -242.510117) (xy 111.855311 -242.54684) (xy 111.813295 -242.577366)
			(xy 111.767021 -242.600944) (xy 111.717628 -242.616992) (xy 111.666333 -242.625117) (xy 111.614399 -242.625117)
			(xy 111.563104 -242.616992) (xy 111.513711 -242.600944) (xy 111.467437 -242.577366) (xy 111.425421 -242.54684)
			(xy 111.388698 -242.510117) (xy 111.358172 -242.468101) (xy 111.334594 -242.421827) (xy 111.318546 -242.372434)
			(xy 111.310421 -242.321139) (xy 111.030765 -242.321139) (xy 111.02264 -242.372434) (xy 111.006592 -242.421827)
			(xy 110.983014 -242.468101) (xy 110.952488 -242.510117) (xy 110.915765 -242.54684) (xy 110.873749 -242.577366)
			(xy 110.827475 -242.600944) (xy 110.778082 -242.616992) (xy 110.726787 -242.625117) (xy 110.674853 -242.625117)
			(xy 110.623558 -242.616992) (xy 110.574165 -242.600944) (xy 110.527891 -242.577366) (xy 110.485875 -242.54684)
			(xy 110.449152 -242.510117) (xy 110.418626 -242.468101) (xy 110.395048 -242.421827) (xy 110.379 -242.372434)
			(xy 110.370875 -242.321139) (xy 110.090711 -242.321139) (xy 110.082586 -242.372434) (xy 110.066538 -242.421827)
			(xy 110.04296 -242.468101) (xy 110.012434 -242.510117) (xy 109.975711 -242.54684) (xy 109.933695 -242.577366)
			(xy 109.887421 -242.600944) (xy 109.838028 -242.616992) (xy 109.786733 -242.625117) (xy 109.734799 -242.625117)
			(xy 109.683504 -242.616992) (xy 109.634111 -242.600944) (xy 109.587837 -242.577366) (xy 109.545821 -242.54684)
			(xy 109.509098 -242.510117) (xy 109.478572 -242.468101) (xy 109.454994 -242.421827) (xy 109.438946 -242.372434)
			(xy 109.430821 -242.321139) (xy 109.010441 -242.321139) (xy 109.010704 -242.334542) (xy 109.010704 -242.334796)
			(xy 109.010249 -242.359322) (xy 109.002987 -242.407835) (xy 108.988636 -242.454742) (xy 108.967512 -242.499014)
			(xy 108.940078 -242.539678) (xy 108.923836 -242.558062) (xy 108.913991 -242.569519) (xy 108.90098 -242.596767)
			(xy 108.896519 -242.626631) (xy 108.900998 -242.656492) (xy 108.914025 -242.683733) (xy 108.923836 -242.695222)
			(xy 108.940667 -242.714304) (xy 108.968855 -242.756662) (xy 108.97997 -242.77955) (xy 108.986343 -242.792211)
			(xy 109.004826 -242.813684) (xy 109.028501 -242.82925) (xy 109.055541 -242.837708) (xy 109.083865 -242.838408)
			(xy 109.111291 -242.831295) (xy 109.123734 -242.824508) (xy 109.149283 -242.810182) (xy 109.204192 -242.789804)
			(xy 109.261836 -242.779437) (xy 109.29112 -242.778788) (xy 109.317089 -242.779215) (xy 109.368389 -242.787343)
			(xy 109.417785 -242.803395) (xy 109.464062 -242.826977) (xy 109.50608 -242.857507) (xy 109.542806 -242.894235)
			(xy 109.573334 -242.936255) (xy 109.596913 -242.982534) (xy 109.612962 -243.031931) (xy 109.621087 -243.08323)
			(xy 109.621087 -243.13517) (xy 109.621081 -243.135209) (xy 109.900975 -243.135209) (xy 109.900975 -243.083275)
			(xy 109.9091 -243.03198) (xy 109.925148 -242.982587) (xy 109.948726 -242.936313) (xy 109.979252 -242.894297)
			(xy 110.015975 -242.857574) (xy 110.057991 -242.827048) (xy 110.104265 -242.80347) (xy 110.153658 -242.787422)
			(xy 110.204953 -242.779297) (xy 110.256887 -242.779297) (xy 110.308182 -242.787422) (xy 110.357575 -242.80347)
			(xy 110.403849 -242.827048) (xy 110.445865 -242.857574) (xy 110.482588 -242.894297) (xy 110.513114 -242.936313)
			(xy 110.536692 -242.982587) (xy 110.55274 -243.03198) (xy 110.560865 -243.083275) (xy 110.561374 -243.109242)
			(xy 110.560865 -243.135209) (xy 110.840775 -243.135209) (xy 110.840775 -243.083275) (xy 110.8489 -243.03198)
			(xy 110.864948 -242.982587) (xy 110.888526 -242.936313) (xy 110.919052 -242.894297) (xy 110.955775 -242.857574)
			(xy 110.997791 -242.827048) (xy 111.044065 -242.80347) (xy 111.093458 -242.787422) (xy 111.144753 -242.779297)
			(xy 111.196687 -242.779297) (xy 111.247982 -242.787422) (xy 111.297375 -242.80347) (xy 111.343649 -242.827048)
			(xy 111.385665 -242.857574) (xy 111.422388 -242.894297) (xy 111.452914 -242.936313) (xy 111.476492 -242.982587)
			(xy 111.49254 -243.03198) (xy 111.500665 -243.083275) (xy 111.501174 -243.109242) (xy 111.500665 -243.135209)
			(xy 111.780575 -243.135209) (xy 111.780575 -243.083275) (xy 111.7887 -243.03198) (xy 111.804748 -242.982587)
			(xy 111.828326 -242.936313) (xy 111.858852 -242.894297) (xy 111.895575 -242.857574) (xy 111.937591 -242.827048)
			(xy 111.983865 -242.80347) (xy 112.033258 -242.787422) (xy 112.084553 -242.779297) (xy 112.136487 -242.779297)
			(xy 112.187782 -242.787422) (xy 112.237175 -242.80347) (xy 112.283449 -242.827048) (xy 112.325465 -242.857574)
			(xy 112.362188 -242.894297) (xy 112.392714 -242.936313) (xy 112.416292 -242.982587) (xy 112.43234 -243.03198)
			(xy 112.440465 -243.083275) (xy 112.440974 -243.109242) (xy 112.440465 -243.135209) (xy 112.720121 -243.135209)
			(xy 112.720121 -243.083275) (xy 112.728246 -243.03198) (xy 112.744294 -242.982587) (xy 112.767872 -242.936313)
			(xy 112.798398 -242.894297) (xy 112.835121 -242.857574) (xy 112.877137 -242.827048) (xy 112.923411 -242.80347)
			(xy 112.972804 -242.787422) (xy 113.024099 -242.779297) (xy 113.076033 -242.779297) (xy 113.127328 -242.787422)
			(xy 113.176721 -242.80347) (xy 113.222995 -242.827048) (xy 113.265011 -242.857574) (xy 113.301734 -242.894297)
			(xy 113.33226 -242.936313) (xy 113.355838 -242.982587) (xy 113.371886 -243.03198) (xy 113.380011 -243.083275)
			(xy 113.38052 -243.109242) (xy 113.380011 -243.135209) (xy 113.660175 -243.135209) (xy 113.660175 -243.083275)
			(xy 113.6683 -243.03198) (xy 113.684348 -242.982587) (xy 113.707926 -242.936313) (xy 113.738452 -242.894297)
			(xy 113.775175 -242.857574) (xy 113.817191 -242.827048) (xy 113.863465 -242.80347) (xy 113.912858 -242.787422)
			(xy 113.964153 -242.779297) (xy 114.016087 -242.779297) (xy 114.067382 -242.787422) (xy 114.116775 -242.80347)
			(xy 114.163049 -242.827048) (xy 114.205065 -242.857574) (xy 114.241788 -242.894297) (xy 114.272314 -242.936313)
			(xy 114.295892 -242.982587) (xy 114.31194 -243.03198) (xy 114.320065 -243.083275) (xy 114.320574 -243.109242)
			(xy 114.320065 -243.135209) (xy 114.31194 -243.186504) (xy 114.295892 -243.235897) (xy 114.272314 -243.282171)
			(xy 114.241788 -243.324187) (xy 114.205065 -243.36091) (xy 114.163049 -243.391436) (xy 114.116775 -243.415014)
			(xy 114.067382 -243.431062) (xy 114.016087 -243.439187) (xy 113.964153 -243.439187) (xy 113.912858 -243.431062)
			(xy 113.863465 -243.415014) (xy 113.817191 -243.391436) (xy 113.775175 -243.36091) (xy 113.738452 -243.324187)
			(xy 113.707926 -243.282171) (xy 113.684348 -243.235897) (xy 113.6683 -243.186504) (xy 113.660175 -243.135209)
			(xy 113.380011 -243.135209) (xy 113.371886 -243.186504) (xy 113.355838 -243.235897) (xy 113.33226 -243.282171)
			(xy 113.301734 -243.324187) (xy 113.265011 -243.36091) (xy 113.222995 -243.391436) (xy 113.176721 -243.415014)
			(xy 113.127328 -243.431062) (xy 113.076033 -243.439187) (xy 113.024099 -243.439187) (xy 112.972804 -243.431062)
			(xy 112.923411 -243.415014) (xy 112.877137 -243.391436) (xy 112.835121 -243.36091) (xy 112.798398 -243.324187)
			(xy 112.767872 -243.282171) (xy 112.744294 -243.235897) (xy 112.728246 -243.186504) (xy 112.720121 -243.135209)
			(xy 112.440465 -243.135209) (xy 112.43234 -243.186504) (xy 112.416292 -243.235897) (xy 112.392714 -243.282171)
			(xy 112.362188 -243.324187) (xy 112.325465 -243.36091) (xy 112.283449 -243.391436) (xy 112.237175 -243.415014)
			(xy 112.187782 -243.431062) (xy 112.136487 -243.439187) (xy 112.084553 -243.439187) (xy 112.033258 -243.431062)
			(xy 111.983865 -243.415014) (xy 111.937591 -243.391436) (xy 111.895575 -243.36091) (xy 111.858852 -243.324187)
			(xy 111.828326 -243.282171) (xy 111.804748 -243.235897) (xy 111.7887 -243.186504) (xy 111.780575 -243.135209)
			(xy 111.500665 -243.135209) (xy 111.49254 -243.186504) (xy 111.476492 -243.235897) (xy 111.452914 -243.282171)
			(xy 111.422388 -243.324187) (xy 111.385665 -243.36091) (xy 111.343649 -243.391436) (xy 111.297375 -243.415014)
			(xy 111.247982 -243.431062) (xy 111.196687 -243.439187) (xy 111.144753 -243.439187) (xy 111.093458 -243.431062)
			(xy 111.044065 -243.415014) (xy 110.997791 -243.391436) (xy 110.955775 -243.36091) (xy 110.919052 -243.324187)
			(xy 110.888526 -243.282171) (xy 110.864948 -243.235897) (xy 110.8489 -243.186504) (xy 110.840775 -243.135209)
			(xy 110.560865 -243.135209) (xy 110.55274 -243.186504) (xy 110.536692 -243.235897) (xy 110.513114 -243.282171)
			(xy 110.482588 -243.324187) (xy 110.445865 -243.36091) (xy 110.403849 -243.391436) (xy 110.357575 -243.415014)
			(xy 110.308182 -243.431062) (xy 110.256887 -243.439187) (xy 110.204953 -243.439187) (xy 110.153658 -243.431062)
			(xy 110.104265 -243.415014) (xy 110.057991 -243.391436) (xy 110.015975 -243.36091) (xy 109.979252 -243.324187)
			(xy 109.948726 -243.282171) (xy 109.925148 -243.235897) (xy 109.9091 -243.186504) (xy 109.900975 -243.135209)
			(xy 109.621081 -243.135209) (xy 109.612962 -243.186469) (xy 109.596913 -243.235866) (xy 109.573334 -243.282145)
			(xy 109.542806 -243.324165) (xy 109.50608 -243.360893) (xy 109.464062 -243.391423) (xy 109.417785 -243.415005)
			(xy 109.368389 -243.431057) (xy 109.317089 -243.439185) (xy 109.29112 -243.439696) (xy 109.264287 -243.4392)
			(xy 109.211326 -243.43053) (xy 109.160462 -243.413416) (xy 109.113032 -243.388306) (xy 109.070284 -243.355862)
			(xy 109.033341 -243.316936) (xy 109.003174 -243.272552) (xy 108.9914 -243.248434) (xy 108.985068 -243.235751)
			(xy 108.966574 -243.214277) (xy 108.942891 -243.198713) (xy 108.915842 -243.190259) (xy 108.887511 -243.189565)
			(xy 108.860081 -243.196685) (xy 108.847636 -243.203476) (xy 108.822093 -243.217812) (xy 108.767181 -243.238186)
			(xy 108.709535 -243.248549) (xy 108.68025 -243.249196) (xy 108.652954 -243.248612) (xy 108.599103 -243.239639)
			(xy 108.547463 -243.221931) (xy 108.499438 -243.195969) (xy 108.456339 -243.16246) (xy 108.437426 -243.14277)
			(xy 108.428151 -243.133144) (xy 108.40558 -243.11883) (xy 108.380066 -243.11087) (xy 108.35336 -243.10981)
			(xy 108.327295 -243.115722) (xy 108.30366 -243.128201) (xy 108.284078 -243.14639) (xy 108.276644 -243.157502)
			(xy 108.261361 -243.180736) (xy 108.224282 -243.222176) (xy 108.180788 -243.256825) (xy 108.132109 -243.283704)
			(xy 108.079617 -243.302056) (xy 108.024794 -243.311363) (xy 107.99699 -243.311934) (xy 107.969691 -243.311409)
			(xy 107.915837 -243.302425) (xy 107.864195 -243.284703) (xy 107.816172 -243.258727) (xy 107.773076 -243.225205)
			(xy 107.754166 -243.205508) (xy 107.744333 -243.195528) (xy 107.720449 -243.180902) (xy 107.693493 -243.173303)
			(xy 107.665487 -243.173303) (xy 107.638531 -243.180902) (xy 107.614647 -243.195528) (xy 107.604814 -243.205508)
			(xy 107.585906 -243.225205) (xy 107.542806 -243.258716) (xy 107.494781 -243.284682) (xy 107.443139 -243.302395)
			(xy 107.389288 -243.311373) (xy 107.36199 -243.311934) (xy 107.336022 -243.311464) (xy 107.284725 -243.303338)
			(xy 107.235331 -243.287287) (xy 107.189055 -243.263708) (xy 107.147038 -243.233179) (xy 107.110314 -243.196454)
			(xy 107.079787 -243.154436) (xy 107.056209 -243.10816) (xy 107.04016 -243.058765) (xy 107.032035 -243.007468)
			(xy 106.421951 -243.007468) (xy 106.413826 -243.058765) (xy 106.397777 -243.10816) (xy 106.374198 -243.154435)
			(xy 106.34367 -243.196452) (xy 106.306945 -243.233176) (xy 106.264927 -243.263703) (xy 106.21865 -243.287281)
			(xy 106.169255 -243.303329) (xy 106.117958 -243.311452) (xy 106.09199 -243.311934) (xy 106.064691 -243.311409)
			(xy 106.010837 -243.302425) (xy 105.959195 -243.284703) (xy 105.911172 -243.258727) (xy 105.868076 -243.225205)
			(xy 105.849166 -243.205508) (xy 105.839333 -243.195528) (xy 105.815449 -243.180902) (xy 105.788493 -243.173303)
			(xy 105.760487 -243.173303) (xy 105.733531 -243.180902) (xy 105.709647 -243.195528) (xy 105.699814 -243.205508)
			(xy 105.680906 -243.225205) (xy 105.637806 -243.258716) (xy 105.589781 -243.284682) (xy 105.538139 -243.302395)
			(xy 105.484288 -243.311373) (xy 105.45699 -243.311934) (xy 105.431022 -243.311464) (xy 105.379725 -243.303338)
			(xy 105.330331 -243.287287) (xy 105.284055 -243.263708) (xy 105.242038 -243.233179) (xy 105.205314 -243.196454)
			(xy 105.174787 -243.154436) (xy 105.151209 -243.10816) (xy 105.13516 -243.058765) (xy 105.127035 -243.007468)
			(xy 104.897951 -243.007468) (xy 104.889826 -243.058765) (xy 104.873777 -243.10816) (xy 104.850198 -243.154435)
			(xy 104.81967 -243.196452) (xy 104.782945 -243.233176) (xy 104.740927 -243.263703) (xy 104.69465 -243.287281)
			(xy 104.645255 -243.303329) (xy 104.593958 -243.311452) (xy 104.56799 -243.311934) (xy 104.567736 -243.311934)
			(xy 104.543211 -243.311452) (xy 104.4947 -243.304195) (xy 104.447793 -243.28985) (xy 104.403521 -243.268732)
			(xy 104.362855 -243.241305) (xy 104.34447 -243.225066) (xy 104.332981 -243.215263) (xy 104.305744 -243.202249)
			(xy 104.27589 -243.197781) (xy 104.246036 -243.202249) (xy 104.218799 -243.215263) (xy 104.20731 -243.225066)
			(xy 104.188936 -243.241321) (xy 104.148275 -243.268766) (xy 104.104002 -243.289895) (xy 104.05709 -243.304241)
			(xy 104.008572 -243.31149) (xy 103.984044 -243.311934) (xy 103.98379 -243.311934) (xy 103.957822 -243.311464)
			(xy 103.906525 -243.303338) (xy 103.857131 -243.287287) (xy 103.810855 -243.263708) (xy 103.768838 -243.233179)
			(xy 103.732114 -243.196454) (xy 103.701587 -243.154436) (xy 103.678009 -243.10816) (xy 103.66196 -243.058765)
			(xy 103.653835 -243.007468) (xy 102.08615 -243.007468) (xy 102.094032 -243.031726) (xy 102.102157 -243.083021)
			(xy 102.102666 -243.108988) (xy 102.102157 -243.134955) (xy 102.094032 -243.18625) (xy 102.077984 -243.235643)
			(xy 102.054406 -243.281917) (xy 102.02388 -243.323933) (xy 101.987157 -243.360656) (xy 101.945141 -243.391182)
			(xy 101.898867 -243.41476) (xy 101.849474 -243.430808) (xy 101.798179 -243.438933) (xy 101.746245 -243.438933)
			(xy 101.69495 -243.430808) (xy 101.645557 -243.41476) (xy 101.599283 -243.391182) (xy 101.557267 -243.360656)
			(xy 101.520544 -243.323933) (xy 101.490018 -243.281917) (xy 101.46644 -243.235643) (xy 101.450392 -243.18625)
			(xy 101.442267 -243.134955) (xy 101.162357 -243.134955) (xy 101.154232 -243.18625) (xy 101.138184 -243.235643)
			(xy 101.114606 -243.281917) (xy 101.08408 -243.323933) (xy 101.047357 -243.360656) (xy 101.005341 -243.391182)
			(xy 100.959067 -243.41476) (xy 100.909674 -243.430808) (xy 100.858379 -243.438933) (xy 100.806445 -243.438933)
			(xy 100.75515 -243.430808) (xy 100.705757 -243.41476) (xy 100.659483 -243.391182) (xy 100.617467 -243.360656)
			(xy 100.580744 -243.323933) (xy 100.550218 -243.281917) (xy 100.52664 -243.235643) (xy 100.510592 -243.18625)
			(xy 100.502467 -243.134955) (xy 100.222557 -243.134955) (xy 100.214432 -243.18625) (xy 100.198384 -243.235643)
			(xy 100.174806 -243.281917) (xy 100.14428 -243.323933) (xy 100.107557 -243.360656) (xy 100.065541 -243.391182)
			(xy 100.019267 -243.41476) (xy 99.969874 -243.430808) (xy 99.918579 -243.438933) (xy 99.866645 -243.438933)
			(xy 99.81535 -243.430808) (xy 99.765957 -243.41476) (xy 99.719683 -243.391182) (xy 99.677667 -243.360656)
			(xy 99.640944 -243.323933) (xy 99.610418 -243.281917) (xy 99.58684 -243.235643) (xy 99.570792 -243.18625)
			(xy 99.562667 -243.134955) (xy 99.282757 -243.134955) (xy 99.274632 -243.18625) (xy 99.258584 -243.235643)
			(xy 99.235006 -243.281917) (xy 99.20448 -243.323933) (xy 99.167757 -243.360656) (xy 99.125741 -243.391182)
			(xy 99.079467 -243.41476) (xy 99.030074 -243.430808) (xy 98.978779 -243.438933) (xy 98.926845 -243.438933)
			(xy 98.87555 -243.430808) (xy 98.826157 -243.41476) (xy 98.779883 -243.391182) (xy 98.737867 -243.360656)
			(xy 98.701144 -243.323933) (xy 98.670618 -243.281917) (xy 98.64704 -243.235643) (xy 98.630992 -243.18625)
			(xy 98.622867 -243.134955) (xy 98.343211 -243.134955) (xy 98.335086 -243.18625) (xy 98.319038 -243.235643)
			(xy 98.29546 -243.281917) (xy 98.264934 -243.323933) (xy 98.228211 -243.360656) (xy 98.186195 -243.391182)
			(xy 98.139921 -243.41476) (xy 98.090528 -243.430808) (xy 98.039233 -243.438933) (xy 97.987299 -243.438933)
			(xy 97.936004 -243.430808) (xy 97.886611 -243.41476) (xy 97.840337 -243.391182) (xy 97.798321 -243.360656)
			(xy 97.761598 -243.323933) (xy 97.731072 -243.281917) (xy 97.707494 -243.235643) (xy 97.691446 -243.18625)
			(xy 97.683321 -243.134955) (xy 97.403157 -243.134955) (xy 97.395032 -243.18625) (xy 97.378984 -243.235643)
			(xy 97.355406 -243.281917) (xy 97.32488 -243.323933) (xy 97.288157 -243.360656) (xy 97.246141 -243.391182)
			(xy 97.199867 -243.41476) (xy 97.150474 -243.430808) (xy 97.099179 -243.438933) (xy 97.047245 -243.438933)
			(xy 96.99595 -243.430808) (xy 96.946557 -243.41476) (xy 96.900283 -243.391182) (xy 96.858267 -243.360656)
			(xy 96.821544 -243.323933) (xy 96.791018 -243.281917) (xy 96.76744 -243.235643) (xy 96.751392 -243.18625)
			(xy 96.743267 -243.134955) (xy 96.463357 -243.134955) (xy 96.455232 -243.18625) (xy 96.439184 -243.235643)
			(xy 96.415606 -243.281917) (xy 96.38508 -243.323933) (xy 96.348357 -243.360656) (xy 96.306341 -243.391182)
			(xy 96.260067 -243.41476) (xy 96.210674 -243.430808) (xy 96.159379 -243.438933) (xy 96.107445 -243.438933)
			(xy 96.05615 -243.430808) (xy 96.006757 -243.41476) (xy 95.960483 -243.391182) (xy 95.918467 -243.360656)
			(xy 95.881744 -243.323933) (xy 95.851218 -243.281917) (xy 95.82764 -243.235643) (xy 95.811592 -243.18625)
			(xy 95.803467 -243.134955) (xy 95.523557 -243.134955) (xy 95.515432 -243.18625) (xy 95.499384 -243.235643)
			(xy 95.475806 -243.281917) (xy 95.44528 -243.323933) (xy 95.408557 -243.360656) (xy 95.366541 -243.391182)
			(xy 95.320267 -243.41476) (xy 95.270874 -243.430808) (xy 95.219579 -243.438933) (xy 95.167645 -243.438933)
			(xy 95.11635 -243.430808) (xy 95.066957 -243.41476) (xy 95.020683 -243.391182) (xy 94.978667 -243.360656)
			(xy 94.941944 -243.323933) (xy 94.911418 -243.281917) (xy 94.88784 -243.235643) (xy 94.871792 -243.18625)
			(xy 94.863667 -243.134955) (xy 94.583757 -243.134955) (xy 94.575632 -243.18625) (xy 94.559584 -243.235643)
			(xy 94.536006 -243.281917) (xy 94.50548 -243.323933) (xy 94.468757 -243.360656) (xy 94.426741 -243.391182)
			(xy 94.380467 -243.41476) (xy 94.331074 -243.430808) (xy 94.279779 -243.438933) (xy 94.227845 -243.438933)
			(xy 94.17655 -243.430808) (xy 94.127157 -243.41476) (xy 94.080883 -243.391182) (xy 94.038867 -243.360656)
			(xy 94.002144 -243.323933) (xy 93.971618 -243.281917) (xy 93.94804 -243.235643) (xy 93.931992 -243.18625)
			(xy 93.923867 -243.134955) (xy 93.643957 -243.134955) (xy 93.635832 -243.18625) (xy 93.619784 -243.235643)
			(xy 93.596206 -243.281917) (xy 93.56568 -243.323933) (xy 93.528957 -243.360656) (xy 93.486941 -243.391182)
			(xy 93.440667 -243.41476) (xy 93.391274 -243.430808) (xy 93.339979 -243.438933) (xy 93.288045 -243.438933)
			(xy 93.23675 -243.430808) (xy 93.187357 -243.41476) (xy 93.141083 -243.391182) (xy 93.099067 -243.360656)
			(xy 93.062344 -243.323933) (xy 93.031818 -243.281917) (xy 93.00824 -243.235643) (xy 92.992192 -243.18625)
			(xy 92.984067 -243.134955) (xy 92.704157 -243.134955) (xy 92.696032 -243.18625) (xy 92.679984 -243.235643)
			(xy 92.656406 -243.281917) (xy 92.62588 -243.323933) (xy 92.589157 -243.360656) (xy 92.547141 -243.391182)
			(xy 92.500867 -243.41476) (xy 92.451474 -243.430808) (xy 92.400179 -243.438933) (xy 92.348245 -243.438933)
			(xy 92.29695 -243.430808) (xy 92.247557 -243.41476) (xy 92.201283 -243.391182) (xy 92.159267 -243.360656)
			(xy 92.122544 -243.323933) (xy 92.092018 -243.281917) (xy 92.06844 -243.235643) (xy 92.052392 -243.18625)
			(xy 92.044267 -243.134955) (xy 91.764991 -243.134955) (xy 91.764991 -243.135547) (xy 91.756509 -243.187969)
			(xy 91.739761 -243.238362) (xy 91.715178 -243.285433) (xy 91.683392 -243.327973) (xy 91.645218 -243.364889)
			(xy 91.601637 -243.395232) (xy 91.577922 -243.407184) (xy 91.565222 -243.41328) (xy 91.53525 -243.458746)
			(xy 91.53525 -243.586254) (xy 91.535681 -243.595276) (xy 91.54214 -243.612128) (xy 91.554133 -243.625615)
			(xy 91.56192 -243.630196) (xy 91.604846 -243.65077) (xy 91.645232 -243.670328) (xy 91.650455 -243.672667)
			(xy 91.661609 -243.675221) (xy 91.66733 -243.675408) (xy 91.69781 -243.664486) (xy 91.70416 -243.65966)
			(xy 91.725908 -243.643779) (xy 91.773477 -243.618546) (xy 91.824504 -243.601348) (xy 91.877642 -243.592639)
			(xy 91.904566 -243.592096) (xy 91.930557 -243.592577) (xy 91.981899 -243.600703) (xy 92.031337 -243.616763)
			(xy 92.077655 -243.640358) (xy 92.11971 -243.670909) (xy 92.156468 -243.707664) (xy 92.187024 -243.749716)
			(xy 92.210624 -243.796031) (xy 92.226689 -243.845468) (xy 92.234821 -243.896809) (xy 92.234821 -243.948771)
			(xy 92.514421 -243.948771) (xy 92.514421 -243.896837) (xy 92.522546 -243.845542) (xy 92.538594 -243.796149)
			(xy 92.562172 -243.749875) (xy 92.592698 -243.707859) (xy 92.629421 -243.671136) (xy 92.671437 -243.64061)
			(xy 92.717711 -243.617032) (xy 92.767104 -243.600984) (xy 92.818399 -243.592859) (xy 92.870333 -243.592859)
			(xy 92.921628 -243.600984) (xy 92.971021 -243.617032) (xy 93.017295 -243.64061) (xy 93.059311 -243.671136)
			(xy 93.096034 -243.707859) (xy 93.12656 -243.749875) (xy 93.150138 -243.796149) (xy 93.166186 -243.845542)
			(xy 93.174311 -243.896837) (xy 93.17482 -243.922804) (xy 93.174311 -243.948771) (xy 93.454221 -243.948771)
			(xy 93.454221 -243.896837) (xy 93.462346 -243.845542) (xy 93.478394 -243.796149) (xy 93.501972 -243.749875)
			(xy 93.532498 -243.707859) (xy 93.569221 -243.671136) (xy 93.611237 -243.64061) (xy 93.657511 -243.617032)
			(xy 93.706904 -243.600984) (xy 93.758199 -243.592859) (xy 93.810133 -243.592859) (xy 93.861428 -243.600984)
			(xy 93.910821 -243.617032) (xy 93.957095 -243.64061) (xy 93.999111 -243.671136) (xy 94.035834 -243.707859)
			(xy 94.06636 -243.749875) (xy 94.089938 -243.796149) (xy 94.105986 -243.845542) (xy 94.114111 -243.896837)
			(xy 94.11462 -243.922804) (xy 94.114111 -243.948771) (xy 94.393767 -243.948771) (xy 94.393767 -243.896837)
			(xy 94.401892 -243.845542) (xy 94.41794 -243.796149) (xy 94.441518 -243.749875) (xy 94.472044 -243.707859)
			(xy 94.508767 -243.671136) (xy 94.550783 -243.64061) (xy 94.597057 -243.617032) (xy 94.64645 -243.600984)
			(xy 94.697745 -243.592859) (xy 94.749679 -243.592859) (xy 94.800974 -243.600984) (xy 94.850367 -243.617032)
			(xy 94.896641 -243.64061) (xy 94.938657 -243.671136) (xy 94.97538 -243.707859) (xy 95.005906 -243.749875)
			(xy 95.029484 -243.796149) (xy 95.045532 -243.845542) (xy 95.053657 -243.896837) (xy 95.054166 -243.922804)
			(xy 95.053657 -243.948771) (xy 95.333821 -243.948771) (xy 95.333821 -243.896837) (xy 95.341946 -243.845542)
			(xy 95.357994 -243.796149) (xy 95.381572 -243.749875) (xy 95.412098 -243.707859) (xy 95.448821 -243.671136)
			(xy 95.490837 -243.64061) (xy 95.537111 -243.617032) (xy 95.586504 -243.600984) (xy 95.637799 -243.592859)
			(xy 95.689733 -243.592859) (xy 95.741028 -243.600984) (xy 95.790421 -243.617032) (xy 95.836695 -243.64061)
			(xy 95.878711 -243.671136) (xy 95.915434 -243.707859) (xy 95.94596 -243.749875) (xy 95.969538 -243.796149)
			(xy 95.985586 -243.845542) (xy 95.993711 -243.896837) (xy 95.99422 -243.922804) (xy 95.993711 -243.948771)
			(xy 96.273621 -243.948771) (xy 96.273621 -243.896837) (xy 96.281746 -243.845542) (xy 96.297794 -243.796149)
			(xy 96.321372 -243.749875) (xy 96.351898 -243.707859) (xy 96.388621 -243.671136) (xy 96.430637 -243.64061)
			(xy 96.476911 -243.617032) (xy 96.526304 -243.600984) (xy 96.577599 -243.592859) (xy 96.629533 -243.592859)
			(xy 96.680828 -243.600984) (xy 96.730221 -243.617032) (xy 96.776495 -243.64061) (xy 96.818511 -243.671136)
			(xy 96.855234 -243.707859) (xy 96.88576 -243.749875) (xy 96.909338 -243.796149) (xy 96.925386 -243.845542)
			(xy 96.933511 -243.896837) (xy 96.93402 -243.922804) (xy 96.933511 -243.948771) (xy 97.213421 -243.948771)
			(xy 97.213421 -243.896837) (xy 97.221546 -243.845542) (xy 97.237594 -243.796149) (xy 97.261172 -243.749875)
			(xy 97.291698 -243.707859) (xy 97.328421 -243.671136) (xy 97.370437 -243.64061) (xy 97.416711 -243.617032)
			(xy 97.466104 -243.600984) (xy 97.517399 -243.592859) (xy 97.569333 -243.592859) (xy 97.620628 -243.600984)
			(xy 97.670021 -243.617032) (xy 97.716295 -243.64061) (xy 97.758311 -243.671136) (xy 97.795034 -243.707859)
			(xy 97.82556 -243.749875) (xy 97.849138 -243.796149) (xy 97.865186 -243.845542) (xy 97.873311 -243.896837)
			(xy 97.87382 -243.922804) (xy 97.873311 -243.948771) (xy 98.153221 -243.948771) (xy 98.153221 -243.896837)
			(xy 98.161346 -243.845542) (xy 98.177394 -243.796149) (xy 98.200972 -243.749875) (xy 98.231498 -243.707859)
			(xy 98.268221 -243.671136) (xy 98.310237 -243.64061) (xy 98.356511 -243.617032) (xy 98.405904 -243.600984)
			(xy 98.457199 -243.592859) (xy 98.509133 -243.592859) (xy 98.560428 -243.600984) (xy 98.609821 -243.617032)
			(xy 98.656095 -243.64061) (xy 98.698111 -243.671136) (xy 98.734834 -243.707859) (xy 98.76536 -243.749875)
			(xy 98.788938 -243.796149) (xy 98.804986 -243.845542) (xy 98.813111 -243.896837) (xy 98.81362 -243.922804)
			(xy 98.813111 -243.948771) (xy 99.093021 -243.948771) (xy 99.093021 -243.896837) (xy 99.101146 -243.845542)
			(xy 99.117194 -243.796149) (xy 99.140772 -243.749875) (xy 99.171298 -243.707859) (xy 99.208021 -243.671136)
			(xy 99.250037 -243.64061) (xy 99.296311 -243.617032) (xy 99.345704 -243.600984) (xy 99.396999 -243.592859)
			(xy 99.448933 -243.592859) (xy 99.500228 -243.600984) (xy 99.549621 -243.617032) (xy 99.595895 -243.64061)
			(xy 99.637911 -243.671136) (xy 99.674634 -243.707859) (xy 99.70516 -243.749875) (xy 99.728738 -243.796149)
			(xy 99.744786 -243.845542) (xy 99.752911 -243.896837) (xy 99.75342 -243.922804) (xy 99.752911 -243.948771)
			(xy 100.032821 -243.948771) (xy 100.032821 -243.896837) (xy 100.040946 -243.845542) (xy 100.056994 -243.796149)
			(xy 100.080572 -243.749875) (xy 100.111098 -243.707859) (xy 100.147821 -243.671136) (xy 100.189837 -243.64061)
			(xy 100.236111 -243.617032) (xy 100.285504 -243.600984) (xy 100.336799 -243.592859) (xy 100.388733 -243.592859)
			(xy 100.440028 -243.600984) (xy 100.489421 -243.617032) (xy 100.535695 -243.64061) (xy 100.577711 -243.671136)
			(xy 100.614434 -243.707859) (xy 100.64496 -243.749875) (xy 100.668538 -243.796149) (xy 100.684586 -243.845542)
			(xy 100.692711 -243.896837) (xy 100.69322 -243.922804) (xy 100.692711 -243.948771) (xy 100.972367 -243.948771)
			(xy 100.972367 -243.896837) (xy 100.980492 -243.845542) (xy 100.99654 -243.796149) (xy 101.020118 -243.749875)
			(xy 101.050644 -243.707859) (xy 101.087367 -243.671136) (xy 101.129383 -243.64061) (xy 101.175657 -243.617032)
			(xy 101.22505 -243.600984) (xy 101.276345 -243.592859) (xy 101.328279 -243.592859) (xy 101.379574 -243.600984)
			(xy 101.428967 -243.617032) (xy 101.475241 -243.64061) (xy 101.517257 -243.671136) (xy 101.55398 -243.707859)
			(xy 101.584506 -243.749875) (xy 101.608084 -243.796149) (xy 101.624132 -243.845542) (xy 101.632257 -243.896837)
			(xy 101.632766 -243.922804) (xy 101.632257 -243.948771) (xy 101.912421 -243.948771) (xy 101.912421 -243.896837)
			(xy 101.920546 -243.845542) (xy 101.936594 -243.796149) (xy 101.960172 -243.749875) (xy 101.990698 -243.707859)
			(xy 102.027421 -243.671136) (xy 102.069437 -243.64061) (xy 102.115711 -243.617032) (xy 102.165104 -243.600984)
			(xy 102.216399 -243.592859) (xy 102.268333 -243.592859) (xy 102.319628 -243.600984) (xy 102.369021 -243.617032)
			(xy 102.415295 -243.64061) (xy 102.457311 -243.671136) (xy 102.494034 -243.707859) (xy 102.52456 -243.749875)
			(xy 102.548138 -243.796149) (xy 102.564186 -243.845542) (xy 102.572311 -243.896837) (xy 102.57282 -243.922804)
			(xy 102.572311 -243.948771) (xy 102.572271 -243.949025) (xy 109.430821 -243.949025) (xy 109.430821 -243.897091)
			(xy 109.438946 -243.845796) (xy 109.454994 -243.796403) (xy 109.478572 -243.750129) (xy 109.509098 -243.708113)
			(xy 109.545821 -243.67139) (xy 109.587837 -243.640864) (xy 109.634111 -243.617286) (xy 109.683504 -243.601238)
			(xy 109.734799 -243.593113) (xy 109.786733 -243.593113) (xy 109.838028 -243.601238) (xy 109.887421 -243.617286)
			(xy 109.933695 -243.640864) (xy 109.975711 -243.67139) (xy 110.012434 -243.708113) (xy 110.04296 -243.750129)
			(xy 110.066538 -243.796403) (xy 110.082586 -243.845796) (xy 110.090711 -243.897091) (xy 110.09122 -243.923058)
			(xy 110.090711 -243.949025) (xy 110.370875 -243.949025) (xy 110.370875 -243.897091) (xy 110.379 -243.845796)
			(xy 110.395048 -243.796403) (xy 110.418626 -243.750129) (xy 110.449152 -243.708113) (xy 110.485875 -243.67139)
			(xy 110.527891 -243.640864) (xy 110.574165 -243.617286) (xy 110.623558 -243.601238) (xy 110.674853 -243.593113)
			(xy 110.726787 -243.593113) (xy 110.778082 -243.601238) (xy 110.827475 -243.617286) (xy 110.873749 -243.640864)
			(xy 110.915765 -243.67139) (xy 110.952488 -243.708113) (xy 110.983014 -243.750129) (xy 111.006592 -243.796403)
			(xy 111.02264 -243.845796) (xy 111.030765 -243.897091) (xy 111.031274 -243.923058) (xy 111.030765 -243.949025)
			(xy 111.310421 -243.949025) (xy 111.310421 -243.897091) (xy 111.318546 -243.845796) (xy 111.334594 -243.796403)
			(xy 111.358172 -243.750129) (xy 111.388698 -243.708113) (xy 111.425421 -243.67139) (xy 111.467437 -243.640864)
			(xy 111.513711 -243.617286) (xy 111.563104 -243.601238) (xy 111.614399 -243.593113) (xy 111.666333 -243.593113)
			(xy 111.717628 -243.601238) (xy 111.767021 -243.617286) (xy 111.813295 -243.640864) (xy 111.855311 -243.67139)
			(xy 111.892034 -243.708113) (xy 111.92256 -243.750129) (xy 111.946138 -243.796403) (xy 111.962186 -243.845796)
			(xy 111.970311 -243.897091) (xy 111.97082 -243.923058) (xy 111.970311 -243.949025) (xy 112.250221 -243.949025)
			(xy 112.250221 -243.897091) (xy 112.258346 -243.845796) (xy 112.274394 -243.796403) (xy 112.297972 -243.750129)
			(xy 112.328498 -243.708113) (xy 112.365221 -243.67139) (xy 112.407237 -243.640864) (xy 112.453511 -243.617286)
			(xy 112.502904 -243.601238) (xy 112.554199 -243.593113) (xy 112.606133 -243.593113) (xy 112.657428 -243.601238)
			(xy 112.706821 -243.617286) (xy 112.753095 -243.640864) (xy 112.795111 -243.67139) (xy 112.831834 -243.708113)
			(xy 112.86236 -243.750129) (xy 112.885938 -243.796403) (xy 112.901986 -243.845796) (xy 112.910111 -243.897091)
			(xy 112.91062 -243.923058) (xy 112.910111 -243.949025) (xy 113.190275 -243.949025) (xy 113.190275 -243.897091)
			(xy 113.1984 -243.845796) (xy 113.214448 -243.796403) (xy 113.238026 -243.750129) (xy 113.268552 -243.708113)
			(xy 113.305275 -243.67139) (xy 113.347291 -243.640864) (xy 113.393565 -243.617286) (xy 113.442958 -243.601238)
			(xy 113.494253 -243.593113) (xy 113.546187 -243.593113) (xy 113.597482 -243.601238) (xy 113.646875 -243.617286)
			(xy 113.693149 -243.640864) (xy 113.735165 -243.67139) (xy 113.771888 -243.708113) (xy 113.802414 -243.750129)
			(xy 113.825992 -243.796403) (xy 113.84204 -243.845796) (xy 113.850165 -243.897091) (xy 113.850674 -243.923058)
			(xy 113.850165 -243.949025) (xy 113.850157 -243.949074) (xy 114.129987 -243.949074) (xy 114.129987 -243.897126)
			(xy 114.138114 -243.845819) (xy 114.154167 -243.796414) (xy 114.177751 -243.750129) (xy 114.208286 -243.708104)
			(xy 114.245019 -243.671373) (xy 114.287047 -243.640841) (xy 114.333333 -243.617259) (xy 114.382738 -243.601209)
			(xy 114.434046 -243.593085) (xy 114.46002 -243.592604) (xy 114.488909 -243.593199) (xy 114.545809 -243.603245)
			(xy 114.600096 -243.623027) (xy 114.650118 -243.651944) (xy 114.672618 -243.670074) (xy 114.683107 -243.678456)
			(xy 114.707436 -243.689801) (xy 114.733882 -243.694406) (xy 114.760614 -243.69195) (xy 114.785779 -243.682605)
			(xy 114.807634 -243.667018) (xy 114.824665 -243.646268) (xy 114.835692 -243.621793) (xy 114.838226 -243.608606)
			(xy 114.84251 -243.584999) (xy 114.856985 -243.539256) (xy 114.877923 -243.496088) (xy 114.904884 -243.456401)
			(xy 114.920776 -243.438426) (xy 114.930535 -243.426902) (xy 114.943553 -243.399677) (xy 114.94803 -243.369834)
			(xy 114.943573 -243.339988) (xy 114.930573 -243.312755) (xy 114.920776 -243.301266) (xy 114.904538 -243.282877)
			(xy 114.877093 -243.24222) (xy 114.855962 -243.19795) (xy 114.841611 -243.151042) (xy 114.834356 -243.102527)
			(xy 114.833908 -243.078) (xy 114.833908 -243.077746) (xy 114.834417 -243.051779) (xy 114.842542 -243.000484)
			(xy 114.85859 -242.951091) (xy 114.882168 -242.904817) (xy 114.912694 -242.862801) (xy 114.949417 -242.826078)
			(xy 114.991433 -242.795552) (xy 115.037707 -242.771974) (xy 115.0871 -242.755926) (xy 115.138395 -242.747801)
			(xy 115.190329 -242.747801) (xy 115.241624 -242.755926) (xy 115.291017 -242.771974) (xy 115.337291 -242.795552)
			(xy 115.379307 -242.826078) (xy 115.41603 -242.862801) (xy 115.446556 -242.904817) (xy 115.470134 -242.951091)
			(xy 115.486182 -243.000484) (xy 115.487285 -243.007447) (xy 116.104671 -243.007447) (xy 116.104671 -242.955513)
			(xy 116.112796 -242.904218) (xy 116.128844 -242.854825) (xy 116.152422 -242.808551) (xy 116.182948 -242.766535)
			(xy 116.219671 -242.729812) (xy 116.261687 -242.699286) (xy 116.307961 -242.675708) (xy 116.357354 -242.65966)
			(xy 116.408649 -242.651535) (xy 116.460583 -242.651535) (xy 116.511878 -242.65966) (xy 116.561271 -242.675708)
			(xy 116.607545 -242.699286) (xy 116.649561 -242.729812) (xy 116.686284 -242.766535) (xy 116.71681 -242.808551)
			(xy 116.740388 -242.854825) (xy 116.756436 -242.904218) (xy 116.764561 -242.955513) (xy 116.76507 -242.98148)
			(xy 116.764561 -243.007447) (xy 116.764558 -243.007469) (xy 116.871735 -243.007469) (xy 116.871735 -242.955531)
			(xy 116.87986 -242.904234) (xy 116.895909 -242.854838) (xy 116.919488 -242.808562) (xy 116.950016 -242.766544)
			(xy 116.986741 -242.729818) (xy 117.028759 -242.69929) (xy 117.075035 -242.675711) (xy 117.12443 -242.659661)
			(xy 117.175727 -242.651536) (xy 117.201696 -242.651026) (xy 117.227233 -242.651512) (xy 117.277698 -242.659375)
			(xy 117.326355 -242.674899) (xy 117.372049 -242.697716) (xy 117.413694 -242.727284) (xy 117.432328 -242.744752)
			(xy 117.44246 -242.753892) (xy 117.466354 -242.767041) (xy 117.492875 -242.773397) (xy 117.520133 -242.772507)
			(xy 117.546184 -242.764433) (xy 117.569168 -242.749753) (xy 117.578632 -242.739926) (xy 117.597579 -242.719744)
			(xy 117.640961 -242.685365) (xy 117.689468 -242.658702) (xy 117.741742 -242.6405) (xy 117.79632 -242.631269)
			(xy 117.823996 -242.630706) (xy 117.849857 -242.631205) (xy 117.900949 -242.639252) (xy 117.950163 -242.655163)
			(xy 117.996294 -242.678552) (xy 118.038216 -242.708845) (xy 118.056914 -242.726718) (xy 118.066629 -242.735763)
			(xy 118.089638 -242.748975) (xy 118.115275 -242.755812) (xy 118.141809 -242.755812) (xy 118.167446 -242.748975)
			(xy 118.190455 -242.735763) (xy 118.20017 -242.726718) (xy 118.218865 -242.708844) (xy 118.260794 -242.678561)
			(xy 118.306927 -242.655178) (xy 118.356138 -242.639264) (xy 118.407228 -242.631207) (xy 118.433088 -242.630706)
			(xy 118.458318 -242.631193) (xy 118.508196 -242.638845) (xy 118.55633 -242.653988) (xy 118.601604 -242.676271)
			(xy 118.642966 -242.705176) (xy 118.679455 -242.740031) (xy 118.695216 -242.759738) (xy 118.704808 -242.771261)
			(xy 118.729211 -242.788652) (xy 118.757608 -242.79822) (xy 118.78756 -242.799143) (xy 118.816492 -242.791342)
			(xy 118.84192 -242.775488) (xy 118.852188 -242.764564) (xy 118.87118 -242.743606) (xy 118.915034 -242.707897)
			(xy 118.964322 -242.680163) (xy 119.017607 -242.661214) (xy 119.073339 -242.651601) (xy 119.101616 -242.651026)
			(xy 119.128915 -242.65156) (xy 119.182768 -242.660544) (xy 119.234409 -242.678264) (xy 119.282432 -242.704238)
			(xy 119.325529 -242.737757) (xy 119.34444 -242.757452) (xy 119.354273 -242.767432) (xy 119.378157 -242.782058)
			(xy 119.405113 -242.789657) (xy 119.433119 -242.789657) (xy 119.460075 -242.782058) (xy 119.483959 -242.767432)
			(xy 119.493792 -242.757452) (xy 119.512689 -242.737745) (xy 119.555793 -242.704237) (xy 119.603821 -242.678274)
			(xy 119.655465 -242.660563) (xy 119.709318 -242.651587) (xy 119.736616 -242.651026) (xy 119.762581 -242.651576)
			(xy 119.813871 -242.659702) (xy 119.863258 -242.675751) (xy 119.909527 -242.699328) (xy 119.951538 -242.729853)
			(xy 119.988257 -242.766574) (xy 120.01878 -242.808586) (xy 120.042355 -242.854857) (xy 120.058402 -242.904245)
			(xy 120.066525 -242.955535) (xy 120.066525 -243.007465) (xy 120.058402 -243.058755) (xy 120.042355 -243.108143)
			(xy 120.028694 -243.134955) (xy 121.178067 -243.134955) (xy 121.178067 -243.083021) (xy 121.186192 -243.031726)
			(xy 121.20224 -242.982333) (xy 121.225818 -242.936059) (xy 121.256344 -242.894043) (xy 121.293067 -242.85732)
			(xy 121.335083 -242.826794) (xy 121.381357 -242.803216) (xy 121.43075 -242.787168) (xy 121.482045 -242.779043)
			(xy 121.533979 -242.779043) (xy 121.585274 -242.787168) (xy 121.634667 -242.803216) (xy 121.680941 -242.826794)
			(xy 121.722957 -242.85732) (xy 121.75968 -242.894043) (xy 121.790206 -242.936059) (xy 121.813784 -242.982333)
			(xy 121.829832 -243.031726) (xy 121.837957 -243.083021) (xy 121.838466 -243.108988) (xy 121.837957 -243.134955)
			(xy 122.117867 -243.134955) (xy 122.117867 -243.083021) (xy 122.125992 -243.031726) (xy 122.14204 -242.982333)
			(xy 122.165618 -242.936059) (xy 122.196144 -242.894043) (xy 122.232867 -242.85732) (xy 122.274883 -242.826794)
			(xy 122.321157 -242.803216) (xy 122.37055 -242.787168) (xy 122.421845 -242.779043) (xy 122.473779 -242.779043)
			(xy 122.525074 -242.787168) (xy 122.574467 -242.803216) (xy 122.620741 -242.826794) (xy 122.662757 -242.85732)
			(xy 122.69948 -242.894043) (xy 122.730006 -242.936059) (xy 122.753584 -242.982333) (xy 122.769632 -243.031726)
			(xy 122.777757 -243.083021) (xy 122.778266 -243.108988) (xy 122.777757 -243.134955) (xy 123.057667 -243.134955)
			(xy 123.057667 -243.083021) (xy 123.065792 -243.031726) (xy 123.08184 -242.982333) (xy 123.105418 -242.936059)
			(xy 123.135944 -242.894043) (xy 123.172667 -242.85732) (xy 123.214683 -242.826794) (xy 123.260957 -242.803216)
			(xy 123.31035 -242.787168) (xy 123.361645 -242.779043) (xy 123.413579 -242.779043) (xy 123.464874 -242.787168)
			(xy 123.514267 -242.803216) (xy 123.560541 -242.826794) (xy 123.602557 -242.85732) (xy 123.63928 -242.894043)
			(xy 123.669806 -242.936059) (xy 123.693384 -242.982333) (xy 123.709432 -243.031726) (xy 123.717557 -243.083021)
			(xy 123.718066 -243.108988) (xy 123.717557 -243.134955) (xy 123.997467 -243.134955) (xy 123.997467 -243.083021)
			(xy 124.005592 -243.031726) (xy 124.02164 -242.982333) (xy 124.045218 -242.936059) (xy 124.075744 -242.894043)
			(xy 124.112467 -242.85732) (xy 124.154483 -242.826794) (xy 124.200757 -242.803216) (xy 124.25015 -242.787168)
			(xy 124.301445 -242.779043) (xy 124.353379 -242.779043) (xy 124.404674 -242.787168) (xy 124.454067 -242.803216)
			(xy 124.500341 -242.826794) (xy 124.542357 -242.85732) (xy 124.57908 -242.894043) (xy 124.609606 -242.936059)
			(xy 124.633184 -242.982333) (xy 124.649232 -243.031726) (xy 124.657357 -243.083021) (xy 124.657866 -243.108988)
			(xy 124.657357 -243.134955) (xy 124.937267 -243.134955) (xy 124.937267 -243.083021) (xy 124.945392 -243.031726)
			(xy 124.96144 -242.982333) (xy 124.985018 -242.936059) (xy 125.015544 -242.894043) (xy 125.052267 -242.85732)
			(xy 125.094283 -242.826794) (xy 125.140557 -242.803216) (xy 125.18995 -242.787168) (xy 125.241245 -242.779043)
			(xy 125.293179 -242.779043) (xy 125.344474 -242.787168) (xy 125.393867 -242.803216) (xy 125.440141 -242.826794)
			(xy 125.482157 -242.85732) (xy 125.51888 -242.894043) (xy 125.549406 -242.936059) (xy 125.572984 -242.982333)
			(xy 125.589032 -243.031726) (xy 125.597157 -243.083021) (xy 125.597666 -243.108988) (xy 125.597157 -243.134955)
			(xy 125.877321 -243.134955) (xy 125.877321 -243.083021) (xy 125.885446 -243.031726) (xy 125.901494 -242.982333)
			(xy 125.925072 -242.936059) (xy 125.955598 -242.894043) (xy 125.992321 -242.85732) (xy 126.034337 -242.826794)
			(xy 126.080611 -242.803216) (xy 126.130004 -242.787168) (xy 126.181299 -242.779043) (xy 126.233233 -242.779043)
			(xy 126.284528 -242.787168) (xy 126.333921 -242.803216) (xy 126.380195 -242.826794) (xy 126.422211 -242.85732)
			(xy 126.458934 -242.894043) (xy 126.48946 -242.936059) (xy 126.513038 -242.982333) (xy 126.529086 -243.031726)
			(xy 126.537211 -243.083021) (xy 126.53772 -243.108988) (xy 126.537211 -243.134955) (xy 126.816867 -243.134955)
			(xy 126.816867 -243.083021) (xy 126.824992 -243.031726) (xy 126.84104 -242.982333) (xy 126.864618 -242.936059)
			(xy 126.895144 -242.894043) (xy 126.931867 -242.85732) (xy 126.973883 -242.826794) (xy 127.020157 -242.803216)
			(xy 127.06955 -242.787168) (xy 127.120845 -242.779043) (xy 127.172779 -242.779043) (xy 127.224074 -242.787168)
			(xy 127.273467 -242.803216) (xy 127.319741 -242.826794) (xy 127.361757 -242.85732) (xy 127.39848 -242.894043)
			(xy 127.429006 -242.936059) (xy 127.452584 -242.982333) (xy 127.468632 -243.031726) (xy 127.476757 -243.083021)
			(xy 127.477266 -243.108988) (xy 127.476757 -243.134955) (xy 127.756667 -243.134955) (xy 127.756667 -243.083021)
			(xy 127.764792 -243.031726) (xy 127.78084 -242.982333) (xy 127.804418 -242.936059) (xy 127.834944 -242.894043)
			(xy 127.871667 -242.85732) (xy 127.913683 -242.826794) (xy 127.959957 -242.803216) (xy 128.00935 -242.787168)
			(xy 128.060645 -242.779043) (xy 128.112579 -242.779043) (xy 128.163874 -242.787168) (xy 128.213267 -242.803216)
			(xy 128.259541 -242.826794) (xy 128.301557 -242.85732) (xy 128.33828 -242.894043) (xy 128.368806 -242.936059)
			(xy 128.392384 -242.982333) (xy 128.408432 -243.031726) (xy 128.416557 -243.083021) (xy 128.417066 -243.108988)
			(xy 128.416557 -243.134955) (xy 128.696467 -243.134955) (xy 128.696467 -243.083021) (xy 128.704592 -243.031726)
			(xy 128.72064 -242.982333) (xy 128.744218 -242.936059) (xy 128.774744 -242.894043) (xy 128.811467 -242.85732)
			(xy 128.853483 -242.826794) (xy 128.899757 -242.803216) (xy 128.94915 -242.787168) (xy 129.000445 -242.779043)
			(xy 129.052379 -242.779043) (xy 129.103674 -242.787168) (xy 129.153067 -242.803216) (xy 129.199341 -242.826794)
			(xy 129.241357 -242.85732) (xy 129.27808 -242.894043) (xy 129.308606 -242.936059) (xy 129.332184 -242.982333)
			(xy 129.348232 -243.031726) (xy 129.356357 -243.083021) (xy 129.356866 -243.108988) (xy 129.356357 -243.134955)
			(xy 129.636267 -243.134955) (xy 129.636267 -243.083021) (xy 129.644392 -243.031726) (xy 129.66044 -242.982333)
			(xy 129.684018 -242.936059) (xy 129.714544 -242.894043) (xy 129.751267 -242.85732) (xy 129.793283 -242.826794)
			(xy 129.839557 -242.803216) (xy 129.88895 -242.787168) (xy 129.940245 -242.779043) (xy 129.992179 -242.779043)
			(xy 130.043474 -242.787168) (xy 130.092867 -242.803216) (xy 130.139141 -242.826794) (xy 130.181157 -242.85732)
			(xy 130.21788 -242.894043) (xy 130.248406 -242.936059) (xy 130.271984 -242.982333) (xy 130.288032 -243.031726)
			(xy 130.296157 -243.083021) (xy 130.296666 -243.108988) (xy 130.296157 -243.134955) (xy 130.576067 -243.134955)
			(xy 130.576067 -243.083021) (xy 130.584192 -243.031726) (xy 130.60024 -242.982333) (xy 130.623818 -242.936059)
			(xy 130.654344 -242.894043) (xy 130.691067 -242.85732) (xy 130.733083 -242.826794) (xy 130.779357 -242.803216)
			(xy 130.82875 -242.787168) (xy 130.880045 -242.779043) (xy 130.931979 -242.779043) (xy 130.983274 -242.787168)
			(xy 131.032667 -242.803216) (xy 131.078941 -242.826794) (xy 131.120957 -242.85732) (xy 131.15768 -242.894043)
			(xy 131.188206 -242.936059) (xy 131.211784 -242.982333) (xy 131.227832 -243.031726) (xy 131.235957 -243.083021)
			(xy 131.236466 -243.108988) (xy 131.235957 -243.134955) (xy 131.227832 -243.18625) (xy 131.211784 -243.235643)
			(xy 131.188206 -243.281917) (xy 131.15768 -243.323933) (xy 131.120957 -243.360656) (xy 131.078941 -243.391182)
			(xy 131.032667 -243.41476) (xy 130.983274 -243.430808) (xy 130.931979 -243.438933) (xy 130.880045 -243.438933)
			(xy 130.82875 -243.430808) (xy 130.779357 -243.41476) (xy 130.733083 -243.391182) (xy 130.691067 -243.360656)
			(xy 130.654344 -243.323933) (xy 130.623818 -243.281917) (xy 130.60024 -243.235643) (xy 130.584192 -243.18625)
			(xy 130.576067 -243.134955) (xy 130.296157 -243.134955) (xy 130.288032 -243.18625) (xy 130.271984 -243.235643)
			(xy 130.248406 -243.281917) (xy 130.21788 -243.323933) (xy 130.181157 -243.360656) (xy 130.139141 -243.391182)
			(xy 130.092867 -243.41476) (xy 130.043474 -243.430808) (xy 129.992179 -243.438933) (xy 129.940245 -243.438933)
			(xy 129.88895 -243.430808) (xy 129.839557 -243.41476) (xy 129.793283 -243.391182) (xy 129.751267 -243.360656)
			(xy 129.714544 -243.323933) (xy 129.684018 -243.281917) (xy 129.66044 -243.235643) (xy 129.644392 -243.18625)
			(xy 129.636267 -243.134955) (xy 129.356357 -243.134955) (xy 129.348232 -243.18625) (xy 129.332184 -243.235643)
			(xy 129.308606 -243.281917) (xy 129.27808 -243.323933) (xy 129.241357 -243.360656) (xy 129.199341 -243.391182)
			(xy 129.153067 -243.41476) (xy 129.103674 -243.430808) (xy 129.052379 -243.438933) (xy 129.000445 -243.438933)
			(xy 128.94915 -243.430808) (xy 128.899757 -243.41476) (xy 128.853483 -243.391182) (xy 128.811467 -243.360656)
			(xy 128.774744 -243.323933) (xy 128.744218 -243.281917) (xy 128.72064 -243.235643) (xy 128.704592 -243.18625)
			(xy 128.696467 -243.134955) (xy 128.416557 -243.134955) (xy 128.408432 -243.18625) (xy 128.392384 -243.235643)
			(xy 128.368806 -243.281917) (xy 128.33828 -243.323933) (xy 128.301557 -243.360656) (xy 128.259541 -243.391182)
			(xy 128.213267 -243.41476) (xy 128.163874 -243.430808) (xy 128.112579 -243.438933) (xy 128.060645 -243.438933)
			(xy 128.00935 -243.430808) (xy 127.959957 -243.41476) (xy 127.913683 -243.391182) (xy 127.871667 -243.360656)
			(xy 127.834944 -243.323933) (xy 127.804418 -243.281917) (xy 127.78084 -243.235643) (xy 127.764792 -243.18625)
			(xy 127.756667 -243.134955) (xy 127.476757 -243.134955) (xy 127.468632 -243.18625) (xy 127.452584 -243.235643)
			(xy 127.429006 -243.281917) (xy 127.39848 -243.323933) (xy 127.361757 -243.360656) (xy 127.319741 -243.391182)
			(xy 127.273467 -243.41476) (xy 127.224074 -243.430808) (xy 127.172779 -243.438933) (xy 127.120845 -243.438933)
			(xy 127.06955 -243.430808) (xy 127.020157 -243.41476) (xy 126.973883 -243.391182) (xy 126.931867 -243.360656)
			(xy 126.895144 -243.323933) (xy 126.864618 -243.281917) (xy 126.84104 -243.235643) (xy 126.824992 -243.18625)
			(xy 126.816867 -243.134955) (xy 126.537211 -243.134955) (xy 126.529086 -243.18625) (xy 126.513038 -243.235643)
			(xy 126.48946 -243.281917) (xy 126.458934 -243.323933) (xy 126.422211 -243.360656) (xy 126.380195 -243.391182)
			(xy 126.333921 -243.41476) (xy 126.284528 -243.430808) (xy 126.233233 -243.438933) (xy 126.181299 -243.438933)
			(xy 126.130004 -243.430808) (xy 126.080611 -243.41476) (xy 126.034337 -243.391182) (xy 125.992321 -243.360656)
			(xy 125.955598 -243.323933) (xy 125.925072 -243.281917) (xy 125.901494 -243.235643) (xy 125.885446 -243.18625)
			(xy 125.877321 -243.134955) (xy 125.597157 -243.134955) (xy 125.589032 -243.18625) (xy 125.572984 -243.235643)
			(xy 125.549406 -243.281917) (xy 125.51888 -243.323933) (xy 125.482157 -243.360656) (xy 125.440141 -243.391182)
			(xy 125.393867 -243.41476) (xy 125.344474 -243.430808) (xy 125.293179 -243.438933) (xy 125.241245 -243.438933)
			(xy 125.18995 -243.430808) (xy 125.140557 -243.41476) (xy 125.094283 -243.391182) (xy 125.052267 -243.360656)
			(xy 125.015544 -243.323933) (xy 124.985018 -243.281917) (xy 124.96144 -243.235643) (xy 124.945392 -243.18625)
			(xy 124.937267 -243.134955) (xy 124.657357 -243.134955) (xy 124.649232 -243.18625) (xy 124.633184 -243.235643)
			(xy 124.609606 -243.281917) (xy 124.57908 -243.323933) (xy 124.542357 -243.360656) (xy 124.500341 -243.391182)
			(xy 124.454067 -243.41476) (xy 124.404674 -243.430808) (xy 124.353379 -243.438933) (xy 124.301445 -243.438933)
			(xy 124.25015 -243.430808) (xy 124.200757 -243.41476) (xy 124.154483 -243.391182) (xy 124.112467 -243.360656)
			(xy 124.075744 -243.323933) (xy 124.045218 -243.281917) (xy 124.02164 -243.235643) (xy 124.005592 -243.18625)
			(xy 123.997467 -243.134955) (xy 123.717557 -243.134955) (xy 123.709432 -243.18625) (xy 123.693384 -243.235643)
			(xy 123.669806 -243.281917) (xy 123.63928 -243.323933) (xy 123.602557 -243.360656) (xy 123.560541 -243.391182)
			(xy 123.514267 -243.41476) (xy 123.464874 -243.430808) (xy 123.413579 -243.438933) (xy 123.361645 -243.438933)
			(xy 123.31035 -243.430808) (xy 123.260957 -243.41476) (xy 123.214683 -243.391182) (xy 123.172667 -243.360656)
			(xy 123.135944 -243.323933) (xy 123.105418 -243.281917) (xy 123.08184 -243.235643) (xy 123.065792 -243.18625)
			(xy 123.057667 -243.134955) (xy 122.777757 -243.134955) (xy 122.769632 -243.18625) (xy 122.753584 -243.235643)
			(xy 122.730006 -243.281917) (xy 122.69948 -243.323933) (xy 122.662757 -243.360656) (xy 122.620741 -243.391182)
			(xy 122.574467 -243.41476) (xy 122.525074 -243.430808) (xy 122.473779 -243.438933) (xy 122.421845 -243.438933)
			(xy 122.37055 -243.430808) (xy 122.321157 -243.41476) (xy 122.274883 -243.391182) (xy 122.232867 -243.360656)
			(xy 122.196144 -243.323933) (xy 122.165618 -243.281917) (xy 122.14204 -243.235643) (xy 122.125992 -243.18625)
			(xy 122.117867 -243.134955) (xy 121.837957 -243.134955) (xy 121.829832 -243.18625) (xy 121.813784 -243.235643)
			(xy 121.790206 -243.281917) (xy 121.75968 -243.323933) (xy 121.722957 -243.360656) (xy 121.680941 -243.391182)
			(xy 121.634667 -243.41476) (xy 121.585274 -243.430808) (xy 121.533979 -243.438933) (xy 121.482045 -243.438933)
			(xy 121.43075 -243.430808) (xy 121.381357 -243.41476) (xy 121.335083 -243.391182) (xy 121.293067 -243.360656)
			(xy 121.256344 -243.323933) (xy 121.225818 -243.281917) (xy 121.20224 -243.235643) (xy 121.186192 -243.18625)
			(xy 121.178067 -243.134955) (xy 120.028694 -243.134955) (xy 120.01878 -243.154414) (xy 119.988257 -243.196426)
			(xy 119.951538 -243.233147) (xy 119.909527 -243.263672) (xy 119.863258 -243.287249) (xy 119.813871 -243.303298)
			(xy 119.762581 -243.311424) (xy 119.736616 -243.311934) (xy 119.709318 -243.311392) (xy 119.655464 -243.302412)
			(xy 119.603822 -243.284695) (xy 119.555799 -243.258722) (xy 119.512703 -243.225203) (xy 119.493792 -243.205508)
			(xy 119.483959 -243.195528) (xy 119.460075 -243.180902) (xy 119.433119 -243.173303) (xy 119.405113 -243.173303)
			(xy 119.378157 -243.180902) (xy 119.354273 -243.195528) (xy 119.34444 -243.205508) (xy 119.32552 -243.225192)
			(xy 119.282423 -243.258705) (xy 119.234401 -243.284673) (xy 119.182762 -243.302389) (xy 119.128913 -243.311371)
			(xy 119.101616 -243.311934) (xy 119.076386 -243.311429) (xy 119.026511 -243.303778) (xy 118.978377 -243.288637)
			(xy 118.933103 -243.266358) (xy 118.891741 -243.237458) (xy 118.855251 -243.202607) (xy 118.839488 -243.182902)
			(xy 118.829893 -243.17138) (xy 118.805492 -243.153983) (xy 118.777095 -243.144411) (xy 118.747142 -243.143486)
			(xy 118.718209 -243.151289) (xy 118.692782 -243.167149) (xy 118.682516 -243.178076) (xy 118.663531 -243.19904)
			(xy 118.619673 -243.234747) (xy 118.570384 -243.262478) (xy 118.517098 -243.281426) (xy 118.461366 -243.291039)
			(xy 118.433088 -243.291614) (xy 118.407227 -243.291119) (xy 118.356135 -243.283071) (xy 118.306921 -243.267158)
			(xy 118.26079 -243.243768) (xy 118.218868 -243.213475) (xy 118.20017 -243.195602) (xy 118.190455 -243.186557)
			(xy 118.167446 -243.173345) (xy 118.141809 -243.166508) (xy 118.115275 -243.166508) (xy 118.089638 -243.173345)
			(xy 118.066629 -243.186557) (xy 118.056914 -243.195602) (xy 118.038229 -243.213487) (xy 117.996297 -243.243767)
			(xy 117.950162 -243.267149) (xy 117.900948 -243.28306) (xy 117.849857 -243.291114) (xy 117.823996 -243.291614)
			(xy 117.798458 -243.29115) (xy 117.747991 -243.283284) (xy 117.699333 -243.267756) (xy 117.653639 -243.244933)
			(xy 117.611996 -243.21536) (xy 117.593364 -243.197888) (xy 117.583235 -243.188746) (xy 117.559339 -243.175606)
			(xy 117.532818 -243.169256) (xy 117.505562 -243.170147) (xy 117.479513 -243.178217) (xy 117.456526 -243.192891)
			(xy 117.44706 -243.202714) (xy 117.428125 -243.222907) (xy 117.384739 -243.257283) (xy 117.336228 -243.283944)
			(xy 117.283952 -243.302143) (xy 117.229373 -243.311372) (xy 117.201696 -243.311934) (xy 117.175727 -243.311464)
			(xy 117.12443 -243.303339) (xy 117.075035 -243.287289) (xy 117.028759 -243.26371) (xy 116.986741 -243.233182)
			(xy 116.950016 -243.196456) (xy 116.919488 -243.154438) (xy 116.895909 -243.108162) (xy 116.87986 -243.058766)
			(xy 116.871735 -243.007469) (xy 116.764558 -243.007469) (xy 116.756436 -243.058742) (xy 116.740388 -243.108135)
			(xy 116.71681 -243.154409) (xy 116.686284 -243.196425) (xy 116.649561 -243.233148) (xy 116.607545 -243.263674)
			(xy 116.561271 -243.287252) (xy 116.511878 -243.3033) (xy 116.460583 -243.311425) (xy 116.408649 -243.311425)
			(xy 116.357354 -243.3033) (xy 116.307961 -243.287252) (xy 116.261687 -243.263674) (xy 116.219671 -243.233148)
			(xy 116.182948 -243.196425) (xy 116.152422 -243.154409) (xy 116.128844 -243.108135) (xy 116.112796 -243.058742)
			(xy 116.104671 -243.007447) (xy 115.487285 -243.007447) (xy 115.494307 -243.051779) (xy 115.494816 -243.077746)
			(xy 115.494816 -243.078) (xy 115.49436 -243.102526) (xy 115.487098 -243.151039) (xy 115.472747 -243.197946)
			(xy 115.451623 -243.242218) (xy 115.424189 -243.282882) (xy 115.407948 -243.301266) (xy 115.398098 -243.312719)
			(xy 115.385086 -243.339969) (xy 115.380625 -243.369834) (xy 115.385106 -243.399697) (xy 115.398136 -243.426937)
			(xy 115.407948 -243.438426) (xy 115.424169 -243.456828) (xy 115.45162 -243.497481) (xy 115.472756 -243.541747)
			(xy 115.48711 -243.588653) (xy 115.494368 -243.637166) (xy 115.494816 -243.661692) (xy 115.494816 -243.661946)
			(xy 115.494387 -243.687916) (xy 115.486255 -243.739217) (xy 115.470197 -243.788613) (xy 115.446611 -243.83489)
			(xy 115.416075 -243.876907) (xy 115.379343 -243.91363) (xy 115.337318 -243.944155) (xy 115.291035 -243.96773)
			(xy 115.241635 -243.983774) (xy 115.190332 -243.991894) (xy 115.164362 -243.9924) (xy 115.135472 -243.991814)
			(xy 115.078573 -243.981765) (xy 115.024286 -243.96198) (xy 114.974264 -243.933061) (xy 114.951764 -243.91493)
			(xy 114.941256 -243.90658) (xy 114.916932 -243.895253) (xy 114.890496 -243.89066) (xy 114.863777 -243.893118)
			(xy 114.838622 -243.902457) (xy 114.816772 -243.918031) (xy 114.799739 -243.938763) (xy 114.7887 -243.963219)
			(xy 114.786156 -243.976398) (xy 114.781494 -244.001855) (xy 114.765275 -244.050998) (xy 114.741595 -244.097013)
			(xy 114.711033 -244.138775) (xy 114.674335 -244.175263) (xy 114.632398 -244.205586) (xy 114.586249 -244.229003)
			(xy 114.537013 -244.24494) (xy 114.485895 -244.253009) (xy 114.46002 -244.253512) (xy 114.434046 -244.253115)
			(xy 114.382738 -244.244991) (xy 114.333333 -244.228941) (xy 114.287047 -244.205359) (xy 114.245019 -244.174827)
			(xy 114.208286 -244.138096) (xy 114.177751 -244.096071) (xy 114.154167 -244.049786) (xy 114.138114 -244.000381)
			(xy 114.129987 -243.949074) (xy 113.850157 -243.949074) (xy 113.84204 -244.00032) (xy 113.825992 -244.049713)
			(xy 113.802414 -244.095987) (xy 113.771888 -244.138003) (xy 113.735165 -244.174726) (xy 113.693149 -244.205252)
			(xy 113.646875 -244.22883) (xy 113.597482 -244.244878) (xy 113.546187 -244.253003) (xy 113.494253 -244.253003)
			(xy 113.442958 -244.244878) (xy 113.393565 -244.22883) (xy 113.347291 -244.205252) (xy 113.305275 -244.174726)
			(xy 113.268552 -244.138003) (xy 113.238026 -244.095987) (xy 113.214448 -244.049713) (xy 113.1984 -244.00032)
			(xy 113.190275 -243.949025) (xy 112.910111 -243.949025) (xy 112.901986 -244.00032) (xy 112.885938 -244.049713)
			(xy 112.86236 -244.095987) (xy 112.831834 -244.138003) (xy 112.795111 -244.174726) (xy 112.753095 -244.205252)
			(xy 112.706821 -244.22883) (xy 112.657428 -244.244878) (xy 112.606133 -244.253003) (xy 112.554199 -244.253003)
			(xy 112.502904 -244.244878) (xy 112.453511 -244.22883) (xy 112.407237 -244.205252) (xy 112.365221 -244.174726)
			(xy 112.328498 -244.138003) (xy 112.297972 -244.095987) (xy 112.274394 -244.049713) (xy 112.258346 -244.00032)
			(xy 112.250221 -243.949025) (xy 111.970311 -243.949025) (xy 111.962186 -244.00032) (xy 111.946138 -244.049713)
			(xy 111.92256 -244.095987) (xy 111.892034 -244.138003) (xy 111.855311 -244.174726) (xy 111.813295 -244.205252)
			(xy 111.767021 -244.22883) (xy 111.717628 -244.244878) (xy 111.666333 -244.253003) (xy 111.614399 -244.253003)
			(xy 111.563104 -244.244878) (xy 111.513711 -244.22883) (xy 111.467437 -244.205252) (xy 111.425421 -244.174726)
			(xy 111.388698 -244.138003) (xy 111.358172 -244.095987) (xy 111.334594 -244.049713) (xy 111.318546 -244.00032)
			(xy 111.310421 -243.949025) (xy 111.030765 -243.949025) (xy 111.02264 -244.00032) (xy 111.006592 -244.049713)
			(xy 110.983014 -244.095987) (xy 110.952488 -244.138003) (xy 110.915765 -244.174726) (xy 110.873749 -244.205252)
			(xy 110.827475 -244.22883) (xy 110.778082 -244.244878) (xy 110.726787 -244.253003) (xy 110.674853 -244.253003)
			(xy 110.623558 -244.244878) (xy 110.574165 -244.22883) (xy 110.527891 -244.205252) (xy 110.485875 -244.174726)
			(xy 110.449152 -244.138003) (xy 110.418626 -244.095987) (xy 110.395048 -244.049713) (xy 110.379 -244.00032)
			(xy 110.370875 -243.949025) (xy 110.090711 -243.949025) (xy 110.082586 -244.00032) (xy 110.066538 -244.049713)
			(xy 110.04296 -244.095987) (xy 110.012434 -244.138003) (xy 109.975711 -244.174726) (xy 109.933695 -244.205252)
			(xy 109.887421 -244.22883) (xy 109.838028 -244.244878) (xy 109.786733 -244.253003) (xy 109.734799 -244.253003)
			(xy 109.683504 -244.244878) (xy 109.634111 -244.22883) (xy 109.587837 -244.205252) (xy 109.545821 -244.174726)
			(xy 109.509098 -244.138003) (xy 109.478572 -244.095987) (xy 109.454994 -244.049713) (xy 109.438946 -244.00032)
			(xy 109.430821 -243.949025) (xy 102.572271 -243.949025) (xy 102.564186 -244.000066) (xy 102.548138 -244.049459)
			(xy 102.52456 -244.095733) (xy 102.494034 -244.137749) (xy 102.457311 -244.174472) (xy 102.415295 -244.204998)
			(xy 102.369021 -244.228576) (xy 102.319628 -244.244624) (xy 102.268333 -244.252749) (xy 102.216399 -244.252749)
			(xy 102.165104 -244.244624) (xy 102.115711 -244.228576) (xy 102.069437 -244.204998) (xy 102.027421 -244.174472)
			(xy 101.990698 -244.137749) (xy 101.960172 -244.095733) (xy 101.936594 -244.049459) (xy 101.920546 -244.000066)
			(xy 101.912421 -243.948771) (xy 101.632257 -243.948771) (xy 101.624132 -244.000066) (xy 101.608084 -244.049459)
			(xy 101.584506 -244.095733) (xy 101.55398 -244.137749) (xy 101.517257 -244.174472) (xy 101.475241 -244.204998)
			(xy 101.428967 -244.228576) (xy 101.379574 -244.244624) (xy 101.328279 -244.252749) (xy 101.276345 -244.252749)
			(xy 101.22505 -244.244624) (xy 101.175657 -244.228576) (xy 101.129383 -244.204998) (xy 101.087367 -244.174472)
			(xy 101.050644 -244.137749) (xy 101.020118 -244.095733) (xy 100.99654 -244.049459) (xy 100.980492 -244.000066)
			(xy 100.972367 -243.948771) (xy 100.692711 -243.948771) (xy 100.684586 -244.000066) (xy 100.668538 -244.049459)
			(xy 100.64496 -244.095733) (xy 100.614434 -244.137749) (xy 100.577711 -244.174472) (xy 100.535695 -244.204998)
			(xy 100.489421 -244.228576) (xy 100.440028 -244.244624) (xy 100.388733 -244.252749) (xy 100.336799 -244.252749)
			(xy 100.285504 -244.244624) (xy 100.236111 -244.228576) (xy 100.189837 -244.204998) (xy 100.147821 -244.174472)
			(xy 100.111098 -244.137749) (xy 100.080572 -244.095733) (xy 100.056994 -244.049459) (xy 100.040946 -244.000066)
			(xy 100.032821 -243.948771) (xy 99.752911 -243.948771) (xy 99.744786 -244.000066) (xy 99.728738 -244.049459)
			(xy 99.70516 -244.095733) (xy 99.674634 -244.137749) (xy 99.637911 -244.174472) (xy 99.595895 -244.204998)
			(xy 99.549621 -244.228576) (xy 99.500228 -244.244624) (xy 99.448933 -244.252749) (xy 99.396999 -244.252749)
			(xy 99.345704 -244.244624) (xy 99.296311 -244.228576) (xy 99.250037 -244.204998) (xy 99.208021 -244.174472)
			(xy 99.171298 -244.137749) (xy 99.140772 -244.095733) (xy 99.117194 -244.049459) (xy 99.101146 -244.000066)
			(xy 99.093021 -243.948771) (xy 98.813111 -243.948771) (xy 98.804986 -244.000066) (xy 98.788938 -244.049459)
			(xy 98.76536 -244.095733) (xy 98.734834 -244.137749) (xy 98.698111 -244.174472) (xy 98.656095 -244.204998)
			(xy 98.609821 -244.228576) (xy 98.560428 -244.244624) (xy 98.509133 -244.252749) (xy 98.457199 -244.252749)
			(xy 98.405904 -244.244624) (xy 98.356511 -244.228576) (xy 98.310237 -244.204998) (xy 98.268221 -244.174472)
			(xy 98.231498 -244.137749) (xy 98.200972 -244.095733) (xy 98.177394 -244.049459) (xy 98.161346 -244.000066)
			(xy 98.153221 -243.948771) (xy 97.873311 -243.948771) (xy 97.865186 -244.000066) (xy 97.849138 -244.049459)
			(xy 97.82556 -244.095733) (xy 97.795034 -244.137749) (xy 97.758311 -244.174472) (xy 97.716295 -244.204998)
			(xy 97.670021 -244.228576) (xy 97.620628 -244.244624) (xy 97.569333 -244.252749) (xy 97.517399 -244.252749)
			(xy 97.466104 -244.244624) (xy 97.416711 -244.228576) (xy 97.370437 -244.204998) (xy 97.328421 -244.174472)
			(xy 97.291698 -244.137749) (xy 97.261172 -244.095733) (xy 97.237594 -244.049459) (xy 97.221546 -244.000066)
			(xy 97.213421 -243.948771) (xy 96.933511 -243.948771) (xy 96.925386 -244.000066) (xy 96.909338 -244.049459)
			(xy 96.88576 -244.095733) (xy 96.855234 -244.137749) (xy 96.818511 -244.174472) (xy 96.776495 -244.204998)
			(xy 96.730221 -244.228576) (xy 96.680828 -244.244624) (xy 96.629533 -244.252749) (xy 96.577599 -244.252749)
			(xy 96.526304 -244.244624) (xy 96.476911 -244.228576) (xy 96.430637 -244.204998) (xy 96.388621 -244.174472)
			(xy 96.351898 -244.137749) (xy 96.321372 -244.095733) (xy 96.297794 -244.049459) (xy 96.281746 -244.000066)
			(xy 96.273621 -243.948771) (xy 95.993711 -243.948771) (xy 95.985586 -244.000066) (xy 95.969538 -244.049459)
			(xy 95.94596 -244.095733) (xy 95.915434 -244.137749) (xy 95.878711 -244.174472) (xy 95.836695 -244.204998)
			(xy 95.790421 -244.228576) (xy 95.741028 -244.244624) (xy 95.689733 -244.252749) (xy 95.637799 -244.252749)
			(xy 95.586504 -244.244624) (xy 95.537111 -244.228576) (xy 95.490837 -244.204998) (xy 95.448821 -244.174472)
			(xy 95.412098 -244.137749) (xy 95.381572 -244.095733) (xy 95.357994 -244.049459) (xy 95.341946 -244.000066)
			(xy 95.333821 -243.948771) (xy 95.053657 -243.948771) (xy 95.045532 -244.000066) (xy 95.029484 -244.049459)
			(xy 95.005906 -244.095733) (xy 94.97538 -244.137749) (xy 94.938657 -244.174472) (xy 94.896641 -244.204998)
			(xy 94.850367 -244.228576) (xy 94.800974 -244.244624) (xy 94.749679 -244.252749) (xy 94.697745 -244.252749)
			(xy 94.64645 -244.244624) (xy 94.597057 -244.228576) (xy 94.550783 -244.204998) (xy 94.508767 -244.174472)
			(xy 94.472044 -244.137749) (xy 94.441518 -244.095733) (xy 94.41794 -244.049459) (xy 94.401892 -244.000066)
			(xy 94.393767 -243.948771) (xy 94.114111 -243.948771) (xy 94.105986 -244.000066) (xy 94.089938 -244.049459)
			(xy 94.06636 -244.095733) (xy 94.035834 -244.137749) (xy 93.999111 -244.174472) (xy 93.957095 -244.204998)
			(xy 93.910821 -244.228576) (xy 93.861428 -244.244624) (xy 93.810133 -244.252749) (xy 93.758199 -244.252749)
			(xy 93.706904 -244.244624) (xy 93.657511 -244.228576) (xy 93.611237 -244.204998) (xy 93.569221 -244.174472)
			(xy 93.532498 -244.137749) (xy 93.501972 -244.095733) (xy 93.478394 -244.049459) (xy 93.462346 -244.000066)
			(xy 93.454221 -243.948771) (xy 93.174311 -243.948771) (xy 93.166186 -244.000066) (xy 93.150138 -244.049459)
			(xy 93.12656 -244.095733) (xy 93.096034 -244.137749) (xy 93.059311 -244.174472) (xy 93.017295 -244.204998)
			(xy 92.971021 -244.228576) (xy 92.921628 -244.244624) (xy 92.870333 -244.252749) (xy 92.818399 -244.252749)
			(xy 92.767104 -244.244624) (xy 92.717711 -244.228576) (xy 92.671437 -244.204998) (xy 92.629421 -244.174472)
			(xy 92.592698 -244.137749) (xy 92.562172 -244.095733) (xy 92.538594 -244.049459) (xy 92.522546 -244.000066)
			(xy 92.514421 -243.948771) (xy 92.234821 -243.948771) (xy 92.234821 -243.948791) (xy 92.226689 -244.000132)
			(xy 92.210624 -244.049569) (xy 92.187024 -244.095884) (xy 92.156468 -244.137936) (xy 92.11971 -244.174691)
			(xy 92.077655 -244.205242) (xy 92.031337 -244.228837) (xy 91.981899 -244.244897) (xy 91.930557 -244.253023)
			(xy 91.904566 -244.253512) (xy 91.877173 -244.252981) (xy 91.823134 -244.243963) (xy 91.77132 -244.226163)
			(xy 91.723147 -244.200068) (xy 91.679934 -244.166391) (xy 91.642861 -244.126052) (xy 91.627452 -244.103398)
			(xy 91.62542 -244.10035) (xy 91.620033 -244.09379) (xy 91.605883 -244.084436) (xy 91.597734 -244.082062)
			(xy 91.573096 -244.082062) (xy 91.562478 -244.085336) (xy 91.545331 -244.099421) (xy 91.535842 -244.119481)
			(xy 91.53525 -244.130576) (xy 91.53525 -244.192806) (xy 91.535755 -244.202561) (xy 91.543188 -244.220605)
			(xy 91.549728 -244.227858) (xy 91.924632 -244.602762) (xy 91.932851 -244.610056) (xy 91.953529 -244.617418)
			(xy 91.96451 -244.616986) (xy 92.046806 -244.605048) (xy 92.083382 -244.579648) (xy 92.085414 -244.576092)
			(xy 92.098014 -244.554329) (xy 92.128776 -244.514549) (xy 92.165213 -244.479892) (xy 92.206482 -244.451159)
			(xy 92.25163 -244.429014) (xy 92.299613 -244.413969) (xy 92.349323 -244.406371) (xy 92.374466 -244.405912)
			(xy 92.400456 -244.406393) (xy 92.451798 -244.41452) (xy 92.501236 -244.430579) (xy 92.547552 -244.454176)
			(xy 92.589607 -244.484727) (xy 92.626363 -244.521483) (xy 92.656917 -244.563536) (xy 92.680515 -244.609851)
			(xy 92.696577 -244.659288) (xy 92.704706 -244.71063) (xy 92.705174 -244.73662) (xy 92.704703 -244.761762)
			(xy 92.704577 -244.762587) (xy 92.984067 -244.762587) (xy 92.984067 -244.710653) (xy 92.992192 -244.659358)
			(xy 93.00824 -244.609965) (xy 93.031818 -244.563691) (xy 93.062344 -244.521675) (xy 93.099067 -244.484952)
			(xy 93.141083 -244.454426) (xy 93.187357 -244.430848) (xy 93.23675 -244.4148) (xy 93.288045 -244.406675)
			(xy 93.339979 -244.406675) (xy 93.391274 -244.4148) (xy 93.440667 -244.430848) (xy 93.486941 -244.454426)
			(xy 93.528957 -244.484952) (xy 93.56568 -244.521675) (xy 93.596206 -244.563691) (xy 93.619784 -244.609965)
			(xy 93.635832 -244.659358) (xy 93.643957 -244.710653) (xy 93.644466 -244.73662) (xy 93.643957 -244.762587)
			(xy 93.923867 -244.762587) (xy 93.923867 -244.710653) (xy 93.931992 -244.659358) (xy 93.94804 -244.609965)
			(xy 93.971618 -244.563691) (xy 94.002144 -244.521675) (xy 94.038867 -244.484952) (xy 94.080883 -244.454426)
			(xy 94.127157 -244.430848) (xy 94.17655 -244.4148) (xy 94.227845 -244.406675) (xy 94.279779 -244.406675)
			(xy 94.331074 -244.4148) (xy 94.380467 -244.430848) (xy 94.426741 -244.454426) (xy 94.468757 -244.484952)
			(xy 94.50548 -244.521675) (xy 94.536006 -244.563691) (xy 94.559584 -244.609965) (xy 94.575632 -244.659358)
			(xy 94.583757 -244.710653) (xy 94.584266 -244.73662) (xy 94.583757 -244.762587) (xy 94.863667 -244.762587)
			(xy 94.863667 -244.710653) (xy 94.871792 -244.659358) (xy 94.88784 -244.609965) (xy 94.911418 -244.563691)
			(xy 94.941944 -244.521675) (xy 94.978667 -244.484952) (xy 95.020683 -244.454426) (xy 95.066957 -244.430848)
			(xy 95.11635 -244.4148) (xy 95.167645 -244.406675) (xy 95.219579 -244.406675) (xy 95.270874 -244.4148)
			(xy 95.320267 -244.430848) (xy 95.366541 -244.454426) (xy 95.408557 -244.484952) (xy 95.44528 -244.521675)
			(xy 95.475806 -244.563691) (xy 95.499384 -244.609965) (xy 95.515432 -244.659358) (xy 95.523557 -244.710653)
			(xy 95.524066 -244.73662) (xy 95.523557 -244.762587) (xy 95.803467 -244.762587) (xy 95.803467 -244.710653)
			(xy 95.811592 -244.659358) (xy 95.82764 -244.609965) (xy 95.851218 -244.563691) (xy 95.881744 -244.521675)
			(xy 95.918467 -244.484952) (xy 95.960483 -244.454426) (xy 96.006757 -244.430848) (xy 96.05615 -244.4148)
			(xy 96.107445 -244.406675) (xy 96.159379 -244.406675) (xy 96.210674 -244.4148) (xy 96.260067 -244.430848)
			(xy 96.306341 -244.454426) (xy 96.348357 -244.484952) (xy 96.38508 -244.521675) (xy 96.415606 -244.563691)
			(xy 96.439184 -244.609965) (xy 96.455232 -244.659358) (xy 96.463357 -244.710653) (xy 96.463866 -244.73662)
			(xy 96.463357 -244.762587) (xy 96.743521 -244.762587) (xy 96.743521 -244.710653) (xy 96.751646 -244.659358)
			(xy 96.767694 -244.609965) (xy 96.791272 -244.563691) (xy 96.821798 -244.521675) (xy 96.858521 -244.484952)
			(xy 96.900537 -244.454426) (xy 96.946811 -244.430848) (xy 96.996204 -244.4148) (xy 97.047499 -244.406675)
			(xy 97.099433 -244.406675) (xy 97.150728 -244.4148) (xy 97.200121 -244.430848) (xy 97.246395 -244.454426)
			(xy 97.288411 -244.484952) (xy 97.325134 -244.521675) (xy 97.35566 -244.563691) (xy 97.379238 -244.609965)
			(xy 97.395286 -244.659358) (xy 97.403411 -244.710653) (xy 97.40392 -244.73662) (xy 97.403411 -244.762587)
			(xy 97.683067 -244.762587) (xy 97.683067 -244.710653) (xy 97.691192 -244.659358) (xy 97.70724 -244.609965)
			(xy 97.730818 -244.563691) (xy 97.761344 -244.521675) (xy 97.798067 -244.484952) (xy 97.840083 -244.454426)
			(xy 97.886357 -244.430848) (xy 97.93575 -244.4148) (xy 97.987045 -244.406675) (xy 98.038979 -244.406675)
			(xy 98.090274 -244.4148) (xy 98.139667 -244.430848) (xy 98.185941 -244.454426) (xy 98.227957 -244.484952)
			(xy 98.26468 -244.521675) (xy 98.295206 -244.563691) (xy 98.318784 -244.609965) (xy 98.334832 -244.659358)
			(xy 98.342957 -244.710653) (xy 98.343466 -244.73662) (xy 98.342957 -244.762587) (xy 98.622867 -244.762587)
			(xy 98.622867 -244.710653) (xy 98.630992 -244.659358) (xy 98.64704 -244.609965) (xy 98.670618 -244.563691)
			(xy 98.701144 -244.521675) (xy 98.737867 -244.484952) (xy 98.779883 -244.454426) (xy 98.826157 -244.430848)
			(xy 98.87555 -244.4148) (xy 98.926845 -244.406675) (xy 98.978779 -244.406675) (xy 99.030074 -244.4148)
			(xy 99.079467 -244.430848) (xy 99.125741 -244.454426) (xy 99.167757 -244.484952) (xy 99.20448 -244.521675)
			(xy 99.235006 -244.563691) (xy 99.258584 -244.609965) (xy 99.274632 -244.659358) (xy 99.282757 -244.710653)
			(xy 99.283266 -244.73662) (xy 99.282757 -244.762587) (xy 99.562667 -244.762587) (xy 99.562667 -244.710653)
			(xy 99.570792 -244.659358) (xy 99.58684 -244.609965) (xy 99.610418 -244.563691) (xy 99.640944 -244.521675)
			(xy 99.677667 -244.484952) (xy 99.719683 -244.454426) (xy 99.765957 -244.430848) (xy 99.81535 -244.4148)
			(xy 99.866645 -244.406675) (xy 99.918579 -244.406675) (xy 99.969874 -244.4148) (xy 100.019267 -244.430848)
			(xy 100.065541 -244.454426) (xy 100.107557 -244.484952) (xy 100.14428 -244.521675) (xy 100.174806 -244.563691)
			(xy 100.198384 -244.609965) (xy 100.214432 -244.659358) (xy 100.222557 -244.710653) (xy 100.223066 -244.73662)
			(xy 100.222557 -244.762587) (xy 100.502467 -244.762587) (xy 100.502467 -244.710653) (xy 100.510592 -244.659358)
			(xy 100.52664 -244.609965) (xy 100.550218 -244.563691) (xy 100.580744 -244.521675) (xy 100.617467 -244.484952)
			(xy 100.659483 -244.454426) (xy 100.705757 -244.430848) (xy 100.75515 -244.4148) (xy 100.806445 -244.406675)
			(xy 100.858379 -244.406675) (xy 100.909674 -244.4148) (xy 100.959067 -244.430848) (xy 101.005341 -244.454426)
			(xy 101.047357 -244.484952) (xy 101.08408 -244.521675) (xy 101.114606 -244.563691) (xy 101.138184 -244.609965)
			(xy 101.154232 -244.659358) (xy 101.162357 -244.710653) (xy 101.162866 -244.73662) (xy 101.162357 -244.762587)
			(xy 101.442267 -244.762587) (xy 101.442267 -244.710653) (xy 101.450392 -244.659358) (xy 101.46644 -244.609965)
			(xy 101.490018 -244.563691) (xy 101.520544 -244.521675) (xy 101.557267 -244.484952) (xy 101.599283 -244.454426)
			(xy 101.645557 -244.430848) (xy 101.69495 -244.4148) (xy 101.746245 -244.406675) (xy 101.798179 -244.406675)
			(xy 101.849474 -244.4148) (xy 101.898867 -244.430848) (xy 101.945141 -244.454426) (xy 101.987157 -244.484952)
			(xy 102.02388 -244.521675) (xy 102.054406 -244.563691) (xy 102.077984 -244.609965) (xy 102.094032 -244.659358)
			(xy 102.102157 -244.710653) (xy 102.102666 -244.73662) (xy 102.102157 -244.762587) (xy 102.094032 -244.813882)
			(xy 102.077984 -244.863275) (xy 102.054406 -244.909549) (xy 102.02388 -244.951565) (xy 101.987157 -244.988288)
			(xy 101.945141 -245.018814) (xy 101.898867 -245.042392) (xy 101.849474 -245.05844) (xy 101.798179 -245.066565)
			(xy 101.746245 -245.066565) (xy 101.69495 -245.05844) (xy 101.645557 -245.042392) (xy 101.599283 -245.018814)
			(xy 101.557267 -244.988288) (xy 101.520544 -244.951565) (xy 101.490018 -244.909549) (xy 101.46644 -244.863275)
			(xy 101.450392 -244.813882) (xy 101.442267 -244.762587) (xy 101.162357 -244.762587) (xy 101.154232 -244.813882)
			(xy 101.138184 -244.863275) (xy 101.114606 -244.909549) (xy 101.08408 -244.951565) (xy 101.047357 -244.988288)
			(xy 101.005341 -245.018814) (xy 100.959067 -245.042392) (xy 100.909674 -245.05844) (xy 100.858379 -245.066565)
			(xy 100.806445 -245.066565) (xy 100.75515 -245.05844) (xy 100.705757 -245.042392) (xy 100.659483 -245.018814)
			(xy 100.617467 -244.988288) (xy 100.580744 -244.951565) (xy 100.550218 -244.909549) (xy 100.52664 -244.863275)
			(xy 100.510592 -244.813882) (xy 100.502467 -244.762587) (xy 100.222557 -244.762587) (xy 100.214432 -244.813882)
			(xy 100.198384 -244.863275) (xy 100.174806 -244.909549) (xy 100.14428 -244.951565) (xy 100.107557 -244.988288)
			(xy 100.065541 -245.018814) (xy 100.019267 -245.042392) (xy 99.969874 -245.05844) (xy 99.918579 -245.066565)
			(xy 99.866645 -245.066565) (xy 99.81535 -245.05844) (xy 99.765957 -245.042392) (xy 99.719683 -245.018814)
			(xy 99.677667 -244.988288) (xy 99.640944 -244.951565) (xy 99.610418 -244.909549) (xy 99.58684 -244.863275)
			(xy 99.570792 -244.813882) (xy 99.562667 -244.762587) (xy 99.282757 -244.762587) (xy 99.274632 -244.813882)
			(xy 99.258584 -244.863275) (xy 99.235006 -244.909549) (xy 99.20448 -244.951565) (xy 99.167757 -244.988288)
			(xy 99.125741 -245.018814) (xy 99.079467 -245.042392) (xy 99.030074 -245.05844) (xy 98.978779 -245.066565)
			(xy 98.926845 -245.066565) (xy 98.87555 -245.05844) (xy 98.826157 -245.042392) (xy 98.779883 -245.018814)
			(xy 98.737867 -244.988288) (xy 98.701144 -244.951565) (xy 98.670618 -244.909549) (xy 98.64704 -244.863275)
			(xy 98.630992 -244.813882) (xy 98.622867 -244.762587) (xy 98.342957 -244.762587) (xy 98.334832 -244.813882)
			(xy 98.318784 -244.863275) (xy 98.295206 -244.909549) (xy 98.26468 -244.951565) (xy 98.227957 -244.988288)
			(xy 98.185941 -245.018814) (xy 98.139667 -245.042392) (xy 98.090274 -245.05844) (xy 98.038979 -245.066565)
			(xy 97.987045 -245.066565) (xy 97.93575 -245.05844) (xy 97.886357 -245.042392) (xy 97.840083 -245.018814)
			(xy 97.798067 -244.988288) (xy 97.761344 -244.951565) (xy 97.730818 -244.909549) (xy 97.70724 -244.863275)
			(xy 97.691192 -244.813882) (xy 97.683067 -244.762587) (xy 97.403411 -244.762587) (xy 97.395286 -244.813882)
			(xy 97.379238 -244.863275) (xy 97.35566 -244.909549) (xy 97.325134 -244.951565) (xy 97.288411 -244.988288)
			(xy 97.246395 -245.018814) (xy 97.200121 -245.042392) (xy 97.150728 -245.05844) (xy 97.099433 -245.066565)
			(xy 97.047499 -245.066565) (xy 96.996204 -245.05844) (xy 96.946811 -245.042392) (xy 96.900537 -245.018814)
			(xy 96.858521 -244.988288) (xy 96.821798 -244.951565) (xy 96.791272 -244.909549) (xy 96.767694 -244.863275)
			(xy 96.751646 -244.813882) (xy 96.743521 -244.762587) (xy 96.463357 -244.762587) (xy 96.455232 -244.813882)
			(xy 96.439184 -244.863275) (xy 96.415606 -244.909549) (xy 96.38508 -244.951565) (xy 96.348357 -244.988288)
			(xy 96.306341 -245.018814) (xy 96.260067 -245.042392) (xy 96.210674 -245.05844) (xy 96.159379 -245.066565)
			(xy 96.107445 -245.066565) (xy 96.05615 -245.05844) (xy 96.006757 -245.042392) (xy 95.960483 -245.018814)
			(xy 95.918467 -244.988288) (xy 95.881744 -244.951565) (xy 95.851218 -244.909549) (xy 95.82764 -244.863275)
			(xy 95.811592 -244.813882) (xy 95.803467 -244.762587) (xy 95.523557 -244.762587) (xy 95.515432 -244.813882)
			(xy 95.499384 -244.863275) (xy 95.475806 -244.909549) (xy 95.44528 -244.951565) (xy 95.408557 -244.988288)
			(xy 95.366541 -245.018814) (xy 95.320267 -245.042392) (xy 95.270874 -245.05844) (xy 95.219579 -245.066565)
			(xy 95.167645 -245.066565) (xy 95.11635 -245.05844) (xy 95.066957 -245.042392) (xy 95.020683 -245.018814)
			(xy 94.978667 -244.988288) (xy 94.941944 -244.951565) (xy 94.911418 -244.909549) (xy 94.88784 -244.863275)
			(xy 94.871792 -244.813882) (xy 94.863667 -244.762587) (xy 94.583757 -244.762587) (xy 94.575632 -244.813882)
			(xy 94.559584 -244.863275) (xy 94.536006 -244.909549) (xy 94.50548 -244.951565) (xy 94.468757 -244.988288)
			(xy 94.426741 -245.018814) (xy 94.380467 -245.042392) (xy 94.331074 -245.05844) (xy 94.279779 -245.066565)
			(xy 94.227845 -245.066565) (xy 94.17655 -245.05844) (xy 94.127157 -245.042392) (xy 94.080883 -245.018814)
			(xy 94.038867 -244.988288) (xy 94.002144 -244.951565) (xy 93.971618 -244.909549) (xy 93.94804 -244.863275)
			(xy 93.931992 -244.813882) (xy 93.923867 -244.762587) (xy 93.643957 -244.762587) (xy 93.635832 -244.813882)
			(xy 93.619784 -244.863275) (xy 93.596206 -244.909549) (xy 93.56568 -244.951565) (xy 93.528957 -244.988288)
			(xy 93.486941 -245.018814) (xy 93.440667 -245.042392) (xy 93.391274 -245.05844) (xy 93.339979 -245.066565)
			(xy 93.288045 -245.066565) (xy 93.23675 -245.05844) (xy 93.187357 -245.042392) (xy 93.141083 -245.018814)
			(xy 93.099067 -244.988288) (xy 93.062344 -244.951565) (xy 93.031818 -244.909549) (xy 93.00824 -244.863275)
			(xy 92.992192 -244.813882) (xy 92.984067 -244.762587) (xy 92.704577 -244.762587) (xy 92.697087 -244.811465)
			(xy 92.682034 -244.859442) (xy 92.65989 -244.904588) (xy 92.631166 -244.94586) (xy 92.596525 -244.982307)
			(xy 92.556765 -245.01309) (xy 92.534994 -245.025672) (xy 92.531438 -245.027704) (xy 92.506038 -245.06428)
			(xy 92.4941 -245.146576) (xy 92.493586 -245.15757) (xy 92.500959 -245.178277) (xy 92.508324 -245.186454)
			(xy 92.593922 -245.272052) (xy 92.602102 -245.279376) (xy 92.622734 -245.286819) (xy 92.644583 -245.284897)
			(xy 92.654374 -245.279926) (xy 92.657422 -245.27764) (xy 92.678121 -245.264014) (xy 92.722741 -245.242458)
			(xy 92.770082 -245.227815) (xy 92.819081 -245.220415) (xy 92.843858 -245.219982) (xy 92.844112 -245.219982)
			(xy 92.870099 -245.220492) (xy 92.921432 -245.228624) (xy 92.970862 -245.244686) (xy 93.017171 -245.268283)
			(xy 93.059218 -245.298832) (xy 93.095969 -245.335584) (xy 93.126518 -245.377631) (xy 93.150114 -245.42394)
			(xy 93.166176 -245.473369) (xy 93.174308 -245.524703) (xy 93.17482 -245.55069) (xy 93.17482 -245.550944)
			(xy 93.1744 -245.574875) (xy 93.174141 -245.576657) (xy 93.454221 -245.576657) (xy 93.454221 -245.524723)
			(xy 93.462346 -245.473428) (xy 93.478394 -245.424035) (xy 93.501972 -245.377761) (xy 93.532498 -245.335745)
			(xy 93.569221 -245.299022) (xy 93.611237 -245.268496) (xy 93.657511 -245.244918) (xy 93.706904 -245.22887)
			(xy 93.758199 -245.220745) (xy 93.810133 -245.220745) (xy 93.861428 -245.22887) (xy 93.910821 -245.244918)
			(xy 93.957095 -245.268496) (xy 93.999111 -245.299022) (xy 94.035834 -245.335745) (xy 94.06636 -245.377761)
			(xy 94.089938 -245.424035) (xy 94.105986 -245.473428) (xy 94.114111 -245.524723) (xy 94.11462 -245.55069)
			(xy 94.114111 -245.576657) (xy 94.394021 -245.576657) (xy 94.394021 -245.524723) (xy 94.402146 -245.473428)
			(xy 94.418194 -245.424035) (xy 94.441772 -245.377761) (xy 94.472298 -245.335745) (xy 94.509021 -245.299022)
			(xy 94.551037 -245.268496) (xy 94.597311 -245.244918) (xy 94.646704 -245.22887) (xy 94.697999 -245.220745)
			(xy 94.749933 -245.220745) (xy 94.801228 -245.22887) (xy 94.850621 -245.244918) (xy 94.896895 -245.268496)
			(xy 94.938911 -245.299022) (xy 94.975634 -245.335745) (xy 95.00616 -245.377761) (xy 95.029738 -245.424035)
			(xy 95.045786 -245.473428) (xy 95.053911 -245.524723) (xy 95.05442 -245.55069) (xy 95.053911 -245.576657)
			(xy 95.333821 -245.576657) (xy 95.333821 -245.524723) (xy 95.341946 -245.473428) (xy 95.357994 -245.424035)
			(xy 95.381572 -245.377761) (xy 95.412098 -245.335745) (xy 95.448821 -245.299022) (xy 95.490837 -245.268496)
			(xy 95.537111 -245.244918) (xy 95.586504 -245.22887) (xy 95.637799 -245.220745) (xy 95.689733 -245.220745)
			(xy 95.741028 -245.22887) (xy 95.790421 -245.244918) (xy 95.836695 -245.268496) (xy 95.878711 -245.299022)
			(xy 95.915434 -245.335745) (xy 95.94596 -245.377761) (xy 95.969538 -245.424035) (xy 95.985586 -245.473428)
			(xy 95.993711 -245.524723) (xy 95.99422 -245.55069) (xy 95.993711 -245.576657) (xy 96.273621 -245.576657)
			(xy 96.273621 -245.524723) (xy 96.281746 -245.473428) (xy 96.297794 -245.424035) (xy 96.321372 -245.377761)
			(xy 96.351898 -245.335745) (xy 96.388621 -245.299022) (xy 96.430637 -245.268496) (xy 96.476911 -245.244918)
			(xy 96.526304 -245.22887) (xy 96.577599 -245.220745) (xy 96.629533 -245.220745) (xy 96.680828 -245.22887)
			(xy 96.730221 -245.244918) (xy 96.776495 -245.268496) (xy 96.818511 -245.299022) (xy 96.855234 -245.335745)
			(xy 96.88576 -245.377761) (xy 96.909338 -245.424035) (xy 96.925386 -245.473428) (xy 96.933511 -245.524723)
			(xy 96.93402 -245.55069) (xy 96.933511 -245.576657) (xy 97.213167 -245.576657) (xy 97.213167 -245.524723)
			(xy 97.221292 -245.473428) (xy 97.23734 -245.424035) (xy 97.260918 -245.377761) (xy 97.291444 -245.335745)
			(xy 97.328167 -245.299022) (xy 97.370183 -245.268496) (xy 97.416457 -245.244918) (xy 97.46585 -245.22887)
			(xy 97.517145 -245.220745) (xy 97.569079 -245.220745) (xy 97.620374 -245.22887) (xy 97.669767 -245.244918)
			(xy 97.716041 -245.268496) (xy 97.758057 -245.299022) (xy 97.79478 -245.335745) (xy 97.825306 -245.377761)
			(xy 97.848884 -245.424035) (xy 97.864932 -245.473428) (xy 97.873057 -245.524723) (xy 97.873566 -245.55069)
			(xy 97.873057 -245.576657) (xy 98.153221 -245.576657) (xy 98.153221 -245.524723) (xy 98.161346 -245.473428)
			(xy 98.177394 -245.424035) (xy 98.200972 -245.377761) (xy 98.231498 -245.335745) (xy 98.268221 -245.299022)
			(xy 98.310237 -245.268496) (xy 98.356511 -245.244918) (xy 98.405904 -245.22887) (xy 98.457199 -245.220745)
			(xy 98.509133 -245.220745) (xy 98.560428 -245.22887) (xy 98.609821 -245.244918) (xy 98.656095 -245.268496)
			(xy 98.698111 -245.299022) (xy 98.734834 -245.335745) (xy 98.76536 -245.377761) (xy 98.788938 -245.424035)
			(xy 98.804986 -245.473428) (xy 98.813111 -245.524723) (xy 98.81362 -245.55069) (xy 98.813111 -245.576657)
			(xy 99.093021 -245.576657) (xy 99.093021 -245.524723) (xy 99.101146 -245.473428) (xy 99.117194 -245.424035)
			(xy 99.140772 -245.377761) (xy 99.171298 -245.335745) (xy 99.208021 -245.299022) (xy 99.250037 -245.268496)
			(xy 99.296311 -245.244918) (xy 99.345704 -245.22887) (xy 99.396999 -245.220745) (xy 99.448933 -245.220745)
			(xy 99.500228 -245.22887) (xy 99.549621 -245.244918) (xy 99.595895 -245.268496) (xy 99.637911 -245.299022)
			(xy 99.674634 -245.335745) (xy 99.70516 -245.377761) (xy 99.728738 -245.424035) (xy 99.744786 -245.473428)
			(xy 99.752911 -245.524723) (xy 99.75342 -245.55069) (xy 99.752911 -245.576657) (xy 100.032821 -245.576657)
			(xy 100.032821 -245.524723) (xy 100.040946 -245.473428) (xy 100.056994 -245.424035) (xy 100.080572 -245.377761)
			(xy 100.111098 -245.335745) (xy 100.147821 -245.299022) (xy 100.189837 -245.268496) (xy 100.236111 -245.244918)
			(xy 100.285504 -245.22887) (xy 100.336799 -245.220745) (xy 100.388733 -245.220745) (xy 100.440028 -245.22887)
			(xy 100.489421 -245.244918) (xy 100.535695 -245.268496) (xy 100.577711 -245.299022) (xy 100.614434 -245.335745)
			(xy 100.64496 -245.377761) (xy 100.668538 -245.424035) (xy 100.684586 -245.473428) (xy 100.692711 -245.524723)
			(xy 100.69322 -245.55069) (xy 100.692711 -245.576657) (xy 100.972621 -245.576657) (xy 100.972621 -245.524723)
			(xy 100.980746 -245.473428) (xy 100.996794 -245.424035) (xy 101.020372 -245.377761) (xy 101.050898 -245.335745)
			(xy 101.087621 -245.299022) (xy 101.129637 -245.268496) (xy 101.175911 -245.244918) (xy 101.225304 -245.22887)
			(xy 101.276599 -245.220745) (xy 101.328533 -245.220745) (xy 101.379828 -245.22887) (xy 101.429221 -245.244918)
			(xy 101.475495 -245.268496) (xy 101.517511 -245.299022) (xy 101.554234 -245.335745) (xy 101.58476 -245.377761)
			(xy 101.608338 -245.424035) (xy 101.624386 -245.473428) (xy 101.632511 -245.524723) (xy 101.63302 -245.55069)
			(xy 101.632511 -245.576657) (xy 101.63251 -245.576666) (xy 101.912445 -245.576666) (xy 101.912445 -245.524734)
			(xy 101.920569 -245.47344) (xy 101.936616 -245.424049) (xy 101.960191 -245.377776) (xy 101.990715 -245.335761)
			(xy 102.027435 -245.299037) (xy 102.069447 -245.268509) (xy 102.115718 -245.244929) (xy 102.165107 -245.228877)
			(xy 102.2164 -245.220748) (xy 102.242366 -245.220236) (xy 102.24262 -245.220236) (xy 102.268058 -245.220694)
			(xy 102.318332 -245.228495) (xy 102.366812 -245.243926) (xy 102.412347 -245.266618) (xy 102.433374 -245.280942)
			(xy 102.444608 -245.288483) (xy 102.469993 -245.297823) (xy 102.496942 -245.30016) (xy 102.523557 -245.29533)
			(xy 102.547965 -245.283671) (xy 102.568449 -245.266006) (xy 102.583568 -245.243576) (xy 102.588314 -245.230904)
			(xy 102.596 -245.209441) (xy 102.616448 -245.168694) (xy 102.642301 -245.131143) (xy 102.657402 -245.114064)
			(xy 102.667219 -245.102586) (xy 102.680228 -245.075345) (xy 102.684692 -245.045488) (xy 102.680221 -245.015633)
			(xy 102.667206 -244.988394) (xy 102.657402 -244.976904) (xy 102.641139 -244.958537) (xy 102.613696 -244.917874)
			(xy 102.59257 -244.873599) (xy 102.578225 -244.826686) (xy 102.570977 -244.778167) (xy 102.570534 -244.753638)
			(xy 102.570534 -244.753384) (xy 102.571043 -244.727417) (xy 102.579168 -244.676122) (xy 102.595216 -244.626729)
			(xy 102.618794 -244.580455) (xy 102.64932 -244.538439) (xy 102.686043 -244.501716) (xy 102.728059 -244.47119)
			(xy 102.774333 -244.447612) (xy 102.823726 -244.431564) (xy 102.875021 -244.423439) (xy 102.926955 -244.423439)
			(xy 102.97825 -244.431564) (xy 103.027643 -244.447612) (xy 103.073917 -244.47119) (xy 103.115933 -244.501716)
			(xy 103.152656 -244.538439) (xy 103.183182 -244.580455) (xy 103.20676 -244.626729) (xy 103.222808 -244.676122)
			(xy 103.230933 -244.727417) (xy 103.231442 -244.753384) (xy 103.231442 -244.753638) (xy 103.231002 -244.778165)
			(xy 103.223735 -244.826678) (xy 103.20938 -244.873585) (xy 103.188252 -244.917856) (xy 103.160816 -244.95852)
			(xy 103.144574 -244.976904) (xy 103.134782 -244.988403) (xy 103.12176 -245.015636) (xy 103.117286 -245.045488)
			(xy 103.121753 -245.075341) (xy 103.134769 -245.102577) (xy 103.144574 -245.114064) (xy 103.160818 -245.132448)
			(xy 103.188264 -245.173106) (xy 103.209395 -245.217377) (xy 103.223744 -245.264286) (xy 103.230996 -245.312802)
			(xy 103.231442 -245.33733) (xy 103.231442 -245.337584) (xy 103.231257 -245.34749) (xy 108.103416 -245.34749)
			(xy 108.103416 -245.347236) (xy 108.103885 -245.32271) (xy 108.111143 -245.274198) (xy 108.12549 -245.227291)
			(xy 108.146612 -245.183019) (xy 108.174043 -245.142354) (xy 108.190284 -245.12397) (xy 108.200096 -245.112488)
			(xy 108.213108 -245.085248) (xy 108.217574 -245.055393) (xy 108.213104 -245.025538) (xy 108.200088 -244.9983)
			(xy 108.190284 -244.98681) (xy 108.174021 -244.968443) (xy 108.146579 -244.927779) (xy 108.125452 -244.883504)
			(xy 108.111108 -244.836591) (xy 108.10386 -244.788073) (xy 108.103416 -244.763544) (xy 108.103416 -244.76329)
			(xy 108.103925 -244.737323) (xy 108.11205 -244.686028) (xy 108.128098 -244.636635) (xy 108.151676 -244.590361)
			(xy 108.182202 -244.548345) (xy 108.218925 -244.511622) (xy 108.260941 -244.481096) (xy 108.307215 -244.457518)
			(xy 108.356608 -244.44147) (xy 108.407903 -244.433345) (xy 108.459837 -244.433345) (xy 108.511132 -244.44147)
			(xy 108.560525 -244.457518) (xy 108.606799 -244.481096) (xy 108.648815 -244.511622) (xy 108.685538 -244.548345)
			(xy 108.716064 -244.590361) (xy 108.739642 -244.636635) (xy 108.75569 -244.686028) (xy 108.763815 -244.737323)
			(xy 108.764315 -244.762841) (xy 108.961175 -244.762841) (xy 108.961175 -244.710907) (xy 108.9693 -244.659612)
			(xy 108.985348 -244.610219) (xy 109.008926 -244.563945) (xy 109.039452 -244.521929) (xy 109.076175 -244.485206)
			(xy 109.118191 -244.45468) (xy 109.164465 -244.431102) (xy 109.213858 -244.415054) (xy 109.265153 -244.406929)
			(xy 109.317087 -244.406929) (xy 109.368382 -244.415054) (xy 109.417775 -244.431102) (xy 109.464049 -244.45468)
			(xy 109.506065 -244.485206) (xy 109.542788 -244.521929) (xy 109.573314 -244.563945) (xy 109.596892 -244.610219)
			(xy 109.61294 -244.659612) (xy 109.621065 -244.710907) (xy 109.621574 -244.736874) (xy 109.621065 -244.762841)
			(xy 109.900975 -244.762841) (xy 109.900975 -244.710907) (xy 109.9091 -244.659612) (xy 109.925148 -244.610219)
			(xy 109.948726 -244.563945) (xy 109.979252 -244.521929) (xy 110.015975 -244.485206) (xy 110.057991 -244.45468)
			(xy 110.104265 -244.431102) (xy 110.153658 -244.415054) (xy 110.204953 -244.406929) (xy 110.256887 -244.406929)
			(xy 110.308182 -244.415054) (xy 110.357575 -244.431102) (xy 110.403849 -244.45468) (xy 110.445865 -244.485206)
			(xy 110.482588 -244.521929) (xy 110.513114 -244.563945) (xy 110.536692 -244.610219) (xy 110.55274 -244.659612)
			(xy 110.560865 -244.710907) (xy 110.561374 -244.736874) (xy 110.560865 -244.762841) (xy 110.840775 -244.762841)
			(xy 110.840775 -244.710907) (xy 110.8489 -244.659612) (xy 110.864948 -244.610219) (xy 110.888526 -244.563945)
			(xy 110.919052 -244.521929) (xy 110.955775 -244.485206) (xy 110.997791 -244.45468) (xy 111.044065 -244.431102)
			(xy 111.093458 -244.415054) (xy 111.144753 -244.406929) (xy 111.196687 -244.406929) (xy 111.247982 -244.415054)
			(xy 111.297375 -244.431102) (xy 111.343649 -244.45468) (xy 111.385665 -244.485206) (xy 111.422388 -244.521929)
			(xy 111.452914 -244.563945) (xy 111.476492 -244.610219) (xy 111.49254 -244.659612) (xy 111.500665 -244.710907)
			(xy 111.501174 -244.736874) (xy 111.500665 -244.762841) (xy 111.780575 -244.762841) (xy 111.780575 -244.710907)
			(xy 111.7887 -244.659612) (xy 111.804748 -244.610219) (xy 111.828326 -244.563945) (xy 111.858852 -244.521929)
			(xy 111.895575 -244.485206) (xy 111.937591 -244.45468) (xy 111.983865 -244.431102) (xy 112.033258 -244.415054)
			(xy 112.084553 -244.406929) (xy 112.136487 -244.406929) (xy 112.187782 -244.415054) (xy 112.237175 -244.431102)
			(xy 112.283449 -244.45468) (xy 112.325465 -244.485206) (xy 112.362188 -244.521929) (xy 112.392714 -244.563945)
			(xy 112.416292 -244.610219) (xy 112.43234 -244.659612) (xy 112.440465 -244.710907) (xy 112.440974 -244.736874)
			(xy 112.440465 -244.762841) (xy 112.720121 -244.762841) (xy 112.720121 -244.710907) (xy 112.728246 -244.659612)
			(xy 112.744294 -244.610219) (xy 112.767872 -244.563945) (xy 112.798398 -244.521929) (xy 112.835121 -244.485206)
			(xy 112.877137 -244.45468) (xy 112.923411 -244.431102) (xy 112.972804 -244.415054) (xy 113.024099 -244.406929)
			(xy 113.076033 -244.406929) (xy 113.127328 -244.415054) (xy 113.176721 -244.431102) (xy 113.222995 -244.45468)
			(xy 113.265011 -244.485206) (xy 113.301734 -244.521929) (xy 113.33226 -244.563945) (xy 113.355838 -244.610219)
			(xy 113.371886 -244.659612) (xy 113.380011 -244.710907) (xy 113.38052 -244.736874) (xy 113.380011 -244.762841)
			(xy 113.660175 -244.762841) (xy 113.660175 -244.710907) (xy 113.6683 -244.659612) (xy 113.684348 -244.610219)
			(xy 113.707926 -244.563945) (xy 113.738452 -244.521929) (xy 113.775175 -244.485206) (xy 113.817191 -244.45468)
			(xy 113.863465 -244.431102) (xy 113.912858 -244.415054) (xy 113.964153 -244.406929) (xy 114.016087 -244.406929)
			(xy 114.067382 -244.415054) (xy 114.116775 -244.431102) (xy 114.163049 -244.45468) (xy 114.205065 -244.485206)
			(xy 114.241788 -244.521929) (xy 114.272314 -244.563945) (xy 114.295892 -244.610219) (xy 114.31194 -244.659612)
			(xy 114.320065 -244.710907) (xy 114.320574 -244.736874) (xy 114.320065 -244.762841) (xy 114.31194 -244.814136)
			(xy 114.295892 -244.863529) (xy 114.272314 -244.909803) (xy 114.241788 -244.951819) (xy 114.205065 -244.988542)
			(xy 114.163049 -245.019068) (xy 114.116775 -245.042646) (xy 114.067382 -245.058694) (xy 114.016087 -245.066819)
			(xy 113.964153 -245.066819) (xy 113.912858 -245.058694) (xy 113.863465 -245.042646) (xy 113.817191 -245.019068)
			(xy 113.775175 -244.988542) (xy 113.738452 -244.951819) (xy 113.707926 -244.909803) (xy 113.684348 -244.863529)
			(xy 113.6683 -244.814136) (xy 113.660175 -244.762841) (xy 113.380011 -244.762841) (xy 113.371886 -244.814136)
			(xy 113.355838 -244.863529) (xy 113.33226 -244.909803) (xy 113.301734 -244.951819) (xy 113.265011 -244.988542)
			(xy 113.222995 -245.019068) (xy 113.176721 -245.042646) (xy 113.127328 -245.058694) (xy 113.076033 -245.066819)
			(xy 113.024099 -245.066819) (xy 112.972804 -245.058694) (xy 112.923411 -245.042646) (xy 112.877137 -245.019068)
			(xy 112.835121 -244.988542) (xy 112.798398 -244.951819) (xy 112.767872 -244.909803) (xy 112.744294 -244.863529)
			(xy 112.728246 -244.814136) (xy 112.720121 -244.762841) (xy 112.440465 -244.762841) (xy 112.43234 -244.814136)
			(xy 112.416292 -244.863529) (xy 112.392714 -244.909803) (xy 112.362188 -244.951819) (xy 112.325465 -244.988542)
			(xy 112.283449 -245.019068) (xy 112.237175 -245.042646) (xy 112.187782 -245.058694) (xy 112.136487 -245.066819)
			(xy 112.084553 -245.066819) (xy 112.033258 -245.058694) (xy 111.983865 -245.042646) (xy 111.937591 -245.019068)
			(xy 111.895575 -244.988542) (xy 111.858852 -244.951819) (xy 111.828326 -244.909803) (xy 111.804748 -244.863529)
			(xy 111.7887 -244.814136) (xy 111.780575 -244.762841) (xy 111.500665 -244.762841) (xy 111.49254 -244.814136)
			(xy 111.476492 -244.863529) (xy 111.452914 -244.909803) (xy 111.422388 -244.951819) (xy 111.385665 -244.988542)
			(xy 111.343649 -245.019068) (xy 111.297375 -245.042646) (xy 111.247982 -245.058694) (xy 111.196687 -245.066819)
			(xy 111.144753 -245.066819) (xy 111.093458 -245.058694) (xy 111.044065 -245.042646) (xy 110.997791 -245.019068)
			(xy 110.955775 -244.988542) (xy 110.919052 -244.951819) (xy 110.888526 -244.909803) (xy 110.864948 -244.863529)
			(xy 110.8489 -244.814136) (xy 110.840775 -244.762841) (xy 110.560865 -244.762841) (xy 110.55274 -244.814136)
			(xy 110.536692 -244.863529) (xy 110.513114 -244.909803) (xy 110.482588 -244.951819) (xy 110.445865 -244.988542)
			(xy 110.403849 -245.019068) (xy 110.357575 -245.042646) (xy 110.308182 -245.058694) (xy 110.256887 -245.066819)
			(xy 110.204953 -245.066819) (xy 110.153658 -245.058694) (xy 110.104265 -245.042646) (xy 110.057991 -245.019068)
			(xy 110.015975 -244.988542) (xy 109.979252 -244.951819) (xy 109.948726 -244.909803) (xy 109.925148 -244.863529)
			(xy 109.9091 -244.814136) (xy 109.900975 -244.762841) (xy 109.621065 -244.762841) (xy 109.61294 -244.814136)
			(xy 109.596892 -244.863529) (xy 109.573314 -244.909803) (xy 109.542788 -244.951819) (xy 109.506065 -244.988542)
			(xy 109.464049 -245.019068) (xy 109.417775 -245.042646) (xy 109.368382 -245.058694) (xy 109.317087 -245.066819)
			(xy 109.265153 -245.066819) (xy 109.213858 -245.058694) (xy 109.164465 -245.042646) (xy 109.118191 -245.019068)
			(xy 109.076175 -244.988542) (xy 109.039452 -244.951819) (xy 109.008926 -244.909803) (xy 108.985348 -244.863529)
			(xy 108.9693 -244.814136) (xy 108.961175 -244.762841) (xy 108.764315 -244.762841) (xy 108.764324 -244.76329)
			(xy 108.764324 -244.763544) (xy 108.763892 -244.788071) (xy 108.756624 -244.836585) (xy 108.742267 -244.883492)
			(xy 108.721138 -244.927763) (xy 108.6937 -244.968427) (xy 108.677456 -244.98681) (xy 108.66766 -244.998306)
			(xy 108.654641 -245.02554) (xy 108.650169 -245.055393) (xy 108.654636 -245.085246) (xy 108.667651 -245.112482)
			(xy 108.677456 -245.12397) (xy 108.6937 -245.142354) (xy 108.721147 -245.183011) (xy 108.742278 -245.227282)
			(xy 108.756627 -245.274192) (xy 108.763879 -245.322708) (xy 108.764324 -245.347236) (xy 108.764324 -245.34749)
			(xy 108.763815 -245.373457) (xy 108.75569 -245.424752) (xy 108.739642 -245.474145) (xy 108.716064 -245.520419)
			(xy 108.685538 -245.562435) (xy 108.671062 -245.576911) (xy 109.430821 -245.576911) (xy 109.430821 -245.524977)
			(xy 109.438946 -245.473682) (xy 109.454994 -245.424289) (xy 109.478572 -245.378015) (xy 109.509098 -245.335999)
			(xy 109.545821 -245.299276) (xy 109.587837 -245.26875) (xy 109.634111 -245.245172) (xy 109.683504 -245.229124)
			(xy 109.734799 -245.220999) (xy 109.786733 -245.220999) (xy 109.838028 -245.229124) (xy 109.887421 -245.245172)
			(xy 109.933695 -245.26875) (xy 109.975711 -245.299276) (xy 110.012434 -245.335999) (xy 110.04296 -245.378015)
			(xy 110.066538 -245.424289) (xy 110.082586 -245.473682) (xy 110.090711 -245.524977) (xy 110.09122 -245.550944)
			(xy 110.090711 -245.576911) (xy 110.370875 -245.576911) (xy 110.370875 -245.524977) (xy 110.379 -245.473682)
			(xy 110.395048 -245.424289) (xy 110.418626 -245.378015) (xy 110.449152 -245.335999) (xy 110.485875 -245.299276)
			(xy 110.527891 -245.26875) (xy 110.574165 -245.245172) (xy 110.623558 -245.229124) (xy 110.674853 -245.220999)
			(xy 110.726787 -245.220999) (xy 110.778082 -245.229124) (xy 110.827475 -245.245172) (xy 110.873749 -245.26875)
			(xy 110.915765 -245.299276) (xy 110.952488 -245.335999) (xy 110.983014 -245.378015) (xy 111.006592 -245.424289)
			(xy 111.02264 -245.473682) (xy 111.030765 -245.524977) (xy 111.031274 -245.550944) (xy 111.030765 -245.576911)
			(xy 111.310421 -245.576911) (xy 111.310421 -245.524977) (xy 111.318546 -245.473682) (xy 111.334594 -245.424289)
			(xy 111.358172 -245.378015) (xy 111.388698 -245.335999) (xy 111.425421 -245.299276) (xy 111.467437 -245.26875)
			(xy 111.513711 -245.245172) (xy 111.563104 -245.229124) (xy 111.614399 -245.220999) (xy 111.666333 -245.220999)
			(xy 111.717628 -245.229124) (xy 111.767021 -245.245172) (xy 111.813295 -245.26875) (xy 111.855311 -245.299276)
			(xy 111.892034 -245.335999) (xy 111.92256 -245.378015) (xy 111.946138 -245.424289) (xy 111.962186 -245.473682)
			(xy 111.970311 -245.524977) (xy 111.97082 -245.550944) (xy 111.970311 -245.576911) (xy 112.250221 -245.576911)
			(xy 112.250221 -245.524977) (xy 112.258346 -245.473682) (xy 112.274394 -245.424289) (xy 112.297972 -245.378015)
			(xy 112.328498 -245.335999) (xy 112.365221 -245.299276) (xy 112.407237 -245.26875) (xy 112.453511 -245.245172)
			(xy 112.502904 -245.229124) (xy 112.554199 -245.220999) (xy 112.606133 -245.220999) (xy 112.657428 -245.229124)
			(xy 112.706821 -245.245172) (xy 112.753095 -245.26875) (xy 112.795111 -245.299276) (xy 112.831834 -245.335999)
			(xy 112.86236 -245.378015) (xy 112.885938 -245.424289) (xy 112.901986 -245.473682) (xy 112.910111 -245.524977)
			(xy 112.91062 -245.550944) (xy 112.910111 -245.576911) (xy 113.190275 -245.576911) (xy 113.190275 -245.524977)
			(xy 113.1984 -245.473682) (xy 113.214448 -245.424289) (xy 113.238026 -245.378015) (xy 113.268552 -245.335999)
			(xy 113.305275 -245.299276) (xy 113.347291 -245.26875) (xy 113.393565 -245.245172) (xy 113.442958 -245.229124)
			(xy 113.494253 -245.220999) (xy 113.546187 -245.220999) (xy 113.597482 -245.229124) (xy 113.646875 -245.245172)
			(xy 113.693149 -245.26875) (xy 113.735165 -245.299276) (xy 113.771888 -245.335999) (xy 113.802414 -245.378015)
			(xy 113.825992 -245.424289) (xy 113.84204 -245.473682) (xy 113.850165 -245.524977) (xy 113.850674 -245.550944)
			(xy 113.850165 -245.576911) (xy 114.130075 -245.576911) (xy 114.130075 -245.524977) (xy 114.1382 -245.473682)
			(xy 114.154248 -245.424289) (xy 114.177826 -245.378015) (xy 114.208352 -245.335999) (xy 114.245075 -245.299276)
			(xy 114.287091 -245.26875) (xy 114.333365 -245.245172) (xy 114.382758 -245.229124) (xy 114.434053 -245.220999)
			(xy 114.485987 -245.220999) (xy 114.537282 -245.229124) (xy 114.586675 -245.245172) (xy 114.632949 -245.26875)
			(xy 114.674965 -245.299276) (xy 114.711688 -245.335999) (xy 114.742214 -245.378015) (xy 114.751768 -245.396766)
			(xy 115.085368 -245.396766) (xy 115.085368 -245.396512) (xy 115.085835 -245.371986) (xy 115.093096 -245.323474)
			(xy 115.107444 -245.276568) (xy 115.128565 -245.232296) (xy 115.155996 -245.19163) (xy 115.172236 -245.173246)
			(xy 115.182076 -245.161784) (xy 115.195091 -245.134538) (xy 115.199555 -245.104675) (xy 115.195076 -245.074814)
			(xy 115.182048 -245.047574) (xy 115.172236 -245.036086) (xy 115.15597 -245.017721) (xy 115.128526 -244.977058)
			(xy 115.1074 -244.932782) (xy 115.093056 -244.885869) (xy 115.08581 -244.837349) (xy 115.085368 -244.81282)
			(xy 115.085368 -244.812566) (xy 115.085877 -244.786599) (xy 115.094002 -244.735304) (xy 115.11005 -244.685911)
			(xy 115.133628 -244.639637) (xy 115.164154 -244.597621) (xy 115.200877 -244.560898) (xy 115.242893 -244.530372)
			(xy 115.289167 -244.506794) (xy 115.33856 -244.490746) (xy 115.389855 -244.482621) (xy 115.441789 -244.482621)
			(xy 115.493084 -244.490746) (xy 115.542477 -244.506794) (xy 115.588751 -244.530372) (xy 115.630767 -244.560898)
			(xy 115.66749 -244.597621) (xy 115.698016 -244.639637) (xy 115.721594 -244.685911) (xy 115.737642 -244.735304)
			(xy 115.745767 -244.786599) (xy 115.746276 -244.812566) (xy 115.746276 -244.81282) (xy 115.745817 -244.837346)
			(xy 115.738553 -244.885858) (xy 115.724202 -244.932764) (xy 115.703079 -244.977036) (xy 115.675648 -245.017701)
			(xy 115.659408 -245.036086) (xy 115.649639 -245.047602) (xy 115.636624 -245.07483) (xy 115.63215 -245.104675)
			(xy 115.636609 -245.134522) (xy 115.649611 -245.161757) (xy 115.659408 -245.173246) (xy 115.675649 -245.191632)
			(xy 115.703095 -245.23229) (xy 115.724225 -245.27656) (xy 115.738575 -245.323469) (xy 115.745829 -245.371985)
			(xy 115.746276 -245.396512) (xy 115.746276 -245.396766) (xy 115.745767 -245.422733) (xy 115.737642 -245.474028)
			(xy 115.721594 -245.523421) (xy 115.698016 -245.569695) (xy 115.676577 -245.599204) (xy 120.645936 -245.599204)
			(xy 120.645936 -245.59895) (xy 120.646374 -245.574423) (xy 120.653643 -245.52591) (xy 120.667999 -245.479004)
			(xy 120.689126 -245.434732) (xy 120.716562 -245.394068) (xy 120.732804 -245.375684) (xy 120.742601 -245.364191)
			(xy 120.755612 -245.336955) (xy 120.760079 -245.307103) (xy 120.755613 -245.277251) (xy 120.742604 -245.250014)
			(xy 120.732804 -245.238524) (xy 120.716535 -245.220128) (xy 120.689068 -245.179422) (xy 120.667932 -245.135096)
			(xy 120.653591 -245.08813) (xy 120.646364 -245.039558) (xy 120.645936 -245.015004) (xy 120.646357 -244.990451)
			(xy 120.653604 -244.941884) (xy 120.667952 -244.894922) (xy 120.689088 -244.850599) (xy 120.716546 -244.809888)
			(xy 120.732804 -244.791484) (xy 120.742601 -244.779991) (xy 120.755612 -244.752755) (xy 120.760079 -244.722903)
			(xy 120.755613 -244.693051) (xy 120.742604 -244.665814) (xy 120.732804 -244.654324) (xy 120.716535 -244.635928)
			(xy 120.689068 -244.595222) (xy 120.667932 -244.550896) (xy 120.653591 -244.50393) (xy 120.646364 -244.455358)
			(xy 120.645936 -244.430804) (xy 120.646357 -244.406251) (xy 120.653604 -244.357684) (xy 120.667952 -244.310722)
			(xy 120.689088 -244.266399) (xy 120.716546 -244.225688) (xy 120.732804 -244.207284) (xy 120.742601 -244.195791)
			(xy 120.755612 -244.168555) (xy 120.760079 -244.138703) (xy 120.755613 -244.108851) (xy 120.742604 -244.081614)
			(xy 120.732804 -244.070124) (xy 120.716551 -244.051748) (xy 120.689106 -244.011088) (xy 120.667978 -243.966815)
			(xy 120.653631 -243.919904) (xy 120.646381 -243.871386) (xy 120.645936 -243.846858) (xy 120.645936 -243.846604)
			(xy 120.646445 -243.820637) (xy 120.65457 -243.769342) (xy 120.670618 -243.719949) (xy 120.694196 -243.673675)
			(xy 120.724722 -243.631659) (xy 120.761445 -243.594936) (xy 120.803461 -243.56441) (xy 120.849735 -243.540832)
			(xy 120.899128 -243.524784) (xy 120.950423 -243.516659) (xy 121.002357 -243.516659) (xy 121.053652 -243.524784)
			(xy 121.103045 -243.540832) (xy 121.149319 -243.56441) (xy 121.191335 -243.594936) (xy 121.228058 -243.631659)
			(xy 121.258584 -243.673675) (xy 121.282162 -243.719949) (xy 121.29821 -243.769342) (xy 121.306335 -243.820637)
			(xy 121.306844 -243.846604) (xy 121.306844 -243.846858) (xy 121.306416 -243.871385) (xy 121.299145 -243.919899)
			(xy 121.290308 -243.948771) (xy 121.647967 -243.948771) (xy 121.647967 -243.896837) (xy 121.656092 -243.845542)
			(xy 121.67214 -243.796149) (xy 121.695718 -243.749875) (xy 121.726244 -243.707859) (xy 121.762967 -243.671136)
			(xy 121.804983 -243.64061) (xy 121.851257 -243.617032) (xy 121.90065 -243.600984) (xy 121.951945 -243.592859)
			(xy 122.003879 -243.592859) (xy 122.055174 -243.600984) (xy 122.104567 -243.617032) (xy 122.150841 -243.64061)
			(xy 122.192857 -243.671136) (xy 122.22958 -243.707859) (xy 122.260106 -243.749875) (xy 122.283684 -243.796149)
			(xy 122.299732 -243.845542) (xy 122.307857 -243.896837) (xy 122.308366 -243.922804) (xy 122.307857 -243.948771)
			(xy 122.587767 -243.948771) (xy 122.587767 -243.896837) (xy 122.595892 -243.845542) (xy 122.61194 -243.796149)
			(xy 122.635518 -243.749875) (xy 122.666044 -243.707859) (xy 122.702767 -243.671136) (xy 122.744783 -243.64061)
			(xy 122.791057 -243.617032) (xy 122.84045 -243.600984) (xy 122.891745 -243.592859) (xy 122.943679 -243.592859)
			(xy 122.994974 -243.600984) (xy 123.044367 -243.617032) (xy 123.090641 -243.64061) (xy 123.132657 -243.671136)
			(xy 123.16938 -243.707859) (xy 123.199906 -243.749875) (xy 123.223484 -243.796149) (xy 123.239532 -243.845542)
			(xy 123.247657 -243.896837) (xy 123.248166 -243.922804) (xy 123.247657 -243.948771) (xy 123.527821 -243.948771)
			(xy 123.527821 -243.896837) (xy 123.535946 -243.845542) (xy 123.551994 -243.796149) (xy 123.575572 -243.749875)
			(xy 123.606098 -243.707859) (xy 123.642821 -243.671136) (xy 123.684837 -243.64061) (xy 123.731111 -243.617032)
			(xy 123.780504 -243.600984) (xy 123.831799 -243.592859) (xy 123.883733 -243.592859) (xy 123.935028 -243.600984)
			(xy 123.984421 -243.617032) (xy 124.030695 -243.64061) (xy 124.072711 -243.671136) (xy 124.109434 -243.707859)
			(xy 124.13996 -243.749875) (xy 124.163538 -243.796149) (xy 124.179586 -243.845542) (xy 124.187711 -243.896837)
			(xy 124.18822 -243.922804) (xy 124.187711 -243.948771) (xy 124.467621 -243.948771) (xy 124.467621 -243.896837)
			(xy 124.475746 -243.845542) (xy 124.491794 -243.796149) (xy 124.515372 -243.749875) (xy 124.545898 -243.707859)
			(xy 124.582621 -243.671136) (xy 124.624637 -243.64061) (xy 124.670911 -243.617032) (xy 124.720304 -243.600984)
			(xy 124.771599 -243.592859) (xy 124.823533 -243.592859) (xy 124.874828 -243.600984) (xy 124.924221 -243.617032)
			(xy 124.970495 -243.64061) (xy 125.012511 -243.671136) (xy 125.049234 -243.707859) (xy 125.07976 -243.749875)
			(xy 125.103338 -243.796149) (xy 125.119386 -243.845542) (xy 125.127511 -243.896837) (xy 125.12802 -243.922804)
			(xy 125.127511 -243.948771) (xy 125.407421 -243.948771) (xy 125.407421 -243.896837) (xy 125.415546 -243.845542)
			(xy 125.431594 -243.796149) (xy 125.455172 -243.749875) (xy 125.485698 -243.707859) (xy 125.522421 -243.671136)
			(xy 125.564437 -243.64061) (xy 125.610711 -243.617032) (xy 125.660104 -243.600984) (xy 125.711399 -243.592859)
			(xy 125.763333 -243.592859) (xy 125.814628 -243.600984) (xy 125.864021 -243.617032) (xy 125.910295 -243.64061)
			(xy 125.952311 -243.671136) (xy 125.989034 -243.707859) (xy 126.01956 -243.749875) (xy 126.043138 -243.796149)
			(xy 126.059186 -243.845542) (xy 126.067311 -243.896837) (xy 126.06782 -243.922804) (xy 126.067311 -243.948771)
			(xy 126.347221 -243.948771) (xy 126.347221 -243.896837) (xy 126.355346 -243.845542) (xy 126.371394 -243.796149)
			(xy 126.394972 -243.749875) (xy 126.425498 -243.707859) (xy 126.462221 -243.671136) (xy 126.504237 -243.64061)
			(xy 126.550511 -243.617032) (xy 126.599904 -243.600984) (xy 126.651199 -243.592859) (xy 126.703133 -243.592859)
			(xy 126.754428 -243.600984) (xy 126.803821 -243.617032) (xy 126.850095 -243.64061) (xy 126.892111 -243.671136)
			(xy 126.928834 -243.707859) (xy 126.95936 -243.749875) (xy 126.982938 -243.796149) (xy 126.998986 -243.845542)
			(xy 127.007111 -243.896837) (xy 127.00762 -243.922804) (xy 127.007111 -243.948771) (xy 127.287021 -243.948771)
			(xy 127.287021 -243.896837) (xy 127.295146 -243.845542) (xy 127.311194 -243.796149) (xy 127.334772 -243.749875)
			(xy 127.365298 -243.707859) (xy 127.402021 -243.671136) (xy 127.444037 -243.64061) (xy 127.490311 -243.617032)
			(xy 127.539704 -243.600984) (xy 127.590999 -243.592859) (xy 127.642933 -243.592859) (xy 127.694228 -243.600984)
			(xy 127.743621 -243.617032) (xy 127.789895 -243.64061) (xy 127.831911 -243.671136) (xy 127.868634 -243.707859)
			(xy 127.89916 -243.749875) (xy 127.922738 -243.796149) (xy 127.938786 -243.845542) (xy 127.946911 -243.896837)
			(xy 127.94742 -243.922804) (xy 127.946911 -243.948771) (xy 128.226821 -243.948771) (xy 128.226821 -243.896837)
			(xy 128.234946 -243.845542) (xy 128.250994 -243.796149) (xy 128.274572 -243.749875) (xy 128.305098 -243.707859)
			(xy 128.341821 -243.671136) (xy 128.383837 -243.64061) (xy 128.430111 -243.617032) (xy 128.479504 -243.600984)
			(xy 128.530799 -243.592859) (xy 128.582733 -243.592859) (xy 128.634028 -243.600984) (xy 128.683421 -243.617032)
			(xy 128.729695 -243.64061) (xy 128.771711 -243.671136) (xy 128.808434 -243.707859) (xy 128.83896 -243.749875)
			(xy 128.862538 -243.796149) (xy 128.878586 -243.845542) (xy 128.886711 -243.896837) (xy 128.88722 -243.922804)
			(xy 128.886711 -243.948771) (xy 129.166367 -243.948771) (xy 129.166367 -243.896837) (xy 129.174492 -243.845542)
			(xy 129.19054 -243.796149) (xy 129.214118 -243.749875) (xy 129.244644 -243.707859) (xy 129.281367 -243.671136)
			(xy 129.323383 -243.64061) (xy 129.369657 -243.617032) (xy 129.41905 -243.600984) (xy 129.470345 -243.592859)
			(xy 129.522279 -243.592859) (xy 129.573574 -243.600984) (xy 129.622967 -243.617032) (xy 129.669241 -243.64061)
			(xy 129.711257 -243.671136) (xy 129.74798 -243.707859) (xy 129.778506 -243.749875) (xy 129.802084 -243.796149)
			(xy 129.818132 -243.845542) (xy 129.826257 -243.896837) (xy 129.826766 -243.922804) (xy 129.826257 -243.948771)
			(xy 130.106421 -243.948771) (xy 130.106421 -243.896837) (xy 130.114546 -243.845542) (xy 130.130594 -243.796149)
			(xy 130.154172 -243.749875) (xy 130.184698 -243.707859) (xy 130.221421 -243.671136) (xy 130.263437 -243.64061)
			(xy 130.309711 -243.617032) (xy 130.359104 -243.600984) (xy 130.410399 -243.592859) (xy 130.462333 -243.592859)
			(xy 130.513628 -243.600984) (xy 130.563021 -243.617032) (xy 130.609295 -243.64061) (xy 130.651311 -243.671136)
			(xy 130.688034 -243.707859) (xy 130.71856 -243.749875) (xy 130.742138 -243.796149) (xy 130.758186 -243.845542)
			(xy 130.766311 -243.896837) (xy 130.76682 -243.922804) (xy 130.766311 -243.948771) (xy 130.758186 -244.000066)
			(xy 130.742138 -244.049459) (xy 130.71856 -244.095733) (xy 130.688034 -244.137749) (xy 130.651311 -244.174472)
			(xy 130.609295 -244.204998) (xy 130.563021 -244.228576) (xy 130.513628 -244.244624) (xy 130.462333 -244.252749)
			(xy 130.410399 -244.252749) (xy 130.359104 -244.244624) (xy 130.309711 -244.228576) (xy 130.263437 -244.204998)
			(xy 130.221421 -244.174472) (xy 130.184698 -244.137749) (xy 130.154172 -244.095733) (xy 130.130594 -244.049459)
			(xy 130.114546 -244.000066) (xy 130.106421 -243.948771) (xy 129.826257 -243.948771) (xy 129.818132 -244.000066)
			(xy 129.802084 -244.049459) (xy 129.778506 -244.095733) (xy 129.74798 -244.137749) (xy 129.711257 -244.174472)
			(xy 129.669241 -244.204998) (xy 129.622967 -244.228576) (xy 129.573574 -244.244624) (xy 129.522279 -244.252749)
			(xy 129.470345 -244.252749) (xy 129.41905 -244.244624) (xy 129.369657 -244.228576) (xy 129.323383 -244.204998)
			(xy 129.281367 -244.174472) (xy 129.244644 -244.137749) (xy 129.214118 -244.095733) (xy 129.19054 -244.049459)
			(xy 129.174492 -244.000066) (xy 129.166367 -243.948771) (xy 128.886711 -243.948771) (xy 128.878586 -244.000066)
			(xy 128.862538 -244.049459) (xy 128.83896 -244.095733) (xy 128.808434 -244.137749) (xy 128.771711 -244.174472)
			(xy 128.729695 -244.204998) (xy 128.683421 -244.228576) (xy 128.634028 -244.244624) (xy 128.582733 -244.252749)
			(xy 128.530799 -244.252749) (xy 128.479504 -244.244624) (xy 128.430111 -244.228576) (xy 128.383837 -244.204998)
			(xy 128.341821 -244.174472) (xy 128.305098 -244.137749) (xy 128.274572 -244.095733) (xy 128.250994 -244.049459)
			(xy 128.234946 -244.000066) (xy 128.226821 -243.948771) (xy 127.946911 -243.948771) (xy 127.938786 -244.000066)
			(xy 127.922738 -244.049459) (xy 127.89916 -244.095733) (xy 127.868634 -244.137749) (xy 127.831911 -244.174472)
			(xy 127.789895 -244.204998) (xy 127.743621 -244.228576) (xy 127.694228 -244.244624) (xy 127.642933 -244.252749)
			(xy 127.590999 -244.252749) (xy 127.539704 -244.244624) (xy 127.490311 -244.228576) (xy 127.444037 -244.204998)
			(xy 127.402021 -244.174472) (xy 127.365298 -244.137749) (xy 127.334772 -244.095733) (xy 127.311194 -244.049459)
			(xy 127.295146 -244.000066) (xy 127.287021 -243.948771) (xy 127.007111 -243.948771) (xy 126.998986 -244.000066)
			(xy 126.982938 -244.049459) (xy 126.95936 -244.095733) (xy 126.928834 -244.137749) (xy 126.892111 -244.174472)
			(xy 126.850095 -244.204998) (xy 126.803821 -244.228576) (xy 126.754428 -244.244624) (xy 126.703133 -244.252749)
			(xy 126.651199 -244.252749) (xy 126.599904 -244.244624) (xy 126.550511 -244.228576) (xy 126.504237 -244.204998)
			(xy 126.462221 -244.174472) (xy 126.425498 -244.137749) (xy 126.394972 -244.095733) (xy 126.371394 -244.049459)
			(xy 126.355346 -244.000066) (xy 126.347221 -243.948771) (xy 126.067311 -243.948771) (xy 126.059186 -244.000066)
			(xy 126.043138 -244.049459) (xy 126.01956 -244.095733) (xy 125.989034 -244.137749) (xy 125.952311 -244.174472)
			(xy 125.910295 -244.204998) (xy 125.864021 -244.228576) (xy 125.814628 -244.244624) (xy 125.763333 -244.252749)
			(xy 125.711399 -244.252749) (xy 125.660104 -244.244624) (xy 125.610711 -244.228576) (xy 125.564437 -244.204998)
			(xy 125.522421 -244.174472) (xy 125.485698 -244.137749) (xy 125.455172 -244.095733) (xy 125.431594 -244.049459)
			(xy 125.415546 -244.000066) (xy 125.407421 -243.948771) (xy 125.127511 -243.948771) (xy 125.119386 -244.000066)
			(xy 125.103338 -244.049459) (xy 125.07976 -244.095733) (xy 125.049234 -244.137749) (xy 125.012511 -244.174472)
			(xy 124.970495 -244.204998) (xy 124.924221 -244.228576) (xy 124.874828 -244.244624) (xy 124.823533 -244.252749)
			(xy 124.771599 -244.252749) (xy 124.720304 -244.244624) (xy 124.670911 -244.228576) (xy 124.624637 -244.204998)
			(xy 124.582621 -244.174472) (xy 124.545898 -244.137749) (xy 124.515372 -244.095733) (xy 124.491794 -244.049459)
			(xy 124.475746 -244.000066) (xy 124.467621 -243.948771) (xy 124.187711 -243.948771) (xy 124.179586 -244.000066)
			(xy 124.163538 -244.049459) (xy 124.13996 -244.095733) (xy 124.109434 -244.137749) (xy 124.072711 -244.174472)
			(xy 124.030695 -244.204998) (xy 123.984421 -244.228576) (xy 123.935028 -244.244624) (xy 123.883733 -244.252749)
			(xy 123.831799 -244.252749) (xy 123.780504 -244.244624) (xy 123.731111 -244.228576) (xy 123.684837 -244.204998)
			(xy 123.642821 -244.174472) (xy 123.606098 -244.137749) (xy 123.575572 -244.095733) (xy 123.551994 -244.049459)
			(xy 123.535946 -244.000066) (xy 123.527821 -243.948771) (xy 123.247657 -243.948771) (xy 123.239532 -244.000066)
			(xy 123.223484 -244.049459) (xy 123.199906 -244.095733) (xy 123.16938 -244.137749) (xy 123.132657 -244.174472)
			(xy 123.090641 -244.204998) (xy 123.044367 -244.228576) (xy 122.994974 -244.244624) (xy 122.943679 -244.252749)
			(xy 122.891745 -244.252749) (xy 122.84045 -244.244624) (xy 122.791057 -244.228576) (xy 122.744783 -244.204998)
			(xy 122.702767 -244.174472) (xy 122.666044 -244.137749) (xy 122.635518 -244.095733) (xy 122.61194 -244.049459)
			(xy 122.595892 -244.000066) (xy 122.587767 -243.948771) (xy 122.307857 -243.948771) (xy 122.299732 -244.000066)
			(xy 122.283684 -244.049459) (xy 122.260106 -244.095733) (xy 122.22958 -244.137749) (xy 122.192857 -244.174472)
			(xy 122.150841 -244.204998) (xy 122.104567 -244.228576) (xy 122.055174 -244.244624) (xy 122.003879 -244.252749)
			(xy 121.951945 -244.252749) (xy 121.90065 -244.244624) (xy 121.851257 -244.228576) (xy 121.804983 -244.204998)
			(xy 121.762967 -244.174472) (xy 121.726244 -244.137749) (xy 121.695718 -244.095733) (xy 121.67214 -244.049459)
			(xy 121.656092 -244.000066) (xy 121.647967 -243.948771) (xy 121.290308 -243.948771) (xy 121.284788 -243.966806)
			(xy 121.263658 -244.011077) (xy 121.236219 -244.051741) (xy 121.219976 -244.070124) (xy 121.210172 -244.081612)
			(xy 121.197165 -244.10885) (xy 121.1927 -244.138703) (xy 121.197167 -244.168555) (xy 121.210176 -244.195793)
			(xy 121.219976 -244.207284) (xy 121.237573 -244.227248) (xy 121.266744 -244.271756) (xy 121.288394 -244.320369)
			(xy 121.295668 -244.345968) (xy 121.299529 -244.358806) (xy 121.312935 -244.382011) (xy 121.331911 -244.400934)
			(xy 121.355152 -244.414278) (xy 121.381062 -244.421123) (xy 121.40786 -244.421002) (xy 121.42089 -244.41785)
			(xy 121.442256 -244.412391) (xy 121.485963 -244.40653) (xy 121.508012 -244.406166) (xy 121.53398 -244.406636)
			(xy 121.585277 -244.414763) (xy 121.634671 -244.430813) (xy 121.680946 -244.454393) (xy 121.722963 -244.484921)
			(xy 121.759686 -244.521647) (xy 121.790213 -244.563664) (xy 121.813791 -244.60994) (xy 121.82984 -244.659335)
			(xy 121.837965 -244.710632) (xy 121.837965 -244.762333) (xy 122.117867 -244.762333) (xy 122.117867 -244.710399)
			(xy 122.125992 -244.659104) (xy 122.14204 -244.609711) (xy 122.165618 -244.563437) (xy 122.196144 -244.521421)
			(xy 122.232867 -244.484698) (xy 122.274883 -244.454172) (xy 122.321157 -244.430594) (xy 122.37055 -244.414546)
			(xy 122.421845 -244.406421) (xy 122.473779 -244.406421) (xy 122.525074 -244.414546) (xy 122.574467 -244.430594)
			(xy 122.620741 -244.454172) (xy 122.662757 -244.484698) (xy 122.69948 -244.521421) (xy 122.730006 -244.563437)
			(xy 122.753584 -244.609711) (xy 122.769632 -244.659104) (xy 122.777757 -244.710399) (xy 122.778266 -244.736366)
			(xy 122.777757 -244.762333) (xy 122.777717 -244.762587) (xy 123.057667 -244.762587) (xy 123.057667 -244.710653)
			(xy 123.065792 -244.659358) (xy 123.08184 -244.609965) (xy 123.105418 -244.563691) (xy 123.135944 -244.521675)
			(xy 123.172667 -244.484952) (xy 123.214683 -244.454426) (xy 123.260957 -244.430848) (xy 123.31035 -244.4148)
			(xy 123.361645 -244.406675) (xy 123.413579 -244.406675) (xy 123.464874 -244.4148) (xy 123.514267 -244.430848)
			(xy 123.560541 -244.454426) (xy 123.602557 -244.484952) (xy 123.63928 -244.521675) (xy 123.669806 -244.563691)
			(xy 123.693384 -244.609965) (xy 123.709432 -244.659358) (xy 123.717557 -244.710653) (xy 123.718066 -244.73662)
			(xy 123.717557 -244.762587) (xy 123.997467 -244.762587) (xy 123.997467 -244.710653) (xy 124.005592 -244.659358)
			(xy 124.02164 -244.609965) (xy 124.045218 -244.563691) (xy 124.075744 -244.521675) (xy 124.112467 -244.484952)
			(xy 124.154483 -244.454426) (xy 124.200757 -244.430848) (xy 124.25015 -244.4148) (xy 124.301445 -244.406675)
			(xy 124.353379 -244.406675) (xy 124.404674 -244.4148) (xy 124.454067 -244.430848) (xy 124.500341 -244.454426)
			(xy 124.542357 -244.484952) (xy 124.57908 -244.521675) (xy 124.609606 -244.563691) (xy 124.633184 -244.609965)
			(xy 124.649232 -244.659358) (xy 124.657357 -244.710653) (xy 124.657866 -244.73662) (xy 124.657357 -244.762587)
			(xy 124.937521 -244.762587) (xy 124.937521 -244.710653) (xy 124.945646 -244.659358) (xy 124.961694 -244.609965)
			(xy 124.985272 -244.563691) (xy 125.015798 -244.521675) (xy 125.052521 -244.484952) (xy 125.094537 -244.454426)
			(xy 125.140811 -244.430848) (xy 125.190204 -244.4148) (xy 125.241499 -244.406675) (xy 125.293433 -244.406675)
			(xy 125.344728 -244.4148) (xy 125.394121 -244.430848) (xy 125.440395 -244.454426) (xy 125.482411 -244.484952)
			(xy 125.519134 -244.521675) (xy 125.54966 -244.563691) (xy 125.573238 -244.609965) (xy 125.589286 -244.659358)
			(xy 125.597411 -244.710653) (xy 125.59792 -244.73662) (xy 125.597411 -244.762587) (xy 125.877067 -244.762587)
			(xy 125.877067 -244.710653) (xy 125.885192 -244.659358) (xy 125.90124 -244.609965) (xy 125.924818 -244.563691)
			(xy 125.955344 -244.521675) (xy 125.992067 -244.484952) (xy 126.034083 -244.454426) (xy 126.080357 -244.430848)
			(xy 126.12975 -244.4148) (xy 126.181045 -244.406675) (xy 126.232979 -244.406675) (xy 126.284274 -244.4148)
			(xy 126.333667 -244.430848) (xy 126.379941 -244.454426) (xy 126.421957 -244.484952) (xy 126.45868 -244.521675)
			(xy 126.489206 -244.563691) (xy 126.512784 -244.609965) (xy 126.528832 -244.659358) (xy 126.536957 -244.710653)
			(xy 126.537466 -244.73662) (xy 126.536957 -244.762587) (xy 126.817121 -244.762587) (xy 126.817121 -244.710653)
			(xy 126.825246 -244.659358) (xy 126.841294 -244.609965) (xy 126.864872 -244.563691) (xy 126.895398 -244.521675)
			(xy 126.932121 -244.484952) (xy 126.974137 -244.454426) (xy 127.020411 -244.430848) (xy 127.069804 -244.4148)
			(xy 127.121099 -244.406675) (xy 127.173033 -244.406675) (xy 127.224328 -244.4148) (xy 127.273721 -244.430848)
			(xy 127.319995 -244.454426) (xy 127.362011 -244.484952) (xy 127.398734 -244.521675) (xy 127.42926 -244.563691)
			(xy 127.452838 -244.609965) (xy 127.468886 -244.659358) (xy 127.477011 -244.710653) (xy 127.47752 -244.73662)
			(xy 127.477011 -244.762587) (xy 127.756667 -244.762587) (xy 127.756667 -244.710653) (xy 127.764792 -244.659358)
			(xy 127.78084 -244.609965) (xy 127.804418 -244.563691) (xy 127.834944 -244.521675) (xy 127.871667 -244.484952)
			(xy 127.913683 -244.454426) (xy 127.959957 -244.430848) (xy 128.00935 -244.4148) (xy 128.060645 -244.406675)
			(xy 128.112579 -244.406675) (xy 128.163874 -244.4148) (xy 128.213267 -244.430848) (xy 128.259541 -244.454426)
			(xy 128.301557 -244.484952) (xy 128.33828 -244.521675) (xy 128.368806 -244.563691) (xy 128.392384 -244.609965)
			(xy 128.408432 -244.659358) (xy 128.416557 -244.710653) (xy 128.417066 -244.73662) (xy 128.416557 -244.762587)
			(xy 128.696467 -244.762587) (xy 128.696467 -244.710653) (xy 128.704592 -244.659358) (xy 128.72064 -244.609965)
			(xy 128.744218 -244.563691) (xy 128.774744 -244.521675) (xy 128.811467 -244.484952) (xy 128.853483 -244.454426)
			(xy 128.899757 -244.430848) (xy 128.94915 -244.4148) (xy 129.000445 -244.406675) (xy 129.052379 -244.406675)
			(xy 129.103674 -244.4148) (xy 129.153067 -244.430848) (xy 129.199341 -244.454426) (xy 129.241357 -244.484952)
			(xy 129.27808 -244.521675) (xy 129.308606 -244.563691) (xy 129.332184 -244.609965) (xy 129.348232 -244.659358)
			(xy 129.356357 -244.710653) (xy 129.356866 -244.73662) (xy 129.356357 -244.762587) (xy 129.636267 -244.762587)
			(xy 129.636267 -244.710653) (xy 129.644392 -244.659358) (xy 129.66044 -244.609965) (xy 129.684018 -244.563691)
			(xy 129.714544 -244.521675) (xy 129.751267 -244.484952) (xy 129.793283 -244.454426) (xy 129.839557 -244.430848)
			(xy 129.88895 -244.4148) (xy 129.940245 -244.406675) (xy 129.992179 -244.406675) (xy 130.043474 -244.4148)
			(xy 130.092867 -244.430848) (xy 130.139141 -244.454426) (xy 130.181157 -244.484952) (xy 130.21788 -244.521675)
			(xy 130.248406 -244.563691) (xy 130.271984 -244.609965) (xy 130.288032 -244.659358) (xy 130.296157 -244.710653)
			(xy 130.296666 -244.73662) (xy 130.296157 -244.762587) (xy 130.576067 -244.762587) (xy 130.576067 -244.710653)
			(xy 130.584192 -244.659358) (xy 130.60024 -244.609965) (xy 130.623818 -244.563691) (xy 130.654344 -244.521675)
			(xy 130.691067 -244.484952) (xy 130.733083 -244.454426) (xy 130.779357 -244.430848) (xy 130.82875 -244.4148)
			(xy 130.880045 -244.406675) (xy 130.931979 -244.406675) (xy 130.983274 -244.4148) (xy 131.032667 -244.430848)
			(xy 131.078941 -244.454426) (xy 131.120957 -244.484952) (xy 131.15768 -244.521675) (xy 131.188206 -244.563691)
			(xy 131.211784 -244.609965) (xy 131.227832 -244.659358) (xy 131.235957 -244.710653) (xy 131.236466 -244.73662)
			(xy 131.235957 -244.762587) (xy 131.227832 -244.813882) (xy 131.211784 -244.863275) (xy 131.188206 -244.909549)
			(xy 131.15768 -244.951565) (xy 131.120957 -244.988288) (xy 131.078941 -245.018814) (xy 131.032667 -245.042392)
			(xy 130.983274 -245.05844) (xy 130.931979 -245.066565) (xy 130.880045 -245.066565) (xy 130.82875 -245.05844)
			(xy 130.779357 -245.042392) (xy 130.733083 -245.018814) (xy 130.691067 -244.988288) (xy 130.654344 -244.951565)
			(xy 130.623818 -244.909549) (xy 130.60024 -244.863275) (xy 130.584192 -244.813882) (xy 130.576067 -244.762587)
			(xy 130.296157 -244.762587) (xy 130.288032 -244.813882) (xy 130.271984 -244.863275) (xy 130.248406 -244.909549)
			(xy 130.21788 -244.951565) (xy 130.181157 -244.988288) (xy 130.139141 -245.018814) (xy 130.092867 -245.042392)
			(xy 130.043474 -245.05844) (xy 129.992179 -245.066565) (xy 129.940245 -245.066565) (xy 129.88895 -245.05844)
			(xy 129.839557 -245.042392) (xy 129.793283 -245.018814) (xy 129.751267 -244.988288) (xy 129.714544 -244.951565)
			(xy 129.684018 -244.909549) (xy 129.66044 -244.863275) (xy 129.644392 -244.813882) (xy 129.636267 -244.762587)
			(xy 129.356357 -244.762587) (xy 129.348232 -244.813882) (xy 129.332184 -244.863275) (xy 129.308606 -244.909549)
			(xy 129.27808 -244.951565) (xy 129.241357 -244.988288) (xy 129.199341 -245.018814) (xy 129.153067 -245.042392)
			(xy 129.103674 -245.05844) (xy 129.052379 -245.066565) (xy 129.000445 -245.066565) (xy 128.94915 -245.05844)
			(xy 128.899757 -245.042392) (xy 128.853483 -245.018814) (xy 128.811467 -244.988288) (xy 128.774744 -244.951565)
			(xy 128.744218 -244.909549) (xy 128.72064 -244.863275) (xy 128.704592 -244.813882) (xy 128.696467 -244.762587)
			(xy 128.416557 -244.762587) (xy 128.408432 -244.813882) (xy 128.392384 -244.863275) (xy 128.368806 -244.909549)
			(xy 128.33828 -244.951565) (xy 128.301557 -244.988288) (xy 128.259541 -245.018814) (xy 128.213267 -245.042392)
			(xy 128.163874 -245.05844) (xy 128.112579 -245.066565) (xy 128.060645 -245.066565) (xy 128.00935 -245.05844)
			(xy 127.959957 -245.042392) (xy 127.913683 -245.018814) (xy 127.871667 -244.988288) (xy 127.834944 -244.951565)
			(xy 127.804418 -244.909549) (xy 127.78084 -244.863275) (xy 127.764792 -244.813882) (xy 127.756667 -244.762587)
			(xy 127.477011 -244.762587) (xy 127.468886 -244.813882) (xy 127.452838 -244.863275) (xy 127.42926 -244.909549)
			(xy 127.398734 -244.951565) (xy 127.362011 -244.988288) (xy 127.319995 -245.018814) (xy 127.273721 -245.042392)
			(xy 127.224328 -245.05844) (xy 127.173033 -245.066565) (xy 127.121099 -245.066565) (xy 127.069804 -245.05844)
			(xy 127.020411 -245.042392) (xy 126.974137 -245.018814) (xy 126.932121 -244.988288) (xy 126.895398 -244.951565)
			(xy 126.864872 -244.909549) (xy 126.841294 -244.863275) (xy 126.825246 -244.813882) (xy 126.817121 -244.762587)
			(xy 126.536957 -244.762587) (xy 126.528832 -244.813882) (xy 126.512784 -244.863275) (xy 126.489206 -244.909549)
			(xy 126.45868 -244.951565) (xy 126.421957 -244.988288) (xy 126.379941 -245.018814) (xy 126.333667 -245.042392)
			(xy 126.284274 -245.05844) (xy 126.232979 -245.066565) (xy 126.181045 -245.066565) (xy 126.12975 -245.05844)
			(xy 126.080357 -245.042392) (xy 126.034083 -245.018814) (xy 125.992067 -244.988288) (xy 125.955344 -244.951565)
			(xy 125.924818 -244.909549) (xy 125.90124 -244.863275) (xy 125.885192 -244.813882) (xy 125.877067 -244.762587)
			(xy 125.597411 -244.762587) (xy 125.589286 -244.813882) (xy 125.573238 -244.863275) (xy 125.54966 -244.909549)
			(xy 125.519134 -244.951565) (xy 125.482411 -244.988288) (xy 125.440395 -245.018814) (xy 125.394121 -245.042392)
			(xy 125.344728 -245.05844) (xy 125.293433 -245.066565) (xy 125.241499 -245.066565) (xy 125.190204 -245.05844)
			(xy 125.140811 -245.042392) (xy 125.094537 -245.018814) (xy 125.052521 -244.988288) (xy 125.015798 -244.951565)
			(xy 124.985272 -244.909549) (xy 124.961694 -244.863275) (xy 124.945646 -244.813882) (xy 124.937521 -244.762587)
			(xy 124.657357 -244.762587) (xy 124.649232 -244.813882) (xy 124.633184 -244.863275) (xy 124.609606 -244.909549)
			(xy 124.57908 -244.951565) (xy 124.542357 -244.988288) (xy 124.500341 -245.018814) (xy 124.454067 -245.042392)
			(xy 124.404674 -245.05844) (xy 124.353379 -245.066565) (xy 124.301445 -245.066565) (xy 124.25015 -245.05844)
			(xy 124.200757 -245.042392) (xy 124.154483 -245.018814) (xy 124.112467 -244.988288) (xy 124.075744 -244.951565)
			(xy 124.045218 -244.909549) (xy 124.02164 -244.863275) (xy 124.005592 -244.813882) (xy 123.997467 -244.762587)
			(xy 123.717557 -244.762587) (xy 123.709432 -244.813882) (xy 123.693384 -244.863275) (xy 123.669806 -244.909549)
			(xy 123.63928 -244.951565) (xy 123.602557 -244.988288) (xy 123.560541 -245.018814) (xy 123.514267 -245.042392)
			(xy 123.464874 -245.05844) (xy 123.413579 -245.066565) (xy 123.361645 -245.066565) (xy 123.31035 -245.05844)
			(xy 123.260957 -245.042392) (xy 123.214683 -245.018814) (xy 123.172667 -244.988288) (xy 123.135944 -244.951565)
			(xy 123.105418 -244.909549) (xy 123.08184 -244.863275) (xy 123.065792 -244.813882) (xy 123.057667 -244.762587)
			(xy 122.777717 -244.762587) (xy 122.769632 -244.813628) (xy 122.753584 -244.863021) (xy 122.730006 -244.909295)
			(xy 122.69948 -244.951311) (xy 122.662757 -244.988034) (xy 122.620741 -245.01856) (xy 122.574467 -245.042138)
			(xy 122.525074 -245.058186) (xy 122.473779 -245.066311) (xy 122.421845 -245.066311) (xy 122.37055 -245.058186)
			(xy 122.321157 -245.042138) (xy 122.274883 -245.01856) (xy 122.232867 -244.988034) (xy 122.196144 -244.951311)
			(xy 122.165618 -244.909295) (xy 122.14204 -244.863021) (xy 122.125992 -244.813628) (xy 122.117867 -244.762333)
			(xy 121.837965 -244.762333) (xy 121.837965 -244.762568) (xy 121.82984 -244.813865) (xy 121.813791 -244.86326)
			(xy 121.790213 -244.909536) (xy 121.759686 -244.951553) (xy 121.722963 -244.988279) (xy 121.680946 -245.018807)
			(xy 121.634671 -245.042387) (xy 121.585277 -245.058437) (xy 121.53398 -245.066564) (xy 121.508012 -245.067074)
			(xy 121.484437 -245.066661) (xy 121.437773 -245.059901) (xy 121.415048 -245.053612) (xy 121.399894 -245.049703)
			(xy 121.368619 -245.050398) (xy 121.339019 -245.060523) (xy 121.31387 -245.079128) (xy 121.295529 -245.104471)
			(xy 121.29008 -245.119144) (xy 121.282396 -245.141098) (xy 121.261713 -245.182759) (xy 121.235399 -245.221113)
			(xy 121.219976 -245.238524) (xy 121.210172 -245.250012) (xy 121.197165 -245.27725) (xy 121.1927 -245.307103)
			(xy 121.197167 -245.336955) (xy 121.210176 -245.364193) (xy 121.219976 -245.375684) (xy 121.236229 -245.394059)
			(xy 121.263675 -245.43472) (xy 121.284803 -245.478993) (xy 121.29915 -245.525904) (xy 121.3064 -245.574422)
			(xy 121.30644 -245.576657) (xy 121.648221 -245.576657) (xy 121.648221 -245.524723) (xy 121.656346 -245.473428)
			(xy 121.672394 -245.424035) (xy 121.695972 -245.377761) (xy 121.726498 -245.335745) (xy 121.763221 -245.299022)
			(xy 121.805237 -245.268496) (xy 121.851511 -245.244918) (xy 121.900904 -245.22887) (xy 121.952199 -245.220745)
			(xy 122.004133 -245.220745) (xy 122.055428 -245.22887) (xy 122.104821 -245.244918) (xy 122.151095 -245.268496)
			(xy 122.193111 -245.299022) (xy 122.229834 -245.335745) (xy 122.26036 -245.377761) (xy 122.283938 -245.424035)
			(xy 122.299986 -245.473428) (xy 122.308111 -245.524723) (xy 122.30862 -245.55069) (xy 122.308111 -245.576657)
			(xy 122.588021 -245.576657) (xy 122.588021 -245.524723) (xy 122.596146 -245.473428) (xy 122.612194 -245.424035)
			(xy 122.635772 -245.377761) (xy 122.666298 -245.335745) (xy 122.703021 -245.299022) (xy 122.745037 -245.268496)
			(xy 122.791311 -245.244918) (xy 122.840704 -245.22887) (xy 122.891999 -245.220745) (xy 122.943933 -245.220745)
			(xy 122.995228 -245.22887) (xy 123.044621 -245.244918) (xy 123.090895 -245.268496) (xy 123.132911 -245.299022)
			(xy 123.169634 -245.335745) (xy 123.20016 -245.377761) (xy 123.223738 -245.424035) (xy 123.239786 -245.473428)
			(xy 123.247911 -245.524723) (xy 123.24842 -245.55069) (xy 123.247911 -245.576657) (xy 123.527821 -245.576657)
			(xy 123.527821 -245.524723) (xy 123.535946 -245.473428) (xy 123.551994 -245.424035) (xy 123.575572 -245.377761)
			(xy 123.606098 -245.335745) (xy 123.642821 -245.299022) (xy 123.684837 -245.268496) (xy 123.731111 -245.244918)
			(xy 123.780504 -245.22887) (xy 123.831799 -245.220745) (xy 123.883733 -245.220745) (xy 123.935028 -245.22887)
			(xy 123.984421 -245.244918) (xy 124.030695 -245.268496) (xy 124.072711 -245.299022) (xy 124.109434 -245.335745)
			(xy 124.13996 -245.377761) (xy 124.163538 -245.424035) (xy 124.179586 -245.473428) (xy 124.187711 -245.524723)
			(xy 124.18822 -245.55069) (xy 124.187711 -245.576657) (xy 124.467621 -245.576657) (xy 124.467621 -245.524723)
			(xy 124.475746 -245.473428) (xy 124.491794 -245.424035) (xy 124.515372 -245.377761) (xy 124.545898 -245.335745)
			(xy 124.582621 -245.299022) (xy 124.624637 -245.268496) (xy 124.670911 -245.244918) (xy 124.720304 -245.22887)
			(xy 124.771599 -245.220745) (xy 124.823533 -245.220745) (xy 124.874828 -245.22887) (xy 124.924221 -245.244918)
			(xy 124.970495 -245.268496) (xy 125.012511 -245.299022) (xy 125.049234 -245.335745) (xy 125.07976 -245.377761)
			(xy 125.103338 -245.424035) (xy 125.119386 -245.473428) (xy 125.127511 -245.524723) (xy 125.12802 -245.55069)
			(xy 125.127511 -245.576657) (xy 125.407167 -245.576657) (xy 125.407167 -245.524723) (xy 125.415292 -245.473428)
			(xy 125.43134 -245.424035) (xy 125.454918 -245.377761) (xy 125.485444 -245.335745) (xy 125.522167 -245.299022)
			(xy 125.564183 -245.268496) (xy 125.610457 -245.244918) (xy 125.65985 -245.22887) (xy 125.711145 -245.220745)
			(xy 125.763079 -245.220745) (xy 125.814374 -245.22887) (xy 125.863767 -245.244918) (xy 125.910041 -245.268496)
			(xy 125.952057 -245.299022) (xy 125.98878 -245.335745) (xy 126.019306 -245.377761) (xy 126.042884 -245.424035)
			(xy 126.058932 -245.473428) (xy 126.067057 -245.524723) (xy 126.067566 -245.55069) (xy 126.067057 -245.576657)
			(xy 126.347221 -245.576657) (xy 126.347221 -245.524723) (xy 126.355346 -245.473428) (xy 126.371394 -245.424035)
			(xy 126.394972 -245.377761) (xy 126.425498 -245.335745) (xy 126.462221 -245.299022) (xy 126.504237 -245.268496)
			(xy 126.550511 -245.244918) (xy 126.599904 -245.22887) (xy 126.651199 -245.220745) (xy 126.703133 -245.220745)
			(xy 126.754428 -245.22887) (xy 126.803821 -245.244918) (xy 126.850095 -245.268496) (xy 126.892111 -245.299022)
			(xy 126.928834 -245.335745) (xy 126.95936 -245.377761) (xy 126.982938 -245.424035) (xy 126.998986 -245.473428)
			(xy 127.007111 -245.524723) (xy 127.00762 -245.55069) (xy 127.007111 -245.576657) (xy 127.286767 -245.576657)
			(xy 127.286767 -245.524723) (xy 127.294892 -245.473428) (xy 127.31094 -245.424035) (xy 127.334518 -245.377761)
			(xy 127.365044 -245.335745) (xy 127.401767 -245.299022) (xy 127.443783 -245.268496) (xy 127.490057 -245.244918)
			(xy 127.53945 -245.22887) (xy 127.590745 -245.220745) (xy 127.642679 -245.220745) (xy 127.693974 -245.22887)
			(xy 127.743367 -245.244918) (xy 127.789641 -245.268496) (xy 127.831657 -245.299022) (xy 127.86838 -245.335745)
			(xy 127.898906 -245.377761) (xy 127.922484 -245.424035) (xy 127.938532 -245.473428) (xy 127.946657 -245.524723)
			(xy 127.947166 -245.55069) (xy 127.946657 -245.576657) (xy 128.226821 -245.576657) (xy 128.226821 -245.524723)
			(xy 128.234946 -245.473428) (xy 128.250994 -245.424035) (xy 128.274572 -245.377761) (xy 128.305098 -245.335745)
			(xy 128.341821 -245.299022) (xy 128.383837 -245.268496) (xy 128.430111 -245.244918) (xy 128.479504 -245.22887)
			(xy 128.530799 -245.220745) (xy 128.582733 -245.220745) (xy 128.634028 -245.22887) (xy 128.683421 -245.244918)
			(xy 128.729695 -245.268496) (xy 128.771711 -245.299022) (xy 128.808434 -245.335745) (xy 128.83896 -245.377761)
			(xy 128.862538 -245.424035) (xy 128.878586 -245.473428) (xy 128.886711 -245.524723) (xy 128.88722 -245.55069)
			(xy 128.886711 -245.576657) (xy 129.166621 -245.576657) (xy 129.166621 -245.524723) (xy 129.174746 -245.473428)
			(xy 129.190794 -245.424035) (xy 129.214372 -245.377761) (xy 129.244898 -245.335745) (xy 129.281621 -245.299022)
			(xy 129.323637 -245.268496) (xy 129.369911 -245.244918) (xy 129.419304 -245.22887) (xy 129.470599 -245.220745)
			(xy 129.522533 -245.220745) (xy 129.573828 -245.22887) (xy 129.623221 -245.244918) (xy 129.669495 -245.268496)
			(xy 129.711511 -245.299022) (xy 129.748234 -245.335745) (xy 129.77876 -245.377761) (xy 129.802338 -245.424035)
			(xy 129.818386 -245.473428) (xy 129.826511 -245.524723) (xy 129.82702 -245.55069) (xy 129.826511 -245.576657)
			(xy 130.106421 -245.576657) (xy 130.106421 -245.524723) (xy 130.114546 -245.473428) (xy 130.130594 -245.424035)
			(xy 130.154172 -245.377761) (xy 130.184698 -245.335745) (xy 130.221421 -245.299022) (xy 130.263437 -245.268496)
			(xy 130.309711 -245.244918) (xy 130.359104 -245.22887) (xy 130.410399 -245.220745) (xy 130.462333 -245.220745)
			(xy 130.513628 -245.22887) (xy 130.563021 -245.244918) (xy 130.609295 -245.268496) (xy 130.651311 -245.299022)
			(xy 130.688034 -245.335745) (xy 130.71856 -245.377761) (xy 130.742138 -245.424035) (xy 130.758186 -245.473428)
			(xy 130.766311 -245.524723) (xy 130.76682 -245.55069) (xy 130.766311 -245.576657) (xy 130.758186 -245.627952)
			(xy 130.742138 -245.677345) (xy 130.71856 -245.723619) (xy 130.688034 -245.765635) (xy 130.651311 -245.802358)
			(xy 130.609295 -245.832884) (xy 130.563021 -245.856462) (xy 130.513628 -245.87251) (xy 130.462333 -245.880635)
			(xy 130.410399 -245.880635) (xy 130.359104 -245.87251) (xy 130.309711 -245.856462) (xy 130.263437 -245.832884)
			(xy 130.221421 -245.802358) (xy 130.184698 -245.765635) (xy 130.154172 -245.723619) (xy 130.130594 -245.677345)
			(xy 130.114546 -245.627952) (xy 130.106421 -245.576657) (xy 129.826511 -245.576657) (xy 129.818386 -245.627952)
			(xy 129.802338 -245.677345) (xy 129.77876 -245.723619) (xy 129.748234 -245.765635) (xy 129.711511 -245.802358)
			(xy 129.669495 -245.832884) (xy 129.623221 -245.856462) (xy 129.573828 -245.87251) (xy 129.522533 -245.880635)
			(xy 129.470599 -245.880635) (xy 129.419304 -245.87251) (xy 129.369911 -245.856462) (xy 129.323637 -245.832884)
			(xy 129.281621 -245.802358) (xy 129.244898 -245.765635) (xy 129.214372 -245.723619) (xy 129.190794 -245.677345)
			(xy 129.174746 -245.627952) (xy 129.166621 -245.576657) (xy 128.886711 -245.576657) (xy 128.878586 -245.627952)
			(xy 128.862538 -245.677345) (xy 128.83896 -245.723619) (xy 128.808434 -245.765635) (xy 128.771711 -245.802358)
			(xy 128.729695 -245.832884) (xy 128.683421 -245.856462) (xy 128.634028 -245.87251) (xy 128.582733 -245.880635)
			(xy 128.530799 -245.880635) (xy 128.479504 -245.87251) (xy 128.430111 -245.856462) (xy 128.383837 -245.832884)
			(xy 128.341821 -245.802358) (xy 128.305098 -245.765635) (xy 128.274572 -245.723619) (xy 128.250994 -245.677345)
			(xy 128.234946 -245.627952) (xy 128.226821 -245.576657) (xy 127.946657 -245.576657) (xy 127.938532 -245.627952)
			(xy 127.922484 -245.677345) (xy 127.898906 -245.723619) (xy 127.86838 -245.765635) (xy 127.831657 -245.802358)
			(xy 127.789641 -245.832884) (xy 127.743367 -245.856462) (xy 127.693974 -245.87251) (xy 127.642679 -245.880635)
			(xy 127.590745 -245.880635) (xy 127.53945 -245.87251) (xy 127.490057 -245.856462) (xy 127.443783 -245.832884)
			(xy 127.401767 -245.802358) (xy 127.365044 -245.765635) (xy 127.334518 -245.723619) (xy 127.31094 -245.677345)
			(xy 127.294892 -245.627952) (xy 127.286767 -245.576657) (xy 127.007111 -245.576657) (xy 126.998986 -245.627952)
			(xy 126.982938 -245.677345) (xy 126.95936 -245.723619) (xy 126.928834 -245.765635) (xy 126.892111 -245.802358)
			(xy 126.850095 -245.832884) (xy 126.803821 -245.856462) (xy 126.754428 -245.87251) (xy 126.703133 -245.880635)
			(xy 126.651199 -245.880635) (xy 126.599904 -245.87251) (xy 126.550511 -245.856462) (xy 126.504237 -245.832884)
			(xy 126.462221 -245.802358) (xy 126.425498 -245.765635) (xy 126.394972 -245.723619) (xy 126.371394 -245.677345)
			(xy 126.355346 -245.627952) (xy 126.347221 -245.576657) (xy 126.067057 -245.576657) (xy 126.058932 -245.627952)
			(xy 126.042884 -245.677345) (xy 126.019306 -245.723619) (xy 125.98878 -245.765635) (xy 125.952057 -245.802358)
			(xy 125.910041 -245.832884) (xy 125.863767 -245.856462) (xy 125.814374 -245.87251) (xy 125.763079 -245.880635)
			(xy 125.711145 -245.880635) (xy 125.65985 -245.87251) (xy 125.610457 -245.856462) (xy 125.564183 -245.832884)
			(xy 125.522167 -245.802358) (xy 125.485444 -245.765635) (xy 125.454918 -245.723619) (xy 125.43134 -245.677345)
			(xy 125.415292 -245.627952) (xy 125.407167 -245.576657) (xy 125.127511 -245.576657) (xy 125.119386 -245.627952)
			(xy 125.103338 -245.677345) (xy 125.07976 -245.723619) (xy 125.049234 -245.765635) (xy 125.012511 -245.802358)
			(xy 124.970495 -245.832884) (xy 124.924221 -245.856462) (xy 124.874828 -245.87251) (xy 124.823533 -245.880635)
			(xy 124.771599 -245.880635) (xy 124.720304 -245.87251) (xy 124.670911 -245.856462) (xy 124.624637 -245.832884)
			(xy 124.582621 -245.802358) (xy 124.545898 -245.765635) (xy 124.515372 -245.723619) (xy 124.491794 -245.677345)
			(xy 124.475746 -245.627952) (xy 124.467621 -245.576657) (xy 124.187711 -245.576657) (xy 124.179586 -245.627952)
			(xy 124.163538 -245.677345) (xy 124.13996 -245.723619) (xy 124.109434 -245.765635) (xy 124.072711 -245.802358)
			(xy 124.030695 -245.832884) (xy 123.984421 -245.856462) (xy 123.935028 -245.87251) (xy 123.883733 -245.880635)
			(xy 123.831799 -245.880635) (xy 123.780504 -245.87251) (xy 123.731111 -245.856462) (xy 123.684837 -245.832884)
			(xy 123.642821 -245.802358) (xy 123.606098 -245.765635) (xy 123.575572 -245.723619) (xy 123.551994 -245.677345)
			(xy 123.535946 -245.627952) (xy 123.527821 -245.576657) (xy 123.247911 -245.576657) (xy 123.239786 -245.627952)
			(xy 123.223738 -245.677345) (xy 123.20016 -245.723619) (xy 123.169634 -245.765635) (xy 123.132911 -245.802358)
			(xy 123.090895 -245.832884) (xy 123.044621 -245.856462) (xy 122.995228 -245.87251) (xy 122.943933 -245.880635)
			(xy 122.891999 -245.880635) (xy 122.840704 -245.87251) (xy 122.791311 -245.856462) (xy 122.745037 -245.832884)
			(xy 122.703021 -245.802358) (xy 122.666298 -245.765635) (xy 122.635772 -245.723619) (xy 122.612194 -245.677345)
			(xy 122.596146 -245.627952) (xy 122.588021 -245.576657) (xy 122.308111 -245.576657) (xy 122.299986 -245.627952)
			(xy 122.283938 -245.677345) (xy 122.26036 -245.723619) (xy 122.229834 -245.765635) (xy 122.193111 -245.802358)
			(xy 122.151095 -245.832884) (xy 122.104821 -245.856462) (xy 122.055428 -245.87251) (xy 122.004133 -245.880635)
			(xy 121.952199 -245.880635) (xy 121.900904 -245.87251) (xy 121.851511 -245.856462) (xy 121.805237 -245.832884)
			(xy 121.763221 -245.802358) (xy 121.726498 -245.765635) (xy 121.695972 -245.723619) (xy 121.672394 -245.677345)
			(xy 121.656346 -245.627952) (xy 121.648221 -245.576657) (xy 121.30644 -245.576657) (xy 121.306844 -245.59895)
			(xy 121.306844 -245.599204) (xy 121.306335 -245.625171) (xy 121.29821 -245.676466) (xy 121.282162 -245.725859)
			(xy 121.258584 -245.772133) (xy 121.228058 -245.814149) (xy 121.191335 -245.850872) (xy 121.149319 -245.881398)
			(xy 121.103045 -245.904976) (xy 121.053652 -245.921024) (xy 121.002357 -245.929149) (xy 120.950423 -245.929149)
			(xy 120.899128 -245.921024) (xy 120.849735 -245.904976) (xy 120.803461 -245.881398) (xy 120.761445 -245.850872)
			(xy 120.724722 -245.814149) (xy 120.694196 -245.772133) (xy 120.670618 -245.725859) (xy 120.65457 -245.676466)
			(xy 120.646445 -245.625171) (xy 120.645936 -245.599204) (xy 115.676577 -245.599204) (xy 115.66749 -245.611711)
			(xy 115.630767 -245.648434) (xy 115.588751 -245.67896) (xy 115.542477 -245.702538) (xy 115.493084 -245.718586)
			(xy 115.441789 -245.726711) (xy 115.389855 -245.726711) (xy 115.33856 -245.718586) (xy 115.289167 -245.702538)
			(xy 115.242893 -245.67896) (xy 115.200877 -245.648434) (xy 115.164154 -245.611711) (xy 115.133628 -245.569695)
			(xy 115.11005 -245.523421) (xy 115.094002 -245.474028) (xy 115.085877 -245.422733) (xy 115.085368 -245.396766)
			(xy 114.751768 -245.396766) (xy 114.765792 -245.424289) (xy 114.78184 -245.473682) (xy 114.789965 -245.524977)
			(xy 114.790474 -245.550944) (xy 114.789965 -245.576911) (xy 114.78184 -245.628206) (xy 114.765792 -245.677599)
			(xy 114.742214 -245.723873) (xy 114.711688 -245.765889) (xy 114.674965 -245.802612) (xy 114.632949 -245.833138)
			(xy 114.586675 -245.856716) (xy 114.537282 -245.872764) (xy 114.485987 -245.880889) (xy 114.434053 -245.880889)
			(xy 114.382758 -245.872764) (xy 114.333365 -245.856716) (xy 114.287091 -245.833138) (xy 114.245075 -245.802612)
			(xy 114.208352 -245.765889) (xy 114.177826 -245.723873) (xy 114.154248 -245.677599) (xy 114.1382 -245.628206)
			(xy 114.130075 -245.576911) (xy 113.850165 -245.576911) (xy 113.84204 -245.628206) (xy 113.825992 -245.677599)
			(xy 113.802414 -245.723873) (xy 113.771888 -245.765889) (xy 113.735165 -245.802612) (xy 113.693149 -245.833138)
			(xy 113.646875 -245.856716) (xy 113.597482 -245.872764) (xy 113.546187 -245.880889) (xy 113.494253 -245.880889)
			(xy 113.442958 -245.872764) (xy 113.393565 -245.856716) (xy 113.347291 -245.833138) (xy 113.305275 -245.802612)
			(xy 113.268552 -245.765889) (xy 113.238026 -245.723873) (xy 113.214448 -245.677599) (xy 113.1984 -245.628206)
			(xy 113.190275 -245.576911) (xy 112.910111 -245.576911) (xy 112.901986 -245.628206) (xy 112.885938 -245.677599)
			(xy 112.86236 -245.723873) (xy 112.831834 -245.765889) (xy 112.795111 -245.802612) (xy 112.753095 -245.833138)
			(xy 112.706821 -245.856716) (xy 112.657428 -245.872764) (xy 112.606133 -245.880889) (xy 112.554199 -245.880889)
			(xy 112.502904 -245.872764) (xy 112.453511 -245.856716) (xy 112.407237 -245.833138) (xy 112.365221 -245.802612)
			(xy 112.328498 -245.765889) (xy 112.297972 -245.723873) (xy 112.274394 -245.677599) (xy 112.258346 -245.628206)
			(xy 112.250221 -245.576911) (xy 111.970311 -245.576911) (xy 111.962186 -245.628206) (xy 111.946138 -245.677599)
			(xy 111.92256 -245.723873) (xy 111.892034 -245.765889) (xy 111.855311 -245.802612) (xy 111.813295 -245.833138)
			(xy 111.767021 -245.856716) (xy 111.717628 -245.872764) (xy 111.666333 -245.880889) (xy 111.614399 -245.880889)
			(xy 111.563104 -245.872764) (xy 111.513711 -245.856716) (xy 111.467437 -245.833138) (xy 111.425421 -245.802612)
			(xy 111.388698 -245.765889) (xy 111.358172 -245.723873) (xy 111.334594 -245.677599) (xy 111.318546 -245.628206)
			(xy 111.310421 -245.576911) (xy 111.030765 -245.576911) (xy 111.02264 -245.628206) (xy 111.006592 -245.677599)
			(xy 110.983014 -245.723873) (xy 110.952488 -245.765889) (xy 110.915765 -245.802612) (xy 110.873749 -245.833138)
			(xy 110.827475 -245.856716) (xy 110.778082 -245.872764) (xy 110.726787 -245.880889) (xy 110.674853 -245.880889)
			(xy 110.623558 -245.872764) (xy 110.574165 -245.856716) (xy 110.527891 -245.833138) (xy 110.485875 -245.802612)
			(xy 110.449152 -245.765889) (xy 110.418626 -245.723873) (xy 110.395048 -245.677599) (xy 110.379 -245.628206)
			(xy 110.370875 -245.576911) (xy 110.090711 -245.576911) (xy 110.082586 -245.628206) (xy 110.066538 -245.677599)
			(xy 110.04296 -245.723873) (xy 110.012434 -245.765889) (xy 109.975711 -245.802612) (xy 109.933695 -245.833138)
			(xy 109.887421 -245.856716) (xy 109.838028 -245.872764) (xy 109.786733 -245.880889) (xy 109.734799 -245.880889)
			(xy 109.683504 -245.872764) (xy 109.634111 -245.856716) (xy 109.587837 -245.833138) (xy 109.545821 -245.802612)
			(xy 109.509098 -245.765889) (xy 109.478572 -245.723873) (xy 109.454994 -245.677599) (xy 109.438946 -245.628206)
			(xy 109.430821 -245.576911) (xy 108.671062 -245.576911) (xy 108.648815 -245.599158) (xy 108.606799 -245.629684)
			(xy 108.560525 -245.653262) (xy 108.511132 -245.66931) (xy 108.459837 -245.677435) (xy 108.407903 -245.677435)
			(xy 108.356608 -245.66931) (xy 108.307215 -245.653262) (xy 108.260941 -245.629684) (xy 108.218925 -245.599158)
			(xy 108.182202 -245.562435) (xy 108.151676 -245.520419) (xy 108.128098 -245.474145) (xy 108.11205 -245.424752)
			(xy 108.103925 -245.373457) (xy 108.103416 -245.34749) (xy 103.231257 -245.34749) (xy 103.230956 -245.363553)
			(xy 103.222833 -245.414853) (xy 103.206785 -245.464251) (xy 103.183206 -245.510529) (xy 103.152678 -245.552549)
			(xy 103.115952 -245.589275) (xy 103.073932 -245.619804) (xy 103.027654 -245.643383) (xy 102.978257 -245.659432)
			(xy 102.926957 -245.667556) (xy 102.900988 -245.668038) (xy 102.900734 -245.668038) (xy 102.875297 -245.667558)
			(xy 102.825023 -245.659764) (xy 102.776543 -245.64434) (xy 102.731008 -245.621654) (xy 102.70998 -245.607332)
			(xy 102.698726 -245.59982) (xy 102.673346 -245.590463) (xy 102.646399 -245.588113) (xy 102.619783 -245.592937)
			(xy 102.595374 -245.604593) (xy 102.574892 -245.622262) (xy 102.559781 -245.644696) (xy 102.55504 -245.65737)
			(xy 102.54628 -245.681497) (xy 102.522417 -245.726938) (xy 102.491811 -245.768139) (xy 102.455199 -245.80411)
			(xy 102.413463 -245.833983) (xy 102.367607 -245.85704) (xy 102.318737 -245.872725) (xy 102.268029 -245.88066)
			(xy 102.242366 -245.881144) (xy 102.2164 -245.880652) (xy 102.165107 -245.872523) (xy 102.115718 -245.856471)
			(xy 102.069447 -245.832891) (xy 102.027435 -245.802363) (xy 101.990715 -245.765639) (xy 101.960191 -245.723624)
			(xy 101.936616 -245.677351) (xy 101.920569 -245.62796) (xy 101.912445 -245.576666) (xy 101.63251 -245.576666)
			(xy 101.624386 -245.627952) (xy 101.608338 -245.677345) (xy 101.58476 -245.723619) (xy 101.554234 -245.765635)
			(xy 101.517511 -245.802358) (xy 101.475495 -245.832884) (xy 101.429221 -245.856462) (xy 101.379828 -245.87251)
			(xy 101.328533 -245.880635) (xy 101.276599 -245.880635) (xy 101.225304 -245.87251) (xy 101.175911 -245.856462)
			(xy 101.129637 -245.832884) (xy 101.087621 -245.802358) (xy 101.050898 -245.765635) (xy 101.020372 -245.723619)
			(xy 100.996794 -245.677345) (xy 100.980746 -245.627952) (xy 100.972621 -245.576657) (xy 100.692711 -245.576657)
			(xy 100.684586 -245.627952) (xy 100.668538 -245.677345) (xy 100.64496 -245.723619) (xy 100.614434 -245.765635)
			(xy 100.577711 -245.802358) (xy 100.535695 -245.832884) (xy 100.489421 -245.856462) (xy 100.440028 -245.87251)
			(xy 100.388733 -245.880635) (xy 100.336799 -245.880635) (xy 100.285504 -245.87251) (xy 100.236111 -245.856462)
			(xy 100.189837 -245.832884) (xy 100.147821 -245.802358) (xy 100.111098 -245.765635) (xy 100.080572 -245.723619)
			(xy 100.056994 -245.677345) (xy 100.040946 -245.627952) (xy 100.032821 -245.576657) (xy 99.752911 -245.576657)
			(xy 99.744786 -245.627952) (xy 99.728738 -245.677345) (xy 99.70516 -245.723619) (xy 99.674634 -245.765635)
			(xy 99.637911 -245.802358) (xy 99.595895 -245.832884) (xy 99.549621 -245.856462) (xy 99.500228 -245.87251)
			(xy 99.448933 -245.880635) (xy 99.396999 -245.880635) (xy 99.345704 -245.87251) (xy 99.296311 -245.856462)
			(xy 99.250037 -245.832884) (xy 99.208021 -245.802358) (xy 99.171298 -245.765635) (xy 99.140772 -245.723619)
			(xy 99.117194 -245.677345) (xy 99.101146 -245.627952) (xy 99.093021 -245.576657) (xy 98.813111 -245.576657)
			(xy 98.804986 -245.627952) (xy 98.788938 -245.677345) (xy 98.76536 -245.723619) (xy 98.734834 -245.765635)
			(xy 98.698111 -245.802358) (xy 98.656095 -245.832884) (xy 98.609821 -245.856462) (xy 98.560428 -245.87251)
			(xy 98.509133 -245.880635) (xy 98.457199 -245.880635) (xy 98.405904 -245.87251) (xy 98.356511 -245.856462)
			(xy 98.310237 -245.832884) (xy 98.268221 -245.802358) (xy 98.231498 -245.765635) (xy 98.200972 -245.723619)
			(xy 98.177394 -245.677345) (xy 98.161346 -245.627952) (xy 98.153221 -245.576657) (xy 97.873057 -245.576657)
			(xy 97.864932 -245.627952) (xy 97.848884 -245.677345) (xy 97.825306 -245.723619) (xy 97.79478 -245.765635)
			(xy 97.758057 -245.802358) (xy 97.716041 -245.832884) (xy 97.669767 -245.856462) (xy 97.620374 -245.87251)
			(xy 97.569079 -245.880635) (xy 97.517145 -245.880635) (xy 97.46585 -245.87251) (xy 97.416457 -245.856462)
			(xy 97.370183 -245.832884) (xy 97.328167 -245.802358) (xy 97.291444 -245.765635) (xy 97.260918 -245.723619)
			(xy 97.23734 -245.677345) (xy 97.221292 -245.627952) (xy 97.213167 -245.576657) (xy 96.933511 -245.576657)
			(xy 96.925386 -245.627952) (xy 96.909338 -245.677345) (xy 96.88576 -245.723619) (xy 96.855234 -245.765635)
			(xy 96.818511 -245.802358) (xy 96.776495 -245.832884) (xy 96.730221 -245.856462) (xy 96.680828 -245.87251)
			(xy 96.629533 -245.880635) (xy 96.577599 -245.880635) (xy 96.526304 -245.87251) (xy 96.476911 -245.856462)
			(xy 96.430637 -245.832884) (xy 96.388621 -245.802358) (xy 96.351898 -245.765635) (xy 96.321372 -245.723619)
			(xy 96.297794 -245.677345) (xy 96.281746 -245.627952) (xy 96.273621 -245.576657) (xy 95.993711 -245.576657)
			(xy 95.985586 -245.627952) (xy 95.969538 -245.677345) (xy 95.94596 -245.723619) (xy 95.915434 -245.765635)
			(xy 95.878711 -245.802358) (xy 95.836695 -245.832884) (xy 95.790421 -245.856462) (xy 95.741028 -245.87251)
			(xy 95.689733 -245.880635) (xy 95.637799 -245.880635) (xy 95.586504 -245.87251) (xy 95.537111 -245.856462)
			(xy 95.490837 -245.832884) (xy 95.448821 -245.802358) (xy 95.412098 -245.765635) (xy 95.381572 -245.723619)
			(xy 95.357994 -245.677345) (xy 95.341946 -245.627952) (xy 95.333821 -245.576657) (xy 95.053911 -245.576657)
			(xy 95.045786 -245.627952) (xy 95.029738 -245.677345) (xy 95.00616 -245.723619) (xy 94.975634 -245.765635)
			(xy 94.938911 -245.802358) (xy 94.896895 -245.832884) (xy 94.850621 -245.856462) (xy 94.801228 -245.87251)
			(xy 94.749933 -245.880635) (xy 94.697999 -245.880635) (xy 94.646704 -245.87251) (xy 94.597311 -245.856462)
			(xy 94.551037 -245.832884) (xy 94.509021 -245.802358) (xy 94.472298 -245.765635) (xy 94.441772 -245.723619)
			(xy 94.418194 -245.677345) (xy 94.402146 -245.627952) (xy 94.394021 -245.576657) (xy 94.114111 -245.576657)
			(xy 94.105986 -245.627952) (xy 94.089938 -245.677345) (xy 94.06636 -245.723619) (xy 94.035834 -245.765635)
			(xy 93.999111 -245.802358) (xy 93.957095 -245.832884) (xy 93.910821 -245.856462) (xy 93.861428 -245.87251)
			(xy 93.810133 -245.880635) (xy 93.758199 -245.880635) (xy 93.706904 -245.87251) (xy 93.657511 -245.856462)
			(xy 93.611237 -245.832884) (xy 93.569221 -245.802358) (xy 93.532498 -245.765635) (xy 93.501972 -245.723619)
			(xy 93.478394 -245.677345) (xy 93.462346 -245.627952) (xy 93.454221 -245.576657) (xy 93.174141 -245.576657)
			(xy 93.167504 -245.622238) (xy 93.153849 -245.668111) (xy 93.133721 -245.711535) (xy 93.120972 -245.731792)
			(xy 93.117162 -245.737634) (xy 93.108272 -245.765828) (xy 93.1088 -245.775669) (xy 93.116373 -245.793844)
			(xy 93.123004 -245.801134) (xy 93.347286 -246.025416) (xy 93.373194 -246.039132) (xy 93.373702 -246.039132)
			(xy 93.379798 -246.040402) (xy 93.380306 -246.040402) (xy 93.403873 -246.045671) (xy 93.449272 -246.062126)
			(xy 93.491797 -246.085006) (xy 93.530544 -246.113825) (xy 93.564688 -246.147972) (xy 93.593506 -246.186721)
			(xy 93.616383 -246.229247) (xy 93.632835 -246.274648) (xy 93.638116 -246.298212) (xy 93.638116 -246.29872)
			(xy 93.639386 -246.304816) (xy 93.639386 -246.305324) (xy 93.653102 -246.331232) (xy 93.752162 -246.430292)
			(xy 93.758995 -246.436516) (xy 93.775874 -246.444008) (xy 93.794316 -246.444971) (xy 93.803216 -246.442484)
			(xy 93.88729 -246.408448) (xy 93.892116 -246.406416) (xy 93.900908 -246.402404) (xy 93.914802 -246.388996)
			(xy 93.922635 -246.371348) (xy 93.923358 -246.361712) (xy 93.923358 -246.360188) (xy 93.924187 -246.334424)
			(xy 93.932849 -246.283613) (xy 93.949289 -246.234761) (xy 93.973111 -246.189051) (xy 94.003737 -246.147592)
			(xy 94.040424 -246.111387) (xy 94.082286 -246.081313) (xy 94.128307 -246.058098) (xy 94.177372 -246.042306)
			(xy 94.228294 -246.034318) (xy 94.254066 -246.033798) (xy 94.280057 -246.034279) (xy 94.331399 -246.042406)
			(xy 94.380838 -246.058465) (xy 94.427155 -246.082061) (xy 94.469211 -246.112613) (xy 94.505969 -246.149368)
			(xy 94.536524 -246.191421) (xy 94.560124 -246.237736) (xy 94.576188 -246.287174) (xy 94.584319 -246.338515)
			(xy 94.584774 -246.364506) (xy 94.584281 -246.390279) (xy 94.584251 -246.390473) (xy 94.863667 -246.390473)
			(xy 94.863667 -246.338539) (xy 94.871792 -246.287244) (xy 94.88784 -246.237851) (xy 94.911418 -246.191577)
			(xy 94.941944 -246.149561) (xy 94.978667 -246.112838) (xy 95.020683 -246.082312) (xy 95.066957 -246.058734)
			(xy 95.11635 -246.042686) (xy 95.167645 -246.034561) (xy 95.219579 -246.034561) (xy 95.270874 -246.042686)
			(xy 95.320267 -246.058734) (xy 95.366541 -246.082312) (xy 95.408557 -246.112838) (xy 95.44528 -246.149561)
			(xy 95.475806 -246.191577) (xy 95.499384 -246.237851) (xy 95.515432 -246.287244) (xy 95.523557 -246.338539)
			(xy 95.524066 -246.364506) (xy 95.523557 -246.390473) (xy 95.803467 -246.390473) (xy 95.803467 -246.338539)
			(xy 95.811592 -246.287244) (xy 95.82764 -246.237851) (xy 95.851218 -246.191577) (xy 95.881744 -246.149561)
			(xy 95.918467 -246.112838) (xy 95.960483 -246.082312) (xy 96.006757 -246.058734) (xy 96.05615 -246.042686)
			(xy 96.107445 -246.034561) (xy 96.159379 -246.034561) (xy 96.210674 -246.042686) (xy 96.260067 -246.058734)
			(xy 96.306341 -246.082312) (xy 96.348357 -246.112838) (xy 96.38508 -246.149561) (xy 96.415606 -246.191577)
			(xy 96.439184 -246.237851) (xy 96.455232 -246.287244) (xy 96.463357 -246.338539) (xy 96.463866 -246.364506)
			(xy 96.463357 -246.390473) (xy 96.743267 -246.390473) (xy 96.743267 -246.338539) (xy 96.751392 -246.287244)
			(xy 96.76744 -246.237851) (xy 96.791018 -246.191577) (xy 96.821544 -246.149561) (xy 96.858267 -246.112838)
			(xy 96.900283 -246.082312) (xy 96.946557 -246.058734) (xy 96.99595 -246.042686) (xy 97.047245 -246.034561)
			(xy 97.099179 -246.034561) (xy 97.150474 -246.042686) (xy 97.199867 -246.058734) (xy 97.246141 -246.082312)
			(xy 97.288157 -246.112838) (xy 97.32488 -246.149561) (xy 97.355406 -246.191577) (xy 97.378984 -246.237851)
			(xy 97.395032 -246.287244) (xy 97.403157 -246.338539) (xy 97.403666 -246.364506) (xy 97.403157 -246.390473)
			(xy 97.683067 -246.390473) (xy 97.683067 -246.338539) (xy 97.691192 -246.287244) (xy 97.70724 -246.237851)
			(xy 97.730818 -246.191577) (xy 97.761344 -246.149561) (xy 97.798067 -246.112838) (xy 97.840083 -246.082312)
			(xy 97.886357 -246.058734) (xy 97.93575 -246.042686) (xy 97.987045 -246.034561) (xy 98.038979 -246.034561)
			(xy 98.090274 -246.042686) (xy 98.139667 -246.058734) (xy 98.185941 -246.082312) (xy 98.227957 -246.112838)
			(xy 98.26468 -246.149561) (xy 98.295206 -246.191577) (xy 98.318784 -246.237851) (xy 98.334832 -246.287244)
			(xy 98.342957 -246.338539) (xy 98.343466 -246.364506) (xy 98.342957 -246.390473) (xy 98.622867 -246.390473)
			(xy 98.622867 -246.338539) (xy 98.630992 -246.287244) (xy 98.64704 -246.237851) (xy 98.670618 -246.191577)
			(xy 98.701144 -246.149561) (xy 98.737867 -246.112838) (xy 98.779883 -246.082312) (xy 98.826157 -246.058734)
			(xy 98.87555 -246.042686) (xy 98.926845 -246.034561) (xy 98.978779 -246.034561) (xy 99.030074 -246.042686)
			(xy 99.079467 -246.058734) (xy 99.125741 -246.082312) (xy 99.167757 -246.112838) (xy 99.20448 -246.149561)
			(xy 99.235006 -246.191577) (xy 99.258584 -246.237851) (xy 99.274632 -246.287244) (xy 99.282757 -246.338539)
			(xy 99.283266 -246.364506) (xy 99.282757 -246.390473) (xy 99.562667 -246.390473) (xy 99.562667 -246.338539)
			(xy 99.570792 -246.287244) (xy 99.58684 -246.237851) (xy 99.610418 -246.191577) (xy 99.640944 -246.149561)
			(xy 99.677667 -246.112838) (xy 99.719683 -246.082312) (xy 99.765957 -246.058734) (xy 99.81535 -246.042686)
			(xy 99.866645 -246.034561) (xy 99.918579 -246.034561) (xy 99.969874 -246.042686) (xy 100.019267 -246.058734)
			(xy 100.065541 -246.082312) (xy 100.107557 -246.112838) (xy 100.14428 -246.149561) (xy 100.174806 -246.191577)
			(xy 100.198384 -246.237851) (xy 100.214432 -246.287244) (xy 100.222557 -246.338539) (xy 100.223066 -246.364506)
			(xy 100.222557 -246.390473) (xy 100.502721 -246.390473) (xy 100.502721 -246.338539) (xy 100.510846 -246.287244)
			(xy 100.526894 -246.237851) (xy 100.550472 -246.191577) (xy 100.580998 -246.149561) (xy 100.617721 -246.112838)
			(xy 100.659737 -246.082312) (xy 100.706011 -246.058734) (xy 100.755404 -246.042686) (xy 100.806699 -246.034561)
			(xy 100.858633 -246.034561) (xy 100.909928 -246.042686) (xy 100.959321 -246.058734) (xy 101.005595 -246.082312)
			(xy 101.047611 -246.112838) (xy 101.084334 -246.149561) (xy 101.11486 -246.191577) (xy 101.138438 -246.237851)
			(xy 101.154486 -246.287244) (xy 101.162611 -246.338539) (xy 101.16312 -246.364506) (xy 101.162611 -246.390473)
			(xy 101.442267 -246.390473) (xy 101.442267 -246.338539) (xy 101.450392 -246.287244) (xy 101.46644 -246.237851)
			(xy 101.490018 -246.191577) (xy 101.520544 -246.149561) (xy 101.557267 -246.112838) (xy 101.599283 -246.082312)
			(xy 101.645557 -246.058734) (xy 101.69495 -246.042686) (xy 101.746245 -246.034561) (xy 101.798179 -246.034561)
			(xy 101.849474 -246.042686) (xy 101.898867 -246.058734) (xy 101.945141 -246.082312) (xy 101.987157 -246.112838)
			(xy 102.02388 -246.149561) (xy 102.054406 -246.191577) (xy 102.077984 -246.237851) (xy 102.094032 -246.287244)
			(xy 102.102157 -246.338539) (xy 102.102666 -246.364506) (xy 102.102157 -246.390473) (xy 102.094032 -246.441768)
			(xy 102.077984 -246.491161) (xy 102.054406 -246.537435) (xy 102.02388 -246.579451) (xy 101.987157 -246.616174)
			(xy 101.945141 -246.6467) (xy 101.898867 -246.670278) (xy 101.852426 -246.685367) (xy 102.485455 -246.685367)
			(xy 102.485455 -246.633433) (xy 102.493579 -246.582139) (xy 102.509627 -246.532747) (xy 102.533204 -246.486474)
			(xy 102.563729 -246.444459) (xy 102.600451 -246.407736) (xy 102.642466 -246.377209) (xy 102.688738 -246.353631)
			(xy 102.738129 -246.337582) (xy 102.789423 -246.329456) (xy 102.81539 -246.328946) (xy 102.815644 -246.328946)
			(xy 102.840171 -246.329385) (xy 102.888684 -246.336653) (xy 102.93559 -246.351009) (xy 102.979862 -246.372136)
			(xy 103.020526 -246.399572) (xy 103.03891 -246.415814) (xy 103.050399 -246.425617) (xy 103.077636 -246.438631)
			(xy 103.10749 -246.443099) (xy 103.137344 -246.438631) (xy 103.164581 -246.425617) (xy 103.17607 -246.415814)
			(xy 103.194469 -246.39955) (xy 103.235175 -246.372082) (xy 103.279499 -246.350944) (xy 103.326465 -246.336603)
			(xy 103.375036 -246.329374) (xy 103.39959 -246.328946) (xy 103.424143 -246.329368) (xy 103.47271 -246.336614)
			(xy 103.519672 -246.350962) (xy 103.563996 -246.372098) (xy 103.604706 -246.399556) (xy 103.62311 -246.415814)
			(xy 103.634599 -246.425617) (xy 103.661836 -246.438631) (xy 103.69169 -246.443099) (xy 103.721544 -246.438631)
			(xy 103.748781 -246.425617) (xy 103.76027 -246.415814) (xy 103.778669 -246.39955) (xy 103.819375 -246.372082)
			(xy 103.863699 -246.350944) (xy 103.910665 -246.336603) (xy 103.959236 -246.329374) (xy 103.98379 -246.328946)
			(xy 104.008343 -246.329368) (xy 104.05691 -246.336614) (xy 104.103872 -246.350962) (xy 104.148196 -246.372098)
			(xy 104.188906 -246.399556) (xy 104.20731 -246.415814) (xy 104.218799 -246.425617) (xy 104.246036 -246.438631)
			(xy 104.27589 -246.443099) (xy 104.305744 -246.438631) (xy 104.332981 -246.425617) (xy 104.34447 -246.415814)
			(xy 104.36285 -246.399566) (xy 104.403509 -246.37212) (xy 104.447781 -246.35099) (xy 104.494691 -246.336642)
			(xy 104.543208 -246.329391) (xy 104.567736 -246.328946) (xy 104.56799 -246.328946) (xy 104.593402 -246.329377)
			(xy 104.643623 -246.337177) (xy 104.692062 -246.352564) (xy 104.737578 -246.375177) (xy 104.779102 -246.404483)
			(xy 104.815656 -246.439794) (xy 104.831388 -246.459756) (xy 104.841111 -246.471705) (xy 104.866155 -246.489618)
			(xy 104.895398 -246.499257) (xy 104.926184 -246.499748) (xy 104.955719 -246.491045) (xy 104.981321 -246.473939)
			(xy 104.991408 -246.462296) (xy 105.007209 -246.443447) (xy 105.043388 -246.410131) (xy 105.084107 -246.382546)
			(xy 105.128465 -246.361302) (xy 105.175482 -246.346869) (xy 105.224119 -246.339565) (xy 105.24871 -246.339106)
			(xy 105.274464 -246.339583) (xy 105.32535 -246.347565) (xy 105.37438 -246.363349) (xy 105.420366 -246.386552)
			(xy 105.462193 -246.416613) (xy 105.480866 -246.434356) (xy 105.490556 -246.443349) (xy 105.513488 -246.456481)
			(xy 105.539027 -246.463276) (xy 105.565453 -246.463276) (xy 105.590992 -246.456481) (xy 105.613924 -246.443349)
			(xy 105.623614 -246.434356) (xy 105.642297 -246.416625) (xy 105.684127 -246.386576) (xy 105.730112 -246.363378)
			(xy 105.779137 -246.347592) (xy 105.830018 -246.3396) (xy 105.85577 -246.339106) (xy 105.881738 -246.339666)
			(xy 105.933034 -246.347787) (xy 105.982429 -246.363832) (xy 106.028705 -246.387407) (xy 106.070723 -246.417932)
			(xy 106.107449 -246.454654) (xy 106.137977 -246.496669) (xy 106.161556 -246.542943) (xy 106.177606 -246.592337)
			(xy 106.185731 -246.643632) (xy 106.185731 -246.685366) (xy 106.402155 -246.685366) (xy 106.402155 -246.633434)
			(xy 106.410279 -246.582142) (xy 106.426325 -246.532752) (xy 106.4499 -246.48648) (xy 106.480423 -246.444466)
			(xy 106.517143 -246.407743) (xy 106.559155 -246.377216) (xy 106.605424 -246.353637) (xy 106.654813 -246.337586)
			(xy 106.706104 -246.329457) (xy 106.73207 -246.328946) (xy 106.759063 -246.329503) (xy 106.812332 -246.338274)
			(xy 106.863466 -246.355588) (xy 106.911106 -246.380984) (xy 106.953983 -246.413786) (xy 106.972862 -246.433086)
			(xy 106.982687 -246.442904) (xy 107.006413 -246.457321) (xy 107.033148 -246.464807) (xy 107.060912 -246.464807)
			(xy 107.087647 -246.457321) (xy 107.111373 -246.442904) (xy 107.121198 -246.433086) (xy 107.140079 -246.413787)
			(xy 107.182955 -246.38098) (xy 107.230594 -246.355579) (xy 107.281727 -246.33826) (xy 107.334996 -246.329483)
			(xy 107.36199 -246.328946) (xy 107.38796 -246.329428) (xy 107.43926 -246.337552) (xy 107.488658 -246.353601)
			(xy 107.534937 -246.37718) (xy 107.576958 -246.407709) (xy 107.613685 -246.444435) (xy 107.644215 -246.486454)
			(xy 107.667795 -246.532733) (xy 107.683846 -246.58213) (xy 107.691971 -246.63343) (xy 107.691971 -246.68537)
			(xy 107.689366 -246.701818) (xy 108.349796 -246.701818) (xy 108.349796 -246.701564) (xy 108.350227 -246.677037)
			(xy 108.357495 -246.628523) (xy 108.371852 -246.581616) (xy 108.392981 -246.537344) (xy 108.42042 -246.496681)
			(xy 108.436664 -246.478298) (xy 108.446451 -246.466796) (xy 108.459468 -246.439563) (xy 108.46394 -246.409713)
			(xy 108.459476 -246.379862) (xy 108.446466 -246.352627) (xy 108.436664 -246.341138) (xy 108.420428 -246.322748)
			(xy 108.392978 -246.282092) (xy 108.371846 -246.237823) (xy 108.357495 -246.190915) (xy 108.350242 -246.142399)
			(xy 108.349796 -246.117872) (xy 108.349796 -246.117618) (xy 108.350372 -246.091654) (xy 108.358492 -246.040364)
			(xy 108.374535 -245.990976) (xy 108.398106 -245.944706) (xy 108.428625 -245.902692) (xy 108.46534 -245.865969)
			(xy 108.507348 -245.835442) (xy 108.553613 -245.811861) (xy 108.602998 -245.795808) (xy 108.654286 -245.787677)
			(xy 108.68025 -245.787164) (xy 108.706119 -245.7876) (xy 108.757226 -245.795648) (xy 108.806452 -245.811572)
			(xy 108.852591 -245.83498) (xy 108.894513 -245.8653) (xy 108.931191 -245.90179) (xy 108.961727 -245.943554)
			(xy 108.985373 -245.989572) (xy 108.99394 -246.013986) (xy 108.999082 -246.027799) (xy 109.015893 -246.051987)
			(xy 109.038906 -246.070373) (xy 109.066208 -246.081429) (xy 109.09553 -246.084235) (xy 109.124433 -246.078558)
			(xy 109.137704 -246.072152) (xy 109.161522 -246.060282) (xy 109.211996 -246.043432) (xy 109.264514 -246.034866)
			(xy 109.29112 -246.034306) (xy 109.317083 -246.034897) (xy 109.368369 -246.043022) (xy 109.417753 -246.059071)
			(xy 109.464019 -246.082647) (xy 109.506027 -246.11317) (xy 109.542743 -246.149888) (xy 109.573264 -246.191898)
			(xy 109.596837 -246.238165) (xy 109.612882 -246.28755) (xy 109.621005 -246.338837) (xy 109.621005 -246.390727)
			(xy 109.900975 -246.390727) (xy 109.900975 -246.338793) (xy 109.9091 -246.287498) (xy 109.925148 -246.238105)
			(xy 109.948726 -246.191831) (xy 109.979252 -246.149815) (xy 110.015975 -246.113092) (xy 110.057991 -246.082566)
			(xy 110.104265 -246.058988) (xy 110.153658 -246.04294) (xy 110.204953 -246.034815) (xy 110.256887 -246.034815)
			(xy 110.308182 -246.04294) (xy 110.357575 -246.058988) (xy 110.403849 -246.082566) (xy 110.445865 -246.113092)
			(xy 110.482588 -246.149815) (xy 110.513114 -246.191831) (xy 110.536692 -246.238105) (xy 110.55274 -246.287498)
			(xy 110.560865 -246.338793) (xy 110.561374 -246.36476) (xy 110.560865 -246.390727) (xy 110.840775 -246.390727)
			(xy 110.840775 -246.338793) (xy 110.8489 -246.287498) (xy 110.864948 -246.238105) (xy 110.888526 -246.191831)
			(xy 110.919052 -246.149815) (xy 110.955775 -246.113092) (xy 110.997791 -246.082566) (xy 111.044065 -246.058988)
			(xy 111.093458 -246.04294) (xy 111.144753 -246.034815) (xy 111.196687 -246.034815) (xy 111.247982 -246.04294)
			(xy 111.297375 -246.058988) (xy 111.343649 -246.082566) (xy 111.385665 -246.113092) (xy 111.422388 -246.149815)
			(xy 111.452914 -246.191831) (xy 111.476492 -246.238105) (xy 111.49254 -246.287498) (xy 111.500665 -246.338793)
			(xy 111.501174 -246.36476) (xy 111.500665 -246.390727) (xy 111.780575 -246.390727) (xy 111.780575 -246.338793)
			(xy 111.7887 -246.287498) (xy 111.804748 -246.238105) (xy 111.828326 -246.191831) (xy 111.858852 -246.149815)
			(xy 111.895575 -246.113092) (xy 111.937591 -246.082566) (xy 111.983865 -246.058988) (xy 112.033258 -246.04294)
			(xy 112.084553 -246.034815) (xy 112.136487 -246.034815) (xy 112.187782 -246.04294) (xy 112.237175 -246.058988)
			(xy 112.283449 -246.082566) (xy 112.325465 -246.113092) (xy 112.362188 -246.149815) (xy 112.392714 -246.191831)
			(xy 112.416292 -246.238105) (xy 112.43234 -246.287498) (xy 112.440465 -246.338793) (xy 112.440974 -246.36476)
			(xy 112.440465 -246.390727) (xy 112.720121 -246.390727) (xy 112.720121 -246.338793) (xy 112.728246 -246.287498)
			(xy 112.744294 -246.238105) (xy 112.767872 -246.191831) (xy 112.798398 -246.149815) (xy 112.835121 -246.113092)
			(xy 112.877137 -246.082566) (xy 112.923411 -246.058988) (xy 112.972804 -246.04294) (xy 113.024099 -246.034815)
			(xy 113.076033 -246.034815) (xy 113.127328 -246.04294) (xy 113.176721 -246.058988) (xy 113.222995 -246.082566)
			(xy 113.265011 -246.113092) (xy 113.301734 -246.149815) (xy 113.33226 -246.191831) (xy 113.355838 -246.238105)
			(xy 113.371886 -246.287498) (xy 113.380011 -246.338793) (xy 113.38052 -246.36476) (xy 113.380011 -246.390727)
			(xy 113.660175 -246.390727) (xy 113.660175 -246.338793) (xy 113.6683 -246.287498) (xy 113.684348 -246.238105)
			(xy 113.707926 -246.191831) (xy 113.738452 -246.149815) (xy 113.775175 -246.113092) (xy 113.817191 -246.082566)
			(xy 113.863465 -246.058988) (xy 113.912858 -246.04294) (xy 113.964153 -246.034815) (xy 114.016087 -246.034815)
			(xy 114.067382 -246.04294) (xy 114.116775 -246.058988) (xy 114.163049 -246.082566) (xy 114.205065 -246.113092)
			(xy 114.241788 -246.149815) (xy 114.272314 -246.191831) (xy 114.295892 -246.238105) (xy 114.31194 -246.287498)
			(xy 114.320065 -246.338793) (xy 114.320574 -246.36476) (xy 114.320065 -246.390727) (xy 114.31194 -246.442022)
			(xy 114.295892 -246.491415) (xy 114.272314 -246.537689) (xy 114.241788 -246.579705) (xy 114.205065 -246.616428)
			(xy 114.163049 -246.646954) (xy 114.116775 -246.670532) (xy 114.067382 -246.68658) (xy 114.016087 -246.694705)
			(xy 113.964153 -246.694705) (xy 113.912858 -246.68658) (xy 113.863465 -246.670532) (xy 113.817191 -246.646954)
			(xy 113.775175 -246.616428) (xy 113.738452 -246.579705) (xy 113.707926 -246.537689) (xy 113.684348 -246.491415)
			(xy 113.6683 -246.442022) (xy 113.660175 -246.390727) (xy 113.380011 -246.390727) (xy 113.371886 -246.442022)
			(xy 113.355838 -246.491415) (xy 113.33226 -246.537689) (xy 113.301734 -246.579705) (xy 113.265011 -246.616428)
			(xy 113.222995 -246.646954) (xy 113.176721 -246.670532) (xy 113.127328 -246.68658) (xy 113.076033 -246.694705)
			(xy 113.024099 -246.694705) (xy 112.972804 -246.68658) (xy 112.923411 -246.670532) (xy 112.877137 -246.646954)
			(xy 112.835121 -246.616428) (xy 112.798398 -246.579705) (xy 112.767872 -246.537689) (xy 112.744294 -246.491415)
			(xy 112.728246 -246.442022) (xy 112.720121 -246.390727) (xy 112.440465 -246.390727) (xy 112.43234 -246.442022)
			(xy 112.416292 -246.491415) (xy 112.392714 -246.537689) (xy 112.362188 -246.579705) (xy 112.325465 -246.616428)
			(xy 112.283449 -246.646954) (xy 112.237175 -246.670532) (xy 112.187782 -246.68658) (xy 112.136487 -246.694705)
			(xy 112.084553 -246.694705) (xy 112.033258 -246.68658) (xy 111.983865 -246.670532) (xy 111.937591 -246.646954)
			(xy 111.895575 -246.616428) (xy 111.858852 -246.579705) (xy 111.828326 -246.537689) (xy 111.804748 -246.491415)
			(xy 111.7887 -246.442022) (xy 111.780575 -246.390727) (xy 111.500665 -246.390727) (xy 111.49254 -246.442022)
			(xy 111.476492 -246.491415) (xy 111.452914 -246.537689) (xy 111.422388 -246.579705) (xy 111.385665 -246.616428)
			(xy 111.343649 -246.646954) (xy 111.297375 -246.670532) (xy 111.247982 -246.68658) (xy 111.196687 -246.694705)
			(xy 111.144753 -246.694705) (xy 111.093458 -246.68658) (xy 111.044065 -246.670532) (xy 110.997791 -246.646954)
			(xy 110.955775 -246.616428) (xy 110.919052 -246.579705) (xy 110.888526 -246.537689) (xy 110.864948 -246.491415)
			(xy 110.8489 -246.442022) (xy 110.840775 -246.390727) (xy 110.560865 -246.390727) (xy 110.55274 -246.442022)
			(xy 110.536692 -246.491415) (xy 110.513114 -246.537689) (xy 110.482588 -246.579705) (xy 110.445865 -246.616428)
			(xy 110.403849 -246.646954) (xy 110.357575 -246.670532) (xy 110.308182 -246.68658) (xy 110.256887 -246.694705)
			(xy 110.204953 -246.694705) (xy 110.153658 -246.68658) (xy 110.104265 -246.670532) (xy 110.057991 -246.646954)
			(xy 110.015975 -246.616428) (xy 109.979252 -246.579705) (xy 109.948726 -246.537689) (xy 109.925148 -246.491415)
			(xy 109.9091 -246.442022) (xy 109.900975 -246.390727) (xy 109.621005 -246.390727) (xy 109.621005 -246.390763)
			(xy 109.612882 -246.44205) (xy 109.596837 -246.491435) (xy 109.573264 -246.537702) (xy 109.542743 -246.579712)
			(xy 109.506027 -246.61643) (xy 109.464019 -246.646953) (xy 109.417753 -246.670529) (xy 109.368369 -246.686578)
			(xy 109.317083 -246.694703) (xy 109.29112 -246.695214) (xy 109.290612 -246.695214) (xy 109.266697 -246.69478)
			(xy 109.219372 -246.687853) (xy 109.173541 -246.674171) (xy 109.151674 -246.66448) (xy 109.139132 -246.659062)
			(xy 109.112195 -246.654533) (xy 109.085023 -246.657314) (xy 109.059562 -246.667204) (xy 109.037637 -246.683495)
			(xy 109.020821 -246.70502) (xy 109.010319 -246.730235) (xy 109.008164 -246.743728) (xy 109.004216 -246.76996)
			(xy 108.98917 -246.820824) (xy 108.966192 -246.868632) (xy 108.935873 -246.912156) (xy 108.898992 -246.950278)
			(xy 108.856495 -246.982019) (xy 108.809473 -247.006565) (xy 108.759134 -247.023285) (xy 108.706771 -247.031749)
			(xy 108.68025 -247.032272) (xy 108.654282 -247.031791) (xy 108.602987 -247.02366) (xy 108.553596 -247.007605)
			(xy 108.507323 -246.984023) (xy 108.465308 -246.953493) (xy 108.428586 -246.916767) (xy 108.39806 -246.87475)
			(xy 108.374482 -246.828475) (xy 108.358433 -246.779082) (xy 108.350307 -246.727786) (xy 108.349796 -246.701818)
			(xy 107.689366 -246.701818) (xy 107.683846 -246.73667) (xy 107.667795 -246.786067) (xy 107.644215 -246.832346)
			(xy 107.613685 -246.874365) (xy 107.576958 -246.911091) (xy 107.534937 -246.94162) (xy 107.488658 -246.965199)
			(xy 107.43926 -246.981248) (xy 107.38796 -246.989372) (xy 107.36199 -246.989854) (xy 107.334996 -246.989323)
			(xy 107.281726 -246.980546) (xy 107.230591 -246.963226) (xy 107.182952 -246.937824) (xy 107.140075 -246.905017)
			(xy 107.121198 -246.885714) (xy 107.111373 -246.875896) (xy 107.087647 -246.861479) (xy 107.060912 -246.853993)
			(xy 107.033148 -246.853993) (xy 107.006413 -246.861479) (xy 106.982687 -246.875896) (xy 106.972862 -246.885714)
			(xy 106.953999 -246.905032) (xy 106.911119 -246.937837) (xy 106.863475 -246.963234) (xy 106.812337 -246.980549)
			(xy 106.759065 -246.98932) (xy 106.73207 -246.989854) (xy 106.706104 -246.989343) (xy 106.654813 -246.981214)
			(xy 106.605424 -246.965163) (xy 106.559155 -246.941584) (xy 106.517143 -246.911057) (xy 106.480423 -246.874334)
			(xy 106.4499 -246.83232) (xy 106.426325 -246.786048) (xy 106.410279 -246.736658) (xy 106.402155 -246.685366)
			(xy 106.185731 -246.685366) (xy 106.185731 -246.695568) (xy 106.177606 -246.746863) (xy 106.161556 -246.796257)
			(xy 106.137977 -246.842531) (xy 106.107449 -246.884546) (xy 106.070723 -246.921268) (xy 106.028705 -246.951793)
			(xy 105.982429 -246.975368) (xy 105.933034 -246.991413) (xy 105.881738 -246.999534) (xy 105.85577 -247.000014)
			(xy 105.830016 -246.999544) (xy 105.77913 -246.991559) (xy 105.7301 -246.975774) (xy 105.684114 -246.952569)
			(xy 105.642287 -246.922507) (xy 105.623614 -246.904764) (xy 105.613924 -246.895771) (xy 105.590992 -246.882639)
			(xy 105.565453 -246.875844) (xy 105.539027 -246.875844) (xy 105.513488 -246.882639) (xy 105.490556 -246.895771)
			(xy 105.480866 -246.904764) (xy 105.462195 -246.922508) (xy 105.420361 -246.952554) (xy 105.374374 -246.975749)
			(xy 105.325346 -246.991532) (xy 105.274463 -246.999521) (xy 105.24871 -247.000014) (xy 105.2233 -246.99956)
			(xy 105.17308 -246.991761) (xy 105.124643 -246.976377) (xy 105.079127 -246.953769) (xy 105.037603 -246.924468)
			(xy 105.001046 -246.889163) (xy 104.985312 -246.869204) (xy 104.975588 -246.857258) (xy 104.950542 -246.839352)
			(xy 104.921301 -246.829717) (xy 104.890517 -246.829226) (xy 104.860984 -246.837926) (xy 104.835381 -246.855025)
			(xy 104.825292 -246.866664) (xy 104.809481 -246.885505) (xy 104.773305 -246.918823) (xy 104.732589 -246.94641)
			(xy 104.688233 -246.967656) (xy 104.641217 -246.98209) (xy 104.592581 -246.989395) (xy 104.56799 -246.989854)
			(xy 104.567736 -246.989854) (xy 104.543211 -246.989367) (xy 104.4947 -246.98211) (xy 104.447794 -246.967766)
			(xy 104.403522 -246.94665) (xy 104.362855 -246.919224) (xy 104.34447 -246.902986) (xy 104.332981 -246.893183)
			(xy 104.305744 -246.880169) (xy 104.27589 -246.875701) (xy 104.246036 -246.880169) (xy 104.218799 -246.893183)
			(xy 104.20731 -246.902986) (xy 104.188919 -246.91926) (xy 104.148211 -246.946726) (xy 104.103884 -246.967862)
			(xy 104.056917 -246.982201) (xy 104.008344 -246.989427) (xy 103.98379 -246.989854) (xy 103.959239 -246.989384)
			(xy 103.910674 -246.982149) (xy 103.863713 -246.967812) (xy 103.819388 -246.946687) (xy 103.778675 -246.919239)
			(xy 103.76027 -246.902986) (xy 103.748781 -246.893183) (xy 103.721544 -246.880169) (xy 103.69169 -246.875701)
			(xy 103.661836 -246.880169) (xy 103.634599 -246.893183) (xy 103.62311 -246.902986) (xy 103.604719 -246.91926)
			(xy 103.564011 -246.946726) (xy 103.519684 -246.967862) (xy 103.472717 -246.982201) (xy 103.424144 -246.989427)
			(xy 103.39959 -246.989854) (xy 103.375039 -246.989384) (xy 103.326474 -246.982149) (xy 103.279513 -246.967812)
			(xy 103.235188 -246.946687) (xy 103.194475 -246.919239) (xy 103.17607 -246.902986) (xy 103.164581 -246.893183)
			(xy 103.137344 -246.880169) (xy 103.10749 -246.875701) (xy 103.077636 -246.880169) (xy 103.050399 -246.893183)
			(xy 103.03891 -246.902986) (xy 103.020538 -246.919244) (xy 102.979877 -246.946688) (xy 102.935603 -246.967816)
			(xy 102.888691 -246.982162) (xy 102.840172 -246.98941) (xy 102.815644 -246.989854) (xy 102.81539 -246.989854)
			(xy 102.789423 -246.989344) (xy 102.738129 -246.981218) (xy 102.688738 -246.965169) (xy 102.642466 -246.941591)
			(xy 102.600451 -246.911064) (xy 102.563729 -246.874341) (xy 102.533204 -246.832326) (xy 102.509627 -246.786053)
			(xy 102.493579 -246.736661) (xy 102.485455 -246.685367) (xy 101.852426 -246.685367) (xy 101.849474 -246.686326)
			(xy 101.798179 -246.694451) (xy 101.746245 -246.694451) (xy 101.69495 -246.686326) (xy 101.645557 -246.670278)
			(xy 101.599283 -246.6467) (xy 101.557267 -246.616174) (xy 101.520544 -246.579451) (xy 101.490018 -246.537435)
			(xy 101.46644 -246.491161) (xy 101.450392 -246.441768) (xy 101.442267 -246.390473) (xy 101.162611 -246.390473)
			(xy 101.154486 -246.441768) (xy 101.138438 -246.491161) (xy 101.11486 -246.537435) (xy 101.084334 -246.579451)
			(xy 101.047611 -246.616174) (xy 101.005595 -246.6467) (xy 100.959321 -246.670278) (xy 100.909928 -246.686326)
			(xy 100.858633 -246.694451) (xy 100.806699 -246.694451) (xy 100.755404 -246.686326) (xy 100.706011 -246.670278)
			(xy 100.659737 -246.6467) (xy 100.617721 -246.616174) (xy 100.580998 -246.579451) (xy 100.550472 -246.537435)
			(xy 100.526894 -246.491161) (xy 100.510846 -246.441768) (xy 100.502721 -246.390473) (xy 100.222557 -246.390473)
			(xy 100.214432 -246.441768) (xy 100.198384 -246.491161) (xy 100.174806 -246.537435) (xy 100.14428 -246.579451)
			(xy 100.107557 -246.616174) (xy 100.065541 -246.6467) (xy 100.019267 -246.670278) (xy 99.969874 -246.686326)
			(xy 99.918579 -246.694451) (xy 99.866645 -246.694451) (xy 99.81535 -246.686326) (xy 99.765957 -246.670278)
			(xy 99.719683 -246.6467) (xy 99.677667 -246.616174) (xy 99.640944 -246.579451) (xy 99.610418 -246.537435)
			(xy 99.58684 -246.491161) (xy 99.570792 -246.441768) (xy 99.562667 -246.390473) (xy 99.282757 -246.390473)
			(xy 99.274632 -246.441768) (xy 99.258584 -246.491161) (xy 99.235006 -246.537435) (xy 99.20448 -246.579451)
			(xy 99.167757 -246.616174) (xy 99.125741 -246.6467) (xy 99.079467 -246.670278) (xy 99.030074 -246.686326)
			(xy 98.978779 -246.694451) (xy 98.926845 -246.694451) (xy 98.87555 -246.686326) (xy 98.826157 -246.670278)
			(xy 98.779883 -246.6467) (xy 98.737867 -246.616174) (xy 98.701144 -246.579451) (xy 98.670618 -246.537435)
			(xy 98.64704 -246.491161) (xy 98.630992 -246.441768) (xy 98.622867 -246.390473) (xy 98.342957 -246.390473)
			(xy 98.334832 -246.441768) (xy 98.318784 -246.491161) (xy 98.295206 -246.537435) (xy 98.26468 -246.579451)
			(xy 98.227957 -246.616174) (xy 98.185941 -246.6467) (xy 98.139667 -246.670278) (xy 98.090274 -246.686326)
			(xy 98.038979 -246.694451) (xy 97.987045 -246.694451) (xy 97.93575 -246.686326) (xy 97.886357 -246.670278)
			(xy 97.840083 -246.6467) (xy 97.798067 -246.616174) (xy 97.761344 -246.579451) (xy 97.730818 -246.537435)
			(xy 97.70724 -246.491161) (xy 97.691192 -246.441768) (xy 97.683067 -246.390473) (xy 97.403157 -246.390473)
			(xy 97.395032 -246.441768) (xy 97.378984 -246.491161) (xy 97.355406 -246.537435) (xy 97.32488 -246.579451)
			(xy 97.288157 -246.616174) (xy 97.246141 -246.6467) (xy 97.199867 -246.670278) (xy 97.150474 -246.686326)
			(xy 97.099179 -246.694451) (xy 97.047245 -246.694451) (xy 96.99595 -246.686326) (xy 96.946557 -246.670278)
			(xy 96.900283 -246.6467) (xy 96.858267 -246.616174) (xy 96.821544 -246.579451) (xy 96.791018 -246.537435)
			(xy 96.76744 -246.491161) (xy 96.751392 -246.441768) (xy 96.743267 -246.390473) (xy 96.463357 -246.390473)
			(xy 96.455232 -246.441768) (xy 96.439184 -246.491161) (xy 96.415606 -246.537435) (xy 96.38508 -246.579451)
			(xy 96.348357 -246.616174) (xy 96.306341 -246.6467) (xy 96.260067 -246.670278) (xy 96.210674 -246.686326)
			(xy 96.159379 -246.694451) (xy 96.107445 -246.694451) (xy 96.05615 -246.686326) (xy 96.006757 -246.670278)
			(xy 95.960483 -246.6467) (xy 95.918467 -246.616174) (xy 95.881744 -246.579451) (xy 95.851218 -246.537435)
			(xy 95.82764 -246.491161) (xy 95.811592 -246.441768) (xy 95.803467 -246.390473) (xy 95.523557 -246.390473)
			(xy 95.515432 -246.441768) (xy 95.499384 -246.491161) (xy 95.475806 -246.537435) (xy 95.44528 -246.579451)
			(xy 95.408557 -246.616174) (xy 95.366541 -246.6467) (xy 95.320267 -246.670278) (xy 95.270874 -246.686326)
			(xy 95.219579 -246.694451) (xy 95.167645 -246.694451) (xy 95.11635 -246.686326) (xy 95.066957 -246.670278)
			(xy 95.020683 -246.6467) (xy 94.978667 -246.616174) (xy 94.941944 -246.579451) (xy 94.911418 -246.537435)
			(xy 94.88784 -246.491161) (xy 94.871792 -246.441768) (xy 94.863667 -246.390473) (xy 94.584251 -246.390473)
			(xy 94.576284 -246.441201) (xy 94.560485 -246.490267) (xy 94.537265 -246.536287) (xy 94.507188 -246.578149)
			(xy 94.470981 -246.614838) (xy 94.429522 -246.645467) (xy 94.383813 -246.669293) (xy 94.334961 -246.68574)
			(xy 94.284149 -246.694411) (xy 94.258384 -246.695214) (xy 94.25686 -246.695214) (xy 94.247237 -246.695997)
			(xy 94.229612 -246.703837) (xy 94.216179 -246.717681) (xy 94.212156 -246.726456) (xy 94.210124 -246.731282)
			(xy 94.176088 -246.815356) (xy 94.17351 -246.824253) (xy 94.17441 -246.842741) (xy 94.181954 -246.859644)
			(xy 94.18828 -246.86641) (xy 94.3102 -246.98833) (xy 94.318126 -246.9955) (xy 94.338121 -247.002992)
			(xy 94.348808 -247.002808) (xy 94.3864 -247.000268) (xy 94.424754 -246.997728) (xy 94.434299 -246.996564)
			(xy 94.451527 -246.988063) (xy 94.458282 -246.981218) (xy 94.460822 -246.977916) (xy 94.476589 -246.95804)
			(xy 94.513146 -246.922866) (xy 94.554641 -246.893681) (xy 94.600103 -246.871166) (xy 94.648467 -246.85585)
			(xy 94.698601 -246.848091) (xy 94.723966 -246.847614) (xy 94.749956 -246.848095) (xy 94.801298 -246.856222)
			(xy 94.850735 -246.872281) (xy 94.897052 -246.895878) (xy 94.939106 -246.92643) (xy 94.975863 -246.963185)
			(xy 95.006416 -247.005238) (xy 95.030014 -247.051553) (xy 95.046075 -247.100991) (xy 95.054204 -247.152332)
			(xy 95.054674 -247.178322) (xy 95.054219 -247.203692) (xy 95.054127 -247.204289) (xy 95.333821 -247.204289)
			(xy 95.333821 -247.152355) (xy 95.341946 -247.10106) (xy 95.357994 -247.051667) (xy 95.381572 -247.005393)
			(xy 95.412098 -246.963377) (xy 95.448821 -246.926654) (xy 95.490837 -246.896128) (xy 95.537111 -246.87255)
			(xy 95.586504 -246.856502) (xy 95.637799 -246.848377) (xy 95.689733 -246.848377) (xy 95.741028 -246.856502)
			(xy 95.790421 -246.87255) (xy 95.836695 -246.896128) (xy 95.878711 -246.926654) (xy 95.915434 -246.963377)
			(xy 95.94596 -247.005393) (xy 95.969538 -247.051667) (xy 95.985586 -247.10106) (xy 95.993711 -247.152355)
			(xy 95.99422 -247.178322) (xy 95.993711 -247.204289) (xy 96.273367 -247.204289) (xy 96.273367 -247.152355)
			(xy 96.281492 -247.10106) (xy 96.29754 -247.051667) (xy 96.321118 -247.005393) (xy 96.351644 -246.963377)
			(xy 96.388367 -246.926654) (xy 96.430383 -246.896128) (xy 96.476657 -246.87255) (xy 96.52605 -246.856502)
			(xy 96.577345 -246.848377) (xy 96.629279 -246.848377) (xy 96.680574 -246.856502) (xy 96.729967 -246.87255)
			(xy 96.776241 -246.896128) (xy 96.818257 -246.926654) (xy 96.85498 -246.963377) (xy 96.885506 -247.005393)
			(xy 96.909084 -247.051667) (xy 96.925132 -247.10106) (xy 96.933257 -247.152355) (xy 96.933766 -247.178322)
			(xy 96.933257 -247.204289) (xy 97.213421 -247.204289) (xy 97.213421 -247.152355) (xy 97.221546 -247.10106)
			(xy 97.237594 -247.051667) (xy 97.261172 -247.005393) (xy 97.291698 -246.963377) (xy 97.328421 -246.926654)
			(xy 97.370437 -246.896128) (xy 97.416711 -246.87255) (xy 97.466104 -246.856502) (xy 97.517399 -246.848377)
			(xy 97.569333 -246.848377) (xy 97.620628 -246.856502) (xy 97.670021 -246.87255) (xy 97.716295 -246.896128)
			(xy 97.758311 -246.926654) (xy 97.795034 -246.963377) (xy 97.82556 -247.005393) (xy 97.849138 -247.051667)
			(xy 97.865186 -247.10106) (xy 97.873311 -247.152355) (xy 97.87382 -247.178322) (xy 97.873311 -247.204289)
			(xy 98.152967 -247.204289) (xy 98.152967 -247.152355) (xy 98.161092 -247.10106) (xy 98.17714 -247.051667)
			(xy 98.200718 -247.005393) (xy 98.231244 -246.963377) (xy 98.267967 -246.926654) (xy 98.309983 -246.896128)
			(xy 98.356257 -246.87255) (xy 98.40565 -246.856502) (xy 98.456945 -246.848377) (xy 98.508879 -246.848377)
			(xy 98.560174 -246.856502) (xy 98.609567 -246.87255) (xy 98.655841 -246.896128) (xy 98.697857 -246.926654)
			(xy 98.73458 -246.963377) (xy 98.765106 -247.005393) (xy 98.788684 -247.051667) (xy 98.804732 -247.10106)
			(xy 98.812857 -247.152355) (xy 98.813366 -247.178322) (xy 98.812857 -247.204289) (xy 99.093021 -247.204289)
			(xy 99.093021 -247.152355) (xy 99.101146 -247.10106) (xy 99.117194 -247.051667) (xy 99.140772 -247.005393)
			(xy 99.171298 -246.963377) (xy 99.208021 -246.926654) (xy 99.250037 -246.896128) (xy 99.296311 -246.87255)
			(xy 99.345704 -246.856502) (xy 99.396999 -246.848377) (xy 99.448933 -246.848377) (xy 99.500228 -246.856502)
			(xy 99.549621 -246.87255) (xy 99.595895 -246.896128) (xy 99.637911 -246.926654) (xy 99.674634 -246.963377)
			(xy 99.70516 -247.005393) (xy 99.728738 -247.051667) (xy 99.744786 -247.10106) (xy 99.752911 -247.152355)
			(xy 99.75342 -247.178322) (xy 99.752911 -247.204289) (xy 100.032821 -247.204289) (xy 100.032821 -247.152355)
			(xy 100.040946 -247.10106) (xy 100.056994 -247.051667) (xy 100.080572 -247.005393) (xy 100.111098 -246.963377)
			(xy 100.147821 -246.926654) (xy 100.189837 -246.896128) (xy 100.236111 -246.87255) (xy 100.285504 -246.856502)
			(xy 100.336799 -246.848377) (xy 100.388733 -246.848377) (xy 100.440028 -246.856502) (xy 100.489421 -246.87255)
			(xy 100.535695 -246.896128) (xy 100.577711 -246.926654) (xy 100.614434 -246.963377) (xy 100.64496 -247.005393)
			(xy 100.668538 -247.051667) (xy 100.684586 -247.10106) (xy 100.692711 -247.152355) (xy 100.69322 -247.178322)
			(xy 100.692711 -247.204289) (xy 100.972621 -247.204289) (xy 100.972621 -247.152355) (xy 100.980746 -247.10106)
			(xy 100.996794 -247.051667) (xy 101.020372 -247.005393) (xy 101.050898 -246.963377) (xy 101.087621 -246.926654)
			(xy 101.129637 -246.896128) (xy 101.175911 -246.87255) (xy 101.225304 -246.856502) (xy 101.276599 -246.848377)
			(xy 101.328533 -246.848377) (xy 101.379828 -246.856502) (xy 101.429221 -246.87255) (xy 101.475495 -246.896128)
			(xy 101.517511 -246.926654) (xy 101.554234 -246.963377) (xy 101.58476 -247.005393) (xy 101.608338 -247.051667)
			(xy 101.624386 -247.10106) (xy 101.632511 -247.152355) (xy 101.63302 -247.178322) (xy 101.632511 -247.204289)
			(xy 101.912421 -247.204289) (xy 101.912421 -247.152355) (xy 101.920546 -247.10106) (xy 101.936594 -247.051667)
			(xy 101.960172 -247.005393) (xy 101.990698 -246.963377) (xy 102.027421 -246.926654) (xy 102.069437 -246.896128)
			(xy 102.115711 -246.87255) (xy 102.165104 -246.856502) (xy 102.216399 -246.848377) (xy 102.268333 -246.848377)
			(xy 102.319628 -246.856502) (xy 102.369021 -246.87255) (xy 102.415295 -246.896128) (xy 102.457311 -246.926654)
			(xy 102.494034 -246.963377) (xy 102.52456 -247.005393) (xy 102.548138 -247.051667) (xy 102.564186 -247.10106)
			(xy 102.572311 -247.152355) (xy 102.57282 -247.178322) (xy 102.572311 -247.204289) (xy 102.572271 -247.204543)
			(xy 109.430821 -247.204543) (xy 109.430821 -247.152609) (xy 109.438946 -247.101314) (xy 109.454994 -247.051921)
			(xy 109.478572 -247.005647) (xy 109.509098 -246.963631) (xy 109.545821 -246.926908) (xy 109.587837 -246.896382)
			(xy 109.634111 -246.872804) (xy 109.683504 -246.856756) (xy 109.734799 -246.848631) (xy 109.786733 -246.848631)
			(xy 109.838028 -246.856756) (xy 109.887421 -246.872804) (xy 109.933695 -246.896382) (xy 109.975711 -246.926908)
			(xy 110.012434 -246.963631) (xy 110.04296 -247.005647) (xy 110.066538 -247.051921) (xy 110.082586 -247.101314)
			(xy 110.090711 -247.152609) (xy 110.09122 -247.178576) (xy 110.090711 -247.204543) (xy 110.370875 -247.204543)
			(xy 110.370875 -247.152609) (xy 110.379 -247.101314) (xy 110.395048 -247.051921) (xy 110.418626 -247.005647)
			(xy 110.449152 -246.963631) (xy 110.485875 -246.926908) (xy 110.527891 -246.896382) (xy 110.574165 -246.872804)
			(xy 110.623558 -246.856756) (xy 110.674853 -246.848631) (xy 110.726787 -246.848631) (xy 110.778082 -246.856756)
			(xy 110.827475 -246.872804) (xy 110.873749 -246.896382) (xy 110.915765 -246.926908) (xy 110.952488 -246.963631)
			(xy 110.983014 -247.005647) (xy 111.006592 -247.051921) (xy 111.02264 -247.101314) (xy 111.030765 -247.152609)
			(xy 111.031274 -247.178576) (xy 111.030765 -247.204543) (xy 111.310421 -247.204543) (xy 111.310421 -247.152609)
			(xy 111.318546 -247.101314) (xy 111.334594 -247.051921) (xy 111.358172 -247.005647) (xy 111.388698 -246.963631)
			(xy 111.425421 -246.926908) (xy 111.467437 -246.896382) (xy 111.513711 -246.872804) (xy 111.563104 -246.856756)
			(xy 111.614399 -246.848631) (xy 111.666333 -246.848631) (xy 111.717628 -246.856756) (xy 111.767021 -246.872804)
			(xy 111.813295 -246.896382) (xy 111.855311 -246.926908) (xy 111.892034 -246.963631) (xy 111.92256 -247.005647)
			(xy 111.946138 -247.051921) (xy 111.962186 -247.101314) (xy 111.970311 -247.152609) (xy 111.97082 -247.178576)
			(xy 111.970311 -247.204543) (xy 112.250221 -247.204543) (xy 112.250221 -247.152609) (xy 112.258346 -247.101314)
			(xy 112.274394 -247.051921) (xy 112.297972 -247.005647) (xy 112.328498 -246.963631) (xy 112.365221 -246.926908)
			(xy 112.407237 -246.896382) (xy 112.453511 -246.872804) (xy 112.502904 -246.856756) (xy 112.554199 -246.848631)
			(xy 112.606133 -246.848631) (xy 112.657428 -246.856756) (xy 112.706821 -246.872804) (xy 112.753095 -246.896382)
			(xy 112.795111 -246.926908) (xy 112.831834 -246.963631) (xy 112.86236 -247.005647) (xy 112.885938 -247.051921)
			(xy 112.901986 -247.101314) (xy 112.910111 -247.152609) (xy 112.91062 -247.178576) (xy 112.910111 -247.204543)
			(xy 113.190275 -247.204543) (xy 113.190275 -247.152609) (xy 113.1984 -247.101314) (xy 113.214448 -247.051921)
			(xy 113.238026 -247.005647) (xy 113.268552 -246.963631) (xy 113.305275 -246.926908) (xy 113.347291 -246.896382)
			(xy 113.393565 -246.872804) (xy 113.442958 -246.856756) (xy 113.494253 -246.848631) (xy 113.546187 -246.848631)
			(xy 113.597482 -246.856756) (xy 113.646875 -246.872804) (xy 113.693149 -246.896382) (xy 113.735165 -246.926908)
			(xy 113.771888 -246.963631) (xy 113.802414 -247.005647) (xy 113.825992 -247.051921) (xy 113.84204 -247.101314)
			(xy 113.850165 -247.152609) (xy 113.850674 -247.178576) (xy 113.850165 -247.204543) (xy 113.85016 -247.204572)
			(xy 114.130005 -247.204572) (xy 114.130005 -247.152628) (xy 114.138131 -247.101323) (xy 114.154183 -247.051921)
			(xy 114.177767 -247.005639) (xy 114.2083 -246.963616) (xy 114.245031 -246.926887) (xy 114.287056 -246.896356)
			(xy 114.33334 -246.872776) (xy 114.382743 -246.856727) (xy 114.434048 -246.848603) (xy 114.46002 -246.848122)
			(xy 114.485824 -246.848632) (xy 114.536805 -246.856645) (xy 114.585921 -246.872487) (xy 114.631976 -246.895775)
			(xy 114.673849 -246.925941) (xy 114.710522 -246.962251) (xy 114.726212 -246.982742) (xy 114.734757 -246.993665)
			(xy 114.756551 -247.010799) (xy 114.782153 -247.02143) (xy 114.809673 -247.024774) (xy 114.837077 -247.020583)
			(xy 114.86234 -247.009166) (xy 114.883595 -246.991369) (xy 114.89182 -246.980202) (xy 114.898486 -246.970619)
			(xy 114.912977 -246.952313) (xy 114.920776 -246.943626) (xy 114.930535 -246.932102) (xy 114.943553 -246.904877)
			(xy 114.94803 -246.875034) (xy 114.943573 -246.845188) (xy 114.930573 -246.817955) (xy 114.920776 -246.806466)
			(xy 114.904538 -246.788077) (xy 114.877093 -246.74742) (xy 114.855962 -246.70315) (xy 114.841611 -246.656242)
			(xy 114.834356 -246.607727) (xy 114.833908 -246.5832) (xy 114.833908 -246.582946) (xy 114.834417 -246.556979)
			(xy 114.842542 -246.505684) (xy 114.85859 -246.456291) (xy 114.882168 -246.410017) (xy 114.912694 -246.368001)
			(xy 114.949417 -246.331278) (xy 114.991433 -246.300752) (xy 115.037707 -246.277174) (xy 115.0871 -246.261126)
			(xy 115.138395 -246.253001) (xy 115.190329 -246.253001) (xy 115.241624 -246.261126) (xy 115.291017 -246.277174)
			(xy 115.337291 -246.300752) (xy 115.379307 -246.331278) (xy 115.41603 -246.368001) (xy 115.446556 -246.410017)
			(xy 115.470134 -246.456291) (xy 115.486182 -246.505684) (xy 115.494307 -246.556979) (xy 115.494816 -246.582946)
			(xy 115.494816 -246.5832) (xy 115.49436 -246.607726) (xy 115.487098 -246.656239) (xy 115.478186 -246.685367)
			(xy 116.104671 -246.685367) (xy 116.104671 -246.633433) (xy 116.112796 -246.582138) (xy 116.128844 -246.532745)
			(xy 116.152422 -246.486471) (xy 116.182948 -246.444455) (xy 116.219671 -246.407732) (xy 116.261687 -246.377206)
			(xy 116.307961 -246.353628) (xy 116.357354 -246.33758) (xy 116.408649 -246.329455) (xy 116.460583 -246.329455)
			(xy 116.511878 -246.33758) (xy 116.561271 -246.353628) (xy 116.607545 -246.377206) (xy 116.649561 -246.407732)
			(xy 116.686284 -246.444455) (xy 116.71681 -246.486471) (xy 116.740388 -246.532745) (xy 116.756436 -246.582138)
			(xy 116.764561 -246.633433) (xy 116.76507 -246.6594) (xy 116.764561 -246.685367) (xy 116.762945 -246.69557)
			(xy 116.871715 -246.69557) (xy 116.871715 -246.64363) (xy 116.879841 -246.592329) (xy 116.895891 -246.542931)
			(xy 116.919471 -246.496652) (xy 116.950001 -246.454631) (xy 116.986728 -246.417903) (xy 117.028748 -246.387373)
			(xy 117.075027 -246.363792) (xy 117.124425 -246.347741) (xy 117.175726 -246.339616) (xy 117.201696 -246.339106)
			(xy 117.228277 -246.339636) (xy 117.280755 -246.348141) (xy 117.331196 -246.364931) (xy 117.378301 -246.389574)
			(xy 117.420857 -246.421436) (xy 117.439694 -246.440198) (xy 117.449465 -246.449723) (xy 117.472907 -246.463667)
			(xy 117.499208 -246.470897) (xy 117.526484 -246.470897) (xy 117.552785 -246.463667) (xy 117.576227 -246.449723)
			(xy 117.585998 -246.440198) (xy 117.604838 -246.42144) (xy 117.647394 -246.389577) (xy 117.694498 -246.364933)
			(xy 117.744938 -246.348142) (xy 117.797415 -246.339637) (xy 117.823996 -246.339106) (xy 117.84932 -246.339548)
			(xy 117.899376 -246.347272) (xy 117.947668 -246.36254) (xy 117.993067 -246.384994) (xy 118.03451 -246.414109)
			(xy 118.053104 -246.431308) (xy 118.062961 -246.440213) (xy 118.086172 -246.453108) (xy 118.111927 -246.459564)
			(xy 118.138476 -246.459143) (xy 118.164014 -246.451873) (xy 118.186804 -246.438248) (xy 118.19636 -246.429022)
			(xy 118.215152 -246.410457) (xy 118.257539 -246.378938) (xy 118.304397 -246.354556) (xy 118.354535 -246.337932)
			(xy 118.406678 -246.329487) (xy 118.433088 -246.328946) (xy 118.457475 -246.329347) (xy 118.505721 -246.336504)
			(xy 118.55239 -246.350678) (xy 118.596467 -246.371561) (xy 118.636994 -246.3987) (xy 118.673089 -246.431503)
			(xy 118.688866 -246.450104) (xy 118.698787 -246.461339) (xy 118.723704 -246.477969) (xy 118.752373 -246.486657)
			(xy 118.782331 -246.486657) (xy 118.811 -246.477969) (xy 118.835917 -246.461339) (xy 118.845838 -246.450104)
			(xy 118.861647 -246.431535) (xy 118.897748 -246.398751) (xy 118.938272 -246.371624) (xy 118.982341 -246.350744)
			(xy 119.028999 -246.336562) (xy 119.077233 -246.329388) (xy 119.101616 -246.328946) (xy 119.128915 -246.329474)
			(xy 119.182769 -246.338458) (xy 119.23441 -246.356179) (xy 119.282434 -246.382155) (xy 119.325529 -246.415676)
			(xy 119.34444 -246.435372) (xy 119.354273 -246.445352) (xy 119.378157 -246.459978) (xy 119.405113 -246.467577)
			(xy 119.433119 -246.467577) (xy 119.460075 -246.459978) (xy 119.483959 -246.445352) (xy 119.493792 -246.435372)
			(xy 119.510937 -246.417427) (xy 119.549653 -246.386375) (xy 119.59258 -246.361467) (xy 119.638751 -246.343264)
			(xy 119.687126 -246.332175) (xy 119.736616 -246.328451) (xy 119.786106 -246.332175) (xy 119.834481 -246.343264)
			(xy 119.880652 -246.361467) (xy 119.923579 -246.386375) (xy 119.962295 -246.417427) (xy 119.97944 -246.435372)
			(xy 119.989273 -246.445352) (xy 120.013157 -246.459978) (xy 120.040113 -246.467577) (xy 120.068119 -246.467577)
			(xy 120.095075 -246.459978) (xy 120.118959 -246.445352) (xy 120.128792 -246.435372) (xy 120.147693 -246.415669)
			(xy 120.190795 -246.382159) (xy 120.238822 -246.356195) (xy 120.290465 -246.338484) (xy 120.344318 -246.329507)
			(xy 120.371616 -246.328946) (xy 120.398292 -246.32941) (xy 120.45095 -246.337977) (xy 120.501551 -246.354886)
			(xy 120.548781 -246.379699) (xy 120.591415 -246.411771) (xy 120.628348 -246.450272) (xy 120.643904 -246.471948)
			(xy 120.651834 -246.482787) (xy 120.672263 -246.500207) (xy 120.696528 -246.511697) (xy 120.72295 -246.516462)
			(xy 120.7497 -246.514174) (xy 120.774928 -246.50499) (xy 120.786144 -246.497602) (xy 120.807123 -246.483341)
			(xy 120.852554 -246.460773) (xy 120.900901 -246.445415) (xy 120.951027 -246.437629) (xy 120.97639 -246.43715)
			(xy 120.995746 -246.43739) (xy 121.0342 -246.441845) (xy 121.053098 -246.44604) (xy 121.067776 -246.448954)
			(xy 121.097628 -246.44712) (xy 121.125672 -246.436724) (xy 121.149506 -246.418657) (xy 121.167092 -246.394464)
			(xy 121.176923 -246.366218) (xy 121.178066 -246.351298) (xy 121.179609 -246.326036) (xy 121.189317 -246.276368)
			(xy 121.206485 -246.228761) (xy 121.230711 -246.184328) (xy 121.261429 -246.144109) (xy 121.29792 -246.109044)
			(xy 121.339331 -246.079953) (xy 121.384694 -246.057517) (xy 121.432947 -246.042259) (xy 121.482962 -246.034537)
			(xy 121.508266 -246.034052) (xy 121.534238 -246.03452) (xy 121.585542 -246.042641) (xy 121.634944 -246.058688)
			(xy 121.681227 -246.082267) (xy 121.723251 -246.112795) (xy 121.759983 -246.149523) (xy 121.790516 -246.191544)
			(xy 121.814099 -246.237825) (xy 121.830151 -246.287225) (xy 121.838277 -246.338529) (xy 121.838277 -246.390471)
			(xy 121.838277 -246.390473) (xy 122.118121 -246.390473) (xy 122.118121 -246.338539) (xy 122.126246 -246.287244)
			(xy 122.142294 -246.237851) (xy 122.165872 -246.191577) (xy 122.196398 -246.149561) (xy 122.233121 -246.112838)
			(xy 122.275137 -246.082312) (xy 122.321411 -246.058734) (xy 122.370804 -246.042686) (xy 122.422099 -246.034561)
			(xy 122.474033 -246.034561) (xy 122.525328 -246.042686) (xy 122.574721 -246.058734) (xy 122.620995 -246.082312)
			(xy 122.663011 -246.112838) (xy 122.699734 -246.149561) (xy 122.73026 -246.191577) (xy 122.753838 -246.237851)
			(xy 122.769886 -246.287244) (xy 122.778011 -246.338539) (xy 122.77852 -246.364506) (xy 122.778011 -246.390473)
			(xy 123.057667 -246.390473) (xy 123.057667 -246.338539) (xy 123.065792 -246.287244) (xy 123.08184 -246.237851)
			(xy 123.105418 -246.191577) (xy 123.135944 -246.149561) (xy 123.172667 -246.112838) (xy 123.214683 -246.082312)
			(xy 123.260957 -246.058734) (xy 123.31035 -246.042686) (xy 123.361645 -246.034561) (xy 123.413579 -246.034561)
			(xy 123.464874 -246.042686) (xy 123.514267 -246.058734) (xy 123.560541 -246.082312) (xy 123.602557 -246.112838)
			(xy 123.63928 -246.149561) (xy 123.669806 -246.191577) (xy 123.693384 -246.237851) (xy 123.709432 -246.287244)
			(xy 123.717557 -246.338539) (xy 123.718066 -246.364506) (xy 123.717557 -246.390473) (xy 123.997467 -246.390473)
			(xy 123.997467 -246.338539) (xy 124.005592 -246.287244) (xy 124.02164 -246.237851) (xy 124.045218 -246.191577)
			(xy 124.075744 -246.149561) (xy 124.112467 -246.112838) (xy 124.154483 -246.082312) (xy 124.200757 -246.058734)
			(xy 124.25015 -246.042686) (xy 124.301445 -246.034561) (xy 124.353379 -246.034561) (xy 124.404674 -246.042686)
			(xy 124.454067 -246.058734) (xy 124.500341 -246.082312) (xy 124.542357 -246.112838) (xy 124.57908 -246.149561)
			(xy 124.609606 -246.191577) (xy 124.633184 -246.237851) (xy 124.649232 -246.287244) (xy 124.657357 -246.338539)
			(xy 124.657866 -246.364506) (xy 124.657357 -246.390473) (xy 124.937267 -246.390473) (xy 124.937267 -246.338539)
			(xy 124.945392 -246.287244) (xy 124.96144 -246.237851) (xy 124.985018 -246.191577) (xy 125.015544 -246.149561)
			(xy 125.052267 -246.112838) (xy 125.094283 -246.082312) (xy 125.140557 -246.058734) (xy 125.18995 -246.042686)
			(xy 125.241245 -246.034561) (xy 125.293179 -246.034561) (xy 125.344474 -246.042686) (xy 125.393867 -246.058734)
			(xy 125.440141 -246.082312) (xy 125.482157 -246.112838) (xy 125.51888 -246.149561) (xy 125.549406 -246.191577)
			(xy 125.572984 -246.237851) (xy 125.589032 -246.287244) (xy 125.597157 -246.338539) (xy 125.597666 -246.364506)
			(xy 125.597157 -246.390473) (xy 125.877067 -246.390473) (xy 125.877067 -246.338539) (xy 125.885192 -246.287244)
			(xy 125.90124 -246.237851) (xy 125.924818 -246.191577) (xy 125.955344 -246.149561) (xy 125.992067 -246.112838)
			(xy 126.034083 -246.082312) (xy 126.080357 -246.058734) (xy 126.12975 -246.042686) (xy 126.181045 -246.034561)
			(xy 126.232979 -246.034561) (xy 126.284274 -246.042686) (xy 126.333667 -246.058734) (xy 126.379941 -246.082312)
			(xy 126.421957 -246.112838) (xy 126.45868 -246.149561) (xy 126.489206 -246.191577) (xy 126.512784 -246.237851)
			(xy 126.528832 -246.287244) (xy 126.536957 -246.338539) (xy 126.537466 -246.364506) (xy 126.536957 -246.390473)
			(xy 126.816867 -246.390473) (xy 126.816867 -246.338539) (xy 126.824992 -246.287244) (xy 126.84104 -246.237851)
			(xy 126.864618 -246.191577) (xy 126.895144 -246.149561) (xy 126.931867 -246.112838) (xy 126.973883 -246.082312)
			(xy 127.020157 -246.058734) (xy 127.06955 -246.042686) (xy 127.120845 -246.034561) (xy 127.172779 -246.034561)
			(xy 127.224074 -246.042686) (xy 127.273467 -246.058734) (xy 127.319741 -246.082312) (xy 127.361757 -246.112838)
			(xy 127.39848 -246.149561) (xy 127.429006 -246.191577) (xy 127.452584 -246.237851) (xy 127.468632 -246.287244)
			(xy 127.476757 -246.338539) (xy 127.477266 -246.364506) (xy 127.476757 -246.390473) (xy 127.756667 -246.390473)
			(xy 127.756667 -246.338539) (xy 127.764792 -246.287244) (xy 127.78084 -246.237851) (xy 127.804418 -246.191577)
			(xy 127.834944 -246.149561) (xy 127.871667 -246.112838) (xy 127.913683 -246.082312) (xy 127.959957 -246.058734)
			(xy 128.00935 -246.042686) (xy 128.060645 -246.034561) (xy 128.112579 -246.034561) (xy 128.163874 -246.042686)
			(xy 128.213267 -246.058734) (xy 128.259541 -246.082312) (xy 128.301557 -246.112838) (xy 128.33828 -246.149561)
			(xy 128.368806 -246.191577) (xy 128.392384 -246.237851) (xy 128.408432 -246.287244) (xy 128.416557 -246.338539)
			(xy 128.417066 -246.364506) (xy 128.416557 -246.390473) (xy 128.696721 -246.390473) (xy 128.696721 -246.338539)
			(xy 128.704846 -246.287244) (xy 128.720894 -246.237851) (xy 128.744472 -246.191577) (xy 128.774998 -246.149561)
			(xy 128.811721 -246.112838) (xy 128.853737 -246.082312) (xy 128.900011 -246.058734) (xy 128.949404 -246.042686)
			(xy 129.000699 -246.034561) (xy 129.052633 -246.034561) (xy 129.103928 -246.042686) (xy 129.153321 -246.058734)
			(xy 129.199595 -246.082312) (xy 129.241611 -246.112838) (xy 129.278334 -246.149561) (xy 129.30886 -246.191577)
			(xy 129.332438 -246.237851) (xy 129.348486 -246.287244) (xy 129.356611 -246.338539) (xy 129.35712 -246.364506)
			(xy 129.356611 -246.390473) (xy 129.636267 -246.390473) (xy 129.636267 -246.338539) (xy 129.644392 -246.287244)
			(xy 129.66044 -246.237851) (xy 129.684018 -246.191577) (xy 129.714544 -246.149561) (xy 129.751267 -246.112838)
			(xy 129.793283 -246.082312) (xy 129.839557 -246.058734) (xy 129.88895 -246.042686) (xy 129.940245 -246.034561)
			(xy 129.992179 -246.034561) (xy 130.043474 -246.042686) (xy 130.092867 -246.058734) (xy 130.139141 -246.082312)
			(xy 130.181157 -246.112838) (xy 130.21788 -246.149561) (xy 130.248406 -246.191577) (xy 130.271984 -246.237851)
			(xy 130.288032 -246.287244) (xy 130.296157 -246.338539) (xy 130.296666 -246.364506) (xy 130.296157 -246.390473)
			(xy 130.576067 -246.390473) (xy 130.576067 -246.338539) (xy 130.584192 -246.287244) (xy 130.60024 -246.237851)
			(xy 130.623818 -246.191577) (xy 130.654344 -246.149561) (xy 130.691067 -246.112838) (xy 130.733083 -246.082312)
			(xy 130.779357 -246.058734) (xy 130.82875 -246.042686) (xy 130.880045 -246.034561) (xy 130.931979 -246.034561)
			(xy 130.983274 -246.042686) (xy 131.032667 -246.058734) (xy 131.078941 -246.082312) (xy 131.120957 -246.112838)
			(xy 131.15768 -246.149561) (xy 131.188206 -246.191577) (xy 131.211784 -246.237851) (xy 131.227832 -246.287244)
			(xy 131.235957 -246.338539) (xy 131.236466 -246.364506) (xy 131.235957 -246.390473) (xy 131.227832 -246.441768)
			(xy 131.211784 -246.491161) (xy 131.188206 -246.537435) (xy 131.15768 -246.579451) (xy 131.120957 -246.616174)
			(xy 131.078941 -246.6467) (xy 131.032667 -246.670278) (xy 130.983274 -246.686326) (xy 130.931979 -246.694451)
			(xy 130.880045 -246.694451) (xy 130.82875 -246.686326) (xy 130.779357 -246.670278) (xy 130.733083 -246.6467)
			(xy 130.691067 -246.616174) (xy 130.654344 -246.579451) (xy 130.623818 -246.537435) (xy 130.60024 -246.491161)
			(xy 130.584192 -246.441768) (xy 130.576067 -246.390473) (xy 130.296157 -246.390473) (xy 130.288032 -246.441768)
			(xy 130.271984 -246.491161) (xy 130.248406 -246.537435) (xy 130.21788 -246.579451) (xy 130.181157 -246.616174)
			(xy 130.139141 -246.6467) (xy 130.092867 -246.670278) (xy 130.043474 -246.686326) (xy 129.992179 -246.694451)
			(xy 129.940245 -246.694451) (xy 129.88895 -246.686326) (xy 129.839557 -246.670278) (xy 129.793283 -246.6467)
			(xy 129.751267 -246.616174) (xy 129.714544 -246.579451) (xy 129.684018 -246.537435) (xy 129.66044 -246.491161)
			(xy 129.644392 -246.441768) (xy 129.636267 -246.390473) (xy 129.356611 -246.390473) (xy 129.348486 -246.441768)
			(xy 129.332438 -246.491161) (xy 129.30886 -246.537435) (xy 129.278334 -246.579451) (xy 129.241611 -246.616174)
			(xy 129.199595 -246.6467) (xy 129.153321 -246.670278) (xy 129.103928 -246.686326) (xy 129.052633 -246.694451)
			(xy 129.000699 -246.694451) (xy 128.949404 -246.686326) (xy 128.900011 -246.670278) (xy 128.853737 -246.6467)
			(xy 128.811721 -246.616174) (xy 128.774998 -246.579451) (xy 128.744472 -246.537435) (xy 128.720894 -246.491161)
			(xy 128.704846 -246.441768) (xy 128.696721 -246.390473) (xy 128.416557 -246.390473) (xy 128.408432 -246.441768)
			(xy 128.392384 -246.491161) (xy 128.368806 -246.537435) (xy 128.33828 -246.579451) (xy 128.301557 -246.616174)
			(xy 128.259541 -246.6467) (xy 128.213267 -246.670278) (xy 128.163874 -246.686326) (xy 128.112579 -246.694451)
			(xy 128.060645 -246.694451) (xy 128.00935 -246.686326) (xy 127.959957 -246.670278) (xy 127.913683 -246.6467)
			(xy 127.871667 -246.616174) (xy 127.834944 -246.579451) (xy 127.804418 -246.537435) (xy 127.78084 -246.491161)
			(xy 127.764792 -246.441768) (xy 127.756667 -246.390473) (xy 127.476757 -246.390473) (xy 127.468632 -246.441768)
			(xy 127.452584 -246.491161) (xy 127.429006 -246.537435) (xy 127.39848 -246.579451) (xy 127.361757 -246.616174)
			(xy 127.319741 -246.6467) (xy 127.273467 -246.670278) (xy 127.224074 -246.686326) (xy 127.172779 -246.694451)
			(xy 127.120845 -246.694451) (xy 127.06955 -246.686326) (xy 127.020157 -246.670278) (xy 126.973883 -246.6467)
			(xy 126.931867 -246.616174) (xy 126.895144 -246.579451) (xy 126.864618 -246.537435) (xy 126.84104 -246.491161)
			(xy 126.824992 -246.441768) (xy 126.816867 -246.390473) (xy 126.536957 -246.390473) (xy 126.528832 -246.441768)
			(xy 126.512784 -246.491161) (xy 126.489206 -246.537435) (xy 126.45868 -246.579451) (xy 126.421957 -246.616174)
			(xy 126.379941 -246.6467) (xy 126.333667 -246.670278) (xy 126.284274 -246.686326) (xy 126.232979 -246.694451)
			(xy 126.181045 -246.694451) (xy 126.12975 -246.686326) (xy 126.080357 -246.670278) (xy 126.034083 -246.6467)
			(xy 125.992067 -246.616174) (xy 125.955344 -246.579451) (xy 125.924818 -246.537435) (xy 125.90124 -246.491161)
			(xy 125.885192 -246.441768) (xy 125.877067 -246.390473) (xy 125.597157 -246.390473) (xy 125.589032 -246.441768)
			(xy 125.572984 -246.491161) (xy 125.549406 -246.537435) (xy 125.51888 -246.579451) (xy 125.482157 -246.616174)
			(xy 125.440141 -246.6467) (xy 125.393867 -246.670278) (xy 125.344474 -246.686326) (xy 125.293179 -246.694451)
			(xy 125.241245 -246.694451) (xy 125.18995 -246.686326) (xy 125.140557 -246.670278) (xy 125.094283 -246.6467)
			(xy 125.052267 -246.616174) (xy 125.015544 -246.579451) (xy 124.985018 -246.537435) (xy 124.96144 -246.491161)
			(xy 124.945392 -246.441768) (xy 124.937267 -246.390473) (xy 124.657357 -246.390473) (xy 124.649232 -246.441768)
			(xy 124.633184 -246.491161) (xy 124.609606 -246.537435) (xy 124.57908 -246.579451) (xy 124.542357 -246.616174)
			(xy 124.500341 -246.6467) (xy 124.454067 -246.670278) (xy 124.404674 -246.686326) (xy 124.353379 -246.694451)
			(xy 124.301445 -246.694451) (xy 124.25015 -246.686326) (xy 124.200757 -246.670278) (xy 124.154483 -246.6467)
			(xy 124.112467 -246.616174) (xy 124.075744 -246.579451) (xy 124.045218 -246.537435) (xy 124.02164 -246.491161)
			(xy 124.005592 -246.441768) (xy 123.997467 -246.390473) (xy 123.717557 -246.390473) (xy 123.709432 -246.441768)
			(xy 123.693384 -246.491161) (xy 123.669806 -246.537435) (xy 123.63928 -246.579451) (xy 123.602557 -246.616174)
			(xy 123.560541 -246.6467) (xy 123.514267 -246.670278) (xy 123.464874 -246.686326) (xy 123.413579 -246.694451)
			(xy 123.361645 -246.694451) (xy 123.31035 -246.686326) (xy 123.260957 -246.670278) (xy 123.214683 -246.6467)
			(xy 123.172667 -246.616174) (xy 123.135944 -246.579451) (xy 123.105418 -246.537435) (xy 123.08184 -246.491161)
			(xy 123.065792 -246.441768) (xy 123.057667 -246.390473) (xy 122.778011 -246.390473) (xy 122.769886 -246.441768)
			(xy 122.753838 -246.491161) (xy 122.73026 -246.537435) (xy 122.699734 -246.579451) (xy 122.663011 -246.616174)
			(xy 122.620995 -246.6467) (xy 122.574721 -246.670278) (xy 122.525328 -246.686326) (xy 122.474033 -246.694451)
			(xy 122.422099 -246.694451) (xy 122.370804 -246.686326) (xy 122.321411 -246.670278) (xy 122.275137 -246.6467)
			(xy 122.233121 -246.616174) (xy 122.196398 -246.579451) (xy 122.165872 -246.537435) (xy 122.142294 -246.491161)
			(xy 122.126246 -246.441768) (xy 122.118121 -246.390473) (xy 121.838277 -246.390473) (xy 121.830151 -246.441775)
			(xy 121.814099 -246.491175) (xy 121.790516 -246.537456) (xy 121.759983 -246.579477) (xy 121.723251 -246.616205)
			(xy 121.681227 -246.646733) (xy 121.634944 -246.670312) (xy 121.585542 -246.686359) (xy 121.534238 -246.69448)
			(xy 121.508266 -246.69496) (xy 121.48891 -246.694727) (xy 121.450455 -246.690267) (xy 121.431558 -246.68607)
			(xy 121.41689 -246.683099) (xy 121.38703 -246.684944) (xy 121.358982 -246.695351) (xy 121.335145 -246.71343)
			(xy 121.31756 -246.737632) (xy 121.307731 -246.765888) (xy 121.30659 -246.780812) (xy 121.305299 -246.804009)
			(xy 121.296976 -246.849719) (xy 121.282337 -246.893813) (xy 121.26167 -246.935424) (xy 121.235382 -246.973732)
			(xy 121.219976 -246.991124) (xy 121.210172 -247.002612) (xy 121.197165 -247.02985) (xy 121.1927 -247.059703)
			(xy 121.197167 -247.089555) (xy 121.210176 -247.116793) (xy 121.219976 -247.128284) (xy 121.236229 -247.146659)
			(xy 121.263675 -247.18732) (xy 121.271773 -247.204289) (xy 121.648221 -247.204289) (xy 121.648221 -247.152355)
			(xy 121.656346 -247.10106) (xy 121.672394 -247.051667) (xy 121.695972 -247.005393) (xy 121.726498 -246.963377)
			(xy 121.763221 -246.926654) (xy 121.805237 -246.896128) (xy 121.851511 -246.87255) (xy 121.900904 -246.856502)
			(xy 121.952199 -246.848377) (xy 122.004133 -246.848377) (xy 122.055428 -246.856502) (xy 122.104821 -246.87255)
			(xy 122.151095 -246.896128) (xy 122.193111 -246.926654) (xy 122.229834 -246.963377) (xy 122.26036 -247.005393)
			(xy 122.283938 -247.051667) (xy 122.299986 -247.10106) (xy 122.308111 -247.152355) (xy 122.30862 -247.178322)
			(xy 122.308111 -247.204289) (xy 122.588021 -247.204289) (xy 122.588021 -247.152355) (xy 122.596146 -247.10106)
			(xy 122.612194 -247.051667) (xy 122.635772 -247.005393) (xy 122.666298 -246.963377) (xy 122.703021 -246.926654)
			(xy 122.745037 -246.896128) (xy 122.791311 -246.87255) (xy 122.840704 -246.856502) (xy 122.891999 -246.848377)
			(xy 122.943933 -246.848377) (xy 122.995228 -246.856502) (xy 123.044621 -246.87255) (xy 123.090895 -246.896128)
			(xy 123.132911 -246.926654) (xy 123.169634 -246.963377) (xy 123.20016 -247.005393) (xy 123.223738 -247.051667)
			(xy 123.239786 -247.10106) (xy 123.247911 -247.152355) (xy 123.24842 -247.178322) (xy 123.247911 -247.204289)
			(xy 123.527821 -247.204289) (xy 123.527821 -247.152355) (xy 123.535946 -247.10106) (xy 123.551994 -247.051667)
			(xy 123.575572 -247.005393) (xy 123.606098 -246.963377) (xy 123.642821 -246.926654) (xy 123.684837 -246.896128)
			(xy 123.731111 -246.87255) (xy 123.780504 -246.856502) (xy 123.831799 -246.848377) (xy 123.883733 -246.848377)
			(xy 123.935028 -246.856502) (xy 123.984421 -246.87255) (xy 124.030695 -246.896128) (xy 124.072711 -246.926654)
			(xy 124.109434 -246.963377) (xy 124.13996 -247.005393) (xy 124.163538 -247.051667) (xy 124.179586 -247.10106)
			(xy 124.187711 -247.152355) (xy 124.18822 -247.178322) (xy 124.187711 -247.204289) (xy 124.467621 -247.204289)
			(xy 124.467621 -247.152355) (xy 124.475746 -247.10106) (xy 124.491794 -247.051667) (xy 124.515372 -247.005393)
			(xy 124.545898 -246.963377) (xy 124.582621 -246.926654) (xy 124.624637 -246.896128) (xy 124.670911 -246.87255)
			(xy 124.720304 -246.856502) (xy 124.771599 -246.848377) (xy 124.823533 -246.848377) (xy 124.874828 -246.856502)
			(xy 124.924221 -246.87255) (xy 124.970495 -246.896128) (xy 125.012511 -246.926654) (xy 125.049234 -246.963377)
			(xy 125.07976 -247.005393) (xy 125.103338 -247.051667) (xy 125.119386 -247.10106) (xy 125.127511 -247.152355)
			(xy 125.12802 -247.178322) (xy 125.127511 -247.204289) (xy 125.407421 -247.204289) (xy 125.407421 -247.152355)
			(xy 125.415546 -247.10106) (xy 125.431594 -247.051667) (xy 125.455172 -247.005393) (xy 125.485698 -246.963377)
			(xy 125.522421 -246.926654) (xy 125.564437 -246.896128) (xy 125.610711 -246.87255) (xy 125.660104 -246.856502)
			(xy 125.711399 -246.848377) (xy 125.763333 -246.848377) (xy 125.814628 -246.856502) (xy 125.864021 -246.87255)
			(xy 125.910295 -246.896128) (xy 125.952311 -246.926654) (xy 125.989034 -246.963377) (xy 126.01956 -247.005393)
			(xy 126.043138 -247.051667) (xy 126.059186 -247.10106) (xy 126.067311 -247.152355) (xy 126.06782 -247.178322)
			(xy 126.067311 -247.204289) (xy 126.346967 -247.204289) (xy 126.346967 -247.152355) (xy 126.355092 -247.10106)
			(xy 126.37114 -247.051667) (xy 126.394718 -247.005393) (xy 126.425244 -246.963377) (xy 126.461967 -246.926654)
			(xy 126.503983 -246.896128) (xy 126.550257 -246.87255) (xy 126.59965 -246.856502) (xy 126.650945 -246.848377)
			(xy 126.702879 -246.848377) (xy 126.754174 -246.856502) (xy 126.803567 -246.87255) (xy 126.849841 -246.896128)
			(xy 126.891857 -246.926654) (xy 126.92858 -246.963377) (xy 126.959106 -247.005393) (xy 126.982684 -247.051667)
			(xy 126.998732 -247.10106) (xy 127.006857 -247.152355) (xy 127.007366 -247.178322) (xy 127.006857 -247.204289)
			(xy 127.287021 -247.204289) (xy 127.287021 -247.152355) (xy 127.295146 -247.10106) (xy 127.311194 -247.051667)
			(xy 127.334772 -247.005393) (xy 127.365298 -246.963377) (xy 127.402021 -246.926654) (xy 127.444037 -246.896128)
			(xy 127.490311 -246.87255) (xy 127.539704 -246.856502) (xy 127.590999 -246.848377) (xy 127.642933 -246.848377)
			(xy 127.694228 -246.856502) (xy 127.743621 -246.87255) (xy 127.789895 -246.896128) (xy 127.831911 -246.926654)
			(xy 127.868634 -246.963377) (xy 127.89916 -247.005393) (xy 127.922738 -247.051667) (xy 127.938786 -247.10106)
			(xy 127.946911 -247.152355) (xy 127.94742 -247.178322) (xy 127.946911 -247.204289) (xy 128.226821 -247.204289)
			(xy 128.226821 -247.152355) (xy 128.234946 -247.10106) (xy 128.250994 -247.051667) (xy 128.274572 -247.005393)
			(xy 128.305098 -246.963377) (xy 128.341821 -246.926654) (xy 128.383837 -246.896128) (xy 128.430111 -246.87255)
			(xy 128.479504 -246.856502) (xy 128.530799 -246.848377) (xy 128.582733 -246.848377) (xy 128.634028 -246.856502)
			(xy 128.683421 -246.87255) (xy 128.729695 -246.896128) (xy 128.771711 -246.926654) (xy 128.808434 -246.963377)
			(xy 128.83896 -247.005393) (xy 128.862538 -247.051667) (xy 128.878586 -247.10106) (xy 128.886711 -247.152355)
			(xy 128.88722 -247.178322) (xy 128.886711 -247.204289) (xy 129.166621 -247.204289) (xy 129.166621 -247.152355)
			(xy 129.174746 -247.10106) (xy 129.190794 -247.051667) (xy 129.214372 -247.005393) (xy 129.244898 -246.963377)
			(xy 129.281621 -246.926654) (xy 129.323637 -246.896128) (xy 129.369911 -246.87255) (xy 129.419304 -246.856502)
			(xy 129.470599 -246.848377) (xy 129.522533 -246.848377) (xy 129.573828 -246.856502) (xy 129.623221 -246.87255)
			(xy 129.669495 -246.896128) (xy 129.711511 -246.926654) (xy 129.748234 -246.963377) (xy 129.77876 -247.005393)
			(xy 129.802338 -247.051667) (xy 129.818386 -247.10106) (xy 129.826511 -247.152355) (xy 129.82702 -247.178322)
			(xy 129.826511 -247.204289) (xy 130.106421 -247.204289) (xy 130.106421 -247.152355) (xy 130.114546 -247.10106)
			(xy 130.130594 -247.051667) (xy 130.154172 -247.005393) (xy 130.184698 -246.963377) (xy 130.221421 -246.926654)
			(xy 130.263437 -246.896128) (xy 130.309711 -246.87255) (xy 130.359104 -246.856502) (xy 130.410399 -246.848377)
			(xy 130.462333 -246.848377) (xy 130.513628 -246.856502) (xy 130.563021 -246.87255) (xy 130.609295 -246.896128)
			(xy 130.651311 -246.926654) (xy 130.688034 -246.963377) (xy 130.71856 -247.005393) (xy 130.742138 -247.051667)
			(xy 130.758186 -247.10106) (xy 130.766311 -247.152355) (xy 130.76682 -247.178322) (xy 130.766311 -247.204289)
			(xy 130.758186 -247.255584) (xy 130.742138 -247.304977) (xy 130.71856 -247.351251) (xy 130.688034 -247.393267)
			(xy 130.651311 -247.42999) (xy 130.609295 -247.460516) (xy 130.563021 -247.484094) (xy 130.513628 -247.500142)
			(xy 130.462333 -247.508267) (xy 130.410399 -247.508267) (xy 130.359104 -247.500142) (xy 130.309711 -247.484094)
			(xy 130.263437 -247.460516) (xy 130.221421 -247.42999) (xy 130.184698 -247.393267) (xy 130.154172 -247.351251)
			(xy 130.130594 -247.304977) (xy 130.114546 -247.255584) (xy 130.106421 -247.204289) (xy 129.826511 -247.204289)
			(xy 129.818386 -247.255584) (xy 129.802338 -247.304977) (xy 129.77876 -247.351251) (xy 129.748234 -247.393267)
			(xy 129.711511 -247.42999) (xy 129.669495 -247.460516) (xy 129.623221 -247.484094) (xy 129.573828 -247.500142)
			(xy 129.522533 -247.508267) (xy 129.470599 -247.508267) (xy 129.419304 -247.500142) (xy 129.369911 -247.484094)
			(xy 129.323637 -247.460516) (xy 129.281621 -247.42999) (xy 129.244898 -247.393267) (xy 129.214372 -247.351251)
			(xy 129.190794 -247.304977) (xy 129.174746 -247.255584) (xy 129.166621 -247.204289) (xy 128.886711 -247.204289)
			(xy 128.878586 -247.255584) (xy 128.862538 -247.304977) (xy 128.83896 -247.351251) (xy 128.808434 -247.393267)
			(xy 128.771711 -247.42999) (xy 128.729695 -247.460516) (xy 128.683421 -247.484094) (xy 128.634028 -247.500142)
			(xy 128.582733 -247.508267) (xy 128.530799 -247.508267) (xy 128.479504 -247.500142) (xy 128.430111 -247.484094)
			(xy 128.383837 -247.460516) (xy 128.341821 -247.42999) (xy 128.305098 -247.393267) (xy 128.274572 -247.351251)
			(xy 128.250994 -247.304977) (xy 128.234946 -247.255584) (xy 128.226821 -247.204289) (xy 127.946911 -247.204289)
			(xy 127.938786 -247.255584) (xy 127.922738 -247.304977) (xy 127.89916 -247.351251) (xy 127.868634 -247.393267)
			(xy 127.831911 -247.42999) (xy 127.789895 -247.460516) (xy 127.743621 -247.484094) (xy 127.694228 -247.500142)
			(xy 127.642933 -247.508267) (xy 127.590999 -247.508267) (xy 127.539704 -247.500142) (xy 127.490311 -247.484094)
			(xy 127.444037 -247.460516) (xy 127.402021 -247.42999) (xy 127.365298 -247.393267) (xy 127.334772 -247.351251)
			(xy 127.311194 -247.304977) (xy 127.295146 -247.255584) (xy 127.287021 -247.204289) (xy 127.006857 -247.204289)
			(xy 126.998732 -247.255584) (xy 126.982684 -247.304977) (xy 126.959106 -247.351251) (xy 126.92858 -247.393267)
			(xy 126.891857 -247.42999) (xy 126.849841 -247.460516) (xy 126.803567 -247.484094) (xy 126.754174 -247.500142)
			(xy 126.702879 -247.508267) (xy 126.650945 -247.508267) (xy 126.59965 -247.500142) (xy 126.550257 -247.484094)
			(xy 126.503983 -247.460516) (xy 126.461967 -247.42999) (xy 126.425244 -247.393267) (xy 126.394718 -247.351251)
			(xy 126.37114 -247.304977) (xy 126.355092 -247.255584) (xy 126.346967 -247.204289) (xy 126.067311 -247.204289)
			(xy 126.059186 -247.255584) (xy 126.043138 -247.304977) (xy 126.01956 -247.351251) (xy 125.989034 -247.393267)
			(xy 125.952311 -247.42999) (xy 125.910295 -247.460516) (xy 125.864021 -247.484094) (xy 125.814628 -247.500142)
			(xy 125.763333 -247.508267) (xy 125.711399 -247.508267) (xy 125.660104 -247.500142) (xy 125.610711 -247.484094)
			(xy 125.564437 -247.460516) (xy 125.522421 -247.42999) (xy 125.485698 -247.393267) (xy 125.455172 -247.351251)
			(xy 125.431594 -247.304977) (xy 125.415546 -247.255584) (xy 125.407421 -247.204289) (xy 125.127511 -247.204289)
			(xy 125.119386 -247.255584) (xy 125.103338 -247.304977) (xy 125.07976 -247.351251) (xy 125.049234 -247.393267)
			(xy 125.012511 -247.42999) (xy 124.970495 -247.460516) (xy 124.924221 -247.484094) (xy 124.874828 -247.500142)
			(xy 124.823533 -247.508267) (xy 124.771599 -247.508267) (xy 124.720304 -247.500142) (xy 124.670911 -247.484094)
			(xy 124.624637 -247.460516) (xy 124.582621 -247.42999) (xy 124.545898 -247.393267) (xy 124.515372 -247.351251)
			(xy 124.491794 -247.304977) (xy 124.475746 -247.255584) (xy 124.467621 -247.204289) (xy 124.187711 -247.204289)
			(xy 124.179586 -247.255584) (xy 124.163538 -247.304977) (xy 124.13996 -247.351251) (xy 124.109434 -247.393267)
			(xy 124.072711 -247.42999) (xy 124.030695 -247.460516) (xy 123.984421 -247.484094) (xy 123.935028 -247.500142)
			(xy 123.883733 -247.508267) (xy 123.831799 -247.508267) (xy 123.780504 -247.500142) (xy 123.731111 -247.484094)
			(xy 123.684837 -247.460516) (xy 123.642821 -247.42999) (xy 123.606098 -247.393267) (xy 123.575572 -247.351251)
			(xy 123.551994 -247.304977) (xy 123.535946 -247.255584) (xy 123.527821 -247.204289) (xy 123.247911 -247.204289)
			(xy 123.239786 -247.255584) (xy 123.223738 -247.304977) (xy 123.20016 -247.351251) (xy 123.169634 -247.393267)
			(xy 123.132911 -247.42999) (xy 123.090895 -247.460516) (xy 123.044621 -247.484094) (xy 122.995228 -247.500142)
			(xy 122.943933 -247.508267) (xy 122.891999 -247.508267) (xy 122.840704 -247.500142) (xy 122.791311 -247.484094)
			(xy 122.745037 -247.460516) (xy 122.703021 -247.42999) (xy 122.666298 -247.393267) (xy 122.635772 -247.351251)
			(xy 122.612194 -247.304977) (xy 122.596146 -247.255584) (xy 122.588021 -247.204289) (xy 122.308111 -247.204289)
			(xy 122.299986 -247.255584) (xy 122.283938 -247.304977) (xy 122.26036 -247.351251) (xy 122.229834 -247.393267)
			(xy 122.193111 -247.42999) (xy 122.151095 -247.460516) (xy 122.104821 -247.484094) (xy 122.055428 -247.500142)
			(xy 122.004133 -247.508267) (xy 121.952199 -247.508267) (xy 121.900904 -247.500142) (xy 121.851511 -247.484094)
			(xy 121.805237 -247.460516) (xy 121.763221 -247.42999) (xy 121.726498 -247.393267) (xy 121.695972 -247.351251)
			(xy 121.672394 -247.304977) (xy 121.656346 -247.255584) (xy 121.648221 -247.204289) (xy 121.271773 -247.204289)
			(xy 121.284803 -247.231593) (xy 121.29915 -247.278504) (xy 121.3064 -247.327022) (xy 121.306844 -247.35155)
			(xy 121.306844 -247.351804) (xy 121.306335 -247.377771) (xy 121.29821 -247.429066) (xy 121.282162 -247.478459)
			(xy 121.258584 -247.524733) (xy 121.228058 -247.566749) (xy 121.191335 -247.603472) (xy 121.149319 -247.633998)
			(xy 121.103045 -247.657576) (xy 121.053652 -247.673624) (xy 121.002357 -247.681749) (xy 120.950423 -247.681749)
			(xy 120.899128 -247.673624) (xy 120.849735 -247.657576) (xy 120.803461 -247.633998) (xy 120.761445 -247.603472)
			(xy 120.724722 -247.566749) (xy 120.694196 -247.524733) (xy 120.670618 -247.478459) (xy 120.65457 -247.429066)
			(xy 120.646445 -247.377771) (xy 120.645936 -247.351804) (xy 120.645936 -247.35155) (xy 120.646374 -247.327023)
			(xy 120.653643 -247.27851) (xy 120.667999 -247.231604) (xy 120.689126 -247.187332) (xy 120.716562 -247.146668)
			(xy 120.732804 -247.128284) (xy 120.742601 -247.116791) (xy 120.755612 -247.089555) (xy 120.760079 -247.059703)
			(xy 120.755613 -247.029851) (xy 120.742604 -247.002614) (xy 120.732804 -246.991124) (xy 120.725083 -246.982555)
			(xy 120.710718 -246.964505) (xy 120.704102 -246.955056) (xy 120.696166 -246.944222) (xy 120.675738 -246.926802)
			(xy 120.651474 -246.915311) (xy 120.625054 -246.910545) (xy 120.598305 -246.912832) (xy 120.573077 -246.922015)
			(xy 120.561862 -246.929402) (xy 120.540882 -246.943661) (xy 120.495451 -246.966229) (xy 120.447105 -246.981588)
			(xy 120.396979 -246.989375) (xy 120.371616 -246.989854) (xy 120.344318 -246.989305) (xy 120.290465 -246.980326)
			(xy 120.238824 -246.96261) (xy 120.1908 -246.936639) (xy 120.147703 -246.903122) (xy 120.128792 -246.883428)
			(xy 120.118959 -246.873448) (xy 120.095075 -246.858822) (xy 120.068119 -246.851223) (xy 120.040113 -246.851223)
			(xy 120.013157 -246.858822) (xy 119.989273 -246.873448) (xy 119.97944 -246.883428) (xy 119.962295 -246.901373)
			(xy 119.923579 -246.932425) (xy 119.880652 -246.957333) (xy 119.834481 -246.975536) (xy 119.786106 -246.986625)
			(xy 119.736616 -246.990349) (xy 119.687126 -246.986625) (xy 119.638751 -246.975536) (xy 119.59258 -246.957333)
			(xy 119.549653 -246.932425) (xy 119.510937 -246.901373) (xy 119.493792 -246.883428) (xy 119.483959 -246.873448)
			(xy 119.460075 -246.858822) (xy 119.433119 -246.851223) (xy 119.405113 -246.851223) (xy 119.378157 -246.858822)
			(xy 119.354273 -246.873448) (xy 119.34444 -246.883428) (xy 119.325524 -246.903116) (xy 119.282425 -246.936627)
			(xy 119.234402 -246.962594) (xy 119.182763 -246.980309) (xy 119.128913 -246.989291) (xy 119.101616 -246.989854)
			(xy 119.077229 -246.98945) (xy 119.028983 -246.982294) (xy 118.982314 -246.968121) (xy 118.938237 -246.947238)
			(xy 118.89771 -246.9201) (xy 118.861616 -246.887297) (xy 118.845838 -246.868696) (xy 118.835917 -246.857461)
			(xy 118.811 -246.840831) (xy 118.782331 -246.832143) (xy 118.752373 -246.832143) (xy 118.723704 -246.840831)
			(xy 118.698787 -246.857461) (xy 118.688866 -246.868696) (xy 118.673054 -246.887263) (xy 118.636954 -246.920047)
			(xy 118.596431 -246.947174) (xy 118.552362 -246.968055) (xy 118.505705 -246.982237) (xy 118.45747 -246.989412)
			(xy 118.433088 -246.989854) (xy 118.407767 -246.989343) (xy 118.357715 -246.981634) (xy 118.309424 -246.966381)
			(xy 118.264024 -246.943943) (xy 118.222577 -246.914843) (xy 118.20398 -246.897652) (xy 118.19414 -246.888725)
			(xy 118.170925 -246.875824) (xy 118.145164 -246.869366) (xy 118.118609 -246.86979) (xy 118.093068 -246.877068)
			(xy 118.070278 -246.890705) (xy 118.060724 -246.899938) (xy 118.04195 -246.918522) (xy 117.999556 -246.950036)
			(xy 117.952693 -246.974413) (xy 117.902552 -246.991033) (xy 117.850407 -246.999474) (xy 117.823996 -247.000014)
			(xy 117.797415 -246.999483) (xy 117.744938 -246.990978) (xy 117.694497 -246.974187) (xy 117.647392 -246.949544)
			(xy 117.604835 -246.917683) (xy 117.585998 -246.898922) (xy 117.576227 -246.889397) (xy 117.552785 -246.875453)
			(xy 117.526484 -246.868223) (xy 117.499208 -246.868223) (xy 117.472907 -246.875453) (xy 117.449465 -246.889397)
			(xy 117.439694 -246.898922) (xy 117.420861 -246.917688) (xy 117.378303 -246.949548) (xy 117.331197 -246.974191)
			(xy 117.280755 -246.99098) (xy 117.228277 -246.999484) (xy 117.201696 -247.000014) (xy 117.175726 -246.999584)
			(xy 117.124425 -246.991459) (xy 117.075027 -246.975408) (xy 117.028748 -246.951827) (xy 116.986728 -246.921297)
			(xy 116.950001 -246.884569) (xy 116.919471 -246.842548) (xy 116.895891 -246.796269) (xy 116.879841 -246.746871)
			(xy 116.871715 -246.69557) (xy 116.762945 -246.69557) (xy 116.756436 -246.736662) (xy 116.740388 -246.786055)
			(xy 116.71681 -246.832329) (xy 116.686284 -246.874345) (xy 116.649561 -246.911068) (xy 116.607545 -246.941594)
			(xy 116.561271 -246.965172) (xy 116.511878 -246.98122) (xy 116.460583 -246.989345) (xy 116.408649 -246.989345)
			(xy 116.357354 -246.98122) (xy 116.307961 -246.965172) (xy 116.261687 -246.941594) (xy 116.219671 -246.911068)
			(xy 116.182948 -246.874345) (xy 116.152422 -246.832329) (xy 116.128844 -246.786055) (xy 116.112796 -246.736662)
			(xy 116.104671 -246.685367) (xy 115.478186 -246.685367) (xy 115.472747 -246.703146) (xy 115.451623 -246.747418)
			(xy 115.424189 -246.788082) (xy 115.407948 -246.806466) (xy 115.398098 -246.817919) (xy 115.385086 -246.845169)
			(xy 115.380625 -246.875034) (xy 115.385106 -246.904897) (xy 115.398136 -246.932137) (xy 115.407948 -246.943626)
			(xy 115.424169 -246.962028) (xy 115.45162 -247.002681) (xy 115.472756 -247.046947) (xy 115.48711 -247.093853)
			(xy 115.494368 -247.142366) (xy 115.494816 -247.166892) (xy 115.494816 -247.167146) (xy 115.494387 -247.193116)
			(xy 115.486255 -247.244417) (xy 115.470197 -247.293813) (xy 115.446611 -247.34009) (xy 115.416075 -247.382107)
			(xy 115.379343 -247.41883) (xy 115.337318 -247.449355) (xy 115.291035 -247.47293) (xy 115.241635 -247.488974)
			(xy 115.190332 -247.497094) (xy 115.164362 -247.4976) (xy 115.138558 -247.497094) (xy 115.087577 -247.48908)
			(xy 115.038462 -247.473235) (xy 114.992407 -247.449947) (xy 114.950534 -247.419781) (xy 114.913861 -247.383471)
			(xy 114.89817 -247.36298) (xy 114.889641 -247.352047) (xy 114.867839 -247.334927) (xy 114.842235 -247.324305)
			(xy 114.814716 -247.320967) (xy 114.787314 -247.325158) (xy 114.762051 -247.336569) (xy 114.740792 -247.354358)
			(xy 114.732562 -247.36552) (xy 114.717032 -247.387267) (xy 114.680097 -247.425884) (xy 114.637433 -247.458058)
			(xy 114.59015 -247.482952) (xy 114.539478 -247.499919) (xy 114.486738 -247.508515) (xy 114.46002 -247.50903)
			(xy 114.434048 -247.508597) (xy 114.382743 -247.500473) (xy 114.33334 -247.484424) (xy 114.287056 -247.460844)
			(xy 114.245031 -247.430313) (xy 114.2083 -247.393584) (xy 114.177767 -247.351561) (xy 114.154183 -247.305279)
			(xy 114.138131 -247.255877) (xy 114.130005 -247.204572) (xy 113.85016 -247.204572) (xy 113.84204 -247.255838)
			(xy 113.825992 -247.305231) (xy 113.802414 -247.351505) (xy 113.771888 -247.393521) (xy 113.735165 -247.430244)
			(xy 113.693149 -247.46077) (xy 113.646875 -247.484348) (xy 113.597482 -247.500396) (xy 113.546187 -247.508521)
			(xy 113.494253 -247.508521) (xy 113.442958 -247.500396) (xy 113.393565 -247.484348) (xy 113.347291 -247.46077)
			(xy 113.305275 -247.430244) (xy 113.268552 -247.393521) (xy 113.238026 -247.351505) (xy 113.214448 -247.305231)
			(xy 113.1984 -247.255838) (xy 113.190275 -247.204543) (xy 112.910111 -247.204543) (xy 112.901986 -247.255838)
			(xy 112.885938 -247.305231) (xy 112.86236 -247.351505) (xy 112.831834 -247.393521) (xy 112.795111 -247.430244)
			(xy 112.753095 -247.46077) (xy 112.706821 -247.484348) (xy 112.657428 -247.500396) (xy 112.606133 -247.508521)
			(xy 112.554199 -247.508521) (xy 112.502904 -247.500396) (xy 112.453511 -247.484348) (xy 112.407237 -247.46077)
			(xy 112.365221 -247.430244) (xy 112.328498 -247.393521) (xy 112.297972 -247.351505) (xy 112.274394 -247.305231)
			(xy 112.258346 -247.255838) (xy 112.250221 -247.204543) (xy 111.970311 -247.204543) (xy 111.962186 -247.255838)
			(xy 111.946138 -247.305231) (xy 111.92256 -247.351505) (xy 111.892034 -247.393521) (xy 111.855311 -247.430244)
			(xy 111.813295 -247.46077) (xy 111.767021 -247.484348) (xy 111.717628 -247.500396) (xy 111.666333 -247.508521)
			(xy 111.614399 -247.508521) (xy 111.563104 -247.500396) (xy 111.513711 -247.484348) (xy 111.467437 -247.46077)
			(xy 111.425421 -247.430244) (xy 111.388698 -247.393521) (xy 111.358172 -247.351505) (xy 111.334594 -247.305231)
			(xy 111.318546 -247.255838) (xy 111.310421 -247.204543) (xy 111.030765 -247.204543) (xy 111.02264 -247.255838)
			(xy 111.006592 -247.305231) (xy 110.983014 -247.351505) (xy 110.952488 -247.393521) (xy 110.915765 -247.430244)
			(xy 110.873749 -247.46077) (xy 110.827475 -247.484348) (xy 110.778082 -247.500396) (xy 110.726787 -247.508521)
			(xy 110.674853 -247.508521) (xy 110.623558 -247.500396) (xy 110.574165 -247.484348) (xy 110.527891 -247.46077)
			(xy 110.485875 -247.430244) (xy 110.449152 -247.393521) (xy 110.418626 -247.351505) (xy 110.395048 -247.305231)
			(xy 110.379 -247.255838) (xy 110.370875 -247.204543) (xy 110.090711 -247.204543) (xy 110.082586 -247.255838)
			(xy 110.066538 -247.305231) (xy 110.04296 -247.351505) (xy 110.012434 -247.393521) (xy 109.975711 -247.430244)
			(xy 109.933695 -247.46077) (xy 109.887421 -247.484348) (xy 109.838028 -247.500396) (xy 109.786733 -247.508521)
			(xy 109.734799 -247.508521) (xy 109.683504 -247.500396) (xy 109.634111 -247.484348) (xy 109.587837 -247.46077)
			(xy 109.545821 -247.430244) (xy 109.509098 -247.393521) (xy 109.478572 -247.351505) (xy 109.454994 -247.305231)
			(xy 109.438946 -247.255838) (xy 109.430821 -247.204543) (xy 102.572271 -247.204543) (xy 102.564186 -247.255584)
			(xy 102.548138 -247.304977) (xy 102.52456 -247.351251) (xy 102.494034 -247.393267) (xy 102.457311 -247.42999)
			(xy 102.415295 -247.460516) (xy 102.369021 -247.484094) (xy 102.319628 -247.500142) (xy 102.268333 -247.508267)
			(xy 102.216399 -247.508267) (xy 102.165104 -247.500142) (xy 102.115711 -247.484094) (xy 102.069437 -247.460516)
			(xy 102.027421 -247.42999) (xy 101.990698 -247.393267) (xy 101.960172 -247.351251) (xy 101.936594 -247.304977)
			(xy 101.920546 -247.255584) (xy 101.912421 -247.204289) (xy 101.632511 -247.204289) (xy 101.624386 -247.255584)
			(xy 101.608338 -247.304977) (xy 101.58476 -247.351251) (xy 101.554234 -247.393267) (xy 101.517511 -247.42999)
			(xy 101.475495 -247.460516) (xy 101.429221 -247.484094) (xy 101.379828 -247.500142) (xy 101.328533 -247.508267)
			(xy 101.276599 -247.508267) (xy 101.225304 -247.500142) (xy 101.175911 -247.484094) (xy 101.129637 -247.460516)
			(xy 101.087621 -247.42999) (xy 101.050898 -247.393267) (xy 101.020372 -247.351251) (xy 100.996794 -247.304977)
			(xy 100.980746 -247.255584) (xy 100.972621 -247.204289) (xy 100.692711 -247.204289) (xy 100.684586 -247.255584)
			(xy 100.668538 -247.304977) (xy 100.64496 -247.351251) (xy 100.614434 -247.393267) (xy 100.577711 -247.42999)
			(xy 100.535695 -247.460516) (xy 100.489421 -247.484094) (xy 100.440028 -247.500142) (xy 100.388733 -247.508267)
			(xy 100.336799 -247.508267) (xy 100.285504 -247.500142) (xy 100.236111 -247.484094) (xy 100.189837 -247.460516)
			(xy 100.147821 -247.42999) (xy 100.111098 -247.393267) (xy 100.080572 -247.351251) (xy 100.056994 -247.304977)
			(xy 100.040946 -247.255584) (xy 100.032821 -247.204289) (xy 99.752911 -247.204289) (xy 99.744786 -247.255584)
			(xy 99.728738 -247.304977) (xy 99.70516 -247.351251) (xy 99.674634 -247.393267) (xy 99.637911 -247.42999)
			(xy 99.595895 -247.460516) (xy 99.549621 -247.484094) (xy 99.500228 -247.500142) (xy 99.448933 -247.508267)
			(xy 99.396999 -247.508267) (xy 99.345704 -247.500142) (xy 99.296311 -247.484094) (xy 99.250037 -247.460516)
			(xy 99.208021 -247.42999) (xy 99.171298 -247.393267) (xy 99.140772 -247.351251) (xy 99.117194 -247.304977)
			(xy 99.101146 -247.255584) (xy 99.093021 -247.204289) (xy 98.812857 -247.204289) (xy 98.804732 -247.255584)
			(xy 98.788684 -247.304977) (xy 98.765106 -247.351251) (xy 98.73458 -247.393267) (xy 98.697857 -247.42999)
			(xy 98.655841 -247.460516) (xy 98.609567 -247.484094) (xy 98.560174 -247.500142) (xy 98.508879 -247.508267)
			(xy 98.456945 -247.508267) (xy 98.40565 -247.500142) (xy 98.356257 -247.484094) (xy 98.309983 -247.460516)
			(xy 98.267967 -247.42999) (xy 98.231244 -247.393267) (xy 98.200718 -247.351251) (xy 98.17714 -247.304977)
			(xy 98.161092 -247.255584) (xy 98.152967 -247.204289) (xy 97.873311 -247.204289) (xy 97.865186 -247.255584)
			(xy 97.849138 -247.304977) (xy 97.82556 -247.351251) (xy 97.795034 -247.393267) (xy 97.758311 -247.42999)
			(xy 97.716295 -247.460516) (xy 97.670021 -247.484094) (xy 97.620628 -247.500142) (xy 97.569333 -247.508267)
			(xy 97.517399 -247.508267) (xy 97.466104 -247.500142) (xy 97.416711 -247.484094) (xy 97.370437 -247.460516)
			(xy 97.328421 -247.42999) (xy 97.291698 -247.393267) (xy 97.261172 -247.351251) (xy 97.237594 -247.304977)
			(xy 97.221546 -247.255584) (xy 97.213421 -247.204289) (xy 96.933257 -247.204289) (xy 96.925132 -247.255584)
			(xy 96.909084 -247.304977) (xy 96.885506 -247.351251) (xy 96.85498 -247.393267) (xy 96.818257 -247.42999)
			(xy 96.776241 -247.460516) (xy 96.729967 -247.484094) (xy 96.680574 -247.500142) (xy 96.629279 -247.508267)
			(xy 96.577345 -247.508267) (xy 96.52605 -247.500142) (xy 96.476657 -247.484094) (xy 96.430383 -247.460516)
			(xy 96.388367 -247.42999) (xy 96.351644 -247.393267) (xy 96.321118 -247.351251) (xy 96.29754 -247.304977)
			(xy 96.281492 -247.255584) (xy 96.273367 -247.204289) (xy 95.993711 -247.204289) (xy 95.985586 -247.255584)
			(xy 95.969538 -247.304977) (xy 95.94596 -247.351251) (xy 95.915434 -247.393267) (xy 95.878711 -247.42999)
			(xy 95.836695 -247.460516) (xy 95.790421 -247.484094) (xy 95.741028 -247.500142) (xy 95.689733 -247.508267)
			(xy 95.637799 -247.508267) (xy 95.586504 -247.500142) (xy 95.537111 -247.484094) (xy 95.490837 -247.460516)
			(xy 95.448821 -247.42999) (xy 95.412098 -247.393267) (xy 95.381572 -247.351251) (xy 95.357994 -247.304977)
			(xy 95.341946 -247.255584) (xy 95.333821 -247.204289) (xy 95.054127 -247.204289) (xy 95.046482 -247.253838)
			(xy 95.031178 -247.302215) (xy 95.008667 -247.347687) (xy 94.979475 -247.389188) (xy 94.944288 -247.425744)
			(xy 94.924372 -247.441466) (xy 94.92107 -247.444006) (xy 94.914213 -247.450747) (xy 94.905739 -247.467989)
			(xy 94.90456 -247.477534) (xy 94.90202 -247.515888) (xy 94.89948 -247.55348) (xy 94.899267 -247.56417)
			(xy 94.906773 -247.584169) (xy 94.913958 -247.592088) (xy 95.002096 -247.680226) (xy 95.009425 -247.686769)
			(xy 95.027589 -247.694207) (xy 95.037402 -247.694704) (xy 95.057722 -247.690386) (xy 95.062294 -247.688354)
			(xy 95.083035 -247.679824) (xy 95.126243 -247.667818) (xy 95.170681 -247.66178) (xy 95.193104 -247.66143)
			(xy 95.193612 -247.66143) (xy 95.2196 -247.661914) (xy 95.270934 -247.670047) (xy 95.320365 -247.686111)
			(xy 95.366674 -247.70971) (xy 95.40872 -247.740263) (xy 95.44547 -247.777018) (xy 95.476016 -247.819069)
			(xy 95.499608 -247.865381) (xy 95.515665 -247.914814) (xy 95.52379 -247.96615) (xy 95.52432 -247.992138)
			(xy 95.52432 -247.992646) (xy 95.52394 -248.015066) (xy 95.523525 -248.018105) (xy 95.803721 -248.018105)
			(xy 95.803721 -247.966171) (xy 95.811846 -247.914876) (xy 95.827894 -247.865483) (xy 95.851472 -247.819209)
			(xy 95.881998 -247.777193) (xy 95.918721 -247.74047) (xy 95.960737 -247.709944) (xy 96.007011 -247.686366)
			(xy 96.056404 -247.670318) (xy 96.107699 -247.662193) (xy 96.159633 -247.662193) (xy 96.210928 -247.670318)
			(xy 96.260321 -247.686366) (xy 96.306595 -247.709944) (xy 96.348611 -247.74047) (xy 96.385334 -247.777193)
			(xy 96.41586 -247.819209) (xy 96.439438 -247.865483) (xy 96.455486 -247.914876) (xy 96.463611 -247.966171)
			(xy 96.46412 -247.992138) (xy 96.463611 -248.018105) (xy 96.743267 -248.018105) (xy 96.743267 -247.966171)
			(xy 96.751392 -247.914876) (xy 96.76744 -247.865483) (xy 96.791018 -247.819209) (xy 96.821544 -247.777193)
			(xy 96.858267 -247.74047) (xy 96.900283 -247.709944) (xy 96.946557 -247.686366) (xy 96.99595 -247.670318)
			(xy 97.047245 -247.662193) (xy 97.099179 -247.662193) (xy 97.150474 -247.670318) (xy 97.199867 -247.686366)
			(xy 97.246141 -247.709944) (xy 97.288157 -247.74047) (xy 97.32488 -247.777193) (xy 97.355406 -247.819209)
			(xy 97.378984 -247.865483) (xy 97.395032 -247.914876) (xy 97.403157 -247.966171) (xy 97.403666 -247.992138)
			(xy 97.403157 -248.018105) (xy 97.683321 -248.018105) (xy 97.683321 -247.966171) (xy 97.691446 -247.914876)
			(xy 97.707494 -247.865483) (xy 97.731072 -247.819209) (xy 97.761598 -247.777193) (xy 97.798321 -247.74047)
			(xy 97.840337 -247.709944) (xy 97.886611 -247.686366) (xy 97.936004 -247.670318) (xy 97.987299 -247.662193)
			(xy 98.039233 -247.662193) (xy 98.090528 -247.670318) (xy 98.139921 -247.686366) (xy 98.186195 -247.709944)
			(xy 98.228211 -247.74047) (xy 98.264934 -247.777193) (xy 98.29546 -247.819209) (xy 98.319038 -247.865483)
			(xy 98.335086 -247.914876) (xy 98.343211 -247.966171) (xy 98.34372 -247.992138) (xy 98.343211 -248.018105)
			(xy 98.623121 -248.018105) (xy 98.623121 -247.966171) (xy 98.631246 -247.914876) (xy 98.647294 -247.865483)
			(xy 98.670872 -247.819209) (xy 98.701398 -247.777193) (xy 98.738121 -247.74047) (xy 98.780137 -247.709944)
			(xy 98.826411 -247.686366) (xy 98.875804 -247.670318) (xy 98.927099 -247.662193) (xy 98.979033 -247.662193)
			(xy 99.030328 -247.670318) (xy 99.079721 -247.686366) (xy 99.125995 -247.709944) (xy 99.168011 -247.74047)
			(xy 99.204734 -247.777193) (xy 99.23526 -247.819209) (xy 99.258838 -247.865483) (xy 99.274886 -247.914876)
			(xy 99.283011 -247.966171) (xy 99.28352 -247.992138) (xy 99.283011 -248.018105) (xy 99.562667 -248.018105)
			(xy 99.562667 -247.966171) (xy 99.570792 -247.914876) (xy 99.58684 -247.865483) (xy 99.610418 -247.819209)
			(xy 99.640944 -247.777193) (xy 99.677667 -247.74047) (xy 99.719683 -247.709944) (xy 99.765957 -247.686366)
			(xy 99.81535 -247.670318) (xy 99.866645 -247.662193) (xy 99.918579 -247.662193) (xy 99.969874 -247.670318)
			(xy 100.019267 -247.686366) (xy 100.065541 -247.709944) (xy 100.107557 -247.74047) (xy 100.14428 -247.777193)
			(xy 100.174806 -247.819209) (xy 100.198384 -247.865483) (xy 100.214432 -247.914876) (xy 100.222557 -247.966171)
			(xy 100.223066 -247.992138) (xy 100.222557 -248.018105) (xy 100.502467 -248.018105) (xy 100.502467 -247.966171)
			(xy 100.510592 -247.914876) (xy 100.52664 -247.865483) (xy 100.550218 -247.819209) (xy 100.580744 -247.777193)
			(xy 100.617467 -247.74047) (xy 100.659483 -247.709944) (xy 100.705757 -247.686366) (xy 100.75515 -247.670318)
			(xy 100.806445 -247.662193) (xy 100.858379 -247.662193) (xy 100.909674 -247.670318) (xy 100.959067 -247.686366)
			(xy 101.005341 -247.709944) (xy 101.047357 -247.74047) (xy 101.08408 -247.777193) (xy 101.114606 -247.819209)
			(xy 101.138184 -247.865483) (xy 101.154232 -247.914876) (xy 101.162357 -247.966171) (xy 101.162866 -247.992138)
			(xy 101.162357 -248.018105) (xy 101.442267 -248.018105) (xy 101.442267 -247.966171) (xy 101.450392 -247.914876)
			(xy 101.46644 -247.865483) (xy 101.490018 -247.819209) (xy 101.520544 -247.777193) (xy 101.557267 -247.74047)
			(xy 101.599283 -247.709944) (xy 101.645557 -247.686366) (xy 101.69495 -247.670318) (xy 101.746245 -247.662193)
			(xy 101.798179 -247.662193) (xy 101.849474 -247.670318) (xy 101.898867 -247.686366) (xy 101.945141 -247.709944)
			(xy 101.987157 -247.74047) (xy 102.02388 -247.777193) (xy 102.054406 -247.819209) (xy 102.077984 -247.865483)
			(xy 102.094032 -247.914876) (xy 102.102157 -247.966171) (xy 102.102666 -247.992138) (xy 102.102157 -248.018105)
			(xy 102.102117 -248.018359) (xy 108.958127 -248.018359) (xy 108.958127 -247.966425) (xy 108.966252 -247.91513)
			(xy 108.9823 -247.865737) (xy 109.005878 -247.819463) (xy 109.036404 -247.777447) (xy 109.073127 -247.740724)
			(xy 109.115143 -247.710198) (xy 109.161417 -247.68662) (xy 109.21081 -247.670572) (xy 109.262105 -247.662447)
			(xy 109.314039 -247.662447) (xy 109.365334 -247.670572) (xy 109.414727 -247.68662) (xy 109.461001 -247.710198)
			(xy 109.503017 -247.740724) (xy 109.53974 -247.777447) (xy 109.570266 -247.819463) (xy 109.593844 -247.865737)
			(xy 109.609892 -247.91513) (xy 109.618017 -247.966425) (xy 109.618526 -247.992392) (xy 109.618017 -248.018359)
			(xy 109.900975 -248.018359) (xy 109.900975 -247.966425) (xy 109.9091 -247.91513) (xy 109.925148 -247.865737)
			(xy 109.948726 -247.819463) (xy 109.979252 -247.777447) (xy 110.015975 -247.740724) (xy 110.057991 -247.710198)
			(xy 110.104265 -247.68662) (xy 110.153658 -247.670572) (xy 110.204953 -247.662447) (xy 110.256887 -247.662447)
			(xy 110.308182 -247.670572) (xy 110.357575 -247.68662) (xy 110.403849 -247.710198) (xy 110.445865 -247.740724)
			(xy 110.482588 -247.777447) (xy 110.513114 -247.819463) (xy 110.536692 -247.865737) (xy 110.55274 -247.91513)
			(xy 110.560865 -247.966425) (xy 110.561374 -247.992392) (xy 110.560865 -248.018359) (xy 110.840775 -248.018359)
			(xy 110.840775 -247.966425) (xy 110.8489 -247.91513) (xy 110.864948 -247.865737) (xy 110.888526 -247.819463)
			(xy 110.919052 -247.777447) (xy 110.955775 -247.740724) (xy 110.997791 -247.710198) (xy 111.044065 -247.68662)
			(xy 111.093458 -247.670572) (xy 111.144753 -247.662447) (xy 111.196687 -247.662447) (xy 111.247982 -247.670572)
			(xy 111.297375 -247.68662) (xy 111.343649 -247.710198) (xy 111.385665 -247.740724) (xy 111.422388 -247.777447)
			(xy 111.452914 -247.819463) (xy 111.476492 -247.865737) (xy 111.49254 -247.91513) (xy 111.500665 -247.966425)
			(xy 111.501174 -247.992392) (xy 111.500665 -248.018359) (xy 111.780575 -248.018359) (xy 111.780575 -247.966425)
			(xy 111.7887 -247.91513) (xy 111.804748 -247.865737) (xy 111.828326 -247.819463) (xy 111.858852 -247.777447)
			(xy 111.895575 -247.740724) (xy 111.937591 -247.710198) (xy 111.983865 -247.68662) (xy 112.033258 -247.670572)
			(xy 112.084553 -247.662447) (xy 112.136487 -247.662447) (xy 112.187782 -247.670572) (xy 112.237175 -247.68662)
			(xy 112.283449 -247.710198) (xy 112.325465 -247.740724) (xy 112.362188 -247.777447) (xy 112.392714 -247.819463)
			(xy 112.416292 -247.865737) (xy 112.43234 -247.91513) (xy 112.440465 -247.966425) (xy 112.440974 -247.992392)
			(xy 112.440465 -248.018359) (xy 112.720121 -248.018359) (xy 112.720121 -247.966425) (xy 112.728246 -247.91513)
			(xy 112.744294 -247.865737) (xy 112.767872 -247.819463) (xy 112.798398 -247.777447) (xy 112.835121 -247.740724)
			(xy 112.877137 -247.710198) (xy 112.923411 -247.68662) (xy 112.972804 -247.670572) (xy 113.024099 -247.662447)
			(xy 113.076033 -247.662447) (xy 113.127328 -247.670572) (xy 113.176721 -247.68662) (xy 113.222995 -247.710198)
			(xy 113.265011 -247.740724) (xy 113.301734 -247.777447) (xy 113.33226 -247.819463) (xy 113.355838 -247.865737)
			(xy 113.371886 -247.91513) (xy 113.380011 -247.966425) (xy 113.38052 -247.992392) (xy 113.380011 -248.018359)
			(xy 113.660175 -248.018359) (xy 113.660175 -247.966425) (xy 113.6683 -247.91513) (xy 113.684348 -247.865737)
			(xy 113.707926 -247.819463) (xy 113.738452 -247.777447) (xy 113.775175 -247.740724) (xy 113.817191 -247.710198)
			(xy 113.863465 -247.68662) (xy 113.912858 -247.670572) (xy 113.964153 -247.662447) (xy 114.016087 -247.662447)
			(xy 114.067382 -247.670572) (xy 114.116775 -247.68662) (xy 114.163049 -247.710198) (xy 114.205065 -247.740724)
			(xy 114.241788 -247.777447) (xy 114.272314 -247.819463) (xy 114.295892 -247.865737) (xy 114.31194 -247.91513)
			(xy 114.320065 -247.966425) (xy 114.320574 -247.992392) (xy 114.320065 -248.018359) (xy 114.31194 -248.069654)
			(xy 114.295892 -248.119047) (xy 114.272314 -248.165321) (xy 114.241788 -248.207337) (xy 114.205065 -248.24406)
			(xy 114.163049 -248.274586) (xy 114.116775 -248.298164) (xy 114.067382 -248.314212) (xy 114.016087 -248.322337)
			(xy 113.964153 -248.322337) (xy 113.912858 -248.314212) (xy 113.863465 -248.298164) (xy 113.817191 -248.274586)
			(xy 113.775175 -248.24406) (xy 113.738452 -248.207337) (xy 113.707926 -248.165321) (xy 113.684348 -248.119047)
			(xy 113.6683 -248.069654) (xy 113.660175 -248.018359) (xy 113.380011 -248.018359) (xy 113.371886 -248.069654)
			(xy 113.355838 -248.119047) (xy 113.33226 -248.165321) (xy 113.301734 -248.207337) (xy 113.265011 -248.24406)
			(xy 113.222995 -248.274586) (xy 113.176721 -248.298164) (xy 113.127328 -248.314212) (xy 113.076033 -248.322337)
			(xy 113.024099 -248.322337) (xy 112.972804 -248.314212) (xy 112.923411 -248.298164) (xy 112.877137 -248.274586)
			(xy 112.835121 -248.24406) (xy 112.798398 -248.207337) (xy 112.767872 -248.165321) (xy 112.744294 -248.119047)
			(xy 112.728246 -248.069654) (xy 112.720121 -248.018359) (xy 112.440465 -248.018359) (xy 112.43234 -248.069654)
			(xy 112.416292 -248.119047) (xy 112.392714 -248.165321) (xy 112.362188 -248.207337) (xy 112.325465 -248.24406)
			(xy 112.283449 -248.274586) (xy 112.237175 -248.298164) (xy 112.187782 -248.314212) (xy 112.136487 -248.322337)
			(xy 112.084553 -248.322337) (xy 112.033258 -248.314212) (xy 111.983865 -248.298164) (xy 111.937591 -248.274586)
			(xy 111.895575 -248.24406) (xy 111.858852 -248.207337) (xy 111.828326 -248.165321) (xy 111.804748 -248.119047)
			(xy 111.7887 -248.069654) (xy 111.780575 -248.018359) (xy 111.500665 -248.018359) (xy 111.49254 -248.069654)
			(xy 111.476492 -248.119047) (xy 111.452914 -248.165321) (xy 111.422388 -248.207337) (xy 111.385665 -248.24406)
			(xy 111.343649 -248.274586) (xy 111.297375 -248.298164) (xy 111.247982 -248.314212) (xy 111.196687 -248.322337)
			(xy 111.144753 -248.322337) (xy 111.093458 -248.314212) (xy 111.044065 -248.298164) (xy 110.997791 -248.274586)
			(xy 110.955775 -248.24406) (xy 110.919052 -248.207337) (xy 110.888526 -248.165321) (xy 110.864948 -248.119047)
			(xy 110.8489 -248.069654) (xy 110.840775 -248.018359) (xy 110.560865 -248.018359) (xy 110.55274 -248.069654)
			(xy 110.536692 -248.119047) (xy 110.513114 -248.165321) (xy 110.482588 -248.207337) (xy 110.445865 -248.24406)
			(xy 110.403849 -248.274586) (xy 110.357575 -248.298164) (xy 110.308182 -248.314212) (xy 110.256887 -248.322337)
			(xy 110.204953 -248.322337) (xy 110.153658 -248.314212) (xy 110.104265 -248.298164) (xy 110.057991 -248.274586)
			(xy 110.015975 -248.24406) (xy 109.979252 -248.207337) (xy 109.948726 -248.165321) (xy 109.925148 -248.119047)
			(xy 109.9091 -248.069654) (xy 109.900975 -248.018359) (xy 109.618017 -248.018359) (xy 109.609892 -248.069654)
			(xy 109.593844 -248.119047) (xy 109.570266 -248.165321) (xy 109.53974 -248.207337) (xy 109.503017 -248.24406)
			(xy 109.461001 -248.274586) (xy 109.414727 -248.298164) (xy 109.365334 -248.314212) (xy 109.314039 -248.322337)
			(xy 109.262105 -248.322337) (xy 109.21081 -248.314212) (xy 109.161417 -248.298164) (xy 109.115143 -248.274586)
			(xy 109.073127 -248.24406) (xy 109.036404 -248.207337) (xy 109.005878 -248.165321) (xy 108.9823 -248.119047)
			(xy 108.966252 -248.069654) (xy 108.958127 -248.018359) (xy 102.102117 -248.018359) (xy 102.094032 -248.0694)
			(xy 102.077984 -248.118793) (xy 102.054406 -248.165067) (xy 102.02388 -248.207083) (xy 101.987157 -248.243806)
			(xy 101.945141 -248.274332) (xy 101.898867 -248.29791) (xy 101.849474 -248.313958) (xy 101.798179 -248.322083)
			(xy 101.746245 -248.322083) (xy 101.69495 -248.313958) (xy 101.645557 -248.29791) (xy 101.599283 -248.274332)
			(xy 101.557267 -248.243806) (xy 101.520544 -248.207083) (xy 101.490018 -248.165067) (xy 101.46644 -248.118793)
			(xy 101.450392 -248.0694) (xy 101.442267 -248.018105) (xy 101.162357 -248.018105) (xy 101.154232 -248.0694)
			(xy 101.138184 -248.118793) (xy 101.114606 -248.165067) (xy 101.08408 -248.207083) (xy 101.047357 -248.243806)
			(xy 101.005341 -248.274332) (xy 100.959067 -248.29791) (xy 100.909674 -248.313958) (xy 100.858379 -248.322083)
			(xy 100.806445 -248.322083) (xy 100.75515 -248.313958) (xy 100.705757 -248.29791) (xy 100.659483 -248.274332)
			(xy 100.617467 -248.243806) (xy 100.580744 -248.207083) (xy 100.550218 -248.165067) (xy 100.52664 -248.118793)
			(xy 100.510592 -248.0694) (xy 100.502467 -248.018105) (xy 100.222557 -248.018105) (xy 100.214432 -248.0694)
			(xy 100.198384 -248.118793) (xy 100.174806 -248.165067) (xy 100.14428 -248.207083) (xy 100.107557 -248.243806)
			(xy 100.065541 -248.274332) (xy 100.019267 -248.29791) (xy 99.969874 -248.313958) (xy 99.918579 -248.322083)
			(xy 99.866645 -248.322083) (xy 99.81535 -248.313958) (xy 99.765957 -248.29791) (xy 99.719683 -248.274332)
			(xy 99.677667 -248.243806) (xy 99.640944 -248.207083) (xy 99.610418 -248.165067) (xy 99.58684 -248.118793)
			(xy 99.570792 -248.0694) (xy 99.562667 -248.018105) (xy 99.283011 -248.018105) (xy 99.274886 -248.0694)
			(xy 99.258838 -248.118793) (xy 99.23526 -248.165067) (xy 99.204734 -248.207083) (xy 99.168011 -248.243806)
			(xy 99.125995 -248.274332) (xy 99.079721 -248.29791) (xy 99.030328 -248.313958) (xy 98.979033 -248.322083)
			(xy 98.927099 -248.322083) (xy 98.875804 -248.313958) (xy 98.826411 -248.29791) (xy 98.780137 -248.274332)
			(xy 98.738121 -248.243806) (xy 98.701398 -248.207083) (xy 98.670872 -248.165067) (xy 98.647294 -248.118793)
			(xy 98.631246 -248.0694) (xy 98.623121 -248.018105) (xy 98.343211 -248.018105) (xy 98.335086 -248.0694)
			(xy 98.319038 -248.118793) (xy 98.29546 -248.165067) (xy 98.264934 -248.207083) (xy 98.228211 -248.243806)
			(xy 98.186195 -248.274332) (xy 98.139921 -248.29791) (xy 98.090528 -248.313958) (xy 98.039233 -248.322083)
			(xy 97.987299 -248.322083) (xy 97.936004 -248.313958) (xy 97.886611 -248.29791) (xy 97.840337 -248.274332)
			(xy 97.798321 -248.243806) (xy 97.761598 -248.207083) (xy 97.731072 -248.165067) (xy 97.707494 -248.118793)
			(xy 97.691446 -248.0694) (xy 97.683321 -248.018105) (xy 97.403157 -248.018105) (xy 97.395032 -248.0694)
			(xy 97.378984 -248.118793) (xy 97.355406 -248.165067) (xy 97.32488 -248.207083) (xy 97.288157 -248.243806)
			(xy 97.246141 -248.274332) (xy 97.199867 -248.29791) (xy 97.150474 -248.313958) (xy 97.099179 -248.322083)
			(xy 97.047245 -248.322083) (xy 96.99595 -248.313958) (xy 96.946557 -248.29791) (xy 96.900283 -248.274332)
			(xy 96.858267 -248.243806) (xy 96.821544 -248.207083) (xy 96.791018 -248.165067) (xy 96.76744 -248.118793)
			(xy 96.751392 -248.0694) (xy 96.743267 -248.018105) (xy 96.463611 -248.018105) (xy 96.455486 -248.0694)
			(xy 96.439438 -248.118793) (xy 96.41586 -248.165067) (xy 96.385334 -248.207083) (xy 96.348611 -248.243806)
			(xy 96.306595 -248.274332) (xy 96.260321 -248.29791) (xy 96.210928 -248.313958) (xy 96.159633 -248.322083)
			(xy 96.107699 -248.322083) (xy 96.056404 -248.313958) (xy 96.007011 -248.29791) (xy 95.960737 -248.274332)
			(xy 95.918721 -248.243806) (xy 95.881998 -248.207083) (xy 95.851472 -248.165067) (xy 95.827894 -248.118793)
			(xy 95.811846 -248.0694) (xy 95.803721 -248.018105) (xy 95.523525 -248.018105) (xy 95.51788 -248.059495)
			(xy 95.50589 -248.102703) (xy 95.497396 -248.123456) (xy 95.495364 -248.128028) (xy 95.491046 -248.148348)
			(xy 95.491403 -248.158188) (xy 95.498878 -248.176387) (xy 95.505524 -248.183654) (xy 95.867728 -248.545858)
			(xy 95.870014 -248.547636) (xy 95.889095 -248.563408) (xy 95.922772 -248.599692) (xy 95.950661 -248.640593)
			(xy 95.972139 -248.685196) (xy 95.986724 -248.732503) (xy 95.994091 -248.781456) (xy 95.994474 -248.806208)
			(xy 95.993959 -248.832175) (xy 96.273621 -248.832175) (xy 96.273621 -248.780241) (xy 96.281746 -248.728946)
			(xy 96.297794 -248.679553) (xy 96.321372 -248.633279) (xy 96.351898 -248.591263) (xy 96.388621 -248.55454)
			(xy 96.430637 -248.524014) (xy 96.476911 -248.500436) (xy 96.526304 -248.484388) (xy 96.577599 -248.476263)
			(xy 96.629533 -248.476263) (xy 96.680828 -248.484388) (xy 96.730221 -248.500436) (xy 96.776495 -248.524014)
			(xy 96.818511 -248.55454) (xy 96.855234 -248.591263) (xy 96.88576 -248.633279) (xy 96.909338 -248.679553)
			(xy 96.925386 -248.728946) (xy 96.933511 -248.780241) (xy 96.93402 -248.806208) (xy 96.933511 -248.832175)
			(xy 97.213421 -248.832175) (xy 97.213421 -248.780241) (xy 97.221546 -248.728946) (xy 97.237594 -248.679553)
			(xy 97.261172 -248.633279) (xy 97.291698 -248.591263) (xy 97.328421 -248.55454) (xy 97.370437 -248.524014)
			(xy 97.416711 -248.500436) (xy 97.466104 -248.484388) (xy 97.517399 -248.476263) (xy 97.569333 -248.476263)
			(xy 97.620628 -248.484388) (xy 97.670021 -248.500436) (xy 97.716295 -248.524014) (xy 97.758311 -248.55454)
			(xy 97.795034 -248.591263) (xy 97.82556 -248.633279) (xy 97.849138 -248.679553) (xy 97.865186 -248.728946)
			(xy 97.873311 -248.780241) (xy 97.87382 -248.806208) (xy 97.873311 -248.832175) (xy 98.153221 -248.832175)
			(xy 98.153221 -248.780241) (xy 98.161346 -248.728946) (xy 98.177394 -248.679553) (xy 98.200972 -248.633279)
			(xy 98.231498 -248.591263) (xy 98.268221 -248.55454) (xy 98.310237 -248.524014) (xy 98.356511 -248.500436)
			(xy 98.405904 -248.484388) (xy 98.457199 -248.476263) (xy 98.509133 -248.476263) (xy 98.560428 -248.484388)
			(xy 98.609821 -248.500436) (xy 98.656095 -248.524014) (xy 98.698111 -248.55454) (xy 98.734834 -248.591263)
			(xy 98.76536 -248.633279) (xy 98.788938 -248.679553) (xy 98.804986 -248.728946) (xy 98.813111 -248.780241)
			(xy 98.81362 -248.806208) (xy 98.813111 -248.832175) (xy 99.093021 -248.832175) (xy 99.093021 -248.780241)
			(xy 99.101146 -248.728946) (xy 99.117194 -248.679553) (xy 99.140772 -248.633279) (xy 99.171298 -248.591263)
			(xy 99.208021 -248.55454) (xy 99.250037 -248.524014) (xy 99.296311 -248.500436) (xy 99.345704 -248.484388)
			(xy 99.396999 -248.476263) (xy 99.448933 -248.476263) (xy 99.500228 -248.484388) (xy 99.549621 -248.500436)
			(xy 99.595895 -248.524014) (xy 99.637911 -248.55454) (xy 99.674634 -248.591263) (xy 99.70516 -248.633279)
			(xy 99.728738 -248.679553) (xy 99.744786 -248.728946) (xy 99.752911 -248.780241) (xy 99.75342 -248.806208)
			(xy 99.752911 -248.832175) (xy 100.032821 -248.832175) (xy 100.032821 -248.780241) (xy 100.040946 -248.728946)
			(xy 100.056994 -248.679553) (xy 100.080572 -248.633279) (xy 100.111098 -248.591263) (xy 100.147821 -248.55454)
			(xy 100.189837 -248.524014) (xy 100.236111 -248.500436) (xy 100.285504 -248.484388) (xy 100.336799 -248.476263)
			(xy 100.388733 -248.476263) (xy 100.440028 -248.484388) (xy 100.489421 -248.500436) (xy 100.535695 -248.524014)
			(xy 100.577711 -248.55454) (xy 100.614434 -248.591263) (xy 100.64496 -248.633279) (xy 100.668538 -248.679553)
			(xy 100.684586 -248.728946) (xy 100.692711 -248.780241) (xy 100.69322 -248.806208) (xy 100.692711 -248.832175)
			(xy 100.972367 -248.832175) (xy 100.972367 -248.780241) (xy 100.980492 -248.728946) (xy 100.99654 -248.679553)
			(xy 101.020118 -248.633279) (xy 101.050644 -248.591263) (xy 101.087367 -248.55454) (xy 101.129383 -248.524014)
			(xy 101.175657 -248.500436) (xy 101.22505 -248.484388) (xy 101.276345 -248.476263) (xy 101.328279 -248.476263)
			(xy 101.379574 -248.484388) (xy 101.428967 -248.500436) (xy 101.475241 -248.524014) (xy 101.517257 -248.55454)
			(xy 101.55398 -248.591263) (xy 101.584506 -248.633279) (xy 101.608084 -248.679553) (xy 101.624132 -248.728946)
			(xy 101.632257 -248.780241) (xy 101.632766 -248.806208) (xy 101.632257 -248.832165) (xy 101.912463 -248.832165)
			(xy 101.912463 -248.780235) (xy 101.920586 -248.728945) (xy 101.936632 -248.679556) (xy 101.960207 -248.633286)
			(xy 101.990728 -248.591272) (xy 102.027446 -248.55455) (xy 102.069457 -248.524024) (xy 102.115725 -248.500445)
			(xy 102.165111 -248.484394) (xy 102.216401 -248.476266) (xy 102.242366 -248.475754) (xy 102.272133 -248.476387)
			(xy 102.330707 -248.487034) (xy 102.38643 -248.507991) (xy 102.412292 -248.522744) (xy 102.423902 -248.529256)
			(xy 102.449486 -248.536581) (xy 102.476094 -248.537032) (xy 102.501911 -248.530577) (xy 102.525176 -248.517658)
			(xy 102.544303 -248.499155) (xy 102.551484 -248.487946) (xy 102.564356 -248.46731) (xy 102.595233 -248.429733)
			(xy 102.631289 -248.397092) (xy 102.671741 -248.370092) (xy 102.715717 -248.349317) (xy 102.762264 -248.335217)
			(xy 102.810376 -248.328097) (xy 102.834694 -248.327672) (xy 102.860664 -248.328134) (xy 102.911966 -248.336259)
			(xy 102.961365 -248.35231) (xy 103.007644 -248.375891) (xy 103.049664 -248.406422) (xy 103.086391 -248.443151)
			(xy 103.116919 -248.485173) (xy 103.140498 -248.531454) (xy 103.156545 -248.580854) (xy 103.164667 -248.632156)
			(xy 103.165148 -248.658126) (xy 103.165148 -248.65838) (xy 103.164672 -248.682906) (xy 103.157413 -248.731417)
			(xy 103.143066 -248.778323) (xy 103.121947 -248.822595) (xy 103.094519 -248.863261) (xy 103.07828 -248.881646)
			(xy 103.068455 -248.893117) (xy 103.05545 -248.920361) (xy 103.050988 -248.950219) (xy 103.055461 -248.980076)
			(xy 103.067534 -249.005344) (xy 108.103416 -249.005344) (xy 108.103416 -249.00509) (xy 108.103858 -248.980563)
			(xy 108.111122 -248.932049) (xy 108.125476 -248.885142) (xy 108.146603 -248.840871) (xy 108.174041 -248.800207)
			(xy 108.190284 -248.781824) (xy 108.200044 -248.770301) (xy 108.213061 -248.743076) (xy 108.217538 -248.713233)
			(xy 108.21308 -248.683386) (xy 108.20008 -248.656153) (xy 108.190284 -248.644664) (xy 108.174047 -248.626275)
			(xy 108.146601 -248.585618) (xy 108.12547 -248.541348) (xy 108.111119 -248.49444) (xy 108.103864 -248.445925)
			(xy 108.103416 -248.421398) (xy 108.103416 -248.421144) (xy 108.103925 -248.395177) (xy 108.11205 -248.343882)
			(xy 108.128098 -248.294489) (xy 108.151676 -248.248215) (xy 108.182202 -248.206199) (xy 108.218925 -248.169476)
			(xy 108.260941 -248.13895) (xy 108.307215 -248.115372) (xy 108.356608 -248.099324) (xy 108.407903 -248.091199)
			(xy 108.459837 -248.091199) (xy 108.511132 -248.099324) (xy 108.560525 -248.115372) (xy 108.606799 -248.13895)
			(xy 108.648815 -248.169476) (xy 108.685538 -248.206199) (xy 108.716064 -248.248215) (xy 108.739642 -248.294489)
			(xy 108.75569 -248.343882) (xy 108.763815 -248.395177) (xy 108.764324 -248.421144) (xy 108.764324 -248.421398)
			(xy 108.763865 -248.445924) (xy 108.756603 -248.494437) (xy 108.742253 -248.541343) (xy 108.72113 -248.585615)
			(xy 108.693697 -248.62628) (xy 108.677456 -248.644664) (xy 108.667607 -248.656118) (xy 108.654594 -248.683367)
			(xy 108.650132 -248.713233) (xy 108.654613 -248.743095) (xy 108.667643 -248.770336) (xy 108.677456 -248.781824)
			(xy 108.693678 -248.800226) (xy 108.715422 -248.832429) (xy 109.430821 -248.832429) (xy 109.430821 -248.780495)
			(xy 109.438946 -248.7292) (xy 109.454994 -248.679807) (xy 109.478572 -248.633533) (xy 109.509098 -248.591517)
			(xy 109.545821 -248.554794) (xy 109.587837 -248.524268) (xy 109.634111 -248.50069) (xy 109.683504 -248.484642)
			(xy 109.734799 -248.476517) (xy 109.786733 -248.476517) (xy 109.838028 -248.484642) (xy 109.887421 -248.50069)
			(xy 109.933695 -248.524268) (xy 109.975711 -248.554794) (xy 110.012434 -248.591517) (xy 110.04296 -248.633533)
			(xy 110.066538 -248.679807) (xy 110.082586 -248.7292) (xy 110.090711 -248.780495) (xy 110.09122 -248.806462)
			(xy 110.090711 -248.832429) (xy 110.370875 -248.832429) (xy 110.370875 -248.780495) (xy 110.379 -248.7292)
			(xy 110.395048 -248.679807) (xy 110.418626 -248.633533) (xy 110.449152 -248.591517) (xy 110.485875 -248.554794)
			(xy 110.527891 -248.524268) (xy 110.574165 -248.50069) (xy 110.623558 -248.484642) (xy 110.674853 -248.476517)
			(xy 110.726787 -248.476517) (xy 110.778082 -248.484642) (xy 110.827475 -248.50069) (xy 110.873749 -248.524268)
			(xy 110.915765 -248.554794) (xy 110.952488 -248.591517) (xy 110.983014 -248.633533) (xy 111.006592 -248.679807)
			(xy 111.02264 -248.7292) (xy 111.030765 -248.780495) (xy 111.031274 -248.806462) (xy 111.030765 -248.832429)
			(xy 111.310421 -248.832429) (xy 111.310421 -248.780495) (xy 111.318546 -248.7292) (xy 111.334594 -248.679807)
			(xy 111.358172 -248.633533) (xy 111.388698 -248.591517) (xy 111.425421 -248.554794) (xy 111.467437 -248.524268)
			(xy 111.513711 -248.50069) (xy 111.563104 -248.484642) (xy 111.614399 -248.476517) (xy 111.666333 -248.476517)
			(xy 111.717628 -248.484642) (xy 111.767021 -248.50069) (xy 111.813295 -248.524268) (xy 111.855311 -248.554794)
			(xy 111.892034 -248.591517) (xy 111.92256 -248.633533) (xy 111.946138 -248.679807) (xy 111.962186 -248.7292)
			(xy 111.970311 -248.780495) (xy 111.97082 -248.806462) (xy 111.970311 -248.832429) (xy 112.250221 -248.832429)
			(xy 112.250221 -248.780495) (xy 112.258346 -248.7292) (xy 112.274394 -248.679807) (xy 112.297972 -248.633533)
			(xy 112.328498 -248.591517) (xy 112.365221 -248.554794) (xy 112.407237 -248.524268) (xy 112.453511 -248.50069)
			(xy 112.502904 -248.484642) (xy 112.554199 -248.476517) (xy 112.606133 -248.476517) (xy 112.657428 -248.484642)
			(xy 112.706821 -248.50069) (xy 112.753095 -248.524268) (xy 112.795111 -248.554794) (xy 112.831834 -248.591517)
			(xy 112.86236 -248.633533) (xy 112.885938 -248.679807) (xy 112.901986 -248.7292) (xy 112.910111 -248.780495)
			(xy 112.91062 -248.806462) (xy 112.910111 -248.832429) (xy 113.190275 -248.832429) (xy 113.190275 -248.780495)
			(xy 113.1984 -248.7292) (xy 113.214448 -248.679807) (xy 113.238026 -248.633533) (xy 113.268552 -248.591517)
			(xy 113.305275 -248.554794) (xy 113.347291 -248.524268) (xy 113.393565 -248.50069) (xy 113.442958 -248.484642)
			(xy 113.494253 -248.476517) (xy 113.546187 -248.476517) (xy 113.597482 -248.484642) (xy 113.646875 -248.50069)
			(xy 113.693149 -248.524268) (xy 113.735165 -248.554794) (xy 113.771888 -248.591517) (xy 113.802414 -248.633533)
			(xy 113.825992 -248.679807) (xy 113.84204 -248.7292) (xy 113.850165 -248.780495) (xy 113.850674 -248.806462)
			(xy 113.850165 -248.832429) (xy 114.130075 -248.832429) (xy 114.130075 -248.780495) (xy 114.1382 -248.7292)
			(xy 114.154248 -248.679807) (xy 114.177826 -248.633533) (xy 114.208352 -248.591517) (xy 114.245075 -248.554794)
			(xy 114.287091 -248.524268) (xy 114.333365 -248.50069) (xy 114.382758 -248.484642) (xy 114.434053 -248.476517)
			(xy 114.485987 -248.476517) (xy 114.537282 -248.484642) (xy 114.586675 -248.50069) (xy 114.632949 -248.524268)
			(xy 114.674965 -248.554794) (xy 114.711688 -248.591517) (xy 114.742214 -248.633533) (xy 114.765792 -248.679807)
			(xy 114.78184 -248.7292) (xy 114.789965 -248.780495) (xy 114.790474 -248.806462) (xy 114.789965 -248.832429)
			(xy 114.78184 -248.883724) (xy 114.765792 -248.933117) (xy 114.742214 -248.979391) (xy 114.711688 -249.021407)
			(xy 114.674965 -249.05813) (xy 114.632949 -249.088656) (xy 114.586675 -249.112234) (xy 114.537282 -249.128282)
			(xy 114.485987 -249.136407) (xy 114.434053 -249.136407) (xy 114.382758 -249.128282) (xy 114.333365 -249.112234)
			(xy 114.287091 -249.088656) (xy 114.245075 -249.05813) (xy 114.208352 -249.021407) (xy 114.177826 -248.979391)
			(xy 114.154248 -248.933117) (xy 114.1382 -248.883724) (xy 114.130075 -248.832429) (xy 113.850165 -248.832429)
			(xy 113.84204 -248.883724) (xy 113.825992 -248.933117) (xy 113.802414 -248.979391) (xy 113.771888 -249.021407)
			(xy 113.735165 -249.05813) (xy 113.693149 -249.088656) (xy 113.646875 -249.112234) (xy 113.597482 -249.128282)
			(xy 113.546187 -249.136407) (xy 113.494253 -249.136407) (xy 113.442958 -249.128282) (xy 113.393565 -249.112234)
			(xy 113.347291 -249.088656) (xy 113.305275 -249.05813) (xy 113.268552 -249.021407) (xy 113.238026 -248.979391)
			(xy 113.214448 -248.933117) (xy 113.1984 -248.883724) (xy 113.190275 -248.832429) (xy 112.910111 -248.832429)
			(xy 112.901986 -248.883724) (xy 112.885938 -248.933117) (xy 112.86236 -248.979391) (xy 112.831834 -249.021407)
			(xy 112.795111 -249.05813) (xy 112.753095 -249.088656) (xy 112.706821 -249.112234) (xy 112.657428 -249.128282)
			(xy 112.606133 -249.136407) (xy 112.554199 -249.136407) (xy 112.502904 -249.128282) (xy 112.453511 -249.112234)
			(xy 112.407237 -249.088656) (xy 112.365221 -249.05813) (xy 112.328498 -249.021407) (xy 112.297972 -248.979391)
			(xy 112.274394 -248.933117) (xy 112.258346 -248.883724) (xy 112.250221 -248.832429) (xy 111.970311 -248.832429)
			(xy 111.962186 -248.883724) (xy 111.946138 -248.933117) (xy 111.92256 -248.979391) (xy 111.892034 -249.021407)
			(xy 111.855311 -249.05813) (xy 111.813295 -249.088656) (xy 111.767021 -249.112234) (xy 111.717628 -249.128282)
			(xy 111.666333 -249.136407) (xy 111.614399 -249.136407) (xy 111.563104 -249.128282) (xy 111.513711 -249.112234)
			(xy 111.467437 -249.088656) (xy 111.425421 -249.05813) (xy 111.388698 -249.021407) (xy 111.358172 -248.979391)
			(xy 111.334594 -248.933117) (xy 111.318546 -248.883724) (xy 111.310421 -248.832429) (xy 111.030765 -248.832429)
			(xy 111.02264 -248.883724) (xy 111.006592 -248.933117) (xy 110.983014 -248.979391) (xy 110.952488 -249.021407)
			(xy 110.915765 -249.05813) (xy 110.873749 -249.088656) (xy 110.827475 -249.112234) (xy 110.778082 -249.128282)
			(xy 110.726787 -249.136407) (xy 110.674853 -249.136407) (xy 110.623558 -249.128282) (xy 110.574165 -249.112234)
			(xy 110.527891 -249.088656) (xy 110.485875 -249.05813) (xy 110.449152 -249.021407) (xy 110.418626 -248.979391)
			(xy 110.395048 -248.933117) (xy 110.379 -248.883724) (xy 110.370875 -248.832429) (xy 110.090711 -248.832429)
			(xy 110.082586 -248.883724) (xy 110.066538 -248.933117) (xy 110.04296 -248.979391) (xy 110.012434 -249.021407)
			(xy 109.975711 -249.05813) (xy 109.933695 -249.088656) (xy 109.887421 -249.112234) (xy 109.838028 -249.128282)
			(xy 109.786733 -249.136407) (xy 109.734799 -249.136407) (xy 109.683504 -249.128282) (xy 109.634111 -249.112234)
			(xy 109.587837 -249.088656) (xy 109.545821 -249.05813) (xy 109.509098 -249.021407) (xy 109.478572 -248.979391)
			(xy 109.454994 -248.933117) (xy 109.438946 -248.883724) (xy 109.430821 -248.832429) (xy 108.715422 -248.832429)
			(xy 108.721128 -248.840879) (xy 108.742263 -248.885145) (xy 108.756618 -248.932051) (xy 108.763875 -248.980564)
			(xy 108.764324 -249.00509) (xy 108.764324 -249.005344) (xy 108.76392 -249.028718) (xy 108.757333 -249.075)
			(xy 108.744283 -249.11989) (xy 108.72503 -249.162489) (xy 108.69996 -249.201947) (xy 108.685076 -249.219974)
			(xy 108.679437 -249.227086) (xy 115.052348 -249.227086) (xy 115.052348 -249.226832) (xy 115.052832 -249.202307)
			(xy 115.060089 -249.153796) (xy 115.074434 -249.10689) (xy 115.095551 -249.062618) (xy 115.122978 -249.021951)
			(xy 115.139216 -249.003566) (xy 115.14903 -248.992086) (xy 115.162037 -248.964845) (xy 115.166501 -248.93499)
			(xy 115.162031 -248.905135) (xy 115.149018 -248.877896) (xy 115.139216 -248.866406) (xy 115.122957 -248.848036)
			(xy 115.095512 -248.807374) (xy 115.074385 -248.7631) (xy 115.060039 -248.716187) (xy 115.052791 -248.667669)
			(xy 115.052348 -248.64314) (xy 115.052348 -248.642886) (xy 115.052857 -248.616919) (xy 115.060982 -248.565624)
			(xy 115.07703 -248.516231) (xy 115.100608 -248.469957) (xy 115.131134 -248.427941) (xy 115.167857 -248.391218)
			(xy 115.209873 -248.360692) (xy 115.256147 -248.337114) (xy 115.30554 -248.321066) (xy 115.356835 -248.312941)
			(xy 115.408769 -248.312941) (xy 115.460064 -248.321066) (xy 115.509457 -248.337114) (xy 115.542925 -248.354167)
			(xy 120.622835 -248.354167) (xy 120.622835 -248.302233) (xy 120.630959 -248.250938) (xy 120.647007 -248.201545)
			(xy 120.670583 -248.15527) (xy 120.701108 -248.113253) (xy 120.737829 -248.076528) (xy 120.779843 -248.046)
			(xy 120.826115 -248.022419) (xy 120.875507 -248.006367) (xy 120.926801 -247.998238) (xy 120.952768 -247.997726)
			(xy 120.953022 -247.997726) (xy 120.978189 -247.998195) (xy 121.027937 -248.00585) (xy 121.052082 -248.012966)
			(xy 121.06597 -248.016894) (xy 121.094811 -248.017583) (xy 121.12269 -248.010161) (xy 121.147371 -247.995222)
			(xy 121.166876 -247.973964) (xy 121.17964 -247.948091) (xy 121.182638 -247.933972) (xy 121.187658 -247.90886)
			(xy 121.204355 -247.860452) (xy 121.228316 -247.815196) (xy 121.258967 -247.774176) (xy 121.295577 -247.738372)
			(xy 121.33727 -247.708642) (xy 121.383047 -247.685694) (xy 121.431816 -247.67008) (xy 121.482409 -247.662171)
			(xy 121.508012 -247.661684) (xy 121.533982 -247.662118) (xy 121.585281 -247.670245) (xy 121.634678 -247.686297)
			(xy 121.680955 -247.709878) (xy 121.722974 -247.740408) (xy 121.7597 -247.777135) (xy 121.790229 -247.819155)
			(xy 121.813808 -247.865433) (xy 121.829858 -247.914831) (xy 121.837983 -247.96613) (xy 121.837983 -248.01807)
			(xy 121.837977 -248.018105) (xy 122.117867 -248.018105) (xy 122.117867 -247.966171) (xy 122.125992 -247.914876)
			(xy 122.14204 -247.865483) (xy 122.165618 -247.819209) (xy 122.196144 -247.777193) (xy 122.232867 -247.74047)
			(xy 122.274883 -247.709944) (xy 122.321157 -247.686366) (xy 122.37055 -247.670318) (xy 122.421845 -247.662193)
			(xy 122.473779 -247.662193) (xy 122.525074 -247.670318) (xy 122.574467 -247.686366) (xy 122.620741 -247.709944)
			(xy 122.662757 -247.74047) (xy 122.69948 -247.777193) (xy 122.730006 -247.819209) (xy 122.753584 -247.865483)
			(xy 122.769632 -247.914876) (xy 122.777757 -247.966171) (xy 122.778266 -247.992138) (xy 122.777757 -248.018105)
			(xy 123.057667 -248.018105) (xy 123.057667 -247.966171) (xy 123.065792 -247.914876) (xy 123.08184 -247.865483)
			(xy 123.105418 -247.819209) (xy 123.135944 -247.777193) (xy 123.172667 -247.74047) (xy 123.214683 -247.709944)
			(xy 123.260957 -247.686366) (xy 123.31035 -247.670318) (xy 123.361645 -247.662193) (xy 123.413579 -247.662193)
			(xy 123.464874 -247.670318) (xy 123.514267 -247.686366) (xy 123.560541 -247.709944) (xy 123.602557 -247.74047)
			(xy 123.63928 -247.777193) (xy 123.669806 -247.819209) (xy 123.693384 -247.865483) (xy 123.709432 -247.914876)
			(xy 123.717557 -247.966171) (xy 123.718066 -247.992138) (xy 123.717557 -248.018105) (xy 123.997467 -248.018105)
			(xy 123.997467 -247.966171) (xy 124.005592 -247.914876) (xy 124.02164 -247.865483) (xy 124.045218 -247.819209)
			(xy 124.075744 -247.777193) (xy 124.112467 -247.74047) (xy 124.154483 -247.709944) (xy 124.200757 -247.686366)
			(xy 124.25015 -247.670318) (xy 124.301445 -247.662193) (xy 124.353379 -247.662193) (xy 124.404674 -247.670318)
			(xy 124.454067 -247.686366) (xy 124.500341 -247.709944) (xy 124.542357 -247.74047) (xy 124.57908 -247.777193)
			(xy 124.609606 -247.819209) (xy 124.633184 -247.865483) (xy 124.649232 -247.914876) (xy 124.657357 -247.966171)
			(xy 124.657866 -247.992138) (xy 124.657357 -248.018105) (xy 124.937267 -248.018105) (xy 124.937267 -247.966171)
			(xy 124.945392 -247.914876) (xy 124.96144 -247.865483) (xy 124.985018 -247.819209) (xy 125.015544 -247.777193)
			(xy 125.052267 -247.74047) (xy 125.094283 -247.709944) (xy 125.140557 -247.686366) (xy 125.18995 -247.670318)
			(xy 125.241245 -247.662193) (xy 125.293179 -247.662193) (xy 125.344474 -247.670318) (xy 125.393867 -247.686366)
			(xy 125.440141 -247.709944) (xy 125.482157 -247.74047) (xy 125.51888 -247.777193) (xy 125.549406 -247.819209)
			(xy 125.572984 -247.865483) (xy 125.589032 -247.914876) (xy 125.597157 -247.966171) (xy 125.597666 -247.992138)
			(xy 125.597157 -248.018105) (xy 125.877321 -248.018105) (xy 125.877321 -247.966171) (xy 125.885446 -247.914876)
			(xy 125.901494 -247.865483) (xy 125.925072 -247.819209) (xy 125.955598 -247.777193) (xy 125.992321 -247.74047)
			(xy 126.034337 -247.709944) (xy 126.080611 -247.686366) (xy 126.130004 -247.670318) (xy 126.181299 -247.662193)
			(xy 126.233233 -247.662193) (xy 126.284528 -247.670318) (xy 126.333921 -247.686366) (xy 126.380195 -247.709944)
			(xy 126.422211 -247.74047) (xy 126.458934 -247.777193) (xy 126.48946 -247.819209) (xy 126.513038 -247.865483)
			(xy 126.529086 -247.914876) (xy 126.537211 -247.966171) (xy 126.53772 -247.992138) (xy 126.537211 -248.018105)
			(xy 126.816867 -248.018105) (xy 126.816867 -247.966171) (xy 126.824992 -247.914876) (xy 126.84104 -247.865483)
			(xy 126.864618 -247.819209) (xy 126.895144 -247.777193) (xy 126.931867 -247.74047) (xy 126.973883 -247.709944)
			(xy 127.020157 -247.686366) (xy 127.06955 -247.670318) (xy 127.120845 -247.662193) (xy 127.172779 -247.662193)
			(xy 127.224074 -247.670318) (xy 127.273467 -247.686366) (xy 127.319741 -247.709944) (xy 127.361757 -247.74047)
			(xy 127.39848 -247.777193) (xy 127.429006 -247.819209) (xy 127.452584 -247.865483) (xy 127.468632 -247.914876)
			(xy 127.476757 -247.966171) (xy 127.477266 -247.992138) (xy 127.476757 -248.018105) (xy 127.756667 -248.018105)
			(xy 127.756667 -247.966171) (xy 127.764792 -247.914876) (xy 127.78084 -247.865483) (xy 127.804418 -247.819209)
			(xy 127.834944 -247.777193) (xy 127.871667 -247.74047) (xy 127.913683 -247.709944) (xy 127.959957 -247.686366)
			(xy 128.00935 -247.670318) (xy 128.060645 -247.662193) (xy 128.112579 -247.662193) (xy 128.163874 -247.670318)
			(xy 128.213267 -247.686366) (xy 128.259541 -247.709944) (xy 128.301557 -247.74047) (xy 128.33828 -247.777193)
			(xy 128.368806 -247.819209) (xy 128.392384 -247.865483) (xy 128.408432 -247.914876) (xy 128.416557 -247.966171)
			(xy 128.417066 -247.992138) (xy 128.416557 -248.018105) (xy 128.696467 -248.018105) (xy 128.696467 -247.966171)
			(xy 128.704592 -247.914876) (xy 128.72064 -247.865483) (xy 128.744218 -247.819209) (xy 128.774744 -247.777193)
			(xy 128.811467 -247.74047) (xy 128.853483 -247.709944) (xy 128.899757 -247.686366) (xy 128.94915 -247.670318)
			(xy 129.000445 -247.662193) (xy 129.052379 -247.662193) (xy 129.103674 -247.670318) (xy 129.153067 -247.686366)
			(xy 129.199341 -247.709944) (xy 129.241357 -247.74047) (xy 129.27808 -247.777193) (xy 129.308606 -247.819209)
			(xy 129.332184 -247.865483) (xy 129.348232 -247.914876) (xy 129.356357 -247.966171) (xy 129.356866 -247.992138)
			(xy 129.356357 -248.018105) (xy 129.636267 -248.018105) (xy 129.636267 -247.966171) (xy 129.644392 -247.914876)
			(xy 129.66044 -247.865483) (xy 129.684018 -247.819209) (xy 129.714544 -247.777193) (xy 129.751267 -247.74047)
			(xy 129.793283 -247.709944) (xy 129.839557 -247.686366) (xy 129.88895 -247.670318) (xy 129.940245 -247.662193)
			(xy 129.992179 -247.662193) (xy 130.043474 -247.670318) (xy 130.092867 -247.686366) (xy 130.139141 -247.709944)
			(xy 130.181157 -247.74047) (xy 130.21788 -247.777193) (xy 130.248406 -247.819209) (xy 130.271984 -247.865483)
			(xy 130.288032 -247.914876) (xy 130.296157 -247.966171) (xy 130.296666 -247.992138) (xy 130.296157 -248.018105)
			(xy 130.576321 -248.018105) (xy 130.576321 -247.966171) (xy 130.584446 -247.914876) (xy 130.600494 -247.865483)
			(xy 130.624072 -247.819209) (xy 130.654598 -247.777193) (xy 130.691321 -247.74047) (xy 130.733337 -247.709944)
			(xy 130.779611 -247.686366) (xy 130.829004 -247.670318) (xy 130.880299 -247.662193) (xy 130.932233 -247.662193)
			(xy 130.983528 -247.670318) (xy 131.032921 -247.686366) (xy 131.079195 -247.709944) (xy 131.121211 -247.74047)
			(xy 131.157934 -247.777193) (xy 131.18846 -247.819209) (xy 131.212038 -247.865483) (xy 131.228086 -247.914876)
			(xy 131.236211 -247.966171) (xy 131.23672 -247.992138) (xy 131.236211 -248.018105) (xy 131.228086 -248.0694)
			(xy 131.212038 -248.118793) (xy 131.18846 -248.165067) (xy 131.157934 -248.207083) (xy 131.121211 -248.243806)
			(xy 131.079195 -248.274332) (xy 131.032921 -248.29791) (xy 130.983528 -248.313958) (xy 130.932233 -248.322083)
			(xy 130.880299 -248.322083) (xy 130.829004 -248.313958) (xy 130.779611 -248.29791) (xy 130.733337 -248.274332)
			(xy 130.691321 -248.243806) (xy 130.654598 -248.207083) (xy 130.624072 -248.165067) (xy 130.600494 -248.118793)
			(xy 130.584446 -248.0694) (xy 130.576321 -248.018105) (xy 130.296157 -248.018105) (xy 130.288032 -248.0694)
			(xy 130.271984 -248.118793) (xy 130.248406 -248.165067) (xy 130.21788 -248.207083) (xy 130.181157 -248.243806)
			(xy 130.139141 -248.274332) (xy 130.092867 -248.29791) (xy 130.043474 -248.313958) (xy 129.992179 -248.322083)
			(xy 129.940245 -248.322083) (xy 129.88895 -248.313958) (xy 129.839557 -248.29791) (xy 129.793283 -248.274332)
			(xy 129.751267 -248.243806) (xy 129.714544 -248.207083) (xy 129.684018 -248.165067) (xy 129.66044 -248.118793)
			(xy 129.644392 -248.0694) (xy 129.636267 -248.018105) (xy 129.356357 -248.018105) (xy 129.348232 -248.0694)
			(xy 129.332184 -248.118793) (xy 129.308606 -248.165067) (xy 129.27808 -248.207083) (xy 129.241357 -248.243806)
			(xy 129.199341 -248.274332) (xy 129.153067 -248.29791) (xy 129.103674 -248.313958) (xy 129.052379 -248.322083)
			(xy 129.000445 -248.322083) (xy 128.94915 -248.313958) (xy 128.899757 -248.29791) (xy 128.853483 -248.274332)
			(xy 128.811467 -248.243806) (xy 128.774744 -248.207083) (xy 128.744218 -248.165067) (xy 128.72064 -248.118793)
			(xy 128.704592 -248.0694) (xy 128.696467 -248.018105) (xy 128.416557 -248.018105) (xy 128.408432 -248.0694)
			(xy 128.392384 -248.118793) (xy 128.368806 -248.165067) (xy 128.33828 -248.207083) (xy 128.301557 -248.243806)
			(xy 128.259541 -248.274332) (xy 128.213267 -248.29791) (xy 128.163874 -248.313958) (xy 128.112579 -248.322083)
			(xy 128.060645 -248.322083) (xy 128.00935 -248.313958) (xy 127.959957 -248.29791) (xy 127.913683 -248.274332)
			(xy 127.871667 -248.243806) (xy 127.834944 -248.207083) (xy 127.804418 -248.165067) (xy 127.78084 -248.118793)
			(xy 127.764792 -248.0694) (xy 127.756667 -248.018105) (xy 127.476757 -248.018105) (xy 127.468632 -248.0694)
			(xy 127.452584 -248.118793) (xy 127.429006 -248.165067) (xy 127.39848 -248.207083) (xy 127.361757 -248.243806)
			(xy 127.319741 -248.274332) (xy 127.273467 -248.29791) (xy 127.224074 -248.313958) (xy 127.172779 -248.322083)
			(xy 127.120845 -248.322083) (xy 127.06955 -248.313958) (xy 127.020157 -248.29791) (xy 126.973883 -248.274332)
			(xy 126.931867 -248.243806) (xy 126.895144 -248.207083) (xy 126.864618 -248.165067) (xy 126.84104 -248.118793)
			(xy 126.824992 -248.0694) (xy 126.816867 -248.018105) (xy 126.537211 -248.018105) (xy 126.529086 -248.0694)
			(xy 126.513038 -248.118793) (xy 126.48946 -248.165067) (xy 126.458934 -248.207083) (xy 126.422211 -248.243806)
			(xy 126.380195 -248.274332) (xy 126.333921 -248.29791) (xy 126.284528 -248.313958) (xy 126.233233 -248.322083)
			(xy 126.181299 -248.322083) (xy 126.130004 -248.313958) (xy 126.080611 -248.29791) (xy 126.034337 -248.274332)
			(xy 125.992321 -248.243806) (xy 125.955598 -248.207083) (xy 125.925072 -248.165067) (xy 125.901494 -248.118793)
			(xy 125.885446 -248.0694) (xy 125.877321 -248.018105) (xy 125.597157 -248.018105) (xy 125.589032 -248.0694)
			(xy 125.572984 -248.118793) (xy 125.549406 -248.165067) (xy 125.51888 -248.207083) (xy 125.482157 -248.243806)
			(xy 125.440141 -248.274332) (xy 125.393867 -248.29791) (xy 125.344474 -248.313958) (xy 125.293179 -248.322083)
			(xy 125.241245 -248.322083) (xy 125.18995 -248.313958) (xy 125.140557 -248.29791) (xy 125.094283 -248.274332)
			(xy 125.052267 -248.243806) (xy 125.015544 -248.207083) (xy 124.985018 -248.165067) (xy 124.96144 -248.118793)
			(xy 124.945392 -248.0694) (xy 124.937267 -248.018105) (xy 124.657357 -248.018105) (xy 124.649232 -248.0694)
			(xy 124.633184 -248.118793) (xy 124.609606 -248.165067) (xy 124.57908 -248.207083) (xy 124.542357 -248.243806)
			(xy 124.500341 -248.274332) (xy 124.454067 -248.29791) (xy 124.404674 -248.313958) (xy 124.353379 -248.322083)
			(xy 124.301445 -248.322083) (xy 124.25015 -248.313958) (xy 124.200757 -248.29791) (xy 124.154483 -248.274332)
			(xy 124.112467 -248.243806) (xy 124.075744 -248.207083) (xy 124.045218 -248.165067) (xy 124.02164 -248.118793)
			(xy 124.005592 -248.0694) (xy 123.997467 -248.018105) (xy 123.717557 -248.018105) (xy 123.709432 -248.0694)
			(xy 123.693384 -248.118793) (xy 123.669806 -248.165067) (xy 123.63928 -248.207083) (xy 123.602557 -248.243806)
			(xy 123.560541 -248.274332) (xy 123.514267 -248.29791) (xy 123.464874 -248.313958) (xy 123.413579 -248.322083)
			(xy 123.361645 -248.322083) (xy 123.31035 -248.313958) (xy 123.260957 -248.29791) (xy 123.214683 -248.274332)
			(xy 123.172667 -248.243806) (xy 123.135944 -248.207083) (xy 123.105418 -248.165067) (xy 123.08184 -248.118793)
			(xy 123.065792 -248.0694) (xy 123.057667 -248.018105) (xy 122.777757 -248.018105) (xy 122.769632 -248.0694)
			(xy 122.753584 -248.118793) (xy 122.730006 -248.165067) (xy 122.69948 -248.207083) (xy 122.662757 -248.243806)
			(xy 122.620741 -248.274332) (xy 122.574467 -248.29791) (xy 122.525074 -248.313958) (xy 122.473779 -248.322083)
			(xy 122.421845 -248.322083) (xy 122.37055 -248.313958) (xy 122.321157 -248.29791) (xy 122.274883 -248.274332)
			(xy 122.232867 -248.243806) (xy 122.196144 -248.207083) (xy 122.165618 -248.165067) (xy 122.14204 -248.118793)
			(xy 122.125992 -248.0694) (xy 122.117867 -248.018105) (xy 121.837977 -248.018105) (xy 121.829858 -248.069369)
			(xy 121.813808 -248.118767) (xy 121.790229 -248.165045) (xy 121.7597 -248.207065) (xy 121.722974 -248.243792)
			(xy 121.680955 -248.274322) (xy 121.634678 -248.297903) (xy 121.585281 -248.313955) (xy 121.533982 -248.322082)
			(xy 121.508012 -248.322592) (xy 121.507758 -248.322592) (xy 121.482591 -248.322127) (xy 121.432843 -248.314469)
			(xy 121.408698 -248.307352) (xy 121.394802 -248.303466) (xy 121.365971 -248.302784) (xy 121.338102 -248.310205)
			(xy 121.313428 -248.325135) (xy 121.293923 -248.346378) (xy 121.281148 -248.372234) (xy 121.278142 -248.386346)
			(xy 121.273154 -248.411465) (xy 121.256453 -248.459875) (xy 121.232488 -248.505131) (xy 121.201832 -248.546151)
			(xy 121.165218 -248.581955) (xy 121.123522 -248.611684) (xy 121.077741 -248.63463) (xy 121.028969 -248.650242)
			(xy 120.978373 -248.658148) (xy 120.952768 -248.658634) (xy 120.926801 -248.658162) (xy 120.875507 -248.650033)
			(xy 120.826115 -248.633981) (xy 120.779843 -248.6104) (xy 120.737829 -248.579872) (xy 120.701108 -248.543147)
			(xy 120.670583 -248.50113) (xy 120.647007 -248.454855) (xy 120.630959 -248.405462) (xy 120.622835 -248.354167)
			(xy 115.542925 -248.354167) (xy 115.555731 -248.360692) (xy 115.597747 -248.391218) (xy 115.63447 -248.427941)
			(xy 115.664996 -248.469957) (xy 115.688574 -248.516231) (xy 115.704622 -248.565624) (xy 115.712747 -248.616919)
			(xy 115.713256 -248.642886) (xy 115.713256 -248.64314) (xy 115.712814 -248.667667) (xy 115.705546 -248.716179)
			(xy 115.691192 -248.763086) (xy 115.670065 -248.807357) (xy 115.64263 -248.848022) (xy 115.626388 -248.866406)
			(xy 115.616601 -248.877907) (xy 115.603591 -248.905141) (xy 115.599121 -248.93499) (xy 115.603585 -248.964839)
			(xy 115.61659 -248.992076) (xy 115.626388 -249.003566) (xy 115.642635 -249.021947) (xy 115.670081 -249.062606)
			(xy 115.69121 -249.106878) (xy 115.699249 -249.13316) (xy 120.659165 -249.13316) (xy 120.659166 -249.081228)
			(xy 120.667291 -249.029935) (xy 120.683339 -248.980544) (xy 120.706917 -248.934273) (xy 120.737443 -248.892259)
			(xy 120.774165 -248.855537) (xy 120.816179 -248.825013) (xy 120.862452 -248.801436) (xy 120.911843 -248.785389)
			(xy 120.963136 -248.777265) (xy 121.015068 -248.777265) (xy 121.066361 -248.78539) (xy 121.115752 -248.801438)
			(xy 121.162024 -248.825015) (xy 121.171879 -248.832175) (xy 121.648221 -248.832175) (xy 121.648221 -248.780241)
			(xy 121.656346 -248.728946) (xy 121.672394 -248.679553) (xy 121.695972 -248.633279) (xy 121.726498 -248.591263)
			(xy 121.763221 -248.55454) (xy 121.805237 -248.524014) (xy 121.851511 -248.500436) (xy 121.900904 -248.484388)
			(xy 121.952199 -248.476263) (xy 122.004133 -248.476263) (xy 122.055428 -248.484388) (xy 122.104821 -248.500436)
			(xy 122.151095 -248.524014) (xy 122.193111 -248.55454) (xy 122.229834 -248.591263) (xy 122.26036 -248.633279)
			(xy 122.283938 -248.679553) (xy 122.299986 -248.728946) (xy 122.308111 -248.780241) (xy 122.30862 -248.806208)
			(xy 122.308111 -248.832175) (xy 122.587767 -248.832175) (xy 122.587767 -248.780241) (xy 122.595892 -248.728946)
			(xy 122.61194 -248.679553) (xy 122.635518 -248.633279) (xy 122.666044 -248.591263) (xy 122.702767 -248.55454)
			(xy 122.744783 -248.524014) (xy 122.791057 -248.500436) (xy 122.84045 -248.484388) (xy 122.891745 -248.476263)
			(xy 122.943679 -248.476263) (xy 122.994974 -248.484388) (xy 123.044367 -248.500436) (xy 123.090641 -248.524014)
			(xy 123.132657 -248.55454) (xy 123.16938 -248.591263) (xy 123.199906 -248.633279) (xy 123.223484 -248.679553)
			(xy 123.239532 -248.728946) (xy 123.247657 -248.780241) (xy 123.248166 -248.806208) (xy 123.247657 -248.832175)
			(xy 123.527821 -248.832175) (xy 123.527821 -248.780241) (xy 123.535946 -248.728946) (xy 123.551994 -248.679553)
			(xy 123.575572 -248.633279) (xy 123.606098 -248.591263) (xy 123.642821 -248.55454) (xy 123.684837 -248.524014)
			(xy 123.731111 -248.500436) (xy 123.780504 -248.484388) (xy 123.831799 -248.476263) (xy 123.883733 -248.476263)
			(xy 123.935028 -248.484388) (xy 123.984421 -248.500436) (xy 124.030695 -248.524014) (xy 124.072711 -248.55454)
			(xy 124.109434 -248.591263) (xy 124.13996 -248.633279) (xy 124.163538 -248.679553) (xy 124.179586 -248.728946)
			(xy 124.187711 -248.780241) (xy 124.18822 -248.806208) (xy 124.187711 -248.832175) (xy 124.467621 -248.832175)
			(xy 124.467621 -248.780241) (xy 124.475746 -248.728946) (xy 124.491794 -248.679553) (xy 124.515372 -248.633279)
			(xy 124.545898 -248.591263) (xy 124.582621 -248.55454) (xy 124.624637 -248.524014) (xy 124.670911 -248.500436)
			(xy 124.720304 -248.484388) (xy 124.771599 -248.476263) (xy 124.823533 -248.476263) (xy 124.874828 -248.484388)
			(xy 124.924221 -248.500436) (xy 124.970495 -248.524014) (xy 125.012511 -248.55454) (xy 125.049234 -248.591263)
			(xy 125.07976 -248.633279) (xy 125.103338 -248.679553) (xy 125.119386 -248.728946) (xy 125.127511 -248.780241)
			(xy 125.12802 -248.806208) (xy 125.127511 -248.832175) (xy 125.407421 -248.832175) (xy 125.407421 -248.780241)
			(xy 125.415546 -248.728946) (xy 125.431594 -248.679553) (xy 125.455172 -248.633279) (xy 125.485698 -248.591263)
			(xy 125.522421 -248.55454) (xy 125.564437 -248.524014) (xy 125.610711 -248.500436) (xy 125.660104 -248.484388)
			(xy 125.711399 -248.476263) (xy 125.763333 -248.476263) (xy 125.814628 -248.484388) (xy 125.864021 -248.500436)
			(xy 125.910295 -248.524014) (xy 125.952311 -248.55454) (xy 125.989034 -248.591263) (xy 126.01956 -248.633279)
			(xy 126.043138 -248.679553) (xy 126.059186 -248.728946) (xy 126.067311 -248.780241) (xy 126.06782 -248.806208)
			(xy 126.067311 -248.832175) (xy 126.347221 -248.832175) (xy 126.347221 -248.780241) (xy 126.355346 -248.728946)
			(xy 126.371394 -248.679553) (xy 126.394972 -248.633279) (xy 126.425498 -248.591263) (xy 126.462221 -248.55454)
			(xy 126.504237 -248.524014) (xy 126.550511 -248.500436) (xy 126.599904 -248.484388) (xy 126.651199 -248.476263)
			(xy 126.703133 -248.476263) (xy 126.754428 -248.484388) (xy 126.803821 -248.500436) (xy 126.850095 -248.524014)
			(xy 126.892111 -248.55454) (xy 126.928834 -248.591263) (xy 126.95936 -248.633279) (xy 126.982938 -248.679553)
			(xy 126.998986 -248.728946) (xy 127.007111 -248.780241) (xy 127.00762 -248.806208) (xy 127.007111 -248.832175)
			(xy 127.287021 -248.832175) (xy 127.287021 -248.780241) (xy 127.295146 -248.728946) (xy 127.311194 -248.679553)
			(xy 127.334772 -248.633279) (xy 127.365298 -248.591263) (xy 127.402021 -248.55454) (xy 127.444037 -248.524014)
			(xy 127.490311 -248.500436) (xy 127.539704 -248.484388) (xy 127.590999 -248.476263) (xy 127.642933 -248.476263)
			(xy 127.694228 -248.484388) (xy 127.743621 -248.500436) (xy 127.789895 -248.524014) (xy 127.831911 -248.55454)
			(xy 127.868634 -248.591263) (xy 127.89916 -248.633279) (xy 127.922738 -248.679553) (xy 127.938786 -248.728946)
			(xy 127.946911 -248.780241) (xy 127.94742 -248.806208) (xy 127.946911 -248.832175) (xy 128.226821 -248.832175)
			(xy 128.226821 -248.780241) (xy 128.234946 -248.728946) (xy 128.250994 -248.679553) (xy 128.274572 -248.633279)
			(xy 128.305098 -248.591263) (xy 128.341821 -248.55454) (xy 128.383837 -248.524014) (xy 128.430111 -248.500436)
			(xy 128.479504 -248.484388) (xy 128.530799 -248.476263) (xy 128.582733 -248.476263) (xy 128.634028 -248.484388)
			(xy 128.683421 -248.500436) (xy 128.729695 -248.524014) (xy 128.771711 -248.55454) (xy 128.808434 -248.591263)
			(xy 128.83896 -248.633279) (xy 128.862538 -248.679553) (xy 128.878586 -248.728946) (xy 128.886711 -248.780241)
			(xy 128.88722 -248.806208) (xy 128.886711 -248.832175) (xy 129.166367 -248.832175) (xy 129.166367 -248.780241)
			(xy 129.174492 -248.728946) (xy 129.19054 -248.679553) (xy 129.214118 -248.633279) (xy 129.244644 -248.591263)
			(xy 129.281367 -248.55454) (xy 129.323383 -248.524014) (xy 129.369657 -248.500436) (xy 129.41905 -248.484388)
			(xy 129.470345 -248.476263) (xy 129.522279 -248.476263) (xy 129.573574 -248.484388) (xy 129.622967 -248.500436)
			(xy 129.669241 -248.524014) (xy 129.711257 -248.55454) (xy 129.74798 -248.591263) (xy 129.778506 -248.633279)
			(xy 129.802084 -248.679553) (xy 129.818132 -248.728946) (xy 129.826257 -248.780241) (xy 129.826766 -248.806208)
			(xy 129.826257 -248.832175) (xy 130.106421 -248.832175) (xy 130.106421 -248.780241) (xy 130.114546 -248.728946)
			(xy 130.130594 -248.679553) (xy 130.154172 -248.633279) (xy 130.184698 -248.591263) (xy 130.221421 -248.55454)
			(xy 130.263437 -248.524014) (xy 130.309711 -248.500436) (xy 130.359104 -248.484388) (xy 130.410399 -248.476263)
			(xy 130.462333 -248.476263) (xy 130.513628 -248.484388) (xy 130.563021 -248.500436) (xy 130.609295 -248.524014)
			(xy 130.651311 -248.55454) (xy 130.688034 -248.591263) (xy 130.71856 -248.633279) (xy 130.742138 -248.679553)
			(xy 130.758186 -248.728946) (xy 130.766311 -248.780241) (xy 130.76682 -248.806208) (xy 130.766311 -248.832175)
			(xy 130.758186 -248.88347) (xy 130.742138 -248.932863) (xy 130.71856 -248.979137) (xy 130.688034 -249.021153)
			(xy 130.651311 -249.057876) (xy 130.609295 -249.088402) (xy 130.563021 -249.11198) (xy 130.513628 -249.128028)
			(xy 130.462333 -249.136153) (xy 130.410399 -249.136153) (xy 130.359104 -249.128028) (xy 130.309711 -249.11198)
			(xy 130.263437 -249.088402) (xy 130.221421 -249.057876) (xy 130.184698 -249.021153) (xy 130.154172 -248.979137)
			(xy 130.130594 -248.932863) (xy 130.114546 -248.88347) (xy 130.106421 -248.832175) (xy 129.826257 -248.832175)
			(xy 129.818132 -248.88347) (xy 129.802084 -248.932863) (xy 129.778506 -248.979137) (xy 129.74798 -249.021153)
			(xy 129.711257 -249.057876) (xy 129.669241 -249.088402) (xy 129.622967 -249.11198) (xy 129.573574 -249.128028)
			(xy 129.522279 -249.136153) (xy 129.470345 -249.136153) (xy 129.41905 -249.128028) (xy 129.369657 -249.11198)
			(xy 129.323383 -249.088402) (xy 129.281367 -249.057876) (xy 129.244644 -249.021153) (xy 129.214118 -248.979137)
			(xy 129.19054 -248.932863) (xy 129.174492 -248.88347) (xy 129.166367 -248.832175) (xy 128.886711 -248.832175)
			(xy 128.878586 -248.88347) (xy 128.862538 -248.932863) (xy 128.83896 -248.979137) (xy 128.808434 -249.021153)
			(xy 128.771711 -249.057876) (xy 128.729695 -249.088402) (xy 128.683421 -249.11198) (xy 128.634028 -249.128028)
			(xy 128.582733 -249.136153) (xy 128.530799 -249.136153) (xy 128.479504 -249.128028) (xy 128.430111 -249.11198)
			(xy 128.383837 -249.088402) (xy 128.341821 -249.057876) (xy 128.305098 -249.021153) (xy 128.274572 -248.979137)
			(xy 128.250994 -248.932863) (xy 128.234946 -248.88347) (xy 128.226821 -248.832175) (xy 127.946911 -248.832175)
			(xy 127.938786 -248.88347) (xy 127.922738 -248.932863) (xy 127.89916 -248.979137) (xy 127.868634 -249.021153)
			(xy 127.831911 -249.057876) (xy 127.789895 -249.088402) (xy 127.743621 -249.11198) (xy 127.694228 -249.128028)
			(xy 127.642933 -249.136153) (xy 127.590999 -249.136153) (xy 127.539704 -249.128028) (xy 127.490311 -249.11198)
			(xy 127.444037 -249.088402) (xy 127.402021 -249.057876) (xy 127.365298 -249.021153) (xy 127.334772 -248.979137)
			(xy 127.311194 -248.932863) (xy 127.295146 -248.88347) (xy 127.287021 -248.832175) (xy 127.007111 -248.832175)
			(xy 126.998986 -248.88347) (xy 126.982938 -248.932863) (xy 126.95936 -248.979137) (xy 126.928834 -249.021153)
			(xy 126.892111 -249.057876) (xy 126.850095 -249.088402) (xy 126.803821 -249.11198) (xy 126.754428 -249.128028)
			(xy 126.703133 -249.136153) (xy 126.651199 -249.136153) (xy 126.599904 -249.128028) (xy 126.550511 -249.11198)
			(xy 126.504237 -249.088402) (xy 126.462221 -249.057876) (xy 126.425498 -249.021153) (xy 126.394972 -248.979137)
			(xy 126.371394 -248.932863) (xy 126.355346 -248.88347) (xy 126.347221 -248.832175) (xy 126.067311 -248.832175)
			(xy 126.059186 -248.88347) (xy 126.043138 -248.932863) (xy 126.01956 -248.979137) (xy 125.989034 -249.021153)
			(xy 125.952311 -249.057876) (xy 125.910295 -249.088402) (xy 125.864021 -249.11198) (xy 125.814628 -249.128028)
			(xy 125.763333 -249.136153) (xy 125.711399 -249.136153) (xy 125.660104 -249.128028) (xy 125.610711 -249.11198)
			(xy 125.564437 -249.088402) (xy 125.522421 -249.057876) (xy 125.485698 -249.021153) (xy 125.455172 -248.979137)
			(xy 125.431594 -248.932863) (xy 125.415546 -248.88347) (xy 125.407421 -248.832175) (xy 125.127511 -248.832175)
			(xy 125.119386 -248.88347) (xy 125.103338 -248.932863) (xy 125.07976 -248.979137) (xy 125.049234 -249.021153)
			(xy 125.012511 -249.057876) (xy 124.970495 -249.088402) (xy 124.924221 -249.11198) (xy 124.874828 -249.128028)
			(xy 124.823533 -249.136153) (xy 124.771599 -249.136153) (xy 124.720304 -249.128028) (xy 124.670911 -249.11198)
			(xy 124.624637 -249.088402) (xy 124.582621 -249.057876) (xy 124.545898 -249.021153) (xy 124.515372 -248.979137)
			(xy 124.491794 -248.932863) (xy 124.475746 -248.88347) (xy 124.467621 -248.832175) (xy 124.187711 -248.832175)
			(xy 124.179586 -248.88347) (xy 124.163538 -248.932863) (xy 124.13996 -248.979137) (xy 124.109434 -249.021153)
			(xy 124.072711 -249.057876) (xy 124.030695 -249.088402) (xy 123.984421 -249.11198) (xy 123.935028 -249.128028)
			(xy 123.883733 -249.136153) (xy 123.831799 -249.136153) (xy 123.780504 -249.128028) (xy 123.731111 -249.11198)
			(xy 123.684837 -249.088402) (xy 123.642821 -249.057876) (xy 123.606098 -249.021153) (xy 123.575572 -248.979137)
			(xy 123.551994 -248.932863) (xy 123.535946 -248.88347) (xy 123.527821 -248.832175) (xy 123.247657 -248.832175)
			(xy 123.239532 -248.88347) (xy 123.223484 -248.932863) (xy 123.199906 -248.979137) (xy 123.16938 -249.021153)
			(xy 123.132657 -249.057876) (xy 123.090641 -249.088402) (xy 123.044367 -249.11198) (xy 122.994974 -249.128028)
			(xy 122.943679 -249.136153) (xy 122.891745 -249.136153) (xy 122.84045 -249.128028) (xy 122.791057 -249.11198)
			(xy 122.744783 -249.088402) (xy 122.702767 -249.057876) (xy 122.666044 -249.021153) (xy 122.635518 -248.979137)
			(xy 122.61194 -248.932863) (xy 122.595892 -248.88347) (xy 122.587767 -248.832175) (xy 122.308111 -248.832175)
			(xy 122.299986 -248.88347) (xy 122.283938 -248.932863) (xy 122.26036 -248.979137) (xy 122.229834 -249.021153)
			(xy 122.193111 -249.057876) (xy 122.151095 -249.088402) (xy 122.104821 -249.11198) (xy 122.055428 -249.128028)
			(xy 122.004133 -249.136153) (xy 121.952199 -249.136153) (xy 121.900904 -249.128028) (xy 121.851511 -249.11198)
			(xy 121.805237 -249.088402) (xy 121.763221 -249.057876) (xy 121.726498 -249.021153) (xy 121.695972 -248.979137)
			(xy 121.672394 -248.932863) (xy 121.656346 -248.88347) (xy 121.648221 -248.832175) (xy 121.171879 -248.832175)
			(xy 121.204038 -248.85554) (xy 121.24076 -248.892262) (xy 121.271285 -248.934276) (xy 121.294862 -248.980548)
			(xy 121.31091 -249.029939) (xy 121.319035 -249.081232) (xy 121.319544 -249.107198) (xy 121.319287 -249.124865)
			(xy 121.315473 -249.159993) (xy 121.311924 -249.177302) (xy 121.309216 -249.191699) (xy 121.311359 -249.220909)
			(xy 121.321695 -249.248312) (xy 121.339377 -249.27166) (xy 121.362952 -249.289038) (xy 121.390487 -249.299018)
			(xy 121.419722 -249.300782) (xy 121.434098 -249.297952) (xy 121.452325 -249.294031) (xy 121.48937 -249.289827)
			(xy 121.508012 -249.28957) (xy 121.533978 -249.290068) (xy 121.585269 -249.298194) (xy 121.634659 -249.314243)
			(xy 121.680929 -249.33782) (xy 121.722942 -249.368346) (xy 121.759662 -249.405067) (xy 121.790186 -249.447081)
			(xy 121.813762 -249.493353) (xy 121.829809 -249.542742) (xy 121.837933 -249.594034) (xy 121.837933 -249.645966)
			(xy 121.837929 -249.645991) (xy 122.117867 -249.645991) (xy 122.117867 -249.594057) (xy 122.125992 -249.542762)
			(xy 122.14204 -249.493369) (xy 122.165618 -249.447095) (xy 122.196144 -249.405079) (xy 122.232867 -249.368356)
			(xy 122.274883 -249.33783) (xy 122.321157 -249.314252) (xy 122.37055 -249.298204) (xy 122.421845 -249.290079)
			(xy 122.473779 -249.290079) (xy 122.525074 -249.298204) (xy 122.574467 -249.314252) (xy 122.620741 -249.33783)
			(xy 122.662757 -249.368356) (xy 122.69948 -249.405079) (xy 122.730006 -249.447095) (xy 122.753584 -249.493369)
			(xy 122.769632 -249.542762) (xy 122.777757 -249.594057) (xy 122.778266 -249.620024) (xy 122.777757 -249.645991)
			(xy 123.057667 -249.645991) (xy 123.057667 -249.594057) (xy 123.065792 -249.542762) (xy 123.08184 -249.493369)
			(xy 123.105418 -249.447095) (xy 123.135944 -249.405079) (xy 123.172667 -249.368356) (xy 123.214683 -249.33783)
			(xy 123.260957 -249.314252) (xy 123.31035 -249.298204) (xy 123.361645 -249.290079) (xy 123.413579 -249.290079)
			(xy 123.464874 -249.298204) (xy 123.514267 -249.314252) (xy 123.560541 -249.33783) (xy 123.602557 -249.368356)
			(xy 123.63928 -249.405079) (xy 123.669806 -249.447095) (xy 123.693384 -249.493369) (xy 123.709432 -249.542762)
			(xy 123.717557 -249.594057) (xy 123.718066 -249.620024) (xy 123.717557 -249.645991) (xy 123.997467 -249.645991)
			(xy 123.997467 -249.594057) (xy 124.005592 -249.542762) (xy 124.02164 -249.493369) (xy 124.045218 -249.447095)
			(xy 124.075744 -249.405079) (xy 124.112467 -249.368356) (xy 124.154483 -249.33783) (xy 124.200757 -249.314252)
			(xy 124.25015 -249.298204) (xy 124.301445 -249.290079) (xy 124.353379 -249.290079) (xy 124.404674 -249.298204)
			(xy 124.454067 -249.314252) (xy 124.500341 -249.33783) (xy 124.542357 -249.368356) (xy 124.57908 -249.405079)
			(xy 124.609606 -249.447095) (xy 124.633184 -249.493369) (xy 124.649232 -249.542762) (xy 124.657357 -249.594057)
			(xy 124.657866 -249.620024) (xy 124.657357 -249.645991) (xy 124.937521 -249.645991) (xy 124.937521 -249.594057)
			(xy 124.945646 -249.542762) (xy 124.961694 -249.493369) (xy 124.985272 -249.447095) (xy 125.015798 -249.405079)
			(xy 125.052521 -249.368356) (xy 125.094537 -249.33783) (xy 125.140811 -249.314252) (xy 125.190204 -249.298204)
			(xy 125.241499 -249.290079) (xy 125.293433 -249.290079) (xy 125.344728 -249.298204) (xy 125.394121 -249.314252)
			(xy 125.440395 -249.33783) (xy 125.482411 -249.368356) (xy 125.519134 -249.405079) (xy 125.54966 -249.447095)
			(xy 125.573238 -249.493369) (xy 125.589286 -249.542762) (xy 125.597411 -249.594057) (xy 125.59792 -249.620024)
			(xy 125.597411 -249.645991) (xy 125.877067 -249.645991) (xy 125.877067 -249.594057) (xy 125.885192 -249.542762)
			(xy 125.90124 -249.493369) (xy 125.924818 -249.447095) (xy 125.955344 -249.405079) (xy 125.992067 -249.368356)
			(xy 126.034083 -249.33783) (xy 126.080357 -249.314252) (xy 126.12975 -249.298204) (xy 126.181045 -249.290079)
			(xy 126.232979 -249.290079) (xy 126.284274 -249.298204) (xy 126.333667 -249.314252) (xy 126.379941 -249.33783)
			(xy 126.421957 -249.368356) (xy 126.45868 -249.405079) (xy 126.489206 -249.447095) (xy 126.512784 -249.493369)
			(xy 126.528832 -249.542762) (xy 126.536957 -249.594057) (xy 126.537466 -249.620024) (xy 126.536957 -249.645991)
			(xy 126.816867 -249.645991) (xy 126.816867 -249.594057) (xy 126.824992 -249.542762) (xy 126.84104 -249.493369)
			(xy 126.864618 -249.447095) (xy 126.895144 -249.405079) (xy 126.931867 -249.368356) (xy 126.973883 -249.33783)
			(xy 127.020157 -249.314252) (xy 127.06955 -249.298204) (xy 127.120845 -249.290079) (xy 127.172779 -249.290079)
			(xy 127.224074 -249.298204) (xy 127.273467 -249.314252) (xy 127.319741 -249.33783) (xy 127.361757 -249.368356)
			(xy 127.39848 -249.405079) (xy 127.429006 -249.447095) (xy 127.452584 -249.493369) (xy 127.468632 -249.542762)
			(xy 127.476757 -249.594057) (xy 127.477266 -249.620024) (xy 127.476757 -249.645991) (xy 127.756667 -249.645991)
			(xy 127.756667 -249.594057) (xy 127.764792 -249.542762) (xy 127.78084 -249.493369) (xy 127.804418 -249.447095)
			(xy 127.834944 -249.405079) (xy 127.871667 -249.368356) (xy 127.913683 -249.33783) (xy 127.959957 -249.314252)
			(xy 128.00935 -249.298204) (xy 128.060645 -249.290079) (xy 128.112579 -249.290079) (xy 128.163874 -249.298204)
			(xy 128.213267 -249.314252) (xy 128.259541 -249.33783) (xy 128.301557 -249.368356) (xy 128.33828 -249.405079)
			(xy 128.368806 -249.447095) (xy 128.392384 -249.493369) (xy 128.408432 -249.542762) (xy 128.416557 -249.594057)
			(xy 128.417066 -249.620024) (xy 128.416557 -249.645991) (xy 128.696467 -249.645991) (xy 128.696467 -249.594057)
			(xy 128.704592 -249.542762) (xy 128.72064 -249.493369) (xy 128.744218 -249.447095) (xy 128.774744 -249.405079)
			(xy 128.811467 -249.368356) (xy 128.853483 -249.33783) (xy 128.899757 -249.314252) (xy 128.94915 -249.298204)
			(xy 129.000445 -249.290079) (xy 129.052379 -249.290079) (xy 129.103674 -249.298204) (xy 129.153067 -249.314252)
			(xy 129.199341 -249.33783) (xy 129.241357 -249.368356) (xy 129.27808 -249.405079) (xy 129.308606 -249.447095)
			(xy 129.332184 -249.493369) (xy 129.348232 -249.542762) (xy 129.356357 -249.594057) (xy 129.356866 -249.620024)
			(xy 129.356357 -249.645991) (xy 129.636267 -249.645991) (xy 129.636267 -249.594057) (xy 129.644392 -249.542762)
			(xy 129.66044 -249.493369) (xy 129.684018 -249.447095) (xy 129.714544 -249.405079) (xy 129.751267 -249.368356)
			(xy 129.793283 -249.33783) (xy 129.839557 -249.314252) (xy 129.88895 -249.298204) (xy 129.940245 -249.290079)
			(xy 129.992179 -249.290079) (xy 130.043474 -249.298204) (xy 130.092867 -249.314252) (xy 130.139141 -249.33783)
			(xy 130.181157 -249.368356) (xy 130.21788 -249.405079) (xy 130.248406 -249.447095) (xy 130.271984 -249.493369)
			(xy 130.288032 -249.542762) (xy 130.296157 -249.594057) (xy 130.296666 -249.620024) (xy 130.296157 -249.645991)
			(xy 130.576067 -249.645991) (xy 130.576067 -249.594057) (xy 130.584192 -249.542762) (xy 130.60024 -249.493369)
			(xy 130.623818 -249.447095) (xy 130.654344 -249.405079) (xy 130.691067 -249.368356) (xy 130.733083 -249.33783)
			(xy 130.779357 -249.314252) (xy 130.82875 -249.298204) (xy 130.880045 -249.290079) (xy 130.931979 -249.290079)
			(xy 130.983274 -249.298204) (xy 131.032667 -249.314252) (xy 131.078941 -249.33783) (xy 131.120957 -249.368356)
			(xy 131.15768 -249.405079) (xy 131.188206 -249.447095) (xy 131.211784 -249.493369) (xy 131.227832 -249.542762)
			(xy 131.235957 -249.594057) (xy 131.236466 -249.620024) (xy 131.235957 -249.645991) (xy 131.227832 -249.697286)
			(xy 131.211784 -249.746679) (xy 131.188206 -249.792953) (xy 131.15768 -249.834969) (xy 131.120957 -249.871692)
			(xy 131.078941 -249.902218) (xy 131.032667 -249.925796) (xy 130.983274 -249.941844) (xy 130.931979 -249.949969)
			(xy 130.880045 -249.949969) (xy 130.82875 -249.941844) (xy 130.779357 -249.925796) (xy 130.733083 -249.902218)
			(xy 130.691067 -249.871692) (xy 130.654344 -249.834969) (xy 130.623818 -249.792953) (xy 130.60024 -249.746679)
			(xy 130.584192 -249.697286) (xy 130.576067 -249.645991) (xy 130.296157 -249.645991) (xy 130.288032 -249.697286)
			(xy 130.271984 -249.746679) (xy 130.248406 -249.792953) (xy 130.21788 -249.834969) (xy 130.181157 -249.871692)
			(xy 130.139141 -249.902218) (xy 130.092867 -249.925796) (xy 130.043474 -249.941844) (xy 129.992179 -249.949969)
			(xy 129.940245 -249.949969) (xy 129.88895 -249.941844) (xy 129.839557 -249.925796) (xy 129.793283 -249.902218)
			(xy 129.751267 -249.871692) (xy 129.714544 -249.834969) (xy 129.684018 -249.792953) (xy 129.66044 -249.746679)
			(xy 129.644392 -249.697286) (xy 129.636267 -249.645991) (xy 129.356357 -249.645991) (xy 129.348232 -249.697286)
			(xy 129.332184 -249.746679) (xy 129.308606 -249.792953) (xy 129.27808 -249.834969) (xy 129.241357 -249.871692)
			(xy 129.199341 -249.902218) (xy 129.153067 -249.925796) (xy 129.103674 -249.941844) (xy 129.052379 -249.949969)
			(xy 129.000445 -249.949969) (xy 128.94915 -249.941844) (xy 128.899757 -249.925796) (xy 128.853483 -249.902218)
			(xy 128.811467 -249.871692) (xy 128.774744 -249.834969) (xy 128.744218 -249.792953) (xy 128.72064 -249.746679)
			(xy 128.704592 -249.697286) (xy 128.696467 -249.645991) (xy 128.416557 -249.645991) (xy 128.408432 -249.697286)
			(xy 128.392384 -249.746679) (xy 128.368806 -249.792953) (xy 128.33828 -249.834969) (xy 128.301557 -249.871692)
			(xy 128.259541 -249.902218) (xy 128.213267 -249.925796) (xy 128.163874 -249.941844) (xy 128.112579 -249.949969)
			(xy 128.060645 -249.949969) (xy 128.00935 -249.941844) (xy 127.959957 -249.925796) (xy 127.913683 -249.902218)
			(xy 127.871667 -249.871692) (xy 127.834944 -249.834969) (xy 127.804418 -249.792953) (xy 127.78084 -249.746679)
			(xy 127.764792 -249.697286) (xy 127.756667 -249.645991) (xy 127.476757 -249.645991) (xy 127.468632 -249.697286)
			(xy 127.452584 -249.746679) (xy 127.429006 -249.792953) (xy 127.39848 -249.834969) (xy 127.361757 -249.871692)
			(xy 127.319741 -249.902218) (xy 127.273467 -249.925796) (xy 127.224074 -249.941844) (xy 127.172779 -249.949969)
			(xy 127.120845 -249.949969) (xy 127.06955 -249.941844) (xy 127.020157 -249.925796) (xy 126.973883 -249.902218)
			(xy 126.931867 -249.871692) (xy 126.895144 -249.834969) (xy 126.864618 -249.792953) (xy 126.84104 -249.746679)
			(xy 126.824992 -249.697286) (xy 126.816867 -249.645991) (xy 126.536957 -249.645991) (xy 126.528832 -249.697286)
			(xy 126.512784 -249.746679) (xy 126.489206 -249.792953) (xy 126.45868 -249.834969) (xy 126.421957 -249.871692)
			(xy 126.379941 -249.902218) (xy 126.333667 -249.925796) (xy 126.284274 -249.941844) (xy 126.232979 -249.949969)
			(xy 126.181045 -249.949969) (xy 126.12975 -249.941844) (xy 126.080357 -249.925796) (xy 126.034083 -249.902218)
			(xy 125.992067 -249.871692) (xy 125.955344 -249.834969) (xy 125.924818 -249.792953) (xy 125.90124 -249.746679)
			(xy 125.885192 -249.697286) (xy 125.877067 -249.645991) (xy 125.597411 -249.645991) (xy 125.589286 -249.697286)
			(xy 125.573238 -249.746679) (xy 125.54966 -249.792953) (xy 125.519134 -249.834969) (xy 125.482411 -249.871692)
			(xy 125.440395 -249.902218) (xy 125.394121 -249.925796) (xy 125.344728 -249.941844) (xy 125.293433 -249.949969)
			(xy 125.241499 -249.949969) (xy 125.190204 -249.941844) (xy 125.140811 -249.925796) (xy 125.094537 -249.902218)
			(xy 125.052521 -249.871692) (xy 125.015798 -249.834969) (xy 124.985272 -249.792953) (xy 124.961694 -249.746679)
			(xy 124.945646 -249.697286) (xy 124.937521 -249.645991) (xy 124.657357 -249.645991) (xy 124.649232 -249.697286)
			(xy 124.633184 -249.746679) (xy 124.609606 -249.792953) (xy 124.57908 -249.834969) (xy 124.542357 -249.871692)
			(xy 124.500341 -249.902218) (xy 124.454067 -249.925796) (xy 124.404674 -249.941844) (xy 124.353379 -249.949969)
			(xy 124.301445 -249.949969) (xy 124.25015 -249.941844) (xy 124.200757 -249.925796) (xy 124.154483 -249.902218)
			(xy 124.112467 -249.871692) (xy 124.075744 -249.834969) (xy 124.045218 -249.792953) (xy 124.02164 -249.746679)
			(xy 124.005592 -249.697286) (xy 123.997467 -249.645991) (xy 123.717557 -249.645991) (xy 123.709432 -249.697286)
			(xy 123.693384 -249.746679) (xy 123.669806 -249.792953) (xy 123.63928 -249.834969) (xy 123.602557 -249.871692)
			(xy 123.560541 -249.902218) (xy 123.514267 -249.925796) (xy 123.464874 -249.941844) (xy 123.413579 -249.949969)
			(xy 123.361645 -249.949969) (xy 123.31035 -249.941844) (xy 123.260957 -249.925796) (xy 123.214683 -249.902218)
			(xy 123.172667 -249.871692) (xy 123.135944 -249.834969) (xy 123.105418 -249.792953) (xy 123.08184 -249.746679)
			(xy 123.065792 -249.697286) (xy 123.057667 -249.645991) (xy 122.777757 -249.645991) (xy 122.769632 -249.697286)
			(xy 122.753584 -249.746679) (xy 122.730006 -249.792953) (xy 122.69948 -249.834969) (xy 122.662757 -249.871692)
			(xy 122.620741 -249.902218) (xy 122.574467 -249.925796) (xy 122.525074 -249.941844) (xy 122.473779 -249.949969)
			(xy 122.421845 -249.949969) (xy 122.37055 -249.941844) (xy 122.321157 -249.925796) (xy 122.274883 -249.902218)
			(xy 122.232867 -249.871692) (xy 122.196144 -249.834969) (xy 122.165618 -249.792953) (xy 122.14204 -249.746679)
			(xy 122.125992 -249.697286) (xy 122.117867 -249.645991) (xy 121.837929 -249.645991) (xy 121.829809 -249.697258)
			(xy 121.813762 -249.746647) (xy 121.790186 -249.792919) (xy 121.759662 -249.834933) (xy 121.722942 -249.871654)
			(xy 121.680929 -249.90218) (xy 121.634659 -249.925757) (xy 121.585269 -249.941806) (xy 121.533978 -249.949932)
			(xy 121.482046 -249.949934) (xy 121.430754 -249.941812) (xy 121.381364 -249.925766) (xy 121.335091 -249.902192)
			(xy 121.293076 -249.87167) (xy 121.256353 -249.834951) (xy 121.225827 -249.792939) (xy 121.202247 -249.74667)
			(xy 121.186196 -249.697281) (xy 121.178069 -249.64599) (xy 121.177558 -249.620024) (xy 121.177803 -249.602357)
			(xy 121.181625 -249.567228) (xy 121.185178 -249.54992) (xy 121.187861 -249.535519) (xy 121.185723 -249.506312)
			(xy 121.175392 -249.47891) (xy 121.157714 -249.455562) (xy 121.134142 -249.438184) (xy 121.10661 -249.428204)
			(xy 121.077378 -249.426439) (xy 121.063004 -249.42927) (xy 121.044777 -249.433191) (xy 121.007732 -249.437395)
			(xy 120.98909 -249.437652) (xy 120.963124 -249.437134) (xy 120.911831 -249.429008) (xy 120.862441 -249.412959)
			(xy 120.816169 -249.389381) (xy 120.774156 -249.358855) (xy 120.737435 -249.322132) (xy 120.706911 -249.280117)
			(xy 120.683335 -249.233845) (xy 120.667288 -249.184453) (xy 120.659165 -249.13316) (xy 115.699249 -249.13316)
			(xy 115.705559 -249.153788) (xy 115.712811 -249.202304) (xy 115.713256 -249.226832) (xy 115.713256 -249.227086)
			(xy 115.712747 -249.253053) (xy 115.704622 -249.304348) (xy 115.688574 -249.353741) (xy 115.664996 -249.400015)
			(xy 115.63447 -249.442031) (xy 115.597747 -249.478754) (xy 115.555731 -249.50928) (xy 115.509457 -249.532858)
			(xy 115.460064 -249.548906) (xy 115.408769 -249.557031) (xy 115.356835 -249.557031) (xy 115.30554 -249.548906)
			(xy 115.256147 -249.532858) (xy 115.209873 -249.50928) (xy 115.167857 -249.478754) (xy 115.131134 -249.442031)
			(xy 115.100608 -249.400015) (xy 115.07703 -249.353741) (xy 115.060982 -249.304348) (xy 115.052857 -249.253053)
			(xy 115.052348 -249.227086) (xy 108.679437 -249.227086) (xy 108.675634 -249.231883) (xy 108.663518 -249.259735)
			(xy 108.660128 -249.289919) (xy 108.665764 -249.319765) (xy 108.679927 -249.346634) (xy 108.701365 -249.36815)
			(xy 108.728182 -249.382412) (xy 108.742988 -249.385836) (xy 108.767708 -249.391083) (xy 108.81529 -249.408102)
			(xy 108.859728 -249.432161) (xy 108.880148 -249.44705) (xy 108.891172 -249.454888) (xy 108.916209 -249.465094)
			(xy 108.943048 -249.468353) (xy 108.969799 -249.464437) (xy 108.994578 -249.453621) (xy 109.015639 -249.436668)
			(xy 109.023912 -249.425968) (xy 109.039605 -249.405291) (xy 109.076307 -249.36859) (xy 109.118298 -249.338081)
			(xy 109.164543 -249.314514) (xy 109.213905 -249.298468) (xy 109.265168 -249.290339) (xy 109.29112 -249.289824)
			(xy 109.317084 -249.290379) (xy 109.368374 -249.298505) (xy 109.41776 -249.314554) (xy 109.464028 -249.338132)
			(xy 109.506039 -249.368656) (xy 109.542757 -249.405377) (xy 109.573279 -249.447389) (xy 109.596853 -249.493658)
			(xy 109.6129 -249.543046) (xy 109.621023 -249.594336) (xy 109.621023 -249.646245) (xy 109.900975 -249.646245)
			(xy 109.900975 -249.594311) (xy 109.9091 -249.543016) (xy 109.925148 -249.493623) (xy 109.948726 -249.447349)
			(xy 109.979252 -249.405333) (xy 110.015975 -249.36861) (xy 110.057991 -249.338084) (xy 110.104265 -249.314506)
			(xy 110.153658 -249.298458) (xy 110.204953 -249.290333) (xy 110.256887 -249.290333) (xy 110.308182 -249.298458)
			(xy 110.357575 -249.314506) (xy 110.403849 -249.338084) (xy 110.445865 -249.36861) (xy 110.482588 -249.405333)
			(xy 110.513114 -249.447349) (xy 110.536692 -249.493623) (xy 110.55274 -249.543016) (xy 110.560865 -249.594311)
			(xy 110.561374 -249.620278) (xy 110.560865 -249.646245) (xy 110.840775 -249.646245) (xy 110.840775 -249.594311)
			(xy 110.8489 -249.543016) (xy 110.864948 -249.493623) (xy 110.888526 -249.447349) (xy 110.919052 -249.405333)
			(xy 110.955775 -249.36861) (xy 110.997791 -249.338084) (xy 111.044065 -249.314506) (xy 111.093458 -249.298458)
			(xy 111.144753 -249.290333) (xy 111.196687 -249.290333) (xy 111.247982 -249.298458) (xy 111.297375 -249.314506)
			(xy 111.343649 -249.338084) (xy 111.385665 -249.36861) (xy 111.422388 -249.405333) (xy 111.452914 -249.447349)
			(xy 111.476492 -249.493623) (xy 111.49254 -249.543016) (xy 111.500665 -249.594311) (xy 111.501174 -249.620278)
			(xy 111.500665 -249.646245) (xy 111.780575 -249.646245) (xy 111.780575 -249.594311) (xy 111.7887 -249.543016)
			(xy 111.804748 -249.493623) (xy 111.828326 -249.447349) (xy 111.858852 -249.405333) (xy 111.895575 -249.36861)
			(xy 111.937591 -249.338084) (xy 111.983865 -249.314506) (xy 112.033258 -249.298458) (xy 112.084553 -249.290333)
			(xy 112.136487 -249.290333) (xy 112.187782 -249.298458) (xy 112.237175 -249.314506) (xy 112.283449 -249.338084)
			(xy 112.325465 -249.36861) (xy 112.362188 -249.405333) (xy 112.392714 -249.447349) (xy 112.416292 -249.493623)
			(xy 112.43234 -249.543016) (xy 112.440465 -249.594311) (xy 112.440974 -249.620278) (xy 112.440465 -249.646245)
			(xy 112.720121 -249.646245) (xy 112.720121 -249.594311) (xy 112.728246 -249.543016) (xy 112.744294 -249.493623)
			(xy 112.767872 -249.447349) (xy 112.798398 -249.405333) (xy 112.835121 -249.36861) (xy 112.877137 -249.338084)
			(xy 112.923411 -249.314506) (xy 112.972804 -249.298458) (xy 113.024099 -249.290333) (xy 113.076033 -249.290333)
			(xy 113.127328 -249.298458) (xy 113.176721 -249.314506) (xy 113.222995 -249.338084) (xy 113.265011 -249.36861)
			(xy 113.301734 -249.405333) (xy 113.33226 -249.447349) (xy 113.355838 -249.493623) (xy 113.371886 -249.543016)
			(xy 113.380011 -249.594311) (xy 113.38052 -249.620278) (xy 113.380011 -249.646245) (xy 113.660175 -249.646245)
			(xy 113.660175 -249.594311) (xy 113.6683 -249.543016) (xy 113.684348 -249.493623) (xy 113.707926 -249.447349)
			(xy 113.738452 -249.405333) (xy 113.775175 -249.36861) (xy 113.817191 -249.338084) (xy 113.863465 -249.314506)
			(xy 113.912858 -249.298458) (xy 113.964153 -249.290333) (xy 114.016087 -249.290333) (xy 114.067382 -249.298458)
			(xy 114.116775 -249.314506) (xy 114.163049 -249.338084) (xy 114.205065 -249.36861) (xy 114.241788 -249.405333)
			(xy 114.272314 -249.447349) (xy 114.295892 -249.493623) (xy 114.31194 -249.543016) (xy 114.320065 -249.594311)
			(xy 114.320574 -249.620278) (xy 114.320065 -249.646245) (xy 114.31194 -249.69754) (xy 114.295892 -249.746933)
			(xy 114.272314 -249.793207) (xy 114.241788 -249.835223) (xy 114.205065 -249.871946) (xy 114.163049 -249.902472)
			(xy 114.116775 -249.92605) (xy 114.067382 -249.942098) (xy 114.016087 -249.950223) (xy 113.964153 -249.950223)
			(xy 113.912858 -249.942098) (xy 113.863465 -249.92605) (xy 113.817191 -249.902472) (xy 113.775175 -249.871946)
			(xy 113.738452 -249.835223) (xy 113.707926 -249.793207) (xy 113.684348 -249.746933) (xy 113.6683 -249.69754)
			(xy 113.660175 -249.646245) (xy 113.380011 -249.646245) (xy 113.371886 -249.69754) (xy 113.355838 -249.746933)
			(xy 113.33226 -249.793207) (xy 113.301734 -249.835223) (xy 113.265011 -249.871946) (xy 113.222995 -249.902472)
			(xy 113.176721 -249.92605) (xy 113.127328 -249.942098) (xy 113.076033 -249.950223) (xy 113.024099 -249.950223)
			(xy 112.972804 -249.942098) (xy 112.923411 -249.92605) (xy 112.877137 -249.902472) (xy 112.835121 -249.871946)
			(xy 112.798398 -249.835223) (xy 112.767872 -249.793207) (xy 112.744294 -249.746933) (xy 112.728246 -249.69754)
			(xy 112.720121 -249.646245) (xy 112.440465 -249.646245) (xy 112.43234 -249.69754) (xy 112.416292 -249.746933)
			(xy 112.392714 -249.793207) (xy 112.362188 -249.835223) (xy 112.325465 -249.871946) (xy 112.283449 -249.902472)
			(xy 112.237175 -249.92605) (xy 112.187782 -249.942098) (xy 112.136487 -249.950223) (xy 112.084553 -249.950223)
			(xy 112.033258 -249.942098) (xy 111.983865 -249.92605) (xy 111.937591 -249.902472) (xy 111.895575 -249.871946)
			(xy 111.858852 -249.835223) (xy 111.828326 -249.793207) (xy 111.804748 -249.746933) (xy 111.7887 -249.69754)
			(xy 111.780575 -249.646245) (xy 111.500665 -249.646245) (xy 111.49254 -249.69754) (xy 111.476492 -249.746933)
			(xy 111.452914 -249.793207) (xy 111.422388 -249.835223) (xy 111.385665 -249.871946) (xy 111.343649 -249.902472)
			(xy 111.297375 -249.92605) (xy 111.247982 -249.942098) (xy 111.196687 -249.950223) (xy 111.144753 -249.950223)
			(xy 111.093458 -249.942098) (xy 111.044065 -249.92605) (xy 110.997791 -249.902472) (xy 110.955775 -249.871946)
			(xy 110.919052 -249.835223) (xy 110.888526 -249.793207) (xy 110.864948 -249.746933) (xy 110.8489 -249.69754)
			(xy 110.840775 -249.646245) (xy 110.560865 -249.646245) (xy 110.55274 -249.69754) (xy 110.536692 -249.746933)
			(xy 110.513114 -249.793207) (xy 110.482588 -249.835223) (xy 110.445865 -249.871946) (xy 110.403849 -249.902472)
			(xy 110.357575 -249.92605) (xy 110.308182 -249.942098) (xy 110.256887 -249.950223) (xy 110.204953 -249.950223)
			(xy 110.153658 -249.942098) (xy 110.104265 -249.92605) (xy 110.057991 -249.902472) (xy 110.015975 -249.871946)
			(xy 109.979252 -249.835223) (xy 109.948726 -249.793207) (xy 109.925148 -249.746933) (xy 109.9091 -249.69754)
			(xy 109.900975 -249.646245) (xy 109.621023 -249.646245) (xy 109.621023 -249.646264) (xy 109.6129 -249.697554)
			(xy 109.596853 -249.746942) (xy 109.573279 -249.793211) (xy 109.542757 -249.835223) (xy 109.506039 -249.871944)
			(xy 109.464028 -249.902468) (xy 109.41776 -249.926046) (xy 109.368374 -249.942095) (xy 109.317084 -249.950221)
			(xy 109.29112 -249.950732) (xy 109.264268 -249.950207) (xy 109.211271 -249.941526) (xy 109.160376 -249.924389)
			(xy 109.112922 -249.899247) (xy 109.091222 -249.883422) (xy 109.080229 -249.875533) (xy 109.055183 -249.865322)
			(xy 109.028332 -249.862065) (xy 109.001571 -249.86599) (xy 108.976786 -249.876821) (xy 108.955727 -249.893794)
			(xy 108.947458 -249.904504) (xy 108.941913 -249.912091) (xy 108.930096 -249.926705) (xy 108.923836 -249.933714)
			(xy 108.914037 -249.945207) (xy 108.901022 -249.972443) (xy 108.896551 -250.002296) (xy 108.901019 -250.032149)
			(xy 108.914032 -250.059385) (xy 108.923836 -250.070874) (xy 108.940078 -250.089259) (xy 108.967527 -250.129916)
			(xy 108.988658 -250.174186) (xy 109.003008 -250.221096) (xy 109.010259 -250.269612) (xy 109.010704 -250.29414)
			(xy 109.010704 -250.294394) (xy 109.010195 -250.320361) (xy 109.00207 -250.371656) (xy 108.986022 -250.421049)
			(xy 108.962444 -250.467323) (xy 108.931918 -250.509339) (xy 108.895195 -250.546062) (xy 108.853179 -250.576588)
			(xy 108.806905 -250.600166) (xy 108.757512 -250.616214) (xy 108.706217 -250.624339) (xy 108.654283 -250.624339)
			(xy 108.602988 -250.616214) (xy 108.553595 -250.600166) (xy 108.507321 -250.576588) (xy 108.465305 -250.546062)
			(xy 108.428582 -250.509339) (xy 108.398056 -250.467323) (xy 108.374478 -250.421049) (xy 108.35843 -250.371656)
			(xy 108.350305 -250.320361) (xy 108.349796 -250.294394) (xy 108.349796 -250.29414) (xy 108.350273 -250.269614)
			(xy 108.35753 -250.221103) (xy 108.371875 -250.174196) (xy 108.392995 -250.129924) (xy 108.420424 -250.089258)
			(xy 108.436664 -250.070874) (xy 108.446474 -250.05939) (xy 108.459489 -250.032151) (xy 108.463957 -250.002296)
			(xy 108.459486 -249.97244) (xy 108.446469 -249.945203) (xy 108.436664 -249.933714) (xy 108.420416 -249.915334)
			(xy 108.392969 -249.874675) (xy 108.371838 -249.830404) (xy 108.35749 -249.783493) (xy 108.35024 -249.734976)
			(xy 108.349796 -249.710448) (xy 108.349796 -249.710194) (xy 108.350217 -249.68682) (xy 108.356799 -249.640539)
			(xy 108.369845 -249.595649) (xy 108.389094 -249.553049) (xy 108.414161 -249.513591) (xy 108.429044 -249.495564)
			(xy 108.438551 -249.483705) (xy 108.450657 -249.455837) (xy 108.454035 -249.425643) (xy 108.448389 -249.395789)
			(xy 108.434216 -249.368914) (xy 108.412769 -249.347393) (xy 108.385943 -249.333128) (xy 108.371132 -249.329702)
			(xy 108.346335 -249.324449) (xy 108.298618 -249.307357) (xy 108.254073 -249.283175) (xy 108.213744 -249.252472)
			(xy 108.17858 -249.215968) (xy 108.149405 -249.17452) (xy 108.126905 -249.129102) (xy 108.111608 -249.080779)
			(xy 108.103873 -249.030687) (xy 108.103416 -249.005344) (xy 103.067534 -249.005344) (xy 103.068476 -249.007315)
			(xy 103.07828 -249.018806) (xy 103.094544 -249.037172) (xy 103.121988 -249.077835) (xy 103.143115 -249.12211)
			(xy 103.157459 -249.169024) (xy 103.164705 -249.217543) (xy 103.165148 -249.242072) (xy 103.165148 -249.242326)
			(xy 103.164639 -249.268293) (xy 103.156514 -249.319588) (xy 103.140466 -249.368981) (xy 103.116888 -249.415255)
			(xy 103.086362 -249.457271) (xy 103.049639 -249.493994) (xy 103.007623 -249.52452) (xy 102.961349 -249.548098)
			(xy 102.911956 -249.564146) (xy 102.860661 -249.572271) (xy 102.808727 -249.572271) (xy 102.757432 -249.564146)
			(xy 102.708039 -249.548098) (xy 102.661765 -249.52452) (xy 102.619749 -249.493994) (xy 102.583026 -249.457271)
			(xy 102.5525 -249.415255) (xy 102.528922 -249.368981) (xy 102.512874 -249.319588) (xy 102.504749 -249.268293)
			(xy 102.50424 -249.242326) (xy 102.505256 -249.215148) (xy 102.505935 -249.200357) (xy 102.499786 -249.171408)
			(xy 102.485604 -249.145432) (xy 102.464577 -249.124606) (xy 102.438466 -249.110676) (xy 102.409459 -249.104807)
			(xy 102.379986 -249.107492) (xy 102.366064 -249.112532) (xy 102.336378 -249.123758) (xy 102.274095 -249.135912)
			(xy 102.242366 -249.136662) (xy 102.216401 -249.136134) (xy 102.165111 -249.128006) (xy 102.115725 -249.111955)
			(xy 102.069457 -249.088376) (xy 102.027446 -249.05785) (xy 101.990728 -249.021128) (xy 101.960207 -248.979114)
			(xy 101.936632 -248.932844) (xy 101.920586 -248.883455) (xy 101.912463 -248.832165) (xy 101.632257 -248.832165)
			(xy 101.632257 -248.832175) (xy 101.624132 -248.88347) (xy 101.608084 -248.932863) (xy 101.584506 -248.979137)
			(xy 101.55398 -249.021153) (xy 101.517257 -249.057876) (xy 101.475241 -249.088402) (xy 101.428967 -249.11198)
			(xy 101.379574 -249.128028) (xy 101.328279 -249.136153) (xy 101.276345 -249.136153) (xy 101.22505 -249.128028)
			(xy 101.175657 -249.11198) (xy 101.129383 -249.088402) (xy 101.087367 -249.057876) (xy 101.050644 -249.021153)
			(xy 101.020118 -248.979137) (xy 100.99654 -248.932863) (xy 100.980492 -248.88347) (xy 100.972367 -248.832175)
			(xy 100.692711 -248.832175) (xy 100.684586 -248.88347) (xy 100.668538 -248.932863) (xy 100.64496 -248.979137)
			(xy 100.614434 -249.021153) (xy 100.577711 -249.057876) (xy 100.535695 -249.088402) (xy 100.489421 -249.11198)
			(xy 100.440028 -249.128028) (xy 100.388733 -249.136153) (xy 100.336799 -249.136153) (xy 100.285504 -249.128028)
			(xy 100.236111 -249.11198) (xy 100.189837 -249.088402) (xy 100.147821 -249.057876) (xy 100.111098 -249.021153)
			(xy 100.080572 -248.979137) (xy 100.056994 -248.932863) (xy 100.040946 -248.88347) (xy 100.032821 -248.832175)
			(xy 99.752911 -248.832175) (xy 99.744786 -248.88347) (xy 99.728738 -248.932863) (xy 99.70516 -248.979137)
			(xy 99.674634 -249.021153) (xy 99.637911 -249.057876) (xy 99.595895 -249.088402) (xy 99.549621 -249.11198)
			(xy 99.500228 -249.128028) (xy 99.448933 -249.136153) (xy 99.396999 -249.136153) (xy 99.345704 -249.128028)
			(xy 99.296311 -249.11198) (xy 99.250037 -249.088402) (xy 99.208021 -249.057876) (xy 99.171298 -249.021153)
			(xy 99.140772 -248.979137) (xy 99.117194 -248.932863) (xy 99.101146 -248.88347) (xy 99.093021 -248.832175)
			(xy 98.813111 -248.832175) (xy 98.804986 -248.88347) (xy 98.788938 -248.932863) (xy 98.76536 -248.979137)
			(xy 98.734834 -249.021153) (xy 98.698111 -249.057876) (xy 98.656095 -249.088402) (xy 98.609821 -249.11198)
			(xy 98.560428 -249.128028) (xy 98.509133 -249.136153) (xy 98.457199 -249.136153) (xy 98.405904 -249.128028)
			(xy 98.356511 -249.11198) (xy 98.310237 -249.088402) (xy 98.268221 -249.057876) (xy 98.231498 -249.021153)
			(xy 98.200972 -248.979137) (xy 98.177394 -248.932863) (xy 98.161346 -248.88347) (xy 98.153221 -248.832175)
			(xy 97.873311 -248.832175) (xy 97.865186 -248.88347) (xy 97.849138 -248.932863) (xy 97.82556 -248.979137)
			(xy 97.795034 -249.021153) (xy 97.758311 -249.057876) (xy 97.716295 -249.088402) (xy 97.670021 -249.11198)
			(xy 97.620628 -249.128028) (xy 97.569333 -249.136153) (xy 97.517399 -249.136153) (xy 97.466104 -249.128028)
			(xy 97.416711 -249.11198) (xy 97.370437 -249.088402) (xy 97.328421 -249.057876) (xy 97.291698 -249.021153)
			(xy 97.261172 -248.979137) (xy 97.237594 -248.932863) (xy 97.221546 -248.88347) (xy 97.213421 -248.832175)
			(xy 96.933511 -248.832175) (xy 96.925386 -248.88347) (xy 96.909338 -248.932863) (xy 96.88576 -248.979137)
			(xy 96.855234 -249.021153) (xy 96.818511 -249.057876) (xy 96.776495 -249.088402) (xy 96.730221 -249.11198)
			(xy 96.680828 -249.128028) (xy 96.629533 -249.136153) (xy 96.577599 -249.136153) (xy 96.526304 -249.128028)
			(xy 96.476911 -249.11198) (xy 96.430637 -249.088402) (xy 96.388621 -249.057876) (xy 96.351898 -249.021153)
			(xy 96.321372 -248.979137) (xy 96.297794 -248.932863) (xy 96.281746 -248.88347) (xy 96.273621 -248.832175)
			(xy 95.993959 -248.832175) (xy 95.993948 -248.832716) (xy 95.985485 -248.885052) (xy 95.968778 -248.935367)
			(xy 95.944255 -248.98237) (xy 95.912544 -249.024857) (xy 95.89389 -249.043698) (xy 95.893636 -249.043952)
			(xy 95.87865 -249.079512) (xy 95.87865 -249.217688) (xy 95.879246 -249.229863) (xy 95.890565 -249.251421)
			(xy 95.90024 -249.258836) (xy 95.934276 -249.282204) (xy 95.970598 -249.30735) (xy 95.979859 -249.312387)
			(xy 96.000734 -249.315148) (xy 96.010984 -249.312684) (xy 96.014794 -249.31116) (xy 96.043197 -249.301009)
			(xy 96.102496 -249.290011) (xy 96.13265 -249.289316) (xy 96.133412 -249.289316) (xy 96.159397 -249.289826)
			(xy 96.210726 -249.297958) (xy 96.260151 -249.314019) (xy 96.306456 -249.337613) (xy 96.348499 -249.368161)
			(xy 96.385247 -249.40491) (xy 96.415793 -249.446954) (xy 96.439386 -249.49326) (xy 96.455445 -249.542686)
			(xy 96.463575 -249.594015) (xy 96.463575 -249.645985) (xy 96.463574 -249.645991) (xy 96.743521 -249.645991)
			(xy 96.743521 -249.594057) (xy 96.751646 -249.542762) (xy 96.767694 -249.493369) (xy 96.791272 -249.447095)
			(xy 96.821798 -249.405079) (xy 96.858521 -249.368356) (xy 96.900537 -249.33783) (xy 96.946811 -249.314252)
			(xy 96.996204 -249.298204) (xy 97.047499 -249.290079) (xy 97.099433 -249.290079) (xy 97.150728 -249.298204)
			(xy 97.200121 -249.314252) (xy 97.246395 -249.33783) (xy 97.288411 -249.368356) (xy 97.325134 -249.405079)
			(xy 97.35566 -249.447095) (xy 97.379238 -249.493369) (xy 97.395286 -249.542762) (xy 97.403411 -249.594057)
			(xy 97.40392 -249.620024) (xy 97.403411 -249.645991) (xy 97.683067 -249.645991) (xy 97.683067 -249.594057)
			(xy 97.691192 -249.542762) (xy 97.70724 -249.493369) (xy 97.730818 -249.447095) (xy 97.761344 -249.405079)
			(xy 97.798067 -249.368356) (xy 97.840083 -249.33783) (xy 97.886357 -249.314252) (xy 97.93575 -249.298204)
			(xy 97.987045 -249.290079) (xy 98.038979 -249.290079) (xy 98.090274 -249.298204) (xy 98.139667 -249.314252)
			(xy 98.185941 -249.33783) (xy 98.227957 -249.368356) (xy 98.26468 -249.405079) (xy 98.295206 -249.447095)
			(xy 98.318784 -249.493369) (xy 98.334832 -249.542762) (xy 98.342957 -249.594057) (xy 98.343466 -249.620024)
			(xy 98.342957 -249.645991) (xy 98.622867 -249.645991) (xy 98.622867 -249.594057) (xy 98.630992 -249.542762)
			(xy 98.64704 -249.493369) (xy 98.670618 -249.447095) (xy 98.701144 -249.405079) (xy 98.737867 -249.368356)
			(xy 98.779883 -249.33783) (xy 98.826157 -249.314252) (xy 98.87555 -249.298204) (xy 98.926845 -249.290079)
			(xy 98.978779 -249.290079) (xy 99.030074 -249.298204) (xy 99.079467 -249.314252) (xy 99.125741 -249.33783)
			(xy 99.167757 -249.368356) (xy 99.20448 -249.405079) (xy 99.235006 -249.447095) (xy 99.258584 -249.493369)
			(xy 99.274632 -249.542762) (xy 99.282757 -249.594057) (xy 99.283266 -249.620024) (xy 99.282757 -249.645991)
			(xy 99.562667 -249.645991) (xy 99.562667 -249.594057) (xy 99.570792 -249.542762) (xy 99.58684 -249.493369)
			(xy 99.610418 -249.447095) (xy 99.640944 -249.405079) (xy 99.677667 -249.368356) (xy 99.719683 -249.33783)
			(xy 99.765957 -249.314252) (xy 99.81535 -249.298204) (xy 99.866645 -249.290079) (xy 99.918579 -249.290079)
			(xy 99.969874 -249.298204) (xy 100.019267 -249.314252) (xy 100.065541 -249.33783) (xy 100.107557 -249.368356)
			(xy 100.14428 -249.405079) (xy 100.174806 -249.447095) (xy 100.198384 -249.493369) (xy 100.214432 -249.542762)
			(xy 100.222557 -249.594057) (xy 100.223066 -249.620024) (xy 100.222557 -249.645991) (xy 100.502467 -249.645991)
			(xy 100.502467 -249.594057) (xy 100.510592 -249.542762) (xy 100.52664 -249.493369) (xy 100.550218 -249.447095)
			(xy 100.580744 -249.405079) (xy 100.617467 -249.368356) (xy 100.659483 -249.33783) (xy 100.705757 -249.314252)
			(xy 100.75515 -249.298204) (xy 100.806445 -249.290079) (xy 100.858379 -249.290079) (xy 100.909674 -249.298204)
			(xy 100.959067 -249.314252) (xy 101.005341 -249.33783) (xy 101.047357 -249.368356) (xy 101.08408 -249.405079)
			(xy 101.114606 -249.447095) (xy 101.138184 -249.493369) (xy 101.154232 -249.542762) (xy 101.162357 -249.594057)
			(xy 101.162866 -249.620024) (xy 101.162357 -249.645991) (xy 101.442267 -249.645991) (xy 101.442267 -249.594057)
			(xy 101.450392 -249.542762) (xy 101.46644 -249.493369) (xy 101.490018 -249.447095) (xy 101.520544 -249.405079)
			(xy 101.557267 -249.368356) (xy 101.599283 -249.33783) (xy 101.645557 -249.314252) (xy 101.69495 -249.298204)
			(xy 101.746245 -249.290079) (xy 101.798179 -249.290079) (xy 101.849474 -249.298204) (xy 101.898867 -249.314252)
			(xy 101.945141 -249.33783) (xy 101.987157 -249.368356) (xy 102.02388 -249.405079) (xy 102.054406 -249.447095)
			(xy 102.077984 -249.493369) (xy 102.094032 -249.542762) (xy 102.102157 -249.594057) (xy 102.102666 -249.620024)
			(xy 102.102157 -249.645991) (xy 102.094032 -249.697286) (xy 102.077984 -249.746679) (xy 102.054406 -249.792953)
			(xy 102.02388 -249.834969) (xy 101.987157 -249.871692) (xy 101.945141 -249.902218) (xy 101.898867 -249.925796)
			(xy 101.849474 -249.941844) (xy 101.798179 -249.949969) (xy 101.746245 -249.949969) (xy 101.69495 -249.941844)
			(xy 101.645557 -249.925796) (xy 101.599283 -249.902218) (xy 101.557267 -249.871692) (xy 101.520544 -249.834969)
			(xy 101.490018 -249.792953) (xy 101.46644 -249.746679) (xy 101.450392 -249.697286) (xy 101.442267 -249.645991)
			(xy 101.162357 -249.645991) (xy 101.154232 -249.697286) (xy 101.138184 -249.746679) (xy 101.114606 -249.792953)
			(xy 101.08408 -249.834969) (xy 101.047357 -249.871692) (xy 101.005341 -249.902218) (xy 100.959067 -249.925796)
			(xy 100.909674 -249.941844) (xy 100.858379 -249.949969) (xy 100.806445 -249.949969) (xy 100.75515 -249.941844)
			(xy 100.705757 -249.925796) (xy 100.659483 -249.902218) (xy 100.617467 -249.871692) (xy 100.580744 -249.834969)
			(xy 100.550218 -249.792953) (xy 100.52664 -249.746679) (xy 100.510592 -249.697286) (xy 100.502467 -249.645991)
			(xy 100.222557 -249.645991) (xy 100.214432 -249.697286) (xy 100.198384 -249.746679) (xy 100.174806 -249.792953)
			(xy 100.14428 -249.834969) (xy 100.107557 -249.871692) (xy 100.065541 -249.902218) (xy 100.019267 -249.925796)
			(xy 99.969874 -249.941844) (xy 99.918579 -249.949969) (xy 99.866645 -249.949969) (xy 99.81535 -249.941844)
			(xy 99.765957 -249.925796) (xy 99.719683 -249.902218) (xy 99.677667 -249.871692) (xy 99.640944 -249.834969)
			(xy 99.610418 -249.792953) (xy 99.58684 -249.746679) (xy 99.570792 -249.697286) (xy 99.562667 -249.645991)
			(xy 99.282757 -249.645991) (xy 99.274632 -249.697286) (xy 99.258584 -249.746679) (xy 99.235006 -249.792953)
			(xy 99.20448 -249.834969) (xy 99.167757 -249.871692) (xy 99.125741 -249.902218) (xy 99.079467 -249.925796)
			(xy 99.030074 -249.941844) (xy 98.978779 -249.949969) (xy 98.926845 -249.949969) (xy 98.87555 -249.941844)
			(xy 98.826157 -249.925796) (xy 98.779883 -249.902218) (xy 98.737867 -249.871692) (xy 98.701144 -249.834969)
			(xy 98.670618 -249.792953) (xy 98.64704 -249.746679) (xy 98.630992 -249.697286) (xy 98.622867 -249.645991)
			(xy 98.342957 -249.645991) (xy 98.334832 -249.697286) (xy 98.318784 -249.746679) (xy 98.295206 -249.792953)
			(xy 98.26468 -249.834969) (xy 98.227957 -249.871692) (xy 98.185941 -249.902218) (xy 98.139667 -249.925796)
			(xy 98.090274 -249.941844) (xy 98.038979 -249.949969) (xy 97.987045 -249.949969) (xy 97.93575 -249.941844)
			(xy 97.886357 -249.925796) (xy 97.840083 -249.902218) (xy 97.798067 -249.871692) (xy 97.761344 -249.834969)
			(xy 97.730818 -249.792953) (xy 97.70724 -249.746679) (xy 97.691192 -249.697286) (xy 97.683067 -249.645991)
			(xy 97.403411 -249.645991) (xy 97.395286 -249.697286) (xy 97.379238 -249.746679) (xy 97.35566 -249.792953)
			(xy 97.325134 -249.834969) (xy 97.288411 -249.871692) (xy 97.246395 -249.902218) (xy 97.200121 -249.925796)
			(xy 97.150728 -249.941844) (xy 97.099433 -249.949969) (xy 97.047499 -249.949969) (xy 96.996204 -249.941844)
			(xy 96.946811 -249.925796) (xy 96.900537 -249.902218) (xy 96.858521 -249.871692) (xy 96.821798 -249.834969)
			(xy 96.791272 -249.792953) (xy 96.767694 -249.746679) (xy 96.751646 -249.697286) (xy 96.743521 -249.645991)
			(xy 96.463574 -249.645991) (xy 96.455445 -249.697314) (xy 96.439386 -249.74674) (xy 96.415793 -249.793046)
			(xy 96.385247 -249.83509) (xy 96.348499 -249.871839) (xy 96.306456 -249.902387) (xy 96.260151 -249.925981)
			(xy 96.210726 -249.942042) (xy 96.159397 -249.950174) (xy 96.133412 -249.950732) (xy 96.13265 -249.950732)
			(xy 96.102494 -249.950046) (xy 96.043192 -249.939057) (xy 96.014794 -249.928888) (xy 96.010984 -249.927364)
			(xy 96.000741 -249.92482) (xy 95.979836 -249.927593) (xy 95.970598 -249.932698) (xy 95.934276 -249.957844)
			(xy 95.90024 -249.981212) (xy 95.89066 -249.988711) (xy 95.879369 -250.010216) (xy 95.87865 -250.02236)
			(xy 95.87865 -251.135134) (xy 102.50424 -251.135134) (xy 102.50424 -251.13488) (xy 102.504695 -251.110354)
			(xy 102.51196 -251.061842) (xy 102.526311 -251.014935) (xy 102.547435 -250.970664) (xy 102.574867 -250.929998)
			(xy 102.591108 -250.911614) (xy 102.600876 -250.900098) (xy 102.613889 -250.87287) (xy 102.618362 -250.843025)
			(xy 102.613904 -250.813178) (xy 102.600904 -250.785944) (xy 102.591108 -250.774454) (xy 102.57487 -250.756066)
			(xy 102.547423 -250.715409) (xy 102.526292 -250.671139) (xy 102.511941 -250.62423) (xy 102.504687 -250.575715)
			(xy 102.50424 -250.551188) (xy 102.50424 -250.550934) (xy 102.504749 -250.524967) (xy 102.512874 -250.473672)
			(xy 102.528922 -250.424279) (xy 102.5525 -250.378005) (xy 102.583026 -250.335989) (xy 102.619749 -250.299266)
			(xy 102.661765 -250.26874) (xy 102.708039 -250.245162) (xy 102.757432 -250.229114) (xy 102.808727 -250.220989)
			(xy 102.860661 -250.220989) (xy 102.911956 -250.229114) (xy 102.961349 -250.245162) (xy 103.007623 -250.26874)
			(xy 103.049639 -250.299266) (xy 103.086362 -250.335989) (xy 103.111702 -250.370867) (xy 103.826569 -250.370867)
			(xy 103.826569 -250.318933) (xy 103.834693 -250.267639) (xy 103.850742 -250.218248) (xy 103.874319 -250.171975)
			(xy 103.904845 -250.129961) (xy 103.941568 -250.093239) (xy 103.983584 -250.062714) (xy 104.029857 -250.039138)
			(xy 104.079249 -250.023091) (xy 104.130543 -250.014968) (xy 104.15651 -250.014486) (xy 104.156764 -250.014486)
			(xy 104.18129 -250.014963) (xy 104.229801 -250.02222) (xy 104.276708 -250.036566) (xy 104.32098 -250.057685)
			(xy 104.361645 -250.085115) (xy 104.38003 -250.101354) (xy 104.391519 -250.111157) (xy 104.418756 -250.124171)
			(xy 104.44861 -250.128639) (xy 104.478464 -250.124171) (xy 104.505701 -250.111157) (xy 104.51719 -250.101354)
			(xy 104.535567 -250.085103) (xy 104.576227 -250.057656) (xy 104.620499 -250.036526) (xy 104.66741 -250.022179)
			(xy 104.715928 -250.01493) (xy 104.740456 -250.014486) (xy 104.74071 -250.014486) (xy 104.767353 -250.01502)
			(xy 104.819951 -250.023544) (xy 104.870499 -250.040402) (xy 104.917685 -250.065155) (xy 104.960286 -250.097162)
			(xy 104.997195 -250.135594) (xy 105.012744 -250.157234) (xy 105.021142 -250.168711) (xy 105.043113 -250.186757)
			(xy 105.069208 -250.198044) (xy 105.097404 -250.201698) (xy 105.125514 -250.197435) (xy 105.151359 -250.185586)
			(xy 105.172935 -250.16707) (xy 105.181146 -250.155456) (xy 105.19656 -250.133013) (xy 105.23356 -250.093076)
			(xy 105.27661 -250.059748) (xy 105.324543 -250.033933) (xy 105.376061 -250.01633) (xy 105.429769 -250.007414)
			(xy 105.45699 -250.006866) (xy 105.482743 -250.007367) (xy 105.533628 -250.015345) (xy 105.582657 -250.031124)
			(xy 105.628643 -250.054321) (xy 105.670471 -250.084376) (xy 105.689146 -250.102116) (xy 105.698836 -250.111109)
			(xy 105.721768 -250.124241) (xy 105.747307 -250.131036) (xy 105.773733 -250.131036) (xy 105.799272 -250.124241)
			(xy 105.822204 -250.111109) (xy 105.831894 -250.102116) (xy 105.850579 -250.084388) (xy 105.89241 -250.05434)
			(xy 105.938394 -250.031143) (xy 105.987418 -250.015356) (xy 106.038298 -250.007362) (xy 106.06405 -250.006866)
			(xy 106.091979 -250.00748) (xy 106.147042 -250.01687) (xy 106.199746 -250.035375) (xy 106.248594 -250.062468)
			(xy 106.292198 -250.09738) (xy 106.311192 -250.117864) (xy 106.321185 -250.128413) (xy 106.345804 -250.143827)
			(xy 106.373768 -250.151681) (xy 106.402812 -250.151339) (xy 106.430583 -250.142828) (xy 106.454832 -250.126839)
			(xy 106.464608 -250.116086) (xy 106.480382 -250.098101) (xy 106.516253 -250.066451) (xy 106.556311 -250.040301)
			(xy 106.599719 -250.020196) (xy 106.645572 -250.006556) (xy 106.692911 -249.999667) (xy 106.71683 -249.999246)
			(xy 106.745106 -249.999838) (xy 106.800836 -250.009445) (xy 106.85412 -250.028392) (xy 106.903405 -250.056125)
			(xy 106.947255 -250.091838) (xy 106.966258 -250.112784) (xy 106.976041 -250.12321) (xy 107.000047 -250.138711)
			(xy 107.027408 -250.146953) (xy 107.055981 -250.147294) (xy 107.083531 -250.139706) (xy 107.1079 -250.124782)
			(xy 107.117896 -250.114562) (xy 107.136835 -250.094642) (xy 107.180088 -250.060732) (xy 107.228355 -250.034445)
			(xy 107.280306 -250.016507) (xy 107.33451 -250.007412) (xy 107.36199 -250.006866) (xy 107.387961 -250.007308)
			(xy 107.439265 -250.015432) (xy 107.488666 -250.031482) (xy 107.534947 -250.055063) (xy 107.576971 -250.085593)
			(xy 107.6137 -250.122322) (xy 107.644232 -250.164344) (xy 107.667814 -250.210625) (xy 107.683865 -250.260025)
			(xy 107.691991 -250.311329) (xy 107.691991 -250.363271) (xy 107.683865 -250.414575) (xy 107.667814 -250.463975)
			(xy 107.644232 -250.510256) (xy 107.6137 -250.552278) (xy 107.576971 -250.589007) (xy 107.534947 -250.619537)
			(xy 107.488666 -250.643118) (xy 107.439265 -250.659168) (xy 107.387961 -250.667292) (xy 107.36199 -250.667774)
			(xy 107.333715 -250.667162) (xy 107.277986 -250.657559) (xy 107.224702 -250.638617) (xy 107.175417 -250.610888)
			(xy 107.131567 -250.57518) (xy 107.112562 -250.554236) (xy 107.10276 -250.543828) (xy 107.07876 -250.528324)
			(xy 107.051404 -250.520077) (xy 107.022833 -250.519733) (xy 106.995286 -250.527318) (xy 106.970919 -250.542239)
			(xy 106.960924 -250.552458) (xy 106.941979 -250.572372) (xy 106.898727 -250.606282) (xy 106.850461 -250.632569)
			(xy 106.798512 -250.650509) (xy 106.74431 -250.659607) (xy 106.71683 -250.660154) (xy 106.688901 -250.659546)
			(xy 106.633838 -250.650154) (xy 106.581134 -250.631647) (xy 106.532286 -250.604553) (xy 106.488683 -250.56964)
			(xy 106.469688 -250.549156) (xy 106.459651 -250.538647) (xy 106.435042 -250.523219) (xy 106.407084 -250.515349)
			(xy 106.378041 -250.515676) (xy 106.350267 -250.524174) (xy 106.326012 -250.540152) (xy 106.316272 -250.550934)
			(xy 106.300491 -250.568913) (xy 106.264623 -250.600567) (xy 106.224567 -250.62672) (xy 106.18116 -250.646826)
			(xy 106.135308 -250.660466) (xy 106.087969 -250.667354) (xy 106.06405 -250.667774) (xy 106.038295 -250.667328)
			(xy 105.987407 -250.659339) (xy 105.938376 -250.643548) (xy 105.892391 -250.620338) (xy 105.850566 -250.590271)
			(xy 105.831894 -250.572524) (xy 105.822204 -250.563531) (xy 105.799272 -250.550399) (xy 105.773733 -250.543604)
			(xy 105.747307 -250.543604) (xy 105.721768 -250.550399) (xy 105.698836 -250.563531) (xy 105.689146 -250.572524)
			(xy 105.670494 -250.590288) (xy 105.628654 -250.620329) (xy 105.582661 -250.64352) (xy 105.533629 -250.659298)
			(xy 105.482744 -250.667283) (xy 105.45699 -250.667774) (xy 105.430346 -250.667257) (xy 105.377746 -250.658732)
			(xy 105.327197 -250.641872) (xy 105.280011 -250.617116) (xy 105.237411 -250.585104) (xy 105.200504 -250.546668)
			(xy 105.184956 -250.525026) (xy 105.176563 -250.513543) (xy 105.154594 -250.495487) (xy 105.128497 -250.484192)
			(xy 105.100296 -250.480536) (xy 105.072181 -250.484801) (xy 105.046335 -250.496657) (xy 105.024762 -250.515184)
			(xy 105.016554 -250.526804) (xy 105.001128 -250.549238) (xy 104.964132 -250.589178) (xy 104.921085 -250.622508)
			(xy 104.873154 -250.648325) (xy 104.821638 -250.66593) (xy 104.782986 -250.672346) (xy 114.833908 -250.672346)
			(xy 114.833908 -250.672092) (xy 114.834353 -250.647565) (xy 114.841617 -250.599052) (xy 114.85597 -250.552145)
			(xy 114.877097 -250.507873) (xy 114.904533 -250.467209) (xy 114.920776 -250.448826) (xy 114.930535 -250.437302)
			(xy 114.943553 -250.410077) (xy 114.94803 -250.380234) (xy 114.943573 -250.350388) (xy 114.930573 -250.323155)
			(xy 114.920776 -250.311666) (xy 114.904538 -250.293277) (xy 114.877093 -250.25262) (xy 114.855962 -250.20835)
			(xy 114.841611 -250.161442) (xy 114.834356 -250.112927) (xy 114.833908 -250.0884) (xy 114.833908 -250.088146)
			(xy 114.834417 -250.062179) (xy 114.842542 -250.010884) (xy 114.85859 -249.961491) (xy 114.882168 -249.915217)
			(xy 114.912694 -249.873201) (xy 114.949417 -249.836478) (xy 114.991433 -249.805952) (xy 115.037707 -249.782374)
			(xy 115.0871 -249.766326) (xy 115.138395 -249.758201) (xy 115.190329 -249.758201) (xy 115.241624 -249.766326)
			(xy 115.291017 -249.782374) (xy 115.337291 -249.805952) (xy 115.379307 -249.836478) (xy 115.41603 -249.873201)
			(xy 115.446556 -249.915217) (xy 115.470134 -249.961491) (xy 115.486182 -250.010884) (xy 115.494307 -250.062179)
			(xy 115.494816 -250.088146) (xy 115.494816 -250.0884) (xy 115.49436 -250.112926) (xy 115.487098 -250.161439)
			(xy 115.472747 -250.208346) (xy 115.451623 -250.252618) (xy 115.424189 -250.293282) (xy 115.407948 -250.311666)
			(xy 115.398098 -250.323119) (xy 115.385086 -250.350369) (xy 115.383156 -250.363287) (xy 116.104671 -250.363287)
			(xy 116.104671 -250.311353) (xy 116.112796 -250.260058) (xy 116.128844 -250.210665) (xy 116.152422 -250.164391)
			(xy 116.182948 -250.122375) (xy 116.219671 -250.085652) (xy 116.261687 -250.055126) (xy 116.307961 -250.031548)
			(xy 116.357354 -250.0155) (xy 116.408649 -250.007375) (xy 116.460583 -250.007375) (xy 116.511878 -250.0155)
			(xy 116.561271 -250.031548) (xy 116.607545 -250.055126) (xy 116.649561 -250.085652) (xy 116.686284 -250.122375)
			(xy 116.71681 -250.164391) (xy 116.740388 -250.210665) (xy 116.756436 -250.260058) (xy 116.764561 -250.311353)
			(xy 116.76507 -250.33732) (xy 116.764561 -250.363265) (xy 116.871775 -250.363265) (xy 116.871775 -250.311335)
			(xy 116.879899 -250.260043) (xy 116.895946 -250.210654) (xy 116.919522 -250.164383) (xy 116.950046 -250.12237)
			(xy 116.986767 -250.085649) (xy 117.028779 -250.055124) (xy 117.07505 -250.031548) (xy 117.124439 -250.0155)
			(xy 117.175731 -250.007375) (xy 117.201696 -250.006866) (xy 117.228276 -250.007408) (xy 117.280753 -250.015912)
			(xy 117.331193 -250.0327) (xy 117.378299 -250.05734) (xy 117.420856 -250.089198) (xy 117.439694 -250.107958)
			(xy 117.449465 -250.117483) (xy 117.472907 -250.131427) (xy 117.499208 -250.138657) (xy 117.526484 -250.138657)
			(xy 117.552785 -250.131427) (xy 117.576227 -250.117483) (xy 117.585998 -250.107958) (xy 117.604831 -250.089193)
			(xy 117.647389 -250.057333) (xy 117.694496 -250.032691) (xy 117.744937 -250.015901) (xy 117.797415 -250.007396)
			(xy 117.823996 -250.006866) (xy 117.849856 -250.007377) (xy 117.900948 -250.015422) (xy 117.95016 -250.031332)
			(xy 117.996292 -250.054717) (xy 118.038215 -250.085007) (xy 118.056914 -250.102878) (xy 118.066629 -250.111923)
			(xy 118.089638 -250.125135) (xy 118.115275 -250.131972) (xy 118.141809 -250.131972) (xy 118.167446 -250.125135)
			(xy 118.190455 -250.111923) (xy 118.20017 -250.102878) (xy 118.218859 -250.084997) (xy 118.26079 -250.054717)
			(xy 118.306925 -250.031335) (xy 118.356137 -250.015423) (xy 118.407227 -250.007367) (xy 118.433088 -250.006866)
			(xy 118.457474 -250.007296) (xy 118.505717 -250.014451) (xy 118.552384 -250.028621) (xy 118.596461 -250.049499)
			(xy 118.636988 -250.076631) (xy 118.673086 -250.109427) (xy 118.688866 -250.128024) (xy 118.698787 -250.139259)
			(xy 118.723704 -250.155889) (xy 118.752373 -250.164577) (xy 118.782331 -250.164577) (xy 118.811 -250.155889)
			(xy 118.835917 -250.139259) (xy 118.845838 -250.128024) (xy 118.861652 -250.109459) (xy 118.897751 -250.076674)
			(xy 118.938274 -250.049546) (xy 118.982342 -250.028665) (xy 119.028999 -250.014483) (xy 119.077234 -250.007308)
			(xy 119.101616 -250.006866) (xy 119.128915 -250.007387) (xy 119.182769 -250.016372) (xy 119.234412 -250.034095)
			(xy 119.282435 -250.060071) (xy 119.32553 -250.093595) (xy 119.34444 -250.113292) (xy 119.354273 -250.123272)
			(xy 119.378157 -250.137898) (xy 119.405113 -250.145497) (xy 119.433119 -250.145497) (xy 119.460075 -250.137898)
			(xy 119.483959 -250.123272) (xy 119.493792 -250.113292) (xy 119.512697 -250.093592) (xy 119.555798 -250.060082)
			(xy 119.603824 -250.034116) (xy 119.655466 -250.016404) (xy 119.709318 -250.007427) (xy 119.736616 -250.006866)
			(xy 119.762584 -250.007337) (xy 119.81388 -250.015463) (xy 119.863274 -250.031514) (xy 119.909548 -250.055094)
			(xy 119.951564 -250.085623) (xy 119.988288 -250.122348) (xy 120.018814 -250.164366) (xy 120.042392 -250.210641)
			(xy 120.05844 -250.260035) (xy 120.066565 -250.311332) (xy 120.066565 -250.363268) (xy 120.05844 -250.414565)
			(xy 120.042392 -250.463959) (xy 120.018814 -250.510234) (xy 119.988288 -250.552252) (xy 119.951564 -250.588977)
			(xy 119.909548 -250.619506) (xy 119.863274 -250.643086) (xy 119.81388 -250.659137) (xy 119.762584 -250.667263)
			(xy 119.736616 -250.667774) (xy 119.709318 -250.667219) (xy 119.655466 -250.65824) (xy 119.603825 -250.640525)
			(xy 119.555801 -250.614556) (xy 119.512704 -250.581041) (xy 119.493792 -250.561348) (xy 119.483959 -250.551368)
			(xy 119.460075 -250.536742) (xy 119.433119 -250.529143) (xy 119.405113 -250.529143) (xy 119.378157 -250.536742)
			(xy 119.354273 -250.551368) (xy 119.34444 -250.561348) (xy 119.325528 -250.58104) (xy 119.282428 -250.61455)
			(xy 119.234404 -250.640515) (xy 119.182763 -250.65823) (xy 119.128913 -250.667211) (xy 119.101616 -250.667774)
			(xy 119.077229 -250.667363) (xy 119.028984 -250.660207) (xy 118.982316 -250.646035) (xy 118.938239 -250.625153)
			(xy 118.897712 -250.598017) (xy 118.861616 -250.565216) (xy 118.845838 -250.546616) (xy 118.835917 -250.535381)
			(xy 118.811 -250.518751) (xy 118.782331 -250.510063) (xy 118.752373 -250.510063) (xy 118.723704 -250.518751)
			(xy 118.698787 -250.535381) (xy 118.688866 -250.546616) (xy 118.673059 -250.565187) (xy 118.636958 -250.59797)
			(xy 118.596433 -250.625096) (xy 118.552363 -250.645976) (xy 118.505705 -250.660157) (xy 118.457471 -250.667332)
			(xy 118.433088 -250.667774) (xy 118.407228 -250.667262) (xy 118.356137 -250.659216) (xy 118.306925 -250.643306)
			(xy 118.260793 -250.619921) (xy 118.218869 -250.589632) (xy 118.20017 -250.571762) (xy 118.190455 -250.562717)
			(xy 118.167446 -250.549505) (xy 118.141809 -250.542668) (xy 118.115275 -250.542668) (xy 118.089638 -250.549505)
			(xy 118.066629 -250.562717) (xy 118.056914 -250.571762) (xy 118.038222 -250.58964) (xy 117.996293 -250.619923)
			(xy 117.95016 -250.643306) (xy 117.900947 -250.659219) (xy 117.849857 -250.667274) (xy 117.823996 -250.667774)
			(xy 117.797414 -250.667255) (xy 117.744936 -250.658749) (xy 117.694495 -250.641956) (xy 117.64739 -250.61731)
			(xy 117.604834 -250.585445) (xy 117.585998 -250.566682) (xy 117.576227 -250.557157) (xy 117.552785 -250.543213)
			(xy 117.526484 -250.535983) (xy 117.499208 -250.535983) (xy 117.472907 -250.543213) (xy 117.449465 -250.557157)
			(xy 117.439694 -250.566682) (xy 117.420854 -250.58544) (xy 117.378299 -250.617304) (xy 117.331195 -250.641948)
			(xy 117.280754 -250.658739) (xy 117.228277 -250.667244) (xy 117.201696 -250.667774) (xy 117.175731 -250.667225)
			(xy 117.124439 -250.6591) (xy 117.07505 -250.643052) (xy 117.028779 -250.619476) (xy 116.986767 -250.588951)
			(xy 116.950046 -250.55223) (xy 116.919522 -250.510217) (xy 116.895946 -250.463946) (xy 116.879899 -250.414557)
			(xy 116.871775 -250.363265) (xy 116.764561 -250.363265) (xy 116.764561 -250.363287) (xy 116.756436 -250.414582)
			(xy 116.740388 -250.463975) (xy 116.71681 -250.510249) (xy 116.686284 -250.552265) (xy 116.649561 -250.588988)
			(xy 116.607545 -250.619514) (xy 116.561271 -250.643092) (xy 116.511878 -250.65914) (xy 116.460583 -250.667265)
			(xy 116.408649 -250.667265) (xy 116.357354 -250.65914) (xy 116.307961 -250.643092) (xy 116.261687 -250.619514)
			(xy 116.219671 -250.588988) (xy 116.182948 -250.552265) (xy 116.152422 -250.510249) (xy 116.128844 -250.463975)
			(xy 116.112796 -250.414582) (xy 116.104671 -250.363287) (xy 115.383156 -250.363287) (xy 115.380625 -250.380234)
			(xy 115.385106 -250.410097) (xy 115.398136 -250.437337) (xy 115.407948 -250.448826) (xy 115.424169 -250.467228)
			(xy 115.45162 -250.507881) (xy 115.472756 -250.552147) (xy 115.48711 -250.599053) (xy 115.494368 -250.647566)
			(xy 115.494816 -250.672092) (xy 115.494816 -250.672346) (xy 115.494307 -250.698313) (xy 115.486182 -250.749608)
			(xy 115.470134 -250.799001) (xy 115.446556 -250.845275) (xy 115.41603 -250.887291) (xy 115.379307 -250.924014)
			(xy 115.337291 -250.95454) (xy 115.291017 -250.978118) (xy 115.241624 -250.994166) (xy 115.190329 -251.002291)
			(xy 115.138395 -251.002291) (xy 115.0871 -250.994166) (xy 115.037707 -250.978118) (xy 114.991433 -250.95454)
			(xy 114.949417 -250.924014) (xy 114.912694 -250.887291) (xy 114.882168 -250.845275) (xy 114.85859 -250.799001)
			(xy 114.842542 -250.749608) (xy 114.834417 -250.698313) (xy 114.833908 -250.672346) (xy 104.782986 -250.672346)
			(xy 104.767931 -250.674845) (xy 104.74071 -250.675394) (xy 104.740456 -250.675394) (xy 104.715928 -250.67497)
			(xy 104.667414 -250.667701) (xy 104.620507 -250.653343) (xy 104.576236 -250.632212) (xy 104.535573 -250.604771)
			(xy 104.51719 -250.588526) (xy 104.505701 -250.578723) (xy 104.478464 -250.565709) (xy 104.44861 -250.561241)
			(xy 104.418756 -250.565709) (xy 104.391519 -250.578723) (xy 104.38003 -250.588526) (xy 104.361656 -250.604781)
			(xy 104.320994 -250.632224) (xy 104.276721 -250.653352) (xy 104.22981 -250.667699) (xy 104.181292 -250.674949)
			(xy 104.156764 -250.675394) (xy 104.15651 -250.675394) (xy 104.130543 -250.674832) (xy 104.079249 -250.666709)
			(xy 104.029857 -250.650662) (xy 103.983584 -250.627086) (xy 103.941568 -250.596561) (xy 103.904845 -250.559839)
			(xy 103.874319 -250.517825) (xy 103.850742 -250.471552) (xy 103.834693 -250.422161) (xy 103.826569 -250.370867)
			(xy 103.111702 -250.370867) (xy 103.116888 -250.378005) (xy 103.140466 -250.424279) (xy 103.156514 -250.473672)
			(xy 103.164639 -250.524967) (xy 103.165148 -250.550934) (xy 103.165148 -250.551188) (xy 103.164677 -250.575714)
			(xy 103.157417 -250.624225) (xy 103.143069 -250.671132) (xy 103.121949 -250.715404) (xy 103.094519 -250.756069)
			(xy 103.07828 -250.774454) (xy 103.068447 -250.785919) (xy 103.055443 -250.813165) (xy 103.050983 -250.843025)
			(xy 103.055457 -250.872883) (xy 103.068475 -250.900123) (xy 103.07828 -250.911614) (xy 103.094548 -250.929977)
			(xy 103.121991 -250.970641) (xy 103.143117 -251.014917) (xy 103.157461 -251.061831) (xy 103.164706 -251.110351)
			(xy 103.165148 -251.13488) (xy 103.165148 -251.135134) (xy 103.164639 -251.161101) (xy 103.156514 -251.212396)
			(xy 103.140466 -251.261789) (xy 103.116888 -251.308063) (xy 103.086362 -251.350079) (xy 103.049639 -251.386802)
			(xy 103.007623 -251.417328) (xy 102.961349 -251.440906) (xy 102.960432 -251.441204) (xy 120.645936 -251.441204)
			(xy 120.645936 -251.44095) (xy 120.646374 -251.416423) (xy 120.653643 -251.36791) (xy 120.667999 -251.321004)
			(xy 120.689126 -251.276732) (xy 120.716562 -251.236068) (xy 120.732804 -251.217684) (xy 120.742601 -251.206191)
			(xy 120.755612 -251.178955) (xy 120.760079 -251.149103) (xy 120.755613 -251.119251) (xy 120.742604 -251.092014)
			(xy 120.732804 -251.080524) (xy 120.716551 -251.062148) (xy 120.689106 -251.021488) (xy 120.667978 -250.977215)
			(xy 120.653631 -250.930304) (xy 120.646381 -250.881786) (xy 120.645936 -250.857258) (xy 120.645936 -250.857004)
			(xy 120.646445 -250.831037) (xy 120.65457 -250.779742) (xy 120.670618 -250.730349) (xy 120.694196 -250.684075)
			(xy 120.724722 -250.642059) (xy 120.761445 -250.605336) (xy 120.803461 -250.57481) (xy 120.849735 -250.551232)
			(xy 120.899128 -250.535184) (xy 120.950423 -250.527059) (xy 121.002357 -250.527059) (xy 121.053652 -250.535184)
			(xy 121.103045 -250.551232) (xy 121.149319 -250.57481) (xy 121.191335 -250.605336) (xy 121.228058 -250.642059)
			(xy 121.258584 -250.684075) (xy 121.282162 -250.730349) (xy 121.29821 -250.779742) (xy 121.306335 -250.831037)
			(xy 121.306844 -250.857004) (xy 121.306844 -250.857258) (xy 121.306416 -250.881785) (xy 121.299145 -250.930299)
			(xy 121.284788 -250.977206) (xy 121.263658 -251.021477) (xy 121.236219 -251.062141) (xy 121.219976 -251.080524)
			(xy 121.210172 -251.092012) (xy 121.197165 -251.11925) (xy 121.1927 -251.149103) (xy 121.197167 -251.178955)
			(xy 121.210176 -251.206193) (xy 121.219976 -251.217684) (xy 121.236229 -251.236059) (xy 121.263675 -251.27672)
			(xy 121.284803 -251.320993) (xy 121.29915 -251.367904) (xy 121.3064 -251.416422) (xy 121.306844 -251.44095)
			(xy 121.306844 -251.441204) (xy 121.306335 -251.467171) (xy 121.29821 -251.518466) (xy 121.282162 -251.567859)
			(xy 121.258584 -251.614133) (xy 121.228058 -251.656149) (xy 121.191335 -251.692872) (xy 121.149319 -251.723398)
			(xy 121.103045 -251.746976) (xy 121.053652 -251.763024) (xy 121.002357 -251.771149) (xy 120.950423 -251.771149)
			(xy 120.899128 -251.763024) (xy 120.849735 -251.746976) (xy 120.803461 -251.723398) (xy 120.761445 -251.692872)
			(xy 120.724722 -251.656149) (xy 120.694196 -251.614133) (xy 120.670618 -251.567859) (xy 120.65457 -251.518466)
			(xy 120.646445 -251.467171) (xy 120.645936 -251.441204) (xy 102.960432 -251.441204) (xy 102.911956 -251.456954)
			(xy 102.860661 -251.465079) (xy 102.808727 -251.465079) (xy 102.757432 -251.456954) (xy 102.708039 -251.440906)
			(xy 102.661765 -251.417328) (xy 102.619749 -251.386802) (xy 102.583026 -251.350079) (xy 102.5525 -251.308063)
			(xy 102.528922 -251.261789) (xy 102.512874 -251.212396) (xy 102.504749 -251.161101) (xy 102.50424 -251.135134)
			(xy 95.87865 -251.135134) (xy 95.87865 -251.431806) (xy 95.878127 -251.44165) (xy 95.870562 -251.459832)
			(xy 95.863918 -251.467112) (xy 94.199143 -253.131887) (xy 94.973395 -253.131887) (xy 94.973395 -253.079953)
			(xy 94.98152 -253.028658) (xy 94.997568 -252.979265) (xy 95.021146 -252.932991) (xy 95.051672 -252.890975)
			(xy 95.088395 -252.854252) (xy 95.130411 -252.823726) (xy 95.176685 -252.800148) (xy 95.226078 -252.7841)
			(xy 95.277373 -252.775975) (xy 95.329307 -252.775975) (xy 95.380602 -252.7841) (xy 95.425951 -252.798834)
			(xy 102.5652 -252.798834) (xy 102.5652 -252.79858) (xy 102.56564 -252.774053) (xy 102.572906 -252.72554)
			(xy 102.58726 -252.678632) (xy 102.608388 -252.634361) (xy 102.635825 -252.593697) (xy 102.652068 -252.575314)
			(xy 102.661839 -252.563799) (xy 102.674857 -252.536571) (xy 102.679333 -252.506725) (xy 102.674872 -252.476877)
			(xy 102.661867 -252.449643) (xy 102.652068 -252.438154) (xy 102.63584 -252.419757) (xy 102.608389 -252.379104)
			(xy 102.587255 -252.334836) (xy 102.572902 -252.287929) (xy 102.565647 -252.239415) (xy 102.5652 -252.214888)
			(xy 102.5652 -252.214634) (xy 102.565709 -252.188667) (xy 102.573834 -252.137372) (xy 102.589882 -252.087979)
			(xy 102.61346 -252.041705) (xy 102.643986 -251.999689) (xy 102.680709 -251.962966) (xy 102.722725 -251.93244)
			(xy 102.768999 -251.908862) (xy 102.818392 -251.892814) (xy 102.869687 -251.884689) (xy 102.921621 -251.884689)
			(xy 102.972916 -251.892814) (xy 103.022309 -251.908862) (xy 103.068583 -251.93244) (xy 103.110599 -251.962966)
			(xy 103.147322 -251.999689) (xy 103.177848 -252.041705) (xy 103.201426 -252.087979) (xy 103.217474 -252.137372)
			(xy 103.225599 -252.188667) (xy 103.226108 -252.214634) (xy 103.226108 -252.214888) (xy 103.225647 -252.239414)
			(xy 103.218386 -252.287927) (xy 103.204037 -252.334834) (xy 103.182914 -252.379105) (xy 103.155481 -252.41977)
			(xy 103.13924 -252.438154) (xy 103.129402 -252.449617) (xy 103.11639 -252.476863) (xy 103.111927 -252.506725)
			(xy 103.116405 -252.536585) (xy 103.12943 -252.563825) (xy 103.13924 -252.575314) (xy 103.155502 -252.593682)
			(xy 103.182947 -252.634344) (xy 103.194898 -252.659388) (xy 108.103416 -252.659388) (xy 108.103416 -252.659134)
			(xy 108.103884 -252.634608) (xy 108.111142 -252.586096) (xy 108.12549 -252.539189) (xy 108.146611 -252.494917)
			(xy 108.174043 -252.454252) (xy 108.190284 -252.435868) (xy 108.200098 -252.424388) (xy 108.21311 -252.397147)
			(xy 108.217575 -252.367291) (xy 108.213104 -252.337436) (xy 108.200088 -252.310198) (xy 108.190284 -252.298708)
			(xy 108.17402 -252.280342) (xy 108.146578 -252.239678) (xy 108.125452 -252.195403) (xy 108.111107 -252.14849)
			(xy 108.103859 -252.099971) (xy 108.103416 -252.075442) (xy 108.103416 -252.075188) (xy 108.103925 -252.049221)
			(xy 108.11205 -251.997926) (xy 108.128098 -251.948533) (xy 108.151676 -251.902259) (xy 108.182202 -251.860243)
			(xy 108.218925 -251.82352) (xy 108.260941 -251.792994) (xy 108.307215 -251.769416) (xy 108.356608 -251.753368)
			(xy 108.407903 -251.745243) (xy 108.459837 -251.745243) (xy 108.511132 -251.753368) (xy 108.560525 -251.769416)
			(xy 108.606799 -251.792994) (xy 108.648815 -251.82352) (xy 108.685538 -251.860243) (xy 108.716064 -251.902259)
			(xy 108.739642 -251.948533) (xy 108.75569 -251.997926) (xy 108.763815 -252.049221) (xy 108.764324 -252.075188)
			(xy 108.764324 -252.075442) (xy 108.763891 -252.099969) (xy 108.756623 -252.148483) (xy 108.742267 -252.19539)
			(xy 108.721137 -252.239661) (xy 108.693699 -252.280325) (xy 108.677456 -252.298708) (xy 108.667662 -252.310205)
			(xy 108.654642 -252.337439) (xy 108.65017 -252.367291) (xy 108.654637 -252.397144) (xy 108.667652 -252.42438)
			(xy 108.677456 -252.435868) (xy 108.693699 -252.454253) (xy 108.721146 -252.49491) (xy 108.742277 -252.539181)
			(xy 108.756627 -252.58609) (xy 108.763879 -252.634606) (xy 108.764324 -252.659134) (xy 108.764324 -252.659388)
			(xy 108.763886 -252.683302) (xy 108.756988 -252.730628) (xy 108.743335 -252.776465) (xy 108.729661 -252.805946)
			(xy 115.103148 -252.805946) (xy 115.103148 -252.805692) (xy 115.103608 -252.781166) (xy 115.110871 -252.732654)
			(xy 115.125221 -252.685747) (xy 115.146344 -252.641476) (xy 115.173776 -252.600811) (xy 115.190016 -252.582426)
			(xy 115.199771 -252.5709) (xy 115.212785 -252.543675) (xy 115.21726 -252.513834) (xy 115.212805 -252.48399)
			(xy 115.199809 -252.456756) (xy 115.190016 -252.445266) (xy 115.173785 -252.426872) (xy 115.146337 -252.386216)
			(xy 115.125204 -252.341948) (xy 115.110852 -252.295041) (xy 115.103596 -252.246527) (xy 115.103148 -252.222)
			(xy 115.103148 -252.221746) (xy 115.103657 -252.195779) (xy 115.111782 -252.144484) (xy 115.12783 -252.095091)
			(xy 115.151408 -252.048817) (xy 115.181934 -252.006801) (xy 115.218657 -251.970078) (xy 115.260673 -251.939552)
			(xy 115.306947 -251.915974) (xy 115.35634 -251.899926) (xy 115.407635 -251.891801) (xy 115.459569 -251.891801)
			(xy 115.510864 -251.899926) (xy 115.560257 -251.915974) (xy 115.606531 -251.939552) (xy 115.648547 -251.970078)
			(xy 115.68527 -252.006801) (xy 115.715796 -252.048817) (xy 115.739374 -252.095091) (xy 115.755422 -252.144484)
			(xy 115.763547 -252.195779) (xy 115.764056 -252.221746) (xy 115.764056 -252.222) (xy 115.76359 -252.246526)
			(xy 115.756328 -252.295037) (xy 115.741979 -252.341944) (xy 115.720858 -252.386216) (xy 115.693428 -252.426881)
			(xy 115.677188 -252.445266) (xy 115.667342 -252.456721) (xy 115.654339 -252.483971) (xy 115.64988 -252.513834)
			(xy 115.654358 -252.543694) (xy 115.667381 -252.570935) (xy 115.677188 -252.582426) (xy 115.693416 -252.600823)
			(xy 115.720865 -252.641478) (xy 115.741998 -252.685745) (xy 115.756351 -252.732652) (xy 115.763608 -252.781165)
			(xy 115.764056 -252.805692) (xy 115.764056 -252.805946) (xy 115.763547 -252.831913) (xy 115.755422 -252.883208)
			(xy 115.739374 -252.932601) (xy 115.715796 -252.978875) (xy 115.68527 -253.020891) (xy 115.648547 -253.057614)
			(xy 115.606531 -253.08814) (xy 115.560257 -253.111718) (xy 115.510864 -253.127766) (xy 115.459569 -253.135891)
			(xy 115.407635 -253.135891) (xy 115.35634 -253.127766) (xy 115.306947 -253.111718) (xy 115.260673 -253.08814)
			(xy 115.218657 -253.057614) (xy 115.181934 -253.020891) (xy 115.151408 -252.978875) (xy 115.12783 -252.932601)
			(xy 115.111782 -252.883208) (xy 115.103657 -252.831913) (xy 115.103148 -252.805946) (xy 108.729661 -252.805946)
			(xy 108.723211 -252.819853) (xy 108.697039 -252.859883) (xy 108.68152 -252.878082) (xy 108.672942 -252.888424)
			(xy 108.661082 -252.912526) (xy 108.655912 -252.938885) (xy 108.657791 -252.965681) (xy 108.666587 -252.991062)
			(xy 108.681694 -253.013273) (xy 108.702067 -253.03078) (xy 108.726299 -253.042373) (xy 108.739432 -253.045214)
			(xy 108.764493 -253.050198) (xy 108.812754 -253.066985) (xy 108.857857 -253.090999) (xy 108.898726 -253.121669)
			(xy 108.934388 -253.158264) (xy 108.959652 -253.193804) (xy 120.645936 -253.193804) (xy 120.645936 -253.19355)
			(xy 120.646374 -253.169023) (xy 120.653643 -253.12051) (xy 120.667999 -253.073604) (xy 120.689126 -253.029332)
			(xy 120.716562 -252.988668) (xy 120.732804 -252.970284) (xy 120.742601 -252.958791) (xy 120.755612 -252.931555)
			(xy 120.760079 -252.901703) (xy 120.755613 -252.871851) (xy 120.742604 -252.844614) (xy 120.732804 -252.833124)
			(xy 120.716551 -252.814748) (xy 120.689106 -252.774088) (xy 120.667978 -252.729815) (xy 120.653631 -252.682904)
			(xy 120.646381 -252.634386) (xy 120.645936 -252.609858) (xy 120.645936 -252.609604) (xy 120.646445 -252.583637)
			(xy 120.65457 -252.532342) (xy 120.670618 -252.482949) (xy 120.694196 -252.436675) (xy 120.724722 -252.394659)
			(xy 120.761445 -252.357936) (xy 120.803461 -252.32741) (xy 120.849735 -252.303832) (xy 120.899128 -252.287784)
			(xy 120.950423 -252.279659) (xy 121.002357 -252.279659) (xy 121.053652 -252.287784) (xy 121.103045 -252.303832)
			(xy 121.149319 -252.32741) (xy 121.191335 -252.357936) (xy 121.228058 -252.394659) (xy 121.258584 -252.436675)
			(xy 121.282162 -252.482949) (xy 121.29821 -252.532342) (xy 121.306335 -252.583637) (xy 121.306844 -252.609604)
			(xy 121.306844 -252.609858) (xy 121.306416 -252.634385) (xy 121.299145 -252.682899) (xy 121.284788 -252.729806)
			(xy 121.263658 -252.774077) (xy 121.236219 -252.814741) (xy 121.219976 -252.833124) (xy 121.210172 -252.844612)
			(xy 121.197165 -252.87185) (xy 121.1927 -252.901703) (xy 121.197167 -252.931555) (xy 121.210176 -252.958793)
			(xy 121.219976 -252.970284) (xy 121.236229 -252.988659) (xy 121.263675 -253.02932) (xy 121.284803 -253.073593)
			(xy 121.29915 -253.120504) (xy 121.3064 -253.169022) (xy 121.306844 -253.19355) (xy 121.306844 -253.193804)
			(xy 121.306335 -253.219771) (xy 121.29821 -253.271066) (xy 121.282162 -253.320459) (xy 121.258584 -253.366733)
			(xy 121.228058 -253.408749) (xy 121.191335 -253.445472) (xy 121.149319 -253.475998) (xy 121.103045 -253.499576)
			(xy 121.053652 -253.515624) (xy 121.002357 -253.523749) (xy 120.950423 -253.523749) (xy 120.899128 -253.515624)
			(xy 120.849735 -253.499576) (xy 120.803461 -253.475998) (xy 120.761445 -253.445472) (xy 120.724722 -253.408749)
			(xy 120.694196 -253.366733) (xy 120.670618 -253.320459) (xy 120.65457 -253.271066) (xy 120.646445 -253.219771)
			(xy 120.645936 -253.193804) (xy 108.959652 -253.193804) (xy 108.963993 -253.199911) (xy 108.986835 -253.245618)
			(xy 109.002371 -253.294296) (xy 109.01023 -253.344785) (xy 109.010704 -253.370334) (xy 109.010704 -253.370588)
			(xy 109.010244 -253.395114) (xy 109.002983 -253.443627) (xy 108.988633 -253.490534) (xy 108.96751 -253.534806)
			(xy 108.940077 -253.57547) (xy 108.923836 -253.593854) (xy 108.913998 -253.605317) (xy 108.900987 -253.632563)
			(xy 108.896524 -253.662425) (xy 108.901002 -253.692285) (xy 108.914027 -253.719525) (xy 108.923836 -253.731014)
			(xy 108.940097 -253.749383) (xy 108.967543 -253.790044) (xy 108.988671 -253.834319) (xy 109.003016 -253.881232)
			(xy 109.010262 -253.929751) (xy 109.010554 -253.945957) (xy 109.540803 -253.945957) (xy 109.540803 -253.894023)
			(xy 109.548928 -253.842728) (xy 109.564976 -253.793335) (xy 109.588554 -253.747061) (xy 109.61908 -253.705045)
			(xy 109.655803 -253.668322) (xy 109.697819 -253.637796) (xy 109.744093 -253.614218) (xy 109.793486 -253.59817)
			(xy 109.844781 -253.590045) (xy 109.896715 -253.590045) (xy 109.94801 -253.59817) (xy 109.997403 -253.614218)
			(xy 110.043677 -253.637796) (xy 110.085693 -253.668322) (xy 110.122416 -253.705045) (xy 110.152942 -253.747061)
			(xy 110.17652 -253.793335) (xy 110.192568 -253.842728) (xy 110.200693 -253.894023) (xy 110.201202 -253.91999)
			(xy 110.200693 -253.945957) (xy 110.480857 -253.945957) (xy 110.480857 -253.894023) (xy 110.488982 -253.842728)
			(xy 110.50503 -253.793335) (xy 110.528608 -253.747061) (xy 110.559134 -253.705045) (xy 110.595857 -253.668322)
			(xy 110.637873 -253.637796) (xy 110.684147 -253.614218) (xy 110.73354 -253.59817) (xy 110.784835 -253.590045)
			(xy 110.836769 -253.590045) (xy 110.888064 -253.59817) (xy 110.937457 -253.614218) (xy 110.983731 -253.637796)
			(xy 111.025747 -253.668322) (xy 111.06247 -253.705045) (xy 111.092996 -253.747061) (xy 111.116574 -253.793335)
			(xy 111.132622 -253.842728) (xy 111.140747 -253.894023) (xy 111.141256 -253.91999) (xy 111.140747 -253.945957)
			(xy 111.420403 -253.945957) (xy 111.420403 -253.894023) (xy 111.428528 -253.842728) (xy 111.444576 -253.793335)
			(xy 111.468154 -253.747061) (xy 111.49868 -253.705045) (xy 111.535403 -253.668322) (xy 111.577419 -253.637796)
			(xy 111.623693 -253.614218) (xy 111.673086 -253.59817) (xy 111.724381 -253.590045) (xy 111.776315 -253.590045)
			(xy 111.82761 -253.59817) (xy 111.877003 -253.614218) (xy 111.923277 -253.637796) (xy 111.965293 -253.668322)
			(xy 112.002016 -253.705045) (xy 112.032542 -253.747061) (xy 112.05612 -253.793335) (xy 112.072168 -253.842728)
			(xy 112.080293 -253.894023) (xy 112.080802 -253.91999) (xy 112.080293 -253.945957) (xy 112.360203 -253.945957)
			(xy 112.360203 -253.894023) (xy 112.368328 -253.842728) (xy 112.384376 -253.793335) (xy 112.407954 -253.747061)
			(xy 112.43848 -253.705045) (xy 112.475203 -253.668322) (xy 112.517219 -253.637796) (xy 112.563493 -253.614218)
			(xy 112.612886 -253.59817) (xy 112.664181 -253.590045) (xy 112.716115 -253.590045) (xy 112.76741 -253.59817)
			(xy 112.816803 -253.614218) (xy 112.863077 -253.637796) (xy 112.905093 -253.668322) (xy 112.941816 -253.705045)
			(xy 112.972342 -253.747061) (xy 112.99592 -253.793335) (xy 113.011968 -253.842728) (xy 113.020093 -253.894023)
			(xy 113.020602 -253.91999) (xy 113.020093 -253.945957) (xy 113.300003 -253.945957) (xy 113.300003 -253.894023)
			(xy 113.308128 -253.842728) (xy 113.324176 -253.793335) (xy 113.347754 -253.747061) (xy 113.37828 -253.705045)
			(xy 113.415003 -253.668322) (xy 113.457019 -253.637796) (xy 113.503293 -253.614218) (xy 113.552686 -253.59817)
			(xy 113.603981 -253.590045) (xy 113.655915 -253.590045) (xy 113.70721 -253.59817) (xy 113.756603 -253.614218)
			(xy 113.802877 -253.637796) (xy 113.844893 -253.668322) (xy 113.881616 -253.705045) (xy 113.912142 -253.747061)
			(xy 113.93572 -253.793335) (xy 113.951768 -253.842728) (xy 113.959893 -253.894023) (xy 113.960402 -253.91999)
			(xy 113.959893 -253.945957) (xy 113.959891 -253.945972) (xy 114.239719 -253.945972) (xy 114.239719 -253.894028)
			(xy 114.247846 -253.842722) (xy 114.263899 -253.79332) (xy 114.287484 -253.747038) (xy 114.318019 -253.705015)
			(xy 114.354752 -253.668287) (xy 114.396779 -253.637758) (xy 114.443065 -253.614181) (xy 114.492469 -253.598135)
			(xy 114.543775 -253.590015) (xy 114.569748 -253.589536) (xy 114.591804 -253.589918) (xy 114.635521 -253.595805)
			(xy 114.67807 -253.607442) (xy 114.698526 -253.615698) (xy 114.712847 -253.621228) (xy 114.743371 -253.624357)
			(xy 114.773446 -253.618274) (xy 114.800354 -253.603528) (xy 114.821664 -253.581451) (xy 114.835451 -253.554039)
			(xy 114.83848 -253.53899) (xy 114.8432 -253.513604) (xy 114.859496 -253.46461) (xy 114.883217 -253.418749)
			(xy 114.913785 -253.377137) (xy 114.950456 -253.340789) (xy 114.992336 -253.310589) (xy 115.038404 -253.287273)
			(xy 115.08754 -253.27141) (xy 115.138545 -253.263386) (xy 115.164362 -253.262892) (xy 115.190333 -253.263364)
			(xy 115.241635 -253.271485) (xy 115.291035 -253.287532) (xy 115.337315 -253.311111) (xy 115.379337 -253.341641)
			(xy 115.416064 -253.378369) (xy 115.446593 -253.420391) (xy 115.470171 -253.466673) (xy 115.486217 -253.516073)
			(xy 115.494337 -253.567375) (xy 115.494816 -253.593346) (xy 115.494816 -253.5936) (xy 115.49436 -253.618126)
			(xy 115.487098 -253.666639) (xy 115.472747 -253.713546) (xy 115.451623 -253.757818) (xy 115.424189 -253.798482)
			(xy 115.407948 -253.816866) (xy 115.398098 -253.828319) (xy 115.385086 -253.855569) (xy 115.380625 -253.885434)
			(xy 115.385106 -253.915297) (xy 115.398136 -253.942537) (xy 115.407948 -253.954026) (xy 115.424169 -253.972428)
			(xy 115.45162 -254.013081) (xy 115.467475 -254.046287) (xy 116.104671 -254.046287) (xy 116.104671 -253.994353)
			(xy 116.112796 -253.943058) (xy 116.128844 -253.893665) (xy 116.152422 -253.847391) (xy 116.182948 -253.805375)
			(xy 116.219671 -253.768652) (xy 116.261687 -253.738126) (xy 116.307961 -253.714548) (xy 116.357354 -253.6985)
			(xy 116.408649 -253.690375) (xy 116.460583 -253.690375) (xy 116.511878 -253.6985) (xy 116.561271 -253.714548)
			(xy 116.607545 -253.738126) (xy 116.649561 -253.768652) (xy 116.686284 -253.805375) (xy 116.71681 -253.847391)
			(xy 116.740388 -253.893665) (xy 116.756436 -253.943058) (xy 116.764561 -253.994353) (xy 116.76507 -254.02032)
			(xy 116.764561 -254.046265) (xy 116.871775 -254.046265) (xy 116.871775 -253.994335) (xy 116.879899 -253.943043)
			(xy 116.895946 -253.893654) (xy 116.919522 -253.847383) (xy 116.950046 -253.80537) (xy 116.986767 -253.768649)
			(xy 117.028779 -253.738124) (xy 117.07505 -253.714548) (xy 117.124439 -253.6985) (xy 117.175731 -253.690375)
			(xy 117.201696 -253.689866) (xy 117.228022 -253.690419) (xy 117.280007 -253.698773) (xy 117.330014 -253.715253)
			(xy 117.37678 -253.739444) (xy 117.419125 -253.770735) (xy 117.437916 -253.78918) (xy 117.447825 -253.798543)
			(xy 117.471385 -253.812233) (xy 117.497724 -253.819212) (xy 117.524971 -253.818984) (xy 117.55119 -253.811565)
			(xy 117.574517 -253.797483) (xy 117.58422 -253.78791) (xy 117.603052 -253.768766) (xy 117.645812 -253.736279)
			(xy 117.693261 -253.711136) (xy 117.744153 -253.693996) (xy 117.797146 -253.685311) (xy 117.823996 -253.684786)
			(xy 117.849857 -253.685291) (xy 117.900948 -253.693337) (xy 117.950162 -253.709247) (xy 117.996293 -253.732635)
			(xy 118.038216 -253.762926) (xy 118.056914 -253.780798) (xy 118.066629 -253.789843) (xy 118.089638 -253.803055)
			(xy 118.115275 -253.809892) (xy 118.141809 -253.809892) (xy 118.167446 -253.803055) (xy 118.190455 -253.789843)
			(xy 118.20017 -253.780798) (xy 118.218862 -253.762921) (xy 118.260792 -253.732639) (xy 118.306926 -253.709257)
			(xy 118.356138 -253.693343) (xy 118.407228 -253.685287) (xy 118.433088 -253.684786) (xy 118.457669 -253.685238)
			(xy 118.506289 -253.692514) (xy 118.553296 -253.706907) (xy 118.597655 -253.728101) (xy 118.638388 -253.755628)
			(xy 118.674596 -253.788881) (xy 118.69039 -253.807722) (xy 118.700211 -253.819077) (xy 118.725043 -253.835929)
			(xy 118.753694 -253.844857) (xy 118.783702 -253.845095) (xy 118.812491 -253.836621) (xy 118.837586 -253.820165)
			(xy 118.847616 -253.808992) (xy 118.863404 -253.790702) (xy 118.899371 -253.758443) (xy 118.939655 -253.73177)
			(xy 118.983396 -253.71125) (xy 119.02966 -253.697323) (xy 119.077459 -253.690285) (xy 119.101616 -253.689866)
			(xy 119.128915 -253.690387) (xy 119.182769 -253.699372) (xy 119.234412 -253.717095) (xy 119.282435 -253.743071)
			(xy 119.32553 -253.776595) (xy 119.34444 -253.796292) (xy 119.354273 -253.806272) (xy 119.378157 -253.820898)
			(xy 119.405113 -253.828497) (xy 119.433119 -253.828497) (xy 119.460075 -253.820898) (xy 119.483959 -253.806272)
			(xy 119.493792 -253.796292) (xy 119.512697 -253.776592) (xy 119.555798 -253.743082) (xy 119.603824 -253.717116)
			(xy 119.655466 -253.699404) (xy 119.709318 -253.690427) (xy 119.736616 -253.689866) (xy 119.762584 -253.690337)
			(xy 119.81388 -253.698463) (xy 119.863274 -253.714514) (xy 119.909548 -253.738094) (xy 119.951564 -253.768623)
			(xy 119.988288 -253.805348) (xy 120.018814 -253.847366) (xy 120.042392 -253.893641) (xy 120.05844 -253.943035)
			(xy 120.058863 -253.945703) (xy 121.758203 -253.945703) (xy 121.758203 -253.893769) (xy 121.766328 -253.842474)
			(xy 121.782376 -253.793081) (xy 121.805954 -253.746807) (xy 121.83648 -253.704791) (xy 121.873203 -253.668068)
			(xy 121.915219 -253.637542) (xy 121.961493 -253.613964) (xy 122.010886 -253.597916) (xy 122.062181 -253.589791)
			(xy 122.114115 -253.589791) (xy 122.16541 -253.597916) (xy 122.214803 -253.613964) (xy 122.261077 -253.637542)
			(xy 122.303093 -253.668068) (xy 122.339816 -253.704791) (xy 122.370342 -253.746807) (xy 122.39392 -253.793081)
			(xy 122.409968 -253.842474) (xy 122.418093 -253.893769) (xy 122.418602 -253.919736) (xy 122.418093 -253.945703)
			(xy 122.697749 -253.945703) (xy 122.697749 -253.893769) (xy 122.705874 -253.842474) (xy 122.721922 -253.793081)
			(xy 122.7455 -253.746807) (xy 122.776026 -253.704791) (xy 122.812749 -253.668068) (xy 122.854765 -253.637542)
			(xy 122.901039 -253.613964) (xy 122.950432 -253.597916) (xy 123.001727 -253.589791) (xy 123.053661 -253.589791)
			(xy 123.104956 -253.597916) (xy 123.154349 -253.613964) (xy 123.200623 -253.637542) (xy 123.242639 -253.668068)
			(xy 123.279362 -253.704791) (xy 123.309888 -253.746807) (xy 123.333466 -253.793081) (xy 123.349514 -253.842474)
			(xy 123.357639 -253.893769) (xy 123.358148 -253.919736) (xy 123.357639 -253.945703) (xy 123.637803 -253.945703)
			(xy 123.637803 -253.893769) (xy 123.645928 -253.842474) (xy 123.661976 -253.793081) (xy 123.685554 -253.746807)
			(xy 123.71608 -253.704791) (xy 123.752803 -253.668068) (xy 123.794819 -253.637542) (xy 123.841093 -253.613964)
			(xy 123.890486 -253.597916) (xy 123.941781 -253.589791) (xy 123.993715 -253.589791) (xy 124.04501 -253.597916)
			(xy 124.094403 -253.613964) (xy 124.140677 -253.637542) (xy 124.182693 -253.668068) (xy 124.219416 -253.704791)
			(xy 124.249942 -253.746807) (xy 124.27352 -253.793081) (xy 124.289568 -253.842474) (xy 124.297693 -253.893769)
			(xy 124.298202 -253.919736) (xy 124.297693 -253.945703) (xy 124.577603 -253.945703) (xy 124.577603 -253.893769)
			(xy 124.585728 -253.842474) (xy 124.601776 -253.793081) (xy 124.625354 -253.746807) (xy 124.65588 -253.704791)
			(xy 124.692603 -253.668068) (xy 124.734619 -253.637542) (xy 124.780893 -253.613964) (xy 124.830286 -253.597916)
			(xy 124.881581 -253.589791) (xy 124.933515 -253.589791) (xy 124.98481 -253.597916) (xy 125.034203 -253.613964)
			(xy 125.080477 -253.637542) (xy 125.122493 -253.668068) (xy 125.159216 -253.704791) (xy 125.189742 -253.746807)
			(xy 125.21332 -253.793081) (xy 125.229368 -253.842474) (xy 125.237493 -253.893769) (xy 125.238002 -253.919736)
			(xy 125.237493 -253.945703) (xy 125.517403 -253.945703) (xy 125.517403 -253.893769) (xy 125.525528 -253.842474)
			(xy 125.541576 -253.793081) (xy 125.565154 -253.746807) (xy 125.59568 -253.704791) (xy 125.632403 -253.668068)
			(xy 125.674419 -253.637542) (xy 125.720693 -253.613964) (xy 125.770086 -253.597916) (xy 125.821381 -253.589791)
			(xy 125.873315 -253.589791) (xy 125.92461 -253.597916) (xy 125.974003 -253.613964) (xy 126.020277 -253.637542)
			(xy 126.062293 -253.668068) (xy 126.099016 -253.704791) (xy 126.129542 -253.746807) (xy 126.15312 -253.793081)
			(xy 126.169168 -253.842474) (xy 126.177293 -253.893769) (xy 126.177802 -253.919736) (xy 126.177293 -253.945703)
			(xy 126.457203 -253.945703) (xy 126.457203 -253.893769) (xy 126.465328 -253.842474) (xy 126.481376 -253.793081)
			(xy 126.504954 -253.746807) (xy 126.53548 -253.704791) (xy 126.572203 -253.668068) (xy 126.614219 -253.637542)
			(xy 126.660493 -253.613964) (xy 126.709886 -253.597916) (xy 126.761181 -253.589791) (xy 126.813115 -253.589791)
			(xy 126.86441 -253.597916) (xy 126.913803 -253.613964) (xy 126.960077 -253.637542) (xy 127.002093 -253.668068)
			(xy 127.038816 -253.704791) (xy 127.069342 -253.746807) (xy 127.09292 -253.793081) (xy 127.108968 -253.842474)
			(xy 127.117093 -253.893769) (xy 127.117602 -253.919736) (xy 127.117093 -253.945703) (xy 127.108968 -253.996998)
			(xy 127.09292 -254.046391) (xy 127.069342 -254.092665) (xy 127.038816 -254.134681) (xy 127.002093 -254.171404)
			(xy 126.960077 -254.20193) (xy 126.913803 -254.225508) (xy 126.86441 -254.241556) (xy 126.813115 -254.249681)
			(xy 126.761181 -254.249681) (xy 126.709886 -254.241556) (xy 126.660493 -254.225508) (xy 126.614219 -254.20193)
			(xy 126.572203 -254.171404) (xy 126.53548 -254.134681) (xy 126.504954 -254.092665) (xy 126.481376 -254.046391)
			(xy 126.465328 -253.996998) (xy 126.457203 -253.945703) (xy 126.177293 -253.945703) (xy 126.169168 -253.996998)
			(xy 126.15312 -254.046391) (xy 126.129542 -254.092665) (xy 126.099016 -254.134681) (xy 126.062293 -254.171404)
			(xy 126.020277 -254.20193) (xy 125.974003 -254.225508) (xy 125.92461 -254.241556) (xy 125.873315 -254.249681)
			(xy 125.821381 -254.249681) (xy 125.770086 -254.241556) (xy 125.720693 -254.225508) (xy 125.674419 -254.20193)
			(xy 125.632403 -254.171404) (xy 125.59568 -254.134681) (xy 125.565154 -254.092665) (xy 125.541576 -254.046391)
			(xy 125.525528 -253.996998) (xy 125.517403 -253.945703) (xy 125.237493 -253.945703) (xy 125.229368 -253.996998)
			(xy 125.21332 -254.046391) (xy 125.189742 -254.092665) (xy 125.159216 -254.134681) (xy 125.122493 -254.171404)
			(xy 125.080477 -254.20193) (xy 125.034203 -254.225508) (xy 124.98481 -254.241556) (xy 124.933515 -254.249681)
			(xy 124.881581 -254.249681) (xy 124.830286 -254.241556) (xy 124.780893 -254.225508) (xy 124.734619 -254.20193)
			(xy 124.692603 -254.171404) (xy 124.65588 -254.134681) (xy 124.625354 -254.092665) (xy 124.601776 -254.046391)
			(xy 124.585728 -253.996998) (xy 124.577603 -253.945703) (xy 124.297693 -253.945703) (xy 124.289568 -253.996998)
			(xy 124.27352 -254.046391) (xy 124.249942 -254.092665) (xy 124.219416 -254.134681) (xy 124.182693 -254.171404)
			(xy 124.140677 -254.20193) (xy 124.094403 -254.225508) (xy 124.04501 -254.241556) (xy 123.993715 -254.249681)
			(xy 123.941781 -254.249681) (xy 123.890486 -254.241556) (xy 123.841093 -254.225508) (xy 123.794819 -254.20193)
			(xy 123.752803 -254.171404) (xy 123.71608 -254.134681) (xy 123.685554 -254.092665) (xy 123.661976 -254.046391)
			(xy 123.645928 -253.996998) (xy 123.637803 -253.945703) (xy 123.357639 -253.945703) (xy 123.349514 -253.996998)
			(xy 123.333466 -254.046391) (xy 123.309888 -254.092665) (xy 123.279362 -254.134681) (xy 123.242639 -254.171404)
			(xy 123.200623 -254.20193) (xy 123.154349 -254.225508) (xy 123.104956 -254.241556) (xy 123.053661 -254.249681)
			(xy 123.001727 -254.249681) (xy 122.950432 -254.241556) (xy 122.901039 -254.225508) (xy 122.854765 -254.20193)
			(xy 122.812749 -254.171404) (xy 122.776026 -254.134681) (xy 122.7455 -254.092665) (xy 122.721922 -254.046391)
			(xy 122.705874 -253.996998) (xy 122.697749 -253.945703) (xy 122.418093 -253.945703) (xy 122.409968 -253.996998)
			(xy 122.39392 -254.046391) (xy 122.370342 -254.092665) (xy 122.339816 -254.134681) (xy 122.303093 -254.171404)
			(xy 122.261077 -254.20193) (xy 122.214803 -254.225508) (xy 122.16541 -254.241556) (xy 122.114115 -254.249681)
			(xy 122.062181 -254.249681) (xy 122.010886 -254.241556) (xy 121.961493 -254.225508) (xy 121.915219 -254.20193)
			(xy 121.873203 -254.171404) (xy 121.83648 -254.134681) (xy 121.805954 -254.092665) (xy 121.782376 -254.046391)
			(xy 121.766328 -253.996998) (xy 121.758203 -253.945703) (xy 120.058863 -253.945703) (xy 120.066565 -253.994332)
			(xy 120.066565 -254.046268) (xy 120.05844 -254.097565) (xy 120.042392 -254.146959) (xy 120.018814 -254.193234)
			(xy 119.988288 -254.235252) (xy 119.951564 -254.271977) (xy 119.909548 -254.302506) (xy 119.863274 -254.326086)
			(xy 119.81388 -254.342137) (xy 119.762584 -254.350263) (xy 119.736616 -254.350774) (xy 119.709318 -254.350219)
			(xy 119.655466 -254.34124) (xy 119.603825 -254.323525) (xy 119.555801 -254.297556) (xy 119.512704 -254.264041)
			(xy 119.493792 -254.244348) (xy 119.483959 -254.234368) (xy 119.460075 -254.219742) (xy 119.433119 -254.212143)
			(xy 119.405113 -254.212143) (xy 119.378157 -254.219742) (xy 119.354273 -254.234368) (xy 119.34444 -254.244348)
			(xy 119.325528 -254.26404) (xy 119.282428 -254.29755) (xy 119.234404 -254.323515) (xy 119.182763 -254.34123)
			(xy 119.128913 -254.350211) (xy 119.101616 -254.350774) (xy 119.077035 -254.350334) (xy 119.028413 -254.343058)
			(xy 118.981405 -254.328663) (xy 118.937046 -254.307467) (xy 118.896314 -254.279937) (xy 118.860106 -254.246681)
			(xy 118.844314 -254.227838) (xy 118.834491 -254.216482) (xy 118.809663 -254.199621) (xy 118.78101 -254.190686)
			(xy 118.750999 -254.190448) (xy 118.722208 -254.198926) (xy 118.697115 -254.215391) (xy 118.687088 -254.226568)
			(xy 118.671312 -254.244868) (xy 118.63534 -254.277123) (xy 118.595053 -254.303794) (xy 118.551311 -254.324312)
			(xy 118.505046 -254.338237) (xy 118.457246 -254.345274) (xy 118.433088 -254.345694) (xy 118.407227 -254.345205)
			(xy 118.356134 -254.337156) (xy 118.30692 -254.321242) (xy 118.260789 -254.297851) (xy 118.218867 -254.267556)
			(xy 118.20017 -254.249682) (xy 118.190455 -254.240637) (xy 118.167446 -254.227425) (xy 118.141809 -254.220588)
			(xy 118.115275 -254.220588) (xy 118.089638 -254.227425) (xy 118.066629 -254.240637) (xy 118.056914 -254.249682)
			(xy 118.038226 -254.267564) (xy 117.996295 -254.297845) (xy 117.950161 -254.321227) (xy 117.900948 -254.33714)
			(xy 117.849857 -254.345194) (xy 117.823996 -254.345694) (xy 117.797669 -254.345157) (xy 117.745683 -254.336802)
			(xy 117.695675 -254.320319) (xy 117.64891 -254.296124) (xy 117.606566 -254.264827) (xy 117.587776 -254.24638)
			(xy 117.577877 -254.237004) (xy 117.554316 -254.223306) (xy 117.527973 -254.216324) (xy 117.500721 -254.216553)
			(xy 117.474499 -254.223978) (xy 117.451173 -254.238071) (xy 117.441472 -254.24765) (xy 117.422636 -254.266791)
			(xy 117.379879 -254.299279) (xy 117.33243 -254.324425) (xy 117.281539 -254.341565) (xy 117.228546 -254.350249)
			(xy 117.201696 -254.350774) (xy 117.175731 -254.350225) (xy 117.124439 -254.3421) (xy 117.07505 -254.326052)
			(xy 117.028779 -254.302476) (xy 116.986767 -254.271951) (xy 116.950046 -254.23523) (xy 116.919522 -254.193217)
			(xy 116.895946 -254.146946) (xy 116.879899 -254.097557) (xy 116.871775 -254.046265) (xy 116.764561 -254.046265)
			(xy 116.764561 -254.046287) (xy 116.756436 -254.097582) (xy 116.740388 -254.146975) (xy 116.71681 -254.193249)
			(xy 116.686284 -254.235265) (xy 116.649561 -254.271988) (xy 116.607545 -254.302514) (xy 116.561271 -254.326092)
			(xy 116.511878 -254.34214) (xy 116.460583 -254.350265) (xy 116.408649 -254.350265) (xy 116.357354 -254.34214)
			(xy 116.307961 -254.326092) (xy 116.261687 -254.302514) (xy 116.219671 -254.271988) (xy 116.182948 -254.235265)
			(xy 116.152422 -254.193249) (xy 116.128844 -254.146975) (xy 116.112796 -254.097582) (xy 116.104671 -254.046287)
			(xy 115.467475 -254.046287) (xy 115.472756 -254.057347) (xy 115.48711 -254.104253) (xy 115.494368 -254.152766)
			(xy 115.494816 -254.177292) (xy 115.494816 -254.177546) (xy 115.494387 -254.203516) (xy 115.486255 -254.254817)
			(xy 115.470197 -254.304213) (xy 115.446611 -254.35049) (xy 115.416075 -254.392507) (xy 115.379343 -254.42923)
			(xy 115.337318 -254.459755) (xy 115.291035 -254.48333) (xy 115.241635 -254.499374) (xy 115.190332 -254.507494)
			(xy 115.164362 -254.508) (xy 115.138403 -254.50743) (xy 115.087127 -254.499292) (xy 115.037754 -254.483237)
			(xy 114.991498 -254.459661) (xy 114.949496 -254.429143) (xy 114.912783 -254.392434) (xy 114.882259 -254.350436)
			(xy 114.858678 -254.304182) (xy 114.850164 -254.279654) (xy 114.845211 -254.266126) (xy 114.829044 -254.242303)
			(xy 114.806862 -254.223949) (xy 114.780433 -254.212527) (xy 114.751865 -254.208948) (xy 114.723436 -254.213497)
			(xy 114.71021 -254.219202) (xy 114.688196 -254.229027) (xy 114.642043 -254.242938) (xy 114.594358 -254.249987)
			(xy 114.570256 -254.250444) (xy 114.569748 -254.250444) (xy 114.543775 -254.249985) (xy 114.492469 -254.241865)
			(xy 114.443065 -254.225819) (xy 114.396779 -254.202242) (xy 114.354752 -254.171713) (xy 114.318019 -254.134985)
			(xy 114.287484 -254.092962) (xy 114.263899 -254.04668) (xy 114.247846 -253.997278) (xy 114.239719 -253.945972)
			(xy 113.959891 -253.945972) (xy 113.951768 -253.997252) (xy 113.93572 -254.046645) (xy 113.912142 -254.092919)
			(xy 113.881616 -254.134935) (xy 113.844893 -254.171658) (xy 113.802877 -254.202184) (xy 113.756603 -254.225762)
			(xy 113.70721 -254.24181) (xy 113.655915 -254.249935) (xy 113.603981 -254.249935) (xy 113.552686 -254.24181)
			(xy 113.503293 -254.225762) (xy 113.457019 -254.202184) (xy 113.415003 -254.171658) (xy 113.37828 -254.134935)
			(xy 113.347754 -254.092919) (xy 113.324176 -254.046645) (xy 113.308128 -253.997252) (xy 113.300003 -253.945957)
			(xy 113.020093 -253.945957) (xy 113.011968 -253.997252) (xy 112.99592 -254.046645) (xy 112.972342 -254.092919)
			(xy 112.941816 -254.134935) (xy 112.905093 -254.171658) (xy 112.863077 -254.202184) (xy 112.816803 -254.225762)
			(xy 112.76741 -254.24181) (xy 112.716115 -254.249935) (xy 112.664181 -254.249935) (xy 112.612886 -254.24181)
			(xy 112.563493 -254.225762) (xy 112.517219 -254.202184) (xy 112.475203 -254.171658) (xy 112.43848 -254.134935)
			(xy 112.407954 -254.092919) (xy 112.384376 -254.046645) (xy 112.368328 -253.997252) (xy 112.360203 -253.945957)
			(xy 112.080293 -253.945957) (xy 112.072168 -253.997252) (xy 112.05612 -254.046645) (xy 112.032542 -254.092919)
			(xy 112.002016 -254.134935) (xy 111.965293 -254.171658) (xy 111.923277 -254.202184) (xy 111.877003 -254.225762)
			(xy 111.82761 -254.24181) (xy 111.776315 -254.249935) (xy 111.724381 -254.249935) (xy 111.673086 -254.24181)
			(xy 111.623693 -254.225762) (xy 111.577419 -254.202184) (xy 111.535403 -254.171658) (xy 111.49868 -254.134935)
			(xy 111.468154 -254.092919) (xy 111.444576 -254.046645) (xy 111.428528 -253.997252) (xy 111.420403 -253.945957)
			(xy 111.140747 -253.945957) (xy 111.132622 -253.997252) (xy 111.116574 -254.046645) (xy 111.092996 -254.092919)
			(xy 111.06247 -254.134935) (xy 111.025747 -254.171658) (xy 110.983731 -254.202184) (xy 110.937457 -254.225762)
			(xy 110.888064 -254.24181) (xy 110.836769 -254.249935) (xy 110.784835 -254.249935) (xy 110.73354 -254.24181)
			(xy 110.684147 -254.225762) (xy 110.637873 -254.202184) (xy 110.595857 -254.171658) (xy 110.559134 -254.134935)
			(xy 110.528608 -254.092919) (xy 110.50503 -254.046645) (xy 110.488982 -253.997252) (xy 110.480857 -253.945957)
			(xy 110.200693 -253.945957) (xy 110.192568 -253.997252) (xy 110.17652 -254.046645) (xy 110.152942 -254.092919)
			(xy 110.122416 -254.134935) (xy 110.085693 -254.171658) (xy 110.043677 -254.202184) (xy 109.997403 -254.225762)
			(xy 109.94801 -254.24181) (xy 109.896715 -254.249935) (xy 109.844781 -254.249935) (xy 109.793486 -254.24181)
			(xy 109.744093 -254.225762) (xy 109.697819 -254.202184) (xy 109.655803 -254.171658) (xy 109.61908 -254.134935)
			(xy 109.588554 -254.092919) (xy 109.564976 -254.046645) (xy 109.548928 -253.997252) (xy 109.540803 -253.945957)
			(xy 109.010554 -253.945957) (xy 109.010704 -253.95428) (xy 109.010704 -253.954534) (xy 109.010195 -253.980501)
			(xy 109.00207 -254.031796) (xy 108.986022 -254.081189) (xy 108.962444 -254.127463) (xy 108.931918 -254.169479)
			(xy 108.895195 -254.206202) (xy 108.853179 -254.236728) (xy 108.806905 -254.260306) (xy 108.757512 -254.276354)
			(xy 108.706217 -254.284479) (xy 108.654283 -254.284479) (xy 108.602988 -254.276354) (xy 108.553595 -254.260306)
			(xy 108.507321 -254.236728) (xy 108.465305 -254.206202) (xy 108.428582 -254.169479) (xy 108.398056 -254.127463)
			(xy 108.374478 -254.081189) (xy 108.35843 -254.031796) (xy 108.350305 -253.980501) (xy 108.349796 -253.954534)
			(xy 108.349796 -253.95428) (xy 108.350237 -253.929753) (xy 108.357502 -253.88124) (xy 108.371857 -253.834332)
			(xy 108.392984 -253.790061) (xy 108.420421 -253.749397) (xy 108.436664 -253.731014) (xy 108.446435 -253.719499)
			(xy 108.459454 -253.692272) (xy 108.46393 -253.662425) (xy 108.459469 -253.632577) (xy 108.446463 -253.605342)
			(xy 108.436664 -253.593854) (xy 108.420435 -253.575458) (xy 108.392985 -253.534804) (xy 108.371851 -253.490536)
			(xy 108.357498 -253.443629) (xy 108.350243 -253.395115) (xy 108.349796 -253.370588) (xy 108.349796 -253.370334)
			(xy 108.350242 -253.346421) (xy 108.357137 -253.299094) (xy 108.370789 -253.253257) (xy 108.39091 -253.20987)
			(xy 108.417082 -253.169839) (xy 108.4326 -253.15164) (xy 108.441194 -253.141306) (xy 108.45307 -253.117203)
			(xy 108.45825 -253.090837) (xy 108.456375 -253.064032) (xy 108.447575 -253.038644) (xy 108.432459 -253.016428)
			(xy 108.412073 -252.998924) (xy 108.387828 -252.987341) (xy 108.374688 -252.984508) (xy 108.349635 -252.979489)
			(xy 108.301375 -252.962707) (xy 108.256274 -252.938696) (xy 108.215405 -252.908031) (xy 108.179742 -252.871441)
			(xy 108.150136 -252.829799) (xy 108.127292 -252.784096) (xy 108.111753 -252.735421) (xy 108.103891 -252.684935)
			(xy 108.103416 -252.659388) (xy 103.194898 -252.659388) (xy 103.204075 -252.678619) (xy 103.21842 -252.725532)
			(xy 103.225666 -252.774051) (xy 103.226108 -252.79858) (xy 103.226108 -252.798834) (xy 103.225599 -252.824801)
			(xy 103.217474 -252.876096) (xy 103.201426 -252.925489) (xy 103.177848 -252.971763) (xy 103.147322 -253.013779)
			(xy 103.110599 -253.050502) (xy 103.068583 -253.081028) (xy 103.022309 -253.104606) (xy 102.972916 -253.120654)
			(xy 102.921621 -253.128779) (xy 102.869687 -253.128779) (xy 102.818392 -253.120654) (xy 102.768999 -253.104606)
			(xy 102.722725 -253.081028) (xy 102.680709 -253.050502) (xy 102.643986 -253.013779) (xy 102.61346 -252.971763)
			(xy 102.589882 -252.925489) (xy 102.573834 -252.876096) (xy 102.565709 -252.824801) (xy 102.5652 -252.798834)
			(xy 95.425951 -252.798834) (xy 95.429995 -252.800148) (xy 95.476269 -252.823726) (xy 95.518285 -252.854252)
			(xy 95.555008 -252.890975) (xy 95.585534 -252.932991) (xy 95.609112 -252.979265) (xy 95.62516 -253.028658)
			(xy 95.633285 -253.079953) (xy 95.633794 -253.10592) (xy 95.633285 -253.131887) (xy 95.62516 -253.183182)
			(xy 95.609112 -253.232575) (xy 95.585534 -253.278849) (xy 95.555008 -253.320865) (xy 95.518285 -253.357588)
			(xy 95.476269 -253.388114) (xy 95.429995 -253.411692) (xy 95.380602 -253.42774) (xy 95.329307 -253.435865)
			(xy 95.277373 -253.435865) (xy 95.226078 -253.42774) (xy 95.176685 -253.411692) (xy 95.130411 -253.388114)
			(xy 95.088395 -253.357588) (xy 95.051672 -253.320865) (xy 95.021146 -253.278849) (xy 94.997568 -253.232575)
			(xy 94.98152 -253.183182) (xy 94.973395 -253.131887) (xy 94.199143 -253.131887) (xy 93.937582 -253.393448)
			(xy 93.930875 -253.400688) (xy 93.923295 -253.418893) (xy 93.92285 -253.428754) (xy 93.92285 -253.547372)
			(xy 93.923436 -253.558217) (xy 93.932595 -253.577884) (xy 93.949126 -253.591935) (xy 93.959426 -253.595378)
			(xy 93.962982 -253.59614) (xy 93.987365 -253.601801) (xy 94.034193 -253.61948) (xy 94.077823 -253.644012)
			(xy 94.11726 -253.674837) (xy 94.151602 -253.711251) (xy 94.180067 -253.752424) (xy 94.202004 -253.797415)
			(xy 94.216912 -253.845197) (xy 94.224452 -253.89468) (xy 94.224451 -253.944735) (xy 94.224303 -253.945703)
			(xy 94.503749 -253.945703) (xy 94.503749 -253.893769) (xy 94.511874 -253.842474) (xy 94.527922 -253.793081)
			(xy 94.5515 -253.746807) (xy 94.582026 -253.704791) (xy 94.618749 -253.668068) (xy 94.660765 -253.637542)
			(xy 94.707039 -253.613964) (xy 94.756432 -253.597916) (xy 94.807727 -253.589791) (xy 94.859661 -253.589791)
			(xy 94.910956 -253.597916) (xy 94.960349 -253.613964) (xy 95.006623 -253.637542) (xy 95.048639 -253.668068)
			(xy 95.085362 -253.704791) (xy 95.115888 -253.746807) (xy 95.139466 -253.793081) (xy 95.155514 -253.842474)
			(xy 95.163639 -253.893769) (xy 95.164148 -253.919736) (xy 95.163639 -253.945703) (xy 95.443803 -253.945703)
			(xy 95.443803 -253.893769) (xy 95.451928 -253.842474) (xy 95.467976 -253.793081) (xy 95.491554 -253.746807)
			(xy 95.52208 -253.704791) (xy 95.558803 -253.668068) (xy 95.600819 -253.637542) (xy 95.647093 -253.613964)
			(xy 95.696486 -253.597916) (xy 95.747781 -253.589791) (xy 95.799715 -253.589791) (xy 95.85101 -253.597916)
			(xy 95.900403 -253.613964) (xy 95.946677 -253.637542) (xy 95.988693 -253.668068) (xy 96.025416 -253.704791)
			(xy 96.055942 -253.746807) (xy 96.07952 -253.793081) (xy 96.095568 -253.842474) (xy 96.103693 -253.893769)
			(xy 96.104202 -253.919736) (xy 96.103693 -253.945703) (xy 96.383603 -253.945703) (xy 96.383603 -253.893769)
			(xy 96.391728 -253.842474) (xy 96.407776 -253.793081) (xy 96.431354 -253.746807) (xy 96.46188 -253.704791)
			(xy 96.498603 -253.668068) (xy 96.540619 -253.637542) (xy 96.586893 -253.613964) (xy 96.636286 -253.597916)
			(xy 96.687581 -253.589791) (xy 96.739515 -253.589791) (xy 96.79081 -253.597916) (xy 96.840203 -253.613964)
			(xy 96.886477 -253.637542) (xy 96.928493 -253.668068) (xy 96.965216 -253.704791) (xy 96.995742 -253.746807)
			(xy 97.01932 -253.793081) (xy 97.035368 -253.842474) (xy 97.043493 -253.893769) (xy 97.044002 -253.919736)
			(xy 97.043493 -253.945703) (xy 97.323403 -253.945703) (xy 97.323403 -253.893769) (xy 97.331528 -253.842474)
			(xy 97.347576 -253.793081) (xy 97.371154 -253.746807) (xy 97.40168 -253.704791) (xy 97.438403 -253.668068)
			(xy 97.480419 -253.637542) (xy 97.526693 -253.613964) (xy 97.576086 -253.597916) (xy 97.627381 -253.589791)
			(xy 97.679315 -253.589791) (xy 97.73061 -253.597916) (xy 97.780003 -253.613964) (xy 97.826277 -253.637542)
			(xy 97.868293 -253.668068) (xy 97.905016 -253.704791) (xy 97.935542 -253.746807) (xy 97.95912 -253.793081)
			(xy 97.975168 -253.842474) (xy 97.983293 -253.893769) (xy 97.983802 -253.919736) (xy 97.983293 -253.945703)
			(xy 98.263203 -253.945703) (xy 98.263203 -253.893769) (xy 98.271328 -253.842474) (xy 98.287376 -253.793081)
			(xy 98.310954 -253.746807) (xy 98.34148 -253.704791) (xy 98.378203 -253.668068) (xy 98.420219 -253.637542)
			(xy 98.466493 -253.613964) (xy 98.515886 -253.597916) (xy 98.567181 -253.589791) (xy 98.619115 -253.589791)
			(xy 98.67041 -253.597916) (xy 98.719803 -253.613964) (xy 98.766077 -253.637542) (xy 98.808093 -253.668068)
			(xy 98.844816 -253.704791) (xy 98.875342 -253.746807) (xy 98.89892 -253.793081) (xy 98.914968 -253.842474)
			(xy 98.923093 -253.893769) (xy 98.923602 -253.919736) (xy 98.923093 -253.945703) (xy 99.203003 -253.945703)
			(xy 99.203003 -253.893769) (xy 99.211128 -253.842474) (xy 99.227176 -253.793081) (xy 99.250754 -253.746807)
			(xy 99.28128 -253.704791) (xy 99.318003 -253.668068) (xy 99.360019 -253.637542) (xy 99.406293 -253.613964)
			(xy 99.455686 -253.597916) (xy 99.506981 -253.589791) (xy 99.558915 -253.589791) (xy 99.61021 -253.597916)
			(xy 99.659603 -253.613964) (xy 99.705877 -253.637542) (xy 99.747893 -253.668068) (xy 99.784616 -253.704791)
			(xy 99.815142 -253.746807) (xy 99.83872 -253.793081) (xy 99.854768 -253.842474) (xy 99.862893 -253.893769)
			(xy 99.863402 -253.919736) (xy 99.862893 -253.945703) (xy 100.142803 -253.945703) (xy 100.142803 -253.893769)
			(xy 100.150928 -253.842474) (xy 100.166976 -253.793081) (xy 100.190554 -253.746807) (xy 100.22108 -253.704791)
			(xy 100.257803 -253.668068) (xy 100.299819 -253.637542) (xy 100.346093 -253.613964) (xy 100.395486 -253.597916)
			(xy 100.446781 -253.589791) (xy 100.498715 -253.589791) (xy 100.55001 -253.597916) (xy 100.599403 -253.613964)
			(xy 100.645677 -253.637542) (xy 100.687693 -253.668068) (xy 100.724416 -253.704791) (xy 100.754942 -253.746807)
			(xy 100.77852 -253.793081) (xy 100.794568 -253.842474) (xy 100.802693 -253.893769) (xy 100.803202 -253.919736)
			(xy 100.802693 -253.945703) (xy 101.082603 -253.945703) (xy 101.082603 -253.893769) (xy 101.090728 -253.842474)
			(xy 101.106776 -253.793081) (xy 101.130354 -253.746807) (xy 101.16088 -253.704791) (xy 101.197603 -253.668068)
			(xy 101.239619 -253.637542) (xy 101.285893 -253.613964) (xy 101.335286 -253.597916) (xy 101.386581 -253.589791)
			(xy 101.438515 -253.589791) (xy 101.48981 -253.597916) (xy 101.539203 -253.613964) (xy 101.585477 -253.637542)
			(xy 101.627493 -253.668068) (xy 101.664216 -253.704791) (xy 101.694742 -253.746807) (xy 101.71832 -253.793081)
			(xy 101.734368 -253.842474) (xy 101.742493 -253.893769) (xy 101.743002 -253.919736) (xy 101.742493 -253.945703)
			(xy 102.022403 -253.945703) (xy 102.022403 -253.893769) (xy 102.030528 -253.842474) (xy 102.046576 -253.793081)
			(xy 102.070154 -253.746807) (xy 102.10068 -253.704791) (xy 102.137403 -253.668068) (xy 102.179419 -253.637542)
			(xy 102.225693 -253.613964) (xy 102.275086 -253.597916) (xy 102.326381 -253.589791) (xy 102.378315 -253.589791)
			(xy 102.42961 -253.597916) (xy 102.479003 -253.613964) (xy 102.525277 -253.637542) (xy 102.567293 -253.668068)
			(xy 102.604016 -253.704791) (xy 102.634542 -253.746807) (xy 102.65812 -253.793081) (xy 102.674168 -253.842474)
			(xy 102.682293 -253.893769) (xy 102.682802 -253.919736) (xy 102.682293 -253.945703) (xy 102.674168 -253.996998)
			(xy 102.658161 -254.046265) (xy 103.831675 -254.046265) (xy 103.831675 -253.994335) (xy 103.839799 -253.943044)
			(xy 103.855846 -253.893655) (xy 103.879421 -253.847385) (xy 103.909945 -253.805372) (xy 103.946664 -253.768651)
			(xy 103.988676 -253.738126) (xy 104.034946 -253.71455) (xy 104.084334 -253.698501) (xy 104.135625 -253.690376)
			(xy 104.16159 -253.689866) (xy 104.161844 -253.689866) (xy 104.186371 -253.6903) (xy 104.234884 -253.697569)
			(xy 104.281791 -253.711925) (xy 104.326063 -253.733053) (xy 104.366727 -253.760491) (xy 104.38511 -253.776734)
			(xy 104.396599 -253.786537) (xy 104.423836 -253.799551) (xy 104.45369 -253.804019) (xy 104.483544 -253.799551)
			(xy 104.510781 -253.786537) (xy 104.52227 -253.776734) (xy 104.540652 -253.760489) (xy 104.581311 -253.733042)
			(xy 104.625582 -253.711912) (xy 104.672492 -253.697563) (xy 104.721008 -253.690311) (xy 104.745536 -253.689866)
			(xy 104.74579 -253.689866) (xy 104.772248 -253.690392) (xy 104.82449 -253.69881) (xy 104.874722 -253.71545)
			(xy 104.921658 -253.739885) (xy 104.964099 -253.77149) (xy 105.000959 -253.809457) (xy 105.016554 -253.830836)
			(xy 105.025014 -253.842059) (xy 105.046809 -253.859787) (xy 105.072611 -253.8709) (xy 105.100465 -253.874558)
			(xy 105.128261 -253.870483) (xy 105.153894 -253.858984) (xy 105.17542 -253.840932) (xy 105.183686 -253.829566)
			(xy 105.199181 -253.807644) (xy 105.236114 -253.768689) (xy 105.278862 -253.736221) (xy 105.326298 -253.711094)
			(xy 105.377174 -253.693972) (xy 105.43015 -253.685303) (xy 105.45699 -253.684786) (xy 105.482743 -253.685281)
			(xy 105.533628 -253.693259) (xy 105.582658 -253.709039) (xy 105.628644 -253.732239) (xy 105.670472 -253.762295)
			(xy 105.689146 -253.780036) (xy 105.698836 -253.789029) (xy 105.721768 -253.802161) (xy 105.747307 -253.808956)
			(xy 105.773733 -253.808956) (xy 105.799272 -253.802161) (xy 105.822204 -253.789029) (xy 105.831894 -253.780036)
			(xy 105.850582 -253.762311) (xy 105.892412 -253.732263) (xy 105.938395 -253.709064) (xy 105.987419 -253.693276)
			(xy 106.038298 -253.685282) (xy 106.06405 -253.684786) (xy 106.088313 -253.68519) (xy 106.136314 -253.692299)
			(xy 106.182759 -253.706355) (xy 106.226647 -253.727057) (xy 106.267033 -253.753958) (xy 106.303048 -253.78648)
			(xy 106.318812 -253.804928) (xy 106.328861 -253.816188) (xy 106.353999 -253.832854) (xy 106.382911 -253.841444)
			(xy 106.41307 -253.841207) (xy 106.441844 -253.832166) (xy 106.466717 -253.815108) (xy 106.476546 -253.803658)
			(xy 106.492358 -253.784696) (xy 106.528598 -253.751171) (xy 106.569422 -253.723409) (xy 106.613921 -253.702029)
			(xy 106.661106 -253.687506) (xy 106.709926 -253.680164) (xy 106.73461 -253.679706) (xy 106.761747 -253.680274)
			(xy 106.815289 -253.689149) (xy 106.866666 -253.706643) (xy 106.914499 -253.732287) (xy 106.957505 -253.765394)
			(xy 106.976418 -253.784862) (xy 106.986147 -253.794632) (xy 107.009656 -253.809021) (xy 107.036153 -253.816609)
			(xy 107.063714 -253.816844) (xy 107.090337 -253.809711) (xy 107.114089 -253.795726) (xy 107.123992 -253.786132)
			(xy 107.142832 -253.767355) (xy 107.185354 -253.735407) (xy 107.23245 -253.710694) (xy 107.282899 -253.693853)
			(xy 107.335397 -253.685321) (xy 107.36199 -253.684786) (xy 107.387963 -253.685188) (xy 107.439269 -253.693313)
			(xy 107.488673 -253.709364) (xy 107.534958 -253.732946) (xy 107.576984 -253.763478) (xy 107.613715 -253.800209)
			(xy 107.644249 -253.842234) (xy 107.667832 -253.888517) (xy 107.683885 -253.937921) (xy 107.692011 -253.989227)
			(xy 107.692011 -254.041173) (xy 107.683885 -254.092479) (xy 107.667832 -254.141883) (xy 107.644249 -254.188166)
			(xy 107.613715 -254.230191) (xy 107.576984 -254.266922) (xy 107.534958 -254.297454) (xy 107.488673 -254.321036)
			(xy 107.439269 -254.337087) (xy 107.387963 -254.345212) (xy 107.36199 -254.345694) (xy 107.334853 -254.345126)
			(xy 107.281311 -254.336251) (xy 107.229934 -254.318757) (xy 107.182101 -254.293113) (xy 107.139095 -254.260006)
			(xy 107.120182 -254.240538) (xy 107.110453 -254.230768) (xy 107.086944 -254.216379) (xy 107.060447 -254.208791)
			(xy 107.032886 -254.208556) (xy 107.006263 -254.215689) (xy 106.982511 -254.229674) (xy 106.972608 -254.239268)
			(xy 106.953768 -254.258045) (xy 106.911246 -254.289993) (xy 106.86415 -254.314706) (xy 106.813701 -254.331547)
			(xy 106.761203 -254.340079) (xy 106.73461 -254.340614) (xy 106.710349 -254.340168) (xy 106.662349 -254.333068)
			(xy 106.615905 -254.31902) (xy 106.572017 -254.298326) (xy 106.53163 -254.271432) (xy 106.495613 -254.238917)
			(xy 106.479848 -254.220472) (xy 106.469841 -254.209171) (xy 106.444691 -254.192507) (xy 106.415769 -254.183921)
			(xy 106.3856 -254.184165) (xy 106.35682 -254.193217) (xy 106.331943 -254.210286) (xy 106.322114 -254.221742)
			(xy 106.306324 -254.240723) (xy 106.270079 -254.274247) (xy 106.229251 -254.302007) (xy 106.184747 -254.323383)
			(xy 106.137559 -254.337902) (xy 106.088736 -254.345239) (xy 106.06405 -254.345694) (xy 106.038295 -254.345242)
			(xy 105.987408 -254.337254) (xy 105.938377 -254.321464) (xy 105.892392 -254.298255) (xy 105.850567 -254.26819)
			(xy 105.831894 -254.250444) (xy 105.822204 -254.241451) (xy 105.799272 -254.228319) (xy 105.773733 -254.221524)
			(xy 105.747307 -254.221524) (xy 105.721768 -254.228319) (xy 105.698836 -254.241451) (xy 105.689146 -254.250444)
			(xy 105.670481 -254.268194) (xy 105.628645 -254.29824) (xy 105.582657 -254.321435) (xy 105.533627 -254.337216)
			(xy 105.482743 -254.345203) (xy 105.45699 -254.345694) (xy 105.430533 -254.345158) (xy 105.378292 -254.336738)
			(xy 105.328062 -254.320098) (xy 105.281126 -254.295666) (xy 105.238685 -254.264064) (xy 105.201823 -254.226101)
			(xy 105.186226 -254.204724) (xy 105.177794 -254.193475) (xy 105.155997 -254.175737) (xy 105.130187 -254.164617)
			(xy 105.102323 -254.160959) (xy 105.074519 -254.165041) (xy 105.048881 -254.176552) (xy 105.027356 -254.19462)
			(xy 105.019094 -254.205994) (xy 105.003567 -254.227891) (xy 104.966638 -254.266844) (xy 104.923896 -254.299313)
			(xy 104.876467 -254.324443) (xy 104.825597 -254.341572) (xy 104.772628 -254.35025) (xy 104.74579 -254.350774)
			(xy 104.745536 -254.350774) (xy 104.721011 -254.350281) (xy 104.672501 -254.343026) (xy 104.625595 -254.328682)
			(xy 104.581323 -254.307567) (xy 104.540656 -254.280143) (xy 104.52227 -254.263906) (xy 104.510781 -254.254103)
			(xy 104.483544 -254.241089) (xy 104.45369 -254.236621) (xy 104.423836 -254.241089) (xy 104.396599 -254.254103)
			(xy 104.38511 -254.263906) (xy 104.366741 -254.280167) (xy 104.326079 -254.30761) (xy 104.281804 -254.328737)
			(xy 104.234891 -254.343082) (xy 104.186373 -254.35033) (xy 104.161844 -254.350774) (xy 104.16159 -254.350774)
			(xy 104.135625 -254.350224) (xy 104.084334 -254.342099) (xy 104.034946 -254.32605) (xy 103.988676 -254.302474)
			(xy 103.946664 -254.271949) (xy 103.909945 -254.235228) (xy 103.879421 -254.193215) (xy 103.855846 -254.146945)
			(xy 103.839799 -254.097556) (xy 103.831675 -254.046265) (xy 102.658161 -254.046265) (xy 102.65812 -254.046391)
			(xy 102.634542 -254.092665) (xy 102.604016 -254.134681) (xy 102.567293 -254.171404) (xy 102.525277 -254.20193)
			(xy 102.479003 -254.225508) (xy 102.42961 -254.241556) (xy 102.378315 -254.249681) (xy 102.326381 -254.249681)
			(xy 102.275086 -254.241556) (xy 102.225693 -254.225508) (xy 102.179419 -254.20193) (xy 102.137403 -254.171404)
			(xy 102.10068 -254.134681) (xy 102.070154 -254.092665) (xy 102.046576 -254.046391) (xy 102.030528 -253.996998)
			(xy 102.022403 -253.945703) (xy 101.742493 -253.945703) (xy 101.734368 -253.996998) (xy 101.71832 -254.046391)
			(xy 101.694742 -254.092665) (xy 101.664216 -254.134681) (xy 101.627493 -254.171404) (xy 101.585477 -254.20193)
			(xy 101.539203 -254.225508) (xy 101.48981 -254.241556) (xy 101.438515 -254.249681) (xy 101.386581 -254.249681)
			(xy 101.335286 -254.241556) (xy 101.285893 -254.225508) (xy 101.239619 -254.20193) (xy 101.197603 -254.171404)
			(xy 101.16088 -254.134681) (xy 101.130354 -254.092665) (xy 101.106776 -254.046391) (xy 101.090728 -253.996998)
			(xy 101.082603 -253.945703) (xy 100.802693 -253.945703) (xy 100.794568 -253.996998) (xy 100.77852 -254.046391)
			(xy 100.754942 -254.092665) (xy 100.724416 -254.134681) (xy 100.687693 -254.171404) (xy 100.645677 -254.20193)
			(xy 100.599403 -254.225508) (xy 100.55001 -254.241556) (xy 100.498715 -254.249681) (xy 100.446781 -254.249681)
			(xy 100.395486 -254.241556) (xy 100.346093 -254.225508) (xy 100.299819 -254.20193) (xy 100.257803 -254.171404)
			(xy 100.22108 -254.134681) (xy 100.190554 -254.092665) (xy 100.166976 -254.046391) (xy 100.150928 -253.996998)
			(xy 100.142803 -253.945703) (xy 99.862893 -253.945703) (xy 99.854768 -253.996998) (xy 99.83872 -254.046391)
			(xy 99.815142 -254.092665) (xy 99.784616 -254.134681) (xy 99.747893 -254.171404) (xy 99.705877 -254.20193)
			(xy 99.659603 -254.225508) (xy 99.61021 -254.241556) (xy 99.558915 -254.249681) (xy 99.506981 -254.249681)
			(xy 99.455686 -254.241556) (xy 99.406293 -254.225508) (xy 99.360019 -254.20193) (xy 99.318003 -254.171404)
			(xy 99.28128 -254.134681) (xy 99.250754 -254.092665) (xy 99.227176 -254.046391) (xy 99.211128 -253.996998)
			(xy 99.203003 -253.945703) (xy 98.923093 -253.945703) (xy 98.914968 -253.996998) (xy 98.89892 -254.046391)
			(xy 98.875342 -254.092665) (xy 98.844816 -254.134681) (xy 98.808093 -254.171404) (xy 98.766077 -254.20193)
			(xy 98.719803 -254.225508) (xy 98.67041 -254.241556) (xy 98.619115 -254.249681) (xy 98.567181 -254.249681)
			(xy 98.515886 -254.241556) (xy 98.466493 -254.225508) (xy 98.420219 -254.20193) (xy 98.378203 -254.171404)
			(xy 98.34148 -254.134681) (xy 98.310954 -254.092665) (xy 98.287376 -254.046391) (xy 98.271328 -253.996998)
			(xy 98.263203 -253.945703) (xy 97.983293 -253.945703) (xy 97.975168 -253.996998) (xy 97.95912 -254.046391)
			(xy 97.935542 -254.092665) (xy 97.905016 -254.134681) (xy 97.868293 -254.171404) (xy 97.826277 -254.20193)
			(xy 97.780003 -254.225508) (xy 97.73061 -254.241556) (xy 97.679315 -254.249681) (xy 97.627381 -254.249681)
			(xy 97.576086 -254.241556) (xy 97.526693 -254.225508) (xy 97.480419 -254.20193) (xy 97.438403 -254.171404)
			(xy 97.40168 -254.134681) (xy 97.371154 -254.092665) (xy 97.347576 -254.046391) (xy 97.331528 -253.996998)
			(xy 97.323403 -253.945703) (xy 97.043493 -253.945703) (xy 97.035368 -253.996998) (xy 97.01932 -254.046391)
			(xy 96.995742 -254.092665) (xy 96.965216 -254.134681) (xy 96.928493 -254.171404) (xy 96.886477 -254.20193)
			(xy 96.840203 -254.225508) (xy 96.79081 -254.241556) (xy 96.739515 -254.249681) (xy 96.687581 -254.249681)
			(xy 96.636286 -254.241556) (xy 96.586893 -254.225508) (xy 96.540619 -254.20193) (xy 96.498603 -254.171404)
			(xy 96.46188 -254.134681) (xy 96.431354 -254.092665) (xy 96.407776 -254.046391) (xy 96.391728 -253.996998)
			(xy 96.383603 -253.945703) (xy 96.103693 -253.945703) (xy 96.095568 -253.996998) (xy 96.07952 -254.046391)
			(xy 96.055942 -254.092665) (xy 96.025416 -254.134681) (xy 95.988693 -254.171404) (xy 95.946677 -254.20193)
			(xy 95.900403 -254.225508) (xy 95.85101 -254.241556) (xy 95.799715 -254.249681) (xy 95.747781 -254.249681)
			(xy 95.696486 -254.241556) (xy 95.647093 -254.225508) (xy 95.600819 -254.20193) (xy 95.558803 -254.171404)
			(xy 95.52208 -254.134681) (xy 95.491554 -254.092665) (xy 95.467976 -254.046391) (xy 95.451928 -253.996998)
			(xy 95.443803 -253.945703) (xy 95.163639 -253.945703) (xy 95.155514 -253.996998) (xy 95.139466 -254.046391)
			(xy 95.115888 -254.092665) (xy 95.085362 -254.134681) (xy 95.048639 -254.171404) (xy 95.006623 -254.20193)
			(xy 94.960349 -254.225508) (xy 94.910956 -254.241556) (xy 94.859661 -254.249681) (xy 94.807727 -254.249681)
			(xy 94.756432 -254.241556) (xy 94.707039 -254.225508) (xy 94.660765 -254.20193) (xy 94.618749 -254.171404)
			(xy 94.582026 -254.134681) (xy 94.5515 -254.092665) (xy 94.527922 -254.046391) (xy 94.511874 -253.996998)
			(xy 94.503749 -253.945703) (xy 94.224303 -253.945703) (xy 94.216909 -253.994217) (xy 94.201998 -254.041999)
			(xy 94.180059 -254.086989) (xy 94.151593 -254.12816) (xy 94.117249 -254.164573) (xy 94.077811 -254.195397)
			(xy 94.034179 -254.219927) (xy 93.98735 -254.237603) (xy 93.962982 -254.243332) (xy 93.959426 -254.244094)
			(xy 93.949114 -254.247517) (xy 93.932565 -254.261561) (xy 93.923427 -254.281249) (xy 93.92285 -254.2921)
			(xy 93.92285 -254.495046) (xy 93.927422 -254.505206) (xy 93.932756 -254.517398) (xy 93.935296 -254.522986)
			(xy 93.975174 -254.553466) (xy 94.061788 -254.564134) (xy 94.068138 -254.564642) (xy 94.107762 -254.544576)
			(xy 94.114874 -254.535686) (xy 94.130044 -254.517291) (xy 94.164955 -254.484818) (xy 94.204321 -254.457917)
			(xy 94.24726 -254.437192) (xy 94.292812 -254.423107) (xy 94.339955 -254.415977) (xy 94.363794 -254.415544)
			(xy 94.388789 -254.416008) (xy 94.438165 -254.423828) (xy 94.485709 -254.439275) (xy 94.530251 -254.461969)
			(xy 94.570694 -254.491353) (xy 94.606043 -254.526701) (xy 94.635427 -254.567144) (xy 94.658123 -254.611686)
			(xy 94.673571 -254.65923) (xy 94.681391 -254.708605) (xy 94.681391 -254.758595) (xy 94.681245 -254.759519)
			(xy 94.973649 -254.759519) (xy 94.973649 -254.707585) (xy 94.981774 -254.65629) (xy 94.997822 -254.606897)
			(xy 95.0214 -254.560623) (xy 95.051926 -254.518607) (xy 95.088649 -254.481884) (xy 95.130665 -254.451358)
			(xy 95.176939 -254.42778) (xy 95.226332 -254.411732) (xy 95.277627 -254.403607) (xy 95.329561 -254.403607)
			(xy 95.380856 -254.411732) (xy 95.430249 -254.42778) (xy 95.476523 -254.451358) (xy 95.518539 -254.481884)
			(xy 95.555262 -254.518607) (xy 95.585788 -254.560623) (xy 95.609366 -254.606897) (xy 95.625414 -254.65629)
			(xy 95.633539 -254.707585) (xy 95.634048 -254.733552) (xy 95.633539 -254.759519) (xy 95.913449 -254.759519)
			(xy 95.913449 -254.707585) (xy 95.921574 -254.65629) (xy 95.937622 -254.606897) (xy 95.9612 -254.560623)
			(xy 95.991726 -254.518607) (xy 96.028449 -254.481884) (xy 96.070465 -254.451358) (xy 96.116739 -254.42778)
			(xy 96.166132 -254.411732) (xy 96.217427 -254.403607) (xy 96.269361 -254.403607) (xy 96.320656 -254.411732)
			(xy 96.370049 -254.42778) (xy 96.416323 -254.451358) (xy 96.458339 -254.481884) (xy 96.495062 -254.518607)
			(xy 96.525588 -254.560623) (xy 96.549166 -254.606897) (xy 96.565214 -254.65629) (xy 96.573339 -254.707585)
			(xy 96.573848 -254.733552) (xy 96.573339 -254.759519) (xy 96.853249 -254.759519) (xy 96.853249 -254.707585)
			(xy 96.861374 -254.65629) (xy 96.877422 -254.606897) (xy 96.901 -254.560623) (xy 96.931526 -254.518607)
			(xy 96.968249 -254.481884) (xy 97.010265 -254.451358) (xy 97.056539 -254.42778) (xy 97.105932 -254.411732)
			(xy 97.157227 -254.403607) (xy 97.209161 -254.403607) (xy 97.260456 -254.411732) (xy 97.309849 -254.42778)
			(xy 97.356123 -254.451358) (xy 97.398139 -254.481884) (xy 97.434862 -254.518607) (xy 97.465388 -254.560623)
			(xy 97.488966 -254.606897) (xy 97.505014 -254.65629) (xy 97.513139 -254.707585) (xy 97.513648 -254.733552)
			(xy 97.513139 -254.759519) (xy 97.793303 -254.759519) (xy 97.793303 -254.707585) (xy 97.801428 -254.65629)
			(xy 97.817476 -254.606897) (xy 97.841054 -254.560623) (xy 97.87158 -254.518607) (xy 97.908303 -254.481884)
			(xy 97.950319 -254.451358) (xy 97.996593 -254.42778) (xy 98.045986 -254.411732) (xy 98.097281 -254.403607)
			(xy 98.149215 -254.403607) (xy 98.20051 -254.411732) (xy 98.249903 -254.42778) (xy 98.296177 -254.451358)
			(xy 98.338193 -254.481884) (xy 98.374916 -254.518607) (xy 98.405442 -254.560623) (xy 98.42902 -254.606897)
			(xy 98.445068 -254.65629) (xy 98.453193 -254.707585) (xy 98.453702 -254.733552) (xy 98.453193 -254.759519)
			(xy 98.732849 -254.759519) (xy 98.732849 -254.707585) (xy 98.740974 -254.65629) (xy 98.757022 -254.606897)
			(xy 98.7806 -254.560623) (xy 98.811126 -254.518607) (xy 98.847849 -254.481884) (xy 98.889865 -254.451358)
			(xy 98.936139 -254.42778) (xy 98.985532 -254.411732) (xy 99.036827 -254.403607) (xy 99.088761 -254.403607)
			(xy 99.140056 -254.411732) (xy 99.189449 -254.42778) (xy 99.235723 -254.451358) (xy 99.277739 -254.481884)
			(xy 99.314462 -254.518607) (xy 99.344988 -254.560623) (xy 99.368566 -254.606897) (xy 99.384614 -254.65629)
			(xy 99.392739 -254.707585) (xy 99.393248 -254.733552) (xy 99.392739 -254.759519) (xy 99.672649 -254.759519)
			(xy 99.672649 -254.707585) (xy 99.680774 -254.65629) (xy 99.696822 -254.606897) (xy 99.7204 -254.560623)
			(xy 99.750926 -254.518607) (xy 99.787649 -254.481884) (xy 99.829665 -254.451358) (xy 99.875939 -254.42778)
			(xy 99.925332 -254.411732) (xy 99.976627 -254.403607) (xy 100.028561 -254.403607) (xy 100.079856 -254.411732)
			(xy 100.129249 -254.42778) (xy 100.175523 -254.451358) (xy 100.217539 -254.481884) (xy 100.254262 -254.518607)
			(xy 100.284788 -254.560623) (xy 100.308366 -254.606897) (xy 100.324414 -254.65629) (xy 100.332539 -254.707585)
			(xy 100.333048 -254.733552) (xy 100.332539 -254.759519) (xy 100.612449 -254.759519) (xy 100.612449 -254.707585)
			(xy 100.620574 -254.65629) (xy 100.636622 -254.606897) (xy 100.6602 -254.560623) (xy 100.690726 -254.518607)
			(xy 100.727449 -254.481884) (xy 100.769465 -254.451358) (xy 100.815739 -254.42778) (xy 100.865132 -254.411732)
			(xy 100.916427 -254.403607) (xy 100.968361 -254.403607) (xy 101.019656 -254.411732) (xy 101.069049 -254.42778)
			(xy 101.115323 -254.451358) (xy 101.157339 -254.481884) (xy 101.194062 -254.518607) (xy 101.224588 -254.560623)
			(xy 101.248166 -254.606897) (xy 101.264214 -254.65629) (xy 101.272339 -254.707585) (xy 101.272848 -254.733552)
			(xy 101.272339 -254.759519) (xy 101.552249 -254.759519) (xy 101.552249 -254.707585) (xy 101.560374 -254.65629)
			(xy 101.576422 -254.606897) (xy 101.6 -254.560623) (xy 101.630526 -254.518607) (xy 101.667249 -254.481884)
			(xy 101.709265 -254.451358) (xy 101.755539 -254.42778) (xy 101.804932 -254.411732) (xy 101.856227 -254.403607)
			(xy 101.908161 -254.403607) (xy 101.959456 -254.411732) (xy 102.008849 -254.42778) (xy 102.055123 -254.451358)
			(xy 102.097139 -254.481884) (xy 102.133862 -254.518607) (xy 102.164388 -254.560623) (xy 102.187966 -254.606897)
			(xy 102.204014 -254.65629) (xy 102.212139 -254.707585) (xy 102.212648 -254.733552) (xy 102.212139 -254.759519)
			(xy 102.212099 -254.759773) (xy 109.070903 -254.759773) (xy 109.070903 -254.707839) (xy 109.079028 -254.656544)
			(xy 109.095076 -254.607151) (xy 109.118654 -254.560877) (xy 109.14918 -254.518861) (xy 109.185903 -254.482138)
			(xy 109.227919 -254.451612) (xy 109.274193 -254.428034) (xy 109.323586 -254.411986) (xy 109.374881 -254.403861)
			(xy 109.426815 -254.403861) (xy 109.47811 -254.411986) (xy 109.527503 -254.428034) (xy 109.573777 -254.451612)
			(xy 109.615793 -254.482138) (xy 109.652516 -254.518861) (xy 109.683042 -254.560877) (xy 109.70662 -254.607151)
			(xy 109.722668 -254.656544) (xy 109.730793 -254.707839) (xy 109.731302 -254.733806) (xy 109.730793 -254.759773)
			(xy 110.010703 -254.759773) (xy 110.010703 -254.707839) (xy 110.018828 -254.656544) (xy 110.034876 -254.607151)
			(xy 110.058454 -254.560877) (xy 110.08898 -254.518861) (xy 110.125703 -254.482138) (xy 110.167719 -254.451612)
			(xy 110.213993 -254.428034) (xy 110.263386 -254.411986) (xy 110.314681 -254.403861) (xy 110.366615 -254.403861)
			(xy 110.41791 -254.411986) (xy 110.467303 -254.428034) (xy 110.513577 -254.451612) (xy 110.555593 -254.482138)
			(xy 110.592316 -254.518861) (xy 110.622842 -254.560877) (xy 110.64642 -254.607151) (xy 110.662468 -254.656544)
			(xy 110.670593 -254.707839) (xy 110.671102 -254.733806) (xy 110.670593 -254.759773) (xy 110.950757 -254.759773)
			(xy 110.950757 -254.707839) (xy 110.958882 -254.656544) (xy 110.97493 -254.607151) (xy 110.998508 -254.560877)
			(xy 111.029034 -254.518861) (xy 111.065757 -254.482138) (xy 111.107773 -254.451612) (xy 111.154047 -254.428034)
			(xy 111.20344 -254.411986) (xy 111.254735 -254.403861) (xy 111.306669 -254.403861) (xy 111.357964 -254.411986)
			(xy 111.407357 -254.428034) (xy 111.453631 -254.451612) (xy 111.495647 -254.482138) (xy 111.53237 -254.518861)
			(xy 111.562896 -254.560877) (xy 111.586474 -254.607151) (xy 111.602522 -254.656544) (xy 111.610647 -254.707839)
			(xy 111.611156 -254.733806) (xy 111.610647 -254.759773) (xy 111.890557 -254.759773) (xy 111.890557 -254.707839)
			(xy 111.898682 -254.656544) (xy 111.91473 -254.607151) (xy 111.938308 -254.560877) (xy 111.968834 -254.518861)
			(xy 112.005557 -254.482138) (xy 112.047573 -254.451612) (xy 112.093847 -254.428034) (xy 112.14324 -254.411986)
			(xy 112.194535 -254.403861) (xy 112.246469 -254.403861) (xy 112.297764 -254.411986) (xy 112.347157 -254.428034)
			(xy 112.393431 -254.451612) (xy 112.435447 -254.482138) (xy 112.47217 -254.518861) (xy 112.502696 -254.560877)
			(xy 112.526274 -254.607151) (xy 112.542322 -254.656544) (xy 112.550447 -254.707839) (xy 112.550956 -254.733806)
			(xy 112.550447 -254.759773) (xy 112.830103 -254.759773) (xy 112.830103 -254.707839) (xy 112.838228 -254.656544)
			(xy 112.854276 -254.607151) (xy 112.877854 -254.560877) (xy 112.90838 -254.518861) (xy 112.945103 -254.482138)
			(xy 112.987119 -254.451612) (xy 113.033393 -254.428034) (xy 113.082786 -254.411986) (xy 113.134081 -254.403861)
			(xy 113.186015 -254.403861) (xy 113.23731 -254.411986) (xy 113.286703 -254.428034) (xy 113.332977 -254.451612)
			(xy 113.374993 -254.482138) (xy 113.411716 -254.518861) (xy 113.442242 -254.560877) (xy 113.46582 -254.607151)
			(xy 113.481868 -254.656544) (xy 113.489993 -254.707839) (xy 113.490502 -254.733806) (xy 113.489993 -254.759773)
			(xy 113.770157 -254.759773) (xy 113.770157 -254.707839) (xy 113.778282 -254.656544) (xy 113.79433 -254.607151)
			(xy 113.817908 -254.560877) (xy 113.848434 -254.518861) (xy 113.885157 -254.482138) (xy 113.927173 -254.451612)
			(xy 113.973447 -254.428034) (xy 114.02284 -254.411986) (xy 114.074135 -254.403861) (xy 114.126069 -254.403861)
			(xy 114.177364 -254.411986) (xy 114.226757 -254.428034) (xy 114.273031 -254.451612) (xy 114.315047 -254.482138)
			(xy 114.35177 -254.518861) (xy 114.382296 -254.560877) (xy 114.405874 -254.607151) (xy 114.421922 -254.656544)
			(xy 114.430047 -254.707839) (xy 114.430556 -254.733806) (xy 114.430047 -254.759773) (xy 114.421922 -254.811068)
			(xy 114.405874 -254.860461) (xy 114.382296 -254.906735) (xy 114.35177 -254.948751) (xy 114.315047 -254.985474)
			(xy 114.273031 -255.016) (xy 114.226757 -255.039578) (xy 114.177364 -255.055626) (xy 114.126069 -255.063751)
			(xy 114.074135 -255.063751) (xy 114.02284 -255.055626) (xy 113.973447 -255.039578) (xy 113.927173 -255.016)
			(xy 113.885157 -254.985474) (xy 113.848434 -254.948751) (xy 113.817908 -254.906735) (xy 113.79433 -254.860461)
			(xy 113.778282 -254.811068) (xy 113.770157 -254.759773) (xy 113.489993 -254.759773) (xy 113.481868 -254.811068)
			(xy 113.46582 -254.860461) (xy 113.442242 -254.906735) (xy 113.411716 -254.948751) (xy 113.374993 -254.985474)
			(xy 113.332977 -255.016) (xy 113.286703 -255.039578) (xy 113.23731 -255.055626) (xy 113.186015 -255.063751)
			(xy 113.134081 -255.063751) (xy 113.082786 -255.055626) (xy 113.033393 -255.039578) (xy 112.987119 -255.016)
			(xy 112.945103 -254.985474) (xy 112.90838 -254.948751) (xy 112.877854 -254.906735) (xy 112.854276 -254.860461)
			(xy 112.838228 -254.811068) (xy 112.830103 -254.759773) (xy 112.550447 -254.759773) (xy 112.542322 -254.811068)
			(xy 112.526274 -254.860461) (xy 112.502696 -254.906735) (xy 112.47217 -254.948751) (xy 112.435447 -254.985474)
			(xy 112.393431 -255.016) (xy 112.347157 -255.039578) (xy 112.297764 -255.055626) (xy 112.246469 -255.063751)
			(xy 112.194535 -255.063751) (xy 112.14324 -255.055626) (xy 112.093847 -255.039578) (xy 112.047573 -255.016)
			(xy 112.005557 -254.985474) (xy 111.968834 -254.948751) (xy 111.938308 -254.906735) (xy 111.91473 -254.860461)
			(xy 111.898682 -254.811068) (xy 111.890557 -254.759773) (xy 111.610647 -254.759773) (xy 111.602522 -254.811068)
			(xy 111.586474 -254.860461) (xy 111.562896 -254.906735) (xy 111.53237 -254.948751) (xy 111.495647 -254.985474)
			(xy 111.453631 -255.016) (xy 111.407357 -255.039578) (xy 111.357964 -255.055626) (xy 111.306669 -255.063751)
			(xy 111.254735 -255.063751) (xy 111.20344 -255.055626) (xy 111.154047 -255.039578) (xy 111.107773 -255.016)
			(xy 111.065757 -254.985474) (xy 111.029034 -254.948751) (xy 110.998508 -254.906735) (xy 110.97493 -254.860461)
			(xy 110.958882 -254.811068) (xy 110.950757 -254.759773) (xy 110.670593 -254.759773) (xy 110.662468 -254.811068)
			(xy 110.64642 -254.860461) (xy 110.622842 -254.906735) (xy 110.592316 -254.948751) (xy 110.555593 -254.985474)
			(xy 110.513577 -255.016) (xy 110.467303 -255.039578) (xy 110.41791 -255.055626) (xy 110.366615 -255.063751)
			(xy 110.314681 -255.063751) (xy 110.263386 -255.055626) (xy 110.213993 -255.039578) (xy 110.167719 -255.016)
			(xy 110.125703 -254.985474) (xy 110.08898 -254.948751) (xy 110.058454 -254.906735) (xy 110.034876 -254.860461)
			(xy 110.018828 -254.811068) (xy 110.010703 -254.759773) (xy 109.730793 -254.759773) (xy 109.722668 -254.811068)
			(xy 109.70662 -254.860461) (xy 109.683042 -254.906735) (xy 109.652516 -254.948751) (xy 109.615793 -254.985474)
			(xy 109.573777 -255.016) (xy 109.527503 -255.039578) (xy 109.47811 -255.055626) (xy 109.426815 -255.063751)
			(xy 109.374881 -255.063751) (xy 109.323586 -255.055626) (xy 109.274193 -255.039578) (xy 109.227919 -255.016)
			(xy 109.185903 -254.985474) (xy 109.14918 -254.948751) (xy 109.118654 -254.906735) (xy 109.095076 -254.860461)
			(xy 109.079028 -254.811068) (xy 109.070903 -254.759773) (xy 102.212099 -254.759773) (xy 102.204014 -254.810814)
			(xy 102.187966 -254.860207) (xy 102.164388 -254.906481) (xy 102.133862 -254.948497) (xy 102.097139 -254.98522)
			(xy 102.055123 -255.015746) (xy 102.008849 -255.039324) (xy 101.959456 -255.055372) (xy 101.908161 -255.063497)
			(xy 101.856227 -255.063497) (xy 101.804932 -255.055372) (xy 101.755539 -255.039324) (xy 101.709265 -255.015746)
			(xy 101.667249 -254.98522) (xy 101.630526 -254.948497) (xy 101.6 -254.906481) (xy 101.576422 -254.860207)
			(xy 101.560374 -254.810814) (xy 101.552249 -254.759519) (xy 101.272339 -254.759519) (xy 101.264214 -254.810814)
			(xy 101.248166 -254.860207) (xy 101.224588 -254.906481) (xy 101.194062 -254.948497) (xy 101.157339 -254.98522)
			(xy 101.115323 -255.015746) (xy 101.069049 -255.039324) (xy 101.019656 -255.055372) (xy 100.968361 -255.063497)
			(xy 100.916427 -255.063497) (xy 100.865132 -255.055372) (xy 100.815739 -255.039324) (xy 100.769465 -255.015746)
			(xy 100.727449 -254.98522) (xy 100.690726 -254.948497) (xy 100.6602 -254.906481) (xy 100.636622 -254.860207)
			(xy 100.620574 -254.810814) (xy 100.612449 -254.759519) (xy 100.332539 -254.759519) (xy 100.324414 -254.810814)
			(xy 100.308366 -254.860207) (xy 100.284788 -254.906481) (xy 100.254262 -254.948497) (xy 100.217539 -254.98522)
			(xy 100.175523 -255.015746) (xy 100.129249 -255.039324) (xy 100.079856 -255.055372) (xy 100.028561 -255.063497)
			(xy 99.976627 -255.063497) (xy 99.925332 -255.055372) (xy 99.875939 -255.039324) (xy 99.829665 -255.015746)
			(xy 99.787649 -254.98522) (xy 99.750926 -254.948497) (xy 99.7204 -254.906481) (xy 99.696822 -254.860207)
			(xy 99.680774 -254.810814) (xy 99.672649 -254.759519) (xy 99.392739 -254.759519) (xy 99.384614 -254.810814)
			(xy 99.368566 -254.860207) (xy 99.344988 -254.906481) (xy 99.314462 -254.948497) (xy 99.277739 -254.98522)
			(xy 99.235723 -255.015746) (xy 99.189449 -255.039324) (xy 99.140056 -255.055372) (xy 99.088761 -255.063497)
			(xy 99.036827 -255.063497) (xy 98.985532 -255.055372) (xy 98.936139 -255.039324) (xy 98.889865 -255.015746)
			(xy 98.847849 -254.98522) (xy 98.811126 -254.948497) (xy 98.7806 -254.906481) (xy 98.757022 -254.860207)
			(xy 98.740974 -254.810814) (xy 98.732849 -254.759519) (xy 98.453193 -254.759519) (xy 98.445068 -254.810814)
			(xy 98.42902 -254.860207) (xy 98.405442 -254.906481) (xy 98.374916 -254.948497) (xy 98.338193 -254.98522)
			(xy 98.296177 -255.015746) (xy 98.249903 -255.039324) (xy 98.20051 -255.055372) (xy 98.149215 -255.063497)
			(xy 98.097281 -255.063497) (xy 98.045986 -255.055372) (xy 97.996593 -255.039324) (xy 97.950319 -255.015746)
			(xy 97.908303 -254.98522) (xy 97.87158 -254.948497) (xy 97.841054 -254.906481) (xy 97.817476 -254.860207)
			(xy 97.801428 -254.810814) (xy 97.793303 -254.759519) (xy 97.513139 -254.759519) (xy 97.505014 -254.810814)
			(xy 97.488966 -254.860207) (xy 97.465388 -254.906481) (xy 97.434862 -254.948497) (xy 97.398139 -254.98522)
			(xy 97.356123 -255.015746) (xy 97.309849 -255.039324) (xy 97.260456 -255.055372) (xy 97.209161 -255.063497)
			(xy 97.157227 -255.063497) (xy 97.105932 -255.055372) (xy 97.056539 -255.039324) (xy 97.010265 -255.015746)
			(xy 96.968249 -254.98522) (xy 96.931526 -254.948497) (xy 96.901 -254.906481) (xy 96.877422 -254.860207)
			(xy 96.861374 -254.810814) (xy 96.853249 -254.759519) (xy 96.573339 -254.759519) (xy 96.565214 -254.810814)
			(xy 96.549166 -254.860207) (xy 96.525588 -254.906481) (xy 96.495062 -254.948497) (xy 96.458339 -254.98522)
			(xy 96.416323 -255.015746) (xy 96.370049 -255.039324) (xy 96.320656 -255.055372) (xy 96.269361 -255.063497)
			(xy 96.217427 -255.063497) (xy 96.166132 -255.055372) (xy 96.116739 -255.039324) (xy 96.070465 -255.015746)
			(xy 96.028449 -254.98522) (xy 95.991726 -254.948497) (xy 95.9612 -254.906481) (xy 95.937622 -254.860207)
			(xy 95.921574 -254.810814) (xy 95.913449 -254.759519) (xy 95.633539 -254.759519) (xy 95.625414 -254.810814)
			(xy 95.609366 -254.860207) (xy 95.585788 -254.906481) (xy 95.555262 -254.948497) (xy 95.518539 -254.98522)
			(xy 95.476523 -255.015746) (xy 95.430249 -255.039324) (xy 95.380856 -255.055372) (xy 95.329561 -255.063497)
			(xy 95.277627 -255.063497) (xy 95.226332 -255.055372) (xy 95.176939 -255.039324) (xy 95.130665 -255.015746)
			(xy 95.088649 -254.98522) (xy 95.051926 -254.948497) (xy 95.0214 -254.906481) (xy 94.997822 -254.860207)
			(xy 94.981774 -254.810814) (xy 94.973649 -254.759519) (xy 94.681245 -254.759519) (xy 94.673571 -254.80797)
			(xy 94.658123 -254.855514) (xy 94.635427 -254.900056) (xy 94.606043 -254.940499) (xy 94.570694 -254.975847)
			(xy 94.530251 -255.005231) (xy 94.485709 -255.027925) (xy 94.438165 -255.043372) (xy 94.388789 -255.051192)
			(xy 94.363794 -255.05156) (xy 94.339954 -255.051133) (xy 94.29281 -255.044011) (xy 94.247258 -255.029927)
			(xy 94.20432 -255.009197) (xy 94.164961 -254.982287) (xy 94.130062 -254.949799) (xy 94.114874 -254.931418)
			(xy 94.107762 -254.922528) (xy 94.068138 -254.902462) (xy 94.061788 -254.90297) (xy 93.975174 -254.913638)
			(xy 93.935296 -254.944118) (xy 93.932756 -254.949706) (xy 93.927422 -254.961898) (xy 93.92285 -254.972058)
			(xy 93.92285 -255.175258) (xy 93.923433 -255.186105) (xy 93.93259 -255.205777) (xy 93.949121 -255.219833)
			(xy 93.959426 -255.223264) (xy 93.962982 -255.224026) (xy 93.987357 -255.229703) (xy 94.034168 -255.247408)
			(xy 94.077781 -255.271957) (xy 94.117202 -255.30279) (xy 94.151533 -255.339205) (xy 94.179993 -255.380372)
			(xy 94.201932 -255.425354) (xy 94.216851 -255.473126) (xy 94.224411 -255.522599) (xy 94.224856 -255.547622)
			(xy 94.224345 -255.573589) (xy 94.504003 -255.573589) (xy 94.504003 -255.521655) (xy 94.512128 -255.47036)
			(xy 94.528176 -255.420967) (xy 94.551754 -255.374693) (xy 94.58228 -255.332677) (xy 94.619003 -255.295954)
			(xy 94.661019 -255.265428) (xy 94.707293 -255.24185) (xy 94.756686 -255.225802) (xy 94.807981 -255.217677)
			(xy 94.859915 -255.217677) (xy 94.91121 -255.225802) (xy 94.960603 -255.24185) (xy 95.006877 -255.265428)
			(xy 95.048893 -255.295954) (xy 95.085616 -255.332677) (xy 95.116142 -255.374693) (xy 95.13972 -255.420967)
			(xy 95.155768 -255.47036) (xy 95.163893 -255.521655) (xy 95.164402 -255.547622) (xy 95.163893 -255.573589)
			(xy 95.443803 -255.573589) (xy 95.443803 -255.521655) (xy 95.451928 -255.47036) (xy 95.467976 -255.420967)
			(xy 95.491554 -255.374693) (xy 95.52208 -255.332677) (xy 95.558803 -255.295954) (xy 95.600819 -255.265428)
			(xy 95.647093 -255.24185) (xy 95.696486 -255.225802) (xy 95.747781 -255.217677) (xy 95.799715 -255.217677)
			(xy 95.85101 -255.225802) (xy 95.900403 -255.24185) (xy 95.946677 -255.265428) (xy 95.988693 -255.295954)
			(xy 96.025416 -255.332677) (xy 96.055942 -255.374693) (xy 96.07952 -255.420967) (xy 96.095568 -255.47036)
			(xy 96.103693 -255.521655) (xy 96.104202 -255.547622) (xy 96.103693 -255.573589) (xy 96.383603 -255.573589)
			(xy 96.383603 -255.521655) (xy 96.391728 -255.47036) (xy 96.407776 -255.420967) (xy 96.431354 -255.374693)
			(xy 96.46188 -255.332677) (xy 96.498603 -255.295954) (xy 96.540619 -255.265428) (xy 96.586893 -255.24185)
			(xy 96.636286 -255.225802) (xy 96.687581 -255.217677) (xy 96.739515 -255.217677) (xy 96.79081 -255.225802)
			(xy 96.840203 -255.24185) (xy 96.886477 -255.265428) (xy 96.928493 -255.295954) (xy 96.965216 -255.332677)
			(xy 96.995742 -255.374693) (xy 97.01932 -255.420967) (xy 97.035368 -255.47036) (xy 97.043493 -255.521655)
			(xy 97.044002 -255.547622) (xy 97.043493 -255.573589) (xy 97.323403 -255.573589) (xy 97.323403 -255.521655)
			(xy 97.331528 -255.47036) (xy 97.347576 -255.420967) (xy 97.371154 -255.374693) (xy 97.40168 -255.332677)
			(xy 97.438403 -255.295954) (xy 97.480419 -255.265428) (xy 97.526693 -255.24185) (xy 97.576086 -255.225802)
			(xy 97.627381 -255.217677) (xy 97.679315 -255.217677) (xy 97.73061 -255.225802) (xy 97.780003 -255.24185)
			(xy 97.826277 -255.265428) (xy 97.868293 -255.295954) (xy 97.905016 -255.332677) (xy 97.935542 -255.374693)
			(xy 97.95912 -255.420967) (xy 97.975168 -255.47036) (xy 97.983293 -255.521655) (xy 97.983802 -255.547622)
			(xy 97.983293 -255.573589) (xy 98.262949 -255.573589) (xy 98.262949 -255.521655) (xy 98.271074 -255.47036)
			(xy 98.287122 -255.420967) (xy 98.3107 -255.374693) (xy 98.341226 -255.332677) (xy 98.377949 -255.295954)
			(xy 98.419965 -255.265428) (xy 98.466239 -255.24185) (xy 98.515632 -255.225802) (xy 98.566927 -255.217677)
			(xy 98.618861 -255.217677) (xy 98.670156 -255.225802) (xy 98.719549 -255.24185) (xy 98.765823 -255.265428)
			(xy 98.807839 -255.295954) (xy 98.844562 -255.332677) (xy 98.875088 -255.374693) (xy 98.898666 -255.420967)
			(xy 98.914714 -255.47036) (xy 98.922839 -255.521655) (xy 98.923348 -255.547622) (xy 98.922839 -255.573589)
			(xy 99.203003 -255.573589) (xy 99.203003 -255.521655) (xy 99.211128 -255.47036) (xy 99.227176 -255.420967)
			(xy 99.250754 -255.374693) (xy 99.28128 -255.332677) (xy 99.318003 -255.295954) (xy 99.360019 -255.265428)
			(xy 99.406293 -255.24185) (xy 99.455686 -255.225802) (xy 99.506981 -255.217677) (xy 99.558915 -255.217677)
			(xy 99.61021 -255.225802) (xy 99.659603 -255.24185) (xy 99.705877 -255.265428) (xy 99.747893 -255.295954)
			(xy 99.784616 -255.332677) (xy 99.815142 -255.374693) (xy 99.83872 -255.420967) (xy 99.854768 -255.47036)
			(xy 99.862893 -255.521655) (xy 99.863402 -255.547622) (xy 99.862893 -255.573589) (xy 100.142803 -255.573589)
			(xy 100.142803 -255.521655) (xy 100.150928 -255.47036) (xy 100.166976 -255.420967) (xy 100.190554 -255.374693)
			(xy 100.22108 -255.332677) (xy 100.257803 -255.295954) (xy 100.299819 -255.265428) (xy 100.346093 -255.24185)
			(xy 100.395486 -255.225802) (xy 100.446781 -255.217677) (xy 100.498715 -255.217677) (xy 100.55001 -255.225802)
			(xy 100.599403 -255.24185) (xy 100.645677 -255.265428) (xy 100.687693 -255.295954) (xy 100.724416 -255.332677)
			(xy 100.754942 -255.374693) (xy 100.77852 -255.420967) (xy 100.794568 -255.47036) (xy 100.802693 -255.521655)
			(xy 100.803202 -255.547622) (xy 100.802693 -255.573589) (xy 101.082603 -255.573589) (xy 101.082603 -255.521655)
			(xy 101.090728 -255.47036) (xy 101.106776 -255.420967) (xy 101.130354 -255.374693) (xy 101.16088 -255.332677)
			(xy 101.197603 -255.295954) (xy 101.239619 -255.265428) (xy 101.285893 -255.24185) (xy 101.335286 -255.225802)
			(xy 101.386581 -255.217677) (xy 101.438515 -255.217677) (xy 101.48981 -255.225802) (xy 101.539203 -255.24185)
			(xy 101.585477 -255.265428) (xy 101.627493 -255.295954) (xy 101.664216 -255.332677) (xy 101.694742 -255.374693)
			(xy 101.71832 -255.420967) (xy 101.734368 -255.47036) (xy 101.742493 -255.521655) (xy 101.743002 -255.547622)
			(xy 101.742493 -255.57357) (xy 102.022351 -255.57357) (xy 102.022351 -255.52163) (xy 102.030477 -255.47033)
			(xy 102.046529 -255.420932) (xy 102.070111 -255.374655) (xy 102.100643 -255.332636) (xy 102.137373 -255.295912)
			(xy 102.179396 -255.265386) (xy 102.225677 -255.24181) (xy 102.275076 -255.225766) (xy 102.326378 -255.217647)
			(xy 102.352348 -255.217168) (xy 102.382366 -255.217814) (xy 102.441411 -255.228683) (xy 102.469696 -255.238758)
			(xy 102.48358 -255.243504) (xy 102.512829 -255.245681) (xy 102.541488 -255.239448) (xy 102.567191 -255.225319)
			(xy 102.587812 -255.204463) (xy 102.601648 -255.178602) (xy 102.605078 -255.164336) (xy 102.610663 -255.139862)
			(xy 102.628165 -255.092816) (xy 102.652581 -255.048958) (xy 102.68335 -255.009297) (xy 102.719762 -254.974745)
			(xy 102.760981 -254.946098) (xy 102.806059 -254.924015) (xy 102.853958 -254.909003) (xy 102.903576 -254.901407)
			(xy 102.928674 -254.900938) (xy 102.954642 -254.901453) (xy 103.00594 -254.909574) (xy 103.055335 -254.92562)
			(xy 103.101612 -254.949195) (xy 103.143631 -254.97972) (xy 103.180358 -255.016443) (xy 103.210887 -255.058459)
			(xy 103.234467 -255.104733) (xy 103.250518 -255.154127) (xy 103.258645 -255.205424) (xy 103.259128 -255.231392)
			(xy 103.258697 -255.256099) (xy 103.251331 -255.304961) (xy 103.236763 -255.352179) (xy 103.215319 -255.396697)
			(xy 103.187477 -255.437521) (xy 103.17099 -255.455928) (xy 103.16104 -255.467422) (xy 103.147834 -255.49479)
			(xy 103.143264 -255.524831) (xy 103.147734 -255.554888) (xy 103.16085 -255.582299) (xy 103.170736 -255.59385)
			(xy 103.187095 -255.612227) (xy 103.214689 -255.652959) (xy 103.235936 -255.697334) (xy 103.250367 -255.744369)
			(xy 103.257661 -255.793024) (xy 103.258112 -255.817624) (xy 103.257693 -255.843596) (xy 103.249563 -255.8949)
			(xy 103.233508 -255.944301) (xy 103.209921 -255.990581) (xy 103.179385 -256.032602) (xy 103.142652 -256.069328)
			(xy 103.100625 -256.099856) (xy 103.054339 -256.123433) (xy 103.004936 -256.139479) (xy 102.95363 -256.147598)
			(xy 102.927658 -256.148078) (xy 102.901501 -256.147618) (xy 102.849838 -256.139383) (xy 102.800119 -256.123111)
			(xy 102.753585 -256.099206) (xy 102.7114 -256.068268) (xy 102.674616 -256.031069) (xy 102.644154 -255.988538)
			(xy 102.620775 -255.941738) (xy 102.612444 -255.916938) (xy 102.607806 -255.903728) (xy 102.592398 -255.880361)
			(xy 102.571223 -255.862059) (xy 102.545871 -255.850197) (xy 102.518251 -255.845668) (xy 102.490439 -255.848811)
			(xy 102.477316 -255.853692) (xy 102.447519 -255.865016) (xy 102.384976 -255.87729) (xy 102.35311 -255.878076)
			(xy 102.352348 -255.878076) (xy 102.326378 -255.877553) (xy 102.275076 -255.869434) (xy 102.225677 -255.85339)
			(xy 102.179396 -255.829814) (xy 102.137373 -255.799288) (xy 102.100643 -255.762564) (xy 102.070111 -255.720545)
			(xy 102.046529 -255.674268) (xy 102.030477 -255.62487) (xy 102.022351 -255.57357) (xy 101.742493 -255.57357)
			(xy 101.742493 -255.573589) (xy 101.734368 -255.624884) (xy 101.71832 -255.674277) (xy 101.694742 -255.720551)
			(xy 101.664216 -255.762567) (xy 101.627493 -255.79929) (xy 101.585477 -255.829816) (xy 101.539203 -255.853394)
			(xy 101.48981 -255.869442) (xy 101.438515 -255.877567) (xy 101.386581 -255.877567) (xy 101.335286 -255.869442)
			(xy 101.285893 -255.853394) (xy 101.239619 -255.829816) (xy 101.197603 -255.79929) (xy 101.16088 -255.762567)
			(xy 101.130354 -255.720551) (xy 101.106776 -255.674277) (xy 101.090728 -255.624884) (xy 101.082603 -255.573589)
			(xy 100.802693 -255.573589) (xy 100.794568 -255.624884) (xy 100.77852 -255.674277) (xy 100.754942 -255.720551)
			(xy 100.724416 -255.762567) (xy 100.687693 -255.79929) (xy 100.645677 -255.829816) (xy 100.599403 -255.853394)
			(xy 100.55001 -255.869442) (xy 100.498715 -255.877567) (xy 100.446781 -255.877567) (xy 100.395486 -255.869442)
			(xy 100.346093 -255.853394) (xy 100.299819 -255.829816) (xy 100.257803 -255.79929) (xy 100.22108 -255.762567)
			(xy 100.190554 -255.720551) (xy 100.166976 -255.674277) (xy 100.150928 -255.624884) (xy 100.142803 -255.573589)
			(xy 99.862893 -255.573589) (xy 99.854768 -255.624884) (xy 99.83872 -255.674277) (xy 99.815142 -255.720551)
			(xy 99.784616 -255.762567) (xy 99.747893 -255.79929) (xy 99.705877 -255.829816) (xy 99.659603 -255.853394)
			(xy 99.61021 -255.869442) (xy 99.558915 -255.877567) (xy 99.506981 -255.877567) (xy 99.455686 -255.869442)
			(xy 99.406293 -255.853394) (xy 99.360019 -255.829816) (xy 99.318003 -255.79929) (xy 99.28128 -255.762567)
			(xy 99.250754 -255.720551) (xy 99.227176 -255.674277) (xy 99.211128 -255.624884) (xy 99.203003 -255.573589)
			(xy 98.922839 -255.573589) (xy 98.914714 -255.624884) (xy 98.898666 -255.674277) (xy 98.875088 -255.720551)
			(xy 98.844562 -255.762567) (xy 98.807839 -255.79929) (xy 98.765823 -255.829816) (xy 98.719549 -255.853394)
			(xy 98.670156 -255.869442) (xy 98.618861 -255.877567) (xy 98.566927 -255.877567) (xy 98.515632 -255.869442)
			(xy 98.466239 -255.853394) (xy 98.419965 -255.829816) (xy 98.377949 -255.79929) (xy 98.341226 -255.762567)
			(xy 98.3107 -255.720551) (xy 98.287122 -255.674277) (xy 98.271074 -255.624884) (xy 98.262949 -255.573589)
			(xy 97.983293 -255.573589) (xy 97.975168 -255.624884) (xy 97.95912 -255.674277) (xy 97.935542 -255.720551)
			(xy 97.905016 -255.762567) (xy 97.868293 -255.79929) (xy 97.826277 -255.829816) (xy 97.780003 -255.853394)
			(xy 97.73061 -255.869442) (xy 97.679315 -255.877567) (xy 97.627381 -255.877567) (xy 97.576086 -255.869442)
			(xy 97.526693 -255.853394) (xy 97.480419 -255.829816) (xy 97.438403 -255.79929) (xy 97.40168 -255.762567)
			(xy 97.371154 -255.720551) (xy 97.347576 -255.674277) (xy 97.331528 -255.624884) (xy 97.323403 -255.573589)
			(xy 97.043493 -255.573589) (xy 97.035368 -255.624884) (xy 97.01932 -255.674277) (xy 96.995742 -255.720551)
			(xy 96.965216 -255.762567) (xy 96.928493 -255.79929) (xy 96.886477 -255.829816) (xy 96.840203 -255.853394)
			(xy 96.79081 -255.869442) (xy 96.739515 -255.877567) (xy 96.687581 -255.877567) (xy 96.636286 -255.869442)
			(xy 96.586893 -255.853394) (xy 96.540619 -255.829816) (xy 96.498603 -255.79929) (xy 96.46188 -255.762567)
			(xy 96.431354 -255.720551) (xy 96.407776 -255.674277) (xy 96.391728 -255.624884) (xy 96.383603 -255.573589)
			(xy 96.103693 -255.573589) (xy 96.095568 -255.624884) (xy 96.07952 -255.674277) (xy 96.055942 -255.720551)
			(xy 96.025416 -255.762567) (xy 95.988693 -255.79929) (xy 95.946677 -255.829816) (xy 95.900403 -255.853394)
			(xy 95.85101 -255.869442) (xy 95.799715 -255.877567) (xy 95.747781 -255.877567) (xy 95.696486 -255.869442)
			(xy 95.647093 -255.853394) (xy 95.600819 -255.829816) (xy 95.558803 -255.79929) (xy 95.52208 -255.762567)
			(xy 95.491554 -255.720551) (xy 95.467976 -255.674277) (xy 95.451928 -255.624884) (xy 95.443803 -255.573589)
			(xy 95.163893 -255.573589) (xy 95.155768 -255.624884) (xy 95.13972 -255.674277) (xy 95.116142 -255.720551)
			(xy 95.085616 -255.762567) (xy 95.048893 -255.79929) (xy 95.006877 -255.829816) (xy 94.960603 -255.853394)
			(xy 94.91121 -255.869442) (xy 94.859915 -255.877567) (xy 94.807981 -255.877567) (xy 94.756686 -255.869442)
			(xy 94.707293 -255.853394) (xy 94.661019 -255.829816) (xy 94.619003 -255.79929) (xy 94.58228 -255.762567)
			(xy 94.551754 -255.720551) (xy 94.528176 -255.674277) (xy 94.512128 -255.624884) (xy 94.504003 -255.573589)
			(xy 94.224345 -255.573589) (xy 94.224345 -255.573609) (xy 94.216212 -255.624944) (xy 94.20015 -255.674375)
			(xy 94.176553 -255.720685) (xy 94.146004 -255.762734) (xy 94.109254 -255.799487) (xy 94.067207 -255.83004)
			(xy 94.020899 -255.85364) (xy 93.971469 -255.869706) (xy 93.920135 -255.877843) (xy 93.894148 -255.87833)
			(xy 93.893894 -255.87833) (xy 93.869472 -255.877897) (xy 93.821157 -255.870718) (xy 93.774427 -255.856503)
			(xy 93.730299 -255.835561) (xy 93.689736 -255.80835) (xy 93.67139 -255.792224) (xy 93.664786 -255.786128)
			(xy 93.630242 -255.772158) (xy 93.557852 -255.77292) (xy 93.548636 -255.773767) (xy 93.531706 -255.781201)
			(xy 93.524832 -255.787398) (xy 93.443044 -255.869186) (xy 93.437294 -255.875525) (xy 93.430056 -255.891021)
			(xy 93.428388 -255.908042) (xy 93.43009 -255.91643) (xy 93.45549 -256.003298) (xy 93.492828 -256.037842)
			(xy 93.505274 -256.04089) (xy 93.528733 -256.04728) (xy 93.573606 -256.065999) (xy 93.615255 -256.091085)
			(xy 93.652783 -256.121998) (xy 93.685381 -256.158072) (xy 93.712346 -256.198529) (xy 93.733098 -256.242499)
			(xy 93.74719 -256.289032) (xy 93.754317 -256.337128) (xy 93.754702 -256.361438) (xy 93.75419 -256.387405)
			(xy 94.034103 -256.387405) (xy 94.034103 -256.335471) (xy 94.042228 -256.284176) (xy 94.058276 -256.234783)
			(xy 94.081854 -256.188509) (xy 94.11238 -256.146493) (xy 94.149103 -256.10977) (xy 94.191119 -256.079244)
			(xy 94.237393 -256.055666) (xy 94.286786 -256.039618) (xy 94.338081 -256.031493) (xy 94.390015 -256.031493)
			(xy 94.44131 -256.039618) (xy 94.490703 -256.055666) (xy 94.536977 -256.079244) (xy 94.578993 -256.10977)
			(xy 94.615716 -256.146493) (xy 94.646242 -256.188509) (xy 94.66982 -256.234783) (xy 94.685868 -256.284176)
			(xy 94.693993 -256.335471) (xy 94.694502 -256.361438) (xy 94.693993 -256.387405) (xy 94.973649 -256.387405)
			(xy 94.973649 -256.335471) (xy 94.981774 -256.284176) (xy 94.997822 -256.234783) (xy 95.0214 -256.188509)
			(xy 95.051926 -256.146493) (xy 95.088649 -256.10977) (xy 95.130665 -256.079244) (xy 95.176939 -256.055666)
			(xy 95.226332 -256.039618) (xy 95.277627 -256.031493) (xy 95.329561 -256.031493) (xy 95.380856 -256.039618)
			(xy 95.430249 -256.055666) (xy 95.476523 -256.079244) (xy 95.518539 -256.10977) (xy 95.555262 -256.146493)
			(xy 95.585788 -256.188509) (xy 95.609366 -256.234783) (xy 95.625414 -256.284176) (xy 95.633539 -256.335471)
			(xy 95.634048 -256.361438) (xy 95.633539 -256.387405) (xy 95.913449 -256.387405) (xy 95.913449 -256.335471)
			(xy 95.921574 -256.284176) (xy 95.937622 -256.234783) (xy 95.9612 -256.188509) (xy 95.991726 -256.146493)
			(xy 96.028449 -256.10977) (xy 96.070465 -256.079244) (xy 96.116739 -256.055666) (xy 96.166132 -256.039618)
			(xy 96.217427 -256.031493) (xy 96.269361 -256.031493) (xy 96.320656 -256.039618) (xy 96.370049 -256.055666)
			(xy 96.416323 -256.079244) (xy 96.458339 -256.10977) (xy 96.495062 -256.146493) (xy 96.525588 -256.188509)
			(xy 96.549166 -256.234783) (xy 96.565214 -256.284176) (xy 96.573339 -256.335471) (xy 96.573848 -256.361438)
			(xy 96.573339 -256.387405) (xy 96.853249 -256.387405) (xy 96.853249 -256.335471) (xy 96.861374 -256.284176)
			(xy 96.877422 -256.234783) (xy 96.901 -256.188509) (xy 96.931526 -256.146493) (xy 96.968249 -256.10977)
			(xy 97.010265 -256.079244) (xy 97.056539 -256.055666) (xy 97.105932 -256.039618) (xy 97.157227 -256.031493)
			(xy 97.209161 -256.031493) (xy 97.260456 -256.039618) (xy 97.309849 -256.055666) (xy 97.356123 -256.079244)
			(xy 97.398139 -256.10977) (xy 97.434862 -256.146493) (xy 97.465388 -256.188509) (xy 97.488966 -256.234783)
			(xy 97.505014 -256.284176) (xy 97.513139 -256.335471) (xy 97.513648 -256.361438) (xy 97.513139 -256.387405)
			(xy 97.793049 -256.387405) (xy 97.793049 -256.335471) (xy 97.801174 -256.284176) (xy 97.817222 -256.234783)
			(xy 97.8408 -256.188509) (xy 97.871326 -256.146493) (xy 97.908049 -256.10977) (xy 97.950065 -256.079244)
			(xy 97.996339 -256.055666) (xy 98.045732 -256.039618) (xy 98.097027 -256.031493) (xy 98.148961 -256.031493)
			(xy 98.200256 -256.039618) (xy 98.249649 -256.055666) (xy 98.295923 -256.079244) (xy 98.337939 -256.10977)
			(xy 98.374662 -256.146493) (xy 98.405188 -256.188509) (xy 98.428766 -256.234783) (xy 98.444814 -256.284176)
			(xy 98.452939 -256.335471) (xy 98.453448 -256.361438) (xy 98.452939 -256.387405) (xy 98.732849 -256.387405)
			(xy 98.732849 -256.335471) (xy 98.740974 -256.284176) (xy 98.757022 -256.234783) (xy 98.7806 -256.188509)
			(xy 98.811126 -256.146493) (xy 98.847849 -256.10977) (xy 98.889865 -256.079244) (xy 98.936139 -256.055666)
			(xy 98.985532 -256.039618) (xy 99.036827 -256.031493) (xy 99.088761 -256.031493) (xy 99.140056 -256.039618)
			(xy 99.189449 -256.055666) (xy 99.235723 -256.079244) (xy 99.277739 -256.10977) (xy 99.314462 -256.146493)
			(xy 99.344988 -256.188509) (xy 99.368566 -256.234783) (xy 99.384614 -256.284176) (xy 99.392739 -256.335471)
			(xy 99.393248 -256.361438) (xy 99.392739 -256.387405) (xy 99.672649 -256.387405) (xy 99.672649 -256.335471)
			(xy 99.680774 -256.284176) (xy 99.696822 -256.234783) (xy 99.7204 -256.188509) (xy 99.750926 -256.146493)
			(xy 99.787649 -256.10977) (xy 99.829665 -256.079244) (xy 99.875939 -256.055666) (xy 99.925332 -256.039618)
			(xy 99.976627 -256.031493) (xy 100.028561 -256.031493) (xy 100.079856 -256.039618) (xy 100.129249 -256.055666)
			(xy 100.175523 -256.079244) (xy 100.217539 -256.10977) (xy 100.254262 -256.146493) (xy 100.284788 -256.188509)
			(xy 100.308366 -256.234783) (xy 100.324414 -256.284176) (xy 100.332539 -256.335471) (xy 100.333048 -256.361438)
			(xy 100.332539 -256.387405) (xy 100.612703 -256.387405) (xy 100.612703 -256.335471) (xy 100.620828 -256.284176)
			(xy 100.636876 -256.234783) (xy 100.660454 -256.188509) (xy 100.69098 -256.146493) (xy 100.727703 -256.10977)
			(xy 100.769719 -256.079244) (xy 100.815993 -256.055666) (xy 100.865386 -256.039618) (xy 100.916681 -256.031493)
			(xy 100.968615 -256.031493) (xy 101.01991 -256.039618) (xy 101.069303 -256.055666) (xy 101.115577 -256.079244)
			(xy 101.157593 -256.10977) (xy 101.194316 -256.146493) (xy 101.224842 -256.188509) (xy 101.24842 -256.234783)
			(xy 101.264468 -256.284176) (xy 101.272593 -256.335471) (xy 101.273102 -256.361438) (xy 101.272593 -256.387405)
			(xy 101.552249 -256.387405) (xy 101.552249 -256.335471) (xy 101.560374 -256.284176) (xy 101.576422 -256.234783)
			(xy 101.6 -256.188509) (xy 101.630526 -256.146493) (xy 101.667249 -256.10977) (xy 101.709265 -256.079244)
			(xy 101.755539 -256.055666) (xy 101.804932 -256.039618) (xy 101.856227 -256.031493) (xy 101.908161 -256.031493)
			(xy 101.959456 -256.039618) (xy 102.008849 -256.055666) (xy 102.055123 -256.079244) (xy 102.097139 -256.10977)
			(xy 102.133862 -256.146493) (xy 102.164388 -256.188509) (xy 102.187966 -256.234783) (xy 102.204014 -256.284176)
			(xy 102.211344 -256.33045) (xy 108.103416 -256.33045) (xy 108.103416 -256.330196) (xy 108.103861 -256.305669)
			(xy 108.111125 -256.257156) (xy 108.125478 -256.210248) (xy 108.146604 -256.165977) (xy 108.174041 -256.125313)
			(xy 108.190284 -256.10693) (xy 108.200038 -256.095402) (xy 108.213056 -256.068179) (xy 108.217534 -256.038337)
			(xy 108.213078 -256.008492) (xy 108.200079 -255.981259) (xy 108.190284 -255.96977) (xy 108.17405 -255.951379)
			(xy 108.146603 -255.910722) (xy 108.125471 -255.866453) (xy 108.11112 -255.819545) (xy 108.103864 -255.771031)
			(xy 108.103416 -255.746504) (xy 108.103416 -255.74625) (xy 108.103925 -255.720283) (xy 108.11205 -255.668988)
			(xy 108.128098 -255.619595) (xy 108.151676 -255.573321) (xy 108.182202 -255.531305) (xy 108.218925 -255.494582)
			(xy 108.260941 -255.464056) (xy 108.307215 -255.440478) (xy 108.356608 -255.42443) (xy 108.407903 -255.416305)
			(xy 108.459837 -255.416305) (xy 108.511132 -255.42443) (xy 108.560525 -255.440478) (xy 108.606799 -255.464056)
			(xy 108.648815 -255.494582) (xy 108.685538 -255.531305) (xy 108.716064 -255.573321) (xy 108.71633 -255.573843)
			(xy 109.540803 -255.573843) (xy 109.540803 -255.521909) (xy 109.548928 -255.470614) (xy 109.564976 -255.421221)
			(xy 109.588554 -255.374947) (xy 109.61908 -255.332931) (xy 109.655803 -255.296208) (xy 109.697819 -255.265682)
			(xy 109.744093 -255.242104) (xy 109.793486 -255.226056) (xy 109.844781 -255.217931) (xy 109.896715 -255.217931)
			(xy 109.94801 -255.226056) (xy 109.997403 -255.242104) (xy 110.043677 -255.265682) (xy 110.085693 -255.296208)
			(xy 110.122416 -255.332931) (xy 110.152942 -255.374947) (xy 110.17652 -255.421221) (xy 110.192568 -255.470614)
			(xy 110.200693 -255.521909) (xy 110.201202 -255.547876) (xy 110.200693 -255.573843) (xy 110.480857 -255.573843)
			(xy 110.480857 -255.521909) (xy 110.488982 -255.470614) (xy 110.50503 -255.421221) (xy 110.528608 -255.374947)
			(xy 110.559134 -255.332931) (xy 110.595857 -255.296208) (xy 110.637873 -255.265682) (xy 110.684147 -255.242104)
			(xy 110.73354 -255.226056) (xy 110.784835 -255.217931) (xy 110.836769 -255.217931) (xy 110.888064 -255.226056)
			(xy 110.937457 -255.242104) (xy 110.983731 -255.265682) (xy 111.025747 -255.296208) (xy 111.06247 -255.332931)
			(xy 111.092996 -255.374947) (xy 111.116574 -255.421221) (xy 111.132622 -255.470614) (xy 111.140747 -255.521909)
			(xy 111.141256 -255.547876) (xy 111.140747 -255.573843) (xy 111.420403 -255.573843) (xy 111.420403 -255.521909)
			(xy 111.428528 -255.470614) (xy 111.444576 -255.421221) (xy 111.468154 -255.374947) (xy 111.49868 -255.332931)
			(xy 111.535403 -255.296208) (xy 111.577419 -255.265682) (xy 111.623693 -255.242104) (xy 111.673086 -255.226056)
			(xy 111.724381 -255.217931) (xy 111.776315 -255.217931) (xy 111.82761 -255.226056) (xy 111.877003 -255.242104)
			(xy 111.923277 -255.265682) (xy 111.965293 -255.296208) (xy 112.002016 -255.332931) (xy 112.032542 -255.374947)
			(xy 112.05612 -255.421221) (xy 112.072168 -255.470614) (xy 112.080293 -255.521909) (xy 112.080802 -255.547876)
			(xy 112.080293 -255.573843) (xy 112.360203 -255.573843) (xy 112.360203 -255.521909) (xy 112.368328 -255.470614)
			(xy 112.384376 -255.421221) (xy 112.407954 -255.374947) (xy 112.43848 -255.332931) (xy 112.475203 -255.296208)
			(xy 112.517219 -255.265682) (xy 112.563493 -255.242104) (xy 112.612886 -255.226056) (xy 112.664181 -255.217931)
			(xy 112.716115 -255.217931) (xy 112.76741 -255.226056) (xy 112.816803 -255.242104) (xy 112.863077 -255.265682)
			(xy 112.905093 -255.296208) (xy 112.941816 -255.332931) (xy 112.972342 -255.374947) (xy 112.99592 -255.421221)
			(xy 113.011968 -255.470614) (xy 113.020093 -255.521909) (xy 113.020602 -255.547876) (xy 113.020093 -255.573843)
			(xy 113.300003 -255.573843) (xy 113.300003 -255.521909) (xy 113.308128 -255.470614) (xy 113.324176 -255.421221)
			(xy 113.347754 -255.374947) (xy 113.37828 -255.332931) (xy 113.415003 -255.296208) (xy 113.457019 -255.265682)
			(xy 113.503293 -255.242104) (xy 113.552686 -255.226056) (xy 113.603981 -255.217931) (xy 113.655915 -255.217931)
			(xy 113.70721 -255.226056) (xy 113.756603 -255.242104) (xy 113.802877 -255.265682) (xy 113.844893 -255.296208)
			(xy 113.881616 -255.332931) (xy 113.912142 -255.374947) (xy 113.93572 -255.421221) (xy 113.951768 -255.470614)
			(xy 113.959893 -255.521909) (xy 113.960402 -255.547876) (xy 113.959893 -255.573843) (xy 114.239803 -255.573843)
			(xy 114.239803 -255.521909) (xy 114.247928 -255.470614) (xy 114.263976 -255.421221) (xy 114.287554 -255.374947)
			(xy 114.31808 -255.332931) (xy 114.354803 -255.296208) (xy 114.396819 -255.265682) (xy 114.443093 -255.242104)
			(xy 114.492486 -255.226056) (xy 114.543781 -255.217931) (xy 114.595715 -255.217931) (xy 114.64701 -255.226056)
			(xy 114.696403 -255.242104) (xy 114.742677 -255.265682) (xy 114.784693 -255.296208) (xy 114.821416 -255.332931)
			(xy 114.851942 -255.374947) (xy 114.87552 -255.421221) (xy 114.891568 -255.470614) (xy 114.899693 -255.521909)
			(xy 114.900202 -255.547876) (xy 114.899693 -255.573843) (xy 114.891568 -255.625138) (xy 114.87552 -255.674531)
			(xy 114.851942 -255.720805) (xy 114.821416 -255.762821) (xy 114.784693 -255.799544) (xy 114.742677 -255.83007)
			(xy 114.696403 -255.853648) (xy 114.64701 -255.869696) (xy 114.595715 -255.877821) (xy 114.543781 -255.877821)
			(xy 114.492486 -255.869696) (xy 114.443093 -255.853648) (xy 114.396819 -255.83007) (xy 114.354803 -255.799544)
			(xy 114.31808 -255.762821) (xy 114.287554 -255.720805) (xy 114.263976 -255.674531) (xy 114.247928 -255.625138)
			(xy 114.239803 -255.573843) (xy 113.959893 -255.573843) (xy 113.951768 -255.625138) (xy 113.93572 -255.674531)
			(xy 113.912142 -255.720805) (xy 113.881616 -255.762821) (xy 113.844893 -255.799544) (xy 113.802877 -255.83007)
			(xy 113.756603 -255.853648) (xy 113.70721 -255.869696) (xy 113.655915 -255.877821) (xy 113.603981 -255.877821)
			(xy 113.552686 -255.869696) (xy 113.503293 -255.853648) (xy 113.457019 -255.83007) (xy 113.415003 -255.799544)
			(xy 113.37828 -255.762821) (xy 113.347754 -255.720805) (xy 113.324176 -255.674531) (xy 113.308128 -255.625138)
			(xy 113.300003 -255.573843) (xy 113.020093 -255.573843) (xy 113.011968 -255.625138) (xy 112.99592 -255.674531)
			(xy 112.972342 -255.720805) (xy 112.941816 -255.762821) (xy 112.905093 -255.799544) (xy 112.863077 -255.83007)
			(xy 112.816803 -255.853648) (xy 112.76741 -255.869696) (xy 112.716115 -255.877821) (xy 112.664181 -255.877821)
			(xy 112.612886 -255.869696) (xy 112.563493 -255.853648) (xy 112.517219 -255.83007) (xy 112.475203 -255.799544)
			(xy 112.43848 -255.762821) (xy 112.407954 -255.720805) (xy 112.384376 -255.674531) (xy 112.368328 -255.625138)
			(xy 112.360203 -255.573843) (xy 112.080293 -255.573843) (xy 112.072168 -255.625138) (xy 112.05612 -255.674531)
			(xy 112.032542 -255.720805) (xy 112.002016 -255.762821) (xy 111.965293 -255.799544) (xy 111.923277 -255.83007)
			(xy 111.877003 -255.853648) (xy 111.82761 -255.869696) (xy 111.776315 -255.877821) (xy 111.724381 -255.877821)
			(xy 111.673086 -255.869696) (xy 111.623693 -255.853648) (xy 111.577419 -255.83007) (xy 111.535403 -255.799544)
			(xy 111.49868 -255.762821) (xy 111.468154 -255.720805) (xy 111.444576 -255.674531) (xy 111.428528 -255.625138)
			(xy 111.420403 -255.573843) (xy 111.140747 -255.573843) (xy 111.132622 -255.625138) (xy 111.116574 -255.674531)
			(xy 111.092996 -255.720805) (xy 111.06247 -255.762821) (xy 111.025747 -255.799544) (xy 110.983731 -255.83007)
			(xy 110.937457 -255.853648) (xy 110.888064 -255.869696) (xy 110.836769 -255.877821) (xy 110.784835 -255.877821)
			(xy 110.73354 -255.869696) (xy 110.684147 -255.853648) (xy 110.637873 -255.83007) (xy 110.595857 -255.799544)
			(xy 110.559134 -255.762821) (xy 110.528608 -255.720805) (xy 110.50503 -255.674531) (xy 110.488982 -255.625138)
			(xy 110.480857 -255.573843) (xy 110.200693 -255.573843) (xy 110.192568 -255.625138) (xy 110.17652 -255.674531)
			(xy 110.152942 -255.720805) (xy 110.122416 -255.762821) (xy 110.085693 -255.799544) (xy 110.043677 -255.83007)
			(xy 109.997403 -255.853648) (xy 109.94801 -255.869696) (xy 109.896715 -255.877821) (xy 109.844781 -255.877821)
			(xy 109.793486 -255.869696) (xy 109.744093 -255.853648) (xy 109.697819 -255.83007) (xy 109.655803 -255.799544)
			(xy 109.61908 -255.762821) (xy 109.588554 -255.720805) (xy 109.564976 -255.674531) (xy 109.548928 -255.625138)
			(xy 109.540803 -255.573843) (xy 108.71633 -255.573843) (xy 108.739642 -255.619595) (xy 108.75569 -255.668988)
			(xy 108.763815 -255.720283) (xy 108.764324 -255.74625) (xy 108.764324 -255.746504) (xy 108.763868 -255.77103)
			(xy 108.756606 -255.819543) (xy 108.742255 -255.86645) (xy 108.721131 -255.910721) (xy 108.693697 -255.951386)
			(xy 108.677456 -255.96977) (xy 108.667601 -255.98122) (xy 108.654589 -256.00847) (xy 108.650128 -256.038337)
			(xy 108.654611 -256.068201) (xy 108.667643 -256.095442) (xy 108.677456 -256.10693) (xy 108.693681 -256.12533)
			(xy 108.721131 -256.165983) (xy 108.742265 -256.21025) (xy 108.756619 -256.257156) (xy 108.763876 -256.305669)
			(xy 108.764324 -256.330196) (xy 108.764324 -256.33045) (xy 108.763815 -256.356417) (xy 108.758866 -256.387659)
			(xy 109.070903 -256.387659) (xy 109.070903 -256.335725) (xy 109.079028 -256.28443) (xy 109.095076 -256.235037)
			(xy 109.118654 -256.188763) (xy 109.14918 -256.146747) (xy 109.185903 -256.110024) (xy 109.227919 -256.079498)
			(xy 109.274193 -256.05592) (xy 109.323586 -256.039872) (xy 109.374881 -256.031747) (xy 109.426815 -256.031747)
			(xy 109.47811 -256.039872) (xy 109.527503 -256.05592) (xy 109.573777 -256.079498) (xy 109.615793 -256.110024)
			(xy 109.652516 -256.146747) (xy 109.683042 -256.188763) (xy 109.70662 -256.235037) (xy 109.722668 -256.28443)
			(xy 109.730793 -256.335725) (xy 109.731302 -256.361692) (xy 109.730793 -256.387659) (xy 110.010449 -256.387659)
			(xy 110.010449 -256.335725) (xy 110.018574 -256.28443) (xy 110.034622 -256.235037) (xy 110.0582 -256.188763)
			(xy 110.088726 -256.146747) (xy 110.125449 -256.110024) (xy 110.167465 -256.079498) (xy 110.213739 -256.05592)
			(xy 110.263132 -256.039872) (xy 110.314427 -256.031747) (xy 110.366361 -256.031747) (xy 110.417656 -256.039872)
			(xy 110.467049 -256.05592) (xy 110.513323 -256.079498) (xy 110.555339 -256.110024) (xy 110.592062 -256.146747)
			(xy 110.622588 -256.188763) (xy 110.646166 -256.235037) (xy 110.662214 -256.28443) (xy 110.670339 -256.335725)
			(xy 110.670848 -256.361692) (xy 110.670339 -256.387659) (xy 110.950757 -256.387659) (xy 110.950757 -256.335725)
			(xy 110.958882 -256.28443) (xy 110.97493 -256.235037) (xy 110.998508 -256.188763) (xy 111.029034 -256.146747)
			(xy 111.065757 -256.110024) (xy 111.107773 -256.079498) (xy 111.154047 -256.05592) (xy 111.20344 -256.039872)
			(xy 111.254735 -256.031747) (xy 111.306669 -256.031747) (xy 111.357964 -256.039872) (xy 111.407357 -256.05592)
			(xy 111.453631 -256.079498) (xy 111.495647 -256.110024) (xy 111.53237 -256.146747) (xy 111.562896 -256.188763)
			(xy 111.586474 -256.235037) (xy 111.602522 -256.28443) (xy 111.610647 -256.335725) (xy 111.611156 -256.361692)
			(xy 111.610647 -256.387659) (xy 111.890557 -256.387659) (xy 111.890557 -256.335725) (xy 111.898682 -256.28443)
			(xy 111.91473 -256.235037) (xy 111.938308 -256.188763) (xy 111.968834 -256.146747) (xy 112.005557 -256.110024)
			(xy 112.047573 -256.079498) (xy 112.093847 -256.05592) (xy 112.14324 -256.039872) (xy 112.194535 -256.031747)
			(xy 112.246469 -256.031747) (xy 112.297764 -256.039872) (xy 112.347157 -256.05592) (xy 112.393431 -256.079498)
			(xy 112.435447 -256.110024) (xy 112.47217 -256.146747) (xy 112.502696 -256.188763) (xy 112.526274 -256.235037)
			(xy 112.542322 -256.28443) (xy 112.550447 -256.335725) (xy 112.550956 -256.361692) (xy 112.550447 -256.387659)
			(xy 112.829849 -256.387659) (xy 112.829849 -256.335725) (xy 112.837974 -256.28443) (xy 112.854022 -256.235037)
			(xy 112.8776 -256.188763) (xy 112.908126 -256.146747) (xy 112.944849 -256.110024) (xy 112.986865 -256.079498)
			(xy 113.033139 -256.05592) (xy 113.082532 -256.039872) (xy 113.133827 -256.031747) (xy 113.185761 -256.031747)
			(xy 113.237056 -256.039872) (xy 113.286449 -256.05592) (xy 113.332723 -256.079498) (xy 113.374739 -256.110024)
			(xy 113.411462 -256.146747) (xy 113.441988 -256.188763) (xy 113.465566 -256.235037) (xy 113.481614 -256.28443)
			(xy 113.489739 -256.335725) (xy 113.490248 -256.361692) (xy 113.489739 -256.387659) (xy 113.770157 -256.387659)
			(xy 113.770157 -256.335725) (xy 113.778282 -256.28443) (xy 113.79433 -256.235037) (xy 113.817908 -256.188763)
			(xy 113.848434 -256.146747) (xy 113.885157 -256.110024) (xy 113.927173 -256.079498) (xy 113.973447 -256.05592)
			(xy 114.02284 -256.039872) (xy 114.074135 -256.031747) (xy 114.126069 -256.031747) (xy 114.177364 -256.039872)
			(xy 114.226757 -256.05592) (xy 114.273031 -256.079498) (xy 114.315047 -256.110024) (xy 114.35177 -256.146747)
			(xy 114.382296 -256.188763) (xy 114.405874 -256.235037) (xy 114.421922 -256.28443) (xy 114.430047 -256.335725)
			(xy 114.430556 -256.361692) (xy 114.430047 -256.387659) (xy 114.421922 -256.438954) (xy 114.405874 -256.488347)
			(xy 114.382296 -256.534621) (xy 114.35177 -256.576637) (xy 114.315047 -256.61336) (xy 114.273031 -256.643886)
			(xy 114.226757 -256.667464) (xy 114.177364 -256.683512) (xy 114.126069 -256.691637) (xy 114.074135 -256.691637)
			(xy 114.02284 -256.683512) (xy 113.973447 -256.667464) (xy 113.927173 -256.643886) (xy 113.885157 -256.61336)
			(xy 113.848434 -256.576637) (xy 113.817908 -256.534621) (xy 113.79433 -256.488347) (xy 113.778282 -256.438954)
			(xy 113.770157 -256.387659) (xy 113.489739 -256.387659) (xy 113.481614 -256.438954) (xy 113.465566 -256.488347)
			(xy 113.441988 -256.534621) (xy 113.411462 -256.576637) (xy 113.374739 -256.61336) (xy 113.332723 -256.643886)
			(xy 113.286449 -256.667464) (xy 113.237056 -256.683512) (xy 113.185761 -256.691637) (xy 113.133827 -256.691637)
			(xy 113.082532 -256.683512) (xy 113.033139 -256.667464) (xy 112.986865 -256.643886) (xy 112.944849 -256.61336)
			(xy 112.908126 -256.576637) (xy 112.8776 -256.534621) (xy 112.854022 -256.488347) (xy 112.837974 -256.438954)
			(xy 112.829849 -256.387659) (xy 112.550447 -256.387659) (xy 112.542322 -256.438954) (xy 112.526274 -256.488347)
			(xy 112.502696 -256.534621) (xy 112.47217 -256.576637) (xy 112.435447 -256.61336) (xy 112.393431 -256.643886)
			(xy 112.347157 -256.667464) (xy 112.297764 -256.683512) (xy 112.246469 -256.691637) (xy 112.194535 -256.691637)
			(xy 112.14324 -256.683512) (xy 112.093847 -256.667464) (xy 112.047573 -256.643886) (xy 112.005557 -256.61336)
			(xy 111.968834 -256.576637) (xy 111.938308 -256.534621) (xy 111.91473 -256.488347) (xy 111.898682 -256.438954)
			(xy 111.890557 -256.387659) (xy 111.610647 -256.387659) (xy 111.602522 -256.438954) (xy 111.586474 -256.488347)
			(xy 111.562896 -256.534621) (xy 111.53237 -256.576637) (xy 111.495647 -256.61336) (xy 111.453631 -256.643886)
			(xy 111.407357 -256.667464) (xy 111.357964 -256.683512) (xy 111.306669 -256.691637) (xy 111.254735 -256.691637)
			(xy 111.20344 -256.683512) (xy 111.154047 -256.667464) (xy 111.107773 -256.643886) (xy 111.065757 -256.61336)
			(xy 111.029034 -256.576637) (xy 110.998508 -256.534621) (xy 110.97493 -256.488347) (xy 110.958882 -256.438954)
			(xy 110.950757 -256.387659) (xy 110.670339 -256.387659) (xy 110.662214 -256.438954) (xy 110.646166 -256.488347)
			(xy 110.622588 -256.534621) (xy 110.592062 -256.576637) (xy 110.555339 -256.61336) (xy 110.513323 -256.643886)
			(xy 110.467049 -256.667464) (xy 110.417656 -256.683512) (xy 110.366361 -256.691637) (xy 110.314427 -256.691637)
			(xy 110.263132 -256.683512) (xy 110.213739 -256.667464) (xy 110.167465 -256.643886) (xy 110.125449 -256.61336)
			(xy 110.088726 -256.576637) (xy 110.0582 -256.534621) (xy 110.034622 -256.488347) (xy 110.018574 -256.438954)
			(xy 110.010449 -256.387659) (xy 109.730793 -256.387659) (xy 109.722668 -256.438954) (xy 109.70662 -256.488347)
			(xy 109.683042 -256.534621) (xy 109.652516 -256.576637) (xy 109.615793 -256.61336) (xy 109.573777 -256.643886)
			(xy 109.527503 -256.667464) (xy 109.47811 -256.683512) (xy 109.426815 -256.691637) (xy 109.374881 -256.691637)
			(xy 109.323586 -256.683512) (xy 109.274193 -256.667464) (xy 109.227919 -256.643886) (xy 109.185903 -256.61336)
			(xy 109.14918 -256.576637) (xy 109.118654 -256.534621) (xy 109.095076 -256.488347) (xy 109.079028 -256.438954)
			(xy 109.070903 -256.387659) (xy 108.758866 -256.387659) (xy 108.75569 -256.407712) (xy 108.739642 -256.457105)
			(xy 108.716064 -256.503379) (xy 108.685538 -256.545395) (xy 108.648815 -256.582118) (xy 108.606799 -256.612644)
			(xy 108.560525 -256.636222) (xy 108.511132 -256.65227) (xy 108.459837 -256.660395) (xy 108.407903 -256.660395)
			(xy 108.356608 -256.65227) (xy 108.307215 -256.636222) (xy 108.260941 -256.612644) (xy 108.218925 -256.582118)
			(xy 108.182202 -256.545395) (xy 108.151676 -256.503379) (xy 108.128098 -256.457105) (xy 108.11205 -256.407712)
			(xy 108.103925 -256.356417) (xy 108.103416 -256.33045) (xy 102.211344 -256.33045) (xy 102.212139 -256.335471)
			(xy 102.212648 -256.361438) (xy 102.212139 -256.387405) (xy 102.204014 -256.4387) (xy 102.187966 -256.488093)
			(xy 102.164388 -256.534367) (xy 102.133862 -256.576383) (xy 102.097139 -256.613106) (xy 102.055123 -256.643632)
			(xy 102.008849 -256.66721) (xy 101.959456 -256.683258) (xy 101.908161 -256.691383) (xy 101.856227 -256.691383)
			(xy 101.804932 -256.683258) (xy 101.755539 -256.66721) (xy 101.709265 -256.643632) (xy 101.667249 -256.613106)
			(xy 101.630526 -256.576383) (xy 101.6 -256.534367) (xy 101.576422 -256.488093) (xy 101.560374 -256.4387)
			(xy 101.552249 -256.387405) (xy 101.272593 -256.387405) (xy 101.264468 -256.4387) (xy 101.24842 -256.488093)
			(xy 101.224842 -256.534367) (xy 101.194316 -256.576383) (xy 101.157593 -256.613106) (xy 101.115577 -256.643632)
			(xy 101.069303 -256.66721) (xy 101.01991 -256.683258) (xy 100.968615 -256.691383) (xy 100.916681 -256.691383)
			(xy 100.865386 -256.683258) (xy 100.815993 -256.66721) (xy 100.769719 -256.643632) (xy 100.727703 -256.613106)
			(xy 100.69098 -256.576383) (xy 100.660454 -256.534367) (xy 100.636876 -256.488093) (xy 100.620828 -256.4387)
			(xy 100.612703 -256.387405) (xy 100.332539 -256.387405) (xy 100.324414 -256.4387) (xy 100.308366 -256.488093)
			(xy 100.284788 -256.534367) (xy 100.254262 -256.576383) (xy 100.217539 -256.613106) (xy 100.175523 -256.643632)
			(xy 100.129249 -256.66721) (xy 100.079856 -256.683258) (xy 100.028561 -256.691383) (xy 99.976627 -256.691383)
			(xy 99.925332 -256.683258) (xy 99.875939 -256.66721) (xy 99.829665 -256.643632) (xy 99.787649 -256.613106)
			(xy 99.750926 -256.576383) (xy 99.7204 -256.534367) (xy 99.696822 -256.488093) (xy 99.680774 -256.4387)
			(xy 99.672649 -256.387405) (xy 99.392739 -256.387405) (xy 99.384614 -256.4387) (xy 99.368566 -256.488093)
			(xy 99.344988 -256.534367) (xy 99.314462 -256.576383) (xy 99.277739 -256.613106) (xy 99.235723 -256.643632)
			(xy 99.189449 -256.66721) (xy 99.140056 -256.683258) (xy 99.088761 -256.691383) (xy 99.036827 -256.691383)
			(xy 98.985532 -256.683258) (xy 98.936139 -256.66721) (xy 98.889865 -256.643632) (xy 98.847849 -256.613106)
			(xy 98.811126 -256.576383) (xy 98.7806 -256.534367) (xy 98.757022 -256.488093) (xy 98.740974 -256.4387)
			(xy 98.732849 -256.387405) (xy 98.452939 -256.387405) (xy 98.444814 -256.4387) (xy 98.428766 -256.488093)
			(xy 98.405188 -256.534367) (xy 98.374662 -256.576383) (xy 98.337939 -256.613106) (xy 98.295923 -256.643632)
			(xy 98.249649 -256.66721) (xy 98.200256 -256.683258) (xy 98.148961 -256.691383) (xy 98.097027 -256.691383)
			(xy 98.045732 -256.683258) (xy 97.996339 -256.66721) (xy 97.950065 -256.643632) (xy 97.908049 -256.613106)
			(xy 97.871326 -256.576383) (xy 97.8408 -256.534367) (xy 97.817222 -256.488093) (xy 97.801174 -256.4387)
			(xy 97.793049 -256.387405) (xy 97.513139 -256.387405) (xy 97.505014 -256.4387) (xy 97.488966 -256.488093)
			(xy 97.465388 -256.534367) (xy 97.434862 -256.576383) (xy 97.398139 -256.613106) (xy 97.356123 -256.643632)
			(xy 97.309849 -256.66721) (xy 97.260456 -256.683258) (xy 97.209161 -256.691383) (xy 97.157227 -256.691383)
			(xy 97.105932 -256.683258) (xy 97.056539 -256.66721) (xy 97.010265 -256.643632) (xy 96.968249 -256.613106)
			(xy 96.931526 -256.576383) (xy 96.901 -256.534367) (xy 96.877422 -256.488093) (xy 96.861374 -256.4387)
			(xy 96.853249 -256.387405) (xy 96.573339 -256.387405) (xy 96.565214 -256.4387) (xy 96.549166 -256.488093)
			(xy 96.525588 -256.534367) (xy 96.495062 -256.576383) (xy 96.458339 -256.613106) (xy 96.416323 -256.643632)
			(xy 96.370049 -256.66721) (xy 96.320656 -256.683258) (xy 96.269361 -256.691383) (xy 96.217427 -256.691383)
			(xy 96.166132 -256.683258) (xy 96.116739 -256.66721) (xy 96.070465 -256.643632) (xy 96.028449 -256.613106)
			(xy 95.991726 -256.576383) (xy 95.9612 -256.534367) (xy 95.937622 -256.488093) (xy 95.921574 -256.4387)
			(xy 95.913449 -256.387405) (xy 95.633539 -256.387405) (xy 95.625414 -256.4387) (xy 95.609366 -256.488093)
			(xy 95.585788 -256.534367) (xy 95.555262 -256.576383) (xy 95.518539 -256.613106) (xy 95.476523 -256.643632)
			(xy 95.430249 -256.66721) (xy 95.380856 -256.683258) (xy 95.329561 -256.691383) (xy 95.277627 -256.691383)
			(xy 95.226332 -256.683258) (xy 95.176939 -256.66721) (xy 95.130665 -256.643632) (xy 95.088649 -256.613106)
			(xy 95.051926 -256.576383) (xy 95.0214 -256.534367) (xy 94.997822 -256.488093) (xy 94.981774 -256.4387)
			(xy 94.973649 -256.387405) (xy 94.693993 -256.387405) (xy 94.685868 -256.4387) (xy 94.66982 -256.488093)
			(xy 94.646242 -256.534367) (xy 94.615716 -256.576383) (xy 94.578993 -256.613106) (xy 94.536977 -256.643632)
			(xy 94.490703 -256.66721) (xy 94.44131 -256.683258) (xy 94.390015 -256.691383) (xy 94.338081 -256.691383)
			(xy 94.286786 -256.683258) (xy 94.237393 -256.66721) (xy 94.191119 -256.643632) (xy 94.149103 -256.613106)
			(xy 94.11238 -256.576383) (xy 94.081854 -256.534367) (xy 94.058276 -256.488093) (xy 94.042228 -256.4387)
			(xy 94.034103 -256.387405) (xy 93.75419 -256.387405) (xy 93.75419 -256.387423) (xy 93.746054 -256.438753)
			(xy 93.72999 -256.488178) (xy 93.706392 -256.534481) (xy 93.675841 -256.576524) (xy 93.63909 -256.61327)
			(xy 93.597044 -256.643815) (xy 93.550737 -256.667407) (xy 93.50131 -256.683465) (xy 93.449979 -256.691593)
			(xy 93.423994 -256.692146) (xy 93.399686 -256.691716) (xy 93.351594 -256.684596) (xy 93.305064 -256.670511)
			(xy 93.261097 -256.649764) (xy 93.220642 -256.622803) (xy 93.184572 -256.590208) (xy 93.153662 -256.552683)
			(xy 93.128581 -256.511037) (xy 93.109869 -256.466167) (xy 93.103446 -256.442718) (xy 93.100398 -256.430272)
			(xy 93.065854 -256.392934) (xy 92.978986 -256.367534) (xy 92.9706 -256.365778) (xy 92.953557 -256.367417)
			(xy 92.938062 -256.374702) (xy 92.931742 -256.380488) (xy 92.732352 -256.579878) (xy 92.725344 -256.587718)
			(xy 92.710475 -256.60259) (xy 92.702634 -256.609596) (xy 92.326968 -256.985262) (xy 92.320446 -256.992455)
			(xy 92.312991 -257.010363) (xy 92.31249 -257.02006) (xy 92.316808 -257.040634) (xy 92.31757 -257.04292)
			(xy 92.326275 -257.063843) (xy 92.338573 -257.107459) (xy 92.344821 -257.152342) (xy 92.345256 -257.175)
			(xy 92.345256 -257.175254) (xy 92.34475 -257.201221) (xy 92.624149 -257.201221) (xy 92.624149 -257.149287)
			(xy 92.632274 -257.097992) (xy 92.648322 -257.048599) (xy 92.6719 -257.002325) (xy 92.702426 -256.960309)
			(xy 92.739149 -256.923586) (xy 92.781165 -256.89306) (xy 92.827439 -256.869482) (xy 92.876832 -256.853434)
			(xy 92.928127 -256.845309) (xy 92.980061 -256.845309) (xy 93.031356 -256.853434) (xy 93.080749 -256.869482)
			(xy 93.127023 -256.89306) (xy 93.169039 -256.923586) (xy 93.205762 -256.960309) (xy 93.236288 -257.002325)
			(xy 93.259866 -257.048599) (xy 93.275914 -257.097992) (xy 93.284039 -257.149287) (xy 93.284548 -257.175254)
			(xy 93.284039 -257.201221) (xy 93.564203 -257.201221) (xy 93.564203 -257.149287) (xy 93.572328 -257.097992)
			(xy 93.588376 -257.048599) (xy 93.611954 -257.002325) (xy 93.64248 -256.960309) (xy 93.679203 -256.923586)
			(xy 93.721219 -256.89306) (xy 93.767493 -256.869482) (xy 93.816886 -256.853434) (xy 93.868181 -256.845309)
			(xy 93.920115 -256.845309) (xy 93.97141 -256.853434) (xy 94.020803 -256.869482) (xy 94.067077 -256.89306)
			(xy 94.109093 -256.923586) (xy 94.145816 -256.960309) (xy 94.176342 -257.002325) (xy 94.19992 -257.048599)
			(xy 94.215968 -257.097992) (xy 94.224093 -257.149287) (xy 94.224602 -257.175254) (xy 94.224093 -257.201221)
			(xy 94.504003 -257.201221) (xy 94.504003 -257.149287) (xy 94.512128 -257.097992) (xy 94.528176 -257.048599)
			(xy 94.551754 -257.002325) (xy 94.58228 -256.960309) (xy 94.619003 -256.923586) (xy 94.661019 -256.89306)
			(xy 94.707293 -256.869482) (xy 94.756686 -256.853434) (xy 94.807981 -256.845309) (xy 94.859915 -256.845309)
			(xy 94.91121 -256.853434) (xy 94.960603 -256.869482) (xy 95.006877 -256.89306) (xy 95.048893 -256.923586)
			(xy 95.085616 -256.960309) (xy 95.116142 -257.002325) (xy 95.13972 -257.048599) (xy 95.155768 -257.097992)
			(xy 95.163893 -257.149287) (xy 95.164402 -257.175254) (xy 95.163893 -257.201221) (xy 95.443803 -257.201221)
			(xy 95.443803 -257.149287) (xy 95.451928 -257.097992) (xy 95.467976 -257.048599) (xy 95.491554 -257.002325)
			(xy 95.52208 -256.960309) (xy 95.558803 -256.923586) (xy 95.600819 -256.89306) (xy 95.647093 -256.869482)
			(xy 95.696486 -256.853434) (xy 95.747781 -256.845309) (xy 95.799715 -256.845309) (xy 95.85101 -256.853434)
			(xy 95.900403 -256.869482) (xy 95.946677 -256.89306) (xy 95.988693 -256.923586) (xy 96.025416 -256.960309)
			(xy 96.055942 -257.002325) (xy 96.07952 -257.048599) (xy 96.095568 -257.097992) (xy 96.103693 -257.149287)
			(xy 96.104202 -257.175254) (xy 96.103693 -257.201221) (xy 96.383603 -257.201221) (xy 96.383603 -257.149287)
			(xy 96.391728 -257.097992) (xy 96.407776 -257.048599) (xy 96.431354 -257.002325) (xy 96.46188 -256.960309)
			(xy 96.498603 -256.923586) (xy 96.540619 -256.89306) (xy 96.586893 -256.869482) (xy 96.636286 -256.853434)
			(xy 96.687581 -256.845309) (xy 96.739515 -256.845309) (xy 96.79081 -256.853434) (xy 96.840203 -256.869482)
			(xy 96.886477 -256.89306) (xy 96.928493 -256.923586) (xy 96.965216 -256.960309) (xy 96.995742 -257.002325)
			(xy 97.01932 -257.048599) (xy 97.035368 -257.097992) (xy 97.043493 -257.149287) (xy 97.044002 -257.175254)
			(xy 97.043493 -257.201221) (xy 97.323149 -257.201221) (xy 97.323149 -257.149287) (xy 97.331274 -257.097992)
			(xy 97.347322 -257.048599) (xy 97.3709 -257.002325) (xy 97.401426 -256.960309) (xy 97.438149 -256.923586)
			(xy 97.480165 -256.89306) (xy 97.526439 -256.869482) (xy 97.575832 -256.853434) (xy 97.627127 -256.845309)
			(xy 97.679061 -256.845309) (xy 97.730356 -256.853434) (xy 97.779749 -256.869482) (xy 97.826023 -256.89306)
			(xy 97.868039 -256.923586) (xy 97.904762 -256.960309) (xy 97.935288 -257.002325) (xy 97.958866 -257.048599)
			(xy 97.974914 -257.097992) (xy 97.983039 -257.149287) (xy 97.983548 -257.175254) (xy 97.983039 -257.201221)
			(xy 98.263203 -257.201221) (xy 98.263203 -257.149287) (xy 98.271328 -257.097992) (xy 98.287376 -257.048599)
			(xy 98.310954 -257.002325) (xy 98.34148 -256.960309) (xy 98.378203 -256.923586) (xy 98.420219 -256.89306)
			(xy 98.466493 -256.869482) (xy 98.515886 -256.853434) (xy 98.567181 -256.845309) (xy 98.619115 -256.845309)
			(xy 98.67041 -256.853434) (xy 98.719803 -256.869482) (xy 98.766077 -256.89306) (xy 98.808093 -256.923586)
			(xy 98.844816 -256.960309) (xy 98.875342 -257.002325) (xy 98.89892 -257.048599) (xy 98.914968 -257.097992)
			(xy 98.923093 -257.149287) (xy 98.923602 -257.175254) (xy 98.923093 -257.201221) (xy 99.202749 -257.201221)
			(xy 99.202749 -257.149287) (xy 99.210874 -257.097992) (xy 99.226922 -257.048599) (xy 99.2505 -257.002325)
			(xy 99.281026 -256.960309) (xy 99.317749 -256.923586) (xy 99.359765 -256.89306) (xy 99.406039 -256.869482)
			(xy 99.455432 -256.853434) (xy 99.506727 -256.845309) (xy 99.558661 -256.845309) (xy 99.609956 -256.853434)
			(xy 99.659349 -256.869482) (xy 99.705623 -256.89306) (xy 99.747639 -256.923586) (xy 99.784362 -256.960309)
			(xy 99.814888 -257.002325) (xy 99.838466 -257.048599) (xy 99.854514 -257.097992) (xy 99.862639 -257.149287)
			(xy 99.863148 -257.175254) (xy 99.862639 -257.201221) (xy 100.142803 -257.201221) (xy 100.142803 -257.149287)
			(xy 100.150928 -257.097992) (xy 100.166976 -257.048599) (xy 100.190554 -257.002325) (xy 100.22108 -256.960309)
			(xy 100.257803 -256.923586) (xy 100.299819 -256.89306) (xy 100.346093 -256.869482) (xy 100.395486 -256.853434)
			(xy 100.446781 -256.845309) (xy 100.498715 -256.845309) (xy 100.55001 -256.853434) (xy 100.599403 -256.869482)
			(xy 100.645677 -256.89306) (xy 100.687693 -256.923586) (xy 100.724416 -256.960309) (xy 100.754942 -257.002325)
			(xy 100.77852 -257.048599) (xy 100.794568 -257.097992) (xy 100.802693 -257.149287) (xy 100.803202 -257.175254)
			(xy 100.802693 -257.201221) (xy 101.082603 -257.201221) (xy 101.082603 -257.149287) (xy 101.090728 -257.097992)
			(xy 101.106776 -257.048599) (xy 101.130354 -257.002325) (xy 101.16088 -256.960309) (xy 101.197603 -256.923586)
			(xy 101.239619 -256.89306) (xy 101.285893 -256.869482) (xy 101.335286 -256.853434) (xy 101.386581 -256.845309)
			(xy 101.438515 -256.845309) (xy 101.48981 -256.853434) (xy 101.539203 -256.869482) (xy 101.585477 -256.89306)
			(xy 101.627493 -256.923586) (xy 101.664216 -256.960309) (xy 101.694742 -257.002325) (xy 101.71832 -257.048599)
			(xy 101.734368 -257.097992) (xy 101.742493 -257.149287) (xy 101.743002 -257.175254) (xy 101.742493 -257.201221)
			(xy 102.022403 -257.201221) (xy 102.022403 -257.149287) (xy 102.030528 -257.097992) (xy 102.046576 -257.048599)
			(xy 102.070154 -257.002325) (xy 102.10068 -256.960309) (xy 102.137403 -256.923586) (xy 102.179419 -256.89306)
			(xy 102.225693 -256.869482) (xy 102.275086 -256.853434) (xy 102.326381 -256.845309) (xy 102.378315 -256.845309)
			(xy 102.42961 -256.853434) (xy 102.479003 -256.869482) (xy 102.525277 -256.89306) (xy 102.567293 -256.923586)
			(xy 102.604016 -256.960309) (xy 102.634542 -257.002325) (xy 102.65812 -257.048599) (xy 102.674168 -257.097992)
			(xy 102.682293 -257.149287) (xy 102.682802 -257.175254) (xy 102.682293 -257.201221) (xy 102.674168 -257.252516)
			(xy 102.65812 -257.301909) (xy 102.634542 -257.348183) (xy 102.604016 -257.390199) (xy 102.567293 -257.426922)
			(xy 102.525277 -257.457448) (xy 102.479003 -257.481026) (xy 102.42961 -257.497074) (xy 102.378315 -257.505199)
			(xy 102.326381 -257.505199) (xy 102.275086 -257.497074) (xy 102.225693 -257.481026) (xy 102.179419 -257.457448)
			(xy 102.137403 -257.426922) (xy 102.10068 -257.390199) (xy 102.070154 -257.348183) (xy 102.046576 -257.301909)
			(xy 102.030528 -257.252516) (xy 102.022403 -257.201221) (xy 101.742493 -257.201221) (xy 101.734368 -257.252516)
			(xy 101.71832 -257.301909) (xy 101.694742 -257.348183) (xy 101.664216 -257.390199) (xy 101.627493 -257.426922)
			(xy 101.585477 -257.457448) (xy 101.539203 -257.481026) (xy 101.48981 -257.497074) (xy 101.438515 -257.505199)
			(xy 101.386581 -257.505199) (xy 101.335286 -257.497074) (xy 101.285893 -257.481026) (xy 101.239619 -257.457448)
			(xy 101.197603 -257.426922) (xy 101.16088 -257.390199) (xy 101.130354 -257.348183) (xy 101.106776 -257.301909)
			(xy 101.090728 -257.252516) (xy 101.082603 -257.201221) (xy 100.802693 -257.201221) (xy 100.794568 -257.252516)
			(xy 100.77852 -257.301909) (xy 100.754942 -257.348183) (xy 100.724416 -257.390199) (xy 100.687693 -257.426922)
			(xy 100.645677 -257.457448) (xy 100.599403 -257.481026) (xy 100.55001 -257.497074) (xy 100.498715 -257.505199)
			(xy 100.446781 -257.505199) (xy 100.395486 -257.497074) (xy 100.346093 -257.481026) (xy 100.299819 -257.457448)
			(xy 100.257803 -257.426922) (xy 100.22108 -257.390199) (xy 100.190554 -257.348183) (xy 100.166976 -257.301909)
			(xy 100.150928 -257.252516) (xy 100.142803 -257.201221) (xy 99.862639 -257.201221) (xy 99.854514 -257.252516)
			(xy 99.838466 -257.301909) (xy 99.814888 -257.348183) (xy 99.784362 -257.390199) (xy 99.747639 -257.426922)
			(xy 99.705623 -257.457448) (xy 99.659349 -257.481026) (xy 99.609956 -257.497074) (xy 99.558661 -257.505199)
			(xy 99.506727 -257.505199) (xy 99.455432 -257.497074) (xy 99.406039 -257.481026) (xy 99.359765 -257.457448)
			(xy 99.317749 -257.426922) (xy 99.281026 -257.390199) (xy 99.2505 -257.348183) (xy 99.226922 -257.301909)
			(xy 99.210874 -257.252516) (xy 99.202749 -257.201221) (xy 98.923093 -257.201221) (xy 98.914968 -257.252516)
			(xy 98.89892 -257.301909) (xy 98.875342 -257.348183) (xy 98.844816 -257.390199) (xy 98.808093 -257.426922)
			(xy 98.766077 -257.457448) (xy 98.719803 -257.481026) (xy 98.67041 -257.497074) (xy 98.619115 -257.505199)
			(xy 98.567181 -257.505199) (xy 98.515886 -257.497074) (xy 98.466493 -257.481026) (xy 98.420219 -257.457448)
			(xy 98.378203 -257.426922) (xy 98.34148 -257.390199) (xy 98.310954 -257.348183) (xy 98.287376 -257.301909)
			(xy 98.271328 -257.252516) (xy 98.263203 -257.201221) (xy 97.983039 -257.201221) (xy 97.974914 -257.252516)
			(xy 97.958866 -257.301909) (xy 97.935288 -257.348183) (xy 97.904762 -257.390199) (xy 97.868039 -257.426922)
			(xy 97.826023 -257.457448) (xy 97.779749 -257.481026) (xy 97.730356 -257.497074) (xy 97.679061 -257.505199)
			(xy 97.627127 -257.505199) (xy 97.575832 -257.497074) (xy 97.526439 -257.481026) (xy 97.480165 -257.457448)
			(xy 97.438149 -257.426922) (xy 97.401426 -257.390199) (xy 97.3709 -257.348183) (xy 97.347322 -257.301909)
			(xy 97.331274 -257.252516) (xy 97.323149 -257.201221) (xy 97.043493 -257.201221) (xy 97.035368 -257.252516)
			(xy 97.01932 -257.301909) (xy 96.995742 -257.348183) (xy 96.965216 -257.390199) (xy 96.928493 -257.426922)
			(xy 96.886477 -257.457448) (xy 96.840203 -257.481026) (xy 96.79081 -257.497074) (xy 96.739515 -257.505199)
			(xy 96.687581 -257.505199) (xy 96.636286 -257.497074) (xy 96.586893 -257.481026) (xy 96.540619 -257.457448)
			(xy 96.498603 -257.426922) (xy 96.46188 -257.390199) (xy 96.431354 -257.348183) (xy 96.407776 -257.301909)
			(xy 96.391728 -257.252516) (xy 96.383603 -257.201221) (xy 96.103693 -257.201221) (xy 96.095568 -257.252516)
			(xy 96.07952 -257.301909) (xy 96.055942 -257.348183) (xy 96.025416 -257.390199) (xy 95.988693 -257.426922)
			(xy 95.946677 -257.457448) (xy 95.900403 -257.481026) (xy 95.85101 -257.497074) (xy 95.799715 -257.505199)
			(xy 95.747781 -257.505199) (xy 95.696486 -257.497074) (xy 95.647093 -257.481026) (xy 95.600819 -257.457448)
			(xy 95.558803 -257.426922) (xy 95.52208 -257.390199) (xy 95.491554 -257.348183) (xy 95.467976 -257.301909)
			(xy 95.451928 -257.252516) (xy 95.443803 -257.201221) (xy 95.163893 -257.201221) (xy 95.155768 -257.252516)
			(xy 95.13972 -257.301909) (xy 95.116142 -257.348183) (xy 95.085616 -257.390199) (xy 95.048893 -257.426922)
			(xy 95.006877 -257.457448) (xy 94.960603 -257.481026) (xy 94.91121 -257.497074) (xy 94.859915 -257.505199)
			(xy 94.807981 -257.505199) (xy 94.756686 -257.497074) (xy 94.707293 -257.481026) (xy 94.661019 -257.457448)
			(xy 94.619003 -257.426922) (xy 94.58228 -257.390199) (xy 94.551754 -257.348183) (xy 94.528176 -257.301909)
			(xy 94.512128 -257.252516) (xy 94.504003 -257.201221) (xy 94.224093 -257.201221) (xy 94.215968 -257.252516)
			(xy 94.19992 -257.301909) (xy 94.176342 -257.348183) (xy 94.145816 -257.390199) (xy 94.109093 -257.426922)
			(xy 94.067077 -257.457448) (xy 94.020803 -257.481026) (xy 93.97141 -257.497074) (xy 93.920115 -257.505199)
			(xy 93.868181 -257.505199) (xy 93.816886 -257.497074) (xy 93.767493 -257.481026) (xy 93.721219 -257.457448)
			(xy 93.679203 -257.426922) (xy 93.64248 -257.390199) (xy 93.611954 -257.348183) (xy 93.588376 -257.301909)
			(xy 93.572328 -257.252516) (xy 93.564203 -257.201221) (xy 93.284039 -257.201221) (xy 93.275914 -257.252516)
			(xy 93.259866 -257.301909) (xy 93.236288 -257.348183) (xy 93.205762 -257.390199) (xy 93.169039 -257.426922)
			(xy 93.127023 -257.457448) (xy 93.080749 -257.481026) (xy 93.031356 -257.497074) (xy 92.980061 -257.505199)
			(xy 92.928127 -257.505199) (xy 92.876832 -257.497074) (xy 92.827439 -257.481026) (xy 92.781165 -257.457448)
			(xy 92.739149 -257.426922) (xy 92.702426 -257.390199) (xy 92.6719 -257.348183) (xy 92.648322 -257.301909)
			(xy 92.632274 -257.252516) (xy 92.624149 -257.201221) (xy 92.34475 -257.201221) (xy 92.34475 -257.201245)
			(xy 92.336625 -257.252588) (xy 92.320569 -257.302028) (xy 92.296976 -257.348347) (xy 92.266428 -257.390405)
			(xy 92.229677 -257.427167) (xy 92.187627 -257.457727) (xy 92.141315 -257.481333) (xy 92.091879 -257.497403)
			(xy 92.040539 -257.505543) (xy 92.014548 -257.505962) (xy 91.986245 -257.505379) (xy 91.930464 -257.495739)
			(xy 91.877137 -257.476749) (xy 91.827819 -257.448963) (xy 91.805506 -257.43154) (xy 91.798902 -257.426206)
			(xy 91.76639 -257.414014) (xy 91.756548 -257.41454) (xy 91.738373 -257.422113) (xy 91.731084 -257.428746)
			(xy 91.702382 -257.457448) (xy 91.695675 -257.464688) (xy 91.688095 -257.482893) (xy 91.68765 -257.492754)
			(xy 91.68765 -257.661156) (xy 91.712034 -257.703574) (xy 91.718638 -257.707892) (xy 91.740365 -257.721942)
			(xy 91.779566 -257.755707) (xy 91.813033 -257.795162) (xy 91.83995 -257.839347) (xy 91.859659 -257.887183)
			(xy 91.871682 -257.937505) (xy 91.875724 -257.989084) (xy 91.873693 -258.015037) (xy 92.154503 -258.015037)
			(xy 92.154503 -257.963103) (xy 92.162628 -257.911808) (xy 92.178676 -257.862415) (xy 92.202254 -257.816141)
			(xy 92.23278 -257.774125) (xy 92.269503 -257.737402) (xy 92.311519 -257.706876) (xy 92.357793 -257.683298)
			(xy 92.407186 -257.66725) (xy 92.458481 -257.659125) (xy 92.510415 -257.659125) (xy 92.56171 -257.66725)
			(xy 92.611103 -257.683298) (xy 92.657377 -257.706876) (xy 92.699393 -257.737402) (xy 92.736116 -257.774125)
			(xy 92.766642 -257.816141) (xy 92.79022 -257.862415) (xy 92.806268 -257.911808) (xy 92.814393 -257.963103)
			(xy 92.814902 -257.98907) (xy 92.814393 -258.015037) (xy 93.094049 -258.015037) (xy 93.094049 -257.963103)
			(xy 93.102174 -257.911808) (xy 93.118222 -257.862415) (xy 93.1418 -257.816141) (xy 93.172326 -257.774125)
			(xy 93.209049 -257.737402) (xy 93.251065 -257.706876) (xy 93.297339 -257.683298) (xy 93.346732 -257.66725)
			(xy 93.398027 -257.659125) (xy 93.449961 -257.659125) (xy 93.501256 -257.66725) (xy 93.550649 -257.683298)
			(xy 93.596923 -257.706876) (xy 93.638939 -257.737402) (xy 93.675662 -257.774125) (xy 93.706188 -257.816141)
			(xy 93.729766 -257.862415) (xy 93.745814 -257.911808) (xy 93.753939 -257.963103) (xy 93.754448 -257.98907)
			(xy 93.753939 -258.015037) (xy 94.033849 -258.015037) (xy 94.033849 -257.963103) (xy 94.041974 -257.911808)
			(xy 94.058022 -257.862415) (xy 94.0816 -257.816141) (xy 94.112126 -257.774125) (xy 94.148849 -257.737402)
			(xy 94.190865 -257.706876) (xy 94.237139 -257.683298) (xy 94.286532 -257.66725) (xy 94.337827 -257.659125)
			(xy 94.389761 -257.659125) (xy 94.441056 -257.66725) (xy 94.490449 -257.683298) (xy 94.536723 -257.706876)
			(xy 94.578739 -257.737402) (xy 94.615462 -257.774125) (xy 94.645988 -257.816141) (xy 94.669566 -257.862415)
			(xy 94.685614 -257.911808) (xy 94.693739 -257.963103) (xy 94.694248 -257.98907) (xy 94.693739 -258.015037)
			(xy 94.973649 -258.015037) (xy 94.973649 -257.963103) (xy 94.981774 -257.911808) (xy 94.997822 -257.862415)
			(xy 95.0214 -257.816141) (xy 95.051926 -257.774125) (xy 95.088649 -257.737402) (xy 95.130665 -257.706876)
			(xy 95.176939 -257.683298) (xy 95.226332 -257.66725) (xy 95.277627 -257.659125) (xy 95.329561 -257.659125)
			(xy 95.380856 -257.66725) (xy 95.430249 -257.683298) (xy 95.476523 -257.706876) (xy 95.518539 -257.737402)
			(xy 95.555262 -257.774125) (xy 95.585788 -257.816141) (xy 95.609366 -257.862415) (xy 95.625414 -257.911808)
			(xy 95.633539 -257.963103) (xy 95.634048 -257.98907) (xy 95.633539 -258.015037) (xy 95.913449 -258.015037)
			(xy 95.913449 -257.963103) (xy 95.921574 -257.911808) (xy 95.937622 -257.862415) (xy 95.9612 -257.816141)
			(xy 95.991726 -257.774125) (xy 96.028449 -257.737402) (xy 96.070465 -257.706876) (xy 96.116739 -257.683298)
			(xy 96.166132 -257.66725) (xy 96.217427 -257.659125) (xy 96.269361 -257.659125) (xy 96.320656 -257.66725)
			(xy 96.370049 -257.683298) (xy 96.416323 -257.706876) (xy 96.458339 -257.737402) (xy 96.495062 -257.774125)
			(xy 96.525588 -257.816141) (xy 96.549166 -257.862415) (xy 96.565214 -257.911808) (xy 96.573339 -257.963103)
			(xy 96.573848 -257.98907) (xy 96.573339 -258.015037) (xy 96.853503 -258.015037) (xy 96.853503 -257.963103)
			(xy 96.861628 -257.911808) (xy 96.877676 -257.862415) (xy 96.901254 -257.816141) (xy 96.93178 -257.774125)
			(xy 96.968503 -257.737402) (xy 97.010519 -257.706876) (xy 97.056793 -257.683298) (xy 97.106186 -257.66725)
			(xy 97.157481 -257.659125) (xy 97.209415 -257.659125) (xy 97.26071 -257.66725) (xy 97.310103 -257.683298)
			(xy 97.356377 -257.706876) (xy 97.398393 -257.737402) (xy 97.435116 -257.774125) (xy 97.465642 -257.816141)
			(xy 97.48922 -257.862415) (xy 97.505268 -257.911808) (xy 97.513393 -257.963103) (xy 97.513902 -257.98907)
			(xy 97.513393 -258.015037) (xy 97.793049 -258.015037) (xy 97.793049 -257.963103) (xy 97.801174 -257.911808)
			(xy 97.817222 -257.862415) (xy 97.8408 -257.816141) (xy 97.871326 -257.774125) (xy 97.908049 -257.737402)
			(xy 97.950065 -257.706876) (xy 97.996339 -257.683298) (xy 98.045732 -257.66725) (xy 98.097027 -257.659125)
			(xy 98.148961 -257.659125) (xy 98.200256 -257.66725) (xy 98.249649 -257.683298) (xy 98.295923 -257.706876)
			(xy 98.337939 -257.737402) (xy 98.374662 -257.774125) (xy 98.405188 -257.816141) (xy 98.428766 -257.862415)
			(xy 98.444814 -257.911808) (xy 98.452939 -257.963103) (xy 98.453448 -257.98907) (xy 98.452939 -258.015037)
			(xy 98.733103 -258.015037) (xy 98.733103 -257.963103) (xy 98.741228 -257.911808) (xy 98.757276 -257.862415)
			(xy 98.780854 -257.816141) (xy 98.81138 -257.774125) (xy 98.848103 -257.737402) (xy 98.890119 -257.706876)
			(xy 98.936393 -257.683298) (xy 98.985786 -257.66725) (xy 99.037081 -257.659125) (xy 99.089015 -257.659125)
			(xy 99.14031 -257.66725) (xy 99.189703 -257.683298) (xy 99.235977 -257.706876) (xy 99.277993 -257.737402)
			(xy 99.314716 -257.774125) (xy 99.345242 -257.816141) (xy 99.36882 -257.862415) (xy 99.384868 -257.911808)
			(xy 99.392993 -257.963103) (xy 99.393502 -257.98907) (xy 99.392993 -258.015037) (xy 99.672649 -258.015037)
			(xy 99.672649 -257.963103) (xy 99.680774 -257.911808) (xy 99.696822 -257.862415) (xy 99.7204 -257.816141)
			(xy 99.750926 -257.774125) (xy 99.787649 -257.737402) (xy 99.829665 -257.706876) (xy 99.875939 -257.683298)
			(xy 99.925332 -257.66725) (xy 99.976627 -257.659125) (xy 100.028561 -257.659125) (xy 100.079856 -257.66725)
			(xy 100.129249 -257.683298) (xy 100.175523 -257.706876) (xy 100.217539 -257.737402) (xy 100.254262 -257.774125)
			(xy 100.284788 -257.816141) (xy 100.308366 -257.862415) (xy 100.324414 -257.911808) (xy 100.332539 -257.963103)
			(xy 100.333048 -257.98907) (xy 100.332539 -258.015037) (xy 100.612449 -258.015037) (xy 100.612449 -257.963103)
			(xy 100.620574 -257.911808) (xy 100.636622 -257.862415) (xy 100.6602 -257.816141) (xy 100.690726 -257.774125)
			(xy 100.727449 -257.737402) (xy 100.769465 -257.706876) (xy 100.815739 -257.683298) (xy 100.865132 -257.66725)
			(xy 100.916427 -257.659125) (xy 100.968361 -257.659125) (xy 101.019656 -257.66725) (xy 101.069049 -257.683298)
			(xy 101.115323 -257.706876) (xy 101.157339 -257.737402) (xy 101.194062 -257.774125) (xy 101.224588 -257.816141)
			(xy 101.248166 -257.862415) (xy 101.264214 -257.911808) (xy 101.272339 -257.963103) (xy 101.272848 -257.98907)
			(xy 101.272339 -258.015037) (xy 101.552249 -258.015037) (xy 101.552249 -257.963103) (xy 101.560374 -257.911808)
			(xy 101.576422 -257.862415) (xy 101.6 -257.816141) (xy 101.630526 -257.774125) (xy 101.667249 -257.737402)
			(xy 101.709265 -257.706876) (xy 101.755539 -257.683298) (xy 101.804932 -257.66725) (xy 101.856227 -257.659125)
			(xy 101.908161 -257.659125) (xy 101.959456 -257.66725) (xy 102.008849 -257.683298) (xy 102.055123 -257.706876)
			(xy 102.072044 -257.71917) (xy 103.069615 -257.71917) (xy 103.069615 -257.66723) (xy 103.07774 -257.61593)
			(xy 103.09379 -257.566532) (xy 103.11737 -257.520253) (xy 103.147899 -257.478233) (xy 103.184625 -257.441505)
			(xy 103.226645 -257.410975) (xy 103.272923 -257.387394) (xy 103.32232 -257.371343) (xy 103.37362 -257.363216)
			(xy 103.39959 -257.362706) (xy 103.399844 -257.362706) (xy 103.424372 -257.36313) (xy 103.472886 -257.370399)
			(xy 103.519793 -257.384757) (xy 103.564064 -257.405888) (xy 103.604727 -257.433329) (xy 103.62311 -257.449574)
			(xy 103.634599 -257.459377) (xy 103.661836 -257.472391) (xy 103.69169 -257.476859) (xy 103.721544 -257.472391)
			(xy 103.748781 -257.459377) (xy 103.76027 -257.449574) (xy 103.778664 -257.433303) (xy 103.819372 -257.405838)
			(xy 103.863697 -257.384702) (xy 103.910664 -257.370362) (xy 103.959236 -257.363134) (xy 103.98379 -257.362706)
			(xy 104.008343 -257.363113) (xy 104.056912 -257.37036) (xy 104.103875 -257.384711) (xy 104.148198 -257.405851)
			(xy 104.188907 -257.433313) (xy 104.20731 -257.449574) (xy 104.218799 -257.459377) (xy 104.246036 -257.472391)
			(xy 104.27589 -257.476859) (xy 104.305744 -257.472391) (xy 104.332981 -257.459377) (xy 104.34447 -257.449574)
			(xy 104.362844 -257.433319) (xy 104.403506 -257.405876) (xy 104.447779 -257.384748) (xy 104.49469 -257.370401)
			(xy 104.543208 -257.363151) (xy 104.567736 -257.362706) (xy 104.56799 -257.362706) (xy 104.593957 -257.363268)
			(xy 104.645251 -257.371391) (xy 104.694643 -257.387438) (xy 104.740916 -257.411014) (xy 104.782932 -257.441539)
			(xy 104.819655 -257.478261) (xy 104.850181 -257.520275) (xy 104.873758 -257.566548) (xy 104.889807 -257.615939)
			(xy 104.897931 -257.667233) (xy 104.897931 -257.719167) (xy 104.897931 -257.71917) (xy 105.127015 -257.71917)
			(xy 105.127015 -257.66723) (xy 105.13514 -257.61593) (xy 105.15119 -257.566532) (xy 105.17477 -257.520253)
			(xy 105.205299 -257.478233) (xy 105.242025 -257.441505) (xy 105.284045 -257.410975) (xy 105.330323 -257.387394)
			(xy 105.37972 -257.371343) (xy 105.43102 -257.363216) (xy 105.45699 -257.362706) (xy 105.482744 -257.363196)
			(xy 105.533629 -257.371174) (xy 105.582659 -257.386955) (xy 105.628645 -257.410156) (xy 105.670472 -257.440214)
			(xy 105.689146 -257.457956) (xy 105.698836 -257.466949) (xy 105.721768 -257.480081) (xy 105.747307 -257.486876)
			(xy 105.773733 -257.486876) (xy 105.799272 -257.480081) (xy 105.822204 -257.466949) (xy 105.831894 -257.457956)
			(xy 105.850585 -257.440235) (xy 105.892413 -257.410185) (xy 105.938396 -257.386985) (xy 105.987419 -257.371197)
			(xy 106.038298 -257.363202) (xy 106.06405 -257.362706) (xy 106.090444 -257.363248) (xy 106.142561 -257.37164)
			(xy 106.192679 -257.388217) (xy 106.23952 -257.412557) (xy 106.281892 -257.444041) (xy 106.318715 -257.481865)
			(xy 106.334306 -257.503168) (xy 106.342974 -257.514567) (xy 106.365256 -257.532526) (xy 106.39165 -257.543589)
			(xy 106.420079 -257.546885) (xy 106.448304 -257.542156) (xy 106.474105 -257.529774) (xy 106.495452 -257.510712)
			(xy 106.50347 -257.49885) (xy 106.518791 -257.475697) (xy 106.555877 -257.434388) (xy 106.599342 -257.399853)
			(xy 106.647965 -257.373065) (xy 106.70038 -257.354774) (xy 106.755113 -257.345496) (xy 106.78287 -257.344926)
			(xy 106.806965 -257.345352) (xy 106.854642 -257.352365) (xy 106.900794 -257.366232) (xy 106.944441 -257.386659)
			(xy 106.984656 -257.413212) (xy 107.020586 -257.445327) (xy 107.036362 -257.463544) (xy 107.046278 -257.474598)
			(xy 107.071066 -257.490929) (xy 107.099498 -257.499453) (xy 107.129182 -257.499453) (xy 107.157614 -257.490929)
			(xy 107.182402 -257.474598) (xy 107.192318 -257.463544) (xy 107.208087 -257.44532) (xy 107.244016 -257.413204)
			(xy 107.284232 -257.386652) (xy 107.327881 -257.366228) (xy 107.374035 -257.352367) (xy 107.421715 -257.345363)
			(xy 107.44581 -257.344926) (xy 107.471775 -257.345476) (xy 107.523066 -257.353601) (xy 107.572454 -257.36965)
			(xy 107.618724 -257.393226) (xy 107.660736 -257.423751) (xy 107.697455 -257.460472) (xy 107.727979 -257.502485)
			(xy 107.751554 -257.548755) (xy 107.767601 -257.598144) (xy 107.775725 -257.649435) (xy 107.775725 -257.670808)
			(xy 108.349796 -257.670808) (xy 108.349796 -257.670554) (xy 108.350221 -257.646026) (xy 108.357491 -257.597512)
			(xy 108.371848 -257.550605) (xy 108.392979 -257.506334) (xy 108.420419 -257.465671) (xy 108.436664 -257.447288)
			(xy 108.446461 -257.435793) (xy 108.459477 -257.408558) (xy 108.463947 -257.378706) (xy 108.45948 -257.348853)
			(xy 108.446467 -257.321617) (xy 108.436664 -257.310128) (xy 108.420423 -257.291742) (xy 108.392974 -257.251085)
			(xy 108.371843 -257.206815) (xy 108.357493 -257.159906) (xy 108.350241 -257.11139) (xy 108.349796 -257.086862)
			(xy 108.349796 -257.086608) (xy 108.350305 -257.060641) (xy 108.35843 -257.009346) (xy 108.374478 -256.959953)
			(xy 108.398056 -256.913679) (xy 108.428582 -256.871663) (xy 108.465305 -256.83494) (xy 108.507321 -256.804414)
			(xy 108.553595 -256.780836) (xy 108.602988 -256.764788) (xy 108.654283 -256.756663) (xy 108.706217 -256.756663)
			(xy 108.757512 -256.764788) (xy 108.806905 -256.780836) (xy 108.853179 -256.804414) (xy 108.895195 -256.83494)
			(xy 108.931918 -256.871663) (xy 108.962444 -256.913679) (xy 108.986022 -256.959953) (xy 109.00207 -257.009346)
			(xy 109.010195 -257.060641) (xy 109.010704 -257.086608) (xy 109.010704 -257.086862) (xy 109.010228 -257.111388)
			(xy 109.002971 -257.159899) (xy 108.990255 -257.201475) (xy 109.540803 -257.201475) (xy 109.540803 -257.149541)
			(xy 109.548928 -257.098246) (xy 109.564976 -257.048853) (xy 109.588554 -257.002579) (xy 109.61908 -256.960563)
			(xy 109.655803 -256.92384) (xy 109.697819 -256.893314) (xy 109.744093 -256.869736) (xy 109.793486 -256.853688)
			(xy 109.844781 -256.845563) (xy 109.896715 -256.845563) (xy 109.94801 -256.853688) (xy 109.997403 -256.869736)
			(xy 110.043677 -256.893314) (xy 110.085693 -256.92384) (xy 110.122416 -256.960563) (xy 110.152942 -257.002579)
			(xy 110.17652 -257.048853) (xy 110.192568 -257.098246) (xy 110.200693 -257.149541) (xy 110.201202 -257.175508)
			(xy 110.200693 -257.201475) (xy 110.480857 -257.201475) (xy 110.480857 -257.149541) (xy 110.488982 -257.098246)
			(xy 110.50503 -257.048853) (xy 110.528608 -257.002579) (xy 110.559134 -256.960563) (xy 110.595857 -256.92384)
			(xy 110.637873 -256.893314) (xy 110.684147 -256.869736) (xy 110.73354 -256.853688) (xy 110.784835 -256.845563)
			(xy 110.836769 -256.845563) (xy 110.888064 -256.853688) (xy 110.937457 -256.869736) (xy 110.983731 -256.893314)
			(xy 111.025747 -256.92384) (xy 111.06247 -256.960563) (xy 111.092996 -257.002579) (xy 111.116574 -257.048853)
			(xy 111.132622 -257.098246) (xy 111.140747 -257.149541) (xy 111.141256 -257.175508) (xy 111.140747 -257.201475)
			(xy 111.420403 -257.201475) (xy 111.420403 -257.149541) (xy 111.428528 -257.098246) (xy 111.444576 -257.048853)
			(xy 111.468154 -257.002579) (xy 111.49868 -256.960563) (xy 111.535403 -256.92384) (xy 111.577419 -256.893314)
			(xy 111.623693 -256.869736) (xy 111.673086 -256.853688) (xy 111.724381 -256.845563) (xy 111.776315 -256.845563)
			(xy 111.82761 -256.853688) (xy 111.877003 -256.869736) (xy 111.923277 -256.893314) (xy 111.965293 -256.92384)
			(xy 112.002016 -256.960563) (xy 112.032542 -257.002579) (xy 112.05612 -257.048853) (xy 112.072168 -257.098246)
			(xy 112.080293 -257.149541) (xy 112.080802 -257.175508) (xy 112.080293 -257.201475) (xy 112.360203 -257.201475)
			(xy 112.360203 -257.149541) (xy 112.368328 -257.098246) (xy 112.384376 -257.048853) (xy 112.407954 -257.002579)
			(xy 112.43848 -256.960563) (xy 112.475203 -256.92384) (xy 112.517219 -256.893314) (xy 112.563493 -256.869736)
			(xy 112.612886 -256.853688) (xy 112.664181 -256.845563) (xy 112.716115 -256.845563) (xy 112.76741 -256.853688)
			(xy 112.816803 -256.869736) (xy 112.863077 -256.893314) (xy 112.905093 -256.92384) (xy 112.941816 -256.960563)
			(xy 112.972342 -257.002579) (xy 112.99592 -257.048853) (xy 113.011968 -257.098246) (xy 113.020093 -257.149541)
			(xy 113.020602 -257.175508) (xy 113.020093 -257.201475) (xy 113.300003 -257.201475) (xy 113.300003 -257.149541)
			(xy 113.308128 -257.098246) (xy 113.324176 -257.048853) (xy 113.347754 -257.002579) (xy 113.37828 -256.960563)
			(xy 113.415003 -256.92384) (xy 113.457019 -256.893314) (xy 113.503293 -256.869736) (xy 113.552686 -256.853688)
			(xy 113.603981 -256.845563) (xy 113.655915 -256.845563) (xy 113.70721 -256.853688) (xy 113.756603 -256.869736)
			(xy 113.802877 -256.893314) (xy 113.844893 -256.92384) (xy 113.881616 -256.960563) (xy 113.912142 -257.002579)
			(xy 113.93572 -257.048853) (xy 113.951768 -257.098246) (xy 113.959893 -257.149541) (xy 113.960402 -257.175508)
			(xy 113.959893 -257.201471) (xy 114.239737 -257.201471) (xy 114.239737 -257.149529) (xy 114.247863 -257.098226)
			(xy 114.263916 -257.048827) (xy 114.287499 -257.002547) (xy 114.318032 -256.960527) (xy 114.354764 -256.923801)
			(xy 114.396788 -256.893274) (xy 114.443071 -256.869697) (xy 114.492473 -256.853652) (xy 114.543777 -256.845533)
			(xy 114.569748 -256.845054) (xy 114.596121 -256.845589) (xy 114.648198 -256.853961) (xy 114.698284 -256.870499)
			(xy 114.745106 -256.894784) (xy 114.766598 -256.910078) (xy 114.779468 -256.918919) (xy 114.808972 -256.929087)
			(xy 114.840169 -256.929869) (xy 114.870145 -256.921193) (xy 114.8961 -256.903867) (xy 114.906298 -256.892044)
			(xy 114.922136 -256.873047) (xy 114.958438 -256.839462) (xy 114.99934 -256.811662) (xy 115.043928 -256.790268)
			(xy 115.091206 -256.775756) (xy 115.115594 -256.771648) (xy 115.128943 -256.76925) (xy 115.153754 -256.758316)
			(xy 115.174815 -256.741241) (xy 115.190645 -256.719228) (xy 115.200129 -256.693827) (xy 115.202599 -256.666826)
			(xy 115.197881 -256.640126) (xy 115.186308 -256.615607) (xy 115.177824 -256.605024) (xy 115.162897 -256.586946)
			(xy 115.137695 -256.547416) (xy 115.118325 -256.504726) (xy 115.105173 -256.459728) (xy 115.098503 -256.413325)
			(xy 115.098068 -256.389886) (xy 115.098068 -256.389632) (xy 115.098547 -256.365107) (xy 115.105805 -256.316595)
			(xy 115.12015 -256.269689) (xy 115.141269 -256.225417) (xy 115.168697 -256.184751) (xy 115.184936 -256.166366)
			(xy 115.194756 -256.154889) (xy 115.207774 -256.127648) (xy 115.212241 -256.09779) (xy 115.207768 -256.067932)
			(xy 115.194745 -256.040694) (xy 115.184936 -256.029206) (xy 115.16868 -256.010833) (xy 115.141234 -255.970172)
			(xy 115.120106 -255.925899) (xy 115.10576 -255.878987) (xy 115.098511 -255.830468) (xy 115.098068 -255.80594)
			(xy 115.098068 -255.805686) (xy 115.098577 -255.779719) (xy 115.106702 -255.728424) (xy 115.12275 -255.679031)
			(xy 115.146328 -255.632757) (xy 115.176854 -255.590741) (xy 115.213577 -255.554018) (xy 115.255593 -255.523492)
			(xy 115.301867 -255.499914) (xy 115.35126 -255.483866) (xy 115.402555 -255.475741) (xy 115.454489 -255.475741)
			(xy 115.505784 -255.483866) (xy 115.555177 -255.499914) (xy 115.601451 -255.523492) (xy 115.61124 -255.530604)
			(xy 120.645936 -255.530604) (xy 120.645936 -255.53035) (xy 120.646374 -255.505823) (xy 120.653643 -255.45731)
			(xy 120.667999 -255.410404) (xy 120.689126 -255.366132) (xy 120.716562 -255.325468) (xy 120.732804 -255.307084)
			(xy 120.742601 -255.295591) (xy 120.755612 -255.268355) (xy 120.760079 -255.238503) (xy 120.755613 -255.208651)
			(xy 120.742604 -255.181414) (xy 120.732804 -255.169924) (xy 120.716551 -255.151548) (xy 120.689106 -255.110888)
			(xy 120.667978 -255.066615) (xy 120.653631 -255.019704) (xy 120.646381 -254.971186) (xy 120.645936 -254.946658)
			(xy 120.645936 -254.946404) (xy 120.646459 -254.920437) (xy 120.654582 -254.869143) (xy 120.67063 -254.819752)
			(xy 120.694206 -254.773479) (xy 120.724731 -254.731463) (xy 120.761452 -254.69474) (xy 120.803467 -254.664213)
			(xy 120.849739 -254.640635) (xy 120.89913 -254.624586) (xy 120.950423 -254.61646) (xy 120.97639 -254.61595)
			(xy 120.976644 -254.61595) (xy 121.000502 -254.616355) (xy 121.047718 -254.623244) (xy 121.093455 -254.636844)
			(xy 121.136765 -254.656873) (xy 121.156984 -254.669544) (xy 121.17003 -254.677435) (xy 121.199343 -254.685783)
			(xy 121.229814 -254.685127) (xy 121.25874 -254.675525) (xy 121.283554 -254.657828) (xy 121.302055 -254.633608)
			(xy 121.30786 -254.619506) (xy 121.317012 -254.596047) (xy 121.341353 -254.55197) (xy 121.372099 -254.512096)
			(xy 121.40854 -254.477349) (xy 121.449831 -254.448533) (xy 121.495017 -254.426316) (xy 121.54305 -254.411212)
			(xy 121.592818 -254.403572) (xy 121.617994 -254.403098) (xy 121.64396 -254.403676) (xy 121.695252 -254.411799)
			(xy 121.744642 -254.427846) (xy 121.790914 -254.451422) (xy 121.832928 -254.481946) (xy 121.86965 -254.518667)
			(xy 121.900175 -254.560681) (xy 121.923751 -254.606952) (xy 121.939799 -254.656342) (xy 121.947923 -254.707634)
			(xy 121.947923 -254.759519) (xy 122.227849 -254.759519) (xy 122.227849 -254.707585) (xy 122.235974 -254.65629)
			(xy 122.252022 -254.606897) (xy 122.2756 -254.560623) (xy 122.306126 -254.518607) (xy 122.342849 -254.481884)
			(xy 122.384865 -254.451358) (xy 122.431139 -254.42778) (xy 122.480532 -254.411732) (xy 122.531827 -254.403607)
			(xy 122.583761 -254.403607) (xy 122.635056 -254.411732) (xy 122.684449 -254.42778) (xy 122.730723 -254.451358)
			(xy 122.772739 -254.481884) (xy 122.809462 -254.518607) (xy 122.839988 -254.560623) (xy 122.863566 -254.606897)
			(xy 122.879614 -254.65629) (xy 122.887739 -254.707585) (xy 122.888248 -254.733552) (xy 122.887739 -254.759519)
			(xy 123.167649 -254.759519) (xy 123.167649 -254.707585) (xy 123.175774 -254.65629) (xy 123.191822 -254.606897)
			(xy 123.2154 -254.560623) (xy 123.245926 -254.518607) (xy 123.282649 -254.481884) (xy 123.324665 -254.451358)
			(xy 123.370939 -254.42778) (xy 123.420332 -254.411732) (xy 123.471627 -254.403607) (xy 123.523561 -254.403607)
			(xy 123.574856 -254.411732) (xy 123.624249 -254.42778) (xy 123.670523 -254.451358) (xy 123.712539 -254.481884)
			(xy 123.749262 -254.518607) (xy 123.779788 -254.560623) (xy 123.803366 -254.606897) (xy 123.819414 -254.65629)
			(xy 123.827539 -254.707585) (xy 123.828048 -254.733552) (xy 123.827539 -254.759519) (xy 124.107703 -254.759519)
			(xy 124.107703 -254.707585) (xy 124.115828 -254.65629) (xy 124.131876 -254.606897) (xy 124.155454 -254.560623)
			(xy 124.18598 -254.518607) (xy 124.222703 -254.481884) (xy 124.264719 -254.451358) (xy 124.310993 -254.42778)
			(xy 124.360386 -254.411732) (xy 124.411681 -254.403607) (xy 124.463615 -254.403607) (xy 124.51491 -254.411732)
			(xy 124.564303 -254.42778) (xy 124.610577 -254.451358) (xy 124.652593 -254.481884) (xy 124.689316 -254.518607)
			(xy 124.719842 -254.560623) (xy 124.74342 -254.606897) (xy 124.759468 -254.65629) (xy 124.767593 -254.707585)
			(xy 124.768102 -254.733552) (xy 124.767593 -254.759519) (xy 125.047249 -254.759519) (xy 125.047249 -254.707585)
			(xy 125.055374 -254.65629) (xy 125.071422 -254.606897) (xy 125.095 -254.560623) (xy 125.125526 -254.518607)
			(xy 125.162249 -254.481884) (xy 125.204265 -254.451358) (xy 125.250539 -254.42778) (xy 125.299932 -254.411732)
			(xy 125.351227 -254.403607) (xy 125.403161 -254.403607) (xy 125.454456 -254.411732) (xy 125.503849 -254.42778)
			(xy 125.550123 -254.451358) (xy 125.592139 -254.481884) (xy 125.628862 -254.518607) (xy 125.659388 -254.560623)
			(xy 125.682966 -254.606897) (xy 125.699014 -254.65629) (xy 125.707139 -254.707585) (xy 125.707648 -254.733552)
			(xy 125.707139 -254.759519) (xy 125.987303 -254.759519) (xy 125.987303 -254.707585) (xy 125.995428 -254.65629)
			(xy 126.011476 -254.606897) (xy 126.035054 -254.560623) (xy 126.06558 -254.518607) (xy 126.102303 -254.481884)
			(xy 126.144319 -254.451358) (xy 126.190593 -254.42778) (xy 126.239986 -254.411732) (xy 126.291281 -254.403607)
			(xy 126.343215 -254.403607) (xy 126.39451 -254.411732) (xy 126.443903 -254.42778) (xy 126.490177 -254.451358)
			(xy 126.532193 -254.481884) (xy 126.568916 -254.518607) (xy 126.599442 -254.560623) (xy 126.62302 -254.606897)
			(xy 126.639068 -254.65629) (xy 126.647193 -254.707585) (xy 126.647702 -254.733552) (xy 126.647193 -254.759519)
			(xy 126.639068 -254.810814) (xy 126.62302 -254.860207) (xy 126.599442 -254.906481) (xy 126.568916 -254.948497)
			(xy 126.532193 -254.98522) (xy 126.490177 -255.015746) (xy 126.443903 -255.039324) (xy 126.39451 -255.055372)
			(xy 126.343215 -255.063497) (xy 126.291281 -255.063497) (xy 126.239986 -255.055372) (xy 126.190593 -255.039324)
			(xy 126.144319 -255.015746) (xy 126.102303 -254.98522) (xy 126.06558 -254.948497) (xy 126.035054 -254.906481)
			(xy 126.011476 -254.860207) (xy 125.995428 -254.810814) (xy 125.987303 -254.759519) (xy 125.707139 -254.759519)
			(xy 125.699014 -254.810814) (xy 125.682966 -254.860207) (xy 125.659388 -254.906481) (xy 125.628862 -254.948497)
			(xy 125.592139 -254.98522) (xy 125.550123 -255.015746) (xy 125.503849 -255.039324) (xy 125.454456 -255.055372)
			(xy 125.403161 -255.063497) (xy 125.351227 -255.063497) (xy 125.299932 -255.055372) (xy 125.250539 -255.039324)
			(xy 125.204265 -255.015746) (xy 125.162249 -254.98522) (xy 125.125526 -254.948497) (xy 125.095 -254.906481)
			(xy 125.071422 -254.860207) (xy 125.055374 -254.810814) (xy 125.047249 -254.759519) (xy 124.767593 -254.759519)
			(xy 124.759468 -254.810814) (xy 124.74342 -254.860207) (xy 124.719842 -254.906481) (xy 124.689316 -254.948497)
			(xy 124.652593 -254.98522) (xy 124.610577 -255.015746) (xy 124.564303 -255.039324) (xy 124.51491 -255.055372)
			(xy 124.463615 -255.063497) (xy 124.411681 -255.063497) (xy 124.360386 -255.055372) (xy 124.310993 -255.039324)
			(xy 124.264719 -255.015746) (xy 124.222703 -254.98522) (xy 124.18598 -254.948497) (xy 124.155454 -254.906481)
			(xy 124.131876 -254.860207) (xy 124.115828 -254.810814) (xy 124.107703 -254.759519) (xy 123.827539 -254.759519)
			(xy 123.819414 -254.810814) (xy 123.803366 -254.860207) (xy 123.779788 -254.906481) (xy 123.749262 -254.948497)
			(xy 123.712539 -254.98522) (xy 123.670523 -255.015746) (xy 123.624249 -255.039324) (xy 123.574856 -255.055372)
			(xy 123.523561 -255.063497) (xy 123.471627 -255.063497) (xy 123.420332 -255.055372) (xy 123.370939 -255.039324)
			(xy 123.324665 -255.015746) (xy 123.282649 -254.98522) (xy 123.245926 -254.948497) (xy 123.2154 -254.906481)
			(xy 123.191822 -254.860207) (xy 123.175774 -254.810814) (xy 123.167649 -254.759519) (xy 122.887739 -254.759519)
			(xy 122.879614 -254.810814) (xy 122.863566 -254.860207) (xy 122.839988 -254.906481) (xy 122.809462 -254.948497)
			(xy 122.772739 -254.98522) (xy 122.730723 -255.015746) (xy 122.684449 -255.039324) (xy 122.635056 -255.055372)
			(xy 122.583761 -255.063497) (xy 122.531827 -255.063497) (xy 122.480532 -255.055372) (xy 122.431139 -255.039324)
			(xy 122.384865 -255.015746) (xy 122.342849 -254.98522) (xy 122.306126 -254.948497) (xy 122.2756 -254.906481)
			(xy 122.252022 -254.860207) (xy 122.235974 -254.810814) (xy 122.227849 -254.759519) (xy 121.947923 -254.759519)
			(xy 121.947923 -254.759566) (xy 121.939799 -254.810858) (xy 121.923751 -254.860248) (xy 121.900175 -254.906519)
			(xy 121.86965 -254.948533) (xy 121.832928 -254.985254) (xy 121.790914 -255.015778) (xy 121.744642 -255.039354)
			(xy 121.695252 -255.055401) (xy 121.64396 -255.063524) (xy 121.617994 -255.064006) (xy 121.61774 -255.064006)
			(xy 121.593884 -255.063552) (xy 121.54667 -255.056676) (xy 121.500933 -255.04309) (xy 121.457622 -255.023076)
			(xy 121.4374 -255.010412) (xy 121.424288 -255.002643) (xy 121.395001 -254.994287) (xy 121.364553 -254.994926)
			(xy 121.335643 -255.004505) (xy 121.310836 -255.022173) (xy 121.292334 -255.046363) (xy 121.286524 -255.06045)
			(xy 121.278805 -255.080516) (xy 121.258914 -255.118631) (xy 121.23424 -255.153838) (xy 121.219976 -255.169924)
			(xy 121.210172 -255.181412) (xy 121.197165 -255.20865) (xy 121.1927 -255.238503) (xy 121.197167 -255.268355)
			(xy 121.210176 -255.295593) (xy 121.219976 -255.307084) (xy 121.236229 -255.325459) (xy 121.263675 -255.36612)
			(xy 121.284803 -255.410393) (xy 121.29915 -255.457304) (xy 121.3064 -255.505822) (xy 121.306844 -255.53035)
			(xy 121.306844 -255.530604) (xy 121.306335 -255.556571) (xy 121.303639 -255.573589) (xy 122.698003 -255.573589)
			(xy 122.698003 -255.521655) (xy 122.706128 -255.47036) (xy 122.722176 -255.420967) (xy 122.745754 -255.374693)
			(xy 122.77628 -255.332677) (xy 122.813003 -255.295954) (xy 122.855019 -255.265428) (xy 122.901293 -255.24185)
			(xy 122.950686 -255.225802) (xy 123.001981 -255.217677) (xy 123.053915 -255.217677) (xy 123.10521 -255.225802)
			(xy 123.154603 -255.24185) (xy 123.200877 -255.265428) (xy 123.242893 -255.295954) (xy 123.279616 -255.332677)
			(xy 123.310142 -255.374693) (xy 123.33372 -255.420967) (xy 123.349768 -255.47036) (xy 123.357893 -255.521655)
			(xy 123.358402 -255.547622) (xy 123.357893 -255.573589) (xy 123.637803 -255.573589) (xy 123.637803 -255.521655)
			(xy 123.645928 -255.47036) (xy 123.661976 -255.420967) (xy 123.685554 -255.374693) (xy 123.71608 -255.332677)
			(xy 123.752803 -255.295954) (xy 123.794819 -255.265428) (xy 123.841093 -255.24185) (xy 123.890486 -255.225802)
			(xy 123.941781 -255.217677) (xy 123.993715 -255.217677) (xy 124.04501 -255.225802) (xy 124.094403 -255.24185)
			(xy 124.140677 -255.265428) (xy 124.182693 -255.295954) (xy 124.219416 -255.332677) (xy 124.249942 -255.374693)
			(xy 124.27352 -255.420967) (xy 124.289568 -255.47036) (xy 124.297693 -255.521655) (xy 124.298202 -255.547622)
			(xy 124.297693 -255.573589) (xy 124.577349 -255.573589) (xy 124.577349 -255.521655) (xy 124.585474 -255.47036)
			(xy 124.601522 -255.420967) (xy 124.6251 -255.374693) (xy 124.655626 -255.332677) (xy 124.692349 -255.295954)
			(xy 124.734365 -255.265428) (xy 124.780639 -255.24185) (xy 124.830032 -255.225802) (xy 124.881327 -255.217677)
			(xy 124.933261 -255.217677) (xy 124.984556 -255.225802) (xy 125.033949 -255.24185) (xy 125.080223 -255.265428)
			(xy 125.122239 -255.295954) (xy 125.158962 -255.332677) (xy 125.189488 -255.374693) (xy 125.213066 -255.420967)
			(xy 125.229114 -255.47036) (xy 125.237239 -255.521655) (xy 125.237748 -255.547622) (xy 125.237239 -255.573589)
			(xy 125.517403 -255.573589) (xy 125.517403 -255.521655) (xy 125.525528 -255.47036) (xy 125.541576 -255.420967)
			(xy 125.565154 -255.374693) (xy 125.59568 -255.332677) (xy 125.632403 -255.295954) (xy 125.674419 -255.265428)
			(xy 125.720693 -255.24185) (xy 125.770086 -255.225802) (xy 125.821381 -255.217677) (xy 125.873315 -255.217677)
			(xy 125.92461 -255.225802) (xy 125.974003 -255.24185) (xy 126.020277 -255.265428) (xy 126.062293 -255.295954)
			(xy 126.099016 -255.332677) (xy 126.129542 -255.374693) (xy 126.15312 -255.420967) (xy 126.169168 -255.47036)
			(xy 126.177293 -255.521655) (xy 126.177802 -255.547622) (xy 126.177293 -255.573589) (xy 126.169168 -255.624884)
			(xy 126.15312 -255.674277) (xy 126.129542 -255.720551) (xy 126.099016 -255.762567) (xy 126.062293 -255.79929)
			(xy 126.020277 -255.829816) (xy 125.974003 -255.853394) (xy 125.92461 -255.869442) (xy 125.873315 -255.877567)
			(xy 125.821381 -255.877567) (xy 125.770086 -255.869442) (xy 125.720693 -255.853394) (xy 125.674419 -255.829816)
			(xy 125.632403 -255.79929) (xy 125.59568 -255.762567) (xy 125.565154 -255.720551) (xy 125.541576 -255.674277)
			(xy 125.525528 -255.624884) (xy 125.517403 -255.573589) (xy 125.237239 -255.573589) (xy 125.229114 -255.624884)
			(xy 125.213066 -255.674277) (xy 125.189488 -255.720551) (xy 125.158962 -255.762567) (xy 125.122239 -255.79929)
			(xy 125.080223 -255.829816) (xy 125.033949 -255.853394) (xy 124.984556 -255.869442) (xy 124.933261 -255.877567)
			(xy 124.881327 -255.877567) (xy 124.830032 -255.869442) (xy 124.780639 -255.853394) (xy 124.734365 -255.829816)
			(xy 124.692349 -255.79929) (xy 124.655626 -255.762567) (xy 124.6251 -255.720551) (xy 124.601522 -255.674277)
			(xy 124.585474 -255.624884) (xy 124.577349 -255.573589) (xy 124.297693 -255.573589) (xy 124.289568 -255.624884)
			(xy 124.27352 -255.674277) (xy 124.249942 -255.720551) (xy 124.219416 -255.762567) (xy 124.182693 -255.79929)
			(xy 124.140677 -255.829816) (xy 124.094403 -255.853394) (xy 124.04501 -255.869442) (xy 123.993715 -255.877567)
			(xy 123.941781 -255.877567) (xy 123.890486 -255.869442) (xy 123.841093 -255.853394) (xy 123.794819 -255.829816)
			(xy 123.752803 -255.79929) (xy 123.71608 -255.762567) (xy 123.685554 -255.720551) (xy 123.661976 -255.674277)
			(xy 123.645928 -255.624884) (xy 123.637803 -255.573589) (xy 123.357893 -255.573589) (xy 123.349768 -255.624884)
			(xy 123.33372 -255.674277) (xy 123.310142 -255.720551) (xy 123.279616 -255.762567) (xy 123.242893 -255.79929)
			(xy 123.200877 -255.829816) (xy 123.154603 -255.853394) (xy 123.10521 -255.869442) (xy 123.053915 -255.877567)
			(xy 123.001981 -255.877567) (xy 122.950686 -255.869442) (xy 122.901293 -255.853394) (xy 122.855019 -255.829816)
			(xy 122.813003 -255.79929) (xy 122.77628 -255.762567) (xy 122.745754 -255.720551) (xy 122.722176 -255.674277)
			(xy 122.706128 -255.624884) (xy 122.698003 -255.573589) (xy 121.303639 -255.573589) (xy 121.29821 -255.607866)
			(xy 121.282162 -255.657259) (xy 121.258584 -255.703533) (xy 121.228058 -255.745549) (xy 121.191335 -255.782272)
			(xy 121.149319 -255.812798) (xy 121.103045 -255.836376) (xy 121.053652 -255.852424) (xy 121.002357 -255.860549)
			(xy 120.950423 -255.860549) (xy 120.899128 -255.852424) (xy 120.849735 -255.836376) (xy 120.803461 -255.812798)
			(xy 120.761445 -255.782272) (xy 120.724722 -255.745549) (xy 120.694196 -255.703533) (xy 120.670618 -255.657259)
			(xy 120.65457 -255.607866) (xy 120.646445 -255.556571) (xy 120.645936 -255.530604) (xy 115.61124 -255.530604)
			(xy 115.643467 -255.554018) (xy 115.68019 -255.590741) (xy 115.710716 -255.632757) (xy 115.734294 -255.679031)
			(xy 115.750342 -255.728424) (xy 115.758467 -255.779719) (xy 115.758976 -255.805686) (xy 115.758976 -255.80594)
			(xy 115.758529 -255.830467) (xy 115.751262 -255.878979) (xy 115.736908 -255.925885) (xy 115.715783 -255.970157)
			(xy 115.688349 -256.010822) (xy 115.672108 -256.029206) (xy 115.66232 -256.040706) (xy 115.649307 -256.06794)
			(xy 115.644836 -256.09779) (xy 115.6493 -256.12764) (xy 115.662308 -256.154876) (xy 115.672108 -256.166366)
			(xy 115.688358 -256.184744) (xy 115.715803 -256.225404) (xy 115.736932 -256.269677) (xy 115.751279 -256.316587)
			(xy 115.758531 -256.365104) (xy 115.758976 -256.389632) (xy 115.758976 -256.389886) (xy 115.758504 -256.416025)
			(xy 115.750289 -256.467653) (xy 115.734047 -256.517343) (xy 115.710182 -256.563856) (xy 115.67929 -256.606029)
			(xy 115.642142 -256.642812) (xy 115.599665 -256.673286) (xy 115.552919 -256.69669) (xy 115.50307 -256.712441)
			(xy 115.47729 -256.716784) (xy 115.463965 -256.719281) (xy 115.439169 -256.730208) (xy 115.418118 -256.74727)
			(xy 115.402294 -256.769266) (xy 115.392809 -256.794648) (xy 115.390331 -256.821631) (xy 115.395034 -256.848317)
			(xy 115.406587 -256.872827) (xy 115.41506 -256.883408) (xy 115.430015 -256.901463) (xy 115.45521 -256.941001)
			(xy 115.474574 -256.983697) (xy 115.487719 -257.028699) (xy 115.494384 -257.075105) (xy 115.494816 -257.098546)
			(xy 115.494816 -257.0988) (xy 115.49436 -257.123326) (xy 115.487098 -257.171839) (xy 115.472747 -257.218746)
			(xy 115.451623 -257.263018) (xy 115.438004 -257.283204) (xy 120.645936 -257.283204) (xy 120.646466 -257.256805)
			(xy 120.654867 -257.204678) (xy 120.67144 -257.154547) (xy 120.695763 -257.107685) (xy 120.727221 -257.06528)
			(xy 120.745758 -257.046476) (xy 120.755065 -257.036749) (xy 120.768745 -257.013578) (xy 120.775884 -256.987634)
			(xy 120.775985 -256.960726) (xy 120.769041 -256.934729) (xy 120.755536 -256.911455) (xy 120.746266 -256.901696)
			(xy 120.728055 -256.882974) (xy 120.697221 -256.840818) (xy 120.673399 -256.794339) (xy 120.657181 -256.744693)
			(xy 120.648969 -256.693114) (xy 120.648476 -256.667) (xy 120.648929 -256.641029) (xy 120.657055 -256.589727)
			(xy 120.673107 -256.540328) (xy 120.696689 -256.494048) (xy 120.727221 -256.452028) (xy 120.763951 -256.415301)
			(xy 120.805974 -256.384773) (xy 120.852256 -256.361195) (xy 120.901656 -256.345148) (xy 120.952959 -256.337027)
			(xy 120.97893 -256.336546) (xy 121.007325 -256.337155) (xy 121.063279 -256.346857) (xy 121.116748 -256.365988)
			(xy 121.141744 -256.379472) (xy 121.15412 -256.385973) (xy 121.181255 -256.392649) (xy 121.209183 -256.391703)
			(xy 121.235803 -256.383205) (xy 121.259115 -256.367796) (xy 121.277363 -256.346633) (xy 121.289177 -256.32131)
			(xy 121.291858 -256.30759) (xy 121.296638 -256.282184) (xy 121.312914 -256.233121) (xy 121.336629 -256.18719)
			(xy 121.367202 -256.145509) (xy 121.40389 -256.109094) (xy 121.445799 -256.078833) (xy 121.491906 -256.055462)
			(xy 121.541089 -256.039553) (xy 121.592148 -256.031492) (xy 121.617994 -256.030984) (xy 121.643967 -256.031391)
			(xy 121.695272 -256.039516) (xy 121.744675 -256.055567) (xy 121.790959 -256.079149) (xy 121.832984 -256.109681)
			(xy 121.869715 -256.146411) (xy 121.900248 -256.188436) (xy 121.923831 -256.234719) (xy 121.939883 -256.284122)
			(xy 121.948009 -256.335427) (xy 121.948009 -256.387373) (xy 121.948004 -256.387405) (xy 122.228103 -256.387405)
			(xy 122.228103 -256.335471) (xy 122.236228 -256.284176) (xy 122.252276 -256.234783) (xy 122.275854 -256.188509)
			(xy 122.30638 -256.146493) (xy 122.343103 -256.10977) (xy 122.385119 -256.079244) (xy 122.431393 -256.055666)
			(xy 122.480786 -256.039618) (xy 122.532081 -256.031493) (xy 122.584015 -256.031493) (xy 122.63531 -256.039618)
			(xy 122.684703 -256.055666) (xy 122.730977 -256.079244) (xy 122.772993 -256.10977) (xy 122.809716 -256.146493)
			(xy 122.840242 -256.188509) (xy 122.86382 -256.234783) (xy 122.879868 -256.284176) (xy 122.887993 -256.335471)
			(xy 122.888502 -256.361438) (xy 122.887993 -256.387405) (xy 123.167649 -256.387405) (xy 123.167649 -256.335471)
			(xy 123.175774 -256.284176) (xy 123.191822 -256.234783) (xy 123.2154 -256.188509) (xy 123.245926 -256.146493)
			(xy 123.282649 -256.10977) (xy 123.324665 -256.079244) (xy 123.370939 -256.055666) (xy 123.420332 -256.039618)
			(xy 123.471627 -256.031493) (xy 123.523561 -256.031493) (xy 123.574856 -256.039618) (xy 123.624249 -256.055666)
			(xy 123.670523 -256.079244) (xy 123.712539 -256.10977) (xy 123.749262 -256.146493) (xy 123.779788 -256.188509)
			(xy 123.803366 -256.234783) (xy 123.819414 -256.284176) (xy 123.827539 -256.335471) (xy 123.828048 -256.361438)
			(xy 123.827539 -256.387405) (xy 124.107449 -256.387405) (xy 124.107449 -256.335471) (xy 124.115574 -256.284176)
			(xy 124.131622 -256.234783) (xy 124.1552 -256.188509) (xy 124.185726 -256.146493) (xy 124.222449 -256.10977)
			(xy 124.264465 -256.079244) (xy 124.310739 -256.055666) (xy 124.360132 -256.039618) (xy 124.411427 -256.031493)
			(xy 124.463361 -256.031493) (xy 124.514656 -256.039618) (xy 124.564049 -256.055666) (xy 124.610323 -256.079244)
			(xy 124.652339 -256.10977) (xy 124.689062 -256.146493) (xy 124.719588 -256.188509) (xy 124.743166 -256.234783)
			(xy 124.759214 -256.284176) (xy 124.767339 -256.335471) (xy 124.767848 -256.361438) (xy 124.767339 -256.387405)
			(xy 125.047249 -256.387405) (xy 125.047249 -256.335471) (xy 125.055374 -256.284176) (xy 125.071422 -256.234783)
			(xy 125.095 -256.188509) (xy 125.125526 -256.146493) (xy 125.162249 -256.10977) (xy 125.204265 -256.079244)
			(xy 125.250539 -256.055666) (xy 125.299932 -256.039618) (xy 125.351227 -256.031493) (xy 125.403161 -256.031493)
			(xy 125.454456 -256.039618) (xy 125.503849 -256.055666) (xy 125.550123 -256.079244) (xy 125.592139 -256.10977)
			(xy 125.628862 -256.146493) (xy 125.659388 -256.188509) (xy 125.682966 -256.234783) (xy 125.699014 -256.284176)
			(xy 125.707139 -256.335471) (xy 125.707648 -256.361438) (xy 125.707139 -256.387405) (xy 125.987049 -256.387405)
			(xy 125.987049 -256.335471) (xy 125.995174 -256.284176) (xy 126.011222 -256.234783) (xy 126.0348 -256.188509)
			(xy 126.065326 -256.146493) (xy 126.102049 -256.10977) (xy 126.144065 -256.079244) (xy 126.190339 -256.055666)
			(xy 126.239732 -256.039618) (xy 126.291027 -256.031493) (xy 126.342961 -256.031493) (xy 126.394256 -256.039618)
			(xy 126.443649 -256.055666) (xy 126.489923 -256.079244) (xy 126.531939 -256.10977) (xy 126.568662 -256.146493)
			(xy 126.599188 -256.188509) (xy 126.622766 -256.234783) (xy 126.638814 -256.284176) (xy 126.646939 -256.335471)
			(xy 126.647448 -256.361438) (xy 126.646939 -256.387405) (xy 126.638814 -256.4387) (xy 126.622766 -256.488093)
			(xy 126.599188 -256.534367) (xy 126.568662 -256.576383) (xy 126.531939 -256.613106) (xy 126.489923 -256.643632)
			(xy 126.443649 -256.66721) (xy 126.394256 -256.683258) (xy 126.342961 -256.691383) (xy 126.291027 -256.691383)
			(xy 126.239732 -256.683258) (xy 126.190339 -256.66721) (xy 126.144065 -256.643632) (xy 126.102049 -256.613106)
			(xy 126.065326 -256.576383) (xy 126.0348 -256.534367) (xy 126.011222 -256.488093) (xy 125.995174 -256.4387)
			(xy 125.987049 -256.387405) (xy 125.707139 -256.387405) (xy 125.699014 -256.4387) (xy 125.682966 -256.488093)
			(xy 125.659388 -256.534367) (xy 125.628862 -256.576383) (xy 125.592139 -256.613106) (xy 125.550123 -256.643632)
			(xy 125.503849 -256.66721) (xy 125.454456 -256.683258) (xy 125.403161 -256.691383) (xy 125.351227 -256.691383)
			(xy 125.299932 -256.683258) (xy 125.250539 -256.66721) (xy 125.204265 -256.643632) (xy 125.162249 -256.613106)
			(xy 125.125526 -256.576383) (xy 125.095 -256.534367) (xy 125.071422 -256.488093) (xy 125.055374 -256.4387)
			(xy 125.047249 -256.387405) (xy 124.767339 -256.387405) (xy 124.759214 -256.4387) (xy 124.743166 -256.488093)
			(xy 124.719588 -256.534367) (xy 124.689062 -256.576383) (xy 124.652339 -256.613106) (xy 124.610323 -256.643632)
			(xy 124.564049 -256.66721) (xy 124.514656 -256.683258) (xy 124.463361 -256.691383) (xy 124.411427 -256.691383)
			(xy 124.360132 -256.683258) (xy 124.310739 -256.66721) (xy 124.264465 -256.643632) (xy 124.222449 -256.613106)
			(xy 124.185726 -256.576383) (xy 124.1552 -256.534367) (xy 124.131622 -256.488093) (xy 124.115574 -256.4387)
			(xy 124.107449 -256.387405) (xy 123.827539 -256.387405) (xy 123.819414 -256.4387) (xy 123.803366 -256.488093)
			(xy 123.779788 -256.534367) (xy 123.749262 -256.576383) (xy 123.712539 -256.613106) (xy 123.670523 -256.643632)
			(xy 123.624249 -256.66721) (xy 123.574856 -256.683258) (xy 123.523561 -256.691383) (xy 123.471627 -256.691383)
			(xy 123.420332 -256.683258) (xy 123.370939 -256.66721) (xy 123.324665 -256.643632) (xy 123.282649 -256.613106)
			(xy 123.245926 -256.576383) (xy 123.2154 -256.534367) (xy 123.191822 -256.488093) (xy 123.175774 -256.4387)
			(xy 123.167649 -256.387405) (xy 122.887993 -256.387405) (xy 122.879868 -256.4387) (xy 122.86382 -256.488093)
			(xy 122.840242 -256.534367) (xy 122.809716 -256.576383) (xy 122.772993 -256.613106) (xy 122.730977 -256.643632)
			(xy 122.684703 -256.66721) (xy 122.63531 -256.683258) (xy 122.584015 -256.691383) (xy 122.532081 -256.691383)
			(xy 122.480786 -256.683258) (xy 122.431393 -256.66721) (xy 122.385119 -256.643632) (xy 122.343103 -256.613106)
			(xy 122.30638 -256.576383) (xy 122.275854 -256.534367) (xy 122.252276 -256.488093) (xy 122.236228 -256.4387)
			(xy 122.228103 -256.387405) (xy 121.948004 -256.387405) (xy 121.939883 -256.438678) (xy 121.923831 -256.488081)
			(xy 121.900248 -256.534364) (xy 121.869715 -256.576389) (xy 121.832984 -256.613119) (xy 121.790959 -256.643651)
			(xy 121.744675 -256.667233) (xy 121.695272 -256.683284) (xy 121.643967 -256.691409) (xy 121.617994 -256.691892)
			(xy 121.589598 -256.691309) (xy 121.533644 -256.681595) (xy 121.480175 -256.662454) (xy 121.45518 -256.648966)
			(xy 121.442831 -256.642415) (xy 121.415689 -256.635759) (xy 121.387759 -256.636721) (xy 121.361138 -256.645228)
			(xy 121.337827 -256.660642) (xy 121.319575 -256.681805) (xy 121.307753 -256.707128) (xy 121.305066 -256.720848)
			(xy 121.300271 -256.746652) (xy 121.283623 -256.796424) (xy 121.259331 -256.842946) (xy 121.228002 -256.885052)
			(xy 121.209562 -256.903728) (xy 121.200249 -256.91345) (xy 121.186567 -256.936622) (xy 121.179427 -256.962568)
			(xy 121.179327 -256.989478) (xy 121.186273 -257.015476) (xy 121.199781 -257.03875) (xy 121.209054 -257.048508)
			(xy 121.22727 -257.067225) (xy 121.258102 -257.109383) (xy 121.281923 -257.155863) (xy 121.29674 -257.201221)
			(xy 121.758203 -257.201221) (xy 121.758203 -257.149287) (xy 121.766328 -257.097992) (xy 121.782376 -257.048599)
			(xy 121.805954 -257.002325) (xy 121.83648 -256.960309) (xy 121.873203 -256.923586) (xy 121.915219 -256.89306)
			(xy 121.961493 -256.869482) (xy 122.010886 -256.853434) (xy 122.062181 -256.845309) (xy 122.114115 -256.845309)
			(xy 122.16541 -256.853434) (xy 122.214803 -256.869482) (xy 122.261077 -256.89306) (xy 122.303093 -256.923586)
			(xy 122.339816 -256.960309) (xy 122.370342 -257.002325) (xy 122.39392 -257.048599) (xy 122.409968 -257.097992)
			(xy 122.418093 -257.149287) (xy 122.418602 -257.175254) (xy 122.418093 -257.201221) (xy 122.698003 -257.201221)
			(xy 122.698003 -257.149287) (xy 122.706128 -257.097992) (xy 122.722176 -257.048599) (xy 122.745754 -257.002325)
			(xy 122.77628 -256.960309) (xy 122.813003 -256.923586) (xy 122.855019 -256.89306) (xy 122.901293 -256.869482)
			(xy 122.950686 -256.853434) (xy 123.001981 -256.845309) (xy 123.053915 -256.845309) (xy 123.10521 -256.853434)
			(xy 123.154603 -256.869482) (xy 123.200877 -256.89306) (xy 123.242893 -256.923586) (xy 123.279616 -256.960309)
			(xy 123.310142 -257.002325) (xy 123.33372 -257.048599) (xy 123.349768 -257.097992) (xy 123.357893 -257.149287)
			(xy 123.358402 -257.175254) (xy 123.357893 -257.201221) (xy 123.637803 -257.201221) (xy 123.637803 -257.149287)
			(xy 123.645928 -257.097992) (xy 123.661976 -257.048599) (xy 123.685554 -257.002325) (xy 123.71608 -256.960309)
			(xy 123.752803 -256.923586) (xy 123.794819 -256.89306) (xy 123.841093 -256.869482) (xy 123.890486 -256.853434)
			(xy 123.941781 -256.845309) (xy 123.993715 -256.845309) (xy 124.04501 -256.853434) (xy 124.094403 -256.869482)
			(xy 124.140677 -256.89306) (xy 124.182693 -256.923586) (xy 124.219416 -256.960309) (xy 124.249942 -257.002325)
			(xy 124.27352 -257.048599) (xy 124.289568 -257.097992) (xy 124.297693 -257.149287) (xy 124.298202 -257.175254)
			(xy 124.297693 -257.201221) (xy 124.577349 -257.201221) (xy 124.577349 -257.149287) (xy 124.585474 -257.097992)
			(xy 124.601522 -257.048599) (xy 124.6251 -257.002325) (xy 124.655626 -256.960309) (xy 124.692349 -256.923586)
			(xy 124.734365 -256.89306) (xy 124.780639 -256.869482) (xy 124.830032 -256.853434) (xy 124.881327 -256.845309)
			(xy 124.933261 -256.845309) (xy 124.984556 -256.853434) (xy 125.033949 -256.869482) (xy 125.080223 -256.89306)
			(xy 125.122239 -256.923586) (xy 125.158962 -256.960309) (xy 125.189488 -257.002325) (xy 125.213066 -257.048599)
			(xy 125.229114 -257.097992) (xy 125.237239 -257.149287) (xy 125.237748 -257.175254) (xy 125.237239 -257.201221)
			(xy 125.517149 -257.201221) (xy 125.517149 -257.149287) (xy 125.525274 -257.097992) (xy 125.541322 -257.048599)
			(xy 125.5649 -257.002325) (xy 125.595426 -256.960309) (xy 125.632149 -256.923586) (xy 125.674165 -256.89306)
			(xy 125.720439 -256.869482) (xy 125.769832 -256.853434) (xy 125.821127 -256.845309) (xy 125.873061 -256.845309)
			(xy 125.924356 -256.853434) (xy 125.973749 -256.869482) (xy 126.020023 -256.89306) (xy 126.062039 -256.923586)
			(xy 126.098762 -256.960309) (xy 126.129288 -257.002325) (xy 126.152866 -257.048599) (xy 126.168914 -257.097992)
			(xy 126.177039 -257.149287) (xy 126.177548 -257.175254) (xy 126.177039 -257.201221) (xy 126.457203 -257.201221)
			(xy 126.457203 -257.149287) (xy 126.465328 -257.097992) (xy 126.481376 -257.048599) (xy 126.504954 -257.002325)
			(xy 126.53548 -256.960309) (xy 126.572203 -256.923586) (xy 126.614219 -256.89306) (xy 126.660493 -256.869482)
			(xy 126.709886 -256.853434) (xy 126.761181 -256.845309) (xy 126.813115 -256.845309) (xy 126.86441 -256.853434)
			(xy 126.913803 -256.869482) (xy 126.960077 -256.89306) (xy 127.002093 -256.923586) (xy 127.038816 -256.960309)
			(xy 127.069342 -257.002325) (xy 127.09292 -257.048599) (xy 127.108968 -257.097992) (xy 127.117093 -257.149287)
			(xy 127.117602 -257.175254) (xy 127.117093 -257.201221) (xy 127.108968 -257.252516) (xy 127.09292 -257.301909)
			(xy 127.069342 -257.348183) (xy 127.038816 -257.390199) (xy 127.002093 -257.426922) (xy 126.960077 -257.457448)
			(xy 126.913803 -257.481026) (xy 126.86441 -257.497074) (xy 126.813115 -257.505199) (xy 126.761181 -257.505199)
			(xy 126.709886 -257.497074) (xy 126.660493 -257.481026) (xy 126.614219 -257.457448) (xy 126.572203 -257.426922)
			(xy 126.53548 -257.390199) (xy 126.504954 -257.348183) (xy 126.481376 -257.301909) (xy 126.465328 -257.252516)
			(xy 126.457203 -257.201221) (xy 126.177039 -257.201221) (xy 126.168914 -257.252516) (xy 126.152866 -257.301909)
			(xy 126.129288 -257.348183) (xy 126.098762 -257.390199) (xy 126.062039 -257.426922) (xy 126.020023 -257.457448)
			(xy 125.973749 -257.481026) (xy 125.924356 -257.497074) (xy 125.873061 -257.505199) (xy 125.821127 -257.505199)
			(xy 125.769832 -257.497074) (xy 125.720439 -257.481026) (xy 125.674165 -257.457448) (xy 125.632149 -257.426922)
			(xy 125.595426 -257.390199) (xy 125.5649 -257.348183) (xy 125.541322 -257.301909) (xy 125.525274 -257.252516)
			(xy 125.517149 -257.201221) (xy 125.237239 -257.201221) (xy 125.229114 -257.252516) (xy 125.213066 -257.301909)
			(xy 125.189488 -257.348183) (xy 125.158962 -257.390199) (xy 125.122239 -257.426922) (xy 125.080223 -257.457448)
			(xy 125.033949 -257.481026) (xy 124.984556 -257.497074) (xy 124.933261 -257.505199) (xy 124.881327 -257.505199)
			(xy 124.830032 -257.497074) (xy 124.780639 -257.481026) (xy 124.734365 -257.457448) (xy 124.692349 -257.426922)
			(xy 124.655626 -257.390199) (xy 124.6251 -257.348183) (xy 124.601522 -257.301909) (xy 124.585474 -257.252516)
			(xy 124.577349 -257.201221) (xy 124.297693 -257.201221) (xy 124.289568 -257.252516) (xy 124.27352 -257.301909)
			(xy 124.249942 -257.348183) (xy 124.219416 -257.390199) (xy 124.182693 -257.426922) (xy 124.140677 -257.457448)
			(xy 124.094403 -257.481026) (xy 124.04501 -257.497074) (xy 123.993715 -257.505199) (xy 123.941781 -257.505199)
			(xy 123.890486 -257.497074) (xy 123.841093 -257.481026) (xy 123.794819 -257.457448) (xy 123.752803 -257.426922)
			(xy 123.71608 -257.390199) (xy 123.685554 -257.348183) (xy 123.661976 -257.301909) (xy 123.645928 -257.252516)
			(xy 123.637803 -257.201221) (xy 123.357893 -257.201221) (xy 123.349768 -257.252516) (xy 123.33372 -257.301909)
			(xy 123.310142 -257.348183) (xy 123.279616 -257.390199) (xy 123.242893 -257.426922) (xy 123.200877 -257.457448)
			(xy 123.154603 -257.481026) (xy 123.10521 -257.497074) (xy 123.053915 -257.505199) (xy 123.001981 -257.505199)
			(xy 122.950686 -257.497074) (xy 122.901293 -257.481026) (xy 122.855019 -257.457448) (xy 122.813003 -257.426922)
			(xy 122.77628 -257.390199) (xy 122.745754 -257.348183) (xy 122.722176 -257.301909) (xy 122.706128 -257.252516)
			(xy 122.698003 -257.201221) (xy 122.418093 -257.201221) (xy 122.409968 -257.252516) (xy 122.39392 -257.301909)
			(xy 122.370342 -257.348183) (xy 122.339816 -257.390199) (xy 122.303093 -257.426922) (xy 122.261077 -257.457448)
			(xy 122.214803 -257.481026) (xy 122.16541 -257.497074) (xy 122.114115 -257.505199) (xy 122.062181 -257.505199)
			(xy 122.010886 -257.497074) (xy 121.961493 -257.481026) (xy 121.915219 -257.457448) (xy 121.873203 -257.426922)
			(xy 121.83648 -257.390199) (xy 121.805954 -257.348183) (xy 121.782376 -257.301909) (xy 121.766328 -257.252516)
			(xy 121.758203 -257.201221) (xy 121.29674 -257.201221) (xy 121.298141 -257.20551) (xy 121.306351 -257.25709)
			(xy 121.306844 -257.283204) (xy 121.306335 -257.309171) (xy 121.29821 -257.360466) (xy 121.282162 -257.409859)
			(xy 121.258584 -257.456133) (xy 121.228058 -257.498149) (xy 121.191335 -257.534872) (xy 121.149319 -257.565398)
			(xy 121.103045 -257.588976) (xy 121.053652 -257.605024) (xy 121.002357 -257.613149) (xy 120.950423 -257.613149)
			(xy 120.899128 -257.605024) (xy 120.849735 -257.588976) (xy 120.803461 -257.565398) (xy 120.761445 -257.534872)
			(xy 120.724722 -257.498149) (xy 120.694196 -257.456133) (xy 120.670618 -257.409859) (xy 120.65457 -257.360466)
			(xy 120.646445 -257.309171) (xy 120.645936 -257.283204) (xy 115.438004 -257.283204) (xy 115.424189 -257.303682)
			(xy 115.407948 -257.322066) (xy 115.398098 -257.333519) (xy 115.385086 -257.360769) (xy 115.380625 -257.390634)
			(xy 115.385106 -257.420497) (xy 115.398136 -257.447737) (xy 115.407948 -257.459226) (xy 115.424169 -257.477628)
			(xy 115.45162 -257.518281) (xy 115.472756 -257.562547) (xy 115.48711 -257.609453) (xy 115.494368 -257.657966)
			(xy 115.494816 -257.682492) (xy 115.494816 -257.682746) (xy 115.494307 -257.708713) (xy 115.49265 -257.719173)
			(xy 116.104589 -257.719173) (xy 116.104589 -257.667227) (xy 116.112715 -257.61592) (xy 116.128768 -257.566516)
			(xy 116.152352 -257.520232) (xy 116.182886 -257.478207) (xy 116.219619 -257.441476) (xy 116.261645 -257.410944)
			(xy 116.307931 -257.387362) (xy 116.357335 -257.371312) (xy 116.408643 -257.363188) (xy 116.434616 -257.362706)
			(xy 116.462312 -257.363253) (xy 116.516926 -257.372498) (xy 116.569232 -257.390726) (xy 116.617764 -257.417426)
			(xy 116.66116 -257.45185) (xy 116.698204 -257.493031) (xy 116.713508 -257.516122) (xy 116.721823 -257.52835)
			(xy 116.744139 -257.547736) (xy 116.771069 -257.559924) (xy 116.800361 -257.563895) (xy 116.829564 -257.559316)
			(xy 116.856235 -257.546572) (xy 116.878144 -257.526727) (xy 116.886228 -257.514344) (xy 116.899174 -257.49385)
			(xy 116.930079 -257.456508) (xy 116.966105 -257.424078) (xy 117.006481 -257.397256) (xy 117.05034 -257.376617)
			(xy 117.096742 -257.362604) (xy 117.144694 -257.355516) (xy 117.16893 -257.355086) (xy 117.192951 -257.355519)
			(xy 117.240488 -257.362479) (xy 117.286515 -257.376248) (xy 117.330065 -257.396536) (xy 117.370218 -257.422916)
			(xy 117.406128 -257.45483) (xy 117.421914 -257.472942) (xy 117.431718 -257.483784) (xy 117.456079 -257.49991)
			(xy 117.484005 -257.508495) (xy 117.513219 -257.508838) (xy 117.541339 -257.500911) (xy 117.566072 -257.48536)
			(xy 117.576092 -257.47472) (xy 117.595036 -257.454014) (xy 117.638706 -257.418769) (xy 117.687705 -257.391411)
			(xy 117.740622 -257.372729) (xy 117.795936 -257.363259) (xy 117.823996 -257.362706) (xy 117.849857 -257.363205)
			(xy 117.900949 -257.371252) (xy 117.950163 -257.387163) (xy 117.996294 -257.410552) (xy 118.038216 -257.440845)
			(xy 118.056914 -257.458718) (xy 118.066629 -257.467763) (xy 118.089638 -257.480975) (xy 118.115275 -257.487812)
			(xy 118.141809 -257.487812) (xy 118.167446 -257.480975) (xy 118.190455 -257.467763) (xy 118.20017 -257.458718)
			(xy 118.218865 -257.440844) (xy 118.260794 -257.410561) (xy 118.306927 -257.387178) (xy 118.356138 -257.371264)
			(xy 118.407228 -257.363207) (xy 118.433088 -257.362706) (xy 118.457443 -257.363121) (xy 118.505625 -257.370271)
			(xy 118.552235 -257.384417) (xy 118.596263 -257.405252) (xy 118.636756 -257.432326) (xy 118.672834 -257.465052)
			(xy 118.688612 -257.48361) (xy 118.698497 -257.494826) (xy 118.723299 -257.511488) (xy 118.75186 -257.520268)
			(xy 118.781739 -257.520416) (xy 118.810385 -257.511919) (xy 118.835351 -257.495503) (xy 118.84533 -257.484372)
			(xy 118.861106 -257.466072) (xy 118.897076 -257.433814) (xy 118.937363 -257.407142) (xy 118.981106 -257.386625)
			(xy 119.027371 -257.3727) (xy 119.075172 -257.365664) (xy 119.09933 -257.365246) (xy 119.123857 -257.365694)
			(xy 119.172369 -257.37296) (xy 119.219276 -257.387313) (xy 119.263547 -257.408438) (xy 119.304212 -257.435873)
			(xy 119.322596 -257.452114) (xy 119.334153 -257.46199) (xy 119.361623 -257.474979) (xy 119.391698 -257.47932)
			(xy 119.42172 -257.474628) (xy 119.449036 -257.461318) (xy 119.460518 -257.451352) (xy 119.47897 -257.434774)
			(xy 119.519914 -257.406776) (xy 119.564581 -257.385209) (xy 119.61197 -257.370556) (xy 119.661015 -257.363149)
			(xy 119.685816 -257.362706) (xy 119.711779 -257.363296) (xy 119.763066 -257.371422) (xy 119.812451 -257.38747)
			(xy 119.858717 -257.411045) (xy 119.900725 -257.441568) (xy 119.937442 -257.478287) (xy 119.967963 -257.520297)
			(xy 119.991536 -257.566564) (xy 120.007582 -257.615949) (xy 120.015705 -257.667237) (xy 120.015705 -257.719163)
			(xy 120.007582 -257.770451) (xy 119.991536 -257.819836) (xy 119.967963 -257.866103) (xy 119.937442 -257.908113)
			(xy 119.900725 -257.944832) (xy 119.858717 -257.975355) (xy 119.812451 -257.99893) (xy 119.763066 -258.014978)
			(xy 119.762694 -258.015037) (xy 121.288049 -258.015037) (xy 121.288049 -257.963103) (xy 121.296174 -257.911808)
			(xy 121.312222 -257.862415) (xy 121.3358 -257.816141) (xy 121.366326 -257.774125) (xy 121.403049 -257.737402)
			(xy 121.445065 -257.706876) (xy 121.491339 -257.683298) (xy 121.540732 -257.66725) (xy 121.592027 -257.659125)
			(xy 121.643961 -257.659125) (xy 121.695256 -257.66725) (xy 121.744649 -257.683298) (xy 121.790923 -257.706876)
			(xy 121.832939 -257.737402) (xy 121.869662 -257.774125) (xy 121.900188 -257.816141) (xy 121.923766 -257.862415)
			(xy 121.939814 -257.911808) (xy 121.947939 -257.963103) (xy 121.948448 -257.98907) (xy 121.947939 -258.015037)
			(xy 122.227849 -258.015037) (xy 122.227849 -257.963103) (xy 122.235974 -257.911808) (xy 122.252022 -257.862415)
			(xy 122.2756 -257.816141) (xy 122.306126 -257.774125) (xy 122.342849 -257.737402) (xy 122.384865 -257.706876)
			(xy 122.431139 -257.683298) (xy 122.480532 -257.66725) (xy 122.531827 -257.659125) (xy 122.583761 -257.659125)
			(xy 122.635056 -257.66725) (xy 122.684449 -257.683298) (xy 122.730723 -257.706876) (xy 122.772739 -257.737402)
			(xy 122.809462 -257.774125) (xy 122.839988 -257.816141) (xy 122.863566 -257.862415) (xy 122.879614 -257.911808)
			(xy 122.887739 -257.963103) (xy 122.888248 -257.98907) (xy 122.887739 -258.015037) (xy 123.167649 -258.015037)
			(xy 123.167649 -257.963103) (xy 123.175774 -257.911808) (xy 123.191822 -257.862415) (xy 123.2154 -257.816141)
			(xy 123.245926 -257.774125) (xy 123.282649 -257.737402) (xy 123.324665 -257.706876) (xy 123.370939 -257.683298)
			(xy 123.420332 -257.66725) (xy 123.471627 -257.659125) (xy 123.523561 -257.659125) (xy 123.574856 -257.66725)
			(xy 123.624249 -257.683298) (xy 123.670523 -257.706876) (xy 123.712539 -257.737402) (xy 123.749262 -257.774125)
			(xy 123.779788 -257.816141) (xy 123.803366 -257.862415) (xy 123.819414 -257.911808) (xy 123.827539 -257.963103)
			(xy 123.828048 -257.98907) (xy 123.827539 -258.015037) (xy 124.107449 -258.015037) (xy 124.107449 -257.963103)
			(xy 124.115574 -257.911808) (xy 124.131622 -257.862415) (xy 124.1552 -257.816141) (xy 124.185726 -257.774125)
			(xy 124.222449 -257.737402) (xy 124.264465 -257.706876) (xy 124.310739 -257.683298) (xy 124.360132 -257.66725)
			(xy 124.411427 -257.659125) (xy 124.463361 -257.659125) (xy 124.514656 -257.66725) (xy 124.564049 -257.683298)
			(xy 124.610323 -257.706876) (xy 124.652339 -257.737402) (xy 124.689062 -257.774125) (xy 124.719588 -257.816141)
			(xy 124.743166 -257.862415) (xy 124.759214 -257.911808) (xy 124.767339 -257.963103) (xy 124.767848 -257.98907)
			(xy 124.767339 -258.015037) (xy 125.047503 -258.015037) (xy 125.047503 -257.963103) (xy 125.055628 -257.911808)
			(xy 125.071676 -257.862415) (xy 125.095254 -257.816141) (xy 125.12578 -257.774125) (xy 125.162503 -257.737402)
			(xy 125.204519 -257.706876) (xy 125.250793 -257.683298) (xy 125.300186 -257.66725) (xy 125.351481 -257.659125)
			(xy 125.403415 -257.659125) (xy 125.45471 -257.66725) (xy 125.504103 -257.683298) (xy 125.550377 -257.706876)
			(xy 125.592393 -257.737402) (xy 125.629116 -257.774125) (xy 125.659642 -257.816141) (xy 125.68322 -257.862415)
			(xy 125.699268 -257.911808) (xy 125.707393 -257.963103) (xy 125.707902 -257.98907) (xy 125.707393 -258.015037)
			(xy 125.987049 -258.015037) (xy 125.987049 -257.963103) (xy 125.995174 -257.911808) (xy 126.011222 -257.862415)
			(xy 126.0348 -257.816141) (xy 126.065326 -257.774125) (xy 126.102049 -257.737402) (xy 126.144065 -257.706876)
			(xy 126.190339 -257.683298) (xy 126.239732 -257.66725) (xy 126.291027 -257.659125) (xy 126.342961 -257.659125)
			(xy 126.394256 -257.66725) (xy 126.443649 -257.683298) (xy 126.489923 -257.706876) (xy 126.531939 -257.737402)
			(xy 126.568662 -257.774125) (xy 126.599188 -257.816141) (xy 126.622766 -257.862415) (xy 126.638814 -257.911808)
			(xy 126.646939 -257.963103) (xy 126.647448 -257.98907) (xy 126.646939 -258.015037) (xy 126.927103 -258.015037)
			(xy 126.927103 -257.963103) (xy 126.935228 -257.911808) (xy 126.951276 -257.862415) (xy 126.974854 -257.816141)
			(xy 127.00538 -257.774125) (xy 127.042103 -257.737402) (xy 127.084119 -257.706876) (xy 127.130393 -257.683298)
			(xy 127.179786 -257.66725) (xy 127.231081 -257.659125) (xy 127.283015 -257.659125) (xy 127.33431 -257.66725)
			(xy 127.383703 -257.683298) (xy 127.429977 -257.706876) (xy 127.471993 -257.737402) (xy 127.508716 -257.774125)
			(xy 127.539242 -257.816141) (xy 127.56282 -257.862415) (xy 127.578868 -257.911808) (xy 127.586993 -257.963103)
			(xy 127.587502 -257.98907) (xy 127.586993 -258.015037) (xy 127.578868 -258.066332) (xy 127.56282 -258.115725)
			(xy 127.539242 -258.161999) (xy 127.508716 -258.204015) (xy 127.471993 -258.240738) (xy 127.429977 -258.271264)
			(xy 127.383703 -258.294842) (xy 127.33431 -258.31089) (xy 127.283015 -258.319015) (xy 127.231081 -258.319015)
			(xy 127.179786 -258.31089) (xy 127.130393 -258.294842) (xy 127.084119 -258.271264) (xy 127.042103 -258.240738)
			(xy 127.00538 -258.204015) (xy 126.974854 -258.161999) (xy 126.951276 -258.115725) (xy 126.935228 -258.066332)
			(xy 126.927103 -258.015037) (xy 126.646939 -258.015037) (xy 126.638814 -258.066332) (xy 126.622766 -258.115725)
			(xy 126.599188 -258.161999) (xy 126.568662 -258.204015) (xy 126.531939 -258.240738) (xy 126.489923 -258.271264)
			(xy 126.443649 -258.294842) (xy 126.394256 -258.31089) (xy 126.342961 -258.319015) (xy 126.291027 -258.319015)
			(xy 126.239732 -258.31089) (xy 126.190339 -258.294842) (xy 126.144065 -258.271264) (xy 126.102049 -258.240738)
			(xy 126.065326 -258.204015) (xy 126.0348 -258.161999) (xy 126.011222 -258.115725) (xy 125.995174 -258.066332)
			(xy 125.987049 -258.015037) (xy 125.707393 -258.015037) (xy 125.699268 -258.066332) (xy 125.68322 -258.115725)
			(xy 125.659642 -258.161999) (xy 125.629116 -258.204015) (xy 125.592393 -258.240738) (xy 125.550377 -258.271264)
			(xy 125.504103 -258.294842) (xy 125.45471 -258.31089) (xy 125.403415 -258.319015) (xy 125.351481 -258.319015)
			(xy 125.300186 -258.31089) (xy 125.250793 -258.294842) (xy 125.204519 -258.271264) (xy 125.162503 -258.240738)
			(xy 125.12578 -258.204015) (xy 125.095254 -258.161999) (xy 125.071676 -258.115725) (xy 125.055628 -258.066332)
			(xy 125.047503 -258.015037) (xy 124.767339 -258.015037) (xy 124.759214 -258.066332) (xy 124.743166 -258.115725)
			(xy 124.719588 -258.161999) (xy 124.689062 -258.204015) (xy 124.652339 -258.240738) (xy 124.610323 -258.271264)
			(xy 124.564049 -258.294842) (xy 124.514656 -258.31089) (xy 124.463361 -258.319015) (xy 124.411427 -258.319015)
			(xy 124.360132 -258.31089) (xy 124.310739 -258.294842) (xy 124.264465 -258.271264) (xy 124.222449 -258.240738)
			(xy 124.185726 -258.204015) (xy 124.1552 -258.161999) (xy 124.131622 -258.115725) (xy 124.115574 -258.066332)
			(xy 124.107449 -258.015037) (xy 123.827539 -258.015037) (xy 123.819414 -258.066332) (xy 123.803366 -258.115725)
			(xy 123.779788 -258.161999) (xy 123.749262 -258.204015) (xy 123.712539 -258.240738) (xy 123.670523 -258.271264)
			(xy 123.624249 -258.294842) (xy 123.574856 -258.31089) (xy 123.523561 -258.319015) (xy 123.471627 -258.319015)
			(xy 123.420332 -258.31089) (xy 123.370939 -258.294842) (xy 123.324665 -258.271264) (xy 123.282649 -258.240738)
			(xy 123.245926 -258.204015) (xy 123.2154 -258.161999) (xy 123.191822 -258.115725) (xy 123.175774 -258.066332)
			(xy 123.167649 -258.015037) (xy 122.887739 -258.015037) (xy 122.879614 -258.066332) (xy 122.863566 -258.115725)
			(xy 122.839988 -258.161999) (xy 122.809462 -258.204015) (xy 122.772739 -258.240738) (xy 122.730723 -258.271264)
			(xy 122.684449 -258.294842) (xy 122.635056 -258.31089) (xy 122.583761 -258.319015) (xy 122.531827 -258.319015)
			(xy 122.480532 -258.31089) (xy 122.431139 -258.294842) (xy 122.384865 -258.271264) (xy 122.342849 -258.240738)
			(xy 122.306126 -258.204015) (xy 122.2756 -258.161999) (xy 122.252022 -258.115725) (xy 122.235974 -258.066332)
			(xy 122.227849 -258.015037) (xy 121.947939 -258.015037) (xy 121.939814 -258.066332) (xy 121.923766 -258.115725)
			(xy 121.900188 -258.161999) (xy 121.869662 -258.204015) (xy 121.832939 -258.240738) (xy 121.790923 -258.271264)
			(xy 121.744649 -258.294842) (xy 121.695256 -258.31089) (xy 121.643961 -258.319015) (xy 121.592027 -258.319015)
			(xy 121.540732 -258.31089) (xy 121.491339 -258.294842) (xy 121.445065 -258.271264) (xy 121.403049 -258.240738)
			(xy 121.366326 -258.204015) (xy 121.3358 -258.161999) (xy 121.312222 -258.115725) (xy 121.296174 -258.066332)
			(xy 121.288049 -258.015037) (xy 119.762694 -258.015037) (xy 119.711779 -258.023104) (xy 119.685816 -258.023614)
			(xy 119.66129 -258.023149) (xy 119.612778 -258.015889) (xy 119.565871 -258.00154) (xy 119.521599 -257.980418)
			(xy 119.480934 -257.952987) (xy 119.46255 -257.936746) (xy 119.450956 -257.926919) (xy 119.423499 -257.91393)
			(xy 119.393436 -257.909582) (xy 119.363424 -257.914261) (xy 119.336111 -257.927552) (xy 119.324628 -257.937508)
			(xy 119.306193 -257.954105) (xy 119.265245 -257.982102) (xy 119.220573 -258.003666) (xy 119.173181 -258.018314)
			(xy 119.124132 -258.025715) (xy 119.09933 -258.026154) (xy 119.074977 -258.025705) (xy 119.026797 -258.018559)
			(xy 118.980188 -258.004419) (xy 118.93616 -257.983589) (xy 118.895667 -257.956523) (xy 118.859585 -257.923805)
			(xy 118.843806 -257.90525) (xy 118.833901 -257.894056) (xy 118.809102 -257.8774) (xy 118.780548 -257.868621)
			(xy 118.750676 -257.86847) (xy 118.722034 -257.876959) (xy 118.697069 -257.893363) (xy 118.687088 -257.904488)
			(xy 118.671293 -257.922772) (xy 118.635328 -257.955032) (xy 118.595045 -257.981707) (xy 118.551306 -258.002228)
			(xy 118.505043 -258.016156) (xy 118.457245 -258.023194) (xy 118.433088 -258.023614) (xy 118.407227 -258.023119)
			(xy 118.356135 -258.015071) (xy 118.306921 -257.999158) (xy 118.26079 -257.975768) (xy 118.218868 -257.945475)
			(xy 118.20017 -257.927602) (xy 118.190455 -257.918557) (xy 118.167446 -257.905345) (xy 118.141809 -257.898508)
			(xy 118.115275 -257.898508) (xy 118.089638 -257.905345) (xy 118.066629 -257.918557) (xy 118.056914 -257.927602)
			(xy 118.038229 -257.945487) (xy 117.996297 -257.975767) (xy 117.950162 -257.999149) (xy 117.900948 -258.01506)
			(xy 117.849857 -258.023114) (xy 117.823996 -258.023614) (xy 117.799975 -258.023163) (xy 117.75244 -258.016207)
			(xy 117.706412 -258.002441) (xy 117.662863 -257.982156) (xy 117.62271 -257.95578) (xy 117.586798 -257.923868)
			(xy 117.571012 -257.905758) (xy 117.561284 -257.894842) (xy 117.536901 -257.878718) (xy 117.508955 -257.870142)
			(xy 117.479725 -257.869813) (xy 117.451594 -257.877758) (xy 117.426855 -257.893329) (xy 117.416834 -257.90398)
			(xy 117.397877 -257.924673) (xy 117.35421 -257.95992) (xy 117.305215 -257.98728) (xy 117.2523 -258.005965)
			(xy 117.196989 -258.015438) (xy 117.16893 -258.015994) (xy 117.141236 -258.015412) (xy 117.086623 -258.006174)
			(xy 117.034317 -257.987953) (xy 116.985785 -257.96126) (xy 116.942388 -257.926842) (xy 116.905342 -257.885666)
			(xy 116.890038 -257.862578) (xy 116.881663 -257.850395) (xy 116.85936 -257.831011) (xy 116.832443 -257.818821)
			(xy 116.803164 -257.814845) (xy 116.773971 -257.819415) (xy 116.747307 -257.832148) (xy 116.725402 -257.85198)
			(xy 116.717318 -257.864356) (xy 116.704409 -257.884874) (xy 116.673498 -257.922217) (xy 116.637465 -257.954645)
			(xy 116.597083 -257.981464) (xy 116.553218 -258.002099) (xy 116.50681 -258.016107) (xy 116.458854 -258.023188)
			(xy 116.434616 -258.023614) (xy 116.408643 -258.023212) (xy 116.357335 -258.015088) (xy 116.307931 -257.999038)
			(xy 116.261645 -257.975456) (xy 116.219619 -257.944924) (xy 116.182886 -257.908193) (xy 116.152352 -257.866168)
			(xy 116.128768 -257.819884) (xy 116.112715 -257.77048) (xy 116.104589 -257.719173) (xy 115.49265 -257.719173)
			(xy 115.486182 -257.760008) (xy 115.470134 -257.809401) (xy 115.446556 -257.855675) (xy 115.41603 -257.897691)
			(xy 115.379307 -257.934414) (xy 115.337291 -257.96494) (xy 115.291017 -257.988518) (xy 115.241624 -258.004566)
			(xy 115.190329 -258.012691) (xy 115.138395 -258.012691) (xy 115.0871 -258.004566) (xy 115.037707 -257.988518)
			(xy 114.991433 -257.96494) (xy 114.949417 -257.934414) (xy 114.912694 -257.897691) (xy 114.882168 -257.855675)
			(xy 114.85859 -257.809401) (xy 114.842542 -257.760008) (xy 114.834417 -257.708713) (xy 114.833908 -257.682746)
			(xy 114.834356 -257.658693) (xy 114.841314 -257.611093) (xy 114.855104 -257.565007) (xy 114.875434 -257.521408)
			(xy 114.901874 -257.48122) (xy 114.933865 -257.445294) (xy 114.952018 -257.429508) (xy 114.960113 -257.421875)
			(xy 114.969498 -257.401738) (xy 114.969511 -257.379521) (xy 114.96015 -257.359372) (xy 114.952018 -257.351784)
			(xy 114.932968 -257.334258) (xy 114.926061 -257.328131) (xy 114.909166 -257.320734) (xy 114.890746 -257.319798)
			(xy 114.873189 -257.325446) (xy 114.858768 -257.336945) (xy 114.85372 -257.344672) (xy 114.840853 -257.365421)
			(xy 114.809956 -257.403222) (xy 114.773836 -257.436067) (xy 114.733277 -257.463242) (xy 114.689162 -257.484157)
			(xy 114.64245 -257.498355) (xy 114.594159 -257.505528) (xy 114.569748 -257.505962) (xy 114.543777 -257.505467)
			(xy 114.492473 -257.497348) (xy 114.443071 -257.481303) (xy 114.396788 -257.457726) (xy 114.354764 -257.427199)
			(xy 114.318032 -257.390473) (xy 114.287499 -257.348453) (xy 114.263916 -257.302173) (xy 114.247863 -257.252774)
			(xy 114.239737 -257.201471) (xy 113.959893 -257.201471) (xy 113.959893 -257.201475) (xy 113.951768 -257.25277)
			(xy 113.93572 -257.302163) (xy 113.912142 -257.348437) (xy 113.881616 -257.390453) (xy 113.844893 -257.427176)
			(xy 113.802877 -257.457702) (xy 113.756603 -257.48128) (xy 113.70721 -257.497328) (xy 113.655915 -257.505453)
			(xy 113.603981 -257.505453) (xy 113.552686 -257.497328) (xy 113.503293 -257.48128) (xy 113.457019 -257.457702)
			(xy 113.415003 -257.427176) (xy 113.37828 -257.390453) (xy 113.347754 -257.348437) (xy 113.324176 -257.302163)
			(xy 113.308128 -257.25277) (xy 113.300003 -257.201475) (xy 113.020093 -257.201475) (xy 113.011968 -257.25277)
			(xy 112.99592 -257.302163) (xy 112.972342 -257.348437) (xy 112.941816 -257.390453) (xy 112.905093 -257.427176)
			(xy 112.863077 -257.457702) (xy 112.816803 -257.48128) (xy 112.76741 -257.497328) (xy 112.716115 -257.505453)
			(xy 112.664181 -257.505453) (xy 112.612886 -257.497328) (xy 112.563493 -257.48128) (xy 112.517219 -257.457702)
			(xy 112.475203 -257.427176) (xy 112.43848 -257.390453) (xy 112.407954 -257.348437) (xy 112.384376 -257.302163)
			(xy 112.368328 -257.25277) (xy 112.360203 -257.201475) (xy 112.080293 -257.201475) (xy 112.072168 -257.25277)
			(xy 112.05612 -257.302163) (xy 112.032542 -257.348437) (xy 112.002016 -257.390453) (xy 111.965293 -257.427176)
			(xy 111.923277 -257.457702) (xy 111.877003 -257.48128) (xy 111.82761 -257.497328) (xy 111.776315 -257.505453)
			(xy 111.724381 -257.505453) (xy 111.673086 -257.497328) (xy 111.623693 -257.48128) (xy 111.577419 -257.457702)
			(xy 111.535403 -257.427176) (xy 111.49868 -257.390453) (xy 111.468154 -257.348437) (xy 111.444576 -257.302163)
			(xy 111.428528 -257.25277) (xy 111.420403 -257.201475) (xy 111.140747 -257.201475) (xy 111.132622 -257.25277)
			(xy 111.116574 -257.302163) (xy 111.092996 -257.348437) (xy 111.06247 -257.390453) (xy 111.025747 -257.427176)
			(xy 110.983731 -257.457702) (xy 110.937457 -257.48128) (xy 110.888064 -257.497328) (xy 110.836769 -257.505453)
			(xy 110.784835 -257.505453) (xy 110.73354 -257.497328) (xy 110.684147 -257.48128) (xy 110.637873 -257.457702)
			(xy 110.595857 -257.427176) (xy 110.559134 -257.390453) (xy 110.528608 -257.348437) (xy 110.50503 -257.302163)
			(xy 110.488982 -257.25277) (xy 110.480857 -257.201475) (xy 110.200693 -257.201475) (xy 110.192568 -257.25277)
			(xy 110.17652 -257.302163) (xy 110.152942 -257.348437) (xy 110.122416 -257.390453) (xy 110.085693 -257.427176)
			(xy 110.043677 -257.457702) (xy 109.997403 -257.48128) (xy 109.94801 -257.497328) (xy 109.896715 -257.505453)
			(xy 109.844781 -257.505453) (xy 109.793486 -257.497328) (xy 109.744093 -257.48128) (xy 109.697819 -257.457702)
			(xy 109.655803 -257.427176) (xy 109.61908 -257.390453) (xy 109.588554 -257.348437) (xy 109.564976 -257.302163)
			(xy 109.548928 -257.25277) (xy 109.540803 -257.201475) (xy 108.990255 -257.201475) (xy 108.988625 -257.206806)
			(xy 108.967505 -257.251078) (xy 108.940076 -257.291744) (xy 108.923836 -257.310128) (xy 108.914024 -257.321611)
			(xy 108.901009 -257.34885) (xy 108.896542 -257.378706) (xy 108.901013 -257.408562) (xy 108.91403 -257.435799)
			(xy 108.923836 -257.447288) (xy 108.940085 -257.465667) (xy 108.967532 -257.506326) (xy 108.988663 -257.550598)
			(xy 109.00301 -257.597509) (xy 109.01026 -257.646026) (xy 109.010704 -257.670554) (xy 109.010704 -257.670808)
			(xy 109.010195 -257.696775) (xy 109.00207 -257.74807) (xy 108.986022 -257.797463) (xy 108.962444 -257.843737)
			(xy 108.931918 -257.885753) (xy 108.895195 -257.922476) (xy 108.853179 -257.953002) (xy 108.806905 -257.97658)
			(xy 108.757512 -257.992628) (xy 108.706217 -258.000753) (xy 108.654283 -258.000753) (xy 108.602988 -257.992628)
			(xy 108.553595 -257.97658) (xy 108.507321 -257.953002) (xy 108.465305 -257.922476) (xy 108.428582 -257.885753)
			(xy 108.398056 -257.843737) (xy 108.374478 -257.797463) (xy 108.35843 -257.74807) (xy 108.350305 -257.696775)
			(xy 108.349796 -257.670808) (xy 107.775725 -257.670808) (xy 107.775725 -257.701365) (xy 107.767601 -257.752656)
			(xy 107.751554 -257.802045) (xy 107.727979 -257.848315) (xy 107.697455 -257.890328) (xy 107.660736 -257.927049)
			(xy 107.618724 -257.957574) (xy 107.572454 -257.98115) (xy 107.523066 -257.997199) (xy 107.471775 -258.005324)
			(xy 107.44581 -258.005834) (xy 107.421716 -258.005367) (xy 107.37404 -257.998364) (xy 107.327889 -257.984506)
			(xy 107.284241 -257.964087) (xy 107.244025 -257.937541) (xy 107.208095 -257.905431) (xy 107.192318 -257.887216)
			(xy 107.182402 -257.876162) (xy 107.157614 -257.859831) (xy 107.129182 -257.851307) (xy 107.099498 -257.851307)
			(xy 107.071066 -257.859831) (xy 107.046278 -257.876162) (xy 107.036362 -257.887216) (xy 107.020595 -257.905442)
			(xy 106.984666 -257.93756) (xy 106.94445 -257.964112) (xy 106.900801 -257.984536) (xy 106.854646 -257.998396)
			(xy 106.806966 -258.005398) (xy 106.78287 -258.005834) (xy 106.756475 -258.005302) (xy 106.704357 -257.996912)
			(xy 106.654237 -257.980335) (xy 106.607395 -257.955993) (xy 106.565024 -257.924506) (xy 106.528204 -257.886677)
			(xy 106.512614 -257.865372) (xy 106.504048 -257.853888) (xy 106.481744 -257.83592) (xy 106.455327 -257.824857)
			(xy 106.426875 -257.821569) (xy 106.39863 -257.826316) (xy 106.372816 -257.838723) (xy 106.351466 -257.857813)
			(xy 106.34345 -257.86969) (xy 106.328129 -257.892842) (xy 106.291041 -257.93415) (xy 106.247576 -257.968683)
			(xy 106.198953 -257.995471) (xy 106.146539 -258.013762) (xy 106.137521 -258.015291) (xy 109.070903 -258.015291)
			(xy 109.070903 -257.963357) (xy 109.079028 -257.912062) (xy 109.095076 -257.862669) (xy 109.118654 -257.816395)
			(xy 109.14918 -257.774379) (xy 109.185903 -257.737656) (xy 109.227919 -257.70713) (xy 109.274193 -257.683552)
			(xy 109.323586 -257.667504) (xy 109.374881 -257.659379) (xy 109.426815 -257.659379) (xy 109.47811 -257.667504)
			(xy 109.527503 -257.683552) (xy 109.573777 -257.70713) (xy 109.615793 -257.737656) (xy 109.652516 -257.774379)
			(xy 109.683042 -257.816395) (xy 109.70662 -257.862669) (xy 109.722668 -257.912062) (xy 109.730793 -257.963357)
			(xy 109.731302 -257.989324) (xy 109.730793 -258.015291) (xy 110.010703 -258.015291) (xy 110.010703 -257.963357)
			(xy 110.018828 -257.912062) (xy 110.034876 -257.862669) (xy 110.058454 -257.816395) (xy 110.08898 -257.774379)
			(xy 110.125703 -257.737656) (xy 110.167719 -257.70713) (xy 110.213993 -257.683552) (xy 110.263386 -257.667504)
			(xy 110.314681 -257.659379) (xy 110.366615 -257.659379) (xy 110.41791 -257.667504) (xy 110.467303 -257.683552)
			(xy 110.513577 -257.70713) (xy 110.555593 -257.737656) (xy 110.592316 -257.774379) (xy 110.622842 -257.816395)
			(xy 110.64642 -257.862669) (xy 110.662468 -257.912062) (xy 110.670593 -257.963357) (xy 110.671102 -257.989324)
			(xy 110.670593 -258.015291) (xy 110.950757 -258.015291) (xy 110.950757 -257.963357) (xy 110.958882 -257.912062)
			(xy 110.97493 -257.862669) (xy 110.998508 -257.816395) (xy 111.029034 -257.774379) (xy 111.065757 -257.737656)
			(xy 111.107773 -257.70713) (xy 111.154047 -257.683552) (xy 111.20344 -257.667504) (xy 111.254735 -257.659379)
			(xy 111.306669 -257.659379) (xy 111.357964 -257.667504) (xy 111.407357 -257.683552) (xy 111.453631 -257.70713)
			(xy 111.495647 -257.737656) (xy 111.53237 -257.774379) (xy 111.562896 -257.816395) (xy 111.586474 -257.862669)
			(xy 111.602522 -257.912062) (xy 111.610647 -257.963357) (xy 111.611156 -257.989324) (xy 111.610647 -258.015291)
			(xy 111.890557 -258.015291) (xy 111.890557 -257.963357) (xy 111.898682 -257.912062) (xy 111.91473 -257.862669)
			(xy 111.938308 -257.816395) (xy 111.968834 -257.774379) (xy 112.005557 -257.737656) (xy 112.047573 -257.70713)
			(xy 112.093847 -257.683552) (xy 112.14324 -257.667504) (xy 112.194535 -257.659379) (xy 112.246469 -257.659379)
			(xy 112.297764 -257.667504) (xy 112.347157 -257.683552) (xy 112.393431 -257.70713) (xy 112.435447 -257.737656)
			(xy 112.47217 -257.774379) (xy 112.502696 -257.816395) (xy 112.526274 -257.862669) (xy 112.542322 -257.912062)
			(xy 112.550447 -257.963357) (xy 112.550956 -257.989324) (xy 112.550447 -258.015291) (xy 112.830103 -258.015291)
			(xy 112.830103 -257.963357) (xy 112.838228 -257.912062) (xy 112.854276 -257.862669) (xy 112.877854 -257.816395)
			(xy 112.90838 -257.774379) (xy 112.945103 -257.737656) (xy 112.987119 -257.70713) (xy 113.033393 -257.683552)
			(xy 113.082786 -257.667504) (xy 113.134081 -257.659379) (xy 113.186015 -257.659379) (xy 113.23731 -257.667504)
			(xy 113.286703 -257.683552) (xy 113.332977 -257.70713) (xy 113.374993 -257.737656) (xy 113.411716 -257.774379)
			(xy 113.442242 -257.816395) (xy 113.46582 -257.862669) (xy 113.481868 -257.912062) (xy 113.489993 -257.963357)
			(xy 113.490502 -257.989324) (xy 113.489993 -258.015291) (xy 113.770157 -258.015291) (xy 113.770157 -257.963357)
			(xy 113.778282 -257.912062) (xy 113.79433 -257.862669) (xy 113.817908 -257.816395) (xy 113.848434 -257.774379)
			(xy 113.885157 -257.737656) (xy 113.927173 -257.70713) (xy 113.973447 -257.683552) (xy 114.02284 -257.667504)
			(xy 114.074135 -257.659379) (xy 114.126069 -257.659379) (xy 114.177364 -257.667504) (xy 114.226757 -257.683552)
			(xy 114.273031 -257.70713) (xy 114.315047 -257.737656) (xy 114.35177 -257.774379) (xy 114.382296 -257.816395)
			(xy 114.405874 -257.862669) (xy 114.421922 -257.912062) (xy 114.430047 -257.963357) (xy 114.430556 -257.989324)
			(xy 114.430047 -258.015291) (xy 114.421922 -258.066586) (xy 114.405874 -258.115979) (xy 114.382296 -258.162253)
			(xy 114.35177 -258.204269) (xy 114.315047 -258.240992) (xy 114.273031 -258.271518) (xy 114.226757 -258.295096)
			(xy 114.177364 -258.311144) (xy 114.126069 -258.319269) (xy 114.074135 -258.319269) (xy 114.02284 -258.311144)
			(xy 113.973447 -258.295096) (xy 113.927173 -258.271518) (xy 113.885157 -258.240992) (xy 113.848434 -258.204269)
			(xy 113.817908 -258.162253) (xy 113.79433 -258.115979) (xy 113.778282 -258.066586) (xy 113.770157 -258.015291)
			(xy 113.489993 -258.015291) (xy 113.481868 -258.066586) (xy 113.46582 -258.115979) (xy 113.442242 -258.162253)
			(xy 113.411716 -258.204269) (xy 113.374993 -258.240992) (xy 113.332977 -258.271518) (xy 113.286703 -258.295096)
			(xy 113.23731 -258.311144) (xy 113.186015 -258.319269) (xy 113.134081 -258.319269) (xy 113.082786 -258.311144)
			(xy 113.033393 -258.295096) (xy 112.987119 -258.271518) (xy 112.945103 -258.240992) (xy 112.90838 -258.204269)
			(xy 112.877854 -258.162253) (xy 112.854276 -258.115979) (xy 112.838228 -258.066586) (xy 112.830103 -258.015291)
			(xy 112.550447 -258.015291) (xy 112.542322 -258.066586) (xy 112.526274 -258.115979) (xy 112.502696 -258.162253)
			(xy 112.47217 -258.204269) (xy 112.435447 -258.240992) (xy 112.393431 -258.271518) (xy 112.347157 -258.295096)
			(xy 112.297764 -258.311144) (xy 112.246469 -258.319269) (xy 112.194535 -258.319269) (xy 112.14324 -258.311144)
			(xy 112.093847 -258.295096) (xy 112.047573 -258.271518) (xy 112.005557 -258.240992) (xy 111.968834 -258.204269)
			(xy 111.938308 -258.162253) (xy 111.91473 -258.115979) (xy 111.898682 -258.066586) (xy 111.890557 -258.015291)
			(xy 111.610647 -258.015291) (xy 111.602522 -258.066586) (xy 111.586474 -258.115979) (xy 111.562896 -258.162253)
			(xy 111.53237 -258.204269) (xy 111.495647 -258.240992) (xy 111.453631 -258.271518) (xy 111.407357 -258.295096)
			(xy 111.357964 -258.311144) (xy 111.306669 -258.319269) (xy 111.254735 -258.319269) (xy 111.20344 -258.311144)
			(xy 111.154047 -258.295096) (xy 111.107773 -258.271518) (xy 111.065757 -258.240992) (xy 111.029034 -258.204269)
			(xy 110.998508 -258.162253) (xy 110.97493 -258.115979) (xy 110.958882 -258.066586) (xy 110.950757 -258.015291)
			(xy 110.670593 -258.015291) (xy 110.662468 -258.066586) (xy 110.64642 -258.115979) (xy 110.622842 -258.162253)
			(xy 110.592316 -258.204269) (xy 110.555593 -258.240992) (xy 110.513577 -258.271518) (xy 110.467303 -258.295096)
			(xy 110.41791 -258.311144) (xy 110.366615 -258.319269) (xy 110.314681 -258.319269) (xy 110.263386 -258.311144)
			(xy 110.213993 -258.295096) (xy 110.167719 -258.271518) (xy 110.125703 -258.240992) (xy 110.08898 -258.204269)
			(xy 110.058454 -258.162253) (xy 110.034876 -258.115979) (xy 110.018828 -258.066586) (xy 110.010703 -258.015291)
			(xy 109.730793 -258.015291) (xy 109.722668 -258.066586) (xy 109.70662 -258.115979) (xy 109.683042 -258.162253)
			(xy 109.652516 -258.204269) (xy 109.615793 -258.240992) (xy 109.573777 -258.271518) (xy 109.527503 -258.295096)
			(xy 109.47811 -258.311144) (xy 109.426815 -258.319269) (xy 109.374881 -258.319269) (xy 109.323586 -258.311144)
			(xy 109.274193 -258.295096) (xy 109.227919 -258.271518) (xy 109.185903 -258.240992) (xy 109.14918 -258.204269)
			(xy 109.118654 -258.162253) (xy 109.095076 -258.115979) (xy 109.079028 -258.066586) (xy 109.070903 -258.015291)
			(xy 106.137521 -258.015291) (xy 106.091807 -258.023042) (xy 106.06405 -258.023614) (xy 106.038295 -258.023156)
			(xy 105.987408 -258.015169) (xy 105.938378 -257.99938) (xy 105.892393 -257.976172) (xy 105.850567 -257.946109)
			(xy 105.831894 -257.928364) (xy 105.822204 -257.919371) (xy 105.799272 -257.906239) (xy 105.773733 -257.899444)
			(xy 105.747307 -257.899444) (xy 105.721768 -257.906239) (xy 105.698836 -257.919371) (xy 105.689146 -257.928364)
			(xy 105.670484 -257.946117) (xy 105.628647 -257.976162) (xy 105.582658 -257.999356) (xy 105.533628 -258.015137)
			(xy 105.482744 -258.023123) (xy 105.45699 -258.023614) (xy 105.43102 -258.023184) (xy 105.37972 -258.015057)
			(xy 105.330323 -257.999006) (xy 105.284045 -257.975425) (xy 105.242025 -257.944895) (xy 105.205299 -257.908167)
			(xy 105.17477 -257.866147) (xy 105.15119 -257.819868) (xy 105.13514 -257.77047) (xy 105.127015 -257.71917)
			(xy 104.897931 -257.71917) (xy 104.889807 -257.770461) (xy 104.873758 -257.819852) (xy 104.850181 -257.866125)
			(xy 104.819655 -257.908139) (xy 104.782932 -257.944861) (xy 104.740916 -257.975386) (xy 104.694643 -257.998962)
			(xy 104.645251 -258.015009) (xy 104.593957 -258.023132) (xy 104.56799 -258.023614) (xy 104.567736 -258.023614)
			(xy 104.54321 -258.023137) (xy 104.494699 -258.01588) (xy 104.447792 -258.001534) (xy 104.40352 -257.980415)
			(xy 104.362855 -257.952985) (xy 104.34447 -257.936746) (xy 104.332981 -257.926943) (xy 104.305744 -257.913929)
			(xy 104.27589 -257.909461) (xy 104.246036 -257.913929) (xy 104.218799 -257.926943) (xy 104.20731 -257.936746)
			(xy 104.188913 -257.953013) (xy 104.148207 -257.980482) (xy 104.103883 -258.00162) (xy 104.056916 -258.01596)
			(xy 104.008344 -258.023187) (xy 103.98379 -258.023614) (xy 103.959239 -258.023154) (xy 103.910672 -258.015919)
			(xy 103.863711 -258.00158) (xy 103.819386 -257.980452) (xy 103.778674 -257.953001) (xy 103.76027 -257.936746)
			(xy 103.748781 -257.926943) (xy 103.721544 -257.913929) (xy 103.69169 -257.909461) (xy 103.661836 -257.913929)
			(xy 103.634599 -257.926943) (xy 103.62311 -257.936746) (xy 103.604733 -257.952997) (xy 103.564073 -257.980444)
			(xy 103.519801 -258.001574) (xy 103.47289 -258.015921) (xy 103.424372 -258.02317) (xy 103.399844 -258.023614)
			(xy 103.39959 -258.023614) (xy 103.37362 -258.023184) (xy 103.32232 -258.015057) (xy 103.272923 -257.999006)
			(xy 103.226645 -257.975425) (xy 103.184625 -257.944895) (xy 103.147899 -257.908167) (xy 103.11737 -257.866147)
			(xy 103.09379 -257.819868) (xy 103.07774 -257.77047) (xy 103.069615 -257.71917) (xy 102.072044 -257.71917)
			(xy 102.097139 -257.737402) (xy 102.133862 -257.774125) (xy 102.164388 -257.816141) (xy 102.187966 -257.862415)
			(xy 102.204014 -257.911808) (xy 102.212139 -257.963103) (xy 102.212648 -257.98907) (xy 102.212139 -258.015037)
			(xy 102.204014 -258.066332) (xy 102.187966 -258.115725) (xy 102.164388 -258.161999) (xy 102.133862 -258.204015)
			(xy 102.097139 -258.240738) (xy 102.055123 -258.271264) (xy 102.008849 -258.294842) (xy 101.959456 -258.31089)
			(xy 101.908161 -258.319015) (xy 101.856227 -258.319015) (xy 101.804932 -258.31089) (xy 101.755539 -258.294842)
			(xy 101.709265 -258.271264) (xy 101.667249 -258.240738) (xy 101.630526 -258.204015) (xy 101.6 -258.161999)
			(xy 101.576422 -258.115725) (xy 101.560374 -258.066332) (xy 101.552249 -258.015037) (xy 101.272339 -258.015037)
			(xy 101.264214 -258.066332) (xy 101.248166 -258.115725) (xy 101.224588 -258.161999) (xy 101.194062 -258.204015)
			(xy 101.157339 -258.240738) (xy 101.115323 -258.271264) (xy 101.069049 -258.294842) (xy 101.019656 -258.31089)
			(xy 100.968361 -258.319015) (xy 100.916427 -258.319015) (xy 100.865132 -258.31089) (xy 100.815739 -258.294842)
			(xy 100.769465 -258.271264) (xy 100.727449 -258.240738) (xy 100.690726 -258.204015) (xy 100.6602 -258.161999)
			(xy 100.636622 -258.115725) (xy 100.620574 -258.066332) (xy 100.612449 -258.015037) (xy 100.332539 -258.015037)
			(xy 100.324414 -258.066332) (xy 100.308366 -258.115725) (xy 100.284788 -258.161999) (xy 100.254262 -258.204015)
			(xy 100.217539 -258.240738) (xy 100.175523 -258.271264) (xy 100.129249 -258.294842) (xy 100.079856 -258.31089)
			(xy 100.028561 -258.319015) (xy 99.976627 -258.319015) (xy 99.925332 -258.31089) (xy 99.875939 -258.294842)
			(xy 99.829665 -258.271264) (xy 99.787649 -258.240738) (xy 99.750926 -258.204015) (xy 99.7204 -258.161999)
			(xy 99.696822 -258.115725) (xy 99.680774 -258.066332) (xy 99.672649 -258.015037) (xy 99.392993 -258.015037)
			(xy 99.384868 -258.066332) (xy 99.36882 -258.115725) (xy 99.345242 -258.161999) (xy 99.314716 -258.204015)
			(xy 99.277993 -258.240738) (xy 99.235977 -258.271264) (xy 99.189703 -258.294842) (xy 99.14031 -258.31089)
			(xy 99.089015 -258.319015) (xy 99.037081 -258.319015) (xy 98.985786 -258.31089) (xy 98.936393 -258.294842)
			(xy 98.890119 -258.271264) (xy 98.848103 -258.240738) (xy 98.81138 -258.204015) (xy 98.780854 -258.161999)
			(xy 98.757276 -258.115725) (xy 98.741228 -258.066332) (xy 98.733103 -258.015037) (xy 98.452939 -258.015037)
			(xy 98.444814 -258.066332) (xy 98.428766 -258.115725) (xy 98.405188 -258.161999) (xy 98.374662 -258.204015)
			(xy 98.337939 -258.240738) (xy 98.295923 -258.271264) (xy 98.249649 -258.294842) (xy 98.200256 -258.31089)
			(xy 98.148961 -258.319015) (xy 98.097027 -258.319015) (xy 98.045732 -258.31089) (xy 97.996339 -258.294842)
			(xy 97.950065 -258.271264) (xy 97.908049 -258.240738) (xy 97.871326 -258.204015) (xy 97.8408 -258.161999)
			(xy 97.817222 -258.115725) (xy 97.801174 -258.066332) (xy 97.793049 -258.015037) (xy 97.513393 -258.015037)
			(xy 97.505268 -258.066332) (xy 97.48922 -258.115725) (xy 97.465642 -258.161999) (xy 97.435116 -258.204015)
			(xy 97.398393 -258.240738) (xy 97.356377 -258.271264) (xy 97.310103 -258.294842) (xy 97.26071 -258.31089)
			(xy 97.209415 -258.319015) (xy 97.157481 -258.319015) (xy 97.106186 -258.31089) (xy 97.056793 -258.294842)
			(xy 97.010519 -258.271264) (xy 96.968503 -258.240738) (xy 96.93178 -258.204015) (xy 96.901254 -258.161999)
			(xy 96.877676 -258.115725) (xy 96.861628 -258.066332) (xy 96.853503 -258.015037) (xy 96.573339 -258.015037)
			(xy 96.565214 -258.066332) (xy 96.549166 -258.115725) (xy 96.525588 -258.161999) (xy 96.495062 -258.204015)
			(xy 96.458339 -258.240738) (xy 96.416323 -258.271264) (xy 96.370049 -258.294842) (xy 96.320656 -258.31089)
			(xy 96.269361 -258.319015) (xy 96.217427 -258.319015) (xy 96.166132 -258.31089) (xy 96.116739 -258.294842)
			(xy 96.070465 -258.271264) (xy 96.028449 -258.240738) (xy 95.991726 -258.204015) (xy 95.9612 -258.161999)
			(xy 95.937622 -258.115725) (xy 95.921574 -258.066332) (xy 95.913449 -258.015037) (xy 95.633539 -258.015037)
			(xy 95.625414 -258.066332) (xy 95.609366 -258.115725) (xy 95.585788 -258.161999) (xy 95.555262 -258.204015)
			(xy 95.518539 -258.240738) (xy 95.476523 -258.271264) (xy 95.430249 -258.294842) (xy 95.380856 -258.31089)
			(xy 95.329561 -258.319015) (xy 95.277627 -258.319015) (xy 95.226332 -258.31089) (xy 95.176939 -258.294842)
			(xy 95.130665 -258.271264) (xy 95.088649 -258.240738) (xy 95.051926 -258.204015) (xy 95.0214 -258.161999)
			(xy 94.997822 -258.115725) (xy 94.981774 -258.066332) (xy 94.973649 -258.015037) (xy 94.693739 -258.015037)
			(xy 94.685614 -258.066332) (xy 94.669566 -258.115725) (xy 94.645988 -258.161999) (xy 94.615462 -258.204015)
			(xy 94.578739 -258.240738) (xy 94.536723 -258.271264) (xy 94.490449 -258.294842) (xy 94.441056 -258.31089)
			(xy 94.389761 -258.319015) (xy 94.337827 -258.319015) (xy 94.286532 -258.31089) (xy 94.237139 -258.294842)
			(xy 94.190865 -258.271264) (xy 94.148849 -258.240738) (xy 94.112126 -258.204015) (xy 94.0816 -258.161999)
			(xy 94.058022 -258.115725) (xy 94.041974 -258.066332) (xy 94.033849 -258.015037) (xy 93.753939 -258.015037)
			(xy 93.745814 -258.066332) (xy 93.729766 -258.115725) (xy 93.706188 -258.161999) (xy 93.675662 -258.204015)
			(xy 93.638939 -258.240738) (xy 93.596923 -258.271264) (xy 93.550649 -258.294842) (xy 93.501256 -258.31089)
			(xy 93.449961 -258.319015) (xy 93.398027 -258.319015) (xy 93.346732 -258.31089) (xy 93.297339 -258.294842)
			(xy 93.251065 -258.271264) (xy 93.209049 -258.240738) (xy 93.172326 -258.204015) (xy 93.1418 -258.161999)
			(xy 93.118222 -258.115725) (xy 93.102174 -258.066332) (xy 93.094049 -258.015037) (xy 92.814393 -258.015037)
			(xy 92.806268 -258.066332) (xy 92.79022 -258.115725) (xy 92.766642 -258.161999) (xy 92.736116 -258.204015)
			(xy 92.699393 -258.240738) (xy 92.657377 -258.271264) (xy 92.611103 -258.294842) (xy 92.56171 -258.31089)
			(xy 92.510415 -258.319015) (xy 92.458481 -258.319015) (xy 92.407186 -258.31089) (xy 92.357793 -258.294842)
			(xy 92.311519 -258.271264) (xy 92.269503 -258.240738) (xy 92.23278 -258.204015) (xy 92.202254 -258.161999)
			(xy 92.178676 -258.115725) (xy 92.162628 -258.066332) (xy 92.154503 -258.015037) (xy 91.873693 -258.015037)
			(xy 91.871687 -258.040664) (xy 91.859669 -258.090987) (xy 91.839964 -258.138825) (xy 91.813051 -258.183012)
			(xy 91.779588 -258.222471) (xy 91.74039 -258.256239) (xy 91.718638 -258.270248) (xy 91.712034 -258.274566)
			(xy 91.68765 -258.316984) (xy 91.68765 -258.436618) (xy 91.688007 -258.445501) (xy 91.694169 -258.462166)
			(xy 91.705722 -258.475664) (xy 91.713304 -258.480306) (xy 91.751658 -258.501642) (xy 91.791536 -258.52374)
			(xy 91.799315 -258.527349) (xy 91.816299 -258.529645) (xy 91.833076 -258.52615) (xy 91.840558 -258.521962)
			(xy 91.840812 -258.521708) (xy 91.860483 -258.51003) (xy 91.902355 -258.491606) (xy 91.946365 -258.479123)
			(xy 91.991675 -258.472817) (xy 92.014548 -258.472432) (xy 92.04053 -258.472945) (xy 92.091852 -258.481081)
			(xy 92.14127 -258.497144) (xy 92.187567 -258.52074) (xy 92.229604 -258.551287) (xy 92.266345 -258.588033)
			(xy 92.296885 -258.630074) (xy 92.320474 -258.676374) (xy 92.33653 -258.725795) (xy 92.344658 -258.777118)
			(xy 92.344658 -258.829082) (xy 92.344654 -258.829107) (xy 92.624403 -258.829107) (xy 92.624403 -258.777173)
			(xy 92.632528 -258.725878) (xy 92.648576 -258.676485) (xy 92.672154 -258.630211) (xy 92.70268 -258.588195)
			(xy 92.739403 -258.551472) (xy 92.781419 -258.520946) (xy 92.827693 -258.497368) (xy 92.877086 -258.48132)
			(xy 92.928381 -258.473195) (xy 92.980315 -258.473195) (xy 93.03161 -258.48132) (xy 93.081003 -258.497368)
			(xy 93.127277 -258.520946) (xy 93.169293 -258.551472) (xy 93.206016 -258.588195) (xy 93.236542 -258.630211)
			(xy 93.26012 -258.676485) (xy 93.276168 -258.725878) (xy 93.284293 -258.777173) (xy 93.284802 -258.80314)
			(xy 93.284293 -258.829107) (xy 93.564203 -258.829107) (xy 93.564203 -258.777173) (xy 93.572328 -258.725878)
			(xy 93.588376 -258.676485) (xy 93.611954 -258.630211) (xy 93.64248 -258.588195) (xy 93.679203 -258.551472)
			(xy 93.721219 -258.520946) (xy 93.767493 -258.497368) (xy 93.816886 -258.48132) (xy 93.868181 -258.473195)
			(xy 93.920115 -258.473195) (xy 93.97141 -258.48132) (xy 94.020803 -258.497368) (xy 94.067077 -258.520946)
			(xy 94.109093 -258.551472) (xy 94.145816 -258.588195) (xy 94.176342 -258.630211) (xy 94.19992 -258.676485)
			(xy 94.215968 -258.725878) (xy 94.224093 -258.777173) (xy 94.224602 -258.80314) (xy 94.224093 -258.829107)
			(xy 94.503749 -258.829107) (xy 94.503749 -258.777173) (xy 94.511874 -258.725878) (xy 94.527922 -258.676485)
			(xy 94.5515 -258.630211) (xy 94.582026 -258.588195) (xy 94.618749 -258.551472) (xy 94.660765 -258.520946)
			(xy 94.707039 -258.497368) (xy 94.756432 -258.48132) (xy 94.807727 -258.473195) (xy 94.859661 -258.473195)
			(xy 94.910956 -258.48132) (xy 94.960349 -258.497368) (xy 95.006623 -258.520946) (xy 95.048639 -258.551472)
			(xy 95.085362 -258.588195) (xy 95.115888 -258.630211) (xy 95.139466 -258.676485) (xy 95.155514 -258.725878)
			(xy 95.163639 -258.777173) (xy 95.164148 -258.80314) (xy 95.163639 -258.829107) (xy 95.443803 -258.829107)
			(xy 95.443803 -258.777173) (xy 95.451928 -258.725878) (xy 95.467976 -258.676485) (xy 95.491554 -258.630211)
			(xy 95.52208 -258.588195) (xy 95.558803 -258.551472) (xy 95.600819 -258.520946) (xy 95.647093 -258.497368)
			(xy 95.696486 -258.48132) (xy 95.747781 -258.473195) (xy 95.799715 -258.473195) (xy 95.85101 -258.48132)
			(xy 95.900403 -258.497368) (xy 95.946677 -258.520946) (xy 95.988693 -258.551472) (xy 96.025416 -258.588195)
			(xy 96.055942 -258.630211) (xy 96.07952 -258.676485) (xy 96.095568 -258.725878) (xy 96.103693 -258.777173)
			(xy 96.104202 -258.80314) (xy 96.103693 -258.829107) (xy 96.383603 -258.829107) (xy 96.383603 -258.777173)
			(xy 96.391728 -258.725878) (xy 96.407776 -258.676485) (xy 96.431354 -258.630211) (xy 96.46188 -258.588195)
			(xy 96.498603 -258.551472) (xy 96.540619 -258.520946) (xy 96.586893 -258.497368) (xy 96.636286 -258.48132)
			(xy 96.687581 -258.473195) (xy 96.739515 -258.473195) (xy 96.79081 -258.48132) (xy 96.840203 -258.497368)
			(xy 96.886477 -258.520946) (xy 96.928493 -258.551472) (xy 96.965216 -258.588195) (xy 96.995742 -258.630211)
			(xy 97.01932 -258.676485) (xy 97.035368 -258.725878) (xy 97.043493 -258.777173) (xy 97.044002 -258.80314)
			(xy 97.043493 -258.829107) (xy 97.323403 -258.829107) (xy 97.323403 -258.777173) (xy 97.331528 -258.725878)
			(xy 97.347576 -258.676485) (xy 97.371154 -258.630211) (xy 97.40168 -258.588195) (xy 97.438403 -258.551472)
			(xy 97.480419 -258.520946) (xy 97.526693 -258.497368) (xy 97.576086 -258.48132) (xy 97.627381 -258.473195)
			(xy 97.679315 -258.473195) (xy 97.73061 -258.48132) (xy 97.780003 -258.497368) (xy 97.826277 -258.520946)
			(xy 97.868293 -258.551472) (xy 97.905016 -258.588195) (xy 97.935542 -258.630211) (xy 97.95912 -258.676485)
			(xy 97.975168 -258.725878) (xy 97.983293 -258.777173) (xy 97.983802 -258.80314) (xy 97.983293 -258.829107)
			(xy 98.263203 -258.829107) (xy 98.263203 -258.777173) (xy 98.271328 -258.725878) (xy 98.287376 -258.676485)
			(xy 98.310954 -258.630211) (xy 98.34148 -258.588195) (xy 98.378203 -258.551472) (xy 98.420219 -258.520946)
			(xy 98.466493 -258.497368) (xy 98.515886 -258.48132) (xy 98.567181 -258.473195) (xy 98.619115 -258.473195)
			(xy 98.67041 -258.48132) (xy 98.719803 -258.497368) (xy 98.766077 -258.520946) (xy 98.808093 -258.551472)
			(xy 98.844816 -258.588195) (xy 98.875342 -258.630211) (xy 98.89892 -258.676485) (xy 98.914968 -258.725878)
			(xy 98.923093 -258.777173) (xy 98.923602 -258.80314) (xy 98.923093 -258.829107) (xy 99.203003 -258.829107)
			(xy 99.203003 -258.777173) (xy 99.211128 -258.725878) (xy 99.227176 -258.676485) (xy 99.250754 -258.630211)
			(xy 99.28128 -258.588195) (xy 99.318003 -258.551472) (xy 99.360019 -258.520946) (xy 99.406293 -258.497368)
			(xy 99.455686 -258.48132) (xy 99.506981 -258.473195) (xy 99.558915 -258.473195) (xy 99.61021 -258.48132)
			(xy 99.659603 -258.497368) (xy 99.705877 -258.520946) (xy 99.747893 -258.551472) (xy 99.784616 -258.588195)
			(xy 99.815142 -258.630211) (xy 99.83872 -258.676485) (xy 99.854768 -258.725878) (xy 99.862893 -258.777173)
			(xy 99.863402 -258.80314) (xy 99.862893 -258.829107) (xy 100.142803 -258.829107) (xy 100.142803 -258.777173)
			(xy 100.150928 -258.725878) (xy 100.166976 -258.676485) (xy 100.190554 -258.630211) (xy 100.22108 -258.588195)
			(xy 100.257803 -258.551472) (xy 100.299819 -258.520946) (xy 100.346093 -258.497368) (xy 100.395486 -258.48132)
			(xy 100.446781 -258.473195) (xy 100.498715 -258.473195) (xy 100.55001 -258.48132) (xy 100.599403 -258.497368)
			(xy 100.645677 -258.520946) (xy 100.687693 -258.551472) (xy 100.724416 -258.588195) (xy 100.754942 -258.630211)
			(xy 100.77852 -258.676485) (xy 100.794568 -258.725878) (xy 100.802693 -258.777173) (xy 100.803202 -258.80314)
			(xy 100.802693 -258.829107) (xy 101.082349 -258.829107) (xy 101.082349 -258.777173) (xy 101.090474 -258.725878)
			(xy 101.106522 -258.676485) (xy 101.1301 -258.630211) (xy 101.160626 -258.588195) (xy 101.197349 -258.551472)
			(xy 101.239365 -258.520946) (xy 101.285639 -258.497368) (xy 101.335032 -258.48132) (xy 101.386327 -258.473195)
			(xy 101.438261 -258.473195) (xy 101.489556 -258.48132) (xy 101.538949 -258.497368) (xy 101.585223 -258.520946)
			(xy 101.627239 -258.551472) (xy 101.663962 -258.588195) (xy 101.694488 -258.630211) (xy 101.718066 -258.676485)
			(xy 101.734114 -258.725878) (xy 101.742239 -258.777173) (xy 101.742748 -258.80314) (xy 101.742239 -258.829107)
			(xy 102.021895 -258.829107) (xy 102.021895 -258.777173) (xy 102.03002 -258.725878) (xy 102.046068 -258.676485)
			(xy 102.069646 -258.630211) (xy 102.100172 -258.588195) (xy 102.136895 -258.551472) (xy 102.178911 -258.520946)
			(xy 102.225185 -258.497368) (xy 102.274578 -258.48132) (xy 102.325873 -258.473195) (xy 102.377807 -258.473195)
			(xy 102.429102 -258.48132) (xy 102.478495 -258.497368) (xy 102.524769 -258.520946) (xy 102.566785 -258.551472)
			(xy 102.603508 -258.588195) (xy 102.634034 -258.630211) (xy 102.657612 -258.676485) (xy 102.67366 -258.725878)
			(xy 102.681785 -258.777173) (xy 102.682294 -258.80314) (xy 102.681785 -258.829107) (xy 102.67366 -258.880402)
			(xy 102.657612 -258.929795) (xy 102.634034 -258.976069) (xy 102.603508 -259.018085) (xy 102.566785 -259.054808)
			(xy 102.524769 -259.085334) (xy 102.478495 -259.108912) (xy 102.429102 -259.12496) (xy 102.377807 -259.133085)
			(xy 102.325873 -259.133085) (xy 102.274578 -259.12496) (xy 102.225185 -259.108912) (xy 102.178911 -259.085334)
			(xy 102.136895 -259.054808) (xy 102.100172 -259.018085) (xy 102.069646 -258.976069) (xy 102.046068 -258.929795)
			(xy 102.03002 -258.880402) (xy 102.021895 -258.829107) (xy 101.742239 -258.829107) (xy 101.734114 -258.880402)
			(xy 101.718066 -258.929795) (xy 101.694488 -258.976069) (xy 101.663962 -259.018085) (xy 101.627239 -259.054808)
			(xy 101.585223 -259.085334) (xy 101.538949 -259.108912) (xy 101.489556 -259.12496) (xy 101.438261 -259.133085)
			(xy 101.386327 -259.133085) (xy 101.335032 -259.12496) (xy 101.285639 -259.108912) (xy 101.239365 -259.085334)
			(xy 101.197349 -259.054808) (xy 101.160626 -259.018085) (xy 101.1301 -258.976069) (xy 101.106522 -258.929795)
			(xy 101.090474 -258.880402) (xy 101.082349 -258.829107) (xy 100.802693 -258.829107) (xy 100.794568 -258.880402)
			(xy 100.77852 -258.929795) (xy 100.754942 -258.976069) (xy 100.724416 -259.018085) (xy 100.687693 -259.054808)
			(xy 100.645677 -259.085334) (xy 100.599403 -259.108912) (xy 100.55001 -259.12496) (xy 100.498715 -259.133085)
			(xy 100.446781 -259.133085) (xy 100.395486 -259.12496) (xy 100.346093 -259.108912) (xy 100.299819 -259.085334)
			(xy 100.257803 -259.054808) (xy 100.22108 -259.018085) (xy 100.190554 -258.976069) (xy 100.166976 -258.929795)
			(xy 100.150928 -258.880402) (xy 100.142803 -258.829107) (xy 99.862893 -258.829107) (xy 99.854768 -258.880402)
			(xy 99.83872 -258.929795) (xy 99.815142 -258.976069) (xy 99.784616 -259.018085) (xy 99.747893 -259.054808)
			(xy 99.705877 -259.085334) (xy 99.659603 -259.108912) (xy 99.61021 -259.12496) (xy 99.558915 -259.133085)
			(xy 99.506981 -259.133085) (xy 99.455686 -259.12496) (xy 99.406293 -259.108912) (xy 99.360019 -259.085334)
			(xy 99.318003 -259.054808) (xy 99.28128 -259.018085) (xy 99.250754 -258.976069) (xy 99.227176 -258.929795)
			(xy 99.211128 -258.880402) (xy 99.203003 -258.829107) (xy 98.923093 -258.829107) (xy 98.914968 -258.880402)
			(xy 98.89892 -258.929795) (xy 98.875342 -258.976069) (xy 98.844816 -259.018085) (xy 98.808093 -259.054808)
			(xy 98.766077 -259.085334) (xy 98.719803 -259.108912) (xy 98.67041 -259.12496) (xy 98.619115 -259.133085)
			(xy 98.567181 -259.133085) (xy 98.515886 -259.12496) (xy 98.466493 -259.108912) (xy 98.420219 -259.085334)
			(xy 98.378203 -259.054808) (xy 98.34148 -259.018085) (xy 98.310954 -258.976069) (xy 98.287376 -258.929795)
			(xy 98.271328 -258.880402) (xy 98.263203 -258.829107) (xy 97.983293 -258.829107) (xy 97.975168 -258.880402)
			(xy 97.95912 -258.929795) (xy 97.935542 -258.976069) (xy 97.905016 -259.018085) (xy 97.868293 -259.054808)
			(xy 97.826277 -259.085334) (xy 97.780003 -259.108912) (xy 97.73061 -259.12496) (xy 97.679315 -259.133085)
			(xy 97.627381 -259.133085) (xy 97.576086 -259.12496) (xy 97.526693 -259.108912) (xy 97.480419 -259.085334)
			(xy 97.438403 -259.054808) (xy 97.40168 -259.018085) (xy 97.371154 -258.976069) (xy 97.347576 -258.929795)
			(xy 97.331528 -258.880402) (xy 97.323403 -258.829107) (xy 97.043493 -258.829107) (xy 97.035368 -258.880402)
			(xy 97.01932 -258.929795) (xy 96.995742 -258.976069) (xy 96.965216 -259.018085) (xy 96.928493 -259.054808)
			(xy 96.886477 -259.085334) (xy 96.840203 -259.108912) (xy 96.79081 -259.12496) (xy 96.739515 -259.133085)
			(xy 96.687581 -259.133085) (xy 96.636286 -259.12496) (xy 96.586893 -259.108912) (xy 96.540619 -259.085334)
			(xy 96.498603 -259.054808) (xy 96.46188 -259.018085) (xy 96.431354 -258.976069) (xy 96.407776 -258.929795)
			(xy 96.391728 -258.880402) (xy 96.383603 -258.829107) (xy 96.103693 -258.829107) (xy 96.095568 -258.880402)
			(xy 96.07952 -258.929795) (xy 96.055942 -258.976069) (xy 96.025416 -259.018085) (xy 95.988693 -259.054808)
			(xy 95.946677 -259.085334) (xy 95.900403 -259.108912) (xy 95.85101 -259.12496) (xy 95.799715 -259.133085)
			(xy 95.747781 -259.133085) (xy 95.696486 -259.12496) (xy 95.647093 -259.108912) (xy 95.600819 -259.085334)
			(xy 95.558803 -259.054808) (xy 95.52208 -259.018085) (xy 95.491554 -258.976069) (xy 95.467976 -258.929795)
			(xy 95.451928 -258.880402) (xy 95.443803 -258.829107) (xy 95.163639 -258.829107) (xy 95.155514 -258.880402)
			(xy 95.139466 -258.929795) (xy 95.115888 -258.976069) (xy 95.085362 -259.018085) (xy 95.048639 -259.054808)
			(xy 95.006623 -259.085334) (xy 94.960349 -259.108912) (xy 94.910956 -259.12496) (xy 94.859661 -259.133085)
			(xy 94.807727 -259.133085) (xy 94.756432 -259.12496) (xy 94.707039 -259.108912) (xy 94.660765 -259.085334)
			(xy 94.618749 -259.054808) (xy 94.582026 -259.018085) (xy 94.5515 -258.976069) (xy 94.527922 -258.929795)
			(xy 94.511874 -258.880402) (xy 94.503749 -258.829107) (xy 94.224093 -258.829107) (xy 94.215968 -258.880402)
			(xy 94.19992 -258.929795) (xy 94.176342 -258.976069) (xy 94.145816 -259.018085) (xy 94.109093 -259.054808)
			(xy 94.067077 -259.085334) (xy 94.020803 -259.108912) (xy 93.97141 -259.12496) (xy 93.920115 -259.133085)
			(xy 93.868181 -259.133085) (xy 93.816886 -259.12496) (xy 93.767493 -259.108912) (xy 93.721219 -259.085334)
			(xy 93.679203 -259.054808) (xy 93.64248 -259.018085) (xy 93.611954 -258.976069) (xy 93.588376 -258.929795)
			(xy 93.572328 -258.880402) (xy 93.564203 -258.829107) (xy 93.284293 -258.829107) (xy 93.276168 -258.880402)
			(xy 93.26012 -258.929795) (xy 93.236542 -258.976069) (xy 93.206016 -259.018085) (xy 93.169293 -259.054808)
			(xy 93.127277 -259.085334) (xy 93.081003 -259.108912) (xy 93.03161 -259.12496) (xy 92.980315 -259.133085)
			(xy 92.928381 -259.133085) (xy 92.877086 -259.12496) (xy 92.827693 -259.108912) (xy 92.781419 -259.085334)
			(xy 92.739403 -259.054808) (xy 92.70268 -259.018085) (xy 92.672154 -258.976069) (xy 92.648576 -258.929795)
			(xy 92.632528 -258.880402) (xy 92.624403 -258.829107) (xy 92.344654 -258.829107) (xy 92.33653 -258.880405)
			(xy 92.320474 -258.929826) (xy 92.296885 -258.976126) (xy 92.266345 -259.018167) (xy 92.229604 -259.054913)
			(xy 92.187567 -259.08546) (xy 92.14127 -259.109056) (xy 92.091852 -259.125119) (xy 92.04053 -259.133255)
			(xy 92.014548 -259.133848) (xy 91.991674 -259.133465) (xy 91.946362 -259.127168) (xy 91.902349 -259.114689)
			(xy 91.860475 -259.096265) (xy 91.840812 -259.084572) (xy 91.840558 -259.084318) (xy 91.833071 -259.080131)
			(xy 91.816298 -259.076597) (xy 91.799314 -259.07892) (xy 91.791536 -259.08254) (xy 91.751658 -259.104638)
			(xy 91.713304 -259.125974) (xy 91.705717 -259.130613) (xy 91.694158 -259.144111) (xy 91.68799 -259.160777)
			(xy 91.68765 -259.169662) (xy 91.68765 -259.288788) (xy 91.712034 -259.33146) (xy 91.722702 -259.338318)
			(xy 91.743957 -259.352441) (xy 91.782247 -259.386172) (xy 91.814899 -259.425386) (xy 91.841137 -259.469153)
			(xy 91.860338 -259.516432) (xy 91.872046 -259.566099) (xy 91.875982 -259.616976) (xy 91.873978 -259.642923)
			(xy 92.154249 -259.642923) (xy 92.154249 -259.590989) (xy 92.162374 -259.539694) (xy 92.178422 -259.490301)
			(xy 92.202 -259.444027) (xy 92.232526 -259.402011) (xy 92.269249 -259.365288) (xy 92.311265 -259.334762)
			(xy 92.357539 -259.311184) (xy 92.406932 -259.295136) (xy 92.458227 -259.287011) (xy 92.510161 -259.287011)
			(xy 92.561456 -259.295136) (xy 92.610849 -259.311184) (xy 92.657123 -259.334762) (xy 92.699139 -259.365288)
			(xy 92.735862 -259.402011) (xy 92.766388 -259.444027) (xy 92.789966 -259.490301) (xy 92.806014 -259.539694)
			(xy 92.814139 -259.590989) (xy 92.814648 -259.616956) (xy 92.814139 -259.642923) (xy 93.094049 -259.642923)
			(xy 93.094049 -259.590989) (xy 93.102174 -259.539694) (xy 93.118222 -259.490301) (xy 93.1418 -259.444027)
			(xy 93.172326 -259.402011) (xy 93.209049 -259.365288) (xy 93.251065 -259.334762) (xy 93.297339 -259.311184)
			(xy 93.346732 -259.295136) (xy 93.398027 -259.287011) (xy 93.449961 -259.287011) (xy 93.501256 -259.295136)
			(xy 93.550649 -259.311184) (xy 93.596923 -259.334762) (xy 93.638939 -259.365288) (xy 93.675662 -259.402011)
			(xy 93.706188 -259.444027) (xy 93.729766 -259.490301) (xy 93.745814 -259.539694) (xy 93.753939 -259.590989)
			(xy 93.754448 -259.616956) (xy 93.753939 -259.642923) (xy 94.033849 -259.642923) (xy 94.033849 -259.590989)
			(xy 94.041974 -259.539694) (xy 94.058022 -259.490301) (xy 94.0816 -259.444027) (xy 94.112126 -259.402011)
			(xy 94.148849 -259.365288) (xy 94.190865 -259.334762) (xy 94.237139 -259.311184) (xy 94.286532 -259.295136)
			(xy 94.337827 -259.287011) (xy 94.389761 -259.287011) (xy 94.441056 -259.295136) (xy 94.490449 -259.311184)
			(xy 94.536723 -259.334762) (xy 94.578739 -259.365288) (xy 94.615462 -259.402011) (xy 94.645988 -259.444027)
			(xy 94.669566 -259.490301) (xy 94.685614 -259.539694) (xy 94.693739 -259.590989) (xy 94.694248 -259.616956)
			(xy 94.693739 -259.642923) (xy 94.973649 -259.642923) (xy 94.973649 -259.590989) (xy 94.981774 -259.539694)
			(xy 94.997822 -259.490301) (xy 95.0214 -259.444027) (xy 95.051926 -259.402011) (xy 95.088649 -259.365288)
			(xy 95.130665 -259.334762) (xy 95.176939 -259.311184) (xy 95.226332 -259.295136) (xy 95.277627 -259.287011)
			(xy 95.329561 -259.287011) (xy 95.380856 -259.295136) (xy 95.430249 -259.311184) (xy 95.476523 -259.334762)
			(xy 95.518539 -259.365288) (xy 95.555262 -259.402011) (xy 95.585788 -259.444027) (xy 95.609366 -259.490301)
			(xy 95.625414 -259.539694) (xy 95.633539 -259.590989) (xy 95.634048 -259.616956) (xy 95.633539 -259.642923)
			(xy 95.913449 -259.642923) (xy 95.913449 -259.590989) (xy 95.921574 -259.539694) (xy 95.937622 -259.490301)
			(xy 95.9612 -259.444027) (xy 95.991726 -259.402011) (xy 96.028449 -259.365288) (xy 96.070465 -259.334762)
			(xy 96.116739 -259.311184) (xy 96.166132 -259.295136) (xy 96.217427 -259.287011) (xy 96.269361 -259.287011)
			(xy 96.320656 -259.295136) (xy 96.370049 -259.311184) (xy 96.416323 -259.334762) (xy 96.458339 -259.365288)
			(xy 96.495062 -259.402011) (xy 96.525588 -259.444027) (xy 96.549166 -259.490301) (xy 96.565214 -259.539694)
			(xy 96.573339 -259.590989) (xy 96.573848 -259.616956) (xy 96.573339 -259.642923) (xy 96.853249 -259.642923)
			(xy 96.853249 -259.590989) (xy 96.861374 -259.539694) (xy 96.877422 -259.490301) (xy 96.901 -259.444027)
			(xy 96.931526 -259.402011) (xy 96.968249 -259.365288) (xy 97.010265 -259.334762) (xy 97.056539 -259.311184)
			(xy 97.105932 -259.295136) (xy 97.157227 -259.287011) (xy 97.209161 -259.287011) (xy 97.260456 -259.295136)
			(xy 97.309849 -259.311184) (xy 97.356123 -259.334762) (xy 97.398139 -259.365288) (xy 97.434862 -259.402011)
			(xy 97.465388 -259.444027) (xy 97.488966 -259.490301) (xy 97.505014 -259.539694) (xy 97.513139 -259.590989)
			(xy 97.513648 -259.616956) (xy 97.513139 -259.642923) (xy 97.793303 -259.642923) (xy 97.793303 -259.590989)
			(xy 97.801428 -259.539694) (xy 97.817476 -259.490301) (xy 97.841054 -259.444027) (xy 97.87158 -259.402011)
			(xy 97.908303 -259.365288) (xy 97.950319 -259.334762) (xy 97.996593 -259.311184) (xy 98.045986 -259.295136)
			(xy 98.097281 -259.287011) (xy 98.149215 -259.287011) (xy 98.20051 -259.295136) (xy 98.249903 -259.311184)
			(xy 98.296177 -259.334762) (xy 98.338193 -259.365288) (xy 98.374916 -259.402011) (xy 98.405442 -259.444027)
			(xy 98.42902 -259.490301) (xy 98.445068 -259.539694) (xy 98.453193 -259.590989) (xy 98.453702 -259.616956)
			(xy 98.453193 -259.642923) (xy 98.732849 -259.642923) (xy 98.732849 -259.590989) (xy 98.740974 -259.539694)
			(xy 98.757022 -259.490301) (xy 98.7806 -259.444027) (xy 98.811126 -259.402011) (xy 98.847849 -259.365288)
			(xy 98.889865 -259.334762) (xy 98.936139 -259.311184) (xy 98.985532 -259.295136) (xy 99.036827 -259.287011)
			(xy 99.088761 -259.287011) (xy 99.140056 -259.295136) (xy 99.189449 -259.311184) (xy 99.235723 -259.334762)
			(xy 99.277739 -259.365288) (xy 99.314462 -259.402011) (xy 99.344988 -259.444027) (xy 99.368566 -259.490301)
			(xy 99.384614 -259.539694) (xy 99.392739 -259.590989) (xy 99.393248 -259.616956) (xy 99.392739 -259.642923)
			(xy 99.672649 -259.642923) (xy 99.672649 -259.590989) (xy 99.680774 -259.539694) (xy 99.696822 -259.490301)
			(xy 99.7204 -259.444027) (xy 99.750926 -259.402011) (xy 99.787649 -259.365288) (xy 99.829665 -259.334762)
			(xy 99.875939 -259.311184) (xy 99.925332 -259.295136) (xy 99.976627 -259.287011) (xy 100.028561 -259.287011)
			(xy 100.079856 -259.295136) (xy 100.129249 -259.311184) (xy 100.175523 -259.334762) (xy 100.217539 -259.365288)
			(xy 100.254262 -259.402011) (xy 100.284788 -259.444027) (xy 100.308366 -259.490301) (xy 100.324414 -259.539694)
			(xy 100.332539 -259.590989) (xy 100.333048 -259.616956) (xy 100.332539 -259.642923) (xy 100.612449 -259.642923)
			(xy 100.612449 -259.590989) (xy 100.620574 -259.539694) (xy 100.636622 -259.490301) (xy 100.6602 -259.444027)
			(xy 100.690726 -259.402011) (xy 100.727449 -259.365288) (xy 100.769465 -259.334762) (xy 100.815739 -259.311184)
			(xy 100.865132 -259.295136) (xy 100.916427 -259.287011) (xy 100.968361 -259.287011) (xy 101.019656 -259.295136)
			(xy 101.069049 -259.311184) (xy 101.115323 -259.334762) (xy 101.157339 -259.365288) (xy 101.194062 -259.402011)
			(xy 101.224588 -259.444027) (xy 101.248166 -259.490301) (xy 101.264214 -259.539694) (xy 101.272339 -259.590989)
			(xy 101.272848 -259.616956) (xy 101.272339 -259.642923) (xy 101.552249 -259.642923) (xy 101.552249 -259.590989)
			(xy 101.560374 -259.539694) (xy 101.576422 -259.490301) (xy 101.6 -259.444027) (xy 101.630526 -259.402011)
			(xy 101.667249 -259.365288) (xy 101.709265 -259.334762) (xy 101.755539 -259.311184) (xy 101.804932 -259.295136)
			(xy 101.856227 -259.287011) (xy 101.908161 -259.287011) (xy 101.959456 -259.295136) (xy 102.008849 -259.311184)
			(xy 102.055123 -259.334762) (xy 102.097139 -259.365288) (xy 102.133862 -259.402011) (xy 102.164388 -259.444027)
			(xy 102.187966 -259.490301) (xy 102.204014 -259.539694) (xy 102.212139 -259.590989) (xy 102.212648 -259.616956)
			(xy 102.212139 -259.642923) (xy 102.204014 -259.694218) (xy 102.194849 -259.722425) (xy 102.536499 -259.722425)
			(xy 102.536499 -259.670491) (xy 102.544624 -259.619196) (xy 102.560672 -259.569803) (xy 102.58425 -259.523529)
			(xy 102.614776 -259.481513) (xy 102.651499 -259.44479) (xy 102.693515 -259.414264) (xy 102.739789 -259.390686)
			(xy 102.789182 -259.374638) (xy 102.840477 -259.366513) (xy 102.892411 -259.366513) (xy 102.943706 -259.374638)
			(xy 102.993099 -259.390686) (xy 103.039373 -259.414264) (xy 103.081389 -259.44479) (xy 103.118112 -259.481513)
			(xy 103.148638 -259.523529) (xy 103.172216 -259.569803) (xy 103.175075 -259.578602) (xy 108.103416 -259.578602)
			(xy 108.103416 -259.578348) (xy 108.103832 -259.55382) (xy 108.111103 -259.505305) (xy 108.125463 -259.458398)
			(xy 108.146596 -259.414127) (xy 108.174038 -259.373464) (xy 108.190284 -259.355082) (xy 108.200085 -259.343591)
			(xy 108.213098 -259.316354) (xy 108.217566 -259.286501) (xy 108.213098 -259.256648) (xy 108.200086 -259.229411)
			(xy 108.190284 -259.217922) (xy 108.174027 -259.19955) (xy 108.146583 -259.158888) (xy 108.125456 -259.114614)
			(xy 108.11111 -259.067702) (xy 108.10386 -259.019184) (xy 108.103416 -258.994656) (xy 108.103416 -258.994402)
			(xy 108.103925 -258.968435) (xy 108.11205 -258.91714) (xy 108.128098 -258.867747) (xy 108.151676 -258.821473)
			(xy 108.182202 -258.779457) (xy 108.218925 -258.742734) (xy 108.260941 -258.712208) (xy 108.307215 -258.68863)
			(xy 108.356608 -258.672582) (xy 108.407903 -258.664457) (xy 108.459837 -258.664457) (xy 108.511132 -258.672582)
			(xy 108.560525 -258.68863) (xy 108.606799 -258.712208) (xy 108.648815 -258.742734) (xy 108.685538 -258.779457)
			(xy 108.716064 -258.821473) (xy 108.720083 -258.829361) (xy 109.540803 -258.829361) (xy 109.540803 -258.777427)
			(xy 109.548928 -258.726132) (xy 109.564976 -258.676739) (xy 109.588554 -258.630465) (xy 109.61908 -258.588449)
			(xy 109.655803 -258.551726) (xy 109.697819 -258.5212) (xy 109.744093 -258.497622) (xy 109.793486 -258.481574)
			(xy 109.844781 -258.473449) (xy 109.896715 -258.473449) (xy 109.94801 -258.481574) (xy 109.997403 -258.497622)
			(xy 110.043677 -258.5212) (xy 110.085693 -258.551726) (xy 110.122416 -258.588449) (xy 110.152942 -258.630465)
			(xy 110.17652 -258.676739) (xy 110.192568 -258.726132) (xy 110.200693 -258.777427) (xy 110.201202 -258.803394)
			(xy 110.200693 -258.829361) (xy 110.480857 -258.829361) (xy 110.480857 -258.777427) (xy 110.488982 -258.726132)
			(xy 110.50503 -258.676739) (xy 110.528608 -258.630465) (xy 110.559134 -258.588449) (xy 110.595857 -258.551726)
			(xy 110.637873 -258.5212) (xy 110.684147 -258.497622) (xy 110.73354 -258.481574) (xy 110.784835 -258.473449)
			(xy 110.836769 -258.473449) (xy 110.888064 -258.481574) (xy 110.937457 -258.497622) (xy 110.983731 -258.5212)
			(xy 111.025747 -258.551726) (xy 111.06247 -258.588449) (xy 111.092996 -258.630465) (xy 111.116574 -258.676739)
			(xy 111.132622 -258.726132) (xy 111.140747 -258.777427) (xy 111.141256 -258.803394) (xy 111.140747 -258.829361)
			(xy 111.420403 -258.829361) (xy 111.420403 -258.777427) (xy 111.428528 -258.726132) (xy 111.444576 -258.676739)
			(xy 111.468154 -258.630465) (xy 111.49868 -258.588449) (xy 111.535403 -258.551726) (xy 111.577419 -258.5212)
			(xy 111.623693 -258.497622) (xy 111.673086 -258.481574) (xy 111.724381 -258.473449) (xy 111.776315 -258.473449)
			(xy 111.82761 -258.481574) (xy 111.877003 -258.497622) (xy 111.923277 -258.5212) (xy 111.965293 -258.551726)
			(xy 112.002016 -258.588449) (xy 112.032542 -258.630465) (xy 112.05612 -258.676739) (xy 112.072168 -258.726132)
			(xy 112.080293 -258.777427) (xy 112.080802 -258.803394) (xy 112.080293 -258.829361) (xy 112.360203 -258.829361)
			(xy 112.360203 -258.777427) (xy 112.368328 -258.726132) (xy 112.384376 -258.676739) (xy 112.407954 -258.630465)
			(xy 112.43848 -258.588449) (xy 112.475203 -258.551726) (xy 112.517219 -258.5212) (xy 112.563493 -258.497622)
			(xy 112.612886 -258.481574) (xy 112.664181 -258.473449) (xy 112.716115 -258.473449) (xy 112.76741 -258.481574)
			(xy 112.816803 -258.497622) (xy 112.863077 -258.5212) (xy 112.905093 -258.551726) (xy 112.941816 -258.588449)
			(xy 112.972342 -258.630465) (xy 112.99592 -258.676739) (xy 113.011968 -258.726132) (xy 113.020093 -258.777427)
			(xy 113.020602 -258.803394) (xy 113.020093 -258.829361) (xy 113.300003 -258.829361) (xy 113.300003 -258.777427)
			(xy 113.308128 -258.726132) (xy 113.324176 -258.676739) (xy 113.347754 -258.630465) (xy 113.37828 -258.588449)
			(xy 113.415003 -258.551726) (xy 113.457019 -258.5212) (xy 113.503293 -258.497622) (xy 113.552686 -258.481574)
			(xy 113.603981 -258.473449) (xy 113.655915 -258.473449) (xy 113.70721 -258.481574) (xy 113.756603 -258.497622)
			(xy 113.802877 -258.5212) (xy 113.844893 -258.551726) (xy 113.881616 -258.588449) (xy 113.912142 -258.630465)
			(xy 113.93572 -258.676739) (xy 113.951768 -258.726132) (xy 113.959893 -258.777427) (xy 113.960402 -258.803394)
			(xy 113.959893 -258.829361) (xy 114.239803 -258.829361) (xy 114.239803 -258.777427) (xy 114.247928 -258.726132)
			(xy 114.263976 -258.676739) (xy 114.287554 -258.630465) (xy 114.31808 -258.588449) (xy 114.354803 -258.551726)
			(xy 114.396819 -258.5212) (xy 114.443093 -258.497622) (xy 114.492486 -258.481574) (xy 114.543781 -258.473449)
			(xy 114.595715 -258.473449) (xy 114.621738 -258.477571) (xy 120.646445 -258.477571) (xy 120.646445 -258.425637)
			(xy 120.65457 -258.374342) (xy 120.670618 -258.324949) (xy 120.694196 -258.278675) (xy 120.724722 -258.236659)
			(xy 120.761445 -258.199936) (xy 120.803461 -258.16941) (xy 120.849735 -258.145832) (xy 120.899128 -258.129784)
			(xy 120.950423 -258.121659) (xy 121.002357 -258.121659) (xy 121.053652 -258.129784) (xy 121.103045 -258.145832)
			(xy 121.149319 -258.16941) (xy 121.191335 -258.199936) (xy 121.228058 -258.236659) (xy 121.258584 -258.278675)
			(xy 121.282162 -258.324949) (xy 121.29821 -258.374342) (xy 121.306335 -258.425637) (xy 121.306844 -258.451604)
			(xy 121.306335 -258.477571) (xy 121.29821 -258.528866) (xy 121.282162 -258.578259) (xy 121.258584 -258.624533)
			(xy 121.228058 -258.666549) (xy 121.191335 -258.703272) (xy 121.149319 -258.733798) (xy 121.103045 -258.757376)
			(xy 121.053652 -258.773424) (xy 121.002357 -258.781549) (xy 120.950423 -258.781549) (xy 120.899128 -258.773424)
			(xy 120.849735 -258.757376) (xy 120.803461 -258.733798) (xy 120.761445 -258.703272) (xy 120.724722 -258.666549)
			(xy 120.694196 -258.624533) (xy 120.670618 -258.578259) (xy 120.65457 -258.528866) (xy 120.646445 -258.477571)
			(xy 114.621738 -258.477571) (xy 114.64701 -258.481574) (xy 114.696403 -258.497622) (xy 114.742677 -258.5212)
			(xy 114.784693 -258.551726) (xy 114.821416 -258.588449) (xy 114.851942 -258.630465) (xy 114.87552 -258.676739)
			(xy 114.891568 -258.726132) (xy 114.899693 -258.777427) (xy 114.900202 -258.803394) (xy 114.899693 -258.829361)
			(xy 114.891568 -258.880656) (xy 114.87552 -258.930049) (xy 114.851942 -258.976323) (xy 114.821416 -259.018339)
			(xy 114.784693 -259.055062) (xy 114.742677 -259.085588) (xy 114.696403 -259.109166) (xy 114.64701 -259.125214)
			(xy 114.595715 -259.133339) (xy 114.543781 -259.133339) (xy 114.492486 -259.125214) (xy 114.443093 -259.109166)
			(xy 114.396819 -259.085588) (xy 114.354803 -259.055062) (xy 114.31808 -259.018339) (xy 114.287554 -258.976323)
			(xy 114.263976 -258.930049) (xy 114.247928 -258.880656) (xy 114.239803 -258.829361) (xy 113.959893 -258.829361)
			(xy 113.951768 -258.880656) (xy 113.93572 -258.930049) (xy 113.912142 -258.976323) (xy 113.881616 -259.018339)
			(xy 113.844893 -259.055062) (xy 113.802877 -259.085588) (xy 113.756603 -259.109166) (xy 113.70721 -259.125214)
			(xy 113.655915 -259.133339) (xy 113.603981 -259.133339) (xy 113.552686 -259.125214) (xy 113.503293 -259.109166)
			(xy 113.457019 -259.085588) (xy 113.415003 -259.055062) (xy 113.37828 -259.018339) (xy 113.347754 -258.976323)
			(xy 113.324176 -258.930049) (xy 113.308128 -258.880656) (xy 113.300003 -258.829361) (xy 113.020093 -258.829361)
			(xy 113.011968 -258.880656) (xy 112.99592 -258.930049) (xy 112.972342 -258.976323) (xy 112.941816 -259.018339)
			(xy 112.905093 -259.055062) (xy 112.863077 -259.085588) (xy 112.816803 -259.109166) (xy 112.76741 -259.125214)
			(xy 112.716115 -259.133339) (xy 112.664181 -259.133339) (xy 112.612886 -259.125214) (xy 112.563493 -259.109166)
			(xy 112.517219 -259.085588) (xy 112.475203 -259.055062) (xy 112.43848 -259.018339) (xy 112.407954 -258.976323)
			(xy 112.384376 -258.930049) (xy 112.368328 -258.880656) (xy 112.360203 -258.829361) (xy 112.080293 -258.829361)
			(xy 112.072168 -258.880656) (xy 112.05612 -258.930049) (xy 112.032542 -258.976323) (xy 112.002016 -259.018339)
			(xy 111.965293 -259.055062) (xy 111.923277 -259.085588) (xy 111.877003 -259.109166) (xy 111.82761 -259.125214)
			(xy 111.776315 -259.133339) (xy 111.724381 -259.133339) (xy 111.673086 -259.125214) (xy 111.623693 -259.109166)
			(xy 111.577419 -259.085588) (xy 111.535403 -259.055062) (xy 111.49868 -259.018339) (xy 111.468154 -258.976323)
			(xy 111.444576 -258.930049) (xy 111.428528 -258.880656) (xy 111.420403 -258.829361) (xy 111.140747 -258.829361)
			(xy 111.132622 -258.880656) (xy 111.116574 -258.930049) (xy 111.092996 -258.976323) (xy 111.06247 -259.018339)
			(xy 111.025747 -259.055062) (xy 110.983731 -259.085588) (xy 110.937457 -259.109166) (xy 110.888064 -259.125214)
			(xy 110.836769 -259.133339) (xy 110.784835 -259.133339) (xy 110.73354 -259.125214) (xy 110.684147 -259.109166)
			(xy 110.637873 -259.085588) (xy 110.595857 -259.055062) (xy 110.559134 -259.018339) (xy 110.528608 -258.976323)
			(xy 110.50503 -258.930049) (xy 110.488982 -258.880656) (xy 110.480857 -258.829361) (xy 110.200693 -258.829361)
			(xy 110.192568 -258.880656) (xy 110.17652 -258.930049) (xy 110.152942 -258.976323) (xy 110.122416 -259.018339)
			(xy 110.085693 -259.055062) (xy 110.043677 -259.085588) (xy 109.997403 -259.109166) (xy 109.94801 -259.125214)
			(xy 109.896715 -259.133339) (xy 109.844781 -259.133339) (xy 109.793486 -259.125214) (xy 109.744093 -259.109166)
			(xy 109.697819 -259.085588) (xy 109.655803 -259.055062) (xy 109.61908 -259.018339) (xy 109.588554 -258.976323)
			(xy 109.564976 -258.930049) (xy 109.548928 -258.880656) (xy 109.540803 -258.829361) (xy 108.720083 -258.829361)
			(xy 108.739642 -258.867747) (xy 108.75569 -258.91714) (xy 108.763815 -258.968435) (xy 108.764324 -258.994402)
			(xy 108.764324 -258.994656) (xy 108.7639 -259.019184) (xy 108.756629 -259.067697) (xy 108.742271 -259.114605)
			(xy 108.72114 -259.158876) (xy 108.6937 -259.199539) (xy 108.677456 -259.217922) (xy 108.667648 -259.229408)
			(xy 108.65463 -259.256646) (xy 108.650161 -259.286501) (xy 108.654631 -259.316357) (xy 108.66765 -259.343594)
			(xy 108.677456 -259.355082) (xy 108.693705 -259.373461) (xy 108.721152 -259.41412) (xy 108.742282 -259.458392)
			(xy 108.75663 -259.505303) (xy 108.76388 -259.55382) (xy 108.764324 -259.578348) (xy 108.764324 -259.578602)
			(xy 108.763815 -259.604569) (xy 108.7577 -259.643177) (xy 109.070903 -259.643177) (xy 109.070903 -259.591243)
			(xy 109.079028 -259.539948) (xy 109.095076 -259.490555) (xy 109.118654 -259.444281) (xy 109.14918 -259.402265)
			(xy 109.185903 -259.365542) (xy 109.227919 -259.335016) (xy 109.274193 -259.311438) (xy 109.323586 -259.29539)
			(xy 109.374881 -259.287265) (xy 109.426815 -259.287265) (xy 109.47811 -259.29539) (xy 109.527503 -259.311438)
			(xy 109.573777 -259.335016) (xy 109.615793 -259.365542) (xy 109.652516 -259.402265) (xy 109.683042 -259.444281)
			(xy 109.70662 -259.490555) (xy 109.722668 -259.539948) (xy 109.730793 -259.591243) (xy 109.731302 -259.61721)
			(xy 109.730793 -259.643177) (xy 110.010449 -259.643177) (xy 110.010449 -259.591243) (xy 110.018574 -259.539948)
			(xy 110.034622 -259.490555) (xy 110.0582 -259.444281) (xy 110.088726 -259.402265) (xy 110.125449 -259.365542)
			(xy 110.167465 -259.335016) (xy 110.213739 -259.311438) (xy 110.263132 -259.29539) (xy 110.314427 -259.287265)
			(xy 110.366361 -259.287265) (xy 110.417656 -259.29539) (xy 110.467049 -259.311438) (xy 110.513323 -259.335016)
			(xy 110.555339 -259.365542) (xy 110.592062 -259.402265) (xy 110.622588 -259.444281) (xy 110.646166 -259.490555)
			(xy 110.662214 -259.539948) (xy 110.670339 -259.591243) (xy 110.670848 -259.61721) (xy 110.670339 -259.643177)
			(xy 110.950757 -259.643177) (xy 110.950757 -259.591243) (xy 110.958882 -259.539948) (xy 110.97493 -259.490555)
			(xy 110.998508 -259.444281) (xy 111.029034 -259.402265) (xy 111.065757 -259.365542) (xy 111.107773 -259.335016)
			(xy 111.154047 -259.311438) (xy 111.20344 -259.29539) (xy 111.254735 -259.287265) (xy 111.306669 -259.287265)
			(xy 111.357964 -259.29539) (xy 111.407357 -259.311438) (xy 111.453631 -259.335016) (xy 111.495647 -259.365542)
			(xy 111.53237 -259.402265) (xy 111.562896 -259.444281) (xy 111.586474 -259.490555) (xy 111.602522 -259.539948)
			(xy 111.610647 -259.591243) (xy 111.611156 -259.61721) (xy 111.610647 -259.643177) (xy 111.890557 -259.643177)
			(xy 111.890557 -259.591243) (xy 111.898682 -259.539948) (xy 111.91473 -259.490555) (xy 111.938308 -259.444281)
			(xy 111.968834 -259.402265) (xy 112.005557 -259.365542) (xy 112.047573 -259.335016) (xy 112.093847 -259.311438)
			(xy 112.14324 -259.29539) (xy 112.194535 -259.287265) (xy 112.246469 -259.287265) (xy 112.297764 -259.29539)
			(xy 112.347157 -259.311438) (xy 112.393431 -259.335016) (xy 112.435447 -259.365542) (xy 112.47217 -259.402265)
			(xy 112.502696 -259.444281) (xy 112.526274 -259.490555) (xy 112.542322 -259.539948) (xy 112.550447 -259.591243)
			(xy 112.550956 -259.61721) (xy 112.550447 -259.643177) (xy 112.829849 -259.643177) (xy 112.829849 -259.591243)
			(xy 112.837974 -259.539948) (xy 112.854022 -259.490555) (xy 112.8776 -259.444281) (xy 112.908126 -259.402265)
			(xy 112.944849 -259.365542) (xy 112.986865 -259.335016) (xy 113.033139 -259.311438) (xy 113.082532 -259.29539)
			(xy 113.133827 -259.287265) (xy 113.185761 -259.287265) (xy 113.237056 -259.29539) (xy 113.286449 -259.311438)
			(xy 113.332723 -259.335016) (xy 113.374739 -259.365542) (xy 113.411462 -259.402265) (xy 113.441988 -259.444281)
			(xy 113.465566 -259.490555) (xy 113.481614 -259.539948) (xy 113.489739 -259.591243) (xy 113.490248 -259.61721)
			(xy 113.489739 -259.643177) (xy 113.770157 -259.643177) (xy 113.770157 -259.591243) (xy 113.778282 -259.539948)
			(xy 113.79433 -259.490555) (xy 113.817908 -259.444281) (xy 113.848434 -259.402265) (xy 113.885157 -259.365542)
			(xy 113.927173 -259.335016) (xy 113.973447 -259.311438) (xy 114.02284 -259.29539) (xy 114.074135 -259.287265)
			(xy 114.126069 -259.287265) (xy 114.177364 -259.29539) (xy 114.226757 -259.311438) (xy 114.273031 -259.335016)
			(xy 114.315047 -259.365542) (xy 114.35177 -259.402265) (xy 114.382296 -259.444281) (xy 114.405874 -259.490555)
			(xy 114.421922 -259.539948) (xy 114.430047 -259.591243) (xy 114.430556 -259.61721) (xy 114.430203 -259.635244)
			(xy 115.095782 -259.635244) (xy 115.095782 -259.63499) (xy 115.096232 -259.610463) (xy 115.103496 -259.561951)
			(xy 115.117848 -259.515044) (xy 115.138974 -259.470772) (xy 115.166408 -259.430108) (xy 115.18265 -259.411724)
			(xy 115.192413 -259.400202) (xy 115.205435 -259.372977) (xy 115.209913 -259.343133) (xy 115.205454 -259.313285)
			(xy 115.192449 -259.286052) (xy 115.18265 -259.274564) (xy 115.166424 -259.256166) (xy 115.138973 -259.215512)
			(xy 115.117839 -259.171245) (xy 115.103486 -259.124338) (xy 115.09623 -259.075825) (xy 115.095782 -259.051298)
			(xy 115.095782 -259.051044) (xy 115.096291 -259.025077) (xy 115.104416 -258.973782) (xy 115.120464 -258.924389)
			(xy 115.144042 -258.878115) (xy 115.174568 -258.836099) (xy 115.211291 -258.799376) (xy 115.253307 -258.76885)
			(xy 115.299581 -258.745272) (xy 115.348974 -258.729224) (xy 115.400269 -258.721099) (xy 115.452203 -258.721099)
			(xy 115.503498 -258.729224) (xy 115.552891 -258.745272) (xy 115.599165 -258.76885) (xy 115.641181 -258.799376)
			(xy 115.670912 -258.829107) (xy 121.757949 -258.829107) (xy 121.757949 -258.777173) (xy 121.766074 -258.725878)
			(xy 121.782122 -258.676485) (xy 121.8057 -258.630211) (xy 121.836226 -258.588195) (xy 121.872949 -258.551472)
			(xy 121.914965 -258.520946) (xy 121.961239 -258.497368) (xy 122.010632 -258.48132) (xy 122.061927 -258.473195)
			(xy 122.113861 -258.473195) (xy 122.165156 -258.48132) (xy 122.214549 -258.497368) (xy 122.260823 -258.520946)
			(xy 122.302839 -258.551472) (xy 122.339562 -258.588195) (xy 122.370088 -258.630211) (xy 122.393666 -258.676485)
			(xy 122.409714 -258.725878) (xy 122.417839 -258.777173) (xy 122.418348 -258.80314) (xy 122.417839 -258.829107)
			(xy 122.697749 -258.829107) (xy 122.697749 -258.777173) (xy 122.705874 -258.725878) (xy 122.721922 -258.676485)
			(xy 122.7455 -258.630211) (xy 122.776026 -258.588195) (xy 122.812749 -258.551472) (xy 122.854765 -258.520946)
			(xy 122.901039 -258.497368) (xy 122.950432 -258.48132) (xy 123.001727 -258.473195) (xy 123.053661 -258.473195)
			(xy 123.104956 -258.48132) (xy 123.154349 -258.497368) (xy 123.200623 -258.520946) (xy 123.242639 -258.551472)
			(xy 123.279362 -258.588195) (xy 123.309888 -258.630211) (xy 123.333466 -258.676485) (xy 123.349514 -258.725878)
			(xy 123.357639 -258.777173) (xy 123.358148 -258.80314) (xy 123.357639 -258.829107) (xy 123.637803 -258.829107)
			(xy 123.637803 -258.777173) (xy 123.645928 -258.725878) (xy 123.661976 -258.676485) (xy 123.685554 -258.630211)
			(xy 123.71608 -258.588195) (xy 123.752803 -258.551472) (xy 123.794819 -258.520946) (xy 123.841093 -258.497368)
			(xy 123.890486 -258.48132) (xy 123.941781 -258.473195) (xy 123.993715 -258.473195) (xy 124.04501 -258.48132)
			(xy 124.094403 -258.497368) (xy 124.140677 -258.520946) (xy 124.182693 -258.551472) (xy 124.219416 -258.588195)
			(xy 124.249942 -258.630211) (xy 124.27352 -258.676485) (xy 124.289568 -258.725878) (xy 124.297693 -258.777173)
			(xy 124.298202 -258.80314) (xy 124.297693 -258.829107) (xy 124.577603 -258.829107) (xy 124.577603 -258.777173)
			(xy 124.585728 -258.725878) (xy 124.601776 -258.676485) (xy 124.625354 -258.630211) (xy 124.65588 -258.588195)
			(xy 124.692603 -258.551472) (xy 124.734619 -258.520946) (xy 124.780893 -258.497368) (xy 124.830286 -258.48132)
			(xy 124.881581 -258.473195) (xy 124.933515 -258.473195) (xy 124.98481 -258.48132) (xy 125.034203 -258.497368)
			(xy 125.080477 -258.520946) (xy 125.122493 -258.551472) (xy 125.159216 -258.588195) (xy 125.189742 -258.630211)
			(xy 125.21332 -258.676485) (xy 125.229368 -258.725878) (xy 125.237493 -258.777173) (xy 125.238002 -258.80314)
			(xy 125.237493 -258.829107) (xy 125.517403 -258.829107) (xy 125.517403 -258.777173) (xy 125.525528 -258.725878)
			(xy 125.541576 -258.676485) (xy 125.565154 -258.630211) (xy 125.59568 -258.588195) (xy 125.632403 -258.551472)
			(xy 125.674419 -258.520946) (xy 125.720693 -258.497368) (xy 125.770086 -258.48132) (xy 125.821381 -258.473195)
			(xy 125.873315 -258.473195) (xy 125.92461 -258.48132) (xy 125.974003 -258.497368) (xy 126.020277 -258.520946)
			(xy 126.062293 -258.551472) (xy 126.099016 -258.588195) (xy 126.129542 -258.630211) (xy 126.15312 -258.676485)
			(xy 126.169168 -258.725878) (xy 126.177293 -258.777173) (xy 126.177802 -258.80314) (xy 126.177293 -258.829107)
			(xy 126.457203 -258.829107) (xy 126.457203 -258.777173) (xy 126.465328 -258.725878) (xy 126.481376 -258.676485)
			(xy 126.504954 -258.630211) (xy 126.53548 -258.588195) (xy 126.572203 -258.551472) (xy 126.614219 -258.520946)
			(xy 126.660493 -258.497368) (xy 126.709886 -258.48132) (xy 126.761181 -258.473195) (xy 126.813115 -258.473195)
			(xy 126.86441 -258.48132) (xy 126.913803 -258.497368) (xy 126.960077 -258.520946) (xy 127.002093 -258.551472)
			(xy 127.038816 -258.588195) (xy 127.069342 -258.630211) (xy 127.09292 -258.676485) (xy 127.108968 -258.725878)
			(xy 127.117093 -258.777173) (xy 127.117602 -258.80314) (xy 127.117093 -258.829107) (xy 127.397003 -258.829107)
			(xy 127.397003 -258.777173) (xy 127.405128 -258.725878) (xy 127.421176 -258.676485) (xy 127.444754 -258.630211)
			(xy 127.47528 -258.588195) (xy 127.512003 -258.551472) (xy 127.554019 -258.520946) (xy 127.600293 -258.497368)
			(xy 127.649686 -258.48132) (xy 127.700981 -258.473195) (xy 127.752915 -258.473195) (xy 127.80421 -258.48132)
			(xy 127.853603 -258.497368) (xy 127.899877 -258.520946) (xy 127.941893 -258.551472) (xy 127.978616 -258.588195)
			(xy 128.009142 -258.630211) (xy 128.03272 -258.676485) (xy 128.048768 -258.725878) (xy 128.056893 -258.777173)
			(xy 128.057402 -258.80314) (xy 128.056893 -258.829107) (xy 128.048768 -258.880402) (xy 128.03272 -258.929795)
			(xy 128.009142 -258.976069) (xy 127.978616 -259.018085) (xy 127.941893 -259.054808) (xy 127.899877 -259.085334)
			(xy 127.853603 -259.108912) (xy 127.80421 -259.12496) (xy 127.752915 -259.133085) (xy 127.700981 -259.133085)
			(xy 127.649686 -259.12496) (xy 127.600293 -259.108912) (xy 127.554019 -259.085334) (xy 127.512003 -259.054808)
			(xy 127.47528 -259.018085) (xy 127.444754 -258.976069) (xy 127.421176 -258.929795) (xy 127.405128 -258.880402)
			(xy 127.397003 -258.829107) (xy 127.117093 -258.829107) (xy 127.108968 -258.880402) (xy 127.09292 -258.929795)
			(xy 127.069342 -258.976069) (xy 127.038816 -259.018085) (xy 127.002093 -259.054808) (xy 126.960077 -259.085334)
			(xy 126.913803 -259.108912) (xy 126.86441 -259.12496) (xy 126.813115 -259.133085) (xy 126.761181 -259.133085)
			(xy 126.709886 -259.12496) (xy 126.660493 -259.108912) (xy 126.614219 -259.085334) (xy 126.572203 -259.054808)
			(xy 126.53548 -259.018085) (xy 126.504954 -258.976069) (xy 126.481376 -258.929795) (xy 126.465328 -258.880402)
			(xy 126.457203 -258.829107) (xy 126.177293 -258.829107) (xy 126.169168 -258.880402) (xy 126.15312 -258.929795)
			(xy 126.129542 -258.976069) (xy 126.099016 -259.018085) (xy 126.062293 -259.054808) (xy 126.020277 -259.085334)
			(xy 125.974003 -259.108912) (xy 125.92461 -259.12496) (xy 125.873315 -259.133085) (xy 125.821381 -259.133085)
			(xy 125.770086 -259.12496) (xy 125.720693 -259.108912) (xy 125.674419 -259.085334) (xy 125.632403 -259.054808)
			(xy 125.59568 -259.018085) (xy 125.565154 -258.976069) (xy 125.541576 -258.929795) (xy 125.525528 -258.880402)
			(xy 125.517403 -258.829107) (xy 125.237493 -258.829107) (xy 125.229368 -258.880402) (xy 125.21332 -258.929795)
			(xy 125.189742 -258.976069) (xy 125.159216 -259.018085) (xy 125.122493 -259.054808) (xy 125.080477 -259.085334)
			(xy 125.034203 -259.108912) (xy 124.98481 -259.12496) (xy 124.933515 -259.133085) (xy 124.881581 -259.133085)
			(xy 124.830286 -259.12496) (xy 124.780893 -259.108912) (xy 124.734619 -259.085334) (xy 124.692603 -259.054808)
			(xy 124.65588 -259.018085) (xy 124.625354 -258.976069) (xy 124.601776 -258.929795) (xy 124.585728 -258.880402)
			(xy 124.577603 -258.829107) (xy 124.297693 -258.829107) (xy 124.289568 -258.880402) (xy 124.27352 -258.929795)
			(xy 124.249942 -258.976069) (xy 124.219416 -259.018085) (xy 124.182693 -259.054808) (xy 124.140677 -259.085334)
			(xy 124.094403 -259.108912) (xy 124.04501 -259.12496) (xy 123.993715 -259.133085) (xy 123.941781 -259.133085)
			(xy 123.890486 -259.12496) (xy 123.841093 -259.108912) (xy 123.794819 -259.085334) (xy 123.752803 -259.054808)
			(xy 123.71608 -259.018085) (xy 123.685554 -258.976069) (xy 123.661976 -258.929795) (xy 123.645928 -258.880402)
			(xy 123.637803 -258.829107) (xy 123.357639 -258.829107) (xy 123.349514 -258.880402) (xy 123.333466 -258.929795)
			(xy 123.309888 -258.976069) (xy 123.279362 -259.018085) (xy 123.242639 -259.054808) (xy 123.200623 -259.085334)
			(xy 123.154349 -259.108912) (xy 123.104956 -259.12496) (xy 123.053661 -259.133085) (xy 123.001727 -259.133085)
			(xy 122.950432 -259.12496) (xy 122.901039 -259.108912) (xy 122.854765 -259.085334) (xy 122.812749 -259.054808)
			(xy 122.776026 -259.018085) (xy 122.7455 -258.976069) (xy 122.721922 -258.929795) (xy 122.705874 -258.880402)
			(xy 122.697749 -258.829107) (xy 122.417839 -258.829107) (xy 122.409714 -258.880402) (xy 122.393666 -258.929795)
			(xy 122.370088 -258.976069) (xy 122.339562 -259.018085) (xy 122.302839 -259.054808) (xy 122.260823 -259.085334)
			(xy 122.214549 -259.108912) (xy 122.165156 -259.12496) (xy 122.113861 -259.133085) (xy 122.061927 -259.133085)
			(xy 122.010632 -259.12496) (xy 121.961239 -259.108912) (xy 121.914965 -259.085334) (xy 121.872949 -259.054808)
			(xy 121.836226 -259.018085) (xy 121.8057 -258.976069) (xy 121.782122 -258.929795) (xy 121.766074 -258.880402)
			(xy 121.757949 -258.829107) (xy 115.670912 -258.829107) (xy 115.677904 -258.836099) (xy 115.70843 -258.878115)
			(xy 115.732008 -258.924389) (xy 115.748056 -258.973782) (xy 115.756181 -259.025077) (xy 115.75669 -259.051044)
			(xy 115.75669 -259.051298) (xy 115.75624 -259.075825) (xy 115.748977 -259.124338) (xy 115.734625 -259.171245)
			(xy 115.7135 -259.215517) (xy 115.686064 -259.256181) (xy 115.669822 -259.274564) (xy 115.659975 -259.286019)
			(xy 115.646967 -259.313269) (xy 115.642507 -259.343133) (xy 115.646986 -259.372994) (xy 115.660012 -259.400235)
			(xy 115.669822 -259.411724) (xy 115.686054 -259.430117) (xy 115.713501 -259.470773) (xy 115.734633 -259.515042)
			(xy 115.748985 -259.561949) (xy 115.756242 -259.610463) (xy 115.75669 -259.63499) (xy 115.75669 -259.635244)
			(xy 115.756181 -259.661211) (xy 115.748056 -259.712506) (xy 115.732008 -259.761899) (xy 115.725098 -259.775461)
			(xy 120.643999 -259.775461) (xy 120.643999 -259.723539) (xy 120.652121 -259.672255) (xy 120.668164 -259.622874)
			(xy 120.691734 -259.576609) (xy 120.722251 -259.534601) (xy 120.758963 -259.497884) (xy 120.800966 -259.46736)
			(xy 120.847227 -259.443783) (xy 120.896607 -259.427732) (xy 120.947889 -259.419603) (xy 120.97385 -259.41909)
			(xy 121.001224 -259.419636) (xy 121.055224 -259.428653) (xy 121.106999 -259.446447) (xy 121.155132 -259.472532)
			(xy 121.17705 -259.48894) (xy 121.188904 -259.497579) (xy 121.216236 -259.508204) (xy 121.245459 -259.510649)
			(xy 121.274177 -259.504714) (xy 121.300036 -259.490885) (xy 121.320918 -259.470297) (xy 121.328434 -259.457698)
			(xy 121.341003 -259.435827) (xy 121.37175 -259.39584) (xy 121.408216 -259.360989) (xy 121.449555 -259.332084)
			(xy 121.494805 -259.309797) (xy 121.542917 -259.294644) (xy 121.592773 -259.286978) (xy 121.617994 -259.286502)
			(xy 121.64396 -259.287072) (xy 121.695253 -259.295195) (xy 121.744644 -259.311243) (xy 121.790916 -259.334819)
			(xy 121.832931 -259.365343) (xy 121.869653 -259.402065) (xy 121.900178 -259.444079) (xy 121.923755 -259.49035)
			(xy 121.939803 -259.539741) (xy 121.947927 -259.591034) (xy 121.947927 -259.642923) (xy 122.227849 -259.642923)
			(xy 122.227849 -259.590989) (xy 122.235974 -259.539694) (xy 122.252022 -259.490301) (xy 122.2756 -259.444027)
			(xy 122.306126 -259.402011) (xy 122.342849 -259.365288) (xy 122.384865 -259.334762) (xy 122.431139 -259.311184)
			(xy 122.480532 -259.295136) (xy 122.531827 -259.287011) (xy 122.583761 -259.287011) (xy 122.635056 -259.295136)
			(xy 122.684449 -259.311184) (xy 122.730723 -259.334762) (xy 122.772739 -259.365288) (xy 122.809462 -259.402011)
			(xy 122.839988 -259.444027) (xy 122.863566 -259.490301) (xy 122.879614 -259.539694) (xy 122.887739 -259.590989)
			(xy 122.888248 -259.616956) (xy 122.887739 -259.642923) (xy 123.167649 -259.642923) (xy 123.167649 -259.590989)
			(xy 123.175774 -259.539694) (xy 123.191822 -259.490301) (xy 123.2154 -259.444027) (xy 123.245926 -259.402011)
			(xy 123.282649 -259.365288) (xy 123.324665 -259.334762) (xy 123.370939 -259.311184) (xy 123.420332 -259.295136)
			(xy 123.471627 -259.287011) (xy 123.523561 -259.287011) (xy 123.574856 -259.295136) (xy 123.624249 -259.311184)
			(xy 123.670523 -259.334762) (xy 123.712539 -259.365288) (xy 123.749262 -259.402011) (xy 123.779788 -259.444027)
			(xy 123.803366 -259.490301) (xy 123.819414 -259.539694) (xy 123.827539 -259.590989) (xy 123.828048 -259.616956)
			(xy 123.827539 -259.642923) (xy 124.107449 -259.642923) (xy 124.107449 -259.590989) (xy 124.115574 -259.539694)
			(xy 124.131622 -259.490301) (xy 124.1552 -259.444027) (xy 124.185726 -259.402011) (xy 124.222449 -259.365288)
			(xy 124.264465 -259.334762) (xy 124.310739 -259.311184) (xy 124.360132 -259.295136) (xy 124.411427 -259.287011)
			(xy 124.463361 -259.287011) (xy 124.514656 -259.295136) (xy 124.564049 -259.311184) (xy 124.610323 -259.334762)
			(xy 124.652339 -259.365288) (xy 124.689062 -259.402011) (xy 124.719588 -259.444027) (xy 124.743166 -259.490301)
			(xy 124.759214 -259.539694) (xy 124.767339 -259.590989) (xy 124.767848 -259.616956) (xy 124.767339 -259.642923)
			(xy 125.047249 -259.642923) (xy 125.047249 -259.590989) (xy 125.055374 -259.539694) (xy 125.071422 -259.490301)
			(xy 125.095 -259.444027) (xy 125.125526 -259.402011) (xy 125.162249 -259.365288) (xy 125.204265 -259.334762)
			(xy 125.250539 -259.311184) (xy 125.299932 -259.295136) (xy 125.351227 -259.287011) (xy 125.403161 -259.287011)
			(xy 125.454456 -259.295136) (xy 125.503849 -259.311184) (xy 125.550123 -259.334762) (xy 125.592139 -259.365288)
			(xy 125.628862 -259.402011) (xy 125.659388 -259.444027) (xy 125.682966 -259.490301) (xy 125.699014 -259.539694)
			(xy 125.707139 -259.590989) (xy 125.707648 -259.616956) (xy 125.707139 -259.642923) (xy 125.987049 -259.642923)
			(xy 125.987049 -259.590989) (xy 125.995174 -259.539694) (xy 126.011222 -259.490301) (xy 126.0348 -259.444027)
			(xy 126.065326 -259.402011) (xy 126.102049 -259.365288) (xy 126.144065 -259.334762) (xy 126.190339 -259.311184)
			(xy 126.239732 -259.295136) (xy 126.291027 -259.287011) (xy 126.342961 -259.287011) (xy 126.394256 -259.295136)
			(xy 126.443649 -259.311184) (xy 126.489923 -259.334762) (xy 126.531939 -259.365288) (xy 126.568662 -259.402011)
			(xy 126.599188 -259.444027) (xy 126.622766 -259.490301) (xy 126.638814 -259.539694) (xy 126.646939 -259.590989)
			(xy 126.647448 -259.616956) (xy 126.646939 -259.642923) (xy 126.926849 -259.642923) (xy 126.926849 -259.590989)
			(xy 126.934974 -259.539694) (xy 126.951022 -259.490301) (xy 126.9746 -259.444027) (xy 127.005126 -259.402011)
			(xy 127.041849 -259.365288) (xy 127.083865 -259.334762) (xy 127.130139 -259.311184) (xy 127.179532 -259.295136)
			(xy 127.230827 -259.287011) (xy 127.282761 -259.287011) (xy 127.334056 -259.295136) (xy 127.383449 -259.311184)
			(xy 127.429723 -259.334762) (xy 127.471739 -259.365288) (xy 127.508462 -259.402011) (xy 127.538988 -259.444027)
			(xy 127.562566 -259.490301) (xy 127.578614 -259.539694) (xy 127.586739 -259.590989) (xy 127.587248 -259.616956)
			(xy 127.586739 -259.642923) (xy 127.866649 -259.642923) (xy 127.866649 -259.590989) (xy 127.874774 -259.539694)
			(xy 127.890822 -259.490301) (xy 127.9144 -259.444027) (xy 127.944926 -259.402011) (xy 127.981649 -259.365288)
			(xy 128.023665 -259.334762) (xy 128.069939 -259.311184) (xy 128.119332 -259.295136) (xy 128.170627 -259.287011)
			(xy 128.222561 -259.287011) (xy 128.273856 -259.295136) (xy 128.323249 -259.311184) (xy 128.369523 -259.334762)
			(xy 128.411539 -259.365288) (xy 128.448262 -259.402011) (xy 128.478788 -259.444027) (xy 128.502366 -259.490301)
			(xy 128.518414 -259.539694) (xy 128.526539 -259.590989) (xy 128.527048 -259.616956) (xy 128.526539 -259.642923)
			(xy 128.806449 -259.642923) (xy 128.806449 -259.590989) (xy 128.814574 -259.539694) (xy 128.830622 -259.490301)
			(xy 128.8542 -259.444027) (xy 128.884726 -259.402011) (xy 128.921449 -259.365288) (xy 128.963465 -259.334762)
			(xy 129.009739 -259.311184) (xy 129.059132 -259.295136) (xy 129.110427 -259.287011) (xy 129.162361 -259.287011)
			(xy 129.213656 -259.295136) (xy 129.263049 -259.311184) (xy 129.309323 -259.334762) (xy 129.351339 -259.365288)
			(xy 129.388062 -259.402011) (xy 129.418588 -259.444027) (xy 129.442166 -259.490301) (xy 129.458214 -259.539694)
			(xy 129.466339 -259.590989) (xy 129.466848 -259.616956) (xy 129.466339 -259.642923) (xy 129.458214 -259.694218)
			(xy 129.442166 -259.743611) (xy 129.418588 -259.789885) (xy 129.388062 -259.831901) (xy 129.351339 -259.868624)
			(xy 129.309323 -259.89915) (xy 129.263049 -259.922728) (xy 129.213656 -259.938776) (xy 129.162361 -259.946901)
			(xy 129.110427 -259.946901) (xy 129.059132 -259.938776) (xy 129.009739 -259.922728) (xy 128.963465 -259.89915)
			(xy 128.921449 -259.868624) (xy 128.884726 -259.831901) (xy 128.8542 -259.789885) (xy 128.830622 -259.743611)
			(xy 128.814574 -259.694218) (xy 128.806449 -259.642923) (xy 128.526539 -259.642923) (xy 128.518414 -259.694218)
			(xy 128.502366 -259.743611) (xy 128.478788 -259.789885) (xy 128.448262 -259.831901) (xy 128.411539 -259.868624)
			(xy 128.369523 -259.89915) (xy 128.323249 -259.922728) (xy 128.273856 -259.938776) (xy 128.222561 -259.946901)
			(xy 128.170627 -259.946901) (xy 128.119332 -259.938776) (xy 128.069939 -259.922728) (xy 128.023665 -259.89915)
			(xy 127.981649 -259.868624) (xy 127.944926 -259.831901) (xy 127.9144 -259.789885) (xy 127.890822 -259.743611)
			(xy 127.874774 -259.694218) (xy 127.866649 -259.642923) (xy 127.586739 -259.642923) (xy 127.578614 -259.694218)
			(xy 127.562566 -259.743611) (xy 127.538988 -259.789885) (xy 127.508462 -259.831901) (xy 127.471739 -259.868624)
			(xy 127.429723 -259.89915) (xy 127.383449 -259.922728) (xy 127.334056 -259.938776) (xy 127.282761 -259.946901)
			(xy 127.230827 -259.946901) (xy 127.179532 -259.938776) (xy 127.130139 -259.922728) (xy 127.083865 -259.89915)
			(xy 127.041849 -259.868624) (xy 127.005126 -259.831901) (xy 126.9746 -259.789885) (xy 126.951022 -259.743611)
			(xy 126.934974 -259.694218) (xy 126.926849 -259.642923) (xy 126.646939 -259.642923) (xy 126.638814 -259.694218)
			(xy 126.622766 -259.743611) (xy 126.599188 -259.789885) (xy 126.568662 -259.831901) (xy 126.531939 -259.868624)
			(xy 126.489923 -259.89915) (xy 126.443649 -259.922728) (xy 126.394256 -259.938776) (xy 126.342961 -259.946901)
			(xy 126.291027 -259.946901) (xy 126.239732 -259.938776) (xy 126.190339 -259.922728) (xy 126.144065 -259.89915)
			(xy 126.102049 -259.868624) (xy 126.065326 -259.831901) (xy 126.0348 -259.789885) (xy 126.011222 -259.743611)
			(xy 125.995174 -259.694218) (xy 125.987049 -259.642923) (xy 125.707139 -259.642923) (xy 125.699014 -259.694218)
			(xy 125.682966 -259.743611) (xy 125.659388 -259.789885) (xy 125.628862 -259.831901) (xy 125.592139 -259.868624)
			(xy 125.550123 -259.89915) (xy 125.503849 -259.922728) (xy 125.454456 -259.938776) (xy 125.403161 -259.946901)
			(xy 125.351227 -259.946901) (xy 125.299932 -259.938776) (xy 125.250539 -259.922728) (xy 125.204265 -259.89915)
			(xy 125.162249 -259.868624) (xy 125.125526 -259.831901) (xy 125.095 -259.789885) (xy 125.071422 -259.743611)
			(xy 125.055374 -259.694218) (xy 125.047249 -259.642923) (xy 124.767339 -259.642923) (xy 124.759214 -259.694218)
			(xy 124.743166 -259.743611) (xy 124.719588 -259.789885) (xy 124.689062 -259.831901) (xy 124.652339 -259.868624)
			(xy 124.610323 -259.89915) (xy 124.564049 -259.922728) (xy 124.514656 -259.938776) (xy 124.463361 -259.946901)
			(xy 124.411427 -259.946901) (xy 124.360132 -259.938776) (xy 124.310739 -259.922728) (xy 124.264465 -259.89915)
			(xy 124.222449 -259.868624) (xy 124.185726 -259.831901) (xy 124.1552 -259.789885) (xy 124.131622 -259.743611)
			(xy 124.115574 -259.694218) (xy 124.107449 -259.642923) (xy 123.827539 -259.642923) (xy 123.819414 -259.694218)
			(xy 123.803366 -259.743611) (xy 123.779788 -259.789885) (xy 123.749262 -259.831901) (xy 123.712539 -259.868624)
			(xy 123.670523 -259.89915) (xy 123.624249 -259.922728) (xy 123.574856 -259.938776) (xy 123.523561 -259.946901)
			(xy 123.471627 -259.946901) (xy 123.420332 -259.938776) (xy 123.370939 -259.922728) (xy 123.324665 -259.89915)
			(xy 123.282649 -259.868624) (xy 123.245926 -259.831901) (xy 123.2154 -259.789885) (xy 123.191822 -259.743611)
			(xy 123.175774 -259.694218) (xy 123.167649 -259.642923) (xy 122.887739 -259.642923) (xy 122.879614 -259.694218)
			(xy 122.863566 -259.743611) (xy 122.839988 -259.789885) (xy 122.809462 -259.831901) (xy 122.772739 -259.868624)
			(xy 122.730723 -259.89915) (xy 122.684449 -259.922728) (xy 122.635056 -259.938776) (xy 122.583761 -259.946901)
			(xy 122.531827 -259.946901) (xy 122.480532 -259.938776) (xy 122.431139 -259.922728) (xy 122.384865 -259.89915)
			(xy 122.342849 -259.868624) (xy 122.306126 -259.831901) (xy 122.2756 -259.789885) (xy 122.252022 -259.743611)
			(xy 122.235974 -259.694218) (xy 122.227849 -259.642923) (xy 121.947927 -259.642923) (xy 121.947927 -259.642966)
			(xy 121.939803 -259.694259) (xy 121.923755 -259.74365) (xy 121.900178 -259.789921) (xy 121.869653 -259.831935)
			(xy 121.832931 -259.868657) (xy 121.790916 -259.899181) (xy 121.744644 -259.922757) (xy 121.695253 -259.938805)
			(xy 121.64396 -259.946928) (xy 121.617994 -259.94741) (xy 121.590619 -259.946893) (xy 121.536618 -259.937868)
			(xy 121.484843 -259.920065) (xy 121.43671 -259.893972) (xy 121.414794 -259.87756) (xy 121.402906 -259.868971)
			(xy 121.375586 -259.858341) (xy 121.346373 -259.855888) (xy 121.317662 -259.861814) (xy 121.291807 -259.875631)
			(xy 121.270927 -259.896209) (xy 121.26341 -259.908802) (xy 121.250809 -259.930654) (xy 121.220067 -259.970641)
			(xy 121.183606 -260.005492) (xy 121.142273 -260.034399) (xy 121.097028 -260.05669) (xy 121.048921 -260.071847)
			(xy 120.999069 -260.079519) (xy 120.97385 -260.079998) (xy 120.947889 -260.079397) (xy 120.896607 -260.071268)
			(xy 120.847227 -260.055217) (xy 120.800967 -260.03164) (xy 120.758963 -260.001116) (xy 120.722251 -259.964399)
			(xy 120.691734 -259.922391) (xy 120.668164 -259.876126) (xy 120.652121 -259.826745) (xy 120.643999 -259.775461)
			(xy 115.725098 -259.775461) (xy 115.70843 -259.808173) (xy 115.677904 -259.850189) (xy 115.641181 -259.886912)
			(xy 115.599165 -259.917438) (xy 115.552891 -259.941016) (xy 115.503498 -259.957064) (xy 115.452203 -259.965189)
			(xy 115.400269 -259.965189) (xy 115.348974 -259.957064) (xy 115.299581 -259.941016) (xy 115.253307 -259.917438)
			(xy 115.211291 -259.886912) (xy 115.174568 -259.850189) (xy 115.144042 -259.808173) (xy 115.120464 -259.761899)
			(xy 115.104416 -259.712506) (xy 115.096291 -259.661211) (xy 115.095782 -259.635244) (xy 114.430203 -259.635244)
			(xy 114.430047 -259.643177) (xy 114.421922 -259.694472) (xy 114.405874 -259.743865) (xy 114.382296 -259.790139)
			(xy 114.35177 -259.832155) (xy 114.315047 -259.868878) (xy 114.273031 -259.899404) (xy 114.226757 -259.922982)
			(xy 114.177364 -259.93903) (xy 114.126069 -259.947155) (xy 114.074135 -259.947155) (xy 114.02284 -259.93903)
			(xy 113.973447 -259.922982) (xy 113.927173 -259.899404) (xy 113.885157 -259.868878) (xy 113.848434 -259.832155)
			(xy 113.817908 -259.790139) (xy 113.79433 -259.743865) (xy 113.778282 -259.694472) (xy 113.770157 -259.643177)
			(xy 113.489739 -259.643177) (xy 113.481614 -259.694472) (xy 113.465566 -259.743865) (xy 113.441988 -259.790139)
			(xy 113.411462 -259.832155) (xy 113.374739 -259.868878) (xy 113.332723 -259.899404) (xy 113.286449 -259.922982)
			(xy 113.237056 -259.93903) (xy 113.185761 -259.947155) (xy 113.133827 -259.947155) (xy 113.082532 -259.93903)
			(xy 113.033139 -259.922982) (xy 112.986865 -259.899404) (xy 112.944849 -259.868878) (xy 112.908126 -259.832155)
			(xy 112.8776 -259.790139) (xy 112.854022 -259.743865) (xy 112.837974 -259.694472) (xy 112.829849 -259.643177)
			(xy 112.550447 -259.643177) (xy 112.542322 -259.694472) (xy 112.526274 -259.743865) (xy 112.502696 -259.790139)
			(xy 112.47217 -259.832155) (xy 112.435447 -259.868878) (xy 112.393431 -259.899404) (xy 112.347157 -259.922982)
			(xy 112.297764 -259.93903) (xy 112.246469 -259.947155) (xy 112.194535 -259.947155) (xy 112.14324 -259.93903)
			(xy 112.093847 -259.922982) (xy 112.047573 -259.899404) (xy 112.005557 -259.868878) (xy 111.968834 -259.832155)
			(xy 111.938308 -259.790139) (xy 111.91473 -259.743865) (xy 111.898682 -259.694472) (xy 111.890557 -259.643177)
			(xy 111.610647 -259.643177) (xy 111.602522 -259.694472) (xy 111.586474 -259.743865) (xy 111.562896 -259.790139)
			(xy 111.53237 -259.832155) (xy 111.495647 -259.868878) (xy 111.453631 -259.899404) (xy 111.407357 -259.922982)
			(xy 111.357964 -259.93903) (xy 111.306669 -259.947155) (xy 111.254735 -259.947155) (xy 111.20344 -259.93903)
			(xy 111.154047 -259.922982) (xy 111.107773 -259.899404) (xy 111.065757 -259.868878) (xy 111.029034 -259.832155)
			(xy 110.998508 -259.790139) (xy 110.97493 -259.743865) (xy 110.958882 -259.694472) (xy 110.950757 -259.643177)
			(xy 110.670339 -259.643177) (xy 110.662214 -259.694472) (xy 110.646166 -259.743865) (xy 110.622588 -259.790139)
			(xy 110.592062 -259.832155) (xy 110.555339 -259.868878) (xy 110.513323 -259.899404) (xy 110.467049 -259.922982)
			(xy 110.417656 -259.93903) (xy 110.366361 -259.947155) (xy 110.314427 -259.947155) (xy 110.263132 -259.93903)
			(xy 110.213739 -259.922982) (xy 110.167465 -259.899404) (xy 110.125449 -259.868878) (xy 110.088726 -259.832155)
			(xy 110.0582 -259.790139) (xy 110.034622 -259.743865) (xy 110.018574 -259.694472) (xy 110.010449 -259.643177)
			(xy 109.730793 -259.643177) (xy 109.722668 -259.694472) (xy 109.70662 -259.743865) (xy 109.683042 -259.790139)
			(xy 109.652516 -259.832155) (xy 109.615793 -259.868878) (xy 109.573777 -259.899404) (xy 109.527503 -259.922982)
			(xy 109.47811 -259.93903) (xy 109.426815 -259.947155) (xy 109.374881 -259.947155) (xy 109.323586 -259.93903)
			(xy 109.274193 -259.922982) (xy 109.227919 -259.899404) (xy 109.185903 -259.868878) (xy 109.14918 -259.832155)
			(xy 109.118654 -259.790139) (xy 109.095076 -259.743865) (xy 109.079028 -259.694472) (xy 109.070903 -259.643177)
			(xy 108.7577 -259.643177) (xy 108.75569 -259.655864) (xy 108.739642 -259.705257) (xy 108.716064 -259.751531)
			(xy 108.685538 -259.793547) (xy 108.648815 -259.83027) (xy 108.606799 -259.860796) (xy 108.560525 -259.884374)
			(xy 108.511132 -259.900422) (xy 108.459837 -259.908547) (xy 108.407903 -259.908547) (xy 108.356608 -259.900422)
			(xy 108.307215 -259.884374) (xy 108.260941 -259.860796) (xy 108.218925 -259.83027) (xy 108.182202 -259.793547)
			(xy 108.151676 -259.751531) (xy 108.128098 -259.705257) (xy 108.11205 -259.655864) (xy 108.103925 -259.604569)
			(xy 108.103416 -259.578602) (xy 103.175075 -259.578602) (xy 103.188264 -259.619196) (xy 103.196389 -259.670491)
			(xy 103.196898 -259.696458) (xy 103.196389 -259.722425) (xy 103.188264 -259.77372) (xy 103.172216 -259.823113)
			(xy 103.148638 -259.869387) (xy 103.118112 -259.911403) (xy 103.081389 -259.948126) (xy 103.039373 -259.978652)
			(xy 102.993099 -260.00223) (xy 102.943706 -260.018278) (xy 102.892411 -260.026403) (xy 102.840477 -260.026403)
			(xy 102.789182 -260.018278) (xy 102.739789 -260.00223) (xy 102.693515 -259.978652) (xy 102.651499 -259.948126)
			(xy 102.614776 -259.911403) (xy 102.58425 -259.869387) (xy 102.560672 -259.823113) (xy 102.544624 -259.77372)
			(xy 102.536499 -259.722425) (xy 102.194849 -259.722425) (xy 102.187966 -259.743611) (xy 102.164388 -259.789885)
			(xy 102.133862 -259.831901) (xy 102.097139 -259.868624) (xy 102.055123 -259.89915) (xy 102.008849 -259.922728)
			(xy 101.959456 -259.938776) (xy 101.908161 -259.946901) (xy 101.856227 -259.946901) (xy 101.804932 -259.938776)
			(xy 101.755539 -259.922728) (xy 101.709265 -259.89915) (xy 101.667249 -259.868624) (xy 101.630526 -259.831901)
			(xy 101.6 -259.789885) (xy 101.576422 -259.743611) (xy 101.560374 -259.694218) (xy 101.552249 -259.642923)
			(xy 101.272339 -259.642923) (xy 101.264214 -259.694218) (xy 101.248166 -259.743611) (xy 101.224588 -259.789885)
			(xy 101.194062 -259.831901) (xy 101.157339 -259.868624) (xy 101.115323 -259.89915) (xy 101.069049 -259.922728)
			(xy 101.019656 -259.938776) (xy 100.968361 -259.946901) (xy 100.916427 -259.946901) (xy 100.865132 -259.938776)
			(xy 100.815739 -259.922728) (xy 100.769465 -259.89915) (xy 100.727449 -259.868624) (xy 100.690726 -259.831901)
			(xy 100.6602 -259.789885) (xy 100.636622 -259.743611) (xy 100.620574 -259.694218) (xy 100.612449 -259.642923)
			(xy 100.332539 -259.642923) (xy 100.324414 -259.694218) (xy 100.308366 -259.743611) (xy 100.284788 -259.789885)
			(xy 100.254262 -259.831901) (xy 100.217539 -259.868624) (xy 100.175523 -259.89915) (xy 100.129249 -259.922728)
			(xy 100.079856 -259.938776) (xy 100.028561 -259.946901) (xy 99.976627 -259.946901) (xy 99.925332 -259.938776)
			(xy 99.875939 -259.922728) (xy 99.829665 -259.89915) (xy 99.787649 -259.868624) (xy 99.750926 -259.831901)
			(xy 99.7204 -259.789885) (xy 99.696822 -259.743611) (xy 99.680774 -259.694218) (xy 99.672649 -259.642923)
			(xy 99.392739 -259.642923) (xy 99.384614 -259.694218) (xy 99.368566 -259.743611) (xy 99.344988 -259.789885)
			(xy 99.314462 -259.831901) (xy 99.277739 -259.868624) (xy 99.235723 -259.89915) (xy 99.189449 -259.922728)
			(xy 99.140056 -259.938776) (xy 99.088761 -259.946901) (xy 99.036827 -259.946901) (xy 98.985532 -259.938776)
			(xy 98.936139 -259.922728) (xy 98.889865 -259.89915) (xy 98.847849 -259.868624) (xy 98.811126 -259.831901)
			(xy 98.7806 -259.789885) (xy 98.757022 -259.743611) (xy 98.740974 -259.694218) (xy 98.732849 -259.642923)
			(xy 98.453193 -259.642923) (xy 98.445068 -259.694218) (xy 98.42902 -259.743611) (xy 98.405442 -259.789885)
			(xy 98.374916 -259.831901) (xy 98.338193 -259.868624) (xy 98.296177 -259.89915) (xy 98.249903 -259.922728)
			(xy 98.20051 -259.938776) (xy 98.149215 -259.946901) (xy 98.097281 -259.946901) (xy 98.045986 -259.938776)
			(xy 97.996593 -259.922728) (xy 97.950319 -259.89915) (xy 97.908303 -259.868624) (xy 97.87158 -259.831901)
			(xy 97.841054 -259.789885) (xy 97.817476 -259.743611) (xy 97.801428 -259.694218) (xy 97.793303 -259.642923)
			(xy 97.513139 -259.642923) (xy 97.505014 -259.694218) (xy 97.488966 -259.743611) (xy 97.465388 -259.789885)
			(xy 97.434862 -259.831901) (xy 97.398139 -259.868624) (xy 97.356123 -259.89915) (xy 97.309849 -259.922728)
			(xy 97.260456 -259.938776) (xy 97.209161 -259.946901) (xy 97.157227 -259.946901) (xy 97.105932 -259.938776)
			(xy 97.056539 -259.922728) (xy 97.010265 -259.89915) (xy 96.968249 -259.868624) (xy 96.931526 -259.831901)
			(xy 96.901 -259.789885) (xy 96.877422 -259.743611) (xy 96.861374 -259.694218) (xy 96.853249 -259.642923)
			(xy 96.573339 -259.642923) (xy 96.565214 -259.694218) (xy 96.549166 -259.743611) (xy 96.525588 -259.789885)
			(xy 96.495062 -259.831901) (xy 96.458339 -259.868624) (xy 96.416323 -259.89915) (xy 96.370049 -259.922728)
			(xy 96.320656 -259.938776) (xy 96.269361 -259.946901) (xy 96.217427 -259.946901) (xy 96.166132 -259.938776)
			(xy 96.116739 -259.922728) (xy 96.070465 -259.89915) (xy 96.028449 -259.868624) (xy 95.991726 -259.831901)
			(xy 95.9612 -259.789885) (xy 95.937622 -259.743611) (xy 95.921574 -259.694218) (xy 95.913449 -259.642923)
			(xy 95.633539 -259.642923) (xy 95.625414 -259.694218) (xy 95.609366 -259.743611) (xy 95.585788 -259.789885)
			(xy 95.555262 -259.831901) (xy 95.518539 -259.868624) (xy 95.476523 -259.89915) (xy 95.430249 -259.922728)
			(xy 95.380856 -259.938776) (xy 95.329561 -259.946901) (xy 95.277627 -259.946901) (xy 95.226332 -259.938776)
			(xy 95.176939 -259.922728) (xy 95.130665 -259.89915) (xy 95.088649 -259.868624) (xy 95.051926 -259.831901)
			(xy 95.0214 -259.789885) (xy 94.997822 -259.743611) (xy 94.981774 -259.694218) (xy 94.973649 -259.642923)
			(xy 94.693739 -259.642923) (xy 94.685614 -259.694218) (xy 94.669566 -259.743611) (xy 94.645988 -259.789885)
			(xy 94.615462 -259.831901) (xy 94.578739 -259.868624) (xy 94.536723 -259.89915) (xy 94.490449 -259.922728)
			(xy 94.441056 -259.938776) (xy 94.389761 -259.946901) (xy 94.337827 -259.946901) (xy 94.286532 -259.938776)
			(xy 94.237139 -259.922728) (xy 94.190865 -259.89915) (xy 94.148849 -259.868624) (xy 94.112126 -259.831901)
			(xy 94.0816 -259.789885) (xy 94.058022 -259.743611) (xy 94.041974 -259.694218) (xy 94.033849 -259.642923)
			(xy 93.753939 -259.642923) (xy 93.745814 -259.694218) (xy 93.729766 -259.743611) (xy 93.706188 -259.789885)
			(xy 93.675662 -259.831901) (xy 93.638939 -259.868624) (xy 93.596923 -259.89915) (xy 93.550649 -259.922728)
			(xy 93.501256 -259.938776) (xy 93.449961 -259.946901) (xy 93.398027 -259.946901) (xy 93.346732 -259.938776)
			(xy 93.297339 -259.922728) (xy 93.251065 -259.89915) (xy 93.209049 -259.868624) (xy 93.172326 -259.831901)
			(xy 93.1418 -259.789885) (xy 93.118222 -259.743611) (xy 93.102174 -259.694218) (xy 93.094049 -259.642923)
			(xy 92.814139 -259.642923) (xy 92.806014 -259.694218) (xy 92.789966 -259.743611) (xy 92.766388 -259.789885)
			(xy 92.735862 -259.831901) (xy 92.699139 -259.868624) (xy 92.657123 -259.89915) (xy 92.610849 -259.922728)
			(xy 92.561456 -259.938776) (xy 92.510161 -259.946901) (xy 92.458227 -259.946901) (xy 92.406932 -259.938776)
			(xy 92.357539 -259.922728) (xy 92.311265 -259.89915) (xy 92.269249 -259.868624) (xy 92.232526 -259.831901)
			(xy 92.202 -259.789885) (xy 92.178422 -259.743611) (xy 92.162374 -259.694218) (xy 92.154249 -259.642923)
			(xy 91.873978 -259.642923) (xy 91.872053 -259.667854) (xy 91.860353 -259.717523) (xy 91.841159 -259.764805)
			(xy 91.814927 -259.808575) (xy 91.78228 -259.847794) (xy 91.743995 -259.881531) (xy 91.722702 -259.895594)
			(xy 91.712034 -259.902452) (xy 91.68765 -259.945124) (xy 91.68765 -260.063996) (xy 91.688004 -260.072881)
			(xy 91.69416 -260.089552) (xy 91.705712 -260.103056) (xy 91.713304 -260.107684) (xy 91.790012 -260.150356)
			(xy 91.795734 -260.153319) (xy 91.808209 -260.156527) (xy 91.81465 -260.156706) (xy 91.840304 -260.14934)
			(xy 91.845892 -260.146038) (xy 91.871546 -260.131619) (xy 91.926702 -260.11112) (xy 91.984618 -260.100718)
			(xy 92.01404 -260.100064) (xy 92.014294 -260.100064) (xy 92.040286 -260.100547) (xy 92.091629 -260.108678)
			(xy 92.141069 -260.124741) (xy 92.187387 -260.14834) (xy 92.229443 -260.178895) (xy 92.266201 -260.215653)
			(xy 92.296756 -260.257708) (xy 92.320357 -260.304026) (xy 92.336421 -260.353465) (xy 92.344553 -260.404808)
			(xy 92.344553 -260.456739) (xy 92.624403 -260.456739) (xy 92.624403 -260.404805) (xy 92.632528 -260.35351)
			(xy 92.648576 -260.304117) (xy 92.672154 -260.257843) (xy 92.70268 -260.215827) (xy 92.739403 -260.179104)
			(xy 92.781419 -260.148578) (xy 92.827693 -260.125) (xy 92.877086 -260.108952) (xy 92.928381 -260.100827)
			(xy 92.980315 -260.100827) (xy 93.03161 -260.108952) (xy 93.081003 -260.125) (xy 93.127277 -260.148578)
			(xy 93.169293 -260.179104) (xy 93.206016 -260.215827) (xy 93.236542 -260.257843) (xy 93.26012 -260.304117)
			(xy 93.276168 -260.35351) (xy 93.284293 -260.404805) (xy 93.284802 -260.430772) (xy 93.284293 -260.456739)
			(xy 93.564203 -260.456739) (xy 93.564203 -260.404805) (xy 93.572328 -260.35351) (xy 93.588376 -260.304117)
			(xy 93.611954 -260.257843) (xy 93.64248 -260.215827) (xy 93.679203 -260.179104) (xy 93.721219 -260.148578)
			(xy 93.767493 -260.125) (xy 93.816886 -260.108952) (xy 93.868181 -260.100827) (xy 93.920115 -260.100827)
			(xy 93.97141 -260.108952) (xy 94.020803 -260.125) (xy 94.067077 -260.148578) (xy 94.109093 -260.179104)
			(xy 94.145816 -260.215827) (xy 94.176342 -260.257843) (xy 94.19992 -260.304117) (xy 94.215968 -260.35351)
			(xy 94.224093 -260.404805) (xy 94.224602 -260.430772) (xy 94.224093 -260.456739) (xy 94.503495 -260.456739)
			(xy 94.503495 -260.404805) (xy 94.51162 -260.35351) (xy 94.527668 -260.304117) (xy 94.551246 -260.257843)
			(xy 94.581772 -260.215827) (xy 94.618495 -260.179104) (xy 94.660511 -260.148578) (xy 94.706785 -260.125)
			(xy 94.756178 -260.108952) (xy 94.807473 -260.100827) (xy 94.859407 -260.100827) (xy 94.910702 -260.108952)
			(xy 94.960095 -260.125) (xy 95.006369 -260.148578) (xy 95.048385 -260.179104) (xy 95.085108 -260.215827)
			(xy 95.115634 -260.257843) (xy 95.139212 -260.304117) (xy 95.15526 -260.35351) (xy 95.163385 -260.404805)
			(xy 95.163894 -260.430772) (xy 95.163385 -260.456739) (xy 95.443803 -260.456739) (xy 95.443803 -260.404805)
			(xy 95.451928 -260.35351) (xy 95.467976 -260.304117) (xy 95.491554 -260.257843) (xy 95.52208 -260.215827)
			(xy 95.558803 -260.179104) (xy 95.600819 -260.148578) (xy 95.647093 -260.125) (xy 95.696486 -260.108952)
			(xy 95.747781 -260.100827) (xy 95.799715 -260.100827) (xy 95.85101 -260.108952) (xy 95.900403 -260.125)
			(xy 95.946677 -260.148578) (xy 95.988693 -260.179104) (xy 96.025416 -260.215827) (xy 96.055942 -260.257843)
			(xy 96.07952 -260.304117) (xy 96.095568 -260.35351) (xy 96.103693 -260.404805) (xy 96.104202 -260.430772)
			(xy 96.103693 -260.456739) (xy 96.383095 -260.456739) (xy 96.383095 -260.404805) (xy 96.39122 -260.35351)
			(xy 96.407268 -260.304117) (xy 96.430846 -260.257843) (xy 96.461372 -260.215827) (xy 96.498095 -260.179104)
			(xy 96.540111 -260.148578) (xy 96.586385 -260.125) (xy 96.635778 -260.108952) (xy 96.687073 -260.100827)
			(xy 96.739007 -260.100827) (xy 96.790302 -260.108952) (xy 96.839695 -260.125) (xy 96.885969 -260.148578)
			(xy 96.927985 -260.179104) (xy 96.964708 -260.215827) (xy 96.995234 -260.257843) (xy 97.018812 -260.304117)
			(xy 97.03486 -260.35351) (xy 97.042985 -260.404805) (xy 97.043494 -260.430772) (xy 97.042985 -260.456739)
			(xy 97.323403 -260.456739) (xy 97.323403 -260.404805) (xy 97.331528 -260.35351) (xy 97.347576 -260.304117)
			(xy 97.371154 -260.257843) (xy 97.40168 -260.215827) (xy 97.438403 -260.179104) (xy 97.480419 -260.148578)
			(xy 97.526693 -260.125) (xy 97.576086 -260.108952) (xy 97.627381 -260.100827) (xy 97.679315 -260.100827)
			(xy 97.73061 -260.108952) (xy 97.780003 -260.125) (xy 97.826277 -260.148578) (xy 97.868293 -260.179104)
			(xy 97.905016 -260.215827) (xy 97.935542 -260.257843) (xy 97.95912 -260.304117) (xy 97.975168 -260.35351)
			(xy 97.983293 -260.404805) (xy 97.983802 -260.430772) (xy 97.983293 -260.456739) (xy 98.262949 -260.456739)
			(xy 98.262949 -260.404805) (xy 98.271074 -260.35351) (xy 98.287122 -260.304117) (xy 98.3107 -260.257843)
			(xy 98.341226 -260.215827) (xy 98.377949 -260.179104) (xy 98.419965 -260.148578) (xy 98.466239 -260.125)
			(xy 98.515632 -260.108952) (xy 98.566927 -260.100827) (xy 98.618861 -260.100827) (xy 98.670156 -260.108952)
			(xy 98.719549 -260.125) (xy 98.765823 -260.148578) (xy 98.807839 -260.179104) (xy 98.844562 -260.215827)
			(xy 98.875088 -260.257843) (xy 98.898666 -260.304117) (xy 98.914714 -260.35351) (xy 98.922839 -260.404805)
			(xy 98.923348 -260.430772) (xy 98.922839 -260.456739) (xy 99.203003 -260.456739) (xy 99.203003 -260.404805)
			(xy 99.211128 -260.35351) (xy 99.227176 -260.304117) (xy 99.250754 -260.257843) (xy 99.28128 -260.215827)
			(xy 99.318003 -260.179104) (xy 99.360019 -260.148578) (xy 99.406293 -260.125) (xy 99.455686 -260.108952)
			(xy 99.506981 -260.100827) (xy 99.558915 -260.100827) (xy 99.61021 -260.108952) (xy 99.659603 -260.125)
			(xy 99.705877 -260.148578) (xy 99.747893 -260.179104) (xy 99.784616 -260.215827) (xy 99.815142 -260.257843)
			(xy 99.83872 -260.304117) (xy 99.854768 -260.35351) (xy 99.862893 -260.404805) (xy 99.863402 -260.430772)
			(xy 99.862893 -260.456739) (xy 100.142803 -260.456739) (xy 100.142803 -260.404805) (xy 100.150928 -260.35351)
			(xy 100.166976 -260.304117) (xy 100.190554 -260.257843) (xy 100.22108 -260.215827) (xy 100.257803 -260.179104)
			(xy 100.299819 -260.148578) (xy 100.346093 -260.125) (xy 100.395486 -260.108952) (xy 100.446781 -260.100827)
			(xy 100.498715 -260.100827) (xy 100.55001 -260.108952) (xy 100.599403 -260.125) (xy 100.645677 -260.148578)
			(xy 100.687693 -260.179104) (xy 100.724416 -260.215827) (xy 100.754942 -260.257843) (xy 100.77852 -260.304117)
			(xy 100.794568 -260.35351) (xy 100.802693 -260.404805) (xy 100.803202 -260.430772) (xy 100.802693 -260.456739)
			(xy 101.082603 -260.456739) (xy 101.082603 -260.404805) (xy 101.090728 -260.35351) (xy 101.106776 -260.304117)
			(xy 101.130354 -260.257843) (xy 101.16088 -260.215827) (xy 101.197603 -260.179104) (xy 101.239619 -260.148578)
			(xy 101.285893 -260.125) (xy 101.335286 -260.108952) (xy 101.386581 -260.100827) (xy 101.438515 -260.100827)
			(xy 101.48981 -260.108952) (xy 101.539203 -260.125) (xy 101.585477 -260.148578) (xy 101.627493 -260.179104)
			(xy 101.664216 -260.215827) (xy 101.694742 -260.257843) (xy 101.71832 -260.304117) (xy 101.734368 -260.35351)
			(xy 101.742493 -260.404805) (xy 101.743002 -260.430772) (xy 101.742493 -260.456739) (xy 101.742487 -260.456774)
			(xy 102.022301 -260.456774) (xy 102.022301 -260.404826) (xy 102.030428 -260.353518) (xy 102.046482 -260.304113)
			(xy 102.070068 -260.257828) (xy 102.100605 -260.215804) (xy 102.13734 -260.179074) (xy 102.179369 -260.148543)
			(xy 102.225658 -260.124964) (xy 102.275065 -260.108917) (xy 102.326374 -260.100797) (xy 102.352348 -260.100318)
			(xy 102.379433 -260.10093) (xy 102.432877 -260.109757) (xy 102.484166 -260.127184) (xy 102.531926 -260.152744)
			(xy 102.574877 -260.185751) (xy 102.611869 -260.225323) (xy 102.64191 -260.270398) (xy 102.664197 -260.31977)
			(xy 102.678132 -260.372115) (xy 102.681278 -260.399022) (xy 102.683079 -260.413169) (xy 102.693479 -260.439712)
			(xy 102.71082 -260.462338) (xy 102.733745 -260.479281) (xy 102.760465 -260.489217) (xy 102.788891 -260.491369)
			(xy 102.802944 -260.488938) (xy 102.819398 -260.485756) (xy 102.852735 -260.48232) (xy 102.869492 -260.48208)
			(xy 102.895464 -260.482494) (xy 102.94677 -260.490619) (xy 102.996172 -260.50667) (xy 103.042456 -260.530252)
			(xy 103.084481 -260.560783) (xy 103.121211 -260.597513) (xy 103.151744 -260.639537) (xy 103.175327 -260.68582)
			(xy 103.191379 -260.735222) (xy 103.199505 -260.786528) (xy 103.199505 -260.838472) (xy 103.191379 -260.889778)
			(xy 103.175327 -260.93918) (xy 103.151744 -260.985463) (xy 103.121211 -261.027487) (xy 103.084481 -261.064217)
			(xy 103.042456 -261.094748) (xy 102.996172 -261.11833) (xy 102.94677 -261.134381) (xy 102.895464 -261.142506)
			(xy 102.869492 -261.142988) (xy 102.842406 -261.142426) (xy 102.788959 -261.133589) (xy 102.73767 -261.116154)
			(xy 102.68991 -261.090587) (xy 102.64696 -261.057574) (xy 102.609969 -261.017997) (xy 102.579929 -260.972917)
			(xy 102.557643 -260.923542) (xy 102.543708 -260.871192) (xy 102.540562 -260.844284) (xy 102.53871 -260.830146)
			(xy 102.528317 -260.80361) (xy 102.510986 -260.780987) (xy 102.488071 -260.764043) (xy 102.461362 -260.754103)
			(xy 102.432946 -260.751943) (xy 102.418896 -260.754368) (xy 102.402444 -260.757559) (xy 102.369105 -260.760989)
			(xy 102.352348 -260.761226) (xy 102.326374 -260.760803) (xy 102.275065 -260.752683) (xy 102.225658 -260.736636)
			(xy 102.179369 -260.713057) (xy 102.13734 -260.682526) (xy 102.100605 -260.645796) (xy 102.070068 -260.603772)
			(xy 102.046482 -260.557487) (xy 102.030428 -260.508082) (xy 102.022301 -260.456774) (xy 101.742487 -260.456774)
			(xy 101.734368 -260.508034) (xy 101.71832 -260.557427) (xy 101.694742 -260.603701) (xy 101.664216 -260.645717)
			(xy 101.627493 -260.68244) (xy 101.585477 -260.712966) (xy 101.539203 -260.736544) (xy 101.48981 -260.752592)
			(xy 101.438515 -260.760717) (xy 101.386581 -260.760717) (xy 101.335286 -260.752592) (xy 101.285893 -260.736544)
			(xy 101.239619 -260.712966) (xy 101.197603 -260.68244) (xy 101.16088 -260.645717) (xy 101.130354 -260.603701)
			(xy 101.106776 -260.557427) (xy 101.090728 -260.508034) (xy 101.082603 -260.456739) (xy 100.802693 -260.456739)
			(xy 100.794568 -260.508034) (xy 100.77852 -260.557427) (xy 100.754942 -260.603701) (xy 100.724416 -260.645717)
			(xy 100.687693 -260.68244) (xy 100.645677 -260.712966) (xy 100.599403 -260.736544) (xy 100.55001 -260.752592)
			(xy 100.498715 -260.760717) (xy 100.446781 -260.760717) (xy 100.395486 -260.752592) (xy 100.346093 -260.736544)
			(xy 100.299819 -260.712966) (xy 100.257803 -260.68244) (xy 100.22108 -260.645717) (xy 100.190554 -260.603701)
			(xy 100.166976 -260.557427) (xy 100.150928 -260.508034) (xy 100.142803 -260.456739) (xy 99.862893 -260.456739)
			(xy 99.854768 -260.508034) (xy 99.83872 -260.557427) (xy 99.815142 -260.603701) (xy 99.784616 -260.645717)
			(xy 99.747893 -260.68244) (xy 99.705877 -260.712966) (xy 99.659603 -260.736544) (xy 99.61021 -260.752592)
			(xy 99.558915 -260.760717) (xy 99.506981 -260.760717) (xy 99.455686 -260.752592) (xy 99.406293 -260.736544)
			(xy 99.360019 -260.712966) (xy 99.318003 -260.68244) (xy 99.28128 -260.645717) (xy 99.250754 -260.603701)
			(xy 99.227176 -260.557427) (xy 99.211128 -260.508034) (xy 99.203003 -260.456739) (xy 98.922839 -260.456739)
			(xy 98.914714 -260.508034) (xy 98.898666 -260.557427) (xy 98.875088 -260.603701) (xy 98.844562 -260.645717)
			(xy 98.807839 -260.68244) (xy 98.765823 -260.712966) (xy 98.719549 -260.736544) (xy 98.670156 -260.752592)
			(xy 98.618861 -260.760717) (xy 98.566927 -260.760717) (xy 98.515632 -260.752592) (xy 98.466239 -260.736544)
			(xy 98.419965 -260.712966) (xy 98.377949 -260.68244) (xy 98.341226 -260.645717) (xy 98.3107 -260.603701)
			(xy 98.287122 -260.557427) (xy 98.271074 -260.508034) (xy 98.262949 -260.456739) (xy 97.983293 -260.456739)
			(xy 97.975168 -260.508034) (xy 97.95912 -260.557427) (xy 97.935542 -260.603701) (xy 97.905016 -260.645717)
			(xy 97.868293 -260.68244) (xy 97.826277 -260.712966) (xy 97.780003 -260.736544) (xy 97.73061 -260.752592)
			(xy 97.679315 -260.760717) (xy 97.627381 -260.760717) (xy 97.576086 -260.752592) (xy 97.526693 -260.736544)
			(xy 97.480419 -260.712966) (xy 97.438403 -260.68244) (xy 97.40168 -260.645717) (xy 97.371154 -260.603701)
			(xy 97.347576 -260.557427) (xy 97.331528 -260.508034) (xy 97.323403 -260.456739) (xy 97.042985 -260.456739)
			(xy 97.03486 -260.508034) (xy 97.018812 -260.557427) (xy 96.995234 -260.603701) (xy 96.964708 -260.645717)
			(xy 96.927985 -260.68244) (xy 96.885969 -260.712966) (xy 96.839695 -260.736544) (xy 96.790302 -260.752592)
			(xy 96.739007 -260.760717) (xy 96.687073 -260.760717) (xy 96.635778 -260.752592) (xy 96.586385 -260.736544)
			(xy 96.540111 -260.712966) (xy 96.498095 -260.68244) (xy 96.461372 -260.645717) (xy 96.430846 -260.603701)
			(xy 96.407268 -260.557427) (xy 96.39122 -260.508034) (xy 96.383095 -260.456739) (xy 96.103693 -260.456739)
			(xy 96.095568 -260.508034) (xy 96.07952 -260.557427) (xy 96.055942 -260.603701) (xy 96.025416 -260.645717)
			(xy 95.988693 -260.68244) (xy 95.946677 -260.712966) (xy 95.900403 -260.736544) (xy 95.85101 -260.752592)
			(xy 95.799715 -260.760717) (xy 95.747781 -260.760717) (xy 95.696486 -260.752592) (xy 95.647093 -260.736544)
			(xy 95.600819 -260.712966) (xy 95.558803 -260.68244) (xy 95.52208 -260.645717) (xy 95.491554 -260.603701)
			(xy 95.467976 -260.557427) (xy 95.451928 -260.508034) (xy 95.443803 -260.456739) (xy 95.163385 -260.456739)
			(xy 95.15526 -260.508034) (xy 95.139212 -260.557427) (xy 95.115634 -260.603701) (xy 95.085108 -260.645717)
			(xy 95.048385 -260.68244) (xy 95.006369 -260.712966) (xy 94.960095 -260.736544) (xy 94.910702 -260.752592)
			(xy 94.859407 -260.760717) (xy 94.807473 -260.760717) (xy 94.756178 -260.752592) (xy 94.706785 -260.736544)
			(xy 94.660511 -260.712966) (xy 94.618495 -260.68244) (xy 94.581772 -260.645717) (xy 94.551246 -260.603701)
			(xy 94.527668 -260.557427) (xy 94.51162 -260.508034) (xy 94.503495 -260.456739) (xy 94.224093 -260.456739)
			(xy 94.215968 -260.508034) (xy 94.19992 -260.557427) (xy 94.176342 -260.603701) (xy 94.145816 -260.645717)
			(xy 94.109093 -260.68244) (xy 94.067077 -260.712966) (xy 94.020803 -260.736544) (xy 93.97141 -260.752592)
			(xy 93.920115 -260.760717) (xy 93.868181 -260.760717) (xy 93.816886 -260.752592) (xy 93.767493 -260.736544)
			(xy 93.721219 -260.712966) (xy 93.679203 -260.68244) (xy 93.64248 -260.645717) (xy 93.611954 -260.603701)
			(xy 93.588376 -260.557427) (xy 93.572328 -260.508034) (xy 93.564203 -260.456739) (xy 93.284293 -260.456739)
			(xy 93.276168 -260.508034) (xy 93.26012 -260.557427) (xy 93.236542 -260.603701) (xy 93.206016 -260.645717)
			(xy 93.169293 -260.68244) (xy 93.127277 -260.712966) (xy 93.081003 -260.736544) (xy 93.03161 -260.752592)
			(xy 92.980315 -260.760717) (xy 92.928381 -260.760717) (xy 92.877086 -260.752592) (xy 92.827693 -260.736544)
			(xy 92.781419 -260.712966) (xy 92.739403 -260.68244) (xy 92.70268 -260.645717) (xy 92.672154 -260.603701)
			(xy 92.648576 -260.557427) (xy 92.632528 -260.508034) (xy 92.624403 -260.456739) (xy 92.344553 -260.456739)
			(xy 92.344553 -260.456792) (xy 92.336421 -260.508135) (xy 92.320357 -260.557574) (xy 92.296756 -260.603892)
			(xy 92.266201 -260.645947) (xy 92.229443 -260.682705) (xy 92.187387 -260.71326) (xy 92.141069 -260.736859)
			(xy 92.091629 -260.752922) (xy 92.040286 -260.761053) (xy 92.014294 -260.76148) (xy 92.01404 -260.76148)
			(xy 91.984621 -260.760815) (xy 91.926715 -260.750382) (xy 91.871553 -260.729908) (xy 91.845892 -260.715506)
			(xy 91.840304 -260.712204) (xy 91.81465 -260.704838) (xy 91.808208 -260.705005) (xy 91.795734 -260.708223)
			(xy 91.790012 -260.711188) (xy 91.713304 -260.75386) (xy 91.705715 -260.758498) (xy 91.694152 -260.771995)
			(xy 91.68798 -260.788662) (xy 91.68765 -260.797548) (xy 91.68765 -260.916928) (xy 91.712034 -260.959346)
			(xy 91.718638 -260.963664) (xy 91.740359 -260.977714) (xy 91.779549 -261.011477) (xy 91.813006 -261.050929)
			(xy 91.839912 -261.095108) (xy 91.859613 -261.142938) (xy 91.871627 -261.193252) (xy 91.875663 -261.244822)
			(xy 91.873626 -261.270809) (xy 92.154249 -261.270809) (xy 92.154249 -261.218875) (xy 92.162374 -261.16758)
			(xy 92.178422 -261.118187) (xy 92.202 -261.071913) (xy 92.232526 -261.029897) (xy 92.269249 -260.993174)
			(xy 92.311265 -260.962648) (xy 92.357539 -260.93907) (xy 92.406932 -260.923022) (xy 92.458227 -260.914897)
			(xy 92.510161 -260.914897) (xy 92.561456 -260.923022) (xy 92.610849 -260.93907) (xy 92.657123 -260.962648)
			(xy 92.699139 -260.993174) (xy 92.735862 -261.029897) (xy 92.766388 -261.071913) (xy 92.789966 -261.118187)
			(xy 92.806014 -261.16758) (xy 92.814139 -261.218875) (xy 92.814648 -261.244842) (xy 92.814139 -261.270809)
			(xy 93.094049 -261.270809) (xy 93.094049 -261.218875) (xy 93.102174 -261.16758) (xy 93.118222 -261.118187)
			(xy 93.1418 -261.071913) (xy 93.172326 -261.029897) (xy 93.209049 -260.993174) (xy 93.251065 -260.962648)
			(xy 93.297339 -260.93907) (xy 93.346732 -260.923022) (xy 93.398027 -260.914897) (xy 93.449961 -260.914897)
			(xy 93.501256 -260.923022) (xy 93.550649 -260.93907) (xy 93.596923 -260.962648) (xy 93.638939 -260.993174)
			(xy 93.675662 -261.029897) (xy 93.706188 -261.071913) (xy 93.729766 -261.118187) (xy 93.745814 -261.16758)
			(xy 93.753939 -261.218875) (xy 93.754448 -261.244842) (xy 93.753939 -261.270809) (xy 94.033849 -261.270809)
			(xy 94.033849 -261.218875) (xy 94.041974 -261.16758) (xy 94.058022 -261.118187) (xy 94.0816 -261.071913)
			(xy 94.112126 -261.029897) (xy 94.148849 -260.993174) (xy 94.190865 -260.962648) (xy 94.237139 -260.93907)
			(xy 94.286532 -260.923022) (xy 94.337827 -260.914897) (xy 94.389761 -260.914897) (xy 94.441056 -260.923022)
			(xy 94.490449 -260.93907) (xy 94.536723 -260.962648) (xy 94.578739 -260.993174) (xy 94.615462 -261.029897)
			(xy 94.645988 -261.071913) (xy 94.669566 -261.118187) (xy 94.685614 -261.16758) (xy 94.693739 -261.218875)
			(xy 94.694248 -261.244842) (xy 94.693739 -261.270809) (xy 94.973649 -261.270809) (xy 94.973649 -261.218875)
			(xy 94.981774 -261.16758) (xy 94.997822 -261.118187) (xy 95.0214 -261.071913) (xy 95.051926 -261.029897)
			(xy 95.088649 -260.993174) (xy 95.130665 -260.962648) (xy 95.176939 -260.93907) (xy 95.226332 -260.923022)
			(xy 95.277627 -260.914897) (xy 95.329561 -260.914897) (xy 95.380856 -260.923022) (xy 95.430249 -260.93907)
			(xy 95.476523 -260.962648) (xy 95.518539 -260.993174) (xy 95.555262 -261.029897) (xy 95.585788 -261.071913)
			(xy 95.609366 -261.118187) (xy 95.625414 -261.16758) (xy 95.633539 -261.218875) (xy 95.634048 -261.244842)
			(xy 95.633539 -261.270809) (xy 95.913449 -261.270809) (xy 95.913449 -261.218875) (xy 95.921574 -261.16758)
			(xy 95.937622 -261.118187) (xy 95.9612 -261.071913) (xy 95.991726 -261.029897) (xy 96.028449 -260.993174)
			(xy 96.070465 -260.962648) (xy 96.116739 -260.93907) (xy 96.166132 -260.923022) (xy 96.217427 -260.914897)
			(xy 96.269361 -260.914897) (xy 96.320656 -260.923022) (xy 96.370049 -260.93907) (xy 96.416323 -260.962648)
			(xy 96.458339 -260.993174) (xy 96.495062 -261.029897) (xy 96.525588 -261.071913) (xy 96.549166 -261.118187)
			(xy 96.565214 -261.16758) (xy 96.573339 -261.218875) (xy 96.573848 -261.244842) (xy 96.573339 -261.270809)
			(xy 96.853249 -261.270809) (xy 96.853249 -261.218875) (xy 96.861374 -261.16758) (xy 96.877422 -261.118187)
			(xy 96.901 -261.071913) (xy 96.931526 -261.029897) (xy 96.968249 -260.993174) (xy 97.010265 -260.962648)
			(xy 97.056539 -260.93907) (xy 97.105932 -260.923022) (xy 97.157227 -260.914897) (xy 97.209161 -260.914897)
			(xy 97.260456 -260.923022) (xy 97.309849 -260.93907) (xy 97.356123 -260.962648) (xy 97.398139 -260.993174)
			(xy 97.434862 -261.029897) (xy 97.465388 -261.071913) (xy 97.488966 -261.118187) (xy 97.505014 -261.16758)
			(xy 97.513139 -261.218875) (xy 97.513648 -261.244842) (xy 97.513139 -261.270809) (xy 97.793049 -261.270809)
			(xy 97.793049 -261.218875) (xy 97.801174 -261.16758) (xy 97.817222 -261.118187) (xy 97.8408 -261.071913)
			(xy 97.871326 -261.029897) (xy 97.908049 -260.993174) (xy 97.950065 -260.962648) (xy 97.996339 -260.93907)
			(xy 98.045732 -260.923022) (xy 98.097027 -260.914897) (xy 98.148961 -260.914897) (xy 98.200256 -260.923022)
			(xy 98.249649 -260.93907) (xy 98.295923 -260.962648) (xy 98.337939 -260.993174) (xy 98.374662 -261.029897)
			(xy 98.405188 -261.071913) (xy 98.428766 -261.118187) (xy 98.444814 -261.16758) (xy 98.452939 -261.218875)
			(xy 98.453448 -261.244842) (xy 98.452939 -261.270809) (xy 98.732849 -261.270809) (xy 98.732849 -261.218875)
			(xy 98.740974 -261.16758) (xy 98.757022 -261.118187) (xy 98.7806 -261.071913) (xy 98.811126 -261.029897)
			(xy 98.847849 -260.993174) (xy 98.889865 -260.962648) (xy 98.936139 -260.93907) (xy 98.985532 -260.923022)
			(xy 99.036827 -260.914897) (xy 99.088761 -260.914897) (xy 99.140056 -260.923022) (xy 99.189449 -260.93907)
			(xy 99.235723 -260.962648) (xy 99.277739 -260.993174) (xy 99.314462 -261.029897) (xy 99.344988 -261.071913)
			(xy 99.368566 -261.118187) (xy 99.384614 -261.16758) (xy 99.392739 -261.218875) (xy 99.393248 -261.244842)
			(xy 99.392739 -261.270809) (xy 99.672649 -261.270809) (xy 99.672649 -261.218875) (xy 99.680774 -261.16758)
			(xy 99.696822 -261.118187) (xy 99.7204 -261.071913) (xy 99.750926 -261.029897) (xy 99.787649 -260.993174)
			(xy 99.829665 -260.962648) (xy 99.875939 -260.93907) (xy 99.925332 -260.923022) (xy 99.976627 -260.914897)
			(xy 100.028561 -260.914897) (xy 100.079856 -260.923022) (xy 100.129249 -260.93907) (xy 100.175523 -260.962648)
			(xy 100.217539 -260.993174) (xy 100.254262 -261.029897) (xy 100.284788 -261.071913) (xy 100.308366 -261.118187)
			(xy 100.324414 -261.16758) (xy 100.332539 -261.218875) (xy 100.333048 -261.244842) (xy 100.332539 -261.270809)
			(xy 100.612449 -261.270809) (xy 100.612449 -261.218875) (xy 100.620574 -261.16758) (xy 100.636622 -261.118187)
			(xy 100.6602 -261.071913) (xy 100.690726 -261.029897) (xy 100.727449 -260.993174) (xy 100.769465 -260.962648)
			(xy 100.815739 -260.93907) (xy 100.865132 -260.923022) (xy 100.916427 -260.914897) (xy 100.968361 -260.914897)
			(xy 101.019656 -260.923022) (xy 101.069049 -260.93907) (xy 101.115323 -260.962648) (xy 101.157339 -260.993174)
			(xy 101.194062 -261.029897) (xy 101.224588 -261.071913) (xy 101.248166 -261.118187) (xy 101.264214 -261.16758)
			(xy 101.272339 -261.218875) (xy 101.272848 -261.244842) (xy 101.272339 -261.270809) (xy 101.552249 -261.270809)
			(xy 101.552249 -261.218875) (xy 101.560374 -261.16758) (xy 101.576422 -261.118187) (xy 101.6 -261.071913)
			(xy 101.630526 -261.029897) (xy 101.667249 -260.993174) (xy 101.709265 -260.962648) (xy 101.755539 -260.93907)
			(xy 101.804932 -260.923022) (xy 101.856227 -260.914897) (xy 101.908161 -260.914897) (xy 101.959456 -260.923022)
			(xy 102.008849 -260.93907) (xy 102.055123 -260.962648) (xy 102.097139 -260.993174) (xy 102.133862 -261.029897)
			(xy 102.164388 -261.071913) (xy 102.187966 -261.118187) (xy 102.204014 -261.16758) (xy 102.212139 -261.218875)
			(xy 102.212648 -261.244842) (xy 102.212139 -261.270809) (xy 102.204014 -261.322104) (xy 102.187966 -261.371497)
			(xy 102.164388 -261.417771) (xy 102.133862 -261.459787) (xy 102.097139 -261.49651) (xy 102.055123 -261.527036)
			(xy 102.008849 -261.550614) (xy 101.959456 -261.566662) (xy 101.908161 -261.574787) (xy 101.856227 -261.574787)
			(xy 101.804932 -261.566662) (xy 101.755539 -261.550614) (xy 101.709265 -261.527036) (xy 101.667249 -261.49651)
			(xy 101.630526 -261.459787) (xy 101.6 -261.417771) (xy 101.576422 -261.371497) (xy 101.560374 -261.322104)
			(xy 101.552249 -261.270809) (xy 101.272339 -261.270809) (xy 101.264214 -261.322104) (xy 101.248166 -261.371497)
			(xy 101.224588 -261.417771) (xy 101.194062 -261.459787) (xy 101.157339 -261.49651) (xy 101.115323 -261.527036)
			(xy 101.069049 -261.550614) (xy 101.019656 -261.566662) (xy 100.968361 -261.574787) (xy 100.916427 -261.574787)
			(xy 100.865132 -261.566662) (xy 100.815739 -261.550614) (xy 100.769465 -261.527036) (xy 100.727449 -261.49651)
			(xy 100.690726 -261.459787) (xy 100.6602 -261.417771) (xy 100.636622 -261.371497) (xy 100.620574 -261.322104)
			(xy 100.612449 -261.270809) (xy 100.332539 -261.270809) (xy 100.324414 -261.322104) (xy 100.308366 -261.371497)
			(xy 100.284788 -261.417771) (xy 100.254262 -261.459787) (xy 100.217539 -261.49651) (xy 100.175523 -261.527036)
			(xy 100.129249 -261.550614) (xy 100.079856 -261.566662) (xy 100.028561 -261.574787) (xy 99.976627 -261.574787)
			(xy 99.925332 -261.566662) (xy 99.875939 -261.550614) (xy 99.829665 -261.527036) (xy 99.787649 -261.49651)
			(xy 99.750926 -261.459787) (xy 99.7204 -261.417771) (xy 99.696822 -261.371497) (xy 99.680774 -261.322104)
			(xy 99.672649 -261.270809) (xy 99.392739 -261.270809) (xy 99.384614 -261.322104) (xy 99.368566 -261.371497)
			(xy 99.344988 -261.417771) (xy 99.314462 -261.459787) (xy 99.277739 -261.49651) (xy 99.235723 -261.527036)
			(xy 99.189449 -261.550614) (xy 99.140056 -261.566662) (xy 99.088761 -261.574787) (xy 99.036827 -261.574787)
			(xy 98.985532 -261.566662) (xy 98.936139 -261.550614) (xy 98.889865 -261.527036) (xy 98.847849 -261.49651)
			(xy 98.811126 -261.459787) (xy 98.7806 -261.417771) (xy 98.757022 -261.371497) (xy 98.740974 -261.322104)
			(xy 98.732849 -261.270809) (xy 98.452939 -261.270809) (xy 98.444814 -261.322104) (xy 98.428766 -261.371497)
			(xy 98.405188 -261.417771) (xy 98.374662 -261.459787) (xy 98.337939 -261.49651) (xy 98.295923 -261.527036)
			(xy 98.249649 -261.550614) (xy 98.200256 -261.566662) (xy 98.148961 -261.574787) (xy 98.097027 -261.574787)
			(xy 98.045732 -261.566662) (xy 97.996339 -261.550614) (xy 97.950065 -261.527036) (xy 97.908049 -261.49651)
			(xy 97.871326 -261.459787) (xy 97.8408 -261.417771) (xy 97.817222 -261.371497) (xy 97.801174 -261.322104)
			(xy 97.793049 -261.270809) (xy 97.513139 -261.270809) (xy 97.505014 -261.322104) (xy 97.488966 -261.371497)
			(xy 97.465388 -261.417771) (xy 97.434862 -261.459787) (xy 97.398139 -261.49651) (xy 97.356123 -261.527036)
			(xy 97.309849 -261.550614) (xy 97.260456 -261.566662) (xy 97.209161 -261.574787) (xy 97.157227 -261.574787)
			(xy 97.105932 -261.566662) (xy 97.056539 -261.550614) (xy 97.010265 -261.527036) (xy 96.968249 -261.49651)
			(xy 96.931526 -261.459787) (xy 96.901 -261.417771) (xy 96.877422 -261.371497) (xy 96.861374 -261.322104)
			(xy 96.853249 -261.270809) (xy 96.573339 -261.270809) (xy 96.565214 -261.322104) (xy 96.549166 -261.371497)
			(xy 96.525588 -261.417771) (xy 96.495062 -261.459787) (xy 96.458339 -261.49651) (xy 96.416323 -261.527036)
			(xy 96.370049 -261.550614) (xy 96.320656 -261.566662) (xy 96.269361 -261.574787) (xy 96.217427 -261.574787)
			(xy 96.166132 -261.566662) (xy 96.116739 -261.550614) (xy 96.070465 -261.527036) (xy 96.028449 -261.49651)
			(xy 95.991726 -261.459787) (xy 95.9612 -261.417771) (xy 95.937622 -261.371497) (xy 95.921574 -261.322104)
			(xy 95.913449 -261.270809) (xy 95.633539 -261.270809) (xy 95.625414 -261.322104) (xy 95.609366 -261.371497)
			(xy 95.585788 -261.417771) (xy 95.555262 -261.459787) (xy 95.518539 -261.49651) (xy 95.476523 -261.527036)
			(xy 95.430249 -261.550614) (xy 95.380856 -261.566662) (xy 95.329561 -261.574787) (xy 95.277627 -261.574787)
			(xy 95.226332 -261.566662) (xy 95.176939 -261.550614) (xy 95.130665 -261.527036) (xy 95.088649 -261.49651)
			(xy 95.051926 -261.459787) (xy 95.0214 -261.417771) (xy 94.997822 -261.371497) (xy 94.981774 -261.322104)
			(xy 94.973649 -261.270809) (xy 94.693739 -261.270809) (xy 94.685614 -261.322104) (xy 94.669566 -261.371497)
			(xy 94.645988 -261.417771) (xy 94.615462 -261.459787) (xy 94.578739 -261.49651) (xy 94.536723 -261.527036)
			(xy 94.490449 -261.550614) (xy 94.441056 -261.566662) (xy 94.389761 -261.574787) (xy 94.337827 -261.574787)
			(xy 94.286532 -261.566662) (xy 94.237139 -261.550614) (xy 94.190865 -261.527036) (xy 94.148849 -261.49651)
			(xy 94.112126 -261.459787) (xy 94.0816 -261.417771) (xy 94.058022 -261.371497) (xy 94.041974 -261.322104)
			(xy 94.033849 -261.270809) (xy 93.753939 -261.270809) (xy 93.745814 -261.322104) (xy 93.729766 -261.371497)
			(xy 93.706188 -261.417771) (xy 93.675662 -261.459787) (xy 93.638939 -261.49651) (xy 93.596923 -261.527036)
			(xy 93.550649 -261.550614) (xy 93.501256 -261.566662) (xy 93.449961 -261.574787) (xy 93.398027 -261.574787)
			(xy 93.346732 -261.566662) (xy 93.297339 -261.550614) (xy 93.251065 -261.527036) (xy 93.209049 -261.49651)
			(xy 93.172326 -261.459787) (xy 93.1418 -261.417771) (xy 93.118222 -261.371497) (xy 93.102174 -261.322104)
			(xy 93.094049 -261.270809) (xy 92.814139 -261.270809) (xy 92.806014 -261.322104) (xy 92.789966 -261.371497)
			(xy 92.766388 -261.417771) (xy 92.735862 -261.459787) (xy 92.699139 -261.49651) (xy 92.657123 -261.527036)
			(xy 92.610849 -261.550614) (xy 92.561456 -261.566662) (xy 92.510161 -261.574787) (xy 92.458227 -261.574787)
			(xy 92.406932 -261.566662) (xy 92.357539 -261.550614) (xy 92.311265 -261.527036) (xy 92.269249 -261.49651)
			(xy 92.232526 -261.459787) (xy 92.202 -261.417771) (xy 92.178422 -261.371497) (xy 92.162374 -261.322104)
			(xy 92.154249 -261.270809) (xy 91.873626 -261.270809) (xy 91.87162 -261.296392) (xy 91.859599 -261.346704)
			(xy 91.839892 -261.394531) (xy 91.81298 -261.438707) (xy 91.779518 -261.478155) (xy 91.740323 -261.511912)
			(xy 91.718638 -261.52602) (xy 91.712034 -261.530338) (xy 91.68765 -261.572756) (xy 91.68765 -261.692136)
			(xy 91.68801 -261.701018) (xy 91.694176 -261.717677) (xy 91.70573 -261.73117) (xy 91.713304 -261.735824)
			(xy 91.751658 -261.75716) (xy 91.791536 -261.779258) (xy 91.799316 -261.782866) (xy 91.816299 -261.785161)
			(xy 91.833076 -261.781667) (xy 91.840558 -261.77748) (xy 91.840812 -261.777226) (xy 91.860483 -261.765547)
			(xy 91.902355 -261.747123) (xy 91.946365 -261.734638) (xy 91.991675 -261.728333) (xy 92.014548 -261.72795)
			(xy 92.040536 -261.728463) (xy 92.091871 -261.736601) (xy 92.141302 -261.752668) (xy 92.18761 -261.776269)
			(xy 92.229657 -261.806824) (xy 92.266407 -261.843579) (xy 92.296956 -261.885631) (xy 92.32055 -261.931943)
			(xy 92.33661 -261.981376) (xy 92.344741 -262.032712) (xy 92.344741 -262.084625) (xy 92.624403 -262.084625)
			(xy 92.624403 -262.032691) (xy 92.632528 -261.981396) (xy 92.648576 -261.932003) (xy 92.672154 -261.885729)
			(xy 92.70268 -261.843713) (xy 92.739403 -261.80699) (xy 92.781419 -261.776464) (xy 92.827693 -261.752886)
			(xy 92.877086 -261.736838) (xy 92.928381 -261.728713) (xy 92.980315 -261.728713) (xy 93.03161 -261.736838)
			(xy 93.081003 -261.752886) (xy 93.127277 -261.776464) (xy 93.169293 -261.80699) (xy 93.206016 -261.843713)
			(xy 93.236542 -261.885729) (xy 93.26012 -261.932003) (xy 93.276168 -261.981396) (xy 93.284293 -262.032691)
			(xy 93.284802 -262.058658) (xy 93.284293 -262.084625) (xy 93.564203 -262.084625) (xy 93.564203 -262.032691)
			(xy 93.572328 -261.981396) (xy 93.588376 -261.932003) (xy 93.611954 -261.885729) (xy 93.64248 -261.843713)
			(xy 93.679203 -261.80699) (xy 93.721219 -261.776464) (xy 93.767493 -261.752886) (xy 93.816886 -261.736838)
			(xy 93.868181 -261.728713) (xy 93.920115 -261.728713) (xy 93.97141 -261.736838) (xy 94.020803 -261.752886)
			(xy 94.067077 -261.776464) (xy 94.109093 -261.80699) (xy 94.145816 -261.843713) (xy 94.176342 -261.885729)
			(xy 94.19992 -261.932003) (xy 94.215968 -261.981396) (xy 94.224093 -262.032691) (xy 94.224602 -262.058658)
			(xy 94.224093 -262.084625) (xy 94.504003 -262.084625) (xy 94.504003 -262.032691) (xy 94.512128 -261.981396)
			(xy 94.528176 -261.932003) (xy 94.551754 -261.885729) (xy 94.58228 -261.843713) (xy 94.619003 -261.80699)
			(xy 94.661019 -261.776464) (xy 94.707293 -261.752886) (xy 94.756686 -261.736838) (xy 94.807981 -261.728713)
			(xy 94.859915 -261.728713) (xy 94.91121 -261.736838) (xy 94.960603 -261.752886) (xy 95.006877 -261.776464)
			(xy 95.048893 -261.80699) (xy 95.085616 -261.843713) (xy 95.116142 -261.885729) (xy 95.13972 -261.932003)
			(xy 95.155768 -261.981396) (xy 95.163893 -262.032691) (xy 95.164402 -262.058658) (xy 95.163893 -262.084625)
			(xy 95.443803 -262.084625) (xy 95.443803 -262.032691) (xy 95.451928 -261.981396) (xy 95.467976 -261.932003)
			(xy 95.491554 -261.885729) (xy 95.52208 -261.843713) (xy 95.558803 -261.80699) (xy 95.600819 -261.776464)
			(xy 95.647093 -261.752886) (xy 95.696486 -261.736838) (xy 95.747781 -261.728713) (xy 95.799715 -261.728713)
			(xy 95.85101 -261.736838) (xy 95.900403 -261.752886) (xy 95.946677 -261.776464) (xy 95.988693 -261.80699)
			(xy 96.025416 -261.843713) (xy 96.055942 -261.885729) (xy 96.07952 -261.932003) (xy 96.095568 -261.981396)
			(xy 96.103693 -262.032691) (xy 96.104202 -262.058658) (xy 96.103693 -262.084625) (xy 96.383603 -262.084625)
			(xy 96.383603 -262.032691) (xy 96.391728 -261.981396) (xy 96.407776 -261.932003) (xy 96.431354 -261.885729)
			(xy 96.46188 -261.843713) (xy 96.498603 -261.80699) (xy 96.540619 -261.776464) (xy 96.586893 -261.752886)
			(xy 96.636286 -261.736838) (xy 96.687581 -261.728713) (xy 96.739515 -261.728713) (xy 96.79081 -261.736838)
			(xy 96.840203 -261.752886) (xy 96.886477 -261.776464) (xy 96.928493 -261.80699) (xy 96.965216 -261.843713)
			(xy 96.995742 -261.885729) (xy 97.01932 -261.932003) (xy 97.035368 -261.981396) (xy 97.043493 -262.032691)
			(xy 97.044002 -262.058658) (xy 97.043493 -262.084625) (xy 97.323149 -262.084625) (xy 97.323149 -262.032691)
			(xy 97.331274 -261.981396) (xy 97.347322 -261.932003) (xy 97.3709 -261.885729) (xy 97.401426 -261.843713)
			(xy 97.438149 -261.80699) (xy 97.480165 -261.776464) (xy 97.526439 -261.752886) (xy 97.575832 -261.736838)
			(xy 97.627127 -261.728713) (xy 97.679061 -261.728713) (xy 97.730356 -261.736838) (xy 97.779749 -261.752886)
			(xy 97.826023 -261.776464) (xy 97.868039 -261.80699) (xy 97.904762 -261.843713) (xy 97.935288 -261.885729)
			(xy 97.958866 -261.932003) (xy 97.974914 -261.981396) (xy 97.983039 -262.032691) (xy 97.983548 -262.058658)
			(xy 97.983039 -262.084625) (xy 98.263203 -262.084625) (xy 98.263203 -262.032691) (xy 98.271328 -261.981396)
			(xy 98.287376 -261.932003) (xy 98.310954 -261.885729) (xy 98.34148 -261.843713) (xy 98.378203 -261.80699)
			(xy 98.420219 -261.776464) (xy 98.466493 -261.752886) (xy 98.515886 -261.736838) (xy 98.567181 -261.728713)
			(xy 98.619115 -261.728713) (xy 98.67041 -261.736838) (xy 98.719803 -261.752886) (xy 98.766077 -261.776464)
			(xy 98.808093 -261.80699) (xy 98.844816 -261.843713) (xy 98.875342 -261.885729) (xy 98.89892 -261.932003)
			(xy 98.914968 -261.981396) (xy 98.923093 -262.032691) (xy 98.923602 -262.058658) (xy 98.923093 -262.084625)
			(xy 99.203003 -262.084625) (xy 99.203003 -262.032691) (xy 99.211128 -261.981396) (xy 99.227176 -261.932003)
			(xy 99.250754 -261.885729) (xy 99.28128 -261.843713) (xy 99.318003 -261.80699) (xy 99.360019 -261.776464)
			(xy 99.406293 -261.752886) (xy 99.455686 -261.736838) (xy 99.506981 -261.728713) (xy 99.558915 -261.728713)
			(xy 99.61021 -261.736838) (xy 99.659603 -261.752886) (xy 99.705877 -261.776464) (xy 99.747893 -261.80699)
			(xy 99.784616 -261.843713) (xy 99.815142 -261.885729) (xy 99.83872 -261.932003) (xy 99.854768 -261.981396)
			(xy 99.862893 -262.032691) (xy 99.863402 -262.058658) (xy 99.862893 -262.084625) (xy 100.142803 -262.084625)
			(xy 100.142803 -262.032691) (xy 100.150928 -261.981396) (xy 100.166976 -261.932003) (xy 100.190554 -261.885729)
			(xy 100.22108 -261.843713) (xy 100.257803 -261.80699) (xy 100.299819 -261.776464) (xy 100.346093 -261.752886)
			(xy 100.395486 -261.736838) (xy 100.446781 -261.728713) (xy 100.498715 -261.728713) (xy 100.55001 -261.736838)
			(xy 100.599403 -261.752886) (xy 100.645677 -261.776464) (xy 100.687693 -261.80699) (xy 100.724416 -261.843713)
			(xy 100.754942 -261.885729) (xy 100.77852 -261.932003) (xy 100.794568 -261.981396) (xy 100.802693 -262.032691)
			(xy 100.803202 -262.058658) (xy 100.802693 -262.084625) (xy 101.082603 -262.084625) (xy 101.082603 -262.032691)
			(xy 101.090728 -261.981396) (xy 101.106776 -261.932003) (xy 101.130354 -261.885729) (xy 101.16088 -261.843713)
			(xy 101.197603 -261.80699) (xy 101.239619 -261.776464) (xy 101.285893 -261.752886) (xy 101.335286 -261.736838)
			(xy 101.386581 -261.728713) (xy 101.438515 -261.728713) (xy 101.48981 -261.736838) (xy 101.539203 -261.752886)
			(xy 101.585477 -261.776464) (xy 101.627493 -261.80699) (xy 101.664216 -261.843713) (xy 101.694742 -261.885729)
			(xy 101.71832 -261.932003) (xy 101.734368 -261.981396) (xy 101.742493 -262.032691) (xy 101.743002 -262.058658)
			(xy 101.742493 -262.084625) (xy 102.022403 -262.084625) (xy 102.022403 -262.032691) (xy 102.030528 -261.981396)
			(xy 102.046576 -261.932003) (xy 102.070154 -261.885729) (xy 102.10068 -261.843713) (xy 102.137403 -261.80699)
			(xy 102.179419 -261.776464) (xy 102.225693 -261.752886) (xy 102.275086 -261.736838) (xy 102.326381 -261.728713)
			(xy 102.378315 -261.728713) (xy 102.42961 -261.736838) (xy 102.479003 -261.752886) (xy 102.525277 -261.776464)
			(xy 102.567293 -261.80699) (xy 102.604016 -261.843713) (xy 102.634542 -261.885729) (xy 102.65812 -261.932003)
			(xy 102.674168 -261.981396) (xy 102.682293 -262.032691) (xy 102.682802 -262.058658) (xy 102.682293 -262.084625)
			(xy 102.674168 -262.13592) (xy 102.65812 -262.185313) (xy 102.634542 -262.231587) (xy 102.604016 -262.273603)
			(xy 102.567293 -262.310326) (xy 102.525277 -262.340852) (xy 102.479003 -262.36443) (xy 102.42961 -262.380478)
			(xy 102.378315 -262.388603) (xy 102.326381 -262.388603) (xy 102.275086 -262.380478) (xy 102.225693 -262.36443)
			(xy 102.179419 -262.340852) (xy 102.137403 -262.310326) (xy 102.10068 -262.273603) (xy 102.070154 -262.231587)
			(xy 102.046576 -262.185313) (xy 102.030528 -262.13592) (xy 102.022403 -262.084625) (xy 101.742493 -262.084625)
			(xy 101.734368 -262.13592) (xy 101.71832 -262.185313) (xy 101.694742 -262.231587) (xy 101.664216 -262.273603)
			(xy 101.627493 -262.310326) (xy 101.585477 -262.340852) (xy 101.539203 -262.36443) (xy 101.48981 -262.380478)
			(xy 101.438515 -262.388603) (xy 101.386581 -262.388603) (xy 101.335286 -262.380478) (xy 101.285893 -262.36443)
			(xy 101.239619 -262.340852) (xy 101.197603 -262.310326) (xy 101.16088 -262.273603) (xy 101.130354 -262.231587)
			(xy 101.106776 -262.185313) (xy 101.090728 -262.13592) (xy 101.082603 -262.084625) (xy 100.802693 -262.084625)
			(xy 100.794568 -262.13592) (xy 100.77852 -262.185313) (xy 100.754942 -262.231587) (xy 100.724416 -262.273603)
			(xy 100.687693 -262.310326) (xy 100.645677 -262.340852) (xy 100.599403 -262.36443) (xy 100.55001 -262.380478)
			(xy 100.498715 -262.388603) (xy 100.446781 -262.388603) (xy 100.395486 -262.380478) (xy 100.346093 -262.36443)
			(xy 100.299819 -262.340852) (xy 100.257803 -262.310326) (xy 100.22108 -262.273603) (xy 100.190554 -262.231587)
			(xy 100.166976 -262.185313) (xy 100.150928 -262.13592) (xy 100.142803 -262.084625) (xy 99.862893 -262.084625)
			(xy 99.854768 -262.13592) (xy 99.83872 -262.185313) (xy 99.815142 -262.231587) (xy 99.784616 -262.273603)
			(xy 99.747893 -262.310326) (xy 99.705877 -262.340852) (xy 99.659603 -262.36443) (xy 99.61021 -262.380478)
			(xy 99.558915 -262.388603) (xy 99.506981 -262.388603) (xy 99.455686 -262.380478) (xy 99.406293 -262.36443)
			(xy 99.360019 -262.340852) (xy 99.318003 -262.310326) (xy 99.28128 -262.273603) (xy 99.250754 -262.231587)
			(xy 99.227176 -262.185313) (xy 99.211128 -262.13592) (xy 99.203003 -262.084625) (xy 98.923093 -262.084625)
			(xy 98.914968 -262.13592) (xy 98.89892 -262.185313) (xy 98.875342 -262.231587) (xy 98.844816 -262.273603)
			(xy 98.808093 -262.310326) (xy 98.766077 -262.340852) (xy 98.719803 -262.36443) (xy 98.67041 -262.380478)
			(xy 98.619115 -262.388603) (xy 98.567181 -262.388603) (xy 98.515886 -262.380478) (xy 98.466493 -262.36443)
			(xy 98.420219 -262.340852) (xy 98.378203 -262.310326) (xy 98.34148 -262.273603) (xy 98.310954 -262.231587)
			(xy 98.287376 -262.185313) (xy 98.271328 -262.13592) (xy 98.263203 -262.084625) (xy 97.983039 -262.084625)
			(xy 97.974914 -262.13592) (xy 97.958866 -262.185313) (xy 97.935288 -262.231587) (xy 97.904762 -262.273603)
			(xy 97.868039 -262.310326) (xy 97.826023 -262.340852) (xy 97.779749 -262.36443) (xy 97.730356 -262.380478)
			(xy 97.679061 -262.388603) (xy 97.627127 -262.388603) (xy 97.575832 -262.380478) (xy 97.526439 -262.36443)
			(xy 97.480165 -262.340852) (xy 97.438149 -262.310326) (xy 97.401426 -262.273603) (xy 97.3709 -262.231587)
			(xy 97.347322 -262.185313) (xy 97.331274 -262.13592) (xy 97.323149 -262.084625) (xy 97.043493 -262.084625)
			(xy 97.035368 -262.13592) (xy 97.01932 -262.185313) (xy 96.995742 -262.231587) (xy 96.965216 -262.273603)
			(xy 96.928493 -262.310326) (xy 96.886477 -262.340852) (xy 96.840203 -262.36443) (xy 96.79081 -262.380478)
			(xy 96.739515 -262.388603) (xy 96.687581 -262.388603) (xy 96.636286 -262.380478) (xy 96.586893 -262.36443)
			(xy 96.540619 -262.340852) (xy 96.498603 -262.310326) (xy 96.46188 -262.273603) (xy 96.431354 -262.231587)
			(xy 96.407776 -262.185313) (xy 96.391728 -262.13592) (xy 96.383603 -262.084625) (xy 96.103693 -262.084625)
			(xy 96.095568 -262.13592) (xy 96.07952 -262.185313) (xy 96.055942 -262.231587) (xy 96.025416 -262.273603)
			(xy 95.988693 -262.310326) (xy 95.946677 -262.340852) (xy 95.900403 -262.36443) (xy 95.85101 -262.380478)
			(xy 95.799715 -262.388603) (xy 95.747781 -262.388603) (xy 95.696486 -262.380478) (xy 95.647093 -262.36443)
			(xy 95.600819 -262.340852) (xy 95.558803 -262.310326) (xy 95.52208 -262.273603) (xy 95.491554 -262.231587)
			(xy 95.467976 -262.185313) (xy 95.451928 -262.13592) (xy 95.443803 -262.084625) (xy 95.163893 -262.084625)
			(xy 95.155768 -262.13592) (xy 95.13972 -262.185313) (xy 95.116142 -262.231587) (xy 95.085616 -262.273603)
			(xy 95.048893 -262.310326) (xy 95.006877 -262.340852) (xy 94.960603 -262.36443) (xy 94.91121 -262.380478)
			(xy 94.859915 -262.388603) (xy 94.807981 -262.388603) (xy 94.756686 -262.380478) (xy 94.707293 -262.36443)
			(xy 94.661019 -262.340852) (xy 94.619003 -262.310326) (xy 94.58228 -262.273603) (xy 94.551754 -262.231587)
			(xy 94.528176 -262.185313) (xy 94.512128 -262.13592) (xy 94.504003 -262.084625) (xy 94.224093 -262.084625)
			(xy 94.215968 -262.13592) (xy 94.19992 -262.185313) (xy 94.176342 -262.231587) (xy 94.145816 -262.273603)
			(xy 94.109093 -262.310326) (xy 94.067077 -262.340852) (xy 94.020803 -262.36443) (xy 93.97141 -262.380478)
			(xy 93.920115 -262.388603) (xy 93.868181 -262.388603) (xy 93.816886 -262.380478) (xy 93.767493 -262.36443)
			(xy 93.721219 -262.340852) (xy 93.679203 -262.310326) (xy 93.64248 -262.273603) (xy 93.611954 -262.231587)
			(xy 93.588376 -262.185313) (xy 93.572328 -262.13592) (xy 93.564203 -262.084625) (xy 93.284293 -262.084625)
			(xy 93.276168 -262.13592) (xy 93.26012 -262.185313) (xy 93.236542 -262.231587) (xy 93.206016 -262.273603)
			(xy 93.169293 -262.310326) (xy 93.127277 -262.340852) (xy 93.081003 -262.36443) (xy 93.03161 -262.380478)
			(xy 92.980315 -262.388603) (xy 92.928381 -262.388603) (xy 92.877086 -262.380478) (xy 92.827693 -262.36443)
			(xy 92.781419 -262.340852) (xy 92.739403 -262.310326) (xy 92.70268 -262.273603) (xy 92.672154 -262.231587)
			(xy 92.648576 -262.185313) (xy 92.632528 -262.13592) (xy 92.624403 -262.084625) (xy 92.344741 -262.084625)
			(xy 92.344741 -262.084688) (xy 92.33661 -262.136024) (xy 92.32055 -262.185457) (xy 92.296956 -262.231769)
			(xy 92.266407 -262.273821) (xy 92.229657 -262.310576) (xy 92.18761 -262.341131) (xy 92.141302 -262.364732)
			(xy 92.091871 -262.380799) (xy 92.040536 -262.388937) (xy 92.014548 -262.389366) (xy 91.991674 -262.388983)
			(xy 91.946361 -262.382687) (xy 91.902348 -262.370208) (xy 91.860474 -262.351784) (xy 91.840812 -262.34009)
			(xy 91.840558 -262.339836) (xy 91.833071 -262.335648) (xy 91.816298 -262.332112) (xy 91.799313 -262.334436)
			(xy 91.791536 -262.338058) (xy 91.751658 -262.360156) (xy 91.713304 -262.381492) (xy 91.705719 -262.386131)
			(xy 91.694165 -262.39963) (xy 91.688002 -262.416296) (xy 91.68765 -262.42518) (xy 91.68765 -262.54456)
			(xy 91.712034 -262.586978) (xy 91.718638 -262.591296) (xy 91.740364 -262.605346) (xy 91.779565 -262.63911)
			(xy 91.813031 -262.678566) (xy 91.839947 -262.72275) (xy 91.859657 -262.770586) (xy 91.871679 -262.820907)
			(xy 91.87572 -262.872486) (xy 91.873689 -262.898441) (xy 92.154249 -262.898441) (xy 92.154249 -262.846507)
			(xy 92.162374 -262.795212) (xy 92.178422 -262.745819) (xy 92.202 -262.699545) (xy 92.232526 -262.657529)
			(xy 92.269249 -262.620806) (xy 92.311265 -262.59028) (xy 92.357539 -262.566702) (xy 92.406932 -262.550654)
			(xy 92.458227 -262.542529) (xy 92.510161 -262.542529) (xy 92.561456 -262.550654) (xy 92.610849 -262.566702)
			(xy 92.657123 -262.59028) (xy 92.699139 -262.620806) (xy 92.735862 -262.657529) (xy 92.766388 -262.699545)
			(xy 92.789966 -262.745819) (xy 92.806014 -262.795212) (xy 92.814139 -262.846507) (xy 92.814648 -262.872474)
			(xy 92.814139 -262.898441) (xy 93.094049 -262.898441) (xy 93.094049 -262.846507) (xy 93.102174 -262.795212)
			(xy 93.118222 -262.745819) (xy 93.1418 -262.699545) (xy 93.172326 -262.657529) (xy 93.209049 -262.620806)
			(xy 93.251065 -262.59028) (xy 93.297339 -262.566702) (xy 93.346732 -262.550654) (xy 93.398027 -262.542529)
			(xy 93.449961 -262.542529) (xy 93.501256 -262.550654) (xy 93.550649 -262.566702) (xy 93.596923 -262.59028)
			(xy 93.638939 -262.620806) (xy 93.675662 -262.657529) (xy 93.706188 -262.699545) (xy 93.729766 -262.745819)
			(xy 93.745814 -262.795212) (xy 93.753939 -262.846507) (xy 93.754448 -262.872474) (xy 93.753939 -262.898441)
			(xy 94.033849 -262.898441) (xy 94.033849 -262.846507) (xy 94.041974 -262.795212) (xy 94.058022 -262.745819)
			(xy 94.0816 -262.699545) (xy 94.112126 -262.657529) (xy 94.148849 -262.620806) (xy 94.190865 -262.59028)
			(xy 94.237139 -262.566702) (xy 94.286532 -262.550654) (xy 94.337827 -262.542529) (xy 94.389761 -262.542529)
			(xy 94.441056 -262.550654) (xy 94.490449 -262.566702) (xy 94.536723 -262.59028) (xy 94.578739 -262.620806)
			(xy 94.615462 -262.657529) (xy 94.645988 -262.699545) (xy 94.669566 -262.745819) (xy 94.685614 -262.795212)
			(xy 94.693739 -262.846507) (xy 94.694248 -262.872474) (xy 94.693739 -262.898441) (xy 94.973649 -262.898441)
			(xy 94.973649 -262.846507) (xy 94.981774 -262.795212) (xy 94.997822 -262.745819) (xy 95.0214 -262.699545)
			(xy 95.051926 -262.657529) (xy 95.088649 -262.620806) (xy 95.130665 -262.59028) (xy 95.176939 -262.566702)
			(xy 95.226332 -262.550654) (xy 95.277627 -262.542529) (xy 95.329561 -262.542529) (xy 95.380856 -262.550654)
			(xy 95.430249 -262.566702) (xy 95.476523 -262.59028) (xy 95.518539 -262.620806) (xy 95.555262 -262.657529)
			(xy 95.585788 -262.699545) (xy 95.609366 -262.745819) (xy 95.625414 -262.795212) (xy 95.633539 -262.846507)
			(xy 95.634048 -262.872474) (xy 95.633539 -262.898441) (xy 95.913449 -262.898441) (xy 95.913449 -262.846507)
			(xy 95.921574 -262.795212) (xy 95.937622 -262.745819) (xy 95.9612 -262.699545) (xy 95.991726 -262.657529)
			(xy 96.028449 -262.620806) (xy 96.070465 -262.59028) (xy 96.116739 -262.566702) (xy 96.166132 -262.550654)
			(xy 96.217427 -262.542529) (xy 96.269361 -262.542529) (xy 96.320656 -262.550654) (xy 96.370049 -262.566702)
			(xy 96.416323 -262.59028) (xy 96.458339 -262.620806) (xy 96.495062 -262.657529) (xy 96.525588 -262.699545)
			(xy 96.549166 -262.745819) (xy 96.565214 -262.795212) (xy 96.573339 -262.846507) (xy 96.573848 -262.872474)
			(xy 96.573339 -262.898441) (xy 96.853503 -262.898441) (xy 96.853503 -262.846507) (xy 96.861628 -262.795212)
			(xy 96.877676 -262.745819) (xy 96.901254 -262.699545) (xy 96.93178 -262.657529) (xy 96.968503 -262.620806)
			(xy 97.010519 -262.59028) (xy 97.056793 -262.566702) (xy 97.106186 -262.550654) (xy 97.157481 -262.542529)
			(xy 97.209415 -262.542529) (xy 97.26071 -262.550654) (xy 97.310103 -262.566702) (xy 97.356377 -262.59028)
			(xy 97.398393 -262.620806) (xy 97.435116 -262.657529) (xy 97.465642 -262.699545) (xy 97.48922 -262.745819)
			(xy 97.505268 -262.795212) (xy 97.513393 -262.846507) (xy 97.513902 -262.872474) (xy 97.513393 -262.898441)
			(xy 97.793049 -262.898441) (xy 97.793049 -262.846507) (xy 97.801174 -262.795212) (xy 97.817222 -262.745819)
			(xy 97.8408 -262.699545) (xy 97.871326 -262.657529) (xy 97.908049 -262.620806) (xy 97.950065 -262.59028)
			(xy 97.996339 -262.566702) (xy 98.045732 -262.550654) (xy 98.097027 -262.542529) (xy 98.148961 -262.542529)
			(xy 98.200256 -262.550654) (xy 98.249649 -262.566702) (xy 98.295923 -262.59028) (xy 98.337939 -262.620806)
			(xy 98.374662 -262.657529) (xy 98.405188 -262.699545) (xy 98.428766 -262.745819) (xy 98.444814 -262.795212)
			(xy 98.452939 -262.846507) (xy 98.453448 -262.872474) (xy 98.452939 -262.898441) (xy 98.732849 -262.898441)
			(xy 98.732849 -262.846507) (xy 98.740974 -262.795212) (xy 98.757022 -262.745819) (xy 98.7806 -262.699545)
			(xy 98.811126 -262.657529) (xy 98.847849 -262.620806) (xy 98.889865 -262.59028) (xy 98.936139 -262.566702)
			(xy 98.985532 -262.550654) (xy 99.036827 -262.542529) (xy 99.088761 -262.542529) (xy 99.140056 -262.550654)
			(xy 99.189449 -262.566702) (xy 99.235723 -262.59028) (xy 99.277739 -262.620806) (xy 99.314462 -262.657529)
			(xy 99.344988 -262.699545) (xy 99.368566 -262.745819) (xy 99.384614 -262.795212) (xy 99.392739 -262.846507)
			(xy 99.393248 -262.872474) (xy 99.392739 -262.898441) (xy 99.672649 -262.898441) (xy 99.672649 -262.846507)
			(xy 99.680774 -262.795212) (xy 99.696822 -262.745819) (xy 99.7204 -262.699545) (xy 99.750926 -262.657529)
			(xy 99.787649 -262.620806) (xy 99.829665 -262.59028) (xy 99.875939 -262.566702) (xy 99.925332 -262.550654)
			(xy 99.976627 -262.542529) (xy 100.028561 -262.542529) (xy 100.079856 -262.550654) (xy 100.129249 -262.566702)
			(xy 100.175523 -262.59028) (xy 100.217539 -262.620806) (xy 100.254262 -262.657529) (xy 100.284788 -262.699545)
			(xy 100.308366 -262.745819) (xy 100.324414 -262.795212) (xy 100.332539 -262.846507) (xy 100.333048 -262.872474)
			(xy 100.332539 -262.898441) (xy 100.612449 -262.898441) (xy 100.612449 -262.846507) (xy 100.620574 -262.795212)
			(xy 100.636622 -262.745819) (xy 100.6602 -262.699545) (xy 100.690726 -262.657529) (xy 100.727449 -262.620806)
			(xy 100.769465 -262.59028) (xy 100.815739 -262.566702) (xy 100.865132 -262.550654) (xy 100.916427 -262.542529)
			(xy 100.968361 -262.542529) (xy 101.019656 -262.550654) (xy 101.069049 -262.566702) (xy 101.115323 -262.59028)
			(xy 101.157339 -262.620806) (xy 101.194062 -262.657529) (xy 101.224588 -262.699545) (xy 101.227283 -262.704834)
			(xy 103.384096 -262.704834) (xy 103.384096 -262.70458) (xy 103.384537 -262.680053) (xy 103.391802 -262.63154)
			(xy 103.406157 -262.584632) (xy 103.427284 -262.540361) (xy 103.454721 -262.499697) (xy 103.470964 -262.481314)
			(xy 103.480735 -262.469799) (xy 103.493754 -262.442572) (xy 103.49823 -262.412725) (xy 103.493769 -262.382877)
			(xy 103.480763 -262.355642) (xy 103.470964 -262.344154) (xy 103.454735 -262.325758) (xy 103.427285 -262.285104)
			(xy 103.406151 -262.240836) (xy 103.391798 -262.193929) (xy 103.384543 -262.145415) (xy 103.384096 -262.120888)
			(xy 103.384096 -262.120634) (xy 103.384605 -262.094667) (xy 103.39273 -262.043372) (xy 103.408778 -261.993979)
			(xy 103.432356 -261.947705) (xy 103.462882 -261.905689) (xy 103.499605 -261.868966) (xy 103.541621 -261.83844)
			(xy 103.587895 -261.814862) (xy 103.637288 -261.798814) (xy 103.688583 -261.790689) (xy 103.740517 -261.790689)
			(xy 103.791812 -261.798814) (xy 103.841205 -261.814862) (xy 103.887479 -261.83844) (xy 103.929495 -261.868966)
			(xy 103.966218 -261.905689) (xy 103.996744 -261.947705) (xy 104.020322 -261.993979) (xy 104.03637 -262.043372)
			(xy 104.044495 -262.094667) (xy 104.045004 -262.120634) (xy 104.045004 -262.120888) (xy 104.044544 -262.145414)
			(xy 104.037283 -262.193927) (xy 104.022933 -262.240834) (xy 104.00181 -262.285106) (xy 103.974377 -262.32577)
			(xy 103.958136 -262.344154) (xy 103.948298 -262.355617) (xy 103.935287 -262.382863) (xy 103.930824 -262.412725)
			(xy 103.935302 -262.442585) (xy 103.948327 -262.469825) (xy 103.958136 -262.481314) (xy 103.974397 -262.499683)
			(xy 104.001843 -262.540344) (xy 104.022971 -262.584619) (xy 104.037316 -262.631532) (xy 104.044562 -262.680051)
			(xy 104.045004 -262.70458) (xy 104.045004 -262.704834) (xy 104.044495 -262.730801) (xy 104.03637 -262.782096)
			(xy 104.020322 -262.831489) (xy 103.996744 -262.877763) (xy 103.966218 -262.919779) (xy 103.929495 -262.956502)
			(xy 103.887479 -262.987028) (xy 103.841205 -263.010606) (xy 103.791812 -263.026654) (xy 103.740517 -263.034779)
			(xy 103.688583 -263.034779) (xy 103.637288 -263.026654) (xy 103.587895 -263.010606) (xy 103.541621 -262.987028)
			(xy 103.499605 -262.956502) (xy 103.462882 -262.919779) (xy 103.432356 -262.877763) (xy 103.408778 -262.831489)
			(xy 103.39273 -262.782096) (xy 103.384605 -262.730801) (xy 103.384096 -262.704834) (xy 101.227283 -262.704834)
			(xy 101.248166 -262.745819) (xy 101.264214 -262.795212) (xy 101.272339 -262.846507) (xy 101.272848 -262.872474)
			(xy 101.272339 -262.898441) (xy 101.264214 -262.949736) (xy 101.248166 -262.999129) (xy 101.224588 -263.045403)
			(xy 101.194062 -263.087419) (xy 101.157339 -263.124142) (xy 101.115323 -263.154668) (xy 101.069049 -263.178246)
			(xy 101.019656 -263.194294) (xy 100.968361 -263.202419) (xy 100.916427 -263.202419) (xy 100.865132 -263.194294)
			(xy 100.815739 -263.178246) (xy 100.769465 -263.154668) (xy 100.727449 -263.124142) (xy 100.690726 -263.087419)
			(xy 100.6602 -263.045403) (xy 100.636622 -262.999129) (xy 100.620574 -262.949736) (xy 100.612449 -262.898441)
			(xy 100.332539 -262.898441) (xy 100.324414 -262.949736) (xy 100.308366 -262.999129) (xy 100.284788 -263.045403)
			(xy 100.254262 -263.087419) (xy 100.217539 -263.124142) (xy 100.175523 -263.154668) (xy 100.129249 -263.178246)
			(xy 100.079856 -263.194294) (xy 100.028561 -263.202419) (xy 99.976627 -263.202419) (xy 99.925332 -263.194294)
			(xy 99.875939 -263.178246) (xy 99.829665 -263.154668) (xy 99.787649 -263.124142) (xy 99.750926 -263.087419)
			(xy 99.7204 -263.045403) (xy 99.696822 -262.999129) (xy 99.680774 -262.949736) (xy 99.672649 -262.898441)
			(xy 99.392739 -262.898441) (xy 99.384614 -262.949736) (xy 99.368566 -262.999129) (xy 99.344988 -263.045403)
			(xy 99.314462 -263.087419) (xy 99.277739 -263.124142) (xy 99.235723 -263.154668) (xy 99.189449 -263.178246)
			(xy 99.140056 -263.194294) (xy 99.088761 -263.202419) (xy 99.036827 -263.202419) (xy 98.985532 -263.194294)
			(xy 98.936139 -263.178246) (xy 98.889865 -263.154668) (xy 98.847849 -263.124142) (xy 98.811126 -263.087419)
			(xy 98.7806 -263.045403) (xy 98.757022 -262.999129) (xy 98.740974 -262.949736) (xy 98.732849 -262.898441)
			(xy 98.452939 -262.898441) (xy 98.444814 -262.949736) (xy 98.428766 -262.999129) (xy 98.405188 -263.045403)
			(xy 98.374662 -263.087419) (xy 98.337939 -263.124142) (xy 98.295923 -263.154668) (xy 98.249649 -263.178246)
			(xy 98.200256 -263.194294) (xy 98.148961 -263.202419) (xy 98.097027 -263.202419) (xy 98.045732 -263.194294)
			(xy 97.996339 -263.178246) (xy 97.950065 -263.154668) (xy 97.908049 -263.124142) (xy 97.871326 -263.087419)
			(xy 97.8408 -263.045403) (xy 97.817222 -262.999129) (xy 97.801174 -262.949736) (xy 97.793049 -262.898441)
			(xy 97.513393 -262.898441) (xy 97.505268 -262.949736) (xy 97.48922 -262.999129) (xy 97.465642 -263.045403)
			(xy 97.435116 -263.087419) (xy 97.398393 -263.124142) (xy 97.356377 -263.154668) (xy 97.310103 -263.178246)
			(xy 97.26071 -263.194294) (xy 97.209415 -263.202419) (xy 97.157481 -263.202419) (xy 97.106186 -263.194294)
			(xy 97.056793 -263.178246) (xy 97.010519 -263.154668) (xy 96.968503 -263.124142) (xy 96.93178 -263.087419)
			(xy 96.901254 -263.045403) (xy 96.877676 -262.999129) (xy 96.861628 -262.949736) (xy 96.853503 -262.898441)
			(xy 96.573339 -262.898441) (xy 96.565214 -262.949736) (xy 96.549166 -262.999129) (xy 96.525588 -263.045403)
			(xy 96.495062 -263.087419) (xy 96.458339 -263.124142) (xy 96.416323 -263.154668) (xy 96.370049 -263.178246)
			(xy 96.320656 -263.194294) (xy 96.269361 -263.202419) (xy 96.217427 -263.202419) (xy 96.166132 -263.194294)
			(xy 96.116739 -263.178246) (xy 96.070465 -263.154668) (xy 96.028449 -263.124142) (xy 95.991726 -263.087419)
			(xy 95.9612 -263.045403) (xy 95.937622 -262.999129) (xy 95.921574 -262.949736) (xy 95.913449 -262.898441)
			(xy 95.633539 -262.898441) (xy 95.625414 -262.949736) (xy 95.609366 -262.999129) (xy 95.585788 -263.045403)
			(xy 95.555262 -263.087419) (xy 95.518539 -263.124142) (xy 95.476523 -263.154668) (xy 95.430249 -263.178246)
			(xy 95.380856 -263.194294) (xy 95.329561 -263.202419) (xy 95.277627 -263.202419) (xy 95.226332 -263.194294)
			(xy 95.176939 -263.178246) (xy 95.130665 -263.154668) (xy 95.088649 -263.124142) (xy 95.051926 -263.087419)
			(xy 95.0214 -263.045403) (xy 94.997822 -262.999129) (xy 94.981774 -262.949736) (xy 94.973649 -262.898441)
			(xy 94.693739 -262.898441) (xy 94.685614 -262.949736) (xy 94.669566 -262.999129) (xy 94.645988 -263.045403)
			(xy 94.615462 -263.087419) (xy 94.578739 -263.124142) (xy 94.536723 -263.154668) (xy 94.490449 -263.178246)
			(xy 94.441056 -263.194294) (xy 94.389761 -263.202419) (xy 94.337827 -263.202419) (xy 94.286532 -263.194294)
			(xy 94.237139 -263.178246) (xy 94.190865 -263.154668) (xy 94.148849 -263.124142) (xy 94.112126 -263.087419)
			(xy 94.0816 -263.045403) (xy 94.058022 -262.999129) (xy 94.041974 -262.949736) (xy 94.033849 -262.898441)
			(xy 93.753939 -262.898441) (xy 93.745814 -262.949736) (xy 93.729766 -262.999129) (xy 93.706188 -263.045403)
			(xy 93.675662 -263.087419) (xy 93.638939 -263.124142) (xy 93.596923 -263.154668) (xy 93.550649 -263.178246)
			(xy 93.501256 -263.194294) (xy 93.449961 -263.202419) (xy 93.398027 -263.202419) (xy 93.346732 -263.194294)
			(xy 93.297339 -263.178246) (xy 93.251065 -263.154668) (xy 93.209049 -263.124142) (xy 93.172326 -263.087419)
			(xy 93.1418 -263.045403) (xy 93.118222 -262.999129) (xy 93.102174 -262.949736) (xy 93.094049 -262.898441)
			(xy 92.814139 -262.898441) (xy 92.806014 -262.949736) (xy 92.789966 -262.999129) (xy 92.766388 -263.045403)
			(xy 92.735862 -263.087419) (xy 92.699139 -263.124142) (xy 92.657123 -263.154668) (xy 92.610849 -263.178246)
			(xy 92.561456 -263.194294) (xy 92.510161 -263.202419) (xy 92.458227 -263.202419) (xy 92.406932 -263.194294)
			(xy 92.357539 -263.178246) (xy 92.311265 -263.154668) (xy 92.269249 -263.124142) (xy 92.232526 -263.087419)
			(xy 92.202 -263.045403) (xy 92.178422 -262.999129) (xy 92.162374 -262.949736) (xy 92.154249 -262.898441)
			(xy 91.873689 -262.898441) (xy 91.871683 -262.924066) (xy 91.859665 -262.974388) (xy 91.83996 -263.022225)
			(xy 91.813047 -263.066412) (xy 91.779584 -263.10587) (xy 91.740386 -263.139638) (xy 91.718638 -263.153652)
			(xy 91.712034 -263.15797) (xy 91.68765 -263.200388) (xy 91.68765 -263.320022) (xy 91.688008 -263.328905)
			(xy 91.69417 -263.345568) (xy 91.705723 -263.359065) (xy 91.713304 -263.36371) (xy 91.751658 -263.385046)
			(xy 91.791536 -263.407144) (xy 91.799315 -263.410753) (xy 91.816299 -263.413049) (xy 91.833076 -263.409554)
			(xy 91.840558 -263.405366) (xy 91.840812 -263.405112) (xy 91.860483 -263.393434) (xy 91.902355 -263.37501)
			(xy 91.946365 -263.362526) (xy 91.991675 -263.356221) (xy 92.014548 -263.355836) (xy 92.040529 -263.356349)
			(xy 92.091851 -263.364485) (xy 92.141268 -263.380548) (xy 92.187565 -263.404143) (xy 92.229601 -263.43469)
			(xy 92.266341 -263.471435) (xy 92.296882 -263.513476) (xy 92.32047 -263.559776) (xy 92.336526 -263.609196)
			(xy 92.344654 -263.660519) (xy 92.344654 -263.712481) (xy 92.344649 -263.712511) (xy 92.624403 -263.712511)
			(xy 92.624403 -263.660577) (xy 92.632528 -263.609282) (xy 92.648576 -263.559889) (xy 92.672154 -263.513615)
			(xy 92.70268 -263.471599) (xy 92.739403 -263.434876) (xy 92.781419 -263.40435) (xy 92.827693 -263.380772)
			(xy 92.877086 -263.364724) (xy 92.928381 -263.356599) (xy 92.980315 -263.356599) (xy 93.03161 -263.364724)
			(xy 93.081003 -263.380772) (xy 93.127277 -263.40435) (xy 93.169293 -263.434876) (xy 93.206016 -263.471599)
			(xy 93.236542 -263.513615) (xy 93.26012 -263.559889) (xy 93.276168 -263.609282) (xy 93.284293 -263.660577)
			(xy 93.284802 -263.686544) (xy 93.284293 -263.712511) (xy 93.564203 -263.712511) (xy 93.564203 -263.660577)
			(xy 93.572328 -263.609282) (xy 93.588376 -263.559889) (xy 93.611954 -263.513615) (xy 93.64248 -263.471599)
			(xy 93.679203 -263.434876) (xy 93.721219 -263.40435) (xy 93.767493 -263.380772) (xy 93.816886 -263.364724)
			(xy 93.868181 -263.356599) (xy 93.920115 -263.356599) (xy 93.97141 -263.364724) (xy 94.020803 -263.380772)
			(xy 94.067077 -263.40435) (xy 94.109093 -263.434876) (xy 94.145816 -263.471599) (xy 94.176342 -263.513615)
			(xy 94.19992 -263.559889) (xy 94.215968 -263.609282) (xy 94.224093 -263.660577) (xy 94.224602 -263.686544)
			(xy 94.224093 -263.712511) (xy 94.503749 -263.712511) (xy 94.503749 -263.660577) (xy 94.511874 -263.609282)
			(xy 94.527922 -263.559889) (xy 94.5515 -263.513615) (xy 94.582026 -263.471599) (xy 94.618749 -263.434876)
			(xy 94.660765 -263.40435) (xy 94.707039 -263.380772) (xy 94.756432 -263.364724) (xy 94.807727 -263.356599)
			(xy 94.859661 -263.356599) (xy 94.910956 -263.364724) (xy 94.960349 -263.380772) (xy 95.006623 -263.40435)
			(xy 95.048639 -263.434876) (xy 95.085362 -263.471599) (xy 95.115888 -263.513615) (xy 95.139466 -263.559889)
			(xy 95.155514 -263.609282) (xy 95.163639 -263.660577) (xy 95.164148 -263.686544) (xy 95.163639 -263.712511)
			(xy 95.443803 -263.712511) (xy 95.443803 -263.660577) (xy 95.451928 -263.609282) (xy 95.467976 -263.559889)
			(xy 95.491554 -263.513615) (xy 95.52208 -263.471599) (xy 95.558803 -263.434876) (xy 95.600819 -263.40435)
			(xy 95.647093 -263.380772) (xy 95.696486 -263.364724) (xy 95.747781 -263.356599) (xy 95.799715 -263.356599)
			(xy 95.85101 -263.364724) (xy 95.900403 -263.380772) (xy 95.946677 -263.40435) (xy 95.988693 -263.434876)
			(xy 96.025416 -263.471599) (xy 96.055942 -263.513615) (xy 96.07952 -263.559889) (xy 96.095568 -263.609282)
			(xy 96.103693 -263.660577) (xy 96.104202 -263.686544) (xy 96.103693 -263.712511) (xy 96.383603 -263.712511)
			(xy 96.383603 -263.660577) (xy 96.391728 -263.609282) (xy 96.407776 -263.559889) (xy 96.431354 -263.513615)
			(xy 96.46188 -263.471599) (xy 96.498603 -263.434876) (xy 96.540619 -263.40435) (xy 96.586893 -263.380772)
			(xy 96.636286 -263.364724) (xy 96.687581 -263.356599) (xy 96.739515 -263.356599) (xy 96.79081 -263.364724)
			(xy 96.840203 -263.380772) (xy 96.886477 -263.40435) (xy 96.928493 -263.434876) (xy 96.965216 -263.471599)
			(xy 96.995742 -263.513615) (xy 97.01932 -263.559889) (xy 97.035368 -263.609282) (xy 97.043493 -263.660577)
			(xy 97.044002 -263.686544) (xy 97.043493 -263.712511) (xy 97.323403 -263.712511) (xy 97.323403 -263.660577)
			(xy 97.331528 -263.609282) (xy 97.347576 -263.559889) (xy 97.371154 -263.513615) (xy 97.40168 -263.471599)
			(xy 97.438403 -263.434876) (xy 97.480419 -263.40435) (xy 97.526693 -263.380772) (xy 97.576086 -263.364724)
			(xy 97.627381 -263.356599) (xy 97.679315 -263.356599) (xy 97.73061 -263.364724) (xy 97.780003 -263.380772)
			(xy 97.826277 -263.40435) (xy 97.868293 -263.434876) (xy 97.905016 -263.471599) (xy 97.935542 -263.513615)
			(xy 97.95912 -263.559889) (xy 97.975168 -263.609282) (xy 97.983293 -263.660577) (xy 97.983802 -263.686544)
			(xy 97.983293 -263.712511) (xy 98.263203 -263.712511) (xy 98.263203 -263.660577) (xy 98.271328 -263.609282)
			(xy 98.287376 -263.559889) (xy 98.310954 -263.513615) (xy 98.34148 -263.471599) (xy 98.378203 -263.434876)
			(xy 98.420219 -263.40435) (xy 98.466493 -263.380772) (xy 98.515886 -263.364724) (xy 98.567181 -263.356599)
			(xy 98.619115 -263.356599) (xy 98.67041 -263.364724) (xy 98.719803 -263.380772) (xy 98.766077 -263.40435)
			(xy 98.808093 -263.434876) (xy 98.844816 -263.471599) (xy 98.875342 -263.513615) (xy 98.89892 -263.559889)
			(xy 98.914968 -263.609282) (xy 98.923093 -263.660577) (xy 98.923602 -263.686544) (xy 98.923093 -263.712511)
			(xy 99.203003 -263.712511) (xy 99.203003 -263.660577) (xy 99.211128 -263.609282) (xy 99.227176 -263.559889)
			(xy 99.250754 -263.513615) (xy 99.28128 -263.471599) (xy 99.318003 -263.434876) (xy 99.360019 -263.40435)
			(xy 99.406293 -263.380772) (xy 99.455686 -263.364724) (xy 99.506981 -263.356599) (xy 99.558915 -263.356599)
			(xy 99.61021 -263.364724) (xy 99.659603 -263.380772) (xy 99.705877 -263.40435) (xy 99.747893 -263.434876)
			(xy 99.784616 -263.471599) (xy 99.815142 -263.513615) (xy 99.83872 -263.559889) (xy 99.854768 -263.609282)
			(xy 99.862893 -263.660577) (xy 99.863402 -263.686544) (xy 99.862893 -263.712511) (xy 100.142803 -263.712511)
			(xy 100.142803 -263.660577) (xy 100.150928 -263.609282) (xy 100.166976 -263.559889) (xy 100.190554 -263.513615)
			(xy 100.22108 -263.471599) (xy 100.257803 -263.434876) (xy 100.299819 -263.40435) (xy 100.346093 -263.380772)
			(xy 100.395486 -263.364724) (xy 100.446781 -263.356599) (xy 100.498715 -263.356599) (xy 100.55001 -263.364724)
			(xy 100.599403 -263.380772) (xy 100.645677 -263.40435) (xy 100.687693 -263.434876) (xy 100.724416 -263.471599)
			(xy 100.754942 -263.513615) (xy 100.77852 -263.559889) (xy 100.794568 -263.609282) (xy 100.802693 -263.660577)
			(xy 100.803202 -263.686544) (xy 100.802693 -263.712511) (xy 101.082349 -263.712511) (xy 101.082349 -263.660577)
			(xy 101.090474 -263.609282) (xy 101.106522 -263.559889) (xy 101.1301 -263.513615) (xy 101.160626 -263.471599)
			(xy 101.197349 -263.434876) (xy 101.239365 -263.40435) (xy 101.285639 -263.380772) (xy 101.335032 -263.364724)
			(xy 101.386327 -263.356599) (xy 101.438261 -263.356599) (xy 101.489556 -263.364724) (xy 101.538949 -263.380772)
			(xy 101.585223 -263.40435) (xy 101.627239 -263.434876) (xy 101.663962 -263.471599) (xy 101.694488 -263.513615)
			(xy 101.718066 -263.559889) (xy 101.734114 -263.609282) (xy 101.742239 -263.660577) (xy 101.742748 -263.686544)
			(xy 101.742239 -263.712511) (xy 102.022403 -263.712511) (xy 102.022403 -263.660577) (xy 102.030528 -263.609282)
			(xy 102.046576 -263.559889) (xy 102.070154 -263.513615) (xy 102.10068 -263.471599) (xy 102.137403 -263.434876)
			(xy 102.179419 -263.40435) (xy 102.225693 -263.380772) (xy 102.275086 -263.364724) (xy 102.326381 -263.356599)
			(xy 102.378315 -263.356599) (xy 102.42961 -263.364724) (xy 102.479003 -263.380772) (xy 102.525277 -263.40435)
			(xy 102.567293 -263.434876) (xy 102.604016 -263.471599) (xy 102.634542 -263.513615) (xy 102.65812 -263.559889)
			(xy 102.674168 -263.609282) (xy 102.682293 -263.660577) (xy 102.682802 -263.686544) (xy 102.682293 -263.712511)
			(xy 102.674168 -263.763806) (xy 102.65812 -263.813199) (xy 102.634542 -263.859473) (xy 102.604016 -263.901489)
			(xy 102.567293 -263.938212) (xy 102.525277 -263.968738) (xy 102.479003 -263.992316) (xy 102.42961 -264.008364)
			(xy 102.378315 -264.016489) (xy 102.326381 -264.016489) (xy 102.275086 -264.008364) (xy 102.225693 -263.992316)
			(xy 102.179419 -263.968738) (xy 102.137403 -263.938212) (xy 102.10068 -263.901489) (xy 102.070154 -263.859473)
			(xy 102.046576 -263.813199) (xy 102.030528 -263.763806) (xy 102.022403 -263.712511) (xy 101.742239 -263.712511)
			(xy 101.734114 -263.763806) (xy 101.718066 -263.813199) (xy 101.694488 -263.859473) (xy 101.663962 -263.901489)
			(xy 101.627239 -263.938212) (xy 101.585223 -263.968738) (xy 101.538949 -263.992316) (xy 101.489556 -264.008364)
			(xy 101.438261 -264.016489) (xy 101.386327 -264.016489) (xy 101.335032 -264.008364) (xy 101.285639 -263.992316)
			(xy 101.239365 -263.968738) (xy 101.197349 -263.938212) (xy 101.160626 -263.901489) (xy 101.1301 -263.859473)
			(xy 101.106522 -263.813199) (xy 101.090474 -263.763806) (xy 101.082349 -263.712511) (xy 100.802693 -263.712511)
			(xy 100.794568 -263.763806) (xy 100.77852 -263.813199) (xy 100.754942 -263.859473) (xy 100.724416 -263.901489)
			(xy 100.687693 -263.938212) (xy 100.645677 -263.968738) (xy 100.599403 -263.992316) (xy 100.55001 -264.008364)
			(xy 100.498715 -264.016489) (xy 100.446781 -264.016489) (xy 100.395486 -264.008364) (xy 100.346093 -263.992316)
			(xy 100.299819 -263.968738) (xy 100.257803 -263.938212) (xy 100.22108 -263.901489) (xy 100.190554 -263.859473)
			(xy 100.166976 -263.813199) (xy 100.150928 -263.763806) (xy 100.142803 -263.712511) (xy 99.862893 -263.712511)
			(xy 99.854768 -263.763806) (xy 99.83872 -263.813199) (xy 99.815142 -263.859473) (xy 99.784616 -263.901489)
			(xy 99.747893 -263.938212) (xy 99.705877 -263.968738) (xy 99.659603 -263.992316) (xy 99.61021 -264.008364)
			(xy 99.558915 -264.016489) (xy 99.506981 -264.016489) (xy 99.455686 -264.008364) (xy 99.406293 -263.992316)
			(xy 99.360019 -263.968738) (xy 99.318003 -263.938212) (xy 99.28128 -263.901489) (xy 99.250754 -263.859473)
			(xy 99.227176 -263.813199) (xy 99.211128 -263.763806) (xy 99.203003 -263.712511) (xy 98.923093 -263.712511)
			(xy 98.914968 -263.763806) (xy 98.89892 -263.813199) (xy 98.875342 -263.859473) (xy 98.844816 -263.901489)
			(xy 98.808093 -263.938212) (xy 98.766077 -263.968738) (xy 98.719803 -263.992316) (xy 98.67041 -264.008364)
			(xy 98.619115 -264.016489) (xy 98.567181 -264.016489) (xy 98.515886 -264.008364) (xy 98.466493 -263.992316)
			(xy 98.420219 -263.968738) (xy 98.378203 -263.938212) (xy 98.34148 -263.901489) (xy 98.310954 -263.859473)
			(xy 98.287376 -263.813199) (xy 98.271328 -263.763806) (xy 98.263203 -263.712511) (xy 97.983293 -263.712511)
			(xy 97.975168 -263.763806) (xy 97.95912 -263.813199) (xy 97.935542 -263.859473) (xy 97.905016 -263.901489)
			(xy 97.868293 -263.938212) (xy 97.826277 -263.968738) (xy 97.780003 -263.992316) (xy 97.73061 -264.008364)
			(xy 97.679315 -264.016489) (xy 97.627381 -264.016489) (xy 97.576086 -264.008364) (xy 97.526693 -263.992316)
			(xy 97.480419 -263.968738) (xy 97.438403 -263.938212) (xy 97.40168 -263.901489) (xy 97.371154 -263.859473)
			(xy 97.347576 -263.813199) (xy 97.331528 -263.763806) (xy 97.323403 -263.712511) (xy 97.043493 -263.712511)
			(xy 97.035368 -263.763806) (xy 97.01932 -263.813199) (xy 96.995742 -263.859473) (xy 96.965216 -263.901489)
			(xy 96.928493 -263.938212) (xy 96.886477 -263.968738) (xy 96.840203 -263.992316) (xy 96.79081 -264.008364)
			(xy 96.739515 -264.016489) (xy 96.687581 -264.016489) (xy 96.636286 -264.008364) (xy 96.586893 -263.992316)
			(xy 96.540619 -263.968738) (xy 96.498603 -263.938212) (xy 96.46188 -263.901489) (xy 96.431354 -263.859473)
			(xy 96.407776 -263.813199) (xy 96.391728 -263.763806) (xy 96.383603 -263.712511) (xy 96.103693 -263.712511)
			(xy 96.095568 -263.763806) (xy 96.07952 -263.813199) (xy 96.055942 -263.859473) (xy 96.025416 -263.901489)
			(xy 95.988693 -263.938212) (xy 95.946677 -263.968738) (xy 95.900403 -263.992316) (xy 95.85101 -264.008364)
			(xy 95.799715 -264.016489) (xy 95.747781 -264.016489) (xy 95.696486 -264.008364) (xy 95.647093 -263.992316)
			(xy 95.600819 -263.968738) (xy 95.558803 -263.938212) (xy 95.52208 -263.901489) (xy 95.491554 -263.859473)
			(xy 95.467976 -263.813199) (xy 95.451928 -263.763806) (xy 95.443803 -263.712511) (xy 95.163639 -263.712511)
			(xy 95.155514 -263.763806) (xy 95.139466 -263.813199) (xy 95.115888 -263.859473) (xy 95.085362 -263.901489)
			(xy 95.048639 -263.938212) (xy 95.006623 -263.968738) (xy 94.960349 -263.992316) (xy 94.910956 -264.008364)
			(xy 94.859661 -264.016489) (xy 94.807727 -264.016489) (xy 94.756432 -264.008364) (xy 94.707039 -263.992316)
			(xy 94.660765 -263.968738) (xy 94.618749 -263.938212) (xy 94.582026 -263.901489) (xy 94.5515 -263.859473)
			(xy 94.527922 -263.813199) (xy 94.511874 -263.763806) (xy 94.503749 -263.712511) (xy 94.224093 -263.712511)
			(xy 94.215968 -263.763806) (xy 94.19992 -263.813199) (xy 94.176342 -263.859473) (xy 94.145816 -263.901489)
			(xy 94.109093 -263.938212) (xy 94.067077 -263.968738) (xy 94.020803 -263.992316) (xy 93.97141 -264.008364)
			(xy 93.920115 -264.016489) (xy 93.868181 -264.016489) (xy 93.816886 -264.008364) (xy 93.767493 -263.992316)
			(xy 93.721219 -263.968738) (xy 93.679203 -263.938212) (xy 93.64248 -263.901489) (xy 93.611954 -263.859473)
			(xy 93.588376 -263.813199) (xy 93.572328 -263.763806) (xy 93.564203 -263.712511) (xy 93.284293 -263.712511)
			(xy 93.276168 -263.763806) (xy 93.26012 -263.813199) (xy 93.236542 -263.859473) (xy 93.206016 -263.901489)
			(xy 93.169293 -263.938212) (xy 93.127277 -263.968738) (xy 93.081003 -263.992316) (xy 93.03161 -264.008364)
			(xy 92.980315 -264.016489) (xy 92.928381 -264.016489) (xy 92.877086 -264.008364) (xy 92.827693 -263.992316)
			(xy 92.781419 -263.968738) (xy 92.739403 -263.938212) (xy 92.70268 -263.901489) (xy 92.672154 -263.859473)
			(xy 92.648576 -263.813199) (xy 92.632528 -263.763806) (xy 92.624403 -263.712511) (xy 92.344649 -263.712511)
			(xy 92.336526 -263.763804) (xy 92.32047 -263.813224) (xy 92.296882 -263.859524) (xy 92.266341 -263.901565)
			(xy 92.229601 -263.93831) (xy 92.187565 -263.968857) (xy 92.141268 -263.992452) (xy 92.091851 -264.008515)
			(xy 92.040529 -264.016651) (xy 92.014548 -264.017252) (xy 91.991674 -264.016869) (xy 91.946362 -264.010572)
			(xy 91.902349 -263.998093) (xy 91.860475 -263.979669) (xy 91.840812 -263.967976) (xy 91.840558 -263.967722)
			(xy 91.833071 -263.963535) (xy 91.816298 -263.96) (xy 91.799314 -263.962323) (xy 91.791536 -263.965944)
			(xy 91.751658 -263.988042) (xy 91.713304 -264.009378) (xy 91.705718 -264.014017) (xy 91.694159 -264.027515)
			(xy 91.687993 -264.044181) (xy 91.68765 -264.053066) (xy 91.68765 -264.172192) (xy 91.712034 -264.214864)
			(xy 91.722702 -264.221722) (xy 91.743956 -264.235845) (xy 91.782246 -264.269576) (xy 91.814898 -264.30879)
			(xy 91.841135 -264.352556) (xy 91.860336 -264.399835) (xy 91.872043 -264.449502) (xy 91.875979 -264.500378)
			(xy 91.873975 -264.526327) (xy 92.154249 -264.526327) (xy 92.154249 -264.474393) (xy 92.162374 -264.423098)
			(xy 92.178422 -264.373705) (xy 92.202 -264.327431) (xy 92.232526 -264.285415) (xy 92.269249 -264.248692)
			(xy 92.311265 -264.218166) (xy 92.357539 -264.194588) (xy 92.406932 -264.17854) (xy 92.458227 -264.170415)
			(xy 92.510161 -264.170415) (xy 92.561456 -264.17854) (xy 92.610849 -264.194588) (xy 92.657123 -264.218166)
			(xy 92.699139 -264.248692) (xy 92.735862 -264.285415) (xy 92.766388 -264.327431) (xy 92.789966 -264.373705)
			(xy 92.806014 -264.423098) (xy 92.814139 -264.474393) (xy 92.814648 -264.50036) (xy 92.814139 -264.526327)
			(xy 93.094049 -264.526327) (xy 93.094049 -264.474393) (xy 93.102174 -264.423098) (xy 93.118222 -264.373705)
			(xy 93.1418 -264.327431) (xy 93.172326 -264.285415) (xy 93.209049 -264.248692) (xy 93.251065 -264.218166)
			(xy 93.297339 -264.194588) (xy 93.346732 -264.17854) (xy 93.398027 -264.170415) (xy 93.449961 -264.170415)
			(xy 93.501256 -264.17854) (xy 93.550649 -264.194588) (xy 93.596923 -264.218166) (xy 93.638939 -264.248692)
			(xy 93.675662 -264.285415) (xy 93.706188 -264.327431) (xy 93.729766 -264.373705) (xy 93.745814 -264.423098)
			(xy 93.753939 -264.474393) (xy 93.754448 -264.50036) (xy 93.753939 -264.526327) (xy 94.033849 -264.526327)
			(xy 94.033849 -264.474393) (xy 94.041974 -264.423098) (xy 94.058022 -264.373705) (xy 94.0816 -264.327431)
			(xy 94.112126 -264.285415) (xy 94.148849 -264.248692) (xy 94.190865 -264.218166) (xy 94.237139 -264.194588)
			(xy 94.286532 -264.17854) (xy 94.337827 -264.170415) (xy 94.389761 -264.170415) (xy 94.441056 -264.17854)
			(xy 94.490449 -264.194588) (xy 94.536723 -264.218166) (xy 94.578739 -264.248692) (xy 94.615462 -264.285415)
			(xy 94.645988 -264.327431) (xy 94.669566 -264.373705) (xy 94.685614 -264.423098) (xy 94.693739 -264.474393)
			(xy 94.694248 -264.50036) (xy 94.693739 -264.526327) (xy 94.973649 -264.526327) (xy 94.973649 -264.474393)
			(xy 94.981774 -264.423098) (xy 94.997822 -264.373705) (xy 95.0214 -264.327431) (xy 95.051926 -264.285415)
			(xy 95.088649 -264.248692) (xy 95.130665 -264.218166) (xy 95.176939 -264.194588) (xy 95.226332 -264.17854)
			(xy 95.277627 -264.170415) (xy 95.329561 -264.170415) (xy 95.380856 -264.17854) (xy 95.430249 -264.194588)
			(xy 95.476523 -264.218166) (xy 95.518539 -264.248692) (xy 95.555262 -264.285415) (xy 95.585788 -264.327431)
			(xy 95.609366 -264.373705) (xy 95.625414 -264.423098) (xy 95.633539 -264.474393) (xy 95.634048 -264.50036)
			(xy 95.633539 -264.526327) (xy 95.913449 -264.526327) (xy 95.913449 -264.474393) (xy 95.921574 -264.423098)
			(xy 95.937622 -264.373705) (xy 95.9612 -264.327431) (xy 95.991726 -264.285415) (xy 96.028449 -264.248692)
			(xy 96.070465 -264.218166) (xy 96.116739 -264.194588) (xy 96.166132 -264.17854) (xy 96.217427 -264.170415)
			(xy 96.269361 -264.170415) (xy 96.320656 -264.17854) (xy 96.370049 -264.194588) (xy 96.416323 -264.218166)
			(xy 96.458339 -264.248692) (xy 96.495062 -264.285415) (xy 96.525588 -264.327431) (xy 96.549166 -264.373705)
			(xy 96.565214 -264.423098) (xy 96.573339 -264.474393) (xy 96.573848 -264.50036) (xy 96.573339 -264.526327)
			(xy 96.853249 -264.526327) (xy 96.853249 -264.474393) (xy 96.861374 -264.423098) (xy 96.877422 -264.373705)
			(xy 96.901 -264.327431) (xy 96.931526 -264.285415) (xy 96.968249 -264.248692) (xy 97.010265 -264.218166)
			(xy 97.056539 -264.194588) (xy 97.105932 -264.17854) (xy 97.157227 -264.170415) (xy 97.209161 -264.170415)
			(xy 97.260456 -264.17854) (xy 97.309849 -264.194588) (xy 97.356123 -264.218166) (xy 97.398139 -264.248692)
			(xy 97.434862 -264.285415) (xy 97.465388 -264.327431) (xy 97.488966 -264.373705) (xy 97.505014 -264.423098)
			(xy 97.513139 -264.474393) (xy 97.513648 -264.50036) (xy 97.513139 -264.526327) (xy 97.793303 -264.526327)
			(xy 97.793303 -264.474393) (xy 97.801428 -264.423098) (xy 97.817476 -264.373705) (xy 97.841054 -264.327431)
			(xy 97.87158 -264.285415) (xy 97.908303 -264.248692) (xy 97.950319 -264.218166) (xy 97.996593 -264.194588)
			(xy 98.045986 -264.17854) (xy 98.097281 -264.170415) (xy 98.149215 -264.170415) (xy 98.20051 -264.17854)
			(xy 98.249903 -264.194588) (xy 98.296177 -264.218166) (xy 98.338193 -264.248692) (xy 98.374916 -264.285415)
			(xy 98.405442 -264.327431) (xy 98.42902 -264.373705) (xy 98.445068 -264.423098) (xy 98.453193 -264.474393)
			(xy 98.453702 -264.50036) (xy 98.453193 -264.526327) (xy 98.732849 -264.526327) (xy 98.732849 -264.474393)
			(xy 98.740974 -264.423098) (xy 98.757022 -264.373705) (xy 98.7806 -264.327431) (xy 98.811126 -264.285415)
			(xy 98.847849 -264.248692) (xy 98.889865 -264.218166) (xy 98.936139 -264.194588) (xy 98.985532 -264.17854)
			(xy 99.036827 -264.170415) (xy 99.088761 -264.170415) (xy 99.140056 -264.17854) (xy 99.189449 -264.194588)
			(xy 99.235723 -264.218166) (xy 99.277739 -264.248692) (xy 99.314462 -264.285415) (xy 99.344988 -264.327431)
			(xy 99.368566 -264.373705) (xy 99.384614 -264.423098) (xy 99.392739 -264.474393) (xy 99.393248 -264.50036)
			(xy 99.392739 -264.526327) (xy 99.672649 -264.526327) (xy 99.672649 -264.474393) (xy 99.680774 -264.423098)
			(xy 99.696822 -264.373705) (xy 99.7204 -264.327431) (xy 99.750926 -264.285415) (xy 99.787649 -264.248692)
			(xy 99.829665 -264.218166) (xy 99.875939 -264.194588) (xy 99.925332 -264.17854) (xy 99.976627 -264.170415)
			(xy 100.028561 -264.170415) (xy 100.079856 -264.17854) (xy 100.129249 -264.194588) (xy 100.175523 -264.218166)
			(xy 100.217539 -264.248692) (xy 100.254262 -264.285415) (xy 100.284788 -264.327431) (xy 100.308366 -264.373705)
			(xy 100.324414 -264.423098) (xy 100.332539 -264.474393) (xy 100.333048 -264.50036) (xy 100.332539 -264.526327)
			(xy 100.612449 -264.526327) (xy 100.612449 -264.474393) (xy 100.620574 -264.423098) (xy 100.636622 -264.373705)
			(xy 100.6602 -264.327431) (xy 100.690726 -264.285415) (xy 100.727449 -264.248692) (xy 100.769465 -264.218166)
			(xy 100.815739 -264.194588) (xy 100.865132 -264.17854) (xy 100.916427 -264.170415) (xy 100.968361 -264.170415)
			(xy 101.019656 -264.17854) (xy 101.069049 -264.194588) (xy 101.115323 -264.218166) (xy 101.157339 -264.248692)
			(xy 101.194062 -264.285415) (xy 101.224588 -264.327431) (xy 101.248166 -264.373705) (xy 101.264214 -264.423098)
			(xy 101.272339 -264.474393) (xy 101.272848 -264.50036) (xy 101.272339 -264.526327) (xy 101.552249 -264.526327)
			(xy 101.552249 -264.474393) (xy 101.560374 -264.423098) (xy 101.576422 -264.373705) (xy 101.6 -264.327431)
			(xy 101.630526 -264.285415) (xy 101.667249 -264.248692) (xy 101.709265 -264.218166) (xy 101.755539 -264.194588)
			(xy 101.804932 -264.17854) (xy 101.856227 -264.170415) (xy 101.908161 -264.170415) (xy 101.959456 -264.17854)
			(xy 102.008849 -264.194588) (xy 102.055123 -264.218166) (xy 102.097139 -264.248692) (xy 102.133862 -264.285415)
			(xy 102.164388 -264.327431) (xy 102.187966 -264.373705) (xy 102.204014 -264.423098) (xy 102.212139 -264.474393)
			(xy 102.212648 -264.50036) (xy 102.212139 -264.526327) (xy 102.492049 -264.526327) (xy 102.492049 -264.474393)
			(xy 102.500174 -264.423098) (xy 102.516222 -264.373705) (xy 102.5398 -264.327431) (xy 102.570326 -264.285415)
			(xy 102.607049 -264.248692) (xy 102.649065 -264.218166) (xy 102.695339 -264.194588) (xy 102.744732 -264.17854)
			(xy 102.796027 -264.170415) (xy 102.847961 -264.170415) (xy 102.899256 -264.17854) (xy 102.948649 -264.194588)
			(xy 102.994923 -264.218166) (xy 103.036939 -264.248692) (xy 103.073662 -264.285415) (xy 103.104188 -264.327431)
			(xy 103.127766 -264.373705) (xy 103.143814 -264.423098) (xy 103.151939 -264.474393) (xy 103.152448 -264.50036)
			(xy 103.151939 -264.526327) (xy 103.151932 -264.52637) (xy 103.431815 -264.52637) (xy 103.431815 -264.47443)
			(xy 103.43994 -264.423129) (xy 103.455991 -264.373731) (xy 103.479571 -264.327452) (xy 103.5101 -264.285432)
			(xy 103.546827 -264.248704) (xy 103.588847 -264.218174) (xy 103.635126 -264.194593) (xy 103.684523 -264.178542)
			(xy 103.735824 -264.170416) (xy 103.761794 -264.169906) (xy 103.787273 -264.170371) (xy 103.837625 -264.178214)
			(xy 103.886173 -264.193699) (xy 103.931767 -264.216459) (xy 103.973323 -264.245953) (xy 103.991918 -264.263378)
			(xy 106.338116 -261.91718) (xy 107.34294 -261.91718) (xy 107.35437 -261.911084) (xy 107.379022 -261.898087)
			(xy 107.431596 -261.879618) (xy 107.486528 -261.870257) (xy 107.51439 -261.869682) (xy 107.542249 -261.870283)
			(xy 107.597173 -261.879665) (xy 107.649754 -261.8981) (xy 107.67441 -261.911084) (xy 107.68584 -261.91718)
			(xy 108.349034 -261.91718) (xy 108.358178 -261.87781) (xy 108.365084 -261.850082) (xy 108.387093 -261.797352)
			(xy 108.417831 -261.749187) (xy 108.436664 -261.727696) (xy 108.446453 -261.716195) (xy 108.45947 -261.688962)
			(xy 108.463942 -261.659112) (xy 108.459477 -261.62926) (xy 108.446466 -261.602025) (xy 108.436664 -261.590536)
			(xy 108.420411 -261.572127) (xy 108.392939 -261.531425) (xy 108.371799 -261.487103) (xy 108.357455 -261.440139)
			(xy 108.350225 -261.391569) (xy 108.349796 -261.367016) (xy 108.350209 -261.342463) (xy 108.357455 -261.293895)
			(xy 108.371805 -261.246932) (xy 108.392943 -261.202608) (xy 108.420404 -261.161899) (xy 108.436664 -261.143496)
			(xy 108.446453 -261.131995) (xy 108.45947 -261.104762) (xy 108.463942 -261.074912) (xy 108.459477 -261.04506)
			(xy 108.446466 -261.017825) (xy 108.436664 -261.006336) (xy 108.420427 -260.987947) (xy 108.392977 -260.947291)
			(xy 108.371845 -260.903022) (xy 108.357495 -260.856113) (xy 108.350242 -260.807597) (xy 108.349796 -260.78307)
			(xy 108.349796 -260.782816) (xy 108.350305 -260.756849) (xy 108.35843 -260.705554) (xy 108.374478 -260.656161)
			(xy 108.398056 -260.609887) (xy 108.428582 -260.567871) (xy 108.465305 -260.531148) (xy 108.507321 -260.500622)
			(xy 108.553595 -260.477044) (xy 108.602988 -260.460996) (xy 108.654283 -260.452871) (xy 108.706217 -260.452871)
			(xy 108.73224 -260.456993) (xy 109.540803 -260.456993) (xy 109.540803 -260.405059) (xy 109.548928 -260.353764)
			(xy 109.564976 -260.304371) (xy 109.588554 -260.258097) (xy 109.61908 -260.216081) (xy 109.655803 -260.179358)
			(xy 109.697819 -260.148832) (xy 109.744093 -260.125254) (xy 109.793486 -260.109206) (xy 109.844781 -260.101081)
			(xy 109.896715 -260.101081) (xy 109.94801 -260.109206) (xy 109.997403 -260.125254) (xy 110.043677 -260.148832)
			(xy 110.085693 -260.179358) (xy 110.122416 -260.216081) (xy 110.152942 -260.258097) (xy 110.17652 -260.304371)
			(xy 110.192568 -260.353764) (xy 110.200693 -260.405059) (xy 110.201202 -260.431026) (xy 110.200693 -260.456993)
			(xy 110.480857 -260.456993) (xy 110.480857 -260.405059) (xy 110.488982 -260.353764) (xy 110.50503 -260.304371)
			(xy 110.528608 -260.258097) (xy 110.559134 -260.216081) (xy 110.595857 -260.179358) (xy 110.637873 -260.148832)
			(xy 110.684147 -260.125254) (xy 110.73354 -260.109206) (xy 110.784835 -260.101081) (xy 110.836769 -260.101081)
			(xy 110.888064 -260.109206) (xy 110.937457 -260.125254) (xy 110.983731 -260.148832) (xy 111.025747 -260.179358)
			(xy 111.06247 -260.216081) (xy 111.092996 -260.258097) (xy 111.116574 -260.304371) (xy 111.132622 -260.353764)
			(xy 111.140747 -260.405059) (xy 111.141256 -260.431026) (xy 111.140747 -260.456993) (xy 111.420403 -260.456993)
			(xy 111.420403 -260.405059) (xy 111.428528 -260.353764) (xy 111.444576 -260.304371) (xy 111.468154 -260.258097)
			(xy 111.49868 -260.216081) (xy 111.535403 -260.179358) (xy 111.577419 -260.148832) (xy 111.623693 -260.125254)
			(xy 111.673086 -260.109206) (xy 111.724381 -260.101081) (xy 111.776315 -260.101081) (xy 111.82761 -260.109206)
			(xy 111.877003 -260.125254) (xy 111.923277 -260.148832) (xy 111.965293 -260.179358) (xy 112.002016 -260.216081)
			(xy 112.032542 -260.258097) (xy 112.05612 -260.304371) (xy 112.072168 -260.353764) (xy 112.080293 -260.405059)
			(xy 112.080802 -260.431026) (xy 112.080293 -260.456993) (xy 112.360203 -260.456993) (xy 112.360203 -260.405059)
			(xy 112.368328 -260.353764) (xy 112.384376 -260.304371) (xy 112.407954 -260.258097) (xy 112.43848 -260.216081)
			(xy 112.475203 -260.179358) (xy 112.517219 -260.148832) (xy 112.563493 -260.125254) (xy 112.612886 -260.109206)
			(xy 112.664181 -260.101081) (xy 112.716115 -260.101081) (xy 112.76741 -260.109206) (xy 112.816803 -260.125254)
			(xy 112.863077 -260.148832) (xy 112.905093 -260.179358) (xy 112.941816 -260.216081) (xy 112.972342 -260.258097)
			(xy 112.99592 -260.304371) (xy 113.011968 -260.353764) (xy 113.020093 -260.405059) (xy 113.020602 -260.431026)
			(xy 113.020093 -260.456993) (xy 113.300003 -260.456993) (xy 113.300003 -260.405059) (xy 113.308128 -260.353764)
			(xy 113.324176 -260.304371) (xy 113.347754 -260.258097) (xy 113.37828 -260.216081) (xy 113.415003 -260.179358)
			(xy 113.457019 -260.148832) (xy 113.503293 -260.125254) (xy 113.552686 -260.109206) (xy 113.603981 -260.101081)
			(xy 113.655915 -260.101081) (xy 113.70721 -260.109206) (xy 113.756603 -260.125254) (xy 113.802877 -260.148832)
			(xy 113.844893 -260.179358) (xy 113.881616 -260.216081) (xy 113.912142 -260.258097) (xy 113.93572 -260.304371)
			(xy 113.951768 -260.353764) (xy 113.959893 -260.405059) (xy 113.960402 -260.431026) (xy 113.959893 -260.456993)
			(xy 114.239803 -260.456993) (xy 114.239803 -260.405059) (xy 114.247928 -260.353764) (xy 114.263976 -260.304371)
			(xy 114.287554 -260.258097) (xy 114.31808 -260.216081) (xy 114.354803 -260.179358) (xy 114.396819 -260.148832)
			(xy 114.443093 -260.125254) (xy 114.492486 -260.109206) (xy 114.543781 -260.101081) (xy 114.595715 -260.101081)
			(xy 114.64701 -260.109206) (xy 114.696403 -260.125254) (xy 114.742677 -260.148832) (xy 114.784693 -260.179358)
			(xy 114.821416 -260.216081) (xy 114.851942 -260.258097) (xy 114.87552 -260.304371) (xy 114.891568 -260.353764)
			(xy 114.899693 -260.405059) (xy 114.900202 -260.431026) (xy 114.899693 -260.456993) (xy 114.891568 -260.508288)
			(xy 114.87552 -260.557681) (xy 114.851942 -260.603955) (xy 114.821416 -260.645971) (xy 114.784693 -260.682694)
			(xy 114.742677 -260.71322) (xy 114.696403 -260.736798) (xy 114.64701 -260.752846) (xy 114.595715 -260.760971)
			(xy 114.543781 -260.760971) (xy 114.492486 -260.752846) (xy 114.443093 -260.736798) (xy 114.396819 -260.71322)
			(xy 114.354803 -260.682694) (xy 114.31808 -260.645971) (xy 114.287554 -260.603955) (xy 114.263976 -260.557681)
			(xy 114.247928 -260.508288) (xy 114.239803 -260.456993) (xy 113.959893 -260.456993) (xy 113.951768 -260.508288)
			(xy 113.93572 -260.557681) (xy 113.912142 -260.603955) (xy 113.881616 -260.645971) (xy 113.844893 -260.682694)
			(xy 113.802877 -260.71322) (xy 113.756603 -260.736798) (xy 113.70721 -260.752846) (xy 113.655915 -260.760971)
			(xy 113.603981 -260.760971) (xy 113.552686 -260.752846) (xy 113.503293 -260.736798) (xy 113.457019 -260.71322)
			(xy 113.415003 -260.682694) (xy 113.37828 -260.645971) (xy 113.347754 -260.603955) (xy 113.324176 -260.557681)
			(xy 113.308128 -260.508288) (xy 113.300003 -260.456993) (xy 113.020093 -260.456993) (xy 113.011968 -260.508288)
			(xy 112.99592 -260.557681) (xy 112.972342 -260.603955) (xy 112.941816 -260.645971) (xy 112.905093 -260.682694)
			(xy 112.863077 -260.71322) (xy 112.816803 -260.736798) (xy 112.76741 -260.752846) (xy 112.716115 -260.760971)
			(xy 112.664181 -260.760971) (xy 112.612886 -260.752846) (xy 112.563493 -260.736798) (xy 112.517219 -260.71322)
			(xy 112.475203 -260.682694) (xy 112.43848 -260.645971) (xy 112.407954 -260.603955) (xy 112.384376 -260.557681)
			(xy 112.368328 -260.508288) (xy 112.360203 -260.456993) (xy 112.080293 -260.456993) (xy 112.072168 -260.508288)
			(xy 112.05612 -260.557681) (xy 112.032542 -260.603955) (xy 112.002016 -260.645971) (xy 111.965293 -260.682694)
			(xy 111.923277 -260.71322) (xy 111.877003 -260.736798) (xy 111.82761 -260.752846) (xy 111.776315 -260.760971)
			(xy 111.724381 -260.760971) (xy 111.673086 -260.752846) (xy 111.623693 -260.736798) (xy 111.577419 -260.71322)
			(xy 111.535403 -260.682694) (xy 111.49868 -260.645971) (xy 111.468154 -260.603955) (xy 111.444576 -260.557681)
			(xy 111.428528 -260.508288) (xy 111.420403 -260.456993) (xy 111.140747 -260.456993) (xy 111.132622 -260.508288)
			(xy 111.116574 -260.557681) (xy 111.092996 -260.603955) (xy 111.06247 -260.645971) (xy 111.025747 -260.682694)
			(xy 110.983731 -260.71322) (xy 110.937457 -260.736798) (xy 110.888064 -260.752846) (xy 110.836769 -260.760971)
			(xy 110.784835 -260.760971) (xy 110.73354 -260.752846) (xy 110.684147 -260.736798) (xy 110.637873 -260.71322)
			(xy 110.595857 -260.682694) (xy 110.559134 -260.645971) (xy 110.528608 -260.603955) (xy 110.50503 -260.557681)
			(xy 110.488982 -260.508288) (xy 110.480857 -260.456993) (xy 110.200693 -260.456993) (xy 110.192568 -260.508288)
			(xy 110.17652 -260.557681) (xy 110.152942 -260.603955) (xy 110.122416 -260.645971) (xy 110.085693 -260.682694)
			(xy 110.043677 -260.71322) (xy 109.997403 -260.736798) (xy 109.94801 -260.752846) (xy 109.896715 -260.760971)
			(xy 109.844781 -260.760971) (xy 109.793486 -260.752846) (xy 109.744093 -260.736798) (xy 109.697819 -260.71322)
			(xy 109.655803 -260.682694) (xy 109.61908 -260.645971) (xy 109.588554 -260.603955) (xy 109.564976 -260.557681)
			(xy 109.548928 -260.508288) (xy 109.540803 -260.456993) (xy 108.73224 -260.456993) (xy 108.757512 -260.460996)
			(xy 108.806905 -260.477044) (xy 108.853179 -260.500622) (xy 108.895195 -260.531148) (xy 108.931918 -260.567871)
			(xy 108.962444 -260.609887) (xy 108.986022 -260.656161) (xy 109.00207 -260.705554) (xy 109.010195 -260.756849)
			(xy 109.010704 -260.782816) (xy 109.010704 -260.78307) (xy 109.010233 -260.807596) (xy 109.002975 -260.856108)
			(xy 108.988628 -260.903015) (xy 108.967507 -260.947287) (xy 108.940076 -260.987952) (xy 108.923836 -261.006336)
			(xy 108.914016 -261.017812) (xy 108.901003 -261.045054) (xy 108.896537 -261.074912) (xy 108.901009 -261.104769)
			(xy 108.914029 -261.132007) (xy 108.923836 -261.143496) (xy 108.926376 -261.146544) (xy 108.936497 -261.157159)
			(xy 108.961467 -261.172527) (xy 108.989772 -261.180174) (xy 109.019084 -261.17947) (xy 109.04699 -261.170473)
			(xy 109.071193 -261.153925) (xy 109.089702 -261.131185) (xy 109.095794 -261.117842) (xy 109.105574 -261.095599)
			(xy 109.130648 -261.05398) (xy 109.161545 -261.016482) (xy 109.197601 -260.983912) (xy 109.238037 -260.956973)
			(xy 109.281982 -260.936245) (xy 109.328489 -260.922176) (xy 109.376554 -260.915068) (xy 109.400848 -260.914642)
			(xy 109.426812 -260.915163) (xy 109.478101 -260.923293) (xy 109.527487 -260.939346) (xy 109.573753 -260.962926)
			(xy 109.615762 -260.993452) (xy 109.652479 -261.030174) (xy 109.682999 -261.072188) (xy 109.706573 -261.118458)
			(xy 109.722618 -261.167846) (xy 109.730741 -261.219135) (xy 109.730741 -261.271063) (xy 110.010449 -261.271063)
			(xy 110.010449 -261.219129) (xy 110.018574 -261.167834) (xy 110.034622 -261.118441) (xy 110.0582 -261.072167)
			(xy 110.088726 -261.030151) (xy 110.125449 -260.993428) (xy 110.167465 -260.962902) (xy 110.213739 -260.939324)
			(xy 110.263132 -260.923276) (xy 110.314427 -260.915151) (xy 110.366361 -260.915151) (xy 110.417656 -260.923276)
			(xy 110.467049 -260.939324) (xy 110.513323 -260.962902) (xy 110.555339 -260.993428) (xy 110.592062 -261.030151)
			(xy 110.622588 -261.072167) (xy 110.646166 -261.118441) (xy 110.662214 -261.167834) (xy 110.670339 -261.219129)
			(xy 110.670848 -261.245096) (xy 110.670339 -261.271063) (xy 110.950757 -261.271063) (xy 110.950757 -261.219129)
			(xy 110.958882 -261.167834) (xy 110.97493 -261.118441) (xy 110.998508 -261.072167) (xy 111.029034 -261.030151)
			(xy 111.065757 -260.993428) (xy 111.107773 -260.962902) (xy 111.154047 -260.939324) (xy 111.20344 -260.923276)
			(xy 111.254735 -260.915151) (xy 111.306669 -260.915151) (xy 111.357964 -260.923276) (xy 111.407357 -260.939324)
			(xy 111.453631 -260.962902) (xy 111.495647 -260.993428) (xy 111.53237 -261.030151) (xy 111.562896 -261.072167)
			(xy 111.586474 -261.118441) (xy 111.602522 -261.167834) (xy 111.610647 -261.219129) (xy 111.611156 -261.245096)
			(xy 111.610647 -261.271063) (xy 111.890557 -261.271063) (xy 111.890557 -261.219129) (xy 111.898682 -261.167834)
			(xy 111.91473 -261.118441) (xy 111.938308 -261.072167) (xy 111.968834 -261.030151) (xy 112.005557 -260.993428)
			(xy 112.047573 -260.962902) (xy 112.093847 -260.939324) (xy 112.14324 -260.923276) (xy 112.194535 -260.915151)
			(xy 112.246469 -260.915151) (xy 112.297764 -260.923276) (xy 112.347157 -260.939324) (xy 112.393431 -260.962902)
			(xy 112.435447 -260.993428) (xy 112.47217 -261.030151) (xy 112.502696 -261.072167) (xy 112.526274 -261.118441)
			(xy 112.542322 -261.167834) (xy 112.550447 -261.219129) (xy 112.550956 -261.245096) (xy 112.550447 -261.271063)
			(xy 112.829849 -261.271063) (xy 112.829849 -261.219129) (xy 112.837974 -261.167834) (xy 112.854022 -261.118441)
			(xy 112.8776 -261.072167) (xy 112.908126 -261.030151) (xy 112.944849 -260.993428) (xy 112.986865 -260.962902)
			(xy 113.033139 -260.939324) (xy 113.082532 -260.923276) (xy 113.133827 -260.915151) (xy 113.185761 -260.915151)
			(xy 113.237056 -260.923276) (xy 113.286449 -260.939324) (xy 113.332723 -260.962902) (xy 113.374739 -260.993428)
			(xy 113.411462 -261.030151) (xy 113.441988 -261.072167) (xy 113.465566 -261.118441) (xy 113.481614 -261.167834)
			(xy 113.489739 -261.219129) (xy 113.490248 -261.245096) (xy 113.489739 -261.271063) (xy 113.770157 -261.271063)
			(xy 113.770157 -261.219129) (xy 113.778282 -261.167834) (xy 113.79433 -261.118441) (xy 113.817908 -261.072167)
			(xy 113.848434 -261.030151) (xy 113.885157 -260.993428) (xy 113.927173 -260.962902) (xy 113.973447 -260.939324)
			(xy 114.02284 -260.923276) (xy 114.074135 -260.915151) (xy 114.126069 -260.915151) (xy 114.177364 -260.923276)
			(xy 114.226757 -260.939324) (xy 114.273031 -260.962902) (xy 114.315047 -260.993428) (xy 114.35177 -261.030151)
			(xy 114.382296 -261.072167) (xy 114.405874 -261.118441) (xy 114.421922 -261.167834) (xy 114.430047 -261.219129)
			(xy 114.430556 -261.245096) (xy 114.430047 -261.271063) (xy 114.421922 -261.322358) (xy 114.405874 -261.371751)
			(xy 114.382296 -261.418025) (xy 114.35177 -261.460041) (xy 114.315047 -261.496764) (xy 114.273031 -261.52729)
			(xy 114.226757 -261.550868) (xy 114.177364 -261.566916) (xy 114.126069 -261.575041) (xy 114.074135 -261.575041)
			(xy 114.02284 -261.566916) (xy 113.973447 -261.550868) (xy 113.927173 -261.52729) (xy 113.885157 -261.496764)
			(xy 113.848434 -261.460041) (xy 113.817908 -261.418025) (xy 113.79433 -261.371751) (xy 113.778282 -261.322358)
			(xy 113.770157 -261.271063) (xy 113.489739 -261.271063) (xy 113.481614 -261.322358) (xy 113.465566 -261.371751)
			(xy 113.441988 -261.418025) (xy 113.411462 -261.460041) (xy 113.374739 -261.496764) (xy 113.332723 -261.52729)
			(xy 113.286449 -261.550868) (xy 113.237056 -261.566916) (xy 113.185761 -261.575041) (xy 113.133827 -261.575041)
			(xy 113.082532 -261.566916) (xy 113.033139 -261.550868) (xy 112.986865 -261.52729) (xy 112.944849 -261.496764)
			(xy 112.908126 -261.460041) (xy 112.8776 -261.418025) (xy 112.854022 -261.371751) (xy 112.837974 -261.322358)
			(xy 112.829849 -261.271063) (xy 112.550447 -261.271063) (xy 112.542322 -261.322358) (xy 112.526274 -261.371751)
			(xy 112.502696 -261.418025) (xy 112.47217 -261.460041) (xy 112.435447 -261.496764) (xy 112.393431 -261.52729)
			(xy 112.347157 -261.550868) (xy 112.297764 -261.566916) (xy 112.246469 -261.575041) (xy 112.194535 -261.575041)
			(xy 112.14324 -261.566916) (xy 112.093847 -261.550868) (xy 112.047573 -261.52729) (xy 112.005557 -261.496764)
			(xy 111.968834 -261.460041) (xy 111.938308 -261.418025) (xy 111.91473 -261.371751) (xy 111.898682 -261.322358)
			(xy 111.890557 -261.271063) (xy 111.610647 -261.271063) (xy 111.602522 -261.322358) (xy 111.586474 -261.371751)
			(xy 111.562896 -261.418025) (xy 111.53237 -261.460041) (xy 111.495647 -261.496764) (xy 111.453631 -261.52729)
			(xy 111.407357 -261.550868) (xy 111.357964 -261.566916) (xy 111.306669 -261.575041) (xy 111.254735 -261.575041)
			(xy 111.20344 -261.566916) (xy 111.154047 -261.550868) (xy 111.107773 -261.52729) (xy 111.065757 -261.496764)
			(xy 111.029034 -261.460041) (xy 110.998508 -261.418025) (xy 110.97493 -261.371751) (xy 110.958882 -261.322358)
			(xy 110.950757 -261.271063) (xy 110.670339 -261.271063) (xy 110.662214 -261.322358) (xy 110.646166 -261.371751)
			(xy 110.622588 -261.418025) (xy 110.592062 -261.460041) (xy 110.555339 -261.496764) (xy 110.513323 -261.52729)
			(xy 110.467049 -261.550868) (xy 110.417656 -261.566916) (xy 110.366361 -261.575041) (xy 110.314427 -261.575041)
			(xy 110.263132 -261.566916) (xy 110.213739 -261.550868) (xy 110.167465 -261.52729) (xy 110.125449 -261.496764)
			(xy 110.088726 -261.460041) (xy 110.0582 -261.418025) (xy 110.034622 -261.371751) (xy 110.018574 -261.322358)
			(xy 110.010449 -261.271063) (xy 109.730741 -261.271063) (xy 109.730741 -261.271065) (xy 109.722618 -261.322354)
			(xy 109.706573 -261.371742) (xy 109.682999 -261.418012) (xy 109.652479 -261.460026) (xy 109.615762 -261.496748)
			(xy 109.573753 -261.527274) (xy 109.527487 -261.550854) (xy 109.478101 -261.566907) (xy 109.426812 -261.575037)
			(xy 109.400848 -261.57555) (xy 109.373064 -261.574961) (xy 109.318279 -261.56566) (xy 109.265821 -261.547329)
			(xy 109.217167 -261.520484) (xy 109.173687 -261.485881) (xy 109.154722 -261.465568) (xy 109.144582 -261.454977)
			(xy 109.119615 -261.439626) (xy 109.091318 -261.431989) (xy 109.062017 -261.432694) (xy 109.03412 -261.441682)
			(xy 109.009919 -261.458216) (xy 108.991403 -261.480936) (xy 108.985304 -261.49427) (xy 108.973703 -261.520547)
			(xy 108.942788 -261.568951) (xy 108.923836 -261.590536) (xy 108.914016 -261.602012) (xy 108.901003 -261.629254)
			(xy 108.896537 -261.659112) (xy 108.901009 -261.688969) (xy 108.914029 -261.716207) (xy 108.923836 -261.727696)
			(xy 108.94268 -261.74918) (xy 108.97343 -261.797341) (xy 108.995432 -261.850076) (xy 109.002322 -261.87781)
			(xy 109.011466 -261.91718) (xy 109.572298 -261.91718) (xy 109.584201 -261.893362) (xy 109.614459 -261.849552)
			(xy 109.65135 -261.811161) (xy 109.693921 -261.779184) (xy 109.741068 -261.754447) (xy 109.791573 -261.737591)
			(xy 109.844127 -261.729053) (xy 109.897369 -261.729053) (xy 109.949923 -261.737591) (xy 110.000428 -261.754447)
			(xy 110.047575 -261.779184) (xy 110.090146 -261.811161) (xy 110.127037 -261.849552) (xy 110.157295 -261.893362)
			(xy 110.169198 -261.91718) (xy 110.512352 -261.91718) (xy 110.524255 -261.893362) (xy 110.554513 -261.849552)
			(xy 110.591404 -261.811161) (xy 110.633975 -261.779184) (xy 110.681122 -261.754447) (xy 110.731627 -261.737591)
			(xy 110.784181 -261.729053) (xy 110.837423 -261.729053) (xy 110.889977 -261.737591) (xy 110.940482 -261.754447)
			(xy 110.987629 -261.779184) (xy 111.0302 -261.811161) (xy 111.067091 -261.849552) (xy 111.097349 -261.893362)
			(xy 111.109252 -261.91718) (xy 111.451898 -261.91718) (xy 111.463801 -261.893362) (xy 111.494059 -261.849552)
			(xy 111.53095 -261.811161) (xy 111.573521 -261.779184) (xy 111.620668 -261.754447) (xy 111.671173 -261.737591)
			(xy 111.723727 -261.729053) (xy 111.776969 -261.729053) (xy 111.829523 -261.737591) (xy 111.880028 -261.754447)
			(xy 111.927175 -261.779184) (xy 111.969746 -261.811161) (xy 112.006637 -261.849552) (xy 112.036895 -261.893362)
			(xy 112.048798 -261.91718) (xy 112.391698 -261.91718) (xy 112.403601 -261.893362) (xy 112.433859 -261.849552)
			(xy 112.47075 -261.811161) (xy 112.513321 -261.779184) (xy 112.560468 -261.754447) (xy 112.610973 -261.737591)
			(xy 112.663527 -261.729053) (xy 112.716769 -261.729053) (xy 112.769323 -261.737591) (xy 112.819828 -261.754447)
			(xy 112.866975 -261.779184) (xy 112.909546 -261.811161) (xy 112.946437 -261.849552) (xy 112.976695 -261.893362)
			(xy 112.988598 -261.91718) (xy 113.331498 -261.91718) (xy 113.343401 -261.893362) (xy 113.373659 -261.849552)
			(xy 113.41055 -261.811161) (xy 113.453121 -261.779184) (xy 113.500268 -261.754447) (xy 113.550773 -261.737591)
			(xy 113.603327 -261.729053) (xy 113.656569 -261.729053) (xy 113.709123 -261.737591) (xy 113.759628 -261.754447)
			(xy 113.806775 -261.779184) (xy 113.849346 -261.811161) (xy 113.886237 -261.849552) (xy 113.916495 -261.893362)
			(xy 113.928398 -261.91718) (xy 114.271298 -261.91718) (xy 114.283201 -261.893362) (xy 114.313459 -261.849552)
			(xy 114.35035 -261.811161) (xy 114.392921 -261.779184) (xy 114.440068 -261.754447) (xy 114.490573 -261.737591)
			(xy 114.543127 -261.729053) (xy 114.596369 -261.729053) (xy 114.648923 -261.737591) (xy 114.699428 -261.754447)
			(xy 114.746575 -261.779184) (xy 114.789146 -261.811161) (xy 114.826037 -261.849552) (xy 114.856295 -261.893362)
			(xy 114.868198 -261.91718) (xy 116.045234 -261.91718) (xy 116.060784 -261.895537) (xy 116.097694 -261.857099)
			(xy 116.140293 -261.825081) (xy 116.187477 -261.800312) (xy 116.238023 -261.783434) (xy 116.290623 -261.774884)
			(xy 116.343913 -261.774884) (xy 116.396513 -261.783434) (xy 116.447059 -261.800312) (xy 116.494243 -261.825081)
			(xy 116.536842 -261.857099) (xy 116.573752 -261.895537) (xy 116.589302 -261.91718) (xy 118.377716 -261.91718)
			(xy 119.876316 -260.41858) (xy 121.755154 -260.41858) (xy 121.762266 -260.376162) (xy 121.76702 -260.350798)
			(xy 121.783356 -260.30185) (xy 121.807102 -260.256037) (xy 121.837681 -260.214472) (xy 121.87435 -260.178166)
			(xy 121.916217 -260.148001) (xy 121.962265 -260.124712) (xy 122.011373 -260.108864) (xy 122.062347 -260.100842)
			(xy 122.113949 -260.100842) (xy 122.164923 -260.108864) (xy 122.214031 -260.124712) (xy 122.260079 -260.148001)
			(xy 122.301946 -260.178166) (xy 122.338615 -260.214472) (xy 122.369194 -260.256037) (xy 122.39294 -260.30185)
			(xy 122.409276 -260.350798) (xy 122.41403 -260.376162) (xy 122.421142 -260.41858) (xy 122.694954 -260.41858)
			(xy 122.702066 -260.376162) (xy 122.706801 -260.350792) (xy 122.723131 -260.301836) (xy 122.746874 -260.256015)
			(xy 122.777454 -260.214444) (xy 122.814125 -260.178132) (xy 122.855996 -260.147965) (xy 122.902049 -260.124674)
			(xy 122.951164 -260.108828) (xy 123.002144 -260.100811) (xy 123.027948 -260.100318) (xy 123.054933 -260.100815)
			(xy 123.108182 -260.109607) (xy 123.159295 -260.126933) (xy 123.206914 -260.152333) (xy 123.249775 -260.185131)
			(xy 123.286737 -260.224457) (xy 123.31682 -260.269265) (xy 123.339223 -260.318365) (xy 123.353352 -260.370453)
			(xy 123.356624 -260.397244) (xy 123.36145 -260.442964) (xy 123.634246 -260.442964) (xy 123.639072 -260.397244)
			(xy 123.642365 -260.370454) (xy 123.656472 -260.31836) (xy 123.678862 -260.269253) (xy 123.708938 -260.224439)
			(xy 123.745899 -260.185111) (xy 123.788763 -260.152316) (xy 123.836389 -260.126926) (xy 123.887509 -260.109618)
			(xy 123.940763 -260.10085) (xy 123.967748 -260.100318) (xy 123.993715 -260.100811) (xy 124.045009 -260.108941)
			(xy 124.0944 -260.124995) (xy 124.140672 -260.148576) (xy 124.182686 -260.179105) (xy 124.219408 -260.215829)
			(xy 124.249934 -260.257845) (xy 124.273513 -260.304118) (xy 124.289563 -260.35351) (xy 124.297691 -260.404805)
			(xy 124.298202 -260.430772) (xy 124.297762 -260.454273) (xy 124.297409 -260.456739) (xy 124.577603 -260.456739)
			(xy 124.577603 -260.404805) (xy 124.585728 -260.35351) (xy 124.601776 -260.304117) (xy 124.625354 -260.257843)
			(xy 124.65588 -260.215827) (xy 124.692603 -260.179104) (xy 124.734619 -260.148578) (xy 124.780893 -260.125)
			(xy 124.830286 -260.108952) (xy 124.881581 -260.100827) (xy 124.933515 -260.100827) (xy 124.98481 -260.108952)
			(xy 125.034203 -260.125) (xy 125.080477 -260.148578) (xy 125.122493 -260.179104) (xy 125.159216 -260.215827)
			(xy 125.189742 -260.257843) (xy 125.21332 -260.304117) (xy 125.229368 -260.35351) (xy 125.237493 -260.404805)
			(xy 125.238002 -260.430772) (xy 125.237493 -260.456739) (xy 125.517403 -260.456739) (xy 125.517403 -260.404805)
			(xy 125.525528 -260.35351) (xy 125.541576 -260.304117) (xy 125.565154 -260.257843) (xy 125.59568 -260.215827)
			(xy 125.632403 -260.179104) (xy 125.674419 -260.148578) (xy 125.720693 -260.125) (xy 125.770086 -260.108952)
			(xy 125.821381 -260.100827) (xy 125.873315 -260.100827) (xy 125.92461 -260.108952) (xy 125.974003 -260.125)
			(xy 126.020277 -260.148578) (xy 126.062293 -260.179104) (xy 126.099016 -260.215827) (xy 126.129542 -260.257843)
			(xy 126.15312 -260.304117) (xy 126.169168 -260.35351) (xy 126.177293 -260.404805) (xy 126.177802 -260.430772)
			(xy 126.177293 -260.456739) (xy 126.456949 -260.456739) (xy 126.456949 -260.404805) (xy 126.465074 -260.35351)
			(xy 126.481122 -260.304117) (xy 126.5047 -260.257843) (xy 126.535226 -260.215827) (xy 126.571949 -260.179104)
			(xy 126.613965 -260.148578) (xy 126.660239 -260.125) (xy 126.709632 -260.108952) (xy 126.760927 -260.100827)
			(xy 126.812861 -260.100827) (xy 126.864156 -260.108952) (xy 126.913549 -260.125) (xy 126.959823 -260.148578)
			(xy 127.001839 -260.179104) (xy 127.038562 -260.215827) (xy 127.069088 -260.257843) (xy 127.092666 -260.304117)
			(xy 127.108714 -260.35351) (xy 127.116839 -260.404805) (xy 127.117348 -260.430772) (xy 127.116839 -260.456739)
			(xy 127.397003 -260.456739) (xy 127.397003 -260.404805) (xy 127.405128 -260.35351) (xy 127.421176 -260.304117)
			(xy 127.444754 -260.257843) (xy 127.47528 -260.215827) (xy 127.512003 -260.179104) (xy 127.554019 -260.148578)
			(xy 127.600293 -260.125) (xy 127.649686 -260.108952) (xy 127.700981 -260.100827) (xy 127.752915 -260.100827)
			(xy 127.80421 -260.108952) (xy 127.853603 -260.125) (xy 127.899877 -260.148578) (xy 127.941893 -260.179104)
			(xy 127.978616 -260.215827) (xy 128.009142 -260.257843) (xy 128.03272 -260.304117) (xy 128.048768 -260.35351)
			(xy 128.056893 -260.404805) (xy 128.057402 -260.430772) (xy 128.056893 -260.456739) (xy 128.336803 -260.456739)
			(xy 128.336803 -260.404805) (xy 128.344928 -260.35351) (xy 128.360976 -260.304117) (xy 128.384554 -260.257843)
			(xy 128.41508 -260.215827) (xy 128.451803 -260.179104) (xy 128.493819 -260.148578) (xy 128.540093 -260.125)
			(xy 128.589486 -260.108952) (xy 128.640781 -260.100827) (xy 128.692715 -260.100827) (xy 128.74401 -260.108952)
			(xy 128.793403 -260.125) (xy 128.839677 -260.148578) (xy 128.881693 -260.179104) (xy 128.918416 -260.215827)
			(xy 128.948942 -260.257843) (xy 128.97252 -260.304117) (xy 128.988568 -260.35351) (xy 128.996693 -260.404805)
			(xy 128.997202 -260.430772) (xy 128.996693 -260.456739) (xy 129.276603 -260.456739) (xy 129.276603 -260.404805)
			(xy 129.284728 -260.35351) (xy 129.300776 -260.304117) (xy 129.324354 -260.257843) (xy 129.35488 -260.215827)
			(xy 129.391603 -260.179104) (xy 129.433619 -260.148578) (xy 129.479893 -260.125) (xy 129.529286 -260.108952)
			(xy 129.580581 -260.100827) (xy 129.632515 -260.100827) (xy 129.68381 -260.108952) (xy 129.733203 -260.125)
			(xy 129.779477 -260.148578) (xy 129.821493 -260.179104) (xy 129.858216 -260.215827) (xy 129.888742 -260.257843)
			(xy 129.91232 -260.304117) (xy 129.928368 -260.35351) (xy 129.936493 -260.404805) (xy 129.937002 -260.430772)
			(xy 129.936493 -260.456739) (xy 129.928368 -260.508034) (xy 129.91232 -260.557427) (xy 129.888742 -260.603701)
			(xy 129.858216 -260.645717) (xy 129.821493 -260.68244) (xy 129.779477 -260.712966) (xy 129.733203 -260.736544)
			(xy 129.68381 -260.752592) (xy 129.632515 -260.760717) (xy 129.580581 -260.760717) (xy 129.529286 -260.752592)
			(xy 129.479893 -260.736544) (xy 129.433619 -260.712966) (xy 129.391603 -260.68244) (xy 129.35488 -260.645717)
			(xy 129.324354 -260.603701) (xy 129.300776 -260.557427) (xy 129.284728 -260.508034) (xy 129.276603 -260.456739)
			(xy 128.996693 -260.456739) (xy 128.988568 -260.508034) (xy 128.97252 -260.557427) (xy 128.948942 -260.603701)
			(xy 128.918416 -260.645717) (xy 128.881693 -260.68244) (xy 128.839677 -260.712966) (xy 128.793403 -260.736544)
			(xy 128.74401 -260.752592) (xy 128.692715 -260.760717) (xy 128.640781 -260.760717) (xy 128.589486 -260.752592)
			(xy 128.540093 -260.736544) (xy 128.493819 -260.712966) (xy 128.451803 -260.68244) (xy 128.41508 -260.645717)
			(xy 128.384554 -260.603701) (xy 128.360976 -260.557427) (xy 128.344928 -260.508034) (xy 128.336803 -260.456739)
			(xy 128.056893 -260.456739) (xy 128.048768 -260.508034) (xy 128.03272 -260.557427) (xy 128.009142 -260.603701)
			(xy 127.978616 -260.645717) (xy 127.941893 -260.68244) (xy 127.899877 -260.712966) (xy 127.853603 -260.736544)
			(xy 127.80421 -260.752592) (xy 127.752915 -260.760717) (xy 127.700981 -260.760717) (xy 127.649686 -260.752592)
			(xy 127.600293 -260.736544) (xy 127.554019 -260.712966) (xy 127.512003 -260.68244) (xy 127.47528 -260.645717)
			(xy 127.444754 -260.603701) (xy 127.421176 -260.557427) (xy 127.405128 -260.508034) (xy 127.397003 -260.456739)
			(xy 127.116839 -260.456739) (xy 127.108714 -260.508034) (xy 127.092666 -260.557427) (xy 127.069088 -260.603701)
			(xy 127.038562 -260.645717) (xy 127.001839 -260.68244) (xy 126.959823 -260.712966) (xy 126.913549 -260.736544)
			(xy 126.864156 -260.752592) (xy 126.812861 -260.760717) (xy 126.760927 -260.760717) (xy 126.709632 -260.752592)
			(xy 126.660239 -260.736544) (xy 126.613965 -260.712966) (xy 126.571949 -260.68244) (xy 126.535226 -260.645717)
			(xy 126.5047 -260.603701) (xy 126.481122 -260.557427) (xy 126.465074 -260.508034) (xy 126.456949 -260.456739)
			(xy 126.177293 -260.456739) (xy 126.169168 -260.508034) (xy 126.15312 -260.557427) (xy 126.129542 -260.603701)
			(xy 126.099016 -260.645717) (xy 126.062293 -260.68244) (xy 126.020277 -260.712966) (xy 125.974003 -260.736544)
			(xy 125.92461 -260.752592) (xy 125.873315 -260.760717) (xy 125.821381 -260.760717) (xy 125.770086 -260.752592)
			(xy 125.720693 -260.736544) (xy 125.674419 -260.712966) (xy 125.632403 -260.68244) (xy 125.59568 -260.645717)
			(xy 125.565154 -260.603701) (xy 125.541576 -260.557427) (xy 125.525528 -260.508034) (xy 125.517403 -260.456739)
			(xy 125.237493 -260.456739) (xy 125.229368 -260.508034) (xy 125.21332 -260.557427) (xy 125.189742 -260.603701)
			(xy 125.159216 -260.645717) (xy 125.122493 -260.68244) (xy 125.080477 -260.712966) (xy 125.034203 -260.736544)
			(xy 124.98481 -260.752592) (xy 124.933515 -260.760717) (xy 124.881581 -260.760717) (xy 124.830286 -260.752592)
			(xy 124.780893 -260.736544) (xy 124.734619 -260.712966) (xy 124.692603 -260.68244) (xy 124.65588 -260.645717)
			(xy 124.625354 -260.603701) (xy 124.601776 -260.557427) (xy 124.585728 -260.508034) (xy 124.577603 -260.456739)
			(xy 124.297409 -260.456739) (xy 124.291101 -260.5008) (xy 124.277922 -260.545916) (xy 124.258492 -260.588713)
			(xy 124.233201 -260.62833) (xy 124.218192 -260.646418) (xy 124.208635 -260.658309) (xy 124.196397 -260.686237)
			(xy 124.19295 -260.716534) (xy 124.198602 -260.746497) (xy 124.212848 -260.773456) (xy 124.223272 -260.784594)
			(xy 124.36094 -260.922262) (xy 124.386594 -260.918452) (xy 124.399209 -260.916564) (xy 124.424639 -260.914533)
			(xy 124.437394 -260.914388) (xy 124.463367 -260.914787) (xy 124.514673 -260.922912) (xy 124.564077 -260.938963)
			(xy 124.610361 -260.962546) (xy 124.652387 -260.993078) (xy 124.689118 -261.029809) (xy 124.719651 -261.071834)
			(xy 124.743234 -261.118118) (xy 124.759287 -261.167521) (xy 124.767413 -261.218827) (xy 124.767413 -261.270773)
			(xy 124.767407 -261.270809) (xy 125.047249 -261.270809) (xy 125.047249 -261.218875) (xy 125.055374 -261.16758)
			(xy 125.071422 -261.118187) (xy 125.095 -261.071913) (xy 125.125526 -261.029897) (xy 125.162249 -260.993174)
			(xy 125.204265 -260.962648) (xy 125.250539 -260.93907) (xy 125.299932 -260.923022) (xy 125.351227 -260.914897)
			(xy 125.403161 -260.914897) (xy 125.454456 -260.923022) (xy 125.503849 -260.93907) (xy 125.550123 -260.962648)
			(xy 125.592139 -260.993174) (xy 125.628862 -261.029897) (xy 125.659388 -261.071913) (xy 125.682966 -261.118187)
			(xy 125.699014 -261.16758) (xy 125.707139 -261.218875) (xy 125.707648 -261.244842) (xy 125.707139 -261.270809)
			(xy 125.987049 -261.270809) (xy 125.987049 -261.218875) (xy 125.995174 -261.16758) (xy 126.011222 -261.118187)
			(xy 126.0348 -261.071913) (xy 126.065326 -261.029897) (xy 126.102049 -260.993174) (xy 126.144065 -260.962648)
			(xy 126.190339 -260.93907) (xy 126.239732 -260.923022) (xy 126.291027 -260.914897) (xy 126.342961 -260.914897)
			(xy 126.394256 -260.923022) (xy 126.443649 -260.93907) (xy 126.489923 -260.962648) (xy 126.531939 -260.993174)
			(xy 126.568662 -261.029897) (xy 126.599188 -261.071913) (xy 126.622766 -261.118187) (xy 126.638814 -261.16758)
			(xy 126.646939 -261.218875) (xy 126.647448 -261.244842) (xy 126.646939 -261.270809) (xy 126.926849 -261.270809)
			(xy 126.926849 -261.218875) (xy 126.934974 -261.16758) (xy 126.951022 -261.118187) (xy 126.9746 -261.071913)
			(xy 127.005126 -261.029897) (xy 127.041849 -260.993174) (xy 127.083865 -260.962648) (xy 127.130139 -260.93907)
			(xy 127.179532 -260.923022) (xy 127.230827 -260.914897) (xy 127.282761 -260.914897) (xy 127.334056 -260.923022)
			(xy 127.383449 -260.93907) (xy 127.429723 -260.962648) (xy 127.471739 -260.993174) (xy 127.508462 -261.029897)
			(xy 127.538988 -261.071913) (xy 127.562566 -261.118187) (xy 127.578614 -261.16758) (xy 127.586739 -261.218875)
			(xy 127.587248 -261.244842) (xy 127.586739 -261.270809) (xy 127.866649 -261.270809) (xy 127.866649 -261.218875)
			(xy 127.874774 -261.16758) (xy 127.890822 -261.118187) (xy 127.9144 -261.071913) (xy 127.944926 -261.029897)
			(xy 127.981649 -260.993174) (xy 128.023665 -260.962648) (xy 128.069939 -260.93907) (xy 128.119332 -260.923022)
			(xy 128.170627 -260.914897) (xy 128.222561 -260.914897) (xy 128.273856 -260.923022) (xy 128.323249 -260.93907)
			(xy 128.369523 -260.962648) (xy 128.411539 -260.993174) (xy 128.448262 -261.029897) (xy 128.478788 -261.071913)
			(xy 128.502366 -261.118187) (xy 128.518414 -261.16758) (xy 128.526539 -261.218875) (xy 128.527048 -261.244842)
			(xy 128.526539 -261.270809) (xy 128.806449 -261.270809) (xy 128.806449 -261.218875) (xy 128.814574 -261.16758)
			(xy 128.830622 -261.118187) (xy 128.8542 -261.071913) (xy 128.884726 -261.029897) (xy 128.921449 -260.993174)
			(xy 128.963465 -260.962648) (xy 129.009739 -260.93907) (xy 129.059132 -260.923022) (xy 129.110427 -260.914897)
			(xy 129.162361 -260.914897) (xy 129.213656 -260.923022) (xy 129.263049 -260.93907) (xy 129.309323 -260.962648)
			(xy 129.351339 -260.993174) (xy 129.388062 -261.029897) (xy 129.418588 -261.071913) (xy 129.442166 -261.118187)
			(xy 129.458214 -261.16758) (xy 129.466339 -261.218875) (xy 129.466848 -261.244842) (xy 129.466339 -261.270809)
			(xy 129.746249 -261.270809) (xy 129.746249 -261.218875) (xy 129.754374 -261.16758) (xy 129.770422 -261.118187)
			(xy 129.794 -261.071913) (xy 129.824526 -261.029897) (xy 129.861249 -260.993174) (xy 129.903265 -260.962648)
			(xy 129.949539 -260.93907) (xy 129.998932 -260.923022) (xy 130.050227 -260.914897) (xy 130.102161 -260.914897)
			(xy 130.153456 -260.923022) (xy 130.202849 -260.93907) (xy 130.249123 -260.962648) (xy 130.291139 -260.993174)
			(xy 130.327862 -261.029897) (xy 130.358388 -261.071913) (xy 130.381966 -261.118187) (xy 130.398014 -261.16758)
			(xy 130.406139 -261.218875) (xy 130.406648 -261.244842) (xy 130.406139 -261.270809) (xy 130.398014 -261.322104)
			(xy 130.381966 -261.371497) (xy 130.358388 -261.417771) (xy 130.327862 -261.459787) (xy 130.291139 -261.49651)
			(xy 130.249123 -261.527036) (xy 130.202849 -261.550614) (xy 130.153456 -261.566662) (xy 130.102161 -261.574787)
			(xy 130.050227 -261.574787) (xy 129.998932 -261.566662) (xy 129.949539 -261.550614) (xy 129.903265 -261.527036)
			(xy 129.861249 -261.49651) (xy 129.824526 -261.459787) (xy 129.794 -261.417771) (xy 129.770422 -261.371497)
			(xy 129.754374 -261.322104) (xy 129.746249 -261.270809) (xy 129.466339 -261.270809) (xy 129.458214 -261.322104)
			(xy 129.442166 -261.371497) (xy 129.418588 -261.417771) (xy 129.388062 -261.459787) (xy 129.351339 -261.49651)
			(xy 129.309323 -261.527036) (xy 129.263049 -261.550614) (xy 129.213656 -261.566662) (xy 129.162361 -261.574787)
			(xy 129.110427 -261.574787) (xy 129.059132 -261.566662) (xy 129.009739 -261.550614) (xy 128.963465 -261.527036)
			(xy 128.921449 -261.49651) (xy 128.884726 -261.459787) (xy 128.8542 -261.417771) (xy 128.830622 -261.371497)
			(xy 128.814574 -261.322104) (xy 128.806449 -261.270809) (xy 128.526539 -261.270809) (xy 128.518414 -261.322104)
			(xy 128.502366 -261.371497) (xy 128.478788 -261.417771) (xy 128.448262 -261.459787) (xy 128.411539 -261.49651)
			(xy 128.369523 -261.527036) (xy 128.323249 -261.550614) (xy 128.273856 -261.566662) (xy 128.222561 -261.574787)
			(xy 128.170627 -261.574787) (xy 128.119332 -261.566662) (xy 128.069939 -261.550614) (xy 128.023665 -261.527036)
			(xy 127.981649 -261.49651) (xy 127.944926 -261.459787) (xy 127.9144 -261.417771) (xy 127.890822 -261.371497)
			(xy 127.874774 -261.322104) (xy 127.866649 -261.270809) (xy 127.586739 -261.270809) (xy 127.578614 -261.322104)
			(xy 127.562566 -261.371497) (xy 127.538988 -261.417771) (xy 127.508462 -261.459787) (xy 127.471739 -261.49651)
			(xy 127.429723 -261.527036) (xy 127.383449 -261.550614) (xy 127.334056 -261.566662) (xy 127.282761 -261.574787)
			(xy 127.230827 -261.574787) (xy 127.179532 -261.566662) (xy 127.130139 -261.550614) (xy 127.083865 -261.527036)
			(xy 127.041849 -261.49651) (xy 127.005126 -261.459787) (xy 126.9746 -261.417771) (xy 126.951022 -261.371497)
			(xy 126.934974 -261.322104) (xy 126.926849 -261.270809) (xy 126.646939 -261.270809) (xy 126.638814 -261.322104)
			(xy 126.622766 -261.371497) (xy 126.599188 -261.417771) (xy 126.568662 -261.459787) (xy 126.531939 -261.49651)
			(xy 126.489923 -261.527036) (xy 126.443649 -261.550614) (xy 126.394256 -261.566662) (xy 126.342961 -261.574787)
			(xy 126.291027 -261.574787) (xy 126.239732 -261.566662) (xy 126.190339 -261.550614) (xy 126.144065 -261.527036)
			(xy 126.102049 -261.49651) (xy 126.065326 -261.459787) (xy 126.0348 -261.417771) (xy 126.011222 -261.371497)
			(xy 125.995174 -261.322104) (xy 125.987049 -261.270809) (xy 125.707139 -261.270809) (xy 125.699014 -261.322104)
			(xy 125.682966 -261.371497) (xy 125.659388 -261.417771) (xy 125.628862 -261.459787) (xy 125.592139 -261.49651)
			(xy 125.550123 -261.527036) (xy 125.503849 -261.550614) (xy 125.454456 -261.566662) (xy 125.403161 -261.574787)
			(xy 125.351227 -261.574787) (xy 125.299932 -261.566662) (xy 125.250539 -261.550614) (xy 125.204265 -261.527036)
			(xy 125.162249 -261.49651) (xy 125.125526 -261.459787) (xy 125.095 -261.417771) (xy 125.071422 -261.371497)
			(xy 125.055374 -261.322104) (xy 125.047249 -261.270809) (xy 124.767407 -261.270809) (xy 124.759287 -261.322079)
			(xy 124.743235 -261.371482) (xy 124.719651 -261.417766) (xy 124.689118 -261.459791) (xy 124.652387 -261.496522)
			(xy 124.610361 -261.527054) (xy 124.564077 -261.550637) (xy 124.514673 -261.566688) (xy 124.463367 -261.574813)
			(xy 124.437394 -261.575296) (xy 124.424948 -261.575042) (xy 124.411279 -261.574969) (xy 124.38467 -261.581181)
			(xy 124.360659 -261.594222) (xy 124.340962 -261.613159) (xy 124.326986 -261.636637) (xy 124.319731 -261.66298)
			(xy 124.319284 -261.676642) (xy 124.319284 -262.084625) (xy 124.577603 -262.084625) (xy 124.577603 -262.032691)
			(xy 124.585728 -261.981396) (xy 124.601776 -261.932003) (xy 124.625354 -261.885729) (xy 124.65588 -261.843713)
			(xy 124.692603 -261.80699) (xy 124.734619 -261.776464) (xy 124.780893 -261.752886) (xy 124.830286 -261.736838)
			(xy 124.881581 -261.728713) (xy 124.933515 -261.728713) (xy 124.98481 -261.736838) (xy 125.034203 -261.752886)
			(xy 125.080477 -261.776464) (xy 125.122493 -261.80699) (xy 125.159216 -261.843713) (xy 125.189742 -261.885729)
			(xy 125.21332 -261.932003) (xy 125.229368 -261.981396) (xy 125.237493 -262.032691) (xy 125.238002 -262.058658)
			(xy 125.237493 -262.084625) (xy 125.517149 -262.084625) (xy 125.517149 -262.032691) (xy 125.525274 -261.981396)
			(xy 125.541322 -261.932003) (xy 125.5649 -261.885729) (xy 125.595426 -261.843713) (xy 125.632149 -261.80699)
			(xy 125.674165 -261.776464) (xy 125.720439 -261.752886) (xy 125.769832 -261.736838) (xy 125.821127 -261.728713)
			(xy 125.873061 -261.728713) (xy 125.924356 -261.736838) (xy 125.973749 -261.752886) (xy 126.020023 -261.776464)
			(xy 126.062039 -261.80699) (xy 126.098762 -261.843713) (xy 126.129288 -261.885729) (xy 126.152866 -261.932003)
			(xy 126.168914 -261.981396) (xy 126.177039 -262.032691) (xy 126.177548 -262.058658) (xy 126.177039 -262.084625)
			(xy 126.457203 -262.084625) (xy 126.457203 -262.032691) (xy 126.465328 -261.981396) (xy 126.481376 -261.932003)
			(xy 126.504954 -261.885729) (xy 126.53548 -261.843713) (xy 126.572203 -261.80699) (xy 126.614219 -261.776464)
			(xy 126.660493 -261.752886) (xy 126.709886 -261.736838) (xy 126.761181 -261.728713) (xy 126.813115 -261.728713)
			(xy 126.86441 -261.736838) (xy 126.913803 -261.752886) (xy 126.960077 -261.776464) (xy 127.002093 -261.80699)
			(xy 127.038816 -261.843713) (xy 127.069342 -261.885729) (xy 127.09292 -261.932003) (xy 127.108968 -261.981396)
			(xy 127.117093 -262.032691) (xy 127.117602 -262.058658) (xy 127.117093 -262.084625) (xy 127.397003 -262.084625)
			(xy 127.397003 -262.032691) (xy 127.405128 -261.981396) (xy 127.421176 -261.932003) (xy 127.444754 -261.885729)
			(xy 127.47528 -261.843713) (xy 127.512003 -261.80699) (xy 127.554019 -261.776464) (xy 127.600293 -261.752886)
			(xy 127.649686 -261.736838) (xy 127.700981 -261.728713) (xy 127.752915 -261.728713) (xy 127.80421 -261.736838)
			(xy 127.853603 -261.752886) (xy 127.899877 -261.776464) (xy 127.941893 -261.80699) (xy 127.978616 -261.843713)
			(xy 128.009142 -261.885729) (xy 128.03272 -261.932003) (xy 128.048768 -261.981396) (xy 128.056893 -262.032691)
			(xy 128.057402 -262.058658) (xy 128.056893 -262.084625) (xy 128.336803 -262.084625) (xy 128.336803 -262.032691)
			(xy 128.344928 -261.981396) (xy 128.360976 -261.932003) (xy 128.384554 -261.885729) (xy 128.41508 -261.843713)
			(xy 128.451803 -261.80699) (xy 128.493819 -261.776464) (xy 128.540093 -261.752886) (xy 128.589486 -261.736838)
			(xy 128.640781 -261.728713) (xy 128.692715 -261.728713) (xy 128.74401 -261.736838) (xy 128.793403 -261.752886)
			(xy 128.839677 -261.776464) (xy 128.881693 -261.80699) (xy 128.918416 -261.843713) (xy 128.948942 -261.885729)
			(xy 128.97252 -261.932003) (xy 128.988568 -261.981396) (xy 128.996693 -262.032691) (xy 128.997202 -262.058658)
			(xy 128.996693 -262.084625) (xy 129.276603 -262.084625) (xy 129.276603 -262.032691) (xy 129.284728 -261.981396)
			(xy 129.300776 -261.932003) (xy 129.324354 -261.885729) (xy 129.35488 -261.843713) (xy 129.391603 -261.80699)
			(xy 129.433619 -261.776464) (xy 129.479893 -261.752886) (xy 129.529286 -261.736838) (xy 129.580581 -261.728713)
			(xy 129.632515 -261.728713) (xy 129.68381 -261.736838) (xy 129.733203 -261.752886) (xy 129.779477 -261.776464)
			(xy 129.821493 -261.80699) (xy 129.858216 -261.843713) (xy 129.888742 -261.885729) (xy 129.91232 -261.932003)
			(xy 129.928368 -261.981396) (xy 129.936493 -262.032691) (xy 129.937002 -262.058658) (xy 129.936493 -262.084625)
			(xy 130.216403 -262.084625) (xy 130.216403 -262.032691) (xy 130.224528 -261.981396) (xy 130.240576 -261.932003)
			(xy 130.264154 -261.885729) (xy 130.29468 -261.843713) (xy 130.331403 -261.80699) (xy 130.373419 -261.776464)
			(xy 130.419693 -261.752886) (xy 130.469086 -261.736838) (xy 130.520381 -261.728713) (xy 130.572315 -261.728713)
			(xy 130.62361 -261.736838) (xy 130.673003 -261.752886) (xy 130.719277 -261.776464) (xy 130.761293 -261.80699)
			(xy 130.798016 -261.843713) (xy 130.828542 -261.885729) (xy 130.85212 -261.932003) (xy 130.868168 -261.981396)
			(xy 130.876293 -262.032691) (xy 130.876802 -262.058658) (xy 130.876293 -262.084625) (xy 130.868168 -262.13592)
			(xy 130.85212 -262.185313) (xy 130.828542 -262.231587) (xy 130.798016 -262.273603) (xy 130.761293 -262.310326)
			(xy 130.719277 -262.340852) (xy 130.673003 -262.36443) (xy 130.62361 -262.380478) (xy 130.572315 -262.388603)
			(xy 130.520381 -262.388603) (xy 130.469086 -262.380478) (xy 130.419693 -262.36443) (xy 130.373419 -262.340852)
			(xy 130.331403 -262.310326) (xy 130.29468 -262.273603) (xy 130.264154 -262.231587) (xy 130.240576 -262.185313)
			(xy 130.224528 -262.13592) (xy 130.216403 -262.084625) (xy 129.936493 -262.084625) (xy 129.928368 -262.13592)
			(xy 129.91232 -262.185313) (xy 129.888742 -262.231587) (xy 129.858216 -262.273603) (xy 129.821493 -262.310326)
			(xy 129.779477 -262.340852) (xy 129.733203 -262.36443) (xy 129.68381 -262.380478) (xy 129.632515 -262.388603)
			(xy 129.580581 -262.388603) (xy 129.529286 -262.380478) (xy 129.479893 -262.36443) (xy 129.433619 -262.340852)
			(xy 129.391603 -262.310326) (xy 129.35488 -262.273603) (xy 129.324354 -262.231587) (xy 129.300776 -262.185313)
			(xy 129.284728 -262.13592) (xy 129.276603 -262.084625) (xy 128.996693 -262.084625) (xy 128.988568 -262.13592)
			(xy 128.97252 -262.185313) (xy 128.948942 -262.231587) (xy 128.918416 -262.273603) (xy 128.881693 -262.310326)
			(xy 128.839677 -262.340852) (xy 128.793403 -262.36443) (xy 128.74401 -262.380478) (xy 128.692715 -262.388603)
			(xy 128.640781 -262.388603) (xy 128.589486 -262.380478) (xy 128.540093 -262.36443) (xy 128.493819 -262.340852)
			(xy 128.451803 -262.310326) (xy 128.41508 -262.273603) (xy 128.384554 -262.231587) (xy 128.360976 -262.185313)
			(xy 128.344928 -262.13592) (xy 128.336803 -262.084625) (xy 128.056893 -262.084625) (xy 128.048768 -262.13592)
			(xy 128.03272 -262.185313) (xy 128.009142 -262.231587) (xy 127.978616 -262.273603) (xy 127.941893 -262.310326)
			(xy 127.899877 -262.340852) (xy 127.853603 -262.36443) (xy 127.80421 -262.380478) (xy 127.752915 -262.388603)
			(xy 127.700981 -262.388603) (xy 127.649686 -262.380478) (xy 127.600293 -262.36443) (xy 127.554019 -262.340852)
			(xy 127.512003 -262.310326) (xy 127.47528 -262.273603) (xy 127.444754 -262.231587) (xy 127.421176 -262.185313)
			(xy 127.405128 -262.13592) (xy 127.397003 -262.084625) (xy 127.117093 -262.084625) (xy 127.108968 -262.13592)
			(xy 127.09292 -262.185313) (xy 127.069342 -262.231587) (xy 127.038816 -262.273603) (xy 127.002093 -262.310326)
			(xy 126.960077 -262.340852) (xy 126.913803 -262.36443) (xy 126.86441 -262.380478) (xy 126.813115 -262.388603)
			(xy 126.761181 -262.388603) (xy 126.709886 -262.380478) (xy 126.660493 -262.36443) (xy 126.614219 -262.340852)
			(xy 126.572203 -262.310326) (xy 126.53548 -262.273603) (xy 126.504954 -262.231587) (xy 126.481376 -262.185313)
			(xy 126.465328 -262.13592) (xy 126.457203 -262.084625) (xy 126.177039 -262.084625) (xy 126.168914 -262.13592)
			(xy 126.152866 -262.185313) (xy 126.129288 -262.231587) (xy 126.098762 -262.273603) (xy 126.062039 -262.310326)
			(xy 126.020023 -262.340852) (xy 125.973749 -262.36443) (xy 125.924356 -262.380478) (xy 125.873061 -262.388603)
			(xy 125.821127 -262.388603) (xy 125.769832 -262.380478) (xy 125.720439 -262.36443) (xy 125.674165 -262.340852)
			(xy 125.632149 -262.310326) (xy 125.595426 -262.273603) (xy 125.5649 -262.231587) (xy 125.541322 -262.185313)
			(xy 125.525274 -262.13592) (xy 125.517149 -262.084625) (xy 125.237493 -262.084625) (xy 125.229368 -262.13592)
			(xy 125.21332 -262.185313) (xy 125.189742 -262.231587) (xy 125.159216 -262.273603) (xy 125.122493 -262.310326)
			(xy 125.080477 -262.340852) (xy 125.034203 -262.36443) (xy 124.98481 -262.380478) (xy 124.933515 -262.388603)
			(xy 124.881581 -262.388603) (xy 124.830286 -262.380478) (xy 124.780893 -262.36443) (xy 124.734619 -262.340852)
			(xy 124.692603 -262.310326) (xy 124.65588 -262.273603) (xy 124.625354 -262.231587) (xy 124.601776 -262.185313)
			(xy 124.585728 -262.13592) (xy 124.577603 -262.084625) (xy 124.319284 -262.084625) (xy 124.319284 -262.440674)
			(xy 124.319667 -262.454348) (xy 124.326897 -262.480721) (xy 124.340872 -262.504227) (xy 124.360588 -262.523177)
			(xy 124.384629 -262.53621) (xy 124.411268 -262.54239) (xy 124.424948 -262.542274) (xy 124.437394 -262.54202)
			(xy 124.463362 -262.542554) (xy 124.514657 -262.550678) (xy 124.564051 -262.566726) (xy 124.610326 -262.590303)
			(xy 124.652342 -262.62083) (xy 124.689066 -262.657553) (xy 124.719593 -262.699569) (xy 124.743172 -262.745844)
			(xy 124.759221 -262.795237) (xy 124.767345 -262.846532) (xy 124.767345 -262.898441) (xy 125.047503 -262.898441)
			(xy 125.047503 -262.846507) (xy 125.055628 -262.795212) (xy 125.071676 -262.745819) (xy 125.095254 -262.699545)
			(xy 125.12578 -262.657529) (xy 125.162503 -262.620806) (xy 125.204519 -262.59028) (xy 125.250793 -262.566702)
			(xy 125.300186 -262.550654) (xy 125.351481 -262.542529) (xy 125.403415 -262.542529) (xy 125.45471 -262.550654)
			(xy 125.504103 -262.566702) (xy 125.550377 -262.59028) (xy 125.592393 -262.620806) (xy 125.629116 -262.657529)
			(xy 125.659642 -262.699545) (xy 125.68322 -262.745819) (xy 125.699268 -262.795212) (xy 125.707393 -262.846507)
			(xy 125.707902 -262.872474) (xy 125.707393 -262.898441) (xy 125.987049 -262.898441) (xy 125.987049 -262.846507)
			(xy 125.995174 -262.795212) (xy 126.011222 -262.745819) (xy 126.0348 -262.699545) (xy 126.065326 -262.657529)
			(xy 126.102049 -262.620806) (xy 126.144065 -262.59028) (xy 126.190339 -262.566702) (xy 126.239732 -262.550654)
			(xy 126.291027 -262.542529) (xy 126.342961 -262.542529) (xy 126.394256 -262.550654) (xy 126.443649 -262.566702)
			(xy 126.489923 -262.59028) (xy 126.531939 -262.620806) (xy 126.568662 -262.657529) (xy 126.599188 -262.699545)
			(xy 126.622766 -262.745819) (xy 126.638814 -262.795212) (xy 126.646939 -262.846507) (xy 126.647448 -262.872474)
			(xy 126.646939 -262.898441) (xy 126.926849 -262.898441) (xy 126.926849 -262.846507) (xy 126.934974 -262.795212)
			(xy 126.951022 -262.745819) (xy 126.9746 -262.699545) (xy 127.005126 -262.657529) (xy 127.041849 -262.620806)
			(xy 127.083865 -262.59028) (xy 127.130139 -262.566702) (xy 127.179532 -262.550654) (xy 127.230827 -262.542529)
			(xy 127.282761 -262.542529) (xy 127.334056 -262.550654) (xy 127.383449 -262.566702) (xy 127.429723 -262.59028)
			(xy 127.471739 -262.620806) (xy 127.508462 -262.657529) (xy 127.538988 -262.699545) (xy 127.562566 -262.745819)
			(xy 127.578614 -262.795212) (xy 127.586739 -262.846507) (xy 127.587248 -262.872474) (xy 127.586739 -262.898441)
			(xy 127.866649 -262.898441) (xy 127.866649 -262.846507) (xy 127.874774 -262.795212) (xy 127.890822 -262.745819)
			(xy 127.9144 -262.699545) (xy 127.944926 -262.657529) (xy 127.981649 -262.620806) (xy 128.023665 -262.59028)
			(xy 128.069939 -262.566702) (xy 128.119332 -262.550654) (xy 128.170627 -262.542529) (xy 128.222561 -262.542529)
			(xy 128.273856 -262.550654) (xy 128.323249 -262.566702) (xy 128.369523 -262.59028) (xy 128.411539 -262.620806)
			(xy 128.448262 -262.657529) (xy 128.478788 -262.699545) (xy 128.502366 -262.745819) (xy 128.518414 -262.795212)
			(xy 128.526539 -262.846507) (xy 128.527048 -262.872474) (xy 128.526539 -262.898441) (xy 128.806449 -262.898441)
			(xy 128.806449 -262.846507) (xy 128.814574 -262.795212) (xy 128.830622 -262.745819) (xy 128.8542 -262.699545)
			(xy 128.884726 -262.657529) (xy 128.921449 -262.620806) (xy 128.963465 -262.59028) (xy 129.009739 -262.566702)
			(xy 129.059132 -262.550654) (xy 129.110427 -262.542529) (xy 129.162361 -262.542529) (xy 129.213656 -262.550654)
			(xy 129.263049 -262.566702) (xy 129.309323 -262.59028) (xy 129.351339 -262.620806) (xy 129.388062 -262.657529)
			(xy 129.418588 -262.699545) (xy 129.442166 -262.745819) (xy 129.458214 -262.795212) (xy 129.466339 -262.846507)
			(xy 129.466848 -262.872474) (xy 129.466339 -262.898441) (xy 129.746249 -262.898441) (xy 129.746249 -262.846507)
			(xy 129.754374 -262.795212) (xy 129.770422 -262.745819) (xy 129.794 -262.699545) (xy 129.824526 -262.657529)
			(xy 129.861249 -262.620806) (xy 129.903265 -262.59028) (xy 129.949539 -262.566702) (xy 129.998932 -262.550654)
			(xy 130.050227 -262.542529) (xy 130.102161 -262.542529) (xy 130.153456 -262.550654) (xy 130.202849 -262.566702)
			(xy 130.249123 -262.59028) (xy 130.291139 -262.620806) (xy 130.327862 -262.657529) (xy 130.358388 -262.699545)
			(xy 130.381966 -262.745819) (xy 130.398014 -262.795212) (xy 130.406139 -262.846507) (xy 130.406648 -262.872474)
			(xy 130.406139 -262.898441) (xy 130.686049 -262.898441) (xy 130.686049 -262.846507) (xy 130.694174 -262.795212)
			(xy 130.710222 -262.745819) (xy 130.7338 -262.699545) (xy 130.764326 -262.657529) (xy 130.801049 -262.620806)
			(xy 130.843065 -262.59028) (xy 130.889339 -262.566702) (xy 130.938732 -262.550654) (xy 130.990027 -262.542529)
			(xy 131.041961 -262.542529) (xy 131.093256 -262.550654) (xy 131.142649 -262.566702) (xy 131.188923 -262.59028)
			(xy 131.230939 -262.620806) (xy 131.267662 -262.657529) (xy 131.298188 -262.699545) (xy 131.321766 -262.745819)
			(xy 131.337814 -262.795212) (xy 131.345939 -262.846507) (xy 131.346448 -262.872474) (xy 131.345939 -262.898441)
			(xy 131.337814 -262.949736) (xy 131.321766 -262.999129) (xy 131.298188 -263.045403) (xy 131.267662 -263.087419)
			(xy 131.230939 -263.124142) (xy 131.188923 -263.154668) (xy 131.142649 -263.178246) (xy 131.093256 -263.194294)
			(xy 131.041961 -263.202419) (xy 130.990027 -263.202419) (xy 130.938732 -263.194294) (xy 130.889339 -263.178246)
			(xy 130.843065 -263.154668) (xy 130.801049 -263.124142) (xy 130.764326 -263.087419) (xy 130.7338 -263.045403)
			(xy 130.710222 -262.999129) (xy 130.694174 -262.949736) (xy 130.686049 -262.898441) (xy 130.406139 -262.898441)
			(xy 130.398014 -262.949736) (xy 130.381966 -262.999129) (xy 130.358388 -263.045403) (xy 130.327862 -263.087419)
			(xy 130.291139 -263.124142) (xy 130.249123 -263.154668) (xy 130.202849 -263.178246) (xy 130.153456 -263.194294)
			(xy 130.102161 -263.202419) (xy 130.050227 -263.202419) (xy 129.998932 -263.194294) (xy 129.949539 -263.178246)
			(xy 129.903265 -263.154668) (xy 129.861249 -263.124142) (xy 129.824526 -263.087419) (xy 129.794 -263.045403)
			(xy 129.770422 -262.999129) (xy 129.754374 -262.949736) (xy 129.746249 -262.898441) (xy 129.466339 -262.898441)
			(xy 129.458214 -262.949736) (xy 129.442166 -262.999129) (xy 129.418588 -263.045403) (xy 129.388062 -263.087419)
			(xy 129.351339 -263.124142) (xy 129.309323 -263.154668) (xy 129.263049 -263.178246) (xy 129.213656 -263.194294)
			(xy 129.162361 -263.202419) (xy 129.110427 -263.202419) (xy 129.059132 -263.194294) (xy 129.009739 -263.178246)
			(xy 128.963465 -263.154668) (xy 128.921449 -263.124142) (xy 128.884726 -263.087419) (xy 128.8542 -263.045403)
			(xy 128.830622 -262.999129) (xy 128.814574 -262.949736) (xy 128.806449 -262.898441) (xy 128.526539 -262.898441)
			(xy 128.518414 -262.949736) (xy 128.502366 -262.999129) (xy 128.478788 -263.045403) (xy 128.448262 -263.087419)
			(xy 128.411539 -263.124142) (xy 128.369523 -263.154668) (xy 128.323249 -263.178246) (xy 128.273856 -263.194294)
			(xy 128.222561 -263.202419) (xy 128.170627 -263.202419) (xy 128.119332 -263.194294) (xy 128.069939 -263.178246)
			(xy 128.023665 -263.154668) (xy 127.981649 -263.124142) (xy 127.944926 -263.087419) (xy 127.9144 -263.045403)
			(xy 127.890822 -262.999129) (xy 127.874774 -262.949736) (xy 127.866649 -262.898441) (xy 127.586739 -262.898441)
			(xy 127.578614 -262.949736) (xy 127.562566 -262.999129) (xy 127.538988 -263.045403) (xy 127.508462 -263.087419)
			(xy 127.471739 -263.124142) (xy 127.429723 -263.154668) (xy 127.383449 -263.178246) (xy 127.334056 -263.194294)
			(xy 127.282761 -263.202419) (xy 127.230827 -263.202419) (xy 127.179532 -263.194294) (xy 127.130139 -263.178246)
			(xy 127.083865 -263.154668) (xy 127.041849 -263.124142) (xy 127.005126 -263.087419) (xy 126.9746 -263.045403)
			(xy 126.951022 -262.999129) (xy 126.934974 -262.949736) (xy 126.926849 -262.898441) (xy 126.646939 -262.898441)
			(xy 126.638814 -262.949736) (xy 126.622766 -262.999129) (xy 126.599188 -263.045403) (xy 126.568662 -263.087419)
			(xy 126.531939 -263.124142) (xy 126.489923 -263.154668) (xy 126.443649 -263.178246) (xy 126.394256 -263.194294)
			(xy 126.342961 -263.202419) (xy 126.291027 -263.202419) (xy 126.239732 -263.194294) (xy 126.190339 -263.178246)
			(xy 126.144065 -263.154668) (xy 126.102049 -263.124142) (xy 126.065326 -263.087419) (xy 126.0348 -263.045403)
			(xy 126.011222 -262.999129) (xy 125.995174 -262.949736) (xy 125.987049 -262.898441) (xy 125.707393 -262.898441)
			(xy 125.699268 -262.949736) (xy 125.68322 -262.999129) (xy 125.659642 -263.045403) (xy 125.629116 -263.087419)
			(xy 125.592393 -263.124142) (xy 125.550377 -263.154668) (xy 125.504103 -263.178246) (xy 125.45471 -263.194294)
			(xy 125.403415 -263.202419) (xy 125.351481 -263.202419) (xy 125.300186 -263.194294) (xy 125.250793 -263.178246)
			(xy 125.204519 -263.154668) (xy 125.162503 -263.124142) (xy 125.12578 -263.087419) (xy 125.095254 -263.045403)
			(xy 125.071676 -262.999129) (xy 125.055628 -262.949736) (xy 125.047503 -262.898441) (xy 124.767345 -262.898441)
			(xy 124.767345 -262.898468) (xy 124.759221 -262.949763) (xy 124.743172 -262.999156) (xy 124.719593 -263.045431)
			(xy 124.689066 -263.087447) (xy 124.652342 -263.12417) (xy 124.610326 -263.154697) (xy 124.564051 -263.178274)
			(xy 124.514657 -263.194322) (xy 124.463362 -263.202446) (xy 124.437394 -263.202928) (xy 124.424948 -263.202674)
			(xy 124.411277 -263.20257) (xy 124.384664 -263.208784) (xy 124.360649 -263.221829) (xy 124.340951 -263.240773)
			(xy 124.326977 -263.264259) (xy 124.319727 -263.29061) (xy 124.319284 -263.304274) (xy 124.319284 -263.712511)
			(xy 124.577603 -263.712511) (xy 124.577603 -263.660577) (xy 124.585728 -263.609282) (xy 124.601776 -263.559889)
			(xy 124.625354 -263.513615) (xy 124.65588 -263.471599) (xy 124.692603 -263.434876) (xy 124.734619 -263.40435)
			(xy 124.780893 -263.380772) (xy 124.830286 -263.364724) (xy 124.881581 -263.356599) (xy 124.933515 -263.356599)
			(xy 124.98481 -263.364724) (xy 125.034203 -263.380772) (xy 125.080477 -263.40435) (xy 125.122493 -263.434876)
			(xy 125.159216 -263.471599) (xy 125.189742 -263.513615) (xy 125.21332 -263.559889) (xy 125.229368 -263.609282)
			(xy 125.237493 -263.660577) (xy 125.238002 -263.686544) (xy 125.237493 -263.712511) (xy 125.517403 -263.712511)
			(xy 125.517403 -263.660577) (xy 125.525528 -263.609282) (xy 125.541576 -263.559889) (xy 125.565154 -263.513615)
			(xy 125.59568 -263.471599) (xy 125.632403 -263.434876) (xy 125.674419 -263.40435) (xy 125.720693 -263.380772)
			(xy 125.770086 -263.364724) (xy 125.821381 -263.356599) (xy 125.873315 -263.356599) (xy 125.92461 -263.364724)
			(xy 125.974003 -263.380772) (xy 126.020277 -263.40435) (xy 126.062293 -263.434876) (xy 126.099016 -263.471599)
			(xy 126.129542 -263.513615) (xy 126.15312 -263.559889) (xy 126.169168 -263.609282) (xy 126.177293 -263.660577)
			(xy 126.177802 -263.686544) (xy 126.177293 -263.712511) (xy 126.457203 -263.712511) (xy 126.457203 -263.660577)
			(xy 126.465328 -263.609282) (xy 126.481376 -263.559889) (xy 126.504954 -263.513615) (xy 126.53548 -263.471599)
			(xy 126.572203 -263.434876) (xy 126.614219 -263.40435) (xy 126.660493 -263.380772) (xy 126.709886 -263.364724)
			(xy 126.761181 -263.356599) (xy 126.813115 -263.356599) (xy 126.86441 -263.364724) (xy 126.913803 -263.380772)
			(xy 126.960077 -263.40435) (xy 127.002093 -263.434876) (xy 127.038816 -263.471599) (xy 127.069342 -263.513615)
			(xy 127.09292 -263.559889) (xy 127.108968 -263.609282) (xy 127.117093 -263.660577) (xy 127.117602 -263.686544)
			(xy 127.117093 -263.712511) (xy 127.397003 -263.712511) (xy 127.397003 -263.660577) (xy 127.405128 -263.609282)
			(xy 127.421176 -263.559889) (xy 127.444754 -263.513615) (xy 127.47528 -263.471599) (xy 127.512003 -263.434876)
			(xy 127.554019 -263.40435) (xy 127.600293 -263.380772) (xy 127.649686 -263.364724) (xy 127.700981 -263.356599)
			(xy 127.752915 -263.356599) (xy 127.80421 -263.364724) (xy 127.853603 -263.380772) (xy 127.899877 -263.40435)
			(xy 127.941893 -263.434876) (xy 127.978616 -263.471599) (xy 128.009142 -263.513615) (xy 128.03272 -263.559889)
			(xy 128.048768 -263.609282) (xy 128.056893 -263.660577) (xy 128.057402 -263.686544) (xy 128.056893 -263.712511)
			(xy 128.336803 -263.712511) (xy 128.336803 -263.660577) (xy 128.344928 -263.609282) (xy 128.360976 -263.559889)
			(xy 128.384554 -263.513615) (xy 128.41508 -263.471599) (xy 128.451803 -263.434876) (xy 128.493819 -263.40435)
			(xy 128.540093 -263.380772) (xy 128.589486 -263.364724) (xy 128.640781 -263.356599) (xy 128.692715 -263.356599)
			(xy 128.74401 -263.364724) (xy 128.793403 -263.380772) (xy 128.839677 -263.40435) (xy 128.881693 -263.434876)
			(xy 128.918416 -263.471599) (xy 128.948942 -263.513615) (xy 128.97252 -263.559889) (xy 128.988568 -263.609282)
			(xy 128.996693 -263.660577) (xy 128.997202 -263.686544) (xy 128.996693 -263.712511) (xy 129.276349 -263.712511)
			(xy 129.276349 -263.660577) (xy 129.284474 -263.609282) (xy 129.300522 -263.559889) (xy 129.3241 -263.513615)
			(xy 129.354626 -263.471599) (xy 129.391349 -263.434876) (xy 129.433365 -263.40435) (xy 129.479639 -263.380772)
			(xy 129.529032 -263.364724) (xy 129.580327 -263.356599) (xy 129.632261 -263.356599) (xy 129.683556 -263.364724)
			(xy 129.732949 -263.380772) (xy 129.779223 -263.40435) (xy 129.821239 -263.434876) (xy 129.857962 -263.471599)
			(xy 129.888488 -263.513615) (xy 129.912066 -263.559889) (xy 129.928114 -263.609282) (xy 129.936239 -263.660577)
			(xy 129.936748 -263.686544) (xy 129.936239 -263.712511) (xy 130.216403 -263.712511) (xy 130.216403 -263.660577)
			(xy 130.224528 -263.609282) (xy 130.240576 -263.559889) (xy 130.264154 -263.513615) (xy 130.29468 -263.471599)
			(xy 130.331403 -263.434876) (xy 130.373419 -263.40435) (xy 130.419693 -263.380772) (xy 130.469086 -263.364724)
			(xy 130.520381 -263.356599) (xy 130.572315 -263.356599) (xy 130.62361 -263.364724) (xy 130.673003 -263.380772)
			(xy 130.719277 -263.40435) (xy 130.761293 -263.434876) (xy 130.798016 -263.471599) (xy 130.828542 -263.513615)
			(xy 130.85212 -263.559889) (xy 130.868168 -263.609282) (xy 130.876293 -263.660577) (xy 130.876802 -263.686544)
			(xy 130.876293 -263.712511) (xy 130.868168 -263.763806) (xy 130.85212 -263.813199) (xy 130.828542 -263.859473)
			(xy 130.798016 -263.901489) (xy 130.761293 -263.938212) (xy 130.719277 -263.968738) (xy 130.673003 -263.992316)
			(xy 130.62361 -264.008364) (xy 130.572315 -264.016489) (xy 130.520381 -264.016489) (xy 130.469086 -264.008364)
			(xy 130.419693 -263.992316) (xy 130.373419 -263.968738) (xy 130.331403 -263.938212) (xy 130.29468 -263.901489)
			(xy 130.264154 -263.859473) (xy 130.240576 -263.813199) (xy 130.224528 -263.763806) (xy 130.216403 -263.712511)
			(xy 129.936239 -263.712511) (xy 129.928114 -263.763806) (xy 129.912066 -263.813199) (xy 129.888488 -263.859473)
			(xy 129.857962 -263.901489) (xy 129.821239 -263.938212) (xy 129.779223 -263.968738) (xy 129.732949 -263.992316)
			(xy 129.683556 -264.008364) (xy 129.632261 -264.016489) (xy 129.580327 -264.016489) (xy 129.529032 -264.008364)
			(xy 129.479639 -263.992316) (xy 129.433365 -263.968738) (xy 129.391349 -263.938212) (xy 129.354626 -263.901489)
			(xy 129.3241 -263.859473) (xy 129.300522 -263.813199) (xy 129.284474 -263.763806) (xy 129.276349 -263.712511)
			(xy 128.996693 -263.712511) (xy 128.988568 -263.763806) (xy 128.97252 -263.813199) (xy 128.948942 -263.859473)
			(xy 128.918416 -263.901489) (xy 128.881693 -263.938212) (xy 128.839677 -263.968738) (xy 128.793403 -263.992316)
			(xy 128.74401 -264.008364) (xy 128.692715 -264.016489) (xy 128.640781 -264.016489) (xy 128.589486 -264.008364)
			(xy 128.540093 -263.992316) (xy 128.493819 -263.968738) (xy 128.451803 -263.938212) (xy 128.41508 -263.901489)
			(xy 128.384554 -263.859473) (xy 128.360976 -263.813199) (xy 128.344928 -263.763806) (xy 128.336803 -263.712511)
			(xy 128.056893 -263.712511) (xy 128.048768 -263.763806) (xy 128.03272 -263.813199) (xy 128.009142 -263.859473)
			(xy 127.978616 -263.901489) (xy 127.941893 -263.938212) (xy 127.899877 -263.968738) (xy 127.853603 -263.992316)
			(xy 127.80421 -264.008364) (xy 127.752915 -264.016489) (xy 127.700981 -264.016489) (xy 127.649686 -264.008364)
			(xy 127.600293 -263.992316) (xy 127.554019 -263.968738) (xy 127.512003 -263.938212) (xy 127.47528 -263.901489)
			(xy 127.444754 -263.859473) (xy 127.421176 -263.813199) (xy 127.405128 -263.763806) (xy 127.397003 -263.712511)
			(xy 127.117093 -263.712511) (xy 127.108968 -263.763806) (xy 127.09292 -263.813199) (xy 127.069342 -263.859473)
			(xy 127.038816 -263.901489) (xy 127.002093 -263.938212) (xy 126.960077 -263.968738) (xy 126.913803 -263.992316)
			(xy 126.86441 -264.008364) (xy 126.813115 -264.016489) (xy 126.761181 -264.016489) (xy 126.709886 -264.008364)
			(xy 126.660493 -263.992316) (xy 126.614219 -263.968738) (xy 126.572203 -263.938212) (xy 126.53548 -263.901489)
			(xy 126.504954 -263.859473) (xy 126.481376 -263.813199) (xy 126.465328 -263.763806) (xy 126.457203 -263.712511)
			(xy 126.177293 -263.712511) (xy 126.169168 -263.763806) (xy 126.15312 -263.813199) (xy 126.129542 -263.859473)
			(xy 126.099016 -263.901489) (xy 126.062293 -263.938212) (xy 126.020277 -263.968738) (xy 125.974003 -263.992316)
			(xy 125.92461 -264.008364) (xy 125.873315 -264.016489) (xy 125.821381 -264.016489) (xy 125.770086 -264.008364)
			(xy 125.720693 -263.992316) (xy 125.674419 -263.968738) (xy 125.632403 -263.938212) (xy 125.59568 -263.901489)
			(xy 125.565154 -263.859473) (xy 125.541576 -263.813199) (xy 125.525528 -263.763806) (xy 125.517403 -263.712511)
			(xy 125.237493 -263.712511) (xy 125.229368 -263.763806) (xy 125.21332 -263.813199) (xy 125.189742 -263.859473)
			(xy 125.159216 -263.901489) (xy 125.122493 -263.938212) (xy 125.080477 -263.968738) (xy 125.034203 -263.992316)
			(xy 124.98481 -264.008364) (xy 124.933515 -264.016489) (xy 124.881581 -264.016489) (xy 124.830286 -264.008364)
			(xy 124.780893 -263.992316) (xy 124.734619 -263.968738) (xy 124.692603 -263.938212) (xy 124.65588 -263.901489)
			(xy 124.625354 -263.859473) (xy 124.601776 -263.813199) (xy 124.585728 -263.763806) (xy 124.577603 -263.712511)
			(xy 124.319284 -263.712511) (xy 124.319284 -264.06856) (xy 124.319679 -264.082233) (xy 124.326906 -264.108606)
			(xy 124.340878 -264.132112) (xy 124.360592 -264.151062) (xy 124.384631 -264.164096) (xy 124.411269 -264.170276)
			(xy 124.424948 -264.17016) (xy 124.437394 -264.169906) (xy 124.46336 -264.170468) (xy 124.514654 -264.178592)
			(xy 124.564045 -264.194639) (xy 124.610318 -264.218215) (xy 124.652333 -264.24874) (xy 124.689056 -264.285462)
			(xy 124.719581 -264.327477) (xy 124.743159 -264.373749) (xy 124.759207 -264.42314) (xy 124.767331 -264.474434)
			(xy 124.767331 -264.526327) (xy 125.047249 -264.526327) (xy 125.047249 -264.474393) (xy 125.055374 -264.423098)
			(xy 125.071422 -264.373705) (xy 125.095 -264.327431) (xy 125.125526 -264.285415) (xy 125.162249 -264.248692)
			(xy 125.204265 -264.218166) (xy 125.250539 -264.194588) (xy 125.299932 -264.17854) (xy 125.351227 -264.170415)
			(xy 125.403161 -264.170415) (xy 125.454456 -264.17854) (xy 125.503849 -264.194588) (xy 125.550123 -264.218166)
			(xy 125.592139 -264.248692) (xy 125.628862 -264.285415) (xy 125.659388 -264.327431) (xy 125.682966 -264.373705)
			(xy 125.699014 -264.423098) (xy 125.707139 -264.474393) (xy 125.707648 -264.50036) (xy 125.707139 -264.526327)
			(xy 125.987303 -264.526327) (xy 125.987303 -264.474393) (xy 125.995428 -264.423098) (xy 126.011476 -264.373705)
			(xy 126.035054 -264.327431) (xy 126.06558 -264.285415) (xy 126.102303 -264.248692) (xy 126.144319 -264.218166)
			(xy 126.190593 -264.194588) (xy 126.239986 -264.17854) (xy 126.291281 -264.170415) (xy 126.343215 -264.170415)
			(xy 126.39451 -264.17854) (xy 126.443903 -264.194588) (xy 126.490177 -264.218166) (xy 126.532193 -264.248692)
			(xy 126.568916 -264.285415) (xy 126.599442 -264.327431) (xy 126.62302 -264.373705) (xy 126.639068 -264.423098)
			(xy 126.647193 -264.474393) (xy 126.647702 -264.50036) (xy 126.647193 -264.526327) (xy 126.926849 -264.526327)
			(xy 126.926849 -264.474393) (xy 126.934974 -264.423098) (xy 126.951022 -264.373705) (xy 126.9746 -264.327431)
			(xy 127.005126 -264.285415) (xy 127.041849 -264.248692) (xy 127.083865 -264.218166) (xy 127.130139 -264.194588)
			(xy 127.179532 -264.17854) (xy 127.230827 -264.170415) (xy 127.282761 -264.170415) (xy 127.334056 -264.17854)
			(xy 127.383449 -264.194588) (xy 127.429723 -264.218166) (xy 127.471739 -264.248692) (xy 127.508462 -264.285415)
			(xy 127.538988 -264.327431) (xy 127.562566 -264.373705) (xy 127.578614 -264.423098) (xy 127.586739 -264.474393)
			(xy 127.587248 -264.50036) (xy 127.586739 -264.526327) (xy 127.866649 -264.526327) (xy 127.866649 -264.474393)
			(xy 127.874774 -264.423098) (xy 127.890822 -264.373705) (xy 127.9144 -264.327431) (xy 127.944926 -264.285415)
			(xy 127.981649 -264.248692) (xy 128.023665 -264.218166) (xy 128.069939 -264.194588) (xy 128.119332 -264.17854)
			(xy 128.170627 -264.170415) (xy 128.222561 -264.170415) (xy 128.273856 -264.17854) (xy 128.323249 -264.194588)
			(xy 128.369523 -264.218166) (xy 128.411539 -264.248692) (xy 128.448262 -264.285415) (xy 128.478788 -264.327431)
			(xy 128.502366 -264.373705) (xy 128.518414 -264.423098) (xy 128.526539 -264.474393) (xy 128.527048 -264.50036)
			(xy 128.526539 -264.526327) (xy 128.806449 -264.526327) (xy 128.806449 -264.474393) (xy 128.814574 -264.423098)
			(xy 128.830622 -264.373705) (xy 128.8542 -264.327431) (xy 128.884726 -264.285415) (xy 128.921449 -264.248692)
			(xy 128.963465 -264.218166) (xy 129.009739 -264.194588) (xy 129.059132 -264.17854) (xy 129.110427 -264.170415)
			(xy 129.162361 -264.170415) (xy 129.213656 -264.17854) (xy 129.263049 -264.194588) (xy 129.309323 -264.218166)
			(xy 129.351339 -264.248692) (xy 129.388062 -264.285415) (xy 129.418588 -264.327431) (xy 129.442166 -264.373705)
			(xy 129.458214 -264.423098) (xy 129.466339 -264.474393) (xy 129.466848 -264.50036) (xy 129.466339 -264.526327)
			(xy 129.746249 -264.526327) (xy 129.746249 -264.474393) (xy 129.754374 -264.423098) (xy 129.770422 -264.373705)
			(xy 129.794 -264.327431) (xy 129.824526 -264.285415) (xy 129.861249 -264.248692) (xy 129.903265 -264.218166)
			(xy 129.949539 -264.194588) (xy 129.998932 -264.17854) (xy 130.050227 -264.170415) (xy 130.102161 -264.170415)
			(xy 130.153456 -264.17854) (xy 130.202849 -264.194588) (xy 130.249123 -264.218166) (xy 130.291139 -264.248692)
			(xy 130.327862 -264.285415) (xy 130.358388 -264.327431) (xy 130.381966 -264.373705) (xy 130.398014 -264.423098)
			(xy 130.406139 -264.474393) (xy 130.406648 -264.50036) (xy 130.406139 -264.526327) (xy 130.686049 -264.526327)
			(xy 130.686049 -264.474393) (xy 130.694174 -264.423098) (xy 130.710222 -264.373705) (xy 130.7338 -264.327431)
			(xy 130.764326 -264.285415) (xy 130.801049 -264.248692) (xy 130.843065 -264.218166) (xy 130.889339 -264.194588)
			(xy 130.938732 -264.17854) (xy 130.990027 -264.170415) (xy 131.041961 -264.170415) (xy 131.093256 -264.17854)
			(xy 131.142649 -264.194588) (xy 131.188923 -264.218166) (xy 131.230939 -264.248692) (xy 131.267662 -264.285415)
			(xy 131.298188 -264.327431) (xy 131.321766 -264.373705) (xy 131.337814 -264.423098) (xy 131.345939 -264.474393)
			(xy 131.346448 -264.50036) (xy 131.345939 -264.526327) (xy 131.337814 -264.577622) (xy 131.321766 -264.627015)
			(xy 131.298188 -264.673289) (xy 131.267662 -264.715305) (xy 131.230939 -264.752028) (xy 131.188923 -264.782554)
			(xy 131.142649 -264.806132) (xy 131.093256 -264.82218) (xy 131.041961 -264.830305) (xy 130.990027 -264.830305)
			(xy 130.938732 -264.82218) (xy 130.889339 -264.806132) (xy 130.843065 -264.782554) (xy 130.801049 -264.752028)
			(xy 130.764326 -264.715305) (xy 130.7338 -264.673289) (xy 130.710222 -264.627015) (xy 130.694174 -264.577622)
			(xy 130.686049 -264.526327) (xy 130.406139 -264.526327) (xy 130.398014 -264.577622) (xy 130.381966 -264.627015)
			(xy 130.358388 -264.673289) (xy 130.327862 -264.715305) (xy 130.291139 -264.752028) (xy 130.249123 -264.782554)
			(xy 130.202849 -264.806132) (xy 130.153456 -264.82218) (xy 130.102161 -264.830305) (xy 130.050227 -264.830305)
			(xy 129.998932 -264.82218) (xy 129.949539 -264.806132) (xy 129.903265 -264.782554) (xy 129.861249 -264.752028)
			(xy 129.824526 -264.715305) (xy 129.794 -264.673289) (xy 129.770422 -264.627015) (xy 129.754374 -264.577622)
			(xy 129.746249 -264.526327) (xy 129.466339 -264.526327) (xy 129.458214 -264.577622) (xy 129.442166 -264.627015)
			(xy 129.418588 -264.673289) (xy 129.388062 -264.715305) (xy 129.351339 -264.752028) (xy 129.309323 -264.782554)
			(xy 129.263049 -264.806132) (xy 129.213656 -264.82218) (xy 129.162361 -264.830305) (xy 129.110427 -264.830305)
			(xy 129.059132 -264.82218) (xy 129.009739 -264.806132) (xy 128.963465 -264.782554) (xy 128.921449 -264.752028)
			(xy 128.884726 -264.715305) (xy 128.8542 -264.673289) (xy 128.830622 -264.627015) (xy 128.814574 -264.577622)
			(xy 128.806449 -264.526327) (xy 128.526539 -264.526327) (xy 128.518414 -264.577622) (xy 128.502366 -264.627015)
			(xy 128.478788 -264.673289) (xy 128.448262 -264.715305) (xy 128.411539 -264.752028) (xy 128.369523 -264.782554)
			(xy 128.323249 -264.806132) (xy 128.273856 -264.82218) (xy 128.222561 -264.830305) (xy 128.170627 -264.830305)
			(xy 128.119332 -264.82218) (xy 128.069939 -264.806132) (xy 128.023665 -264.782554) (xy 127.981649 -264.752028)
			(xy 127.944926 -264.715305) (xy 127.9144 -264.673289) (xy 127.890822 -264.627015) (xy 127.874774 -264.577622)
			(xy 127.866649 -264.526327) (xy 127.586739 -264.526327) (xy 127.578614 -264.577622) (xy 127.562566 -264.627015)
			(xy 127.538988 -264.673289) (xy 127.508462 -264.715305) (xy 127.471739 -264.752028) (xy 127.429723 -264.782554)
			(xy 127.383449 -264.806132) (xy 127.334056 -264.82218) (xy 127.282761 -264.830305) (xy 127.230827 -264.830305)
			(xy 127.179532 -264.82218) (xy 127.130139 -264.806132) (xy 127.083865 -264.782554) (xy 127.041849 -264.752028)
			(xy 127.005126 -264.715305) (xy 126.9746 -264.673289) (xy 126.951022 -264.627015) (xy 126.934974 -264.577622)
			(xy 126.926849 -264.526327) (xy 126.647193 -264.526327) (xy 126.639068 -264.577622) (xy 126.62302 -264.627015)
			(xy 126.599442 -264.673289) (xy 126.568916 -264.715305) (xy 126.532193 -264.752028) (xy 126.490177 -264.782554)
			(xy 126.443903 -264.806132) (xy 126.39451 -264.82218) (xy 126.343215 -264.830305) (xy 126.291281 -264.830305)
			(xy 126.239986 -264.82218) (xy 126.190593 -264.806132) (xy 126.144319 -264.782554) (xy 126.102303 -264.752028)
			(xy 126.06558 -264.715305) (xy 126.035054 -264.673289) (xy 126.011476 -264.627015) (xy 125.995428 -264.577622)
			(xy 125.987303 -264.526327) (xy 125.707139 -264.526327) (xy 125.699014 -264.577622) (xy 125.682966 -264.627015)
			(xy 125.659388 -264.673289) (xy 125.628862 -264.715305) (xy 125.592139 -264.752028) (xy 125.550123 -264.782554)
			(xy 125.503849 -264.806132) (xy 125.454456 -264.82218) (xy 125.403161 -264.830305) (xy 125.351227 -264.830305)
			(xy 125.299932 -264.82218) (xy 125.250539 -264.806132) (xy 125.204265 -264.782554) (xy 125.162249 -264.752028)
			(xy 125.125526 -264.715305) (xy 125.095 -264.673289) (xy 125.071422 -264.627015) (xy 125.055374 -264.577622)
			(xy 125.047249 -264.526327) (xy 124.767331 -264.526327) (xy 124.767331 -264.526366) (xy 124.759207 -264.57766)
			(xy 124.743159 -264.627051) (xy 124.719581 -264.673323) (xy 124.689056 -264.715338) (xy 124.652333 -264.75206)
			(xy 124.610318 -264.782585) (xy 124.564045 -264.806161) (xy 124.514654 -264.822208) (xy 124.46336 -264.830332)
			(xy 124.437394 -264.830814) (xy 124.424948 -264.83056) (xy 124.411278 -264.83047) (xy 124.384667 -264.836683)
			(xy 124.360654 -264.849726) (xy 124.340956 -264.868667) (xy 124.326981 -264.89215) (xy 124.319729 -264.918497)
			(xy 124.319284 -264.93216) (xy 124.319284 -265.340143) (xy 124.577603 -265.340143) (xy 124.577603 -265.288209)
			(xy 124.585728 -265.236914) (xy 124.601776 -265.187521) (xy 124.625354 -265.141247) (xy 124.65588 -265.099231)
			(xy 124.692603 -265.062508) (xy 124.734619 -265.031982) (xy 124.780893 -265.008404) (xy 124.830286 -264.992356)
			(xy 124.881581 -264.984231) (xy 124.933515 -264.984231) (xy 124.98481 -264.992356) (xy 125.034203 -265.008404)
			(xy 125.080477 -265.031982) (xy 125.122493 -265.062508) (xy 125.159216 -265.099231) (xy 125.189742 -265.141247)
			(xy 125.21332 -265.187521) (xy 125.229368 -265.236914) (xy 125.237493 -265.288209) (xy 125.238002 -265.314176)
			(xy 125.237493 -265.340143) (xy 125.517403 -265.340143) (xy 125.517403 -265.288209) (xy 125.525528 -265.236914)
			(xy 125.541576 -265.187521) (xy 125.565154 -265.141247) (xy 125.59568 -265.099231) (xy 125.632403 -265.062508)
			(xy 125.674419 -265.031982) (xy 125.720693 -265.008404) (xy 125.770086 -264.992356) (xy 125.821381 -264.984231)
			(xy 125.873315 -264.984231) (xy 125.92461 -264.992356) (xy 125.974003 -265.008404) (xy 126.020277 -265.031982)
			(xy 126.062293 -265.062508) (xy 126.099016 -265.099231) (xy 126.129542 -265.141247) (xy 126.15312 -265.187521)
			(xy 126.169168 -265.236914) (xy 126.177293 -265.288209) (xy 126.177802 -265.314176) (xy 126.177293 -265.340143)
			(xy 126.456949 -265.340143) (xy 126.456949 -265.288209) (xy 126.465074 -265.236914) (xy 126.481122 -265.187521)
			(xy 126.5047 -265.141247) (xy 126.535226 -265.099231) (xy 126.571949 -265.062508) (xy 126.613965 -265.031982)
			(xy 126.660239 -265.008404) (xy 126.709632 -264.992356) (xy 126.760927 -264.984231) (xy 126.812861 -264.984231)
			(xy 126.864156 -264.992356) (xy 126.913549 -265.008404) (xy 126.959823 -265.031982) (xy 127.001839 -265.062508)
			(xy 127.038562 -265.099231) (xy 127.069088 -265.141247) (xy 127.092666 -265.187521) (xy 127.108714 -265.236914)
			(xy 127.116839 -265.288209) (xy 127.117348 -265.314176) (xy 127.116839 -265.340143) (xy 127.397003 -265.340143)
			(xy 127.397003 -265.288209) (xy 127.405128 -265.236914) (xy 127.421176 -265.187521) (xy 127.444754 -265.141247)
			(xy 127.47528 -265.099231) (xy 127.512003 -265.062508) (xy 127.554019 -265.031982) (xy 127.600293 -265.008404)
			(xy 127.649686 -264.992356) (xy 127.700981 -264.984231) (xy 127.752915 -264.984231) (xy 127.80421 -264.992356)
			(xy 127.853603 -265.008404) (xy 127.899877 -265.031982) (xy 127.941893 -265.062508) (xy 127.978616 -265.099231)
			(xy 128.009142 -265.141247) (xy 128.03272 -265.187521) (xy 128.048768 -265.236914) (xy 128.056893 -265.288209)
			(xy 128.057402 -265.314176) (xy 128.056893 -265.340143) (xy 128.336803 -265.340143) (xy 128.336803 -265.288209)
			(xy 128.344928 -265.236914) (xy 128.360976 -265.187521) (xy 128.384554 -265.141247) (xy 128.41508 -265.099231)
			(xy 128.451803 -265.062508) (xy 128.493819 -265.031982) (xy 128.540093 -265.008404) (xy 128.589486 -264.992356)
			(xy 128.640781 -264.984231) (xy 128.692715 -264.984231) (xy 128.74401 -264.992356) (xy 128.793403 -265.008404)
			(xy 128.839677 -265.031982) (xy 128.881693 -265.062508) (xy 128.918416 -265.099231) (xy 128.948942 -265.141247)
			(xy 128.97252 -265.187521) (xy 128.988568 -265.236914) (xy 128.996693 -265.288209) (xy 128.997202 -265.314176)
			(xy 128.996693 -265.340143) (xy 129.276603 -265.340143) (xy 129.276603 -265.288209) (xy 129.284728 -265.236914)
			(xy 129.300776 -265.187521) (xy 129.324354 -265.141247) (xy 129.35488 -265.099231) (xy 129.391603 -265.062508)
			(xy 129.433619 -265.031982) (xy 129.479893 -265.008404) (xy 129.529286 -264.992356) (xy 129.580581 -264.984231)
			(xy 129.632515 -264.984231) (xy 129.68381 -264.992356) (xy 129.733203 -265.008404) (xy 129.779477 -265.031982)
			(xy 129.821493 -265.062508) (xy 129.858216 -265.099231) (xy 129.888742 -265.141247) (xy 129.91232 -265.187521)
			(xy 129.928368 -265.236914) (xy 129.936493 -265.288209) (xy 129.937002 -265.314176) (xy 129.936493 -265.340143)
			(xy 130.216403 -265.340143) (xy 130.216403 -265.288209) (xy 130.224528 -265.236914) (xy 130.240576 -265.187521)
			(xy 130.264154 -265.141247) (xy 130.29468 -265.099231) (xy 130.331403 -265.062508) (xy 130.373419 -265.031982)
			(xy 130.419693 -265.008404) (xy 130.469086 -264.992356) (xy 130.520381 -264.984231) (xy 130.572315 -264.984231)
			(xy 130.62361 -264.992356) (xy 130.673003 -265.008404) (xy 130.719277 -265.031982) (xy 130.761293 -265.062508)
			(xy 130.798016 -265.099231) (xy 130.828542 -265.141247) (xy 130.85212 -265.187521) (xy 130.868168 -265.236914)
			(xy 130.876293 -265.288209) (xy 130.876802 -265.314176) (xy 130.876293 -265.340143) (xy 130.868168 -265.391438)
			(xy 130.85212 -265.440831) (xy 130.828542 -265.487105) (xy 130.798016 -265.529121) (xy 130.761293 -265.565844)
			(xy 130.719277 -265.59637) (xy 130.673003 -265.619948) (xy 130.62361 -265.635996) (xy 130.572315 -265.644121)
			(xy 130.520381 -265.644121) (xy 130.469086 -265.635996) (xy 130.419693 -265.619948) (xy 130.373419 -265.59637)
			(xy 130.331403 -265.565844) (xy 130.29468 -265.529121) (xy 130.264154 -265.487105) (xy 130.240576 -265.440831)
			(xy 130.224528 -265.391438) (xy 130.216403 -265.340143) (xy 129.936493 -265.340143) (xy 129.928368 -265.391438)
			(xy 129.91232 -265.440831) (xy 129.888742 -265.487105) (xy 129.858216 -265.529121) (xy 129.821493 -265.565844)
			(xy 129.779477 -265.59637) (xy 129.733203 -265.619948) (xy 129.68381 -265.635996) (xy 129.632515 -265.644121)
			(xy 129.580581 -265.644121) (xy 129.529286 -265.635996) (xy 129.479893 -265.619948) (xy 129.433619 -265.59637)
			(xy 129.391603 -265.565844) (xy 129.35488 -265.529121) (xy 129.324354 -265.487105) (xy 129.300776 -265.440831)
			(xy 129.284728 -265.391438) (xy 129.276603 -265.340143) (xy 128.996693 -265.340143) (xy 128.988568 -265.391438)
			(xy 128.97252 -265.440831) (xy 128.948942 -265.487105) (xy 128.918416 -265.529121) (xy 128.881693 -265.565844)
			(xy 128.839677 -265.59637) (xy 128.793403 -265.619948) (xy 128.74401 -265.635996) (xy 128.692715 -265.644121)
			(xy 128.640781 -265.644121) (xy 128.589486 -265.635996) (xy 128.540093 -265.619948) (xy 128.493819 -265.59637)
			(xy 128.451803 -265.565844) (xy 128.41508 -265.529121) (xy 128.384554 -265.487105) (xy 128.360976 -265.440831)
			(xy 128.344928 -265.391438) (xy 128.336803 -265.340143) (xy 128.056893 -265.340143) (xy 128.048768 -265.391438)
			(xy 128.03272 -265.440831) (xy 128.009142 -265.487105) (xy 127.978616 -265.529121) (xy 127.941893 -265.565844)
			(xy 127.899877 -265.59637) (xy 127.853603 -265.619948) (xy 127.80421 -265.635996) (xy 127.752915 -265.644121)
			(xy 127.700981 -265.644121) (xy 127.649686 -265.635996) (xy 127.600293 -265.619948) (xy 127.554019 -265.59637)
			(xy 127.512003 -265.565844) (xy 127.47528 -265.529121) (xy 127.444754 -265.487105) (xy 127.421176 -265.440831)
			(xy 127.405128 -265.391438) (xy 127.397003 -265.340143) (xy 127.116839 -265.340143) (xy 127.108714 -265.391438)
			(xy 127.092666 -265.440831) (xy 127.069088 -265.487105) (xy 127.038562 -265.529121) (xy 127.001839 -265.565844)
			(xy 126.959823 -265.59637) (xy 126.913549 -265.619948) (xy 126.864156 -265.635996) (xy 126.812861 -265.644121)
			(xy 126.760927 -265.644121) (xy 126.709632 -265.635996) (xy 126.660239 -265.619948) (xy 126.613965 -265.59637)
			(xy 126.571949 -265.565844) (xy 126.535226 -265.529121) (xy 126.5047 -265.487105) (xy 126.481122 -265.440831)
			(xy 126.465074 -265.391438) (xy 126.456949 -265.340143) (xy 126.177293 -265.340143) (xy 126.169168 -265.391438)
			(xy 126.15312 -265.440831) (xy 126.129542 -265.487105) (xy 126.099016 -265.529121) (xy 126.062293 -265.565844)
			(xy 126.020277 -265.59637) (xy 125.974003 -265.619948) (xy 125.92461 -265.635996) (xy 125.873315 -265.644121)
			(xy 125.821381 -265.644121) (xy 125.770086 -265.635996) (xy 125.720693 -265.619948) (xy 125.674419 -265.59637)
			(xy 125.632403 -265.565844) (xy 125.59568 -265.529121) (xy 125.565154 -265.487105) (xy 125.541576 -265.440831)
			(xy 125.525528 -265.391438) (xy 125.517403 -265.340143) (xy 125.237493 -265.340143) (xy 125.229368 -265.391438)
			(xy 125.21332 -265.440831) (xy 125.189742 -265.487105) (xy 125.159216 -265.529121) (xy 125.122493 -265.565844)
			(xy 125.080477 -265.59637) (xy 125.034203 -265.619948) (xy 124.98481 -265.635996) (xy 124.933515 -265.644121)
			(xy 124.881581 -265.644121) (xy 124.830286 -265.635996) (xy 124.780893 -265.619948) (xy 124.734619 -265.59637)
			(xy 124.692603 -265.565844) (xy 124.65588 -265.529121) (xy 124.625354 -265.487105) (xy 124.601776 -265.440831)
			(xy 124.585728 -265.391438) (xy 124.577603 -265.340143) (xy 124.319284 -265.340143) (xy 124.319284 -265.696446)
			(xy 124.319691 -265.710119) (xy 124.326915 -265.736491) (xy 124.340884 -265.759997) (xy 124.360596 -265.778948)
			(xy 124.384633 -265.791982) (xy 124.411269 -265.798162) (xy 124.424948 -265.798046) (xy 124.437394 -265.797792)
			(xy 124.463367 -265.798183) (xy 124.514674 -265.806308) (xy 124.564078 -265.82236) (xy 124.610363 -265.845942)
			(xy 124.652389 -265.876475) (xy 124.689121 -265.913206) (xy 124.719655 -265.955232) (xy 124.743238 -266.001516)
			(xy 124.759291 -266.05092) (xy 124.767417 -266.102227) (xy 124.767417 -266.154173) (xy 124.767411 -266.154213)
			(xy 125.047249 -266.154213) (xy 125.047249 -266.102279) (xy 125.055374 -266.050984) (xy 125.071422 -266.001591)
			(xy 125.095 -265.955317) (xy 125.125526 -265.913301) (xy 125.162249 -265.876578) (xy 125.204265 -265.846052)
			(xy 125.250539 -265.822474) (xy 125.299932 -265.806426) (xy 125.351227 -265.798301) (xy 125.403161 -265.798301)
			(xy 125.454456 -265.806426) (xy 125.503849 -265.822474) (xy 125.550123 -265.846052) (xy 125.592139 -265.876578)
			(xy 125.628862 -265.913301) (xy 125.659388 -265.955317) (xy 125.682966 -266.001591) (xy 125.699014 -266.050984)
			(xy 125.707139 -266.102279) (xy 125.707648 -266.128246) (xy 125.707139 -266.154213) (xy 125.987049 -266.154213)
			(xy 125.987049 -266.102279) (xy 125.995174 -266.050984) (xy 126.011222 -266.001591) (xy 126.0348 -265.955317)
			(xy 126.065326 -265.913301) (xy 126.102049 -265.876578) (xy 126.144065 -265.846052) (xy 126.190339 -265.822474)
			(xy 126.239732 -265.806426) (xy 126.291027 -265.798301) (xy 126.342961 -265.798301) (xy 126.394256 -265.806426)
			(xy 126.443649 -265.822474) (xy 126.489923 -265.846052) (xy 126.531939 -265.876578) (xy 126.568662 -265.913301)
			(xy 126.599188 -265.955317) (xy 126.622766 -266.001591) (xy 126.638814 -266.050984) (xy 126.646939 -266.102279)
			(xy 126.647448 -266.128246) (xy 126.646939 -266.154213) (xy 126.926849 -266.154213) (xy 126.926849 -266.102279)
			(xy 126.934974 -266.050984) (xy 126.951022 -266.001591) (xy 126.9746 -265.955317) (xy 127.005126 -265.913301)
			(xy 127.041849 -265.876578) (xy 127.083865 -265.846052) (xy 127.130139 -265.822474) (xy 127.179532 -265.806426)
			(xy 127.230827 -265.798301) (xy 127.282761 -265.798301) (xy 127.334056 -265.806426) (xy 127.383449 -265.822474)
			(xy 127.429723 -265.846052) (xy 127.471739 -265.876578) (xy 127.508462 -265.913301) (xy 127.538988 -265.955317)
			(xy 127.562566 -266.001591) (xy 127.578614 -266.050984) (xy 127.586739 -266.102279) (xy 127.587248 -266.128246)
			(xy 127.586739 -266.154213) (xy 127.866649 -266.154213) (xy 127.866649 -266.102279) (xy 127.874774 -266.050984)
			(xy 127.890822 -266.001591) (xy 127.9144 -265.955317) (xy 127.944926 -265.913301) (xy 127.981649 -265.876578)
			(xy 128.023665 -265.846052) (xy 128.069939 -265.822474) (xy 128.119332 -265.806426) (xy 128.170627 -265.798301)
			(xy 128.222561 -265.798301) (xy 128.273856 -265.806426) (xy 128.323249 -265.822474) (xy 128.369523 -265.846052)
			(xy 128.411539 -265.876578) (xy 128.448262 -265.913301) (xy 128.478788 -265.955317) (xy 128.502366 -266.001591)
			(xy 128.518414 -266.050984) (xy 128.526539 -266.102279) (xy 128.527048 -266.128246) (xy 128.526539 -266.154213)
			(xy 128.806449 -266.154213) (xy 128.806449 -266.102279) (xy 128.814574 -266.050984) (xy 128.830622 -266.001591)
			(xy 128.8542 -265.955317) (xy 128.884726 -265.913301) (xy 128.921449 -265.876578) (xy 128.963465 -265.846052)
			(xy 129.009739 -265.822474) (xy 129.059132 -265.806426) (xy 129.110427 -265.798301) (xy 129.162361 -265.798301)
			(xy 129.213656 -265.806426) (xy 129.263049 -265.822474) (xy 129.309323 -265.846052) (xy 129.351339 -265.876578)
			(xy 129.388062 -265.913301) (xy 129.418588 -265.955317) (xy 129.442166 -266.001591) (xy 129.458214 -266.050984)
			(xy 129.466339 -266.102279) (xy 129.466848 -266.128246) (xy 129.466339 -266.154213) (xy 129.746249 -266.154213)
			(xy 129.746249 -266.102279) (xy 129.754374 -266.050984) (xy 129.770422 -266.001591) (xy 129.794 -265.955317)
			(xy 129.824526 -265.913301) (xy 129.861249 -265.876578) (xy 129.903265 -265.846052) (xy 129.949539 -265.822474)
			(xy 129.998932 -265.806426) (xy 130.050227 -265.798301) (xy 130.102161 -265.798301) (xy 130.153456 -265.806426)
			(xy 130.202849 -265.822474) (xy 130.249123 -265.846052) (xy 130.291139 -265.876578) (xy 130.327862 -265.913301)
			(xy 130.358388 -265.955317) (xy 130.381966 -266.001591) (xy 130.398014 -266.050984) (xy 130.406139 -266.102279)
			(xy 130.406648 -266.128246) (xy 130.406139 -266.154213) (xy 130.686049 -266.154213) (xy 130.686049 -266.102279)
			(xy 130.694174 -266.050984) (xy 130.710222 -266.001591) (xy 130.7338 -265.955317) (xy 130.764326 -265.913301)
			(xy 130.801049 -265.876578) (xy 130.843065 -265.846052) (xy 130.889339 -265.822474) (xy 130.938732 -265.806426)
			(xy 130.990027 -265.798301) (xy 131.041961 -265.798301) (xy 131.093256 -265.806426) (xy 131.142649 -265.822474)
			(xy 131.188923 -265.846052) (xy 131.230939 -265.876578) (xy 131.267662 -265.913301) (xy 131.298188 -265.955317)
			(xy 131.321766 -266.001591) (xy 131.337814 -266.050984) (xy 131.345939 -266.102279) (xy 131.346448 -266.128246)
			(xy 131.345939 -266.154213) (xy 131.337814 -266.205508) (xy 131.321766 -266.254901) (xy 131.298188 -266.301175)
			(xy 131.267662 -266.343191) (xy 131.230939 -266.379914) (xy 131.188923 -266.41044) (xy 131.142649 -266.434018)
			(xy 131.093256 -266.450066) (xy 131.041961 -266.458191) (xy 130.990027 -266.458191) (xy 130.938732 -266.450066)
			(xy 130.889339 -266.434018) (xy 130.843065 -266.41044) (xy 130.801049 -266.379914) (xy 130.764326 -266.343191)
			(xy 130.7338 -266.301175) (xy 130.710222 -266.254901) (xy 130.694174 -266.205508) (xy 130.686049 -266.154213)
			(xy 130.406139 -266.154213) (xy 130.398014 -266.205508) (xy 130.381966 -266.254901) (xy 130.358388 -266.301175)
			(xy 130.327862 -266.343191) (xy 130.291139 -266.379914) (xy 130.249123 -266.41044) (xy 130.202849 -266.434018)
			(xy 130.153456 -266.450066) (xy 130.102161 -266.458191) (xy 130.050227 -266.458191) (xy 129.998932 -266.450066)
			(xy 129.949539 -266.434018) (xy 129.903265 -266.41044) (xy 129.861249 -266.379914) (xy 129.824526 -266.343191)
			(xy 129.794 -266.301175) (xy 129.770422 -266.254901) (xy 129.754374 -266.205508) (xy 129.746249 -266.154213)
			(xy 129.466339 -266.154213) (xy 129.458214 -266.205508) (xy 129.442166 -266.254901) (xy 129.418588 -266.301175)
			(xy 129.388062 -266.343191) (xy 129.351339 -266.379914) (xy 129.309323 -266.41044) (xy 129.263049 -266.434018)
			(xy 129.213656 -266.450066) (xy 129.162361 -266.458191) (xy 129.110427 -266.458191) (xy 129.059132 -266.450066)
			(xy 129.009739 -266.434018) (xy 128.963465 -266.41044) (xy 128.921449 -266.379914) (xy 128.884726 -266.343191)
			(xy 128.8542 -266.301175) (xy 128.830622 -266.254901) (xy 128.814574 -266.205508) (xy 128.806449 -266.154213)
			(xy 128.526539 -266.154213) (xy 128.518414 -266.205508) (xy 128.502366 -266.254901) (xy 128.478788 -266.301175)
			(xy 128.448262 -266.343191) (xy 128.411539 -266.379914) (xy 128.369523 -266.41044) (xy 128.323249 -266.434018)
			(xy 128.273856 -266.450066) (xy 128.222561 -266.458191) (xy 128.170627 -266.458191) (xy 128.119332 -266.450066)
			(xy 128.069939 -266.434018) (xy 128.023665 -266.41044) (xy 127.981649 -266.379914) (xy 127.944926 -266.343191)
			(xy 127.9144 -266.301175) (xy 127.890822 -266.254901) (xy 127.874774 -266.205508) (xy 127.866649 -266.154213)
			(xy 127.586739 -266.154213) (xy 127.578614 -266.205508) (xy 127.562566 -266.254901) (xy 127.538988 -266.301175)
			(xy 127.508462 -266.343191) (xy 127.471739 -266.379914) (xy 127.429723 -266.41044) (xy 127.383449 -266.434018)
			(xy 127.334056 -266.450066) (xy 127.282761 -266.458191) (xy 127.230827 -266.458191) (xy 127.179532 -266.450066)
			(xy 127.130139 -266.434018) (xy 127.083865 -266.41044) (xy 127.041849 -266.379914) (xy 127.005126 -266.343191)
			(xy 126.9746 -266.301175) (xy 126.951022 -266.254901) (xy 126.934974 -266.205508) (xy 126.926849 -266.154213)
			(xy 126.646939 -266.154213) (xy 126.638814 -266.205508) (xy 126.622766 -266.254901) (xy 126.599188 -266.301175)
			(xy 126.568662 -266.343191) (xy 126.531939 -266.379914) (xy 126.489923 -266.41044) (xy 126.443649 -266.434018)
			(xy 126.394256 -266.450066) (xy 126.342961 -266.458191) (xy 126.291027 -266.458191) (xy 126.239732 -266.450066)
			(xy 126.190339 -266.434018) (xy 126.144065 -266.41044) (xy 126.102049 -266.379914) (xy 126.065326 -266.343191)
			(xy 126.0348 -266.301175) (xy 126.011222 -266.254901) (xy 125.995174 -266.205508) (xy 125.987049 -266.154213)
			(xy 125.707139 -266.154213) (xy 125.699014 -266.205508) (xy 125.682966 -266.254901) (xy 125.659388 -266.301175)
			(xy 125.628862 -266.343191) (xy 125.592139 -266.379914) (xy 125.550123 -266.41044) (xy 125.503849 -266.434018)
			(xy 125.454456 -266.450066) (xy 125.403161 -266.458191) (xy 125.351227 -266.458191) (xy 125.299932 -266.450066)
			(xy 125.250539 -266.434018) (xy 125.204265 -266.41044) (xy 125.162249 -266.379914) (xy 125.125526 -266.343191)
			(xy 125.095 -266.301175) (xy 125.071422 -266.254901) (xy 125.055374 -266.205508) (xy 125.047249 -266.154213)
			(xy 124.767411 -266.154213) (xy 124.759291 -266.20548) (xy 124.743238 -266.254884) (xy 124.719655 -266.301168)
			(xy 124.689121 -266.343194) (xy 124.652389 -266.379925) (xy 124.610363 -266.410458) (xy 124.564078 -266.43404)
			(xy 124.514674 -266.450092) (xy 124.463367 -266.458217) (xy 124.437394 -266.4587) (xy 124.424948 -266.458446)
			(xy 124.411278 -266.458369) (xy 124.38467 -266.464582) (xy 124.360658 -266.477623) (xy 124.34096 -266.49656)
			(xy 124.326985 -266.52004) (xy 124.319731 -266.546384) (xy 124.319284 -266.560046) (xy 124.319284 -266.967775)
			(xy 124.577603 -266.967775) (xy 124.577603 -266.915841) (xy 124.585728 -266.864546) (xy 124.601776 -266.815153)
			(xy 124.625354 -266.768879) (xy 124.65588 -266.726863) (xy 124.692603 -266.69014) (xy 124.734619 -266.659614)
			(xy 124.780893 -266.636036) (xy 124.830286 -266.619988) (xy 124.881581 -266.611863) (xy 124.933515 -266.611863)
			(xy 124.98481 -266.619988) (xy 125.034203 -266.636036) (xy 125.080477 -266.659614) (xy 125.122493 -266.69014)
			(xy 125.159216 -266.726863) (xy 125.189742 -266.768879) (xy 125.21332 -266.815153) (xy 125.229368 -266.864546)
			(xy 125.237493 -266.915841) (xy 125.238002 -266.941808) (xy 125.237493 -266.967775) (xy 125.517149 -266.967775)
			(xy 125.517149 -266.915841) (xy 125.525274 -266.864546) (xy 125.541322 -266.815153) (xy 125.5649 -266.768879)
			(xy 125.595426 -266.726863) (xy 125.632149 -266.69014) (xy 125.674165 -266.659614) (xy 125.720439 -266.636036)
			(xy 125.769832 -266.619988) (xy 125.821127 -266.611863) (xy 125.873061 -266.611863) (xy 125.924356 -266.619988)
			(xy 125.973749 -266.636036) (xy 126.020023 -266.659614) (xy 126.062039 -266.69014) (xy 126.098762 -266.726863)
			(xy 126.129288 -266.768879) (xy 126.152866 -266.815153) (xy 126.168914 -266.864546) (xy 126.177039 -266.915841)
			(xy 126.177548 -266.941808) (xy 126.177039 -266.967775) (xy 126.457203 -266.967775) (xy 126.457203 -266.915841)
			(xy 126.465328 -266.864546) (xy 126.481376 -266.815153) (xy 126.504954 -266.768879) (xy 126.53548 -266.726863)
			(xy 126.572203 -266.69014) (xy 126.614219 -266.659614) (xy 126.660493 -266.636036) (xy 126.709886 -266.619988)
			(xy 126.761181 -266.611863) (xy 126.813115 -266.611863) (xy 126.86441 -266.619988) (xy 126.913803 -266.636036)
			(xy 126.960077 -266.659614) (xy 127.002093 -266.69014) (xy 127.038816 -266.726863) (xy 127.069342 -266.768879)
			(xy 127.09292 -266.815153) (xy 127.108968 -266.864546) (xy 127.117093 -266.915841) (xy 127.117602 -266.941808)
			(xy 127.117093 -266.967775) (xy 127.397003 -266.967775) (xy 127.397003 -266.915841) (xy 127.405128 -266.864546)
			(xy 127.421176 -266.815153) (xy 127.444754 -266.768879) (xy 127.47528 -266.726863) (xy 127.512003 -266.69014)
			(xy 127.554019 -266.659614) (xy 127.600293 -266.636036) (xy 127.649686 -266.619988) (xy 127.700981 -266.611863)
			(xy 127.752915 -266.611863) (xy 127.80421 -266.619988) (xy 127.853603 -266.636036) (xy 127.899877 -266.659614)
			(xy 127.941893 -266.69014) (xy 127.978616 -266.726863) (xy 128.009142 -266.768879) (xy 128.03272 -266.815153)
			(xy 128.048768 -266.864546) (xy 128.056893 -266.915841) (xy 128.057402 -266.941808) (xy 128.056893 -266.967775)
			(xy 128.336803 -266.967775) (xy 128.336803 -266.915841) (xy 128.344928 -266.864546) (xy 128.360976 -266.815153)
			(xy 128.384554 -266.768879) (xy 128.41508 -266.726863) (xy 128.451803 -266.69014) (xy 128.493819 -266.659614)
			(xy 128.540093 -266.636036) (xy 128.589486 -266.619988) (xy 128.640781 -266.611863) (xy 128.692715 -266.611863)
			(xy 128.74401 -266.619988) (xy 128.793403 -266.636036) (xy 128.839677 -266.659614) (xy 128.881693 -266.69014)
			(xy 128.918416 -266.726863) (xy 128.948942 -266.768879) (xy 128.97252 -266.815153) (xy 128.988568 -266.864546)
			(xy 128.996693 -266.915841) (xy 128.997202 -266.941808) (xy 128.996693 -266.967775) (xy 129.276603 -266.967775)
			(xy 129.276603 -266.915841) (xy 129.284728 -266.864546) (xy 129.300776 -266.815153) (xy 129.324354 -266.768879)
			(xy 129.35488 -266.726863) (xy 129.391603 -266.69014) (xy 129.433619 -266.659614) (xy 129.479893 -266.636036)
			(xy 129.529286 -266.619988) (xy 129.580581 -266.611863) (xy 129.632515 -266.611863) (xy 129.68381 -266.619988)
			(xy 129.733203 -266.636036) (xy 129.779477 -266.659614) (xy 129.821493 -266.69014) (xy 129.858216 -266.726863)
			(xy 129.888742 -266.768879) (xy 129.91232 -266.815153) (xy 129.928368 -266.864546) (xy 129.936493 -266.915841)
			(xy 129.937002 -266.941808) (xy 129.936493 -266.967775) (xy 130.216403 -266.967775) (xy 130.216403 -266.915841)
			(xy 130.224528 -266.864546) (xy 130.240576 -266.815153) (xy 130.264154 -266.768879) (xy 130.29468 -266.726863)
			(xy 130.331403 -266.69014) (xy 130.373419 -266.659614) (xy 130.419693 -266.636036) (xy 130.469086 -266.619988)
			(xy 130.520381 -266.611863) (xy 130.572315 -266.611863) (xy 130.62361 -266.619988) (xy 130.673003 -266.636036)
			(xy 130.719277 -266.659614) (xy 130.761293 -266.69014) (xy 130.798016 -266.726863) (xy 130.828542 -266.768879)
			(xy 130.85212 -266.815153) (xy 130.868168 -266.864546) (xy 130.876293 -266.915841) (xy 130.876802 -266.941808)
			(xy 130.876293 -266.967775) (xy 130.868168 -267.01907) (xy 130.85212 -267.068463) (xy 130.828542 -267.114737)
			(xy 130.798016 -267.156753) (xy 130.761293 -267.193476) (xy 130.719277 -267.224002) (xy 130.673003 -267.24758)
			(xy 130.62361 -267.263628) (xy 130.572315 -267.271753) (xy 130.520381 -267.271753) (xy 130.469086 -267.263628)
			(xy 130.419693 -267.24758) (xy 130.373419 -267.224002) (xy 130.331403 -267.193476) (xy 130.29468 -267.156753)
			(xy 130.264154 -267.114737) (xy 130.240576 -267.068463) (xy 130.224528 -267.01907) (xy 130.216403 -266.967775)
			(xy 129.936493 -266.967775) (xy 129.928368 -267.01907) (xy 129.91232 -267.068463) (xy 129.888742 -267.114737)
			(xy 129.858216 -267.156753) (xy 129.821493 -267.193476) (xy 129.779477 -267.224002) (xy 129.733203 -267.24758)
			(xy 129.68381 -267.263628) (xy 129.632515 -267.271753) (xy 129.580581 -267.271753) (xy 129.529286 -267.263628)
			(xy 129.479893 -267.24758) (xy 129.433619 -267.224002) (xy 129.391603 -267.193476) (xy 129.35488 -267.156753)
			(xy 129.324354 -267.114737) (xy 129.300776 -267.068463) (xy 129.284728 -267.01907) (xy 129.276603 -266.967775)
			(xy 128.996693 -266.967775) (xy 128.988568 -267.01907) (xy 128.97252 -267.068463) (xy 128.948942 -267.114737)
			(xy 128.918416 -267.156753) (xy 128.881693 -267.193476) (xy 128.839677 -267.224002) (xy 128.793403 -267.24758)
			(xy 128.74401 -267.263628) (xy 128.692715 -267.271753) (xy 128.640781 -267.271753) (xy 128.589486 -267.263628)
			(xy 128.540093 -267.24758) (xy 128.493819 -267.224002) (xy 128.451803 -267.193476) (xy 128.41508 -267.156753)
			(xy 128.384554 -267.114737) (xy 128.360976 -267.068463) (xy 128.344928 -267.01907) (xy 128.336803 -266.967775)
			(xy 128.056893 -266.967775) (xy 128.048768 -267.01907) (xy 128.03272 -267.068463) (xy 128.009142 -267.114737)
			(xy 127.978616 -267.156753) (xy 127.941893 -267.193476) (xy 127.899877 -267.224002) (xy 127.853603 -267.24758)
			(xy 127.80421 -267.263628) (xy 127.752915 -267.271753) (xy 127.700981 -267.271753) (xy 127.649686 -267.263628)
			(xy 127.600293 -267.24758) (xy 127.554019 -267.224002) (xy 127.512003 -267.193476) (xy 127.47528 -267.156753)
			(xy 127.444754 -267.114737) (xy 127.421176 -267.068463) (xy 127.405128 -267.01907) (xy 127.397003 -266.967775)
			(xy 127.117093 -266.967775) (xy 127.108968 -267.01907) (xy 127.09292 -267.068463) (xy 127.069342 -267.114737)
			(xy 127.038816 -267.156753) (xy 127.002093 -267.193476) (xy 126.960077 -267.224002) (xy 126.913803 -267.24758)
			(xy 126.86441 -267.263628) (xy 126.813115 -267.271753) (xy 126.761181 -267.271753) (xy 126.709886 -267.263628)
			(xy 126.660493 -267.24758) (xy 126.614219 -267.224002) (xy 126.572203 -267.193476) (xy 126.53548 -267.156753)
			(xy 126.504954 -267.114737) (xy 126.481376 -267.068463) (xy 126.465328 -267.01907) (xy 126.457203 -266.967775)
			(xy 126.177039 -266.967775) (xy 126.168914 -267.01907) (xy 126.152866 -267.068463) (xy 126.129288 -267.114737)
			(xy 126.098762 -267.156753) (xy 126.062039 -267.193476) (xy 126.020023 -267.224002) (xy 125.973749 -267.24758)
			(xy 125.924356 -267.263628) (xy 125.873061 -267.271753) (xy 125.821127 -267.271753) (xy 125.769832 -267.263628)
			(xy 125.720439 -267.24758) (xy 125.674165 -267.224002) (xy 125.632149 -267.193476) (xy 125.595426 -267.156753)
			(xy 125.5649 -267.114737) (xy 125.541322 -267.068463) (xy 125.525274 -267.01907) (xy 125.517149 -266.967775)
			(xy 125.237493 -266.967775) (xy 125.229368 -267.01907) (xy 125.21332 -267.068463) (xy 125.189742 -267.114737)
			(xy 125.159216 -267.156753) (xy 125.122493 -267.193476) (xy 125.080477 -267.224002) (xy 125.034203 -267.24758)
			(xy 124.98481 -267.263628) (xy 124.933515 -267.271753) (xy 124.881581 -267.271753) (xy 124.830286 -267.263628)
			(xy 124.780893 -267.24758) (xy 124.734619 -267.224002) (xy 124.692603 -267.193476) (xy 124.65588 -267.156753)
			(xy 124.625354 -267.114737) (xy 124.601776 -267.068463) (xy 124.585728 -267.01907) (xy 124.577603 -266.967775)
			(xy 124.319284 -266.967775) (xy 124.319284 -267.324078) (xy 124.319664 -267.337752) (xy 124.326895 -267.364125)
			(xy 124.340871 -267.387631) (xy 124.360587 -267.406581) (xy 124.384629 -267.419614) (xy 124.411268 -267.425794)
			(xy 124.424948 -267.425678) (xy 124.437394 -267.425424) (xy 124.463362 -267.42595) (xy 124.514658 -267.434074)
			(xy 124.564052 -267.450122) (xy 124.610328 -267.4737) (xy 124.652345 -267.504227) (xy 124.689069 -267.54095)
			(xy 124.719597 -267.582967) (xy 124.743175 -267.629242) (xy 124.759225 -267.678636) (xy 124.767349 -267.729932)
			(xy 124.767349 -267.781845) (xy 125.047249 -267.781845) (xy 125.047249 -267.729911) (xy 125.055374 -267.678616)
			(xy 125.071422 -267.629223) (xy 125.095 -267.582949) (xy 125.125526 -267.540933) (xy 125.162249 -267.50421)
			(xy 125.204265 -267.473684) (xy 125.250539 -267.450106) (xy 125.299932 -267.434058) (xy 125.351227 -267.425933)
			(xy 125.403161 -267.425933) (xy 125.454456 -267.434058) (xy 125.503849 -267.450106) (xy 125.550123 -267.473684)
			(xy 125.592139 -267.50421) (xy 125.628862 -267.540933) (xy 125.659388 -267.582949) (xy 125.682966 -267.629223)
			(xy 125.699014 -267.678616) (xy 125.707139 -267.729911) (xy 125.707648 -267.755878) (xy 125.707139 -267.781845)
			(xy 125.987049 -267.781845) (xy 125.987049 -267.729911) (xy 125.995174 -267.678616) (xy 126.011222 -267.629223)
			(xy 126.0348 -267.582949) (xy 126.065326 -267.540933) (xy 126.102049 -267.50421) (xy 126.144065 -267.473684)
			(xy 126.190339 -267.450106) (xy 126.239732 -267.434058) (xy 126.291027 -267.425933) (xy 126.342961 -267.425933)
			(xy 126.394256 -267.434058) (xy 126.443649 -267.450106) (xy 126.489923 -267.473684) (xy 126.531939 -267.50421)
			(xy 126.568662 -267.540933) (xy 126.599188 -267.582949) (xy 126.622766 -267.629223) (xy 126.638814 -267.678616)
			(xy 126.646939 -267.729911) (xy 126.647448 -267.755878) (xy 126.646939 -267.781845) (xy 126.926849 -267.781845)
			(xy 126.926849 -267.729911) (xy 126.934974 -267.678616) (xy 126.951022 -267.629223) (xy 126.9746 -267.582949)
			(xy 127.005126 -267.540933) (xy 127.041849 -267.50421) (xy 127.083865 -267.473684) (xy 127.130139 -267.450106)
			(xy 127.179532 -267.434058) (xy 127.230827 -267.425933) (xy 127.282761 -267.425933) (xy 127.334056 -267.434058)
			(xy 127.383449 -267.450106) (xy 127.429723 -267.473684) (xy 127.471739 -267.50421) (xy 127.508462 -267.540933)
			(xy 127.538988 -267.582949) (xy 127.562566 -267.629223) (xy 127.578614 -267.678616) (xy 127.586739 -267.729911)
			(xy 127.587248 -267.755878) (xy 127.586739 -267.781845) (xy 127.866649 -267.781845) (xy 127.866649 -267.729911)
			(xy 127.874774 -267.678616) (xy 127.890822 -267.629223) (xy 127.9144 -267.582949) (xy 127.944926 -267.540933)
			(xy 127.981649 -267.50421) (xy 128.023665 -267.473684) (xy 128.069939 -267.450106) (xy 128.119332 -267.434058)
			(xy 128.170627 -267.425933) (xy 128.222561 -267.425933) (xy 128.273856 -267.434058) (xy 128.323249 -267.450106)
			(xy 128.369523 -267.473684) (xy 128.411539 -267.50421) (xy 128.448262 -267.540933) (xy 128.478788 -267.582949)
			(xy 128.502366 -267.629223) (xy 128.518414 -267.678616) (xy 128.526539 -267.729911) (xy 128.527048 -267.755878)
			(xy 128.526539 -267.781845) (xy 128.806449 -267.781845) (xy 128.806449 -267.729911) (xy 128.814574 -267.678616)
			(xy 128.830622 -267.629223) (xy 128.8542 -267.582949) (xy 128.884726 -267.540933) (xy 128.921449 -267.50421)
			(xy 128.963465 -267.473684) (xy 129.009739 -267.450106) (xy 129.059132 -267.434058) (xy 129.110427 -267.425933)
			(xy 129.162361 -267.425933) (xy 129.213656 -267.434058) (xy 129.263049 -267.450106) (xy 129.309323 -267.473684)
			(xy 129.351339 -267.50421) (xy 129.388062 -267.540933) (xy 129.418588 -267.582949) (xy 129.442166 -267.629223)
			(xy 129.458214 -267.678616) (xy 129.466339 -267.729911) (xy 129.466848 -267.755878) (xy 129.466339 -267.781845)
			(xy 129.746249 -267.781845) (xy 129.746249 -267.729911) (xy 129.754374 -267.678616) (xy 129.770422 -267.629223)
			(xy 129.794 -267.582949) (xy 129.824526 -267.540933) (xy 129.861249 -267.50421) (xy 129.903265 -267.473684)
			(xy 129.949539 -267.450106) (xy 129.998932 -267.434058) (xy 130.050227 -267.425933) (xy 130.102161 -267.425933)
			(xy 130.153456 -267.434058) (xy 130.202849 -267.450106) (xy 130.249123 -267.473684) (xy 130.291139 -267.50421)
			(xy 130.327862 -267.540933) (xy 130.358388 -267.582949) (xy 130.381966 -267.629223) (xy 130.398014 -267.678616)
			(xy 130.406139 -267.729911) (xy 130.406648 -267.755878) (xy 130.406139 -267.781845) (xy 130.686049 -267.781845)
			(xy 130.686049 -267.729911) (xy 130.694174 -267.678616) (xy 130.710222 -267.629223) (xy 130.7338 -267.582949)
			(xy 130.764326 -267.540933) (xy 130.801049 -267.50421) (xy 130.843065 -267.473684) (xy 130.889339 -267.450106)
			(xy 130.938732 -267.434058) (xy 130.990027 -267.425933) (xy 131.041961 -267.425933) (xy 131.093256 -267.434058)
			(xy 131.142649 -267.450106) (xy 131.188923 -267.473684) (xy 131.230939 -267.50421) (xy 131.267662 -267.540933)
			(xy 131.298188 -267.582949) (xy 131.321766 -267.629223) (xy 131.337814 -267.678616) (xy 131.345939 -267.729911)
			(xy 131.346448 -267.755878) (xy 131.345939 -267.781845) (xy 131.337814 -267.83314) (xy 131.321766 -267.882533)
			(xy 131.298188 -267.928807) (xy 131.267662 -267.970823) (xy 131.230939 -268.007546) (xy 131.188923 -268.038072)
			(xy 131.142649 -268.06165) (xy 131.093256 -268.077698) (xy 131.041961 -268.085823) (xy 130.990027 -268.085823)
			(xy 130.938732 -268.077698) (xy 130.889339 -268.06165) (xy 130.843065 -268.038072) (xy 130.801049 -268.007546)
			(xy 130.764326 -267.970823) (xy 130.7338 -267.928807) (xy 130.710222 -267.882533) (xy 130.694174 -267.83314)
			(xy 130.686049 -267.781845) (xy 130.406139 -267.781845) (xy 130.398014 -267.83314) (xy 130.381966 -267.882533)
			(xy 130.358388 -267.928807) (xy 130.327862 -267.970823) (xy 130.291139 -268.007546) (xy 130.249123 -268.038072)
			(xy 130.202849 -268.06165) (xy 130.153456 -268.077698) (xy 130.102161 -268.085823) (xy 130.050227 -268.085823)
			(xy 129.998932 -268.077698) (xy 129.949539 -268.06165) (xy 129.903265 -268.038072) (xy 129.861249 -268.007546)
			(xy 129.824526 -267.970823) (xy 129.794 -267.928807) (xy 129.770422 -267.882533) (xy 129.754374 -267.83314)
			(xy 129.746249 -267.781845) (xy 129.466339 -267.781845) (xy 129.458214 -267.83314) (xy 129.442166 -267.882533)
			(xy 129.418588 -267.928807) (xy 129.388062 -267.970823) (xy 129.351339 -268.007546) (xy 129.309323 -268.038072)
			(xy 129.263049 -268.06165) (xy 129.213656 -268.077698) (xy 129.162361 -268.085823) (xy 129.110427 -268.085823)
			(xy 129.059132 -268.077698) (xy 129.009739 -268.06165) (xy 128.963465 -268.038072) (xy 128.921449 -268.007546)
			(xy 128.884726 -267.970823) (xy 128.8542 -267.928807) (xy 128.830622 -267.882533) (xy 128.814574 -267.83314)
			(xy 128.806449 -267.781845) (xy 128.526539 -267.781845) (xy 128.518414 -267.83314) (xy 128.502366 -267.882533)
			(xy 128.478788 -267.928807) (xy 128.448262 -267.970823) (xy 128.411539 -268.007546) (xy 128.369523 -268.038072)
			(xy 128.323249 -268.06165) (xy 128.273856 -268.077698) (xy 128.222561 -268.085823) (xy 128.170627 -268.085823)
			(xy 128.119332 -268.077698) (xy 128.069939 -268.06165) (xy 128.023665 -268.038072) (xy 127.981649 -268.007546)
			(xy 127.944926 -267.970823) (xy 127.9144 -267.928807) (xy 127.890822 -267.882533) (xy 127.874774 -267.83314)
			(xy 127.866649 -267.781845) (xy 127.586739 -267.781845) (xy 127.578614 -267.83314) (xy 127.562566 -267.882533)
			(xy 127.538988 -267.928807) (xy 127.508462 -267.970823) (xy 127.471739 -268.007546) (xy 127.429723 -268.038072)
			(xy 127.383449 -268.06165) (xy 127.334056 -268.077698) (xy 127.282761 -268.085823) (xy 127.230827 -268.085823)
			(xy 127.179532 -268.077698) (xy 127.130139 -268.06165) (xy 127.083865 -268.038072) (xy 127.041849 -268.007546)
			(xy 127.005126 -267.970823) (xy 126.9746 -267.928807) (xy 126.951022 -267.882533) (xy 126.934974 -267.83314)
			(xy 126.926849 -267.781845) (xy 126.646939 -267.781845) (xy 126.638814 -267.83314) (xy 126.622766 -267.882533)
			(xy 126.599188 -267.928807) (xy 126.568662 -267.970823) (xy 126.531939 -268.007546) (xy 126.489923 -268.038072)
			(xy 126.443649 -268.06165) (xy 126.394256 -268.077698) (xy 126.342961 -268.085823) (xy 126.291027 -268.085823)
			(xy 126.239732 -268.077698) (xy 126.190339 -268.06165) (xy 126.144065 -268.038072) (xy 126.102049 -268.007546)
			(xy 126.065326 -267.970823) (xy 126.0348 -267.928807) (xy 126.011222 -267.882533) (xy 125.995174 -267.83314)
			(xy 125.987049 -267.781845) (xy 125.707139 -267.781845) (xy 125.699014 -267.83314) (xy 125.682966 -267.882533)
			(xy 125.659388 -267.928807) (xy 125.628862 -267.970823) (xy 125.592139 -268.007546) (xy 125.550123 -268.038072)
			(xy 125.503849 -268.06165) (xy 125.454456 -268.077698) (xy 125.403161 -268.085823) (xy 125.351227 -268.085823)
			(xy 125.299932 -268.077698) (xy 125.250539 -268.06165) (xy 125.204265 -268.038072) (xy 125.162249 -268.007546)
			(xy 125.125526 -267.970823) (xy 125.095 -267.928807) (xy 125.071422 -267.882533) (xy 125.055374 -267.83314)
			(xy 125.047249 -267.781845) (xy 124.767349 -267.781845) (xy 124.767349 -267.781868) (xy 124.759225 -267.833164)
			(xy 124.743175 -267.882558) (xy 124.719597 -267.928833) (xy 124.689069 -267.97085) (xy 124.652345 -268.007573)
			(xy 124.610328 -268.0381) (xy 124.564052 -268.061678) (xy 124.514658 -268.077726) (xy 124.463362 -268.08585)
			(xy 124.437394 -268.086332) (xy 124.424948 -268.086078) (xy 124.411277 -268.08597) (xy 124.384663 -268.092184)
			(xy 124.360648 -268.10523) (xy 124.340949 -268.124175) (xy 124.326976 -268.147662) (xy 124.319727 -268.174013)
			(xy 124.319284 -268.187678) (xy 124.319284 -268.595661) (xy 124.577603 -268.595661) (xy 124.577603 -268.543727)
			(xy 124.585728 -268.492432) (xy 124.601776 -268.443039) (xy 124.625354 -268.396765) (xy 124.65588 -268.354749)
			(xy 124.692603 -268.318026) (xy 124.734619 -268.2875) (xy 124.780893 -268.263922) (xy 124.830286 -268.247874)
			(xy 124.881581 -268.239749) (xy 124.933515 -268.239749) (xy 124.98481 -268.247874) (xy 125.034203 -268.263922)
			(xy 125.080477 -268.2875) (xy 125.122493 -268.318026) (xy 125.159216 -268.354749) (xy 125.189742 -268.396765)
			(xy 125.21332 -268.443039) (xy 125.229368 -268.492432) (xy 125.237493 -268.543727) (xy 125.238002 -268.569694)
			(xy 125.237493 -268.595661) (xy 125.517403 -268.595661) (xy 125.517403 -268.543727) (xy 125.525528 -268.492432)
			(xy 125.541576 -268.443039) (xy 125.565154 -268.396765) (xy 125.59568 -268.354749) (xy 125.632403 -268.318026)
			(xy 125.674419 -268.2875) (xy 125.720693 -268.263922) (xy 125.770086 -268.247874) (xy 125.821381 -268.239749)
			(xy 125.873315 -268.239749) (xy 125.92461 -268.247874) (xy 125.974003 -268.263922) (xy 126.020277 -268.2875)
			(xy 126.062293 -268.318026) (xy 126.099016 -268.354749) (xy 126.129542 -268.396765) (xy 126.15312 -268.443039)
			(xy 126.169168 -268.492432) (xy 126.177293 -268.543727) (xy 126.177802 -268.569694) (xy 126.177293 -268.595661)
			(xy 126.457203 -268.595661) (xy 126.457203 -268.543727) (xy 126.465328 -268.492432) (xy 126.481376 -268.443039)
			(xy 126.504954 -268.396765) (xy 126.53548 -268.354749) (xy 126.572203 -268.318026) (xy 126.614219 -268.2875)
			(xy 126.660493 -268.263922) (xy 126.709886 -268.247874) (xy 126.761181 -268.239749) (xy 126.813115 -268.239749)
			(xy 126.86441 -268.247874) (xy 126.913803 -268.263922) (xy 126.960077 -268.2875) (xy 127.002093 -268.318026)
			(xy 127.038816 -268.354749) (xy 127.069342 -268.396765) (xy 127.09292 -268.443039) (xy 127.108968 -268.492432)
			(xy 127.117093 -268.543727) (xy 127.117602 -268.569694) (xy 127.117093 -268.595661) (xy 127.397003 -268.595661)
			(xy 127.397003 -268.543727) (xy 127.405128 -268.492432) (xy 127.421176 -268.443039) (xy 127.444754 -268.396765)
			(xy 127.47528 -268.354749) (xy 127.512003 -268.318026) (xy 127.554019 -268.2875) (xy 127.600293 -268.263922)
			(xy 127.649686 -268.247874) (xy 127.700981 -268.239749) (xy 127.752915 -268.239749) (xy 127.80421 -268.247874)
			(xy 127.853603 -268.263922) (xy 127.899877 -268.2875) (xy 127.941893 -268.318026) (xy 127.978616 -268.354749)
			(xy 128.009142 -268.396765) (xy 128.03272 -268.443039) (xy 128.048768 -268.492432) (xy 128.056893 -268.543727)
			(xy 128.057402 -268.569694) (xy 128.056893 -268.595661) (xy 128.336803 -268.595661) (xy 128.336803 -268.543727)
			(xy 128.344928 -268.492432) (xy 128.360976 -268.443039) (xy 128.384554 -268.396765) (xy 128.41508 -268.354749)
			(xy 128.451803 -268.318026) (xy 128.493819 -268.2875) (xy 128.540093 -268.263922) (xy 128.589486 -268.247874)
			(xy 128.640781 -268.239749) (xy 128.692715 -268.239749) (xy 128.74401 -268.247874) (xy 128.793403 -268.263922)
			(xy 128.839677 -268.2875) (xy 128.881693 -268.318026) (xy 128.918416 -268.354749) (xy 128.948942 -268.396765)
			(xy 128.97252 -268.443039) (xy 128.988568 -268.492432) (xy 128.996693 -268.543727) (xy 128.997202 -268.569694)
			(xy 128.996693 -268.595661) (xy 129.276603 -268.595661) (xy 129.276603 -268.543727) (xy 129.284728 -268.492432)
			(xy 129.300776 -268.443039) (xy 129.324354 -268.396765) (xy 129.35488 -268.354749) (xy 129.391603 -268.318026)
			(xy 129.433619 -268.2875) (xy 129.479893 -268.263922) (xy 129.529286 -268.247874) (xy 129.580581 -268.239749)
			(xy 129.632515 -268.239749) (xy 129.68381 -268.247874) (xy 129.733203 -268.263922) (xy 129.779477 -268.2875)
			(xy 129.821493 -268.318026) (xy 129.858216 -268.354749) (xy 129.888742 -268.396765) (xy 129.91232 -268.443039)
			(xy 129.928368 -268.492432) (xy 129.936493 -268.543727) (xy 129.937002 -268.569694) (xy 129.936493 -268.595661)
			(xy 130.216403 -268.595661) (xy 130.216403 -268.543727) (xy 130.224528 -268.492432) (xy 130.240576 -268.443039)
			(xy 130.264154 -268.396765) (xy 130.29468 -268.354749) (xy 130.331403 -268.318026) (xy 130.373419 -268.2875)
			(xy 130.419693 -268.263922) (xy 130.469086 -268.247874) (xy 130.520381 -268.239749) (xy 130.572315 -268.239749)
			(xy 130.62361 -268.247874) (xy 130.673003 -268.263922) (xy 130.719277 -268.2875) (xy 130.761293 -268.318026)
			(xy 130.798016 -268.354749) (xy 130.828542 -268.396765) (xy 130.85212 -268.443039) (xy 130.868168 -268.492432)
			(xy 130.876293 -268.543727) (xy 130.876802 -268.569694) (xy 130.876293 -268.595661) (xy 130.868168 -268.646956)
			(xy 130.85212 -268.696349) (xy 130.828542 -268.742623) (xy 130.798016 -268.784639) (xy 130.761293 -268.821362)
			(xy 130.719277 -268.851888) (xy 130.673003 -268.875466) (xy 130.62361 -268.891514) (xy 130.572315 -268.899639)
			(xy 130.520381 -268.899639) (xy 130.469086 -268.891514) (xy 130.419693 -268.875466) (xy 130.373419 -268.851888)
			(xy 130.331403 -268.821362) (xy 130.29468 -268.784639) (xy 130.264154 -268.742623) (xy 130.240576 -268.696349)
			(xy 130.224528 -268.646956) (xy 130.216403 -268.595661) (xy 129.936493 -268.595661) (xy 129.928368 -268.646956)
			(xy 129.91232 -268.696349) (xy 129.888742 -268.742623) (xy 129.858216 -268.784639) (xy 129.821493 -268.821362)
			(xy 129.779477 -268.851888) (xy 129.733203 -268.875466) (xy 129.68381 -268.891514) (xy 129.632515 -268.899639)
			(xy 129.580581 -268.899639) (xy 129.529286 -268.891514) (xy 129.479893 -268.875466) (xy 129.433619 -268.851888)
			(xy 129.391603 -268.821362) (xy 129.35488 -268.784639) (xy 129.324354 -268.742623) (xy 129.300776 -268.696349)
			(xy 129.284728 -268.646956) (xy 129.276603 -268.595661) (xy 128.996693 -268.595661) (xy 128.988568 -268.646956)
			(xy 128.97252 -268.696349) (xy 128.948942 -268.742623) (xy 128.918416 -268.784639) (xy 128.881693 -268.821362)
			(xy 128.839677 -268.851888) (xy 128.793403 -268.875466) (xy 128.74401 -268.891514) (xy 128.692715 -268.899639)
			(xy 128.640781 -268.899639) (xy 128.589486 -268.891514) (xy 128.540093 -268.875466) (xy 128.493819 -268.851888)
			(xy 128.451803 -268.821362) (xy 128.41508 -268.784639) (xy 128.384554 -268.742623) (xy 128.360976 -268.696349)
			(xy 128.344928 -268.646956) (xy 128.336803 -268.595661) (xy 128.056893 -268.595661) (xy 128.048768 -268.646956)
			(xy 128.03272 -268.696349) (xy 128.009142 -268.742623) (xy 127.978616 -268.784639) (xy 127.941893 -268.821362)
			(xy 127.899877 -268.851888) (xy 127.853603 -268.875466) (xy 127.80421 -268.891514) (xy 127.752915 -268.899639)
			(xy 127.700981 -268.899639) (xy 127.649686 -268.891514) (xy 127.600293 -268.875466) (xy 127.554019 -268.851888)
			(xy 127.512003 -268.821362) (xy 127.47528 -268.784639) (xy 127.444754 -268.742623) (xy 127.421176 -268.696349)
			(xy 127.405128 -268.646956) (xy 127.397003 -268.595661) (xy 127.117093 -268.595661) (xy 127.108968 -268.646956)
			(xy 127.09292 -268.696349) (xy 127.069342 -268.742623) (xy 127.038816 -268.784639) (xy 127.002093 -268.821362)
			(xy 126.960077 -268.851888) (xy 126.913803 -268.875466) (xy 126.86441 -268.891514) (xy 126.813115 -268.899639)
			(xy 126.761181 -268.899639) (xy 126.709886 -268.891514) (xy 126.660493 -268.875466) (xy 126.614219 -268.851888)
			(xy 126.572203 -268.821362) (xy 126.53548 -268.784639) (xy 126.504954 -268.742623) (xy 126.481376 -268.696349)
			(xy 126.465328 -268.646956) (xy 126.457203 -268.595661) (xy 126.177293 -268.595661) (xy 126.169168 -268.646956)
			(xy 126.15312 -268.696349) (xy 126.129542 -268.742623) (xy 126.099016 -268.784639) (xy 126.062293 -268.821362)
			(xy 126.020277 -268.851888) (xy 125.974003 -268.875466) (xy 125.92461 -268.891514) (xy 125.873315 -268.899639)
			(xy 125.821381 -268.899639) (xy 125.770086 -268.891514) (xy 125.720693 -268.875466) (xy 125.674419 -268.851888)
			(xy 125.632403 -268.821362) (xy 125.59568 -268.784639) (xy 125.565154 -268.742623) (xy 125.541576 -268.696349)
			(xy 125.525528 -268.646956) (xy 125.517403 -268.595661) (xy 125.237493 -268.595661) (xy 125.229368 -268.646956)
			(xy 125.21332 -268.696349) (xy 125.189742 -268.742623) (xy 125.159216 -268.784639) (xy 125.122493 -268.821362)
			(xy 125.080477 -268.851888) (xy 125.034203 -268.875466) (xy 124.98481 -268.891514) (xy 124.933515 -268.899639)
			(xy 124.881581 -268.899639) (xy 124.830286 -268.891514) (xy 124.780893 -268.875466) (xy 124.734619 -268.851888)
			(xy 124.692603 -268.821362) (xy 124.65588 -268.784639) (xy 124.625354 -268.742623) (xy 124.601776 -268.696349)
			(xy 124.585728 -268.646956) (xy 124.577603 -268.595661) (xy 124.319284 -268.595661) (xy 124.319284 -268.95171)
			(xy 124.319636 -268.965385) (xy 124.326875 -268.99176) (xy 124.340857 -269.015265) (xy 124.360579 -269.034214)
			(xy 124.384624 -269.047246) (xy 124.411266 -269.053426) (xy 124.424948 -269.05331) (xy 124.437394 -269.053056)
			(xy 124.463364 -269.053518) (xy 124.514666 -269.061643) (xy 124.564065 -269.077693) (xy 124.610344 -269.101273)
			(xy 124.652366 -269.131802) (xy 124.689094 -269.16853) (xy 124.719624 -269.21055) (xy 124.743205 -269.25683)
			(xy 124.759256 -269.306228) (xy 124.767381 -269.35753) (xy 124.767381 -269.40947) (xy 124.76738 -269.409477)
			(xy 125.047249 -269.409477) (xy 125.047249 -269.357543) (xy 125.055374 -269.306248) (xy 125.071422 -269.256855)
			(xy 125.095 -269.210581) (xy 125.125526 -269.168565) (xy 125.162249 -269.131842) (xy 125.204265 -269.101316)
			(xy 125.250539 -269.077738) (xy 125.299932 -269.06169) (xy 125.351227 -269.053565) (xy 125.403161 -269.053565)
			(xy 125.454456 -269.06169) (xy 125.503849 -269.077738) (xy 125.550123 -269.101316) (xy 125.592139 -269.131842)
			(xy 125.628862 -269.168565) (xy 125.659388 -269.210581) (xy 125.682966 -269.256855) (xy 125.699014 -269.306248)
			(xy 125.707139 -269.357543) (xy 125.707648 -269.38351) (xy 125.707139 -269.409477) (xy 125.987049 -269.409477)
			(xy 125.987049 -269.357543) (xy 125.995174 -269.306248) (xy 126.011222 -269.256855) (xy 126.0348 -269.210581)
			(xy 126.065326 -269.168565) (xy 126.102049 -269.131842) (xy 126.144065 -269.101316) (xy 126.190339 -269.077738)
			(xy 126.239732 -269.06169) (xy 126.291027 -269.053565) (xy 126.342961 -269.053565) (xy 126.394256 -269.06169)
			(xy 126.443649 -269.077738) (xy 126.489923 -269.101316) (xy 126.531939 -269.131842) (xy 126.568662 -269.168565)
			(xy 126.599188 -269.210581) (xy 126.622766 -269.256855) (xy 126.638814 -269.306248) (xy 126.646939 -269.357543)
			(xy 126.647448 -269.38351) (xy 126.646939 -269.409477) (xy 126.926849 -269.409477) (xy 126.926849 -269.357543)
			(xy 126.934974 -269.306248) (xy 126.951022 -269.256855) (xy 126.9746 -269.210581) (xy 127.005126 -269.168565)
			(xy 127.041849 -269.131842) (xy 127.083865 -269.101316) (xy 127.130139 -269.077738) (xy 127.179532 -269.06169)
			(xy 127.230827 -269.053565) (xy 127.282761 -269.053565) (xy 127.334056 -269.06169) (xy 127.383449 -269.077738)
			(xy 127.429723 -269.101316) (xy 127.471739 -269.131842) (xy 127.508462 -269.168565) (xy 127.538988 -269.210581)
			(xy 127.562566 -269.256855) (xy 127.578614 -269.306248) (xy 127.586739 -269.357543) (xy 127.587248 -269.38351)
			(xy 127.586739 -269.409477) (xy 127.866649 -269.409477) (xy 127.866649 -269.357543) (xy 127.874774 -269.306248)
			(xy 127.890822 -269.256855) (xy 127.9144 -269.210581) (xy 127.944926 -269.168565) (xy 127.981649 -269.131842)
			(xy 128.023665 -269.101316) (xy 128.069939 -269.077738) (xy 128.119332 -269.06169) (xy 128.170627 -269.053565)
			(xy 128.222561 -269.053565) (xy 128.273856 -269.06169) (xy 128.323249 -269.077738) (xy 128.369523 -269.101316)
			(xy 128.411539 -269.131842) (xy 128.448262 -269.168565) (xy 128.478788 -269.210581) (xy 128.502366 -269.256855)
			(xy 128.518414 -269.306248) (xy 128.526539 -269.357543) (xy 128.527048 -269.38351) (xy 128.526539 -269.409477)
			(xy 128.806449 -269.409477) (xy 128.806449 -269.357543) (xy 128.814574 -269.306248) (xy 128.830622 -269.256855)
			(xy 128.8542 -269.210581) (xy 128.884726 -269.168565) (xy 128.921449 -269.131842) (xy 128.963465 -269.101316)
			(xy 129.009739 -269.077738) (xy 129.059132 -269.06169) (xy 129.110427 -269.053565) (xy 129.162361 -269.053565)
			(xy 129.213656 -269.06169) (xy 129.263049 -269.077738) (xy 129.309323 -269.101316) (xy 129.351339 -269.131842)
			(xy 129.388062 -269.168565) (xy 129.418588 -269.210581) (xy 129.442166 -269.256855) (xy 129.458214 -269.306248)
			(xy 129.466339 -269.357543) (xy 129.466848 -269.38351) (xy 129.466339 -269.409477) (xy 129.746249 -269.409477)
			(xy 129.746249 -269.357543) (xy 129.754374 -269.306248) (xy 129.770422 -269.256855) (xy 129.794 -269.210581)
			(xy 129.824526 -269.168565) (xy 129.861249 -269.131842) (xy 129.903265 -269.101316) (xy 129.949539 -269.077738)
			(xy 129.998932 -269.06169) (xy 130.050227 -269.053565) (xy 130.102161 -269.053565) (xy 130.153456 -269.06169)
			(xy 130.202849 -269.077738) (xy 130.249123 -269.101316) (xy 130.291139 -269.131842) (xy 130.327862 -269.168565)
			(xy 130.358388 -269.210581) (xy 130.381966 -269.256855) (xy 130.398014 -269.306248) (xy 130.406139 -269.357543)
			(xy 130.406648 -269.38351) (xy 130.406139 -269.409477) (xy 130.686049 -269.409477) (xy 130.686049 -269.357543)
			(xy 130.694174 -269.306248) (xy 130.710222 -269.256855) (xy 130.7338 -269.210581) (xy 130.764326 -269.168565)
			(xy 130.801049 -269.131842) (xy 130.843065 -269.101316) (xy 130.889339 -269.077738) (xy 130.938732 -269.06169)
			(xy 130.990027 -269.053565) (xy 131.041961 -269.053565) (xy 131.093256 -269.06169) (xy 131.142649 -269.077738)
			(xy 131.188923 -269.101316) (xy 131.230939 -269.131842) (xy 131.267662 -269.168565) (xy 131.298188 -269.210581)
			(xy 131.321766 -269.256855) (xy 131.337814 -269.306248) (xy 131.345939 -269.357543) (xy 131.346448 -269.38351)
			(xy 131.345939 -269.409477) (xy 131.337814 -269.460772) (xy 131.321766 -269.510165) (xy 131.298188 -269.556439)
			(xy 131.267662 -269.598455) (xy 131.230939 -269.635178) (xy 131.188923 -269.665704) (xy 131.142649 -269.689282)
			(xy 131.093256 -269.70533) (xy 131.041961 -269.713455) (xy 130.990027 -269.713455) (xy 130.938732 -269.70533)
			(xy 130.889339 -269.689282) (xy 130.843065 -269.665704) (xy 130.801049 -269.635178) (xy 130.764326 -269.598455)
			(xy 130.7338 -269.556439) (xy 130.710222 -269.510165) (xy 130.694174 -269.460772) (xy 130.686049 -269.409477)
			(xy 130.406139 -269.409477) (xy 130.398014 -269.460772) (xy 130.381966 -269.510165) (xy 130.358388 -269.556439)
			(xy 130.327862 -269.598455) (xy 130.291139 -269.635178) (xy 130.249123 -269.665704) (xy 130.202849 -269.689282)
			(xy 130.153456 -269.70533) (xy 130.102161 -269.713455) (xy 130.050227 -269.713455) (xy 129.998932 -269.70533)
			(xy 129.949539 -269.689282) (xy 129.903265 -269.665704) (xy 129.861249 -269.635178) (xy 129.824526 -269.598455)
			(xy 129.794 -269.556439) (xy 129.770422 -269.510165) (xy 129.754374 -269.460772) (xy 129.746249 -269.409477)
			(xy 129.466339 -269.409477) (xy 129.458214 -269.460772) (xy 129.442166 -269.510165) (xy 129.418588 -269.556439)
			(xy 129.388062 -269.598455) (xy 129.351339 -269.635178) (xy 129.309323 -269.665704) (xy 129.263049 -269.689282)
			(xy 129.213656 -269.70533) (xy 129.162361 -269.713455) (xy 129.110427 -269.713455) (xy 129.059132 -269.70533)
			(xy 129.009739 -269.689282) (xy 128.963465 -269.665704) (xy 128.921449 -269.635178) (xy 128.884726 -269.598455)
			(xy 128.8542 -269.556439) (xy 128.830622 -269.510165) (xy 128.814574 -269.460772) (xy 128.806449 -269.409477)
			(xy 128.526539 -269.409477) (xy 128.518414 -269.460772) (xy 128.502366 -269.510165) (xy 128.478788 -269.556439)
			(xy 128.448262 -269.598455) (xy 128.411539 -269.635178) (xy 128.369523 -269.665704) (xy 128.323249 -269.689282)
			(xy 128.273856 -269.70533) (xy 128.222561 -269.713455) (xy 128.170627 -269.713455) (xy 128.119332 -269.70533)
			(xy 128.069939 -269.689282) (xy 128.023665 -269.665704) (xy 127.981649 -269.635178) (xy 127.944926 -269.598455)
			(xy 127.9144 -269.556439) (xy 127.890822 -269.510165) (xy 127.874774 -269.460772) (xy 127.866649 -269.409477)
			(xy 127.586739 -269.409477) (xy 127.578614 -269.460772) (xy 127.562566 -269.510165) (xy 127.538988 -269.556439)
			(xy 127.508462 -269.598455) (xy 127.471739 -269.635178) (xy 127.429723 -269.665704) (xy 127.383449 -269.689282)
			(xy 127.334056 -269.70533) (xy 127.282761 -269.713455) (xy 127.230827 -269.713455) (xy 127.179532 -269.70533)
			(xy 127.130139 -269.689282) (xy 127.083865 -269.665704) (xy 127.041849 -269.635178) (xy 127.005126 -269.598455)
			(xy 126.9746 -269.556439) (xy 126.951022 -269.510165) (xy 126.934974 -269.460772) (xy 126.926849 -269.409477)
			(xy 126.646939 -269.409477) (xy 126.638814 -269.460772) (xy 126.622766 -269.510165) (xy 126.599188 -269.556439)
			(xy 126.568662 -269.598455) (xy 126.531939 -269.635178) (xy 126.489923 -269.665704) (xy 126.443649 -269.689282)
			(xy 126.394256 -269.70533) (xy 126.342961 -269.713455) (xy 126.291027 -269.713455) (xy 126.239732 -269.70533)
			(xy 126.190339 -269.689282) (xy 126.144065 -269.665704) (xy 126.102049 -269.635178) (xy 126.065326 -269.598455)
			(xy 126.0348 -269.556439) (xy 126.011222 -269.510165) (xy 125.995174 -269.460772) (xy 125.987049 -269.409477)
			(xy 125.707139 -269.409477) (xy 125.699014 -269.460772) (xy 125.682966 -269.510165) (xy 125.659388 -269.556439)
			(xy 125.628862 -269.598455) (xy 125.592139 -269.635178) (xy 125.550123 -269.665704) (xy 125.503849 -269.689282)
			(xy 125.454456 -269.70533) (xy 125.403161 -269.713455) (xy 125.351227 -269.713455) (xy 125.299932 -269.70533)
			(xy 125.250539 -269.689282) (xy 125.204265 -269.665704) (xy 125.162249 -269.635178) (xy 125.125526 -269.598455)
			(xy 125.095 -269.556439) (xy 125.071422 -269.510165) (xy 125.055374 -269.460772) (xy 125.047249 -269.409477)
			(xy 124.76738 -269.409477) (xy 124.759256 -269.460772) (xy 124.743205 -269.51017) (xy 124.719624 -269.55645)
			(xy 124.689094 -269.59847) (xy 124.652366 -269.635198) (xy 124.610344 -269.665727) (xy 124.564065 -269.689307)
			(xy 124.514666 -269.705357) (xy 124.463364 -269.713482) (xy 124.437394 -269.713964) (xy 124.424948 -269.71371)
			(xy 124.41128 -269.713669) (xy 124.384677 -269.719879) (xy 124.36067 -269.732914) (xy 124.340973 -269.751844)
			(xy 124.326995 -269.775316) (xy 124.319735 -269.801651) (xy 124.319284 -269.81531) (xy 124.319284 -270.223547)
			(xy 124.577603 -270.223547) (xy 124.577603 -270.171613) (xy 124.585728 -270.120318) (xy 124.601776 -270.070925)
			(xy 124.625354 -270.024651) (xy 124.65588 -269.982635) (xy 124.692603 -269.945912) (xy 124.734619 -269.915386)
			(xy 124.780893 -269.891808) (xy 124.830286 -269.87576) (xy 124.881581 -269.867635) (xy 124.933515 -269.867635)
			(xy 124.98481 -269.87576) (xy 125.034203 -269.891808) (xy 125.080477 -269.915386) (xy 125.122493 -269.945912)
			(xy 125.159216 -269.982635) (xy 125.189742 -270.024651) (xy 125.21332 -270.070925) (xy 125.229368 -270.120318)
			(xy 125.237493 -270.171613) (xy 125.238002 -270.19758) (xy 125.237493 -270.223547) (xy 125.517403 -270.223547)
			(xy 125.517403 -270.171613) (xy 125.525528 -270.120318) (xy 125.541576 -270.070925) (xy 125.565154 -270.024651)
			(xy 125.59568 -269.982635) (xy 125.632403 -269.945912) (xy 125.674419 -269.915386) (xy 125.720693 -269.891808)
			(xy 125.770086 -269.87576) (xy 125.821381 -269.867635) (xy 125.873315 -269.867635) (xy 125.92461 -269.87576)
			(xy 125.974003 -269.891808) (xy 126.020277 -269.915386) (xy 126.062293 -269.945912) (xy 126.099016 -269.982635)
			(xy 126.129542 -270.024651) (xy 126.15312 -270.070925) (xy 126.169168 -270.120318) (xy 126.177293 -270.171613)
			(xy 126.177802 -270.19758) (xy 126.177293 -270.223547) (xy 126.457203 -270.223547) (xy 126.457203 -270.171613)
			(xy 126.465328 -270.120318) (xy 126.481376 -270.070925) (xy 126.504954 -270.024651) (xy 126.53548 -269.982635)
			(xy 126.572203 -269.945912) (xy 126.614219 -269.915386) (xy 126.660493 -269.891808) (xy 126.709886 -269.87576)
			(xy 126.761181 -269.867635) (xy 126.813115 -269.867635) (xy 126.86441 -269.87576) (xy 126.913803 -269.891808)
			(xy 126.960077 -269.915386) (xy 127.002093 -269.945912) (xy 127.038816 -269.982635) (xy 127.069342 -270.024651)
			(xy 127.09292 -270.070925) (xy 127.108968 -270.120318) (xy 127.117093 -270.171613) (xy 127.117602 -270.19758)
			(xy 127.117093 -270.223547) (xy 127.397003 -270.223547) (xy 127.397003 -270.171613) (xy 127.405128 -270.120318)
			(xy 127.421176 -270.070925) (xy 127.444754 -270.024651) (xy 127.47528 -269.982635) (xy 127.512003 -269.945912)
			(xy 127.554019 -269.915386) (xy 127.600293 -269.891808) (xy 127.649686 -269.87576) (xy 127.700981 -269.867635)
			(xy 127.752915 -269.867635) (xy 127.80421 -269.87576) (xy 127.853603 -269.891808) (xy 127.899877 -269.915386)
			(xy 127.941893 -269.945912) (xy 127.978616 -269.982635) (xy 128.009142 -270.024651) (xy 128.03272 -270.070925)
			(xy 128.048768 -270.120318) (xy 128.056893 -270.171613) (xy 128.057402 -270.19758) (xy 128.056893 -270.223547)
			(xy 128.336803 -270.223547) (xy 128.336803 -270.171613) (xy 128.344928 -270.120318) (xy 128.360976 -270.070925)
			(xy 128.384554 -270.024651) (xy 128.41508 -269.982635) (xy 128.451803 -269.945912) (xy 128.493819 -269.915386)
			(xy 128.540093 -269.891808) (xy 128.589486 -269.87576) (xy 128.640781 -269.867635) (xy 128.692715 -269.867635)
			(xy 128.74401 -269.87576) (xy 128.793403 -269.891808) (xy 128.839677 -269.915386) (xy 128.881693 -269.945912)
			(xy 128.918416 -269.982635) (xy 128.948942 -270.024651) (xy 128.97252 -270.070925) (xy 128.988568 -270.120318)
			(xy 128.996693 -270.171613) (xy 128.997202 -270.19758) (xy 128.996693 -270.223547) (xy 129.276603 -270.223547)
			(xy 129.276603 -270.171613) (xy 129.284728 -270.120318) (xy 129.300776 -270.070925) (xy 129.324354 -270.024651)
			(xy 129.35488 -269.982635) (xy 129.391603 -269.945912) (xy 129.433619 -269.915386) (xy 129.479893 -269.891808)
			(xy 129.529286 -269.87576) (xy 129.580581 -269.867635) (xy 129.632515 -269.867635) (xy 129.68381 -269.87576)
			(xy 129.733203 -269.891808) (xy 129.779477 -269.915386) (xy 129.821493 -269.945912) (xy 129.858216 -269.982635)
			(xy 129.888742 -270.024651) (xy 129.91232 -270.070925) (xy 129.928368 -270.120318) (xy 129.936493 -270.171613)
			(xy 129.937002 -270.19758) (xy 129.936493 -270.223547) (xy 130.216403 -270.223547) (xy 130.216403 -270.171613)
			(xy 130.224528 -270.120318) (xy 130.240576 -270.070925) (xy 130.264154 -270.024651) (xy 130.29468 -269.982635)
			(xy 130.331403 -269.945912) (xy 130.373419 -269.915386) (xy 130.419693 -269.891808) (xy 130.469086 -269.87576)
			(xy 130.520381 -269.867635) (xy 130.572315 -269.867635) (xy 130.62361 -269.87576) (xy 130.673003 -269.891808)
			(xy 130.719277 -269.915386) (xy 130.761293 -269.945912) (xy 130.798016 -269.982635) (xy 130.828542 -270.024651)
			(xy 130.85212 -270.070925) (xy 130.868168 -270.120318) (xy 130.876293 -270.171613) (xy 130.876802 -270.19758)
			(xy 130.876293 -270.223547) (xy 130.868168 -270.274842) (xy 130.85212 -270.324235) (xy 130.828542 -270.370509)
			(xy 130.798016 -270.412525) (xy 130.761293 -270.449248) (xy 130.719277 -270.479774) (xy 130.673003 -270.503352)
			(xy 130.62361 -270.5194) (xy 130.572315 -270.527525) (xy 130.520381 -270.527525) (xy 130.469086 -270.5194)
			(xy 130.419693 -270.503352) (xy 130.373419 -270.479774) (xy 130.331403 -270.449248) (xy 130.29468 -270.412525)
			(xy 130.264154 -270.370509) (xy 130.240576 -270.324235) (xy 130.224528 -270.274842) (xy 130.216403 -270.223547)
			(xy 129.936493 -270.223547) (xy 129.928368 -270.274842) (xy 129.91232 -270.324235) (xy 129.888742 -270.370509)
			(xy 129.858216 -270.412525) (xy 129.821493 -270.449248) (xy 129.779477 -270.479774) (xy 129.733203 -270.503352)
			(xy 129.68381 -270.5194) (xy 129.632515 -270.527525) (xy 129.580581 -270.527525) (xy 129.529286 -270.5194)
			(xy 129.479893 -270.503352) (xy 129.433619 -270.479774) (xy 129.391603 -270.449248) (xy 129.35488 -270.412525)
			(xy 129.324354 -270.370509) (xy 129.300776 -270.324235) (xy 129.284728 -270.274842) (xy 129.276603 -270.223547)
			(xy 128.996693 -270.223547) (xy 128.988568 -270.274842) (xy 128.97252 -270.324235) (xy 128.948942 -270.370509)
			(xy 128.918416 -270.412525) (xy 128.881693 -270.449248) (xy 128.839677 -270.479774) (xy 128.793403 -270.503352)
			(xy 128.74401 -270.5194) (xy 128.692715 -270.527525) (xy 128.640781 -270.527525) (xy 128.589486 -270.5194)
			(xy 128.540093 -270.503352) (xy 128.493819 -270.479774) (xy 128.451803 -270.449248) (xy 128.41508 -270.412525)
			(xy 128.384554 -270.370509) (xy 128.360976 -270.324235) (xy 128.344928 -270.274842) (xy 128.336803 -270.223547)
			(xy 128.056893 -270.223547) (xy 128.048768 -270.274842) (xy 128.03272 -270.324235) (xy 128.009142 -270.370509)
			(xy 127.978616 -270.412525) (xy 127.941893 -270.449248) (xy 127.899877 -270.479774) (xy 127.853603 -270.503352)
			(xy 127.80421 -270.5194) (xy 127.752915 -270.527525) (xy 127.700981 -270.527525) (xy 127.649686 -270.5194)
			(xy 127.600293 -270.503352) (xy 127.554019 -270.479774) (xy 127.512003 -270.449248) (xy 127.47528 -270.412525)
			(xy 127.444754 -270.370509) (xy 127.421176 -270.324235) (xy 127.405128 -270.274842) (xy 127.397003 -270.223547)
			(xy 127.117093 -270.223547) (xy 127.108968 -270.274842) (xy 127.09292 -270.324235) (xy 127.069342 -270.370509)
			(xy 127.038816 -270.412525) (xy 127.002093 -270.449248) (xy 126.960077 -270.479774) (xy 126.913803 -270.503352)
			(xy 126.86441 -270.5194) (xy 126.813115 -270.527525) (xy 126.761181 -270.527525) (xy 126.709886 -270.5194)
			(xy 126.660493 -270.503352) (xy 126.614219 -270.479774) (xy 126.572203 -270.449248) (xy 126.53548 -270.412525)
			(xy 126.504954 -270.370509) (xy 126.481376 -270.324235) (xy 126.465328 -270.274842) (xy 126.457203 -270.223547)
			(xy 126.177293 -270.223547) (xy 126.169168 -270.274842) (xy 126.15312 -270.324235) (xy 126.129542 -270.370509)
			(xy 126.099016 -270.412525) (xy 126.062293 -270.449248) (xy 126.020277 -270.479774) (xy 125.974003 -270.503352)
			(xy 125.92461 -270.5194) (xy 125.873315 -270.527525) (xy 125.821381 -270.527525) (xy 125.770086 -270.5194)
			(xy 125.720693 -270.503352) (xy 125.674419 -270.479774) (xy 125.632403 -270.449248) (xy 125.59568 -270.412525)
			(xy 125.565154 -270.370509) (xy 125.541576 -270.324235) (xy 125.525528 -270.274842) (xy 125.517403 -270.223547)
			(xy 125.237493 -270.223547) (xy 125.229368 -270.274842) (xy 125.21332 -270.324235) (xy 125.189742 -270.370509)
			(xy 125.159216 -270.412525) (xy 125.122493 -270.449248) (xy 125.080477 -270.479774) (xy 125.034203 -270.503352)
			(xy 124.98481 -270.5194) (xy 124.933515 -270.527525) (xy 124.881581 -270.527525) (xy 124.830286 -270.5194)
			(xy 124.780893 -270.503352) (xy 124.734619 -270.479774) (xy 124.692603 -270.449248) (xy 124.65588 -270.412525)
			(xy 124.625354 -270.370509) (xy 124.601776 -270.324235) (xy 124.585728 -270.274842) (xy 124.577603 -270.223547)
			(xy 124.319284 -270.223547) (xy 124.319284 -270.51254) (xy 124.057918 -270.77416) (xy 123.90755 -270.77416)
			(xy 123.893844 -270.774689) (xy 123.867437 -270.782051) (xy 123.843942 -270.796175) (xy 123.825053 -270.816042)
			(xy 123.812133 -270.840221) (xy 123.806114 -270.866966) (xy 123.80743 -270.894348) (xy 123.811284 -270.90751)
			(xy 123.819106 -270.932766) (xy 123.827528 -270.984961) (xy 123.828048 -271.011396) (xy 123.827539 -271.037363)
			(xy 124.107449 -271.037363) (xy 124.107449 -270.985429) (xy 124.115574 -270.934134) (xy 124.131622 -270.884741)
			(xy 124.1552 -270.838467) (xy 124.185726 -270.796451) (xy 124.222449 -270.759728) (xy 124.264465 -270.729202)
			(xy 124.310739 -270.705624) (xy 124.360132 -270.689576) (xy 124.411427 -270.681451) (xy 124.463361 -270.681451)
			(xy 124.514656 -270.689576) (xy 124.564049 -270.705624) (xy 124.610323 -270.729202) (xy 124.652339 -270.759728)
			(xy 124.689062 -270.796451) (xy 124.719588 -270.838467) (xy 124.743166 -270.884741) (xy 124.759214 -270.934134)
			(xy 124.767339 -270.985429) (xy 124.767848 -271.011396) (xy 124.767339 -271.037363) (xy 125.047249 -271.037363)
			(xy 125.047249 -270.985429) (xy 125.055374 -270.934134) (xy 125.071422 -270.884741) (xy 125.095 -270.838467)
			(xy 125.125526 -270.796451) (xy 125.162249 -270.759728) (xy 125.204265 -270.729202) (xy 125.250539 -270.705624)
			(xy 125.299932 -270.689576) (xy 125.351227 -270.681451) (xy 125.403161 -270.681451) (xy 125.454456 -270.689576)
			(xy 125.503849 -270.705624) (xy 125.550123 -270.729202) (xy 125.592139 -270.759728) (xy 125.628862 -270.796451)
			(xy 125.659388 -270.838467) (xy 125.682966 -270.884741) (xy 125.699014 -270.934134) (xy 125.707139 -270.985429)
			(xy 125.707648 -271.011396) (xy 125.707139 -271.037363) (xy 125.987049 -271.037363) (xy 125.987049 -270.985429)
			(xy 125.995174 -270.934134) (xy 126.011222 -270.884741) (xy 126.0348 -270.838467) (xy 126.065326 -270.796451)
			(xy 126.102049 -270.759728) (xy 126.144065 -270.729202) (xy 126.190339 -270.705624) (xy 126.239732 -270.689576)
			(xy 126.291027 -270.681451) (xy 126.342961 -270.681451) (xy 126.394256 -270.689576) (xy 126.443649 -270.705624)
			(xy 126.489923 -270.729202) (xy 126.531939 -270.759728) (xy 126.568662 -270.796451) (xy 126.599188 -270.838467)
			(xy 126.622766 -270.884741) (xy 126.638814 -270.934134) (xy 126.646939 -270.985429) (xy 126.647448 -271.011396)
			(xy 126.646939 -271.037363) (xy 126.926849 -271.037363) (xy 126.926849 -270.985429) (xy 126.934974 -270.934134)
			(xy 126.951022 -270.884741) (xy 126.9746 -270.838467) (xy 127.005126 -270.796451) (xy 127.041849 -270.759728)
			(xy 127.083865 -270.729202) (xy 127.130139 -270.705624) (xy 127.179532 -270.689576) (xy 127.230827 -270.681451)
			(xy 127.282761 -270.681451) (xy 127.334056 -270.689576) (xy 127.383449 -270.705624) (xy 127.429723 -270.729202)
			(xy 127.471739 -270.759728) (xy 127.508462 -270.796451) (xy 127.538988 -270.838467) (xy 127.562566 -270.884741)
			(xy 127.578614 -270.934134) (xy 127.586739 -270.985429) (xy 127.587248 -271.011396) (xy 127.586739 -271.037363)
			(xy 127.866649 -271.037363) (xy 127.866649 -270.985429) (xy 127.874774 -270.934134) (xy 127.890822 -270.884741)
			(xy 127.9144 -270.838467) (xy 127.944926 -270.796451) (xy 127.981649 -270.759728) (xy 128.023665 -270.729202)
			(xy 128.069939 -270.705624) (xy 128.119332 -270.689576) (xy 128.170627 -270.681451) (xy 128.222561 -270.681451)
			(xy 128.273856 -270.689576) (xy 128.323249 -270.705624) (xy 128.369523 -270.729202) (xy 128.411539 -270.759728)
			(xy 128.448262 -270.796451) (xy 128.478788 -270.838467) (xy 128.502366 -270.884741) (xy 128.518414 -270.934134)
			(xy 128.526539 -270.985429) (xy 128.527048 -271.011396) (xy 128.526539 -271.037363) (xy 128.806449 -271.037363)
			(xy 128.806449 -270.985429) (xy 128.814574 -270.934134) (xy 128.830622 -270.884741) (xy 128.8542 -270.838467)
			(xy 128.884726 -270.796451) (xy 128.921449 -270.759728) (xy 128.963465 -270.729202) (xy 129.009739 -270.705624)
			(xy 129.059132 -270.689576) (xy 129.110427 -270.681451) (xy 129.162361 -270.681451) (xy 129.213656 -270.689576)
			(xy 129.263049 -270.705624) (xy 129.309323 -270.729202) (xy 129.351339 -270.759728) (xy 129.388062 -270.796451)
			(xy 129.418588 -270.838467) (xy 129.442166 -270.884741) (xy 129.458214 -270.934134) (xy 129.466339 -270.985429)
			(xy 129.466848 -271.011396) (xy 129.466339 -271.037363) (xy 129.746249 -271.037363) (xy 129.746249 -270.985429)
			(xy 129.754374 -270.934134) (xy 129.770422 -270.884741) (xy 129.794 -270.838467) (xy 129.824526 -270.796451)
			(xy 129.861249 -270.759728) (xy 129.903265 -270.729202) (xy 129.949539 -270.705624) (xy 129.998932 -270.689576)
			(xy 130.050227 -270.681451) (xy 130.102161 -270.681451) (xy 130.153456 -270.689576) (xy 130.202849 -270.705624)
			(xy 130.249123 -270.729202) (xy 130.291139 -270.759728) (xy 130.327862 -270.796451) (xy 130.358388 -270.838467)
			(xy 130.381966 -270.884741) (xy 130.398014 -270.934134) (xy 130.406139 -270.985429) (xy 130.406648 -271.011396)
			(xy 130.406139 -271.037363) (xy 130.686049 -271.037363) (xy 130.686049 -270.985429) (xy 130.694174 -270.934134)
			(xy 130.710222 -270.884741) (xy 130.7338 -270.838467) (xy 130.764326 -270.796451) (xy 130.801049 -270.759728)
			(xy 130.843065 -270.729202) (xy 130.889339 -270.705624) (xy 130.938732 -270.689576) (xy 130.990027 -270.681451)
			(xy 131.041961 -270.681451) (xy 131.093256 -270.689576) (xy 131.142649 -270.705624) (xy 131.188923 -270.729202)
			(xy 131.230939 -270.759728) (xy 131.267662 -270.796451) (xy 131.298188 -270.838467) (xy 131.321766 -270.884741)
			(xy 131.337814 -270.934134) (xy 131.345939 -270.985429) (xy 131.346448 -271.011396) (xy 131.345939 -271.037363)
			(xy 131.337814 -271.088658) (xy 131.321766 -271.138051) (xy 131.298188 -271.184325) (xy 131.267662 -271.226341)
			(xy 131.230939 -271.263064) (xy 131.188923 -271.29359) (xy 131.142649 -271.317168) (xy 131.093256 -271.333216)
			(xy 131.041961 -271.341341) (xy 130.990027 -271.341341) (xy 130.938732 -271.333216) (xy 130.889339 -271.317168)
			(xy 130.843065 -271.29359) (xy 130.801049 -271.263064) (xy 130.764326 -271.226341) (xy 130.7338 -271.184325)
			(xy 130.710222 -271.138051) (xy 130.694174 -271.088658) (xy 130.686049 -271.037363) (xy 130.406139 -271.037363)
			(xy 130.398014 -271.088658) (xy 130.381966 -271.138051) (xy 130.358388 -271.184325) (xy 130.327862 -271.226341)
			(xy 130.291139 -271.263064) (xy 130.249123 -271.29359) (xy 130.202849 -271.317168) (xy 130.153456 -271.333216)
			(xy 130.102161 -271.341341) (xy 130.050227 -271.341341) (xy 129.998932 -271.333216) (xy 129.949539 -271.317168)
			(xy 129.903265 -271.29359) (xy 129.861249 -271.263064) (xy 129.824526 -271.226341) (xy 129.794 -271.184325)
			(xy 129.770422 -271.138051) (xy 129.754374 -271.088658) (xy 129.746249 -271.037363) (xy 129.466339 -271.037363)
			(xy 129.458214 -271.088658) (xy 129.442166 -271.138051) (xy 129.418588 -271.184325) (xy 129.388062 -271.226341)
			(xy 129.351339 -271.263064) (xy 129.309323 -271.29359) (xy 129.263049 -271.317168) (xy 129.213656 -271.333216)
			(xy 129.162361 -271.341341) (xy 129.110427 -271.341341) (xy 129.059132 -271.333216) (xy 129.009739 -271.317168)
			(xy 128.963465 -271.29359) (xy 128.921449 -271.263064) (xy 128.884726 -271.226341) (xy 128.8542 -271.184325)
			(xy 128.830622 -271.138051) (xy 128.814574 -271.088658) (xy 128.806449 -271.037363) (xy 128.526539 -271.037363)
			(xy 128.518414 -271.088658) (xy 128.502366 -271.138051) (xy 128.478788 -271.184325) (xy 128.448262 -271.226341)
			(xy 128.411539 -271.263064) (xy 128.369523 -271.29359) (xy 128.323249 -271.317168) (xy 128.273856 -271.333216)
			(xy 128.222561 -271.341341) (xy 128.170627 -271.341341) (xy 128.119332 -271.333216) (xy 128.069939 -271.317168)
			(xy 128.023665 -271.29359) (xy 127.981649 -271.263064) (xy 127.944926 -271.226341) (xy 127.9144 -271.184325)
			(xy 127.890822 -271.138051) (xy 127.874774 -271.088658) (xy 127.866649 -271.037363) (xy 127.586739 -271.037363)
			(xy 127.578614 -271.088658) (xy 127.562566 -271.138051) (xy 127.538988 -271.184325) (xy 127.508462 -271.226341)
			(xy 127.471739 -271.263064) (xy 127.429723 -271.29359) (xy 127.383449 -271.317168) (xy 127.334056 -271.333216)
			(xy 127.282761 -271.341341) (xy 127.230827 -271.341341) (xy 127.179532 -271.333216) (xy 127.130139 -271.317168)
			(xy 127.083865 -271.29359) (xy 127.041849 -271.263064) (xy 127.005126 -271.226341) (xy 126.9746 -271.184325)
			(xy 126.951022 -271.138051) (xy 126.934974 -271.088658) (xy 126.926849 -271.037363) (xy 126.646939 -271.037363)
			(xy 126.638814 -271.088658) (xy 126.622766 -271.138051) (xy 126.599188 -271.184325) (xy 126.568662 -271.226341)
			(xy 126.531939 -271.263064) (xy 126.489923 -271.29359) (xy 126.443649 -271.317168) (xy 126.394256 -271.333216)
			(xy 126.342961 -271.341341) (xy 126.291027 -271.341341) (xy 126.239732 -271.333216) (xy 126.190339 -271.317168)
			(xy 126.144065 -271.29359) (xy 126.102049 -271.263064) (xy 126.065326 -271.226341) (xy 126.0348 -271.184325)
			(xy 126.011222 -271.138051) (xy 125.995174 -271.088658) (xy 125.987049 -271.037363) (xy 125.707139 -271.037363)
			(xy 125.699014 -271.088658) (xy 125.682966 -271.138051) (xy 125.659388 -271.184325) (xy 125.628862 -271.226341)
			(xy 125.592139 -271.263064) (xy 125.550123 -271.29359) (xy 125.503849 -271.317168) (xy 125.454456 -271.333216)
			(xy 125.403161 -271.341341) (xy 125.351227 -271.341341) (xy 125.299932 -271.333216) (xy 125.250539 -271.317168)
			(xy 125.204265 -271.29359) (xy 125.162249 -271.263064) (xy 125.125526 -271.226341) (xy 125.095 -271.184325)
			(xy 125.071422 -271.138051) (xy 125.055374 -271.088658) (xy 125.047249 -271.037363) (xy 124.767339 -271.037363)
			(xy 124.759214 -271.088658) (xy 124.743166 -271.138051) (xy 124.719588 -271.184325) (xy 124.689062 -271.226341)
			(xy 124.652339 -271.263064) (xy 124.610323 -271.29359) (xy 124.564049 -271.317168) (xy 124.514656 -271.333216)
			(xy 124.463361 -271.341341) (xy 124.411427 -271.341341) (xy 124.360132 -271.333216) (xy 124.310739 -271.317168)
			(xy 124.264465 -271.29359) (xy 124.222449 -271.263064) (xy 124.185726 -271.226341) (xy 124.1552 -271.184325)
			(xy 124.131622 -271.138051) (xy 124.115574 -271.088658) (xy 124.107449 -271.037363) (xy 123.827539 -271.037363)
			(xy 123.819414 -271.088658) (xy 123.803366 -271.138051) (xy 123.779788 -271.184325) (xy 123.749262 -271.226341)
			(xy 123.712539 -271.263064) (xy 123.670523 -271.29359) (xy 123.624249 -271.317168) (xy 123.574856 -271.333216)
			(xy 123.523561 -271.341341) (xy 123.471627 -271.341341) (xy 123.420332 -271.333216) (xy 123.370939 -271.317168)
			(xy 123.324665 -271.29359) (xy 123.282649 -271.263064) (xy 123.245926 -271.226341) (xy 123.2154 -271.184325)
			(xy 123.191822 -271.138051) (xy 123.175774 -271.088658) (xy 123.167649 -271.037363) (xy 123.16714 -271.011396)
			(xy 123.16765 -270.984961) (xy 123.176079 -270.932766) (xy 123.183904 -270.90751) (xy 123.187818 -270.89436)
			(xy 123.189135 -270.866962) (xy 123.183113 -270.840202) (xy 123.170185 -270.81601) (xy 123.151284 -270.796132)
			(xy 123.127774 -270.782002) (xy 123.101352 -270.774639) (xy 123.087638 -270.77416) (xy 122.968004 -270.77416)
			(xy 122.9543 -270.774734) (xy 122.927893 -270.782082) (xy 122.904396 -270.796197) (xy 122.885505 -270.816057)
			(xy 122.872584 -270.840231) (xy 122.866565 -270.866972) (xy 122.867883 -270.894351) (xy 122.871738 -270.90751)
			(xy 122.879559 -270.932767) (xy 122.887981 -270.984961) (xy 122.888502 -271.011396) (xy 122.887993 -271.037363)
			(xy 122.879868 -271.088658) (xy 122.86382 -271.138051) (xy 122.840242 -271.184325) (xy 122.809716 -271.226341)
			(xy 122.772993 -271.263064) (xy 122.730977 -271.29359) (xy 122.684703 -271.317168) (xy 122.63531 -271.333216)
			(xy 122.584015 -271.341341) (xy 122.532081 -271.341341) (xy 122.480786 -271.333216) (xy 122.431393 -271.317168)
			(xy 122.385119 -271.29359) (xy 122.343103 -271.263064) (xy 122.30638 -271.226341) (xy 122.275854 -271.184325)
			(xy 122.252276 -271.138051) (xy 122.236228 -271.088658) (xy 122.228103 -271.037363) (xy 122.227594 -271.011396)
			(xy 122.228101 -270.98496) (xy 122.236531 -270.932766) (xy 122.244358 -270.90751) (xy 122.24822 -270.894348)
			(xy 122.249535 -270.86696) (xy 122.243516 -270.84021) (xy 122.230596 -270.816025) (xy 122.211707 -270.79615)
			(xy 122.18821 -270.782017) (xy 122.1618 -270.774646) (xy 122.148092 -270.77416) (xy 122.02795 -270.77416)
			(xy 122.014244 -270.774689) (xy 121.987837 -270.782051) (xy 121.964342 -270.796175) (xy 121.945453 -270.816042)
			(xy 121.932533 -270.840221) (xy 121.926514 -270.866966) (xy 121.92783 -270.894348) (xy 121.931684 -270.90751)
			(xy 121.939506 -270.932766) (xy 121.947928 -270.984961) (xy 121.948448 -271.011396) (xy 121.947939 -271.037363)
			(xy 121.939814 -271.088658) (xy 121.923766 -271.138051) (xy 121.900188 -271.184325) (xy 121.869662 -271.226341)
			(xy 121.832939 -271.263064) (xy 121.790923 -271.29359) (xy 121.744649 -271.317168) (xy 121.695256 -271.333216)
			(xy 121.643961 -271.341341) (xy 121.592027 -271.341341) (xy 121.540732 -271.333216) (xy 121.491339 -271.317168)
			(xy 121.445065 -271.29359) (xy 121.403049 -271.263064) (xy 121.366326 -271.226341) (xy 121.3358 -271.184325)
			(xy 121.312222 -271.138051) (xy 121.296174 -271.088658) (xy 121.288049 -271.037363) (xy 121.28754 -271.011396)
			(xy 121.28805 -270.984961) (xy 121.296479 -270.932766) (xy 121.304304 -270.90751) (xy 121.308218 -270.89436)
			(xy 121.309535 -270.866962) (xy 121.303513 -270.840202) (xy 121.290585 -270.81601) (xy 121.271684 -270.796132)
			(xy 121.248174 -270.782002) (xy 121.221752 -270.774639) (xy 121.208038 -270.77416) (xy 121.08815 -270.77416)
			(xy 121.074444 -270.774689) (xy 121.048037 -270.782051) (xy 121.024542 -270.796175) (xy 121.005653 -270.816042)
			(xy 120.992733 -270.840221) (xy 120.986714 -270.866966) (xy 120.98803 -270.894348) (xy 120.991884 -270.90751)
			(xy 120.999706 -270.932766) (xy 121.008128 -270.984961) (xy 121.008648 -271.011396) (xy 121.008139 -271.037363)
			(xy 121.000014 -271.088658) (xy 120.983966 -271.138051) (xy 120.960388 -271.184325) (xy 120.929862 -271.226341)
			(xy 120.893139 -271.263064) (xy 120.851123 -271.29359) (xy 120.804849 -271.317168) (xy 120.755456 -271.333216)
			(xy 120.704161 -271.341341) (xy 120.652227 -271.341341) (xy 120.600932 -271.333216) (xy 120.551539 -271.317168)
			(xy 120.505265 -271.29359) (xy 120.463249 -271.263064) (xy 120.426526 -271.226341) (xy 120.396 -271.184325)
			(xy 120.372422 -271.138051) (xy 120.356374 -271.088658) (xy 120.348249 -271.037363) (xy 120.34774 -271.011396)
			(xy 120.34825 -270.984961) (xy 120.356679 -270.932766) (xy 120.364504 -270.90751) (xy 120.368418 -270.89436)
			(xy 120.369735 -270.866962) (xy 120.363713 -270.840202) (xy 120.350785 -270.81601) (xy 120.331884 -270.796132)
			(xy 120.308374 -270.782002) (xy 120.281952 -270.774639) (xy 120.268238 -270.77416) (xy 120.14835 -270.77416)
			(xy 120.134644 -270.774689) (xy 120.108237 -270.782051) (xy 120.084742 -270.796175) (xy 120.065853 -270.816042)
			(xy 120.052933 -270.840221) (xy 120.046914 -270.866966) (xy 120.04823 -270.894348) (xy 120.052084 -270.90751)
			(xy 120.059906 -270.932766) (xy 120.068328 -270.984961) (xy 120.068848 -271.011396) (xy 120.068339 -271.037363)
			(xy 120.060214 -271.088658) (xy 120.044166 -271.138051) (xy 120.020588 -271.184325) (xy 119.990062 -271.226341)
			(xy 119.953339 -271.263064) (xy 119.911323 -271.29359) (xy 119.865049 -271.317168) (xy 119.815656 -271.333216)
			(xy 119.764361 -271.341341) (xy 119.712427 -271.341341) (xy 119.661132 -271.333216) (xy 119.611739 -271.317168)
			(xy 119.565465 -271.29359) (xy 119.523449 -271.263064) (xy 119.486726 -271.226341) (xy 119.4562 -271.184325)
			(xy 119.432622 -271.138051) (xy 119.416574 -271.088658) (xy 119.408449 -271.037363) (xy 119.40794 -271.011396)
			(xy 119.40845 -270.984961) (xy 119.416879 -270.932766) (xy 119.424704 -270.90751) (xy 119.428618 -270.89436)
			(xy 119.429935 -270.866962) (xy 119.423913 -270.840202) (xy 119.410985 -270.81601) (xy 119.392084 -270.796132)
			(xy 119.368574 -270.782002) (xy 119.342152 -270.774639) (xy 119.328438 -270.77416) (xy 119.20855 -270.77416)
			(xy 119.194844 -270.774689) (xy 119.168437 -270.782051) (xy 119.144942 -270.796175) (xy 119.126053 -270.816042)
			(xy 119.113133 -270.840221) (xy 119.107114 -270.866966) (xy 119.10843 -270.894348) (xy 119.112284 -270.90751)
			(xy 119.120106 -270.932766) (xy 119.128528 -270.984961) (xy 119.129048 -271.011396) (xy 119.128539 -271.037363)
			(xy 119.120414 -271.088658) (xy 119.104366 -271.138051) (xy 119.080788 -271.184325) (xy 119.050262 -271.226341)
			(xy 119.013539 -271.263064) (xy 118.971523 -271.29359) (xy 118.925249 -271.317168) (xy 118.875856 -271.333216)
			(xy 118.824561 -271.341341) (xy 118.772627 -271.341341) (xy 118.721332 -271.333216) (xy 118.671939 -271.317168)
			(xy 118.625665 -271.29359) (xy 118.583649 -271.263064) (xy 118.546926 -271.226341) (xy 118.5164 -271.184325)
			(xy 118.492822 -271.138051) (xy 118.476774 -271.088658) (xy 118.468649 -271.037363) (xy 118.46814 -271.011396)
			(xy 118.46865 -270.984961) (xy 118.477079 -270.932766) (xy 118.484904 -270.90751) (xy 118.488818 -270.89436)
			(xy 118.490135 -270.866962) (xy 118.484113 -270.840202) (xy 118.471185 -270.81601) (xy 118.452284 -270.796132)
			(xy 118.428774 -270.782002) (xy 118.402352 -270.774639) (xy 118.388638 -270.77416) (xy 118.26875 -270.77416)
			(xy 118.255044 -270.774689) (xy 118.228637 -270.782051) (xy 118.205142 -270.796175) (xy 118.186253 -270.816042)
			(xy 118.173333 -270.840221) (xy 118.167314 -270.866966) (xy 118.16863 -270.894348) (xy 118.172484 -270.90751)
			(xy 118.180306 -270.932766) (xy 118.188728 -270.984961) (xy 118.189248 -271.011396) (xy 118.188739 -271.037363)
			(xy 118.180614 -271.088658) (xy 118.164566 -271.138051) (xy 118.140988 -271.184325) (xy 118.110462 -271.226341)
			(xy 118.073739 -271.263064) (xy 118.031723 -271.29359) (xy 117.985449 -271.317168) (xy 117.936056 -271.333216)
			(xy 117.884761 -271.341341) (xy 117.832827 -271.341341) (xy 117.781532 -271.333216) (xy 117.732139 -271.317168)
			(xy 117.685865 -271.29359) (xy 117.643849 -271.263064) (xy 117.607126 -271.226341) (xy 117.5766 -271.184325)
			(xy 117.553022 -271.138051) (xy 117.536974 -271.088658) (xy 117.528849 -271.037363) (xy 117.52834 -271.011396)
			(xy 117.52885 -270.984961) (xy 117.537279 -270.932766) (xy 117.545104 -270.90751) (xy 117.549018 -270.89436)
			(xy 117.550335 -270.866962) (xy 117.544313 -270.840202) (xy 117.531385 -270.81601) (xy 117.512484 -270.796132)
			(xy 117.488974 -270.782002) (xy 117.462552 -270.774639) (xy 117.448838 -270.77416) (xy 117.32895 -270.77416)
			(xy 117.315244 -270.774689) (xy 117.288837 -270.782051) (xy 117.265342 -270.796175) (xy 117.246453 -270.816042)
			(xy 117.233533 -270.840221) (xy 117.227514 -270.866966) (xy 117.22883 -270.894348) (xy 117.232684 -270.90751)
			(xy 117.240506 -270.932766) (xy 117.248928 -270.984961) (xy 117.249448 -271.011396) (xy 117.248939 -271.037363)
			(xy 117.240814 -271.088658) (xy 117.224766 -271.138051) (xy 117.201188 -271.184325) (xy 117.170662 -271.226341)
			(xy 117.133939 -271.263064) (xy 117.091923 -271.29359) (xy 117.045649 -271.317168) (xy 116.996256 -271.333216)
			(xy 116.944961 -271.341341) (xy 116.893027 -271.341341) (xy 116.841732 -271.333216) (xy 116.792339 -271.317168)
			(xy 116.746065 -271.29359) (xy 116.704049 -271.263064) (xy 116.667326 -271.226341) (xy 116.6368 -271.184325)
			(xy 116.613222 -271.138051) (xy 116.597174 -271.088658) (xy 116.589049 -271.037363) (xy 116.58854 -271.011396)
			(xy 116.588977 -270.987859) (xy 116.595647 -270.94126) (xy 116.608864 -270.896079) (xy 116.628361 -270.853233)
			(xy 116.653743 -270.813588) (xy 116.668804 -270.795496) (xy 116.699538 -270.759682) (xy 116.468144 -270.528288)
			(xy 116.447062 -270.528034) (xy 116.421327 -270.52734) (xy 116.370527 -270.519012) (xy 116.321632 -270.502907)
			(xy 116.275828 -270.479413) (xy 116.234221 -270.4491) (xy 116.197819 -270.412701) (xy 116.167502 -270.371096)
			(xy 116.144004 -270.325294) (xy 116.127894 -270.276401) (xy 116.119562 -270.225601) (xy 116.118894 -270.199866)
			(xy 116.11864 -270.178784) (xy 115.478814 -269.538958) (xy 115.467631 -269.528504) (xy 115.440585 -269.514199)
			(xy 115.410516 -269.508547) (xy 115.380121 -269.512056) (xy 115.352131 -269.524413) (xy 115.329057 -269.544506)
			(xy 115.320572 -269.557246) (xy 115.307526 -269.577425) (xy 115.276616 -269.614211) (xy 115.240704 -269.646132)
			(xy 115.200547 -269.672516) (xy 115.156993 -269.692807) (xy 115.11096 -269.706576) (xy 115.063418 -269.713533)
			(xy 115.039394 -269.713964) (xy 115.013427 -269.71345) (xy 114.962133 -269.705325) (xy 114.912741 -269.689277)
			(xy 114.866468 -269.665699) (xy 114.824452 -269.635173) (xy 114.787729 -269.598451) (xy 114.757203 -269.556436)
			(xy 114.733625 -269.510163) (xy 114.717576 -269.460771) (xy 114.70945 -269.409477) (xy 114.70894 -269.38351)
			(xy 114.709346 -269.359485) (xy 114.716323 -269.311944) (xy 114.730103 -269.265913) (xy 114.750395 -269.222358)
			(xy 114.776774 -269.182196) (xy 114.808685 -269.146272) (xy 114.845455 -269.115341) (xy 114.865658 -269.102332)
			(xy 114.878411 -269.093861) (xy 114.898508 -269.070783) (xy 114.910867 -269.042787) (xy 114.914378 -269.012386)
			(xy 114.908726 -268.98231) (xy 114.894418 -268.955258) (xy 114.883946 -268.94409) (xy 114.772948 -268.833092)
			(xy 114.739166 -268.853412) (xy 114.713345 -268.868035) (xy 114.657794 -268.888882) (xy 114.599415 -268.89948)
			(xy 114.569748 -268.900148) (xy 114.54378 -268.899627) (xy 114.492482 -268.891509) (xy 114.443085 -268.875465)
			(xy 114.396807 -268.851891) (xy 114.354787 -268.821367) (xy 114.31806 -268.784645) (xy 114.287531 -268.742629)
			(xy 114.263951 -268.696354) (xy 114.247901 -268.646959) (xy 114.239776 -268.595662) (xy 114.239294 -268.569694)
			(xy 114.239965 -268.540027) (xy 114.250554 -268.481644) (xy 114.271391 -268.426089) (xy 114.28603 -268.400276)
			(xy 114.30635 -268.366494) (xy 114.01552 -268.075664) (xy 114.003328 -268.072108) (xy 113.979857 -268.064406)
			(xy 113.935278 -268.043134) (xy 113.894359 -268.015468) (xy 113.858009 -267.982025) (xy 113.827038 -267.943547)
			(xy 113.802133 -267.900891) (xy 113.78385 -267.855005) (xy 113.777776 -267.831062) (xy 113.774474 -267.816838)
			(xy 113.663222 -267.705586) (xy 113.652448 -267.695558) (xy 113.626642 -267.681447) (xy 113.597882 -267.675283)
			(xy 113.568559 -267.677578) (xy 113.541109 -267.688142) (xy 113.517812 -267.706096) (xy 113.500604 -267.72995)
			(xy 113.490915 -267.75772) (xy 113.48974 -267.772388) (xy 113.48802 -267.797473) (xy 113.477956 -267.846735)
			(xy 113.460541 -267.893902) (xy 113.436177 -267.937884) (xy 113.405427 -267.977664) (xy 113.369003 -268.012323)
			(xy 113.327745 -268.04106) (xy 113.282608 -268.063211) (xy 113.234635 -268.078263) (xy 113.184934 -268.085869)
			(xy 113.159794 -268.086332) (xy 113.133823 -268.085877) (xy 113.082522 -268.07775) (xy 113.033123 -268.061698)
			(xy 112.986844 -268.038116) (xy 112.944824 -268.007584) (xy 112.908098 -267.970854) (xy 112.87757 -267.928832)
			(xy 112.853991 -267.882551) (xy 112.837943 -267.833151) (xy 112.829821 -267.781849) (xy 112.82934 -267.755878)
			(xy 112.829835 -267.729068) (xy 112.83849 -267.676152) (xy 112.855568 -267.625325) (xy 112.880623 -267.577919)
			(xy 112.896396 -267.556234) (xy 112.904567 -267.544741) (xy 112.914771 -267.518461) (xy 112.917399 -267.490393)
			(xy 112.912251 -267.462675) (xy 112.89972 -267.437422) (xy 112.88076 -267.416559) (xy 112.856818 -267.401675)
			(xy 112.829719 -267.393906) (xy 112.815624 -267.39342) (xy 112.564418 -267.39342) (xy 112.550329 -267.39391)
			(xy 112.523243 -267.401688) (xy 112.499315 -267.416574) (xy 112.480367 -267.437435) (xy 112.467844 -267.46268)
			(xy 112.462698 -267.490387) (xy 112.465321 -267.518445) (xy 112.475515 -267.544717) (xy 112.483646 -267.556234)
			(xy 112.499402 -267.57793) (xy 112.524452 -267.625333) (xy 112.541527 -267.676157) (xy 112.55018 -267.72907)
			(xy 112.550702 -267.755878) (xy 112.550193 -267.781845) (xy 112.542068 -267.83314) (xy 112.52602 -267.882533)
			(xy 112.502442 -267.928807) (xy 112.471916 -267.970823) (xy 112.435193 -268.007546) (xy 112.393177 -268.038072)
			(xy 112.346903 -268.06165) (xy 112.29751 -268.077698) (xy 112.246215 -268.085823) (xy 112.194281 -268.085823)
			(xy 112.142986 -268.077698) (xy 112.093593 -268.06165) (xy 112.047319 -268.038072) (xy 112.005303 -268.007546)
			(xy 111.96858 -267.970823) (xy 111.938054 -267.928807) (xy 111.914476 -267.882533) (xy 111.898428 -267.83314)
			(xy 111.890303 -267.781845) (xy 111.889794 -267.755878) (xy 111.890299 -267.729069) (xy 111.898952 -267.676153)
			(xy 111.916028 -267.625326) (xy 111.941079 -267.57792) (xy 111.95685 -267.556234) (xy 111.965056 -267.544761)
			(xy 111.975267 -267.518475) (xy 111.977899 -267.490397) (xy 111.972749 -267.462671) (xy 111.960212 -267.437411)
			(xy 111.941242 -267.416544) (xy 111.917289 -267.401662) (xy 111.890177 -267.3939) (xy 111.876078 -267.39342)
			(xy 111.624618 -267.39342) (xy 111.610529 -267.39391) (xy 111.583443 -267.401688) (xy 111.559515 -267.416574)
			(xy 111.540567 -267.437435) (xy 111.528044 -267.46268) (xy 111.522898 -267.490387) (xy 111.525521 -267.518445)
			(xy 111.535715 -267.544717) (xy 111.543846 -267.556234) (xy 111.559602 -267.57793) (xy 111.584652 -267.625333)
			(xy 111.601727 -267.676157) (xy 111.61038 -267.72907) (xy 111.610902 -267.755878) (xy 111.610393 -267.781845)
			(xy 111.602268 -267.83314) (xy 111.58622 -267.882533) (xy 111.562642 -267.928807) (xy 111.532116 -267.970823)
			(xy 111.495393 -268.007546) (xy 111.453377 -268.038072) (xy 111.407103 -268.06165) (xy 111.35771 -268.077698)
			(xy 111.306415 -268.085823) (xy 111.254481 -268.085823) (xy 111.203186 -268.077698) (xy 111.153793 -268.06165)
			(xy 111.107519 -268.038072) (xy 111.065503 -268.007546) (xy 111.02878 -267.970823) (xy 110.998254 -267.928807)
			(xy 110.974676 -267.882533) (xy 110.958628 -267.83314) (xy 110.950503 -267.781845) (xy 110.949994 -267.755878)
			(xy 110.950499 -267.729069) (xy 110.959152 -267.676153) (xy 110.976228 -267.625326) (xy 111.001279 -267.57792)
			(xy 111.01705 -267.556234) (xy 111.025256 -267.544761) (xy 111.035467 -267.518475) (xy 111.038099 -267.490397)
			(xy 111.032949 -267.462671) (xy 111.020412 -267.437411) (xy 111.001442 -267.416544) (xy 110.977489 -267.401662)
			(xy 110.950377 -267.3939) (xy 110.936278 -267.39342) (xy 110.684564 -267.39342) (xy 110.670474 -267.393874)
			(xy 110.643391 -267.401664) (xy 110.619466 -267.416559) (xy 110.600523 -267.437424) (xy 110.588001 -267.462671)
			(xy 110.582855 -267.490379) (xy 110.585476 -267.518439) (xy 110.595664 -267.544715) (xy 110.603792 -267.556234)
			(xy 110.619554 -267.577925) (xy 110.644602 -267.625331) (xy 110.661675 -267.676156) (xy 110.670327 -267.72907)
			(xy 110.670848 -267.755878) (xy 110.670339 -267.781845) (xy 110.662214 -267.83314) (xy 110.646166 -267.882533)
			(xy 110.622588 -267.928807) (xy 110.592062 -267.970823) (xy 110.555339 -268.007546) (xy 110.513323 -268.038072)
			(xy 110.467049 -268.06165) (xy 110.417656 -268.077698) (xy 110.366361 -268.085823) (xy 110.314427 -268.085823)
			(xy 110.263132 -268.077698) (xy 110.213739 -268.06165) (xy 110.167465 -268.038072) (xy 110.125449 -268.007546)
			(xy 110.088726 -267.970823) (xy 110.0582 -267.928807) (xy 110.034622 -267.882533) (xy 110.018574 -267.83314)
			(xy 110.010449 -267.781845) (xy 110.00994 -267.755878) (xy 110.010435 -267.729068) (xy 110.01909 -267.676152)
			(xy 110.036168 -267.625325) (xy 110.061223 -267.577919) (xy 110.076996 -267.556234) (xy 110.085167 -267.544741)
			(xy 110.095371 -267.518461) (xy 110.097999 -267.490393) (xy 110.092851 -267.462675) (xy 110.08032 -267.437422)
			(xy 110.06136 -267.416559) (xy 110.037418 -267.401675) (xy 110.010319 -267.393906) (xy 109.996224 -267.39342)
			(xy 109.744764 -267.39342) (xy 109.730674 -267.393874) (xy 109.703591 -267.401664) (xy 109.679666 -267.416559)
			(xy 109.660723 -267.437424) (xy 109.648201 -267.462671) (xy 109.643055 -267.490379) (xy 109.645676 -267.518439)
			(xy 109.655864 -267.544715) (xy 109.663992 -267.556234) (xy 109.679754 -267.577925) (xy 109.704802 -267.625331)
			(xy 109.721875 -267.676156) (xy 109.730527 -267.72907) (xy 109.731048 -267.755878) (xy 109.730539 -267.781845)
			(xy 109.722414 -267.83314) (xy 109.706366 -267.882533) (xy 109.682788 -267.928807) (xy 109.652262 -267.970823)
			(xy 109.615539 -268.007546) (xy 109.573523 -268.038072) (xy 109.527249 -268.06165) (xy 109.477856 -268.077698)
			(xy 109.426561 -268.085823) (xy 109.374627 -268.085823) (xy 109.323332 -268.077698) (xy 109.273939 -268.06165)
			(xy 109.227665 -268.038072) (xy 109.185649 -268.007546) (xy 109.148926 -267.970823) (xy 109.1184 -267.928807)
			(xy 109.094822 -267.882533) (xy 109.078774 -267.83314) (xy 109.070649 -267.781845) (xy 109.07014 -267.755878)
			(xy 109.070635 -267.729068) (xy 109.07929 -267.676152) (xy 109.096368 -267.625325) (xy 109.121423 -267.577919)
			(xy 109.137196 -267.556234) (xy 109.145367 -267.544741) (xy 109.155571 -267.518461) (xy 109.158199 -267.490393)
			(xy 109.153051 -267.462675) (xy 109.14052 -267.437422) (xy 109.12156 -267.416559) (xy 109.097618 -267.401675)
			(xy 109.070519 -267.393906) (xy 109.056424 -267.39342) (xy 108.804964 -267.39342) (xy 108.790874 -267.393874)
			(xy 108.763791 -267.401664) (xy 108.739866 -267.416559) (xy 108.720923 -267.437424) (xy 108.708401 -267.462671)
			(xy 108.703255 -267.490379) (xy 108.705876 -267.518439) (xy 108.716064 -267.544715) (xy 108.724192 -267.556234)
			(xy 108.739954 -267.577925) (xy 108.765002 -267.625331) (xy 108.782075 -267.676156) (xy 108.790727 -267.72907)
			(xy 108.791248 -267.755878) (xy 108.790739 -267.781845) (xy 108.782614 -267.83314) (xy 108.766566 -267.882533)
			(xy 108.742988 -267.928807) (xy 108.712462 -267.970823) (xy 108.675739 -268.007546) (xy 108.633723 -268.038072)
			(xy 108.587449 -268.06165) (xy 108.538056 -268.077698) (xy 108.486761 -268.085823) (xy 108.434827 -268.085823)
			(xy 108.383532 -268.077698) (xy 108.334139 -268.06165) (xy 108.287865 -268.038072) (xy 108.245849 -268.007546)
			(xy 108.209126 -267.970823) (xy 108.1786 -267.928807) (xy 108.155022 -267.882533) (xy 108.138974 -267.83314)
			(xy 108.130849 -267.781845) (xy 108.13034 -267.755878) (xy 108.130835 -267.729068) (xy 108.13949 -267.676152)
			(xy 108.156568 -267.625325) (xy 108.181623 -267.577919) (xy 108.197396 -267.556234) (xy 108.205567 -267.544741)
			(xy 108.215771 -267.518461) (xy 108.218399 -267.490393) (xy 108.213251 -267.462675) (xy 108.20072 -267.437422)
			(xy 108.18176 -267.416559) (xy 108.157818 -267.401675) (xy 108.130719 -267.393906) (xy 108.116624 -267.39342)
			(xy 107.865164 -267.39342) (xy 107.851074 -267.393874) (xy 107.823991 -267.401664) (xy 107.800066 -267.416559)
			(xy 107.781123 -267.437424) (xy 107.768601 -267.462671) (xy 107.763455 -267.490379) (xy 107.766076 -267.518439)
			(xy 107.776264 -267.544715) (xy 107.784392 -267.556234) (xy 107.800154 -267.577925) (xy 107.825202 -267.625331)
			(xy 107.842275 -267.676156) (xy 107.850927 -267.72907) (xy 107.851448 -267.755878) (xy 107.850939 -267.781845)
			(xy 107.842814 -267.83314) (xy 107.826766 -267.882533) (xy 107.803188 -267.928807) (xy 107.772662 -267.970823)
			(xy 107.735939 -268.007546) (xy 107.693923 -268.038072) (xy 107.647649 -268.06165) (xy 107.598256 -268.077698)
			(xy 107.546961 -268.085823) (xy 107.495027 -268.085823) (xy 107.443732 -268.077698) (xy 107.394339 -268.06165)
			(xy 107.348065 -268.038072) (xy 107.306049 -268.007546) (xy 107.269326 -267.970823) (xy 107.2388 -267.928807)
			(xy 107.215222 -267.882533) (xy 107.199174 -267.83314) (xy 107.191049 -267.781845) (xy 107.19054 -267.755878)
			(xy 107.191035 -267.729068) (xy 107.19969 -267.676152) (xy 107.216768 -267.625325) (xy 107.241823 -267.577919)
			(xy 107.257596 -267.556234) (xy 107.265767 -267.544741) (xy 107.275971 -267.518461) (xy 107.278599 -267.490393)
			(xy 107.273451 -267.462675) (xy 107.26092 -267.437422) (xy 107.24196 -267.416559) (xy 107.218018 -267.401675)
			(xy 107.190919 -267.393906) (xy 107.176824 -267.39342) (xy 106.925364 -267.39342) (xy 106.911274 -267.393874)
			(xy 106.884191 -267.401664) (xy 106.860266 -267.416559) (xy 106.841323 -267.437424) (xy 106.828801 -267.462671)
			(xy 106.823655 -267.490379) (xy 106.826276 -267.518439) (xy 106.836464 -267.544715) (xy 106.844592 -267.556234)
			(xy 106.860354 -267.577925) (xy 106.885402 -267.625331) (xy 106.902475 -267.676156) (xy 106.911127 -267.72907)
			(xy 106.911648 -267.755878) (xy 106.911139 -267.781845) (xy 106.903014 -267.83314) (xy 106.886966 -267.882533)
			(xy 106.863388 -267.928807) (xy 106.832862 -267.970823) (xy 106.796139 -268.007546) (xy 106.754123 -268.038072)
			(xy 106.707849 -268.06165) (xy 106.658456 -268.077698) (xy 106.607161 -268.085823) (xy 106.555227 -268.085823)
			(xy 106.503932 -268.077698) (xy 106.454539 -268.06165) (xy 106.408265 -268.038072) (xy 106.366249 -268.007546)
			(xy 106.329526 -267.970823) (xy 106.299 -267.928807) (xy 106.275422 -267.882533) (xy 106.259374 -267.83314)
			(xy 106.251249 -267.781845) (xy 106.25074 -267.755878) (xy 106.251235 -267.729068) (xy 106.25989 -267.676152)
			(xy 106.276968 -267.625325) (xy 106.302023 -267.577919) (xy 106.317796 -267.556234) (xy 106.325967 -267.544741)
			(xy 106.336171 -267.518461) (xy 106.338799 -267.490393) (xy 106.333651 -267.462675) (xy 106.32112 -267.437422)
			(xy 106.30216 -267.416559) (xy 106.278218 -267.401675) (xy 106.251119 -267.393906) (xy 106.237024 -267.39342)
			(xy 105.985564 -267.39342) (xy 105.971474 -267.393874) (xy 105.944391 -267.401664) (xy 105.920466 -267.416559)
			(xy 105.901523 -267.437424) (xy 105.889001 -267.462671) (xy 105.883855 -267.490379) (xy 105.886476 -267.518439)
			(xy 105.896664 -267.544715) (xy 105.904792 -267.556234) (xy 105.920554 -267.577925) (xy 105.945602 -267.625331)
			(xy 105.962675 -267.676156) (xy 105.971327 -267.72907) (xy 105.971848 -267.755878) (xy 105.971339 -267.781845)
			(xy 105.963214 -267.83314) (xy 105.947166 -267.882533) (xy 105.923588 -267.928807) (xy 105.893062 -267.970823)
			(xy 105.856339 -268.007546) (xy 105.814323 -268.038072) (xy 105.768049 -268.06165) (xy 105.718656 -268.077698)
			(xy 105.667361 -268.085823) (xy 105.615427 -268.085823) (xy 105.564132 -268.077698) (xy 105.514739 -268.06165)
			(xy 105.468465 -268.038072) (xy 105.426449 -268.007546) (xy 105.389726 -267.970823) (xy 105.3592 -267.928807)
			(xy 105.335622 -267.882533) (xy 105.319574 -267.83314) (xy 105.311449 -267.781845) (xy 105.31094 -267.755878)
			(xy 105.311435 -267.729068) (xy 105.32009 -267.676152) (xy 105.337168 -267.625325) (xy 105.362223 -267.577919)
			(xy 105.377996 -267.556234) (xy 105.386167 -267.544741) (xy 105.396371 -267.518461) (xy 105.398999 -267.490393)
			(xy 105.393851 -267.462675) (xy 105.38132 -267.437422) (xy 105.36236 -267.416559) (xy 105.338418 -267.401675)
			(xy 105.311319 -267.393906) (xy 105.297224 -267.39342) (xy 105.045764 -267.39342) (xy 105.031674 -267.393874)
			(xy 105.004591 -267.401664) (xy 104.980666 -267.416559) (xy 104.961723 -267.437424) (xy 104.949201 -267.462671)
			(xy 104.944055 -267.490379) (xy 104.946676 -267.518439) (xy 104.956864 -267.544715) (xy 104.964992 -267.556234)
			(xy 104.980754 -267.577925) (xy 105.005802 -267.625331) (xy 105.022875 -267.676156) (xy 105.031527 -267.72907)
			(xy 105.032048 -267.755878) (xy 105.031539 -267.781845) (xy 105.023414 -267.83314) (xy 105.007366 -267.882533)
			(xy 104.983788 -267.928807) (xy 104.953262 -267.970823) (xy 104.916539 -268.007546) (xy 104.874523 -268.038072)
			(xy 104.828249 -268.06165) (xy 104.778856 -268.077698) (xy 104.727561 -268.085823) (xy 104.675627 -268.085823)
			(xy 104.624332 -268.077698) (xy 104.574939 -268.06165) (xy 104.528665 -268.038072) (xy 104.486649 -268.007546)
			(xy 104.449926 -267.970823) (xy 104.4194 -267.928807) (xy 104.395822 -267.882533) (xy 104.379774 -267.83314)
			(xy 104.371649 -267.781845) (xy 104.37114 -267.755878) (xy 104.371667 -267.729215) (xy 104.380247 -267.676582)
			(xy 104.397165 -267.62601) (xy 104.421981 -267.578809) (xy 104.454053 -267.536204) (xy 104.492548 -267.4993)
			(xy 104.536468 -267.469054) (xy 104.584674 -267.446251) (xy 104.610154 -267.438378) (xy 104.624518 -267.433726)
			(xy 104.649816 -267.417268) (xy 104.66921 -267.394142) (xy 104.68101 -267.366364) (xy 104.68419 -267.336351)
			(xy 104.678472 -267.306717) (xy 104.664354 -267.280041) (xy 104.654096 -267.26896) (xy 104.583738 -267.198602)
			(xy 104.572593 -267.188285) (xy 104.545777 -267.174072) (xy 104.515964 -267.168387) (xy 104.4858 -267.171736)
			(xy 104.45796 -267.183822) (xy 104.44607 -267.193268) (xy 104.42805 -267.208105) (xy 104.388624 -267.233092)
			(xy 104.346073 -267.252282) (xy 104.301245 -267.265291) (xy 104.255033 -267.27186) (xy 104.231694 -267.272262)
			(xy 104.205727 -267.27175) (xy 104.154433 -267.263625) (xy 104.105041 -267.247576) (xy 104.058767 -267.223999)
			(xy 104.016752 -267.193473) (xy 103.980029 -267.15675) (xy 103.949502 -267.114735) (xy 103.925924 -267.068461)
			(xy 103.909875 -267.019069) (xy 103.90175 -266.967775) (xy 103.90124 -266.941808) (xy 103.90163 -266.918469)
			(xy 103.908209 -266.872258) (xy 103.921223 -266.827431) (xy 103.940413 -266.784881) (xy 103.965398 -266.745453)
			(xy 103.980234 -266.727432) (xy 103.989648 -266.715529) (xy 104.001674 -266.687684) (xy 104.005005 -266.657536)
			(xy 103.999349 -266.627737) (xy 103.985202 -266.600907) (xy 103.9749 -266.589764) (xy 103.91648 -266.53109)
			(xy 103.91648 -266.444222) (xy 103.858568 -266.444222) (xy 103.85171 -266.446254) (xy 103.829749 -266.452056)
			(xy 103.784759 -266.458303) (xy 103.762048 -266.4587) (xy 103.761794 -266.4587) (xy 103.735831 -266.458098)
			(xy 103.684544 -266.449974) (xy 103.635159 -266.433928) (xy 103.588892 -266.410353) (xy 103.546883 -266.379831)
			(xy 103.510165 -266.343113) (xy 103.479644 -266.301103) (xy 103.45607 -266.254836) (xy 103.440024 -266.205451)
			(xy 103.431901 -266.154163) (xy 103.431901 -266.102237) (xy 103.440024 -266.050949) (xy 103.45607 -266.001564)
			(xy 103.479644 -265.955297) (xy 103.510165 -265.913287) (xy 103.546883 -265.876569) (xy 103.588892 -265.846047)
			(xy 103.635159 -265.822472) (xy 103.684544 -265.806426) (xy 103.735831 -265.798302) (xy 103.761794 -265.797792)
			(xy 103.771917 -265.797885) (xy 103.792125 -265.799155) (xy 103.80218 -265.800332) (xy 103.816514 -265.801689)
			(xy 103.844938 -265.797158) (xy 103.870971 -265.784883) (xy 103.89255 -265.765836) (xy 103.907962 -265.741527)
			(xy 103.915986 -265.713885) (xy 103.91648 -265.699494) (xy 103.91648 -265.412474) (xy 103.914448 -265.405616)
			(xy 103.908394 -265.383243) (xy 103.9019 -265.33735) (xy 103.901494 -265.314176) (xy 103.901888 -265.291001)
			(xy 103.908391 -265.245109) (xy 103.914448 -265.222736) (xy 103.91648 -265.215878) (xy 103.91648 -264.929112)
			(xy 103.91603 -264.91472) (xy 103.908003 -264.887077) (xy 103.892583 -264.862771) (xy 103.870994 -264.843732)
			(xy 103.844951 -264.831473) (xy 103.816521 -264.826965) (xy 103.80218 -264.828274) (xy 103.792125 -264.829452)
			(xy 103.771917 -264.830722) (xy 103.761794 -264.830814) (xy 103.735824 -264.830384) (xy 103.684523 -264.822258)
			(xy 103.635126 -264.806207) (xy 103.588847 -264.782626) (xy 103.546827 -264.752096) (xy 103.5101 -264.715368)
			(xy 103.479571 -264.673348) (xy 103.455991 -264.627069) (xy 103.43994 -264.577671) (xy 103.431815 -264.52637)
			(xy 103.151932 -264.52637) (xy 103.143814 -264.577622) (xy 103.127766 -264.627015) (xy 103.104188 -264.673289)
			(xy 103.073662 -264.715305) (xy 103.036939 -264.752028) (xy 102.994923 -264.782554) (xy 102.948649 -264.806132)
			(xy 102.899256 -264.82218) (xy 102.847961 -264.830305) (xy 102.796027 -264.830305) (xy 102.744732 -264.82218)
			(xy 102.695339 -264.806132) (xy 102.649065 -264.782554) (xy 102.607049 -264.752028) (xy 102.570326 -264.715305)
			(xy 102.5398 -264.673289) (xy 102.516222 -264.627015) (xy 102.500174 -264.577622) (xy 102.492049 -264.526327)
			(xy 102.212139 -264.526327) (xy 102.204014 -264.577622) (xy 102.187966 -264.627015) (xy 102.164388 -264.673289)
			(xy 102.133862 -264.715305) (xy 102.097139 -264.752028) (xy 102.055123 -264.782554) (xy 102.008849 -264.806132)
			(xy 101.959456 -264.82218) (xy 101.908161 -264.830305) (xy 101.856227 -264.830305) (xy 101.804932 -264.82218)
			(xy 101.755539 -264.806132) (xy 101.709265 -264.782554) (xy 101.667249 -264.752028) (xy 101.630526 -264.715305)
			(xy 101.6 -264.673289) (xy 101.576422 -264.627015) (xy 101.560374 -264.577622) (xy 101.552249 -264.526327)
			(xy 101.272339 -264.526327) (xy 101.264214 -264.577622) (xy 101.248166 -264.627015) (xy 101.224588 -264.673289)
			(xy 101.194062 -264.715305) (xy 101.157339 -264.752028) (xy 101.115323 -264.782554) (xy 101.069049 -264.806132)
			(xy 101.019656 -264.82218) (xy 100.968361 -264.830305) (xy 100.916427 -264.830305) (xy 100.865132 -264.82218)
			(xy 100.815739 -264.806132) (xy 100.769465 -264.782554) (xy 100.727449 -264.752028) (xy 100.690726 -264.715305)
			(xy 100.6602 -264.673289) (xy 100.636622 -264.627015) (xy 100.620574 -264.577622) (xy 100.612449 -264.526327)
			(xy 100.332539 -264.526327) (xy 100.324414 -264.577622) (xy 100.308366 -264.627015) (xy 100.284788 -264.673289)
			(xy 100.254262 -264.715305) (xy 100.217539 -264.752028) (xy 100.175523 -264.782554) (xy 100.129249 -264.806132)
			(xy 100.079856 -264.82218) (xy 100.028561 -264.830305) (xy 99.976627 -264.830305) (xy 99.925332 -264.82218)
			(xy 99.875939 -264.806132) (xy 99.829665 -264.782554) (xy 99.787649 -264.752028) (xy 99.750926 -264.715305)
			(xy 99.7204 -264.673289) (xy 99.696822 -264.627015) (xy 99.680774 -264.577622) (xy 99.672649 -264.526327)
			(xy 99.392739 -264.526327) (xy 99.384614 -264.577622) (xy 99.368566 -264.627015) (xy 99.344988 -264.673289)
			(xy 99.314462 -264.715305) (xy 99.277739 -264.752028) (xy 99.235723 -264.782554) (xy 99.189449 -264.806132)
			(xy 99.140056 -264.82218) (xy 99.088761 -264.830305) (xy 99.036827 -264.830305) (xy 98.985532 -264.82218)
			(xy 98.936139 -264.806132) (xy 98.889865 -264.782554) (xy 98.847849 -264.752028) (xy 98.811126 -264.715305)
			(xy 98.7806 -264.673289) (xy 98.757022 -264.627015) (xy 98.740974 -264.577622) (xy 98.732849 -264.526327)
			(xy 98.453193 -264.526327) (xy 98.445068 -264.577622) (xy 98.42902 -264.627015) (xy 98.405442 -264.673289)
			(xy 98.374916 -264.715305) (xy 98.338193 -264.752028) (xy 98.296177 -264.782554) (xy 98.249903 -264.806132)
			(xy 98.20051 -264.82218) (xy 98.149215 -264.830305) (xy 98.097281 -264.830305) (xy 98.045986 -264.82218)
			(xy 97.996593 -264.806132) (xy 97.950319 -264.782554) (xy 97.908303 -264.752028) (xy 97.87158 -264.715305)
			(xy 97.841054 -264.673289) (xy 97.817476 -264.627015) (xy 97.801428 -264.577622) (xy 97.793303 -264.526327)
			(xy 97.513139 -264.526327) (xy 97.505014 -264.577622) (xy 97.488966 -264.627015) (xy 97.465388 -264.673289)
			(xy 97.434862 -264.715305) (xy 97.398139 -264.752028) (xy 97.356123 -264.782554) (xy 97.309849 -264.806132)
			(xy 97.260456 -264.82218) (xy 97.209161 -264.830305) (xy 97.157227 -264.830305) (xy 97.105932 -264.82218)
			(xy 97.056539 -264.806132) (xy 97.010265 -264.782554) (xy 96.968249 -264.752028) (xy 96.931526 -264.715305)
			(xy 96.901 -264.673289) (xy 96.877422 -264.627015) (xy 96.861374 -264.577622) (xy 96.853249 -264.526327)
			(xy 96.573339 -264.526327) (xy 96.565214 -264.577622) (xy 96.549166 -264.627015) (xy 96.525588 -264.673289)
			(xy 96.495062 -264.715305) (xy 96.458339 -264.752028) (xy 96.416323 -264.782554) (xy 96.370049 -264.806132)
			(xy 96.320656 -264.82218) (xy 96.269361 -264.830305) (xy 96.217427 -264.830305) (xy 96.166132 -264.82218)
			(xy 96.116739 -264.806132) (xy 96.070465 -264.782554) (xy 96.028449 -264.752028) (xy 95.991726 -264.715305)
			(xy 95.9612 -264.673289) (xy 95.937622 -264.627015) (xy 95.921574 -264.577622) (xy 95.913449 -264.526327)
			(xy 95.633539 -264.526327) (xy 95.625414 -264.577622) (xy 95.609366 -264.627015) (xy 95.585788 -264.673289)
			(xy 95.555262 -264.715305) (xy 95.518539 -264.752028) (xy 95.476523 -264.782554) (xy 95.430249 -264.806132)
			(xy 95.380856 -264.82218) (xy 95.329561 -264.830305) (xy 95.277627 -264.830305) (xy 95.226332 -264.82218)
			(xy 95.176939 -264.806132) (xy 95.130665 -264.782554) (xy 95.088649 -264.752028) (xy 95.051926 -264.715305)
			(xy 95.0214 -264.673289) (xy 94.997822 -264.627015) (xy 94.981774 -264.577622) (xy 94.973649 -264.526327)
			(xy 94.693739 -264.526327) (xy 94.685614 -264.577622) (xy 94.669566 -264.627015) (xy 94.645988 -264.673289)
			(xy 94.615462 -264.715305) (xy 94.578739 -264.752028) (xy 94.536723 -264.782554) (xy 94.490449 -264.806132)
			(xy 94.441056 -264.82218) (xy 94.389761 -264.830305) (xy 94.337827 -264.830305) (xy 94.286532 -264.82218)
			(xy 94.237139 -264.806132) (xy 94.190865 -264.782554) (xy 94.148849 -264.752028) (xy 94.112126 -264.715305)
			(xy 94.0816 -264.673289) (xy 94.058022 -264.627015) (xy 94.041974 -264.577622) (xy 94.033849 -264.526327)
			(xy 93.753939 -264.526327) (xy 93.745814 -264.577622) (xy 93.729766 -264.627015) (xy 93.706188 -264.673289)
			(xy 93.675662 -264.715305) (xy 93.638939 -264.752028) (xy 93.596923 -264.782554) (xy 93.550649 -264.806132)
			(xy 93.501256 -264.82218) (xy 93.449961 -264.830305) (xy 93.398027 -264.830305) (xy 93.346732 -264.82218)
			(xy 93.297339 -264.806132) (xy 93.251065 -264.782554) (xy 93.209049 -264.752028) (xy 93.172326 -264.715305)
			(xy 93.1418 -264.673289) (xy 93.118222 -264.627015) (xy 93.102174 -264.577622) (xy 93.094049 -264.526327)
			(xy 92.814139 -264.526327) (xy 92.806014 -264.577622) (xy 92.789966 -264.627015) (xy 92.766388 -264.673289)
			(xy 92.735862 -264.715305) (xy 92.699139 -264.752028) (xy 92.657123 -264.782554) (xy 92.610849 -264.806132)
			(xy 92.561456 -264.82218) (xy 92.510161 -264.830305) (xy 92.458227 -264.830305) (xy 92.406932 -264.82218)
			(xy 92.357539 -264.806132) (xy 92.311265 -264.782554) (xy 92.269249 -264.752028) (xy 92.232526 -264.715305)
			(xy 92.202 -264.673289) (xy 92.178422 -264.627015) (xy 92.162374 -264.577622) (xy 92.154249 -264.526327)
			(xy 91.873975 -264.526327) (xy 91.87205 -264.551255) (xy 91.860349 -264.600924) (xy 91.841155 -264.648205)
			(xy 91.814923 -264.691975) (xy 91.782276 -264.731193) (xy 91.743991 -264.76493) (xy 91.722702 -264.778998)
			(xy 91.712034 -264.785856) (xy 91.68765 -264.828528) (xy 91.68765 -264.9474) (xy 91.688005 -264.956285)
			(xy 91.694162 -264.972954) (xy 91.705714 -264.986457) (xy 91.713304 -264.991088) (xy 91.790012 -265.03376)
			(xy 91.795734 -265.036722) (xy 91.808209 -265.039931) (xy 91.81465 -265.04011) (xy 91.840304 -265.032744)
			(xy 91.845892 -265.029442) (xy 91.871546 -265.015023) (xy 91.926702 -264.994523) (xy 91.984618 -264.984122)
			(xy 92.01404 -264.983468) (xy 92.014294 -264.983468) (xy 92.040285 -264.983951) (xy 92.091628 -264.992082)
			(xy 92.141067 -265.008145) (xy 92.187385 -265.031744) (xy 92.22944 -265.062298) (xy 92.266198 -265.099055)
			(xy 92.296753 -265.14111) (xy 92.320353 -265.187427) (xy 92.336417 -265.236866) (xy 92.344549 -265.288209)
			(xy 92.344549 -265.340143) (xy 92.624403 -265.340143) (xy 92.624403 -265.288209) (xy 92.632528 -265.236914)
			(xy 92.648576 -265.187521) (xy 92.672154 -265.141247) (xy 92.70268 -265.099231) (xy 92.739403 -265.062508)
			(xy 92.781419 -265.031982) (xy 92.827693 -265.008404) (xy 92.877086 -264.992356) (xy 92.928381 -264.984231)
			(xy 92.980315 -264.984231) (xy 93.03161 -264.992356) (xy 93.081003 -265.008404) (xy 93.127277 -265.031982)
			(xy 93.169293 -265.062508) (xy 93.206016 -265.099231) (xy 93.236542 -265.141247) (xy 93.26012 -265.187521)
			(xy 93.276168 -265.236914) (xy 93.284293 -265.288209) (xy 93.284802 -265.314176) (xy 93.284293 -265.340143)
			(xy 93.564203 -265.340143) (xy 93.564203 -265.288209) (xy 93.572328 -265.236914) (xy 93.588376 -265.187521)
			(xy 93.611954 -265.141247) (xy 93.64248 -265.099231) (xy 93.679203 -265.062508) (xy 93.721219 -265.031982)
			(xy 93.767493 -265.008404) (xy 93.816886 -264.992356) (xy 93.868181 -264.984231) (xy 93.920115 -264.984231)
			(xy 93.97141 -264.992356) (xy 94.020803 -265.008404) (xy 94.067077 -265.031982) (xy 94.109093 -265.062508)
			(xy 94.145816 -265.099231) (xy 94.176342 -265.141247) (xy 94.19992 -265.187521) (xy 94.215968 -265.236914)
			(xy 94.224093 -265.288209) (xy 94.224602 -265.314176) (xy 94.224093 -265.340143) (xy 94.504003 -265.340143)
			(xy 94.504003 -265.288209) (xy 94.512128 -265.236914) (xy 94.528176 -265.187521) (xy 94.551754 -265.141247)
			(xy 94.58228 -265.099231) (xy 94.619003 -265.062508) (xy 94.661019 -265.031982) (xy 94.707293 -265.008404)
			(xy 94.756686 -264.992356) (xy 94.807981 -264.984231) (xy 94.859915 -264.984231) (xy 94.91121 -264.992356)
			(xy 94.960603 -265.008404) (xy 95.006877 -265.031982) (xy 95.048893 -265.062508) (xy 95.085616 -265.099231)
			(xy 95.116142 -265.141247) (xy 95.13972 -265.187521) (xy 95.155768 -265.236914) (xy 95.163893 -265.288209)
			(xy 95.164402 -265.314176) (xy 95.163893 -265.340143) (xy 95.443803 -265.340143) (xy 95.443803 -265.288209)
			(xy 95.451928 -265.236914) (xy 95.467976 -265.187521) (xy 95.491554 -265.141247) (xy 95.52208 -265.099231)
			(xy 95.558803 -265.062508) (xy 95.600819 -265.031982) (xy 95.647093 -265.008404) (xy 95.696486 -264.992356)
			(xy 95.747781 -264.984231) (xy 95.799715 -264.984231) (xy 95.85101 -264.992356) (xy 95.900403 -265.008404)
			(xy 95.946677 -265.031982) (xy 95.988693 -265.062508) (xy 96.025416 -265.099231) (xy 96.055942 -265.141247)
			(xy 96.07952 -265.187521) (xy 96.095568 -265.236914) (xy 96.103693 -265.288209) (xy 96.104202 -265.314176)
			(xy 96.103693 -265.340143) (xy 96.383603 -265.340143) (xy 96.383603 -265.288209) (xy 96.391728 -265.236914)
			(xy 96.407776 -265.187521) (xy 96.431354 -265.141247) (xy 96.46188 -265.099231) (xy 96.498603 -265.062508)
			(xy 96.540619 -265.031982) (xy 96.586893 -265.008404) (xy 96.636286 -264.992356) (xy 96.687581 -264.984231)
			(xy 96.739515 -264.984231) (xy 96.79081 -264.992356) (xy 96.840203 -265.008404) (xy 96.886477 -265.031982)
			(xy 96.928493 -265.062508) (xy 96.965216 -265.099231) (xy 96.995742 -265.141247) (xy 97.01932 -265.187521)
			(xy 97.035368 -265.236914) (xy 97.043493 -265.288209) (xy 97.044002 -265.314176) (xy 97.043493 -265.340143)
			(xy 97.323403 -265.340143) (xy 97.323403 -265.288209) (xy 97.331528 -265.236914) (xy 97.347576 -265.187521)
			(xy 97.371154 -265.141247) (xy 97.40168 -265.099231) (xy 97.438403 -265.062508) (xy 97.480419 -265.031982)
			(xy 97.526693 -265.008404) (xy 97.576086 -264.992356) (xy 97.627381 -264.984231) (xy 97.679315 -264.984231)
			(xy 97.73061 -264.992356) (xy 97.780003 -265.008404) (xy 97.826277 -265.031982) (xy 97.868293 -265.062508)
			(xy 97.905016 -265.099231) (xy 97.935542 -265.141247) (xy 97.95912 -265.187521) (xy 97.975168 -265.236914)
			(xy 97.983293 -265.288209) (xy 97.983802 -265.314176) (xy 97.983293 -265.340143) (xy 98.262949 -265.340143)
			(xy 98.262949 -265.288209) (xy 98.271074 -265.236914) (xy 98.287122 -265.187521) (xy 98.3107 -265.141247)
			(xy 98.341226 -265.099231) (xy 98.377949 -265.062508) (xy 98.419965 -265.031982) (xy 98.466239 -265.008404)
			(xy 98.515632 -264.992356) (xy 98.566927 -264.984231) (xy 98.618861 -264.984231) (xy 98.670156 -264.992356)
			(xy 98.719549 -265.008404) (xy 98.765823 -265.031982) (xy 98.807839 -265.062508) (xy 98.844562 -265.099231)
			(xy 98.875088 -265.141247) (xy 98.898666 -265.187521) (xy 98.914714 -265.236914) (xy 98.922839 -265.288209)
			(xy 98.923348 -265.314176) (xy 98.922839 -265.340143) (xy 99.203003 -265.340143) (xy 99.203003 -265.288209)
			(xy 99.211128 -265.236914) (xy 99.227176 -265.187521) (xy 99.250754 -265.141247) (xy 99.28128 -265.099231)
			(xy 99.318003 -265.062508) (xy 99.360019 -265.031982) (xy 99.406293 -265.008404) (xy 99.455686 -264.992356)
			(xy 99.506981 -264.984231) (xy 99.558915 -264.984231) (xy 99.61021 -264.992356) (xy 99.659603 -265.008404)
			(xy 99.705877 -265.031982) (xy 99.747893 -265.062508) (xy 99.784616 -265.099231) (xy 99.815142 -265.141247)
			(xy 99.83872 -265.187521) (xy 99.854768 -265.236914) (xy 99.862893 -265.288209) (xy 99.863402 -265.314176)
			(xy 99.862893 -265.340143) (xy 100.142803 -265.340143) (xy 100.142803 -265.288209) (xy 100.150928 -265.236914)
			(xy 100.166976 -265.187521) (xy 100.190554 -265.141247) (xy 100.22108 -265.099231) (xy 100.257803 -265.062508)
			(xy 100.299819 -265.031982) (xy 100.346093 -265.008404) (xy 100.395486 -264.992356) (xy 100.446781 -264.984231)
			(xy 100.498715 -264.984231) (xy 100.55001 -264.992356) (xy 100.599403 -265.008404) (xy 100.645677 -265.031982)
			(xy 100.687693 -265.062508) (xy 100.724416 -265.099231) (xy 100.754942 -265.141247) (xy 100.77852 -265.187521)
			(xy 100.794568 -265.236914) (xy 100.802693 -265.288209) (xy 100.803202 -265.314176) (xy 100.802693 -265.340143)
			(xy 101.082603 -265.340143) (xy 101.082603 -265.288209) (xy 101.090728 -265.236914) (xy 101.106776 -265.187521)
			(xy 101.130354 -265.141247) (xy 101.16088 -265.099231) (xy 101.197603 -265.062508) (xy 101.239619 -265.031982)
			(xy 101.285893 -265.008404) (xy 101.335286 -264.992356) (xy 101.386581 -264.984231) (xy 101.438515 -264.984231)
			(xy 101.48981 -264.992356) (xy 101.539203 -265.008404) (xy 101.585477 -265.031982) (xy 101.627493 -265.062508)
			(xy 101.664216 -265.099231) (xy 101.694742 -265.141247) (xy 101.71832 -265.187521) (xy 101.734368 -265.236914)
			(xy 101.742493 -265.288209) (xy 101.743002 -265.314176) (xy 101.742493 -265.340143) (xy 102.022403 -265.340143)
			(xy 102.022403 -265.288209) (xy 102.030528 -265.236914) (xy 102.046576 -265.187521) (xy 102.070154 -265.141247)
			(xy 102.10068 -265.099231) (xy 102.137403 -265.062508) (xy 102.179419 -265.031982) (xy 102.225693 -265.008404)
			(xy 102.275086 -264.992356) (xy 102.326381 -264.984231) (xy 102.378315 -264.984231) (xy 102.42961 -264.992356)
			(xy 102.479003 -265.008404) (xy 102.525277 -265.031982) (xy 102.567293 -265.062508) (xy 102.604016 -265.099231)
			(xy 102.634542 -265.141247) (xy 102.65812 -265.187521) (xy 102.674168 -265.236914) (xy 102.682293 -265.288209)
			(xy 102.682802 -265.314176) (xy 102.682293 -265.340143) (xy 102.962203 -265.340143) (xy 102.962203 -265.288209)
			(xy 102.970328 -265.236914) (xy 102.986376 -265.187521) (xy 103.009954 -265.141247) (xy 103.04048 -265.099231)
			(xy 103.077203 -265.062508) (xy 103.119219 -265.031982) (xy 103.165493 -265.008404) (xy 103.214886 -264.992356)
			(xy 103.266181 -264.984231) (xy 103.318115 -264.984231) (xy 103.36941 -264.992356) (xy 103.418803 -265.008404)
			(xy 103.465077 -265.031982) (xy 103.507093 -265.062508) (xy 103.543816 -265.099231) (xy 103.574342 -265.141247)
			(xy 103.59792 -265.187521) (xy 103.613968 -265.236914) (xy 103.622093 -265.288209) (xy 103.622602 -265.314176)
			(xy 103.622093 -265.340143) (xy 103.613968 -265.391438) (xy 103.59792 -265.440831) (xy 103.574342 -265.487105)
			(xy 103.543816 -265.529121) (xy 103.507093 -265.565844) (xy 103.465077 -265.59637) (xy 103.418803 -265.619948)
			(xy 103.36941 -265.635996) (xy 103.318115 -265.644121) (xy 103.266181 -265.644121) (xy 103.214886 -265.635996)
			(xy 103.165493 -265.619948) (xy 103.119219 -265.59637) (xy 103.077203 -265.565844) (xy 103.04048 -265.529121)
			(xy 103.009954 -265.487105) (xy 102.986376 -265.440831) (xy 102.970328 -265.391438) (xy 102.962203 -265.340143)
			(xy 102.682293 -265.340143) (xy 102.674168 -265.391438) (xy 102.65812 -265.440831) (xy 102.634542 -265.487105)
			(xy 102.604016 -265.529121) (xy 102.567293 -265.565844) (xy 102.525277 -265.59637) (xy 102.479003 -265.619948)
			(xy 102.42961 -265.635996) (xy 102.378315 -265.644121) (xy 102.326381 -265.644121) (xy 102.275086 -265.635996)
			(xy 102.225693 -265.619948) (xy 102.179419 -265.59637) (xy 102.137403 -265.565844) (xy 102.10068 -265.529121)
			(xy 102.070154 -265.487105) (xy 102.046576 -265.440831) (xy 102.030528 -265.391438) (xy 102.022403 -265.340143)
			(xy 101.742493 -265.340143) (xy 101.734368 -265.391438) (xy 101.71832 -265.440831) (xy 101.694742 -265.487105)
			(xy 101.664216 -265.529121) (xy 101.627493 -265.565844) (xy 101.585477 -265.59637) (xy 101.539203 -265.619948)
			(xy 101.48981 -265.635996) (xy 101.438515 -265.644121) (xy 101.386581 -265.644121) (xy 101.335286 -265.635996)
			(xy 101.285893 -265.619948) (xy 101.239619 -265.59637) (xy 101.197603 -265.565844) (xy 101.16088 -265.529121)
			(xy 101.130354 -265.487105) (xy 101.106776 -265.440831) (xy 101.090728 -265.391438) (xy 101.082603 -265.340143)
			(xy 100.802693 -265.340143) (xy 100.794568 -265.391438) (xy 100.77852 -265.440831) (xy 100.754942 -265.487105)
			(xy 100.724416 -265.529121) (xy 100.687693 -265.565844) (xy 100.645677 -265.59637) (xy 100.599403 -265.619948)
			(xy 100.55001 -265.635996) (xy 100.498715 -265.644121) (xy 100.446781 -265.644121) (xy 100.395486 -265.635996)
			(xy 100.346093 -265.619948) (xy 100.299819 -265.59637) (xy 100.257803 -265.565844) (xy 100.22108 -265.529121)
			(xy 100.190554 -265.487105) (xy 100.166976 -265.440831) (xy 100.150928 -265.391438) (xy 100.142803 -265.340143)
			(xy 99.862893 -265.340143) (xy 99.854768 -265.391438) (xy 99.83872 -265.440831) (xy 99.815142 -265.487105)
			(xy 99.784616 -265.529121) (xy 99.747893 -265.565844) (xy 99.705877 -265.59637) (xy 99.659603 -265.619948)
			(xy 99.61021 -265.635996) (xy 99.558915 -265.644121) (xy 99.506981 -265.644121) (xy 99.455686 -265.635996)
			(xy 99.406293 -265.619948) (xy 99.360019 -265.59637) (xy 99.318003 -265.565844) (xy 99.28128 -265.529121)
			(xy 99.250754 -265.487105) (xy 99.227176 -265.440831) (xy 99.211128 -265.391438) (xy 99.203003 -265.340143)
			(xy 98.922839 -265.340143) (xy 98.914714 -265.391438) (xy 98.898666 -265.440831) (xy 98.875088 -265.487105)
			(xy 98.844562 -265.529121) (xy 98.807839 -265.565844) (xy 98.765823 -265.59637) (xy 98.719549 -265.619948)
			(xy 98.670156 -265.635996) (xy 98.618861 -265.644121) (xy 98.566927 -265.644121) (xy 98.515632 -265.635996)
			(xy 98.466239 -265.619948) (xy 98.419965 -265.59637) (xy 98.377949 -265.565844) (xy 98.341226 -265.529121)
			(xy 98.3107 -265.487105) (xy 98.287122 -265.440831) (xy 98.271074 -265.391438) (xy 98.262949 -265.340143)
			(xy 97.983293 -265.340143) (xy 97.975168 -265.391438) (xy 97.95912 -265.440831) (xy 97.935542 -265.487105)
			(xy 97.905016 -265.529121) (xy 97.868293 -265.565844) (xy 97.826277 -265.59637) (xy 97.780003 -265.619948)
			(xy 97.73061 -265.635996) (xy 97.679315 -265.644121) (xy 97.627381 -265.644121) (xy 97.576086 -265.635996)
			(xy 97.526693 -265.619948) (xy 97.480419 -265.59637) (xy 97.438403 -265.565844) (xy 97.40168 -265.529121)
			(xy 97.371154 -265.487105) (xy 97.347576 -265.440831) (xy 97.331528 -265.391438) (xy 97.323403 -265.340143)
			(xy 97.043493 -265.340143) (xy 97.035368 -265.391438) (xy 97.01932 -265.440831) (xy 96.995742 -265.487105)
			(xy 96.965216 -265.529121) (xy 96.928493 -265.565844) (xy 96.886477 -265.59637) (xy 96.840203 -265.619948)
			(xy 96.79081 -265.635996) (xy 96.739515 -265.644121) (xy 96.687581 -265.644121) (xy 96.636286 -265.635996)
			(xy 96.586893 -265.619948) (xy 96.540619 -265.59637) (xy 96.498603 -265.565844) (xy 96.46188 -265.529121)
			(xy 96.431354 -265.487105) (xy 96.407776 -265.440831) (xy 96.391728 -265.391438) (xy 96.383603 -265.340143)
			(xy 96.103693 -265.340143) (xy 96.095568 -265.391438) (xy 96.07952 -265.440831) (xy 96.055942 -265.487105)
			(xy 96.025416 -265.529121) (xy 95.988693 -265.565844) (xy 95.946677 -265.59637) (xy 95.900403 -265.619948)
			(xy 95.85101 -265.635996) (xy 95.799715 -265.644121) (xy 95.747781 -265.644121) (xy 95.696486 -265.635996)
			(xy 95.647093 -265.619948) (xy 95.600819 -265.59637) (xy 95.558803 -265.565844) (xy 95.52208 -265.529121)
			(xy 95.491554 -265.487105) (xy 95.467976 -265.440831) (xy 95.451928 -265.391438) (xy 95.443803 -265.340143)
			(xy 95.163893 -265.340143) (xy 95.155768 -265.391438) (xy 95.13972 -265.440831) (xy 95.116142 -265.487105)
			(xy 95.085616 -265.529121) (xy 95.048893 -265.565844) (xy 95.006877 -265.59637) (xy 94.960603 -265.619948)
			(xy 94.91121 -265.635996) (xy 94.859915 -265.644121) (xy 94.807981 -265.644121) (xy 94.756686 -265.635996)
			(xy 94.707293 -265.619948) (xy 94.661019 -265.59637) (xy 94.619003 -265.565844) (xy 94.58228 -265.529121)
			(xy 94.551754 -265.487105) (xy 94.528176 -265.440831) (xy 94.512128 -265.391438) (xy 94.504003 -265.340143)
			(xy 94.224093 -265.340143) (xy 94.215968 -265.391438) (xy 94.19992 -265.440831) (xy 94.176342 -265.487105)
			(xy 94.145816 -265.529121) (xy 94.109093 -265.565844) (xy 94.067077 -265.59637) (xy 94.020803 -265.619948)
			(xy 93.97141 -265.635996) (xy 93.920115 -265.644121) (xy 93.868181 -265.644121) (xy 93.816886 -265.635996)
			(xy 93.767493 -265.619948) (xy 93.721219 -265.59637) (xy 93.679203 -265.565844) (xy 93.64248 -265.529121)
			(xy 93.611954 -265.487105) (xy 93.588376 -265.440831) (xy 93.572328 -265.391438) (xy 93.564203 -265.340143)
			(xy 93.284293 -265.340143) (xy 93.276168 -265.391438) (xy 93.26012 -265.440831) (xy 93.236542 -265.487105)
			(xy 93.206016 -265.529121) (xy 93.169293 -265.565844) (xy 93.127277 -265.59637) (xy 93.081003 -265.619948)
			(xy 93.03161 -265.635996) (xy 92.980315 -265.644121) (xy 92.928381 -265.644121) (xy 92.877086 -265.635996)
			(xy 92.827693 -265.619948) (xy 92.781419 -265.59637) (xy 92.739403 -265.565844) (xy 92.70268 -265.529121)
			(xy 92.672154 -265.487105) (xy 92.648576 -265.440831) (xy 92.632528 -265.391438) (xy 92.624403 -265.340143)
			(xy 92.344549 -265.340143) (xy 92.344549 -265.340191) (xy 92.336417 -265.391534) (xy 92.320353 -265.440973)
			(xy 92.296753 -265.48729) (xy 92.266198 -265.529345) (xy 92.22944 -265.566102) (xy 92.187385 -265.596656)
			(xy 92.141067 -265.620255) (xy 92.091628 -265.636318) (xy 92.040285 -265.644449) (xy 92.014294 -265.644884)
			(xy 92.01404 -265.644884) (xy 91.984621 -265.644219) (xy 91.926715 -265.633786) (xy 91.871553 -265.613312)
			(xy 91.845892 -265.59891) (xy 91.840304 -265.595608) (xy 91.81465 -265.588242) (xy 91.808208 -265.588409)
			(xy 91.795734 -265.591627) (xy 91.790012 -265.594592) (xy 91.713304 -265.637264) (xy 91.705716 -265.641902)
			(xy 91.694154 -265.6554) (xy 91.687983 -265.672066) (xy 91.68765 -265.680952) (xy 91.68765 -265.800332)
			(xy 91.712034 -265.84275) (xy 91.718638 -265.847068) (xy 91.740359 -265.861118) (xy 91.779548 -265.894881)
			(xy 91.813004 -265.934333) (xy 91.83991 -265.978512) (xy 91.85961 -266.026341) (xy 91.871624 -266.076654)
			(xy 91.875659 -266.128224) (xy 91.873622 -266.154213) (xy 92.154249 -266.154213) (xy 92.154249 -266.102279)
			(xy 92.162374 -266.050984) (xy 92.178422 -266.001591) (xy 92.202 -265.955317) (xy 92.232526 -265.913301)
			(xy 92.269249 -265.876578) (xy 92.311265 -265.846052) (xy 92.357539 -265.822474) (xy 92.406932 -265.806426)
			(xy 92.458227 -265.798301) (xy 92.510161 -265.798301) (xy 92.561456 -265.806426) (xy 92.610849 -265.822474)
			(xy 92.657123 -265.846052) (xy 92.699139 -265.876578) (xy 92.735862 -265.913301) (xy 92.766388 -265.955317)
			(xy 92.789966 -266.001591) (xy 92.806014 -266.050984) (xy 92.814139 -266.102279) (xy 92.814648 -266.128246)
			(xy 92.814139 -266.154213) (xy 93.094049 -266.154213) (xy 93.094049 -266.102279) (xy 93.102174 -266.050984)
			(xy 93.118222 -266.001591) (xy 93.1418 -265.955317) (xy 93.172326 -265.913301) (xy 93.209049 -265.876578)
			(xy 93.251065 -265.846052) (xy 93.297339 -265.822474) (xy 93.346732 -265.806426) (xy 93.398027 -265.798301)
			(xy 93.449961 -265.798301) (xy 93.501256 -265.806426) (xy 93.550649 -265.822474) (xy 93.596923 -265.846052)
			(xy 93.638939 -265.876578) (xy 93.675662 -265.913301) (xy 93.706188 -265.955317) (xy 93.729766 -266.001591)
			(xy 93.745814 -266.050984) (xy 93.753939 -266.102279) (xy 93.754448 -266.128246) (xy 93.753939 -266.154213)
			(xy 94.033849 -266.154213) (xy 94.033849 -266.102279) (xy 94.041974 -266.050984) (xy 94.058022 -266.001591)
			(xy 94.0816 -265.955317) (xy 94.112126 -265.913301) (xy 94.148849 -265.876578) (xy 94.190865 -265.846052)
			(xy 94.237139 -265.822474) (xy 94.286532 -265.806426) (xy 94.337827 -265.798301) (xy 94.389761 -265.798301)
			(xy 94.441056 -265.806426) (xy 94.490449 -265.822474) (xy 94.536723 -265.846052) (xy 94.578739 -265.876578)
			(xy 94.615462 -265.913301) (xy 94.645988 -265.955317) (xy 94.669566 -266.001591) (xy 94.685614 -266.050984)
			(xy 94.693739 -266.102279) (xy 94.694248 -266.128246) (xy 94.693739 -266.154213) (xy 94.973649 -266.154213)
			(xy 94.973649 -266.102279) (xy 94.981774 -266.050984) (xy 94.997822 -266.001591) (xy 95.0214 -265.955317)
			(xy 95.051926 -265.913301) (xy 95.088649 -265.876578) (xy 95.130665 -265.846052) (xy 95.176939 -265.822474)
			(xy 95.226332 -265.806426) (xy 95.277627 -265.798301) (xy 95.329561 -265.798301) (xy 95.380856 -265.806426)
			(xy 95.430249 -265.822474) (xy 95.476523 -265.846052) (xy 95.518539 -265.876578) (xy 95.555262 -265.913301)
			(xy 95.585788 -265.955317) (xy 95.609366 -266.001591) (xy 95.625414 -266.050984) (xy 95.633539 -266.102279)
			(xy 95.634048 -266.128246) (xy 95.633539 -266.154213) (xy 95.913449 -266.154213) (xy 95.913449 -266.102279)
			(xy 95.921574 -266.050984) (xy 95.937622 -266.001591) (xy 95.9612 -265.955317) (xy 95.991726 -265.913301)
			(xy 96.028449 -265.876578) (xy 96.070465 -265.846052) (xy 96.116739 -265.822474) (xy 96.166132 -265.806426)
			(xy 96.217427 -265.798301) (xy 96.269361 -265.798301) (xy 96.320656 -265.806426) (xy 96.370049 -265.822474)
			(xy 96.416323 -265.846052) (xy 96.458339 -265.876578) (xy 96.495062 -265.913301) (xy 96.525588 -265.955317)
			(xy 96.549166 -266.001591) (xy 96.565214 -266.050984) (xy 96.573339 -266.102279) (xy 96.573848 -266.128246)
			(xy 96.573339 -266.154213) (xy 96.853249 -266.154213) (xy 96.853249 -266.102279) (xy 96.861374 -266.050984)
			(xy 96.877422 -266.001591) (xy 96.901 -265.955317) (xy 96.931526 -265.913301) (xy 96.968249 -265.876578)
			(xy 97.010265 -265.846052) (xy 97.056539 -265.822474) (xy 97.105932 -265.806426) (xy 97.157227 -265.798301)
			(xy 97.209161 -265.798301) (xy 97.260456 -265.806426) (xy 97.309849 -265.822474) (xy 97.356123 -265.846052)
			(xy 97.398139 -265.876578) (xy 97.434862 -265.913301) (xy 97.465388 -265.955317) (xy 97.488966 -266.001591)
			(xy 97.505014 -266.050984) (xy 97.513139 -266.102279) (xy 97.513648 -266.128246) (xy 97.513139 -266.154213)
			(xy 97.793049 -266.154213) (xy 97.793049 -266.102279) (xy 97.801174 -266.050984) (xy 97.817222 -266.001591)
			(xy 97.8408 -265.955317) (xy 97.871326 -265.913301) (xy 97.908049 -265.876578) (xy 97.950065 -265.846052)
			(xy 97.996339 -265.822474) (xy 98.045732 -265.806426) (xy 98.097027 -265.798301) (xy 98.148961 -265.798301)
			(xy 98.200256 -265.806426) (xy 98.249649 -265.822474) (xy 98.295923 -265.846052) (xy 98.337939 -265.876578)
			(xy 98.374662 -265.913301) (xy 98.405188 -265.955317) (xy 98.428766 -266.001591) (xy 98.444814 -266.050984)
			(xy 98.452939 -266.102279) (xy 98.453448 -266.128246) (xy 98.452939 -266.154213) (xy 98.732849 -266.154213)
			(xy 98.732849 -266.102279) (xy 98.740974 -266.050984) (xy 98.757022 -266.001591) (xy 98.7806 -265.955317)
			(xy 98.811126 -265.913301) (xy 98.847849 -265.876578) (xy 98.889865 -265.846052) (xy 98.936139 -265.822474)
			(xy 98.985532 -265.806426) (xy 99.036827 -265.798301) (xy 99.088761 -265.798301) (xy 99.140056 -265.806426)
			(xy 99.189449 -265.822474) (xy 99.235723 -265.846052) (xy 99.277739 -265.876578) (xy 99.314462 -265.913301)
			(xy 99.344988 -265.955317) (xy 99.368566 -266.001591) (xy 99.384614 -266.050984) (xy 99.392739 -266.102279)
			(xy 99.393248 -266.128246) (xy 99.392739 -266.154213) (xy 99.672649 -266.154213) (xy 99.672649 -266.102279)
			(xy 99.680774 -266.050984) (xy 99.696822 -266.001591) (xy 99.7204 -265.955317) (xy 99.750926 -265.913301)
			(xy 99.787649 -265.876578) (xy 99.829665 -265.846052) (xy 99.875939 -265.822474) (xy 99.925332 -265.806426)
			(xy 99.976627 -265.798301) (xy 100.028561 -265.798301) (xy 100.079856 -265.806426) (xy 100.129249 -265.822474)
			(xy 100.175523 -265.846052) (xy 100.217539 -265.876578) (xy 100.254262 -265.913301) (xy 100.284788 -265.955317)
			(xy 100.308366 -266.001591) (xy 100.324414 -266.050984) (xy 100.332539 -266.102279) (xy 100.333048 -266.128246)
			(xy 100.332539 -266.154213) (xy 100.612449 -266.154213) (xy 100.612449 -266.102279) (xy 100.620574 -266.050984)
			(xy 100.636622 -266.001591) (xy 100.6602 -265.955317) (xy 100.690726 -265.913301) (xy 100.727449 -265.876578)
			(xy 100.769465 -265.846052) (xy 100.815739 -265.822474) (xy 100.865132 -265.806426) (xy 100.916427 -265.798301)
			(xy 100.968361 -265.798301) (xy 101.019656 -265.806426) (xy 101.069049 -265.822474) (xy 101.115323 -265.846052)
			(xy 101.157339 -265.876578) (xy 101.194062 -265.913301) (xy 101.224588 -265.955317) (xy 101.248166 -266.001591)
			(xy 101.264214 -266.050984) (xy 101.272339 -266.102279) (xy 101.272848 -266.128246) (xy 101.272339 -266.154213)
			(xy 101.552249 -266.154213) (xy 101.552249 -266.102279) (xy 101.560374 -266.050984) (xy 101.576422 -266.001591)
			(xy 101.6 -265.955317) (xy 101.630526 -265.913301) (xy 101.667249 -265.876578) (xy 101.709265 -265.846052)
			(xy 101.755539 -265.822474) (xy 101.804932 -265.806426) (xy 101.856227 -265.798301) (xy 101.908161 -265.798301)
			(xy 101.959456 -265.806426) (xy 102.008849 -265.822474) (xy 102.055123 -265.846052) (xy 102.097139 -265.876578)
			(xy 102.133862 -265.913301) (xy 102.164388 -265.955317) (xy 102.187966 -266.001591) (xy 102.204014 -266.050984)
			(xy 102.212139 -266.102279) (xy 102.212648 -266.128246) (xy 102.212139 -266.154213) (xy 102.492049 -266.154213)
			(xy 102.492049 -266.102279) (xy 102.500174 -266.050984) (xy 102.516222 -266.001591) (xy 102.5398 -265.955317)
			(xy 102.570326 -265.913301) (xy 102.607049 -265.876578) (xy 102.649065 -265.846052) (xy 102.695339 -265.822474)
			(xy 102.744732 -265.806426) (xy 102.796027 -265.798301) (xy 102.847961 -265.798301) (xy 102.899256 -265.806426)
			(xy 102.948649 -265.822474) (xy 102.994923 -265.846052) (xy 103.036939 -265.876578) (xy 103.073662 -265.913301)
			(xy 103.104188 -265.955317) (xy 103.127766 -266.001591) (xy 103.143814 -266.050984) (xy 103.151939 -266.102279)
			(xy 103.152448 -266.128246) (xy 103.151939 -266.154213) (xy 103.143814 -266.205508) (xy 103.127766 -266.254901)
			(xy 103.104188 -266.301175) (xy 103.073662 -266.343191) (xy 103.036939 -266.379914) (xy 102.994923 -266.41044)
			(xy 102.948649 -266.434018) (xy 102.899256 -266.450066) (xy 102.847961 -266.458191) (xy 102.796027 -266.458191)
			(xy 102.744732 -266.450066) (xy 102.695339 -266.434018) (xy 102.649065 -266.41044) (xy 102.607049 -266.379914)
			(xy 102.570326 -266.343191) (xy 102.5398 -266.301175) (xy 102.516222 -266.254901) (xy 102.500174 -266.205508)
			(xy 102.492049 -266.154213) (xy 102.212139 -266.154213) (xy 102.204014 -266.205508) (xy 102.187966 -266.254901)
			(xy 102.164388 -266.301175) (xy 102.133862 -266.343191) (xy 102.097139 -266.379914) (xy 102.055123 -266.41044)
			(xy 102.008849 -266.434018) (xy 101.959456 -266.450066) (xy 101.908161 -266.458191) (xy 101.856227 -266.458191)
			(xy 101.804932 -266.450066) (xy 101.755539 -266.434018) (xy 101.709265 -266.41044) (xy 101.667249 -266.379914)
			(xy 101.630526 -266.343191) (xy 101.6 -266.301175) (xy 101.576422 -266.254901) (xy 101.560374 -266.205508)
			(xy 101.552249 -266.154213) (xy 101.272339 -266.154213) (xy 101.264214 -266.205508) (xy 101.248166 -266.254901)
			(xy 101.224588 -266.301175) (xy 101.194062 -266.343191) (xy 101.157339 -266.379914) (xy 101.115323 -266.41044)
			(xy 101.069049 -266.434018) (xy 101.019656 -266.450066) (xy 100.968361 -266.458191) (xy 100.916427 -266.458191)
			(xy 100.865132 -266.450066) (xy 100.815739 -266.434018) (xy 100.769465 -266.41044) (xy 100.727449 -266.379914)
			(xy 100.690726 -266.343191) (xy 100.6602 -266.301175) (xy 100.636622 -266.254901) (xy 100.620574 -266.205508)
			(xy 100.612449 -266.154213) (xy 100.332539 -266.154213) (xy 100.324414 -266.205508) (xy 100.308366 -266.254901)
			(xy 100.284788 -266.301175) (xy 100.254262 -266.343191) (xy 100.217539 -266.379914) (xy 100.175523 -266.41044)
			(xy 100.129249 -266.434018) (xy 100.079856 -266.450066) (xy 100.028561 -266.458191) (xy 99.976627 -266.458191)
			(xy 99.925332 -266.450066) (xy 99.875939 -266.434018) (xy 99.829665 -266.41044) (xy 99.787649 -266.379914)
			(xy 99.750926 -266.343191) (xy 99.7204 -266.301175) (xy 99.696822 -266.254901) (xy 99.680774 -266.205508)
			(xy 99.672649 -266.154213) (xy 99.392739 -266.154213) (xy 99.384614 -266.205508) (xy 99.368566 -266.254901)
			(xy 99.344988 -266.301175) (xy 99.314462 -266.343191) (xy 99.277739 -266.379914) (xy 99.235723 -266.41044)
			(xy 99.189449 -266.434018) (xy 99.140056 -266.450066) (xy 99.088761 -266.458191) (xy 99.036827 -266.458191)
			(xy 98.985532 -266.450066) (xy 98.936139 -266.434018) (xy 98.889865 -266.41044) (xy 98.847849 -266.379914)
			(xy 98.811126 -266.343191) (xy 98.7806 -266.301175) (xy 98.757022 -266.254901) (xy 98.740974 -266.205508)
			(xy 98.732849 -266.154213) (xy 98.452939 -266.154213) (xy 98.444814 -266.205508) (xy 98.428766 -266.254901)
			(xy 98.405188 -266.301175) (xy 98.374662 -266.343191) (xy 98.337939 -266.379914) (xy 98.295923 -266.41044)
			(xy 98.249649 -266.434018) (xy 98.200256 -266.450066) (xy 98.148961 -266.458191) (xy 98.097027 -266.458191)
			(xy 98.045732 -266.450066) (xy 97.996339 -266.434018) (xy 97.950065 -266.41044) (xy 97.908049 -266.379914)
			(xy 97.871326 -266.343191) (xy 97.8408 -266.301175) (xy 97.817222 -266.254901) (xy 97.801174 -266.205508)
			(xy 97.793049 -266.154213) (xy 97.513139 -266.154213) (xy 97.505014 -266.205508) (xy 97.488966 -266.254901)
			(xy 97.465388 -266.301175) (xy 97.434862 -266.343191) (xy 97.398139 -266.379914) (xy 97.356123 -266.41044)
			(xy 97.309849 -266.434018) (xy 97.260456 -266.450066) (xy 97.209161 -266.458191) (xy 97.157227 -266.458191)
			(xy 97.105932 -266.450066) (xy 97.056539 -266.434018) (xy 97.010265 -266.41044) (xy 96.968249 -266.379914)
			(xy 96.931526 -266.343191) (xy 96.901 -266.301175) (xy 96.877422 -266.254901) (xy 96.861374 -266.205508)
			(xy 96.853249 -266.154213) (xy 96.573339 -266.154213) (xy 96.565214 -266.205508) (xy 96.549166 -266.254901)
			(xy 96.525588 -266.301175) (xy 96.495062 -266.343191) (xy 96.458339 -266.379914) (xy 96.416323 -266.41044)
			(xy 96.370049 -266.434018) (xy 96.320656 -266.450066) (xy 96.269361 -266.458191) (xy 96.217427 -266.458191)
			(xy 96.166132 -266.450066) (xy 96.116739 -266.434018) (xy 96.070465 -266.41044) (xy 96.028449 -266.379914)
			(xy 95.991726 -266.343191) (xy 95.9612 -266.301175) (xy 95.937622 -266.254901) (xy 95.921574 -266.205508)
			(xy 95.913449 -266.154213) (xy 95.633539 -266.154213) (xy 95.625414 -266.205508) (xy 95.609366 -266.254901)
			(xy 95.585788 -266.301175) (xy 95.555262 -266.343191) (xy 95.518539 -266.379914) (xy 95.476523 -266.41044)
			(xy 95.430249 -266.434018) (xy 95.380856 -266.450066) (xy 95.329561 -266.458191) (xy 95.277627 -266.458191)
			(xy 95.226332 -266.450066) (xy 95.176939 -266.434018) (xy 95.130665 -266.41044) (xy 95.088649 -266.379914)
			(xy 95.051926 -266.343191) (xy 95.0214 -266.301175) (xy 94.997822 -266.254901) (xy 94.981774 -266.205508)
			(xy 94.973649 -266.154213) (xy 94.693739 -266.154213) (xy 94.685614 -266.205508) (xy 94.669566 -266.254901)
			(xy 94.645988 -266.301175) (xy 94.615462 -266.343191) (xy 94.578739 -266.379914) (xy 94.536723 -266.41044)
			(xy 94.490449 -266.434018) (xy 94.441056 -266.450066) (xy 94.389761 -266.458191) (xy 94.337827 -266.458191)
			(xy 94.286532 -266.450066) (xy 94.237139 -266.434018) (xy 94.190865 -266.41044) (xy 94.148849 -266.379914)
			(xy 94.112126 -266.343191) (xy 94.0816 -266.301175) (xy 94.058022 -266.254901) (xy 94.041974 -266.205508)
			(xy 94.033849 -266.154213) (xy 93.753939 -266.154213) (xy 93.745814 -266.205508) (xy 93.729766 -266.254901)
			(xy 93.706188 -266.301175) (xy 93.675662 -266.343191) (xy 93.638939 -266.379914) (xy 93.596923 -266.41044)
			(xy 93.550649 -266.434018) (xy 93.501256 -266.450066) (xy 93.449961 -266.458191) (xy 93.398027 -266.458191)
			(xy 93.346732 -266.450066) (xy 93.297339 -266.434018) (xy 93.251065 -266.41044) (xy 93.209049 -266.379914)
			(xy 93.172326 -266.343191) (xy 93.1418 -266.301175) (xy 93.118222 -266.254901) (xy 93.102174 -266.205508)
			(xy 93.094049 -266.154213) (xy 92.814139 -266.154213) (xy 92.806014 -266.205508) (xy 92.789966 -266.254901)
			(xy 92.766388 -266.301175) (xy 92.735862 -266.343191) (xy 92.699139 -266.379914) (xy 92.657123 -266.41044)
			(xy 92.610849 -266.434018) (xy 92.561456 -266.450066) (xy 92.510161 -266.458191) (xy 92.458227 -266.458191)
			(xy 92.406932 -266.450066) (xy 92.357539 -266.434018) (xy 92.311265 -266.41044) (xy 92.269249 -266.379914)
			(xy 92.232526 -266.343191) (xy 92.202 -266.301175) (xy 92.178422 -266.254901) (xy 92.162374 -266.205508)
			(xy 92.154249 -266.154213) (xy 91.873622 -266.154213) (xy 91.871617 -266.179794) (xy 91.859595 -266.230105)
			(xy 91.839888 -266.277931) (xy 91.812976 -266.322107) (xy 91.779514 -266.361554) (xy 91.74032 -266.395311)
			(xy 91.718638 -266.409424) (xy 91.712034 -266.413742) (xy 91.68765 -266.45616) (xy 91.68765 -266.575286)
			(xy 91.688002 -266.584172) (xy 91.694157 -266.600845) (xy 91.705707 -266.614352) (xy 91.713304 -266.618974)
			(xy 91.751658 -266.64031) (xy 91.791536 -266.662408) (xy 91.799315 -266.666018) (xy 91.816299 -266.668316)
			(xy 91.833076 -266.664819) (xy 91.840558 -266.66063) (xy 91.840812 -266.660376) (xy 91.860482 -266.648696)
			(xy 91.902354 -266.630268) (xy 91.946364 -266.617782) (xy 91.991674 -266.611475) (xy 92.014548 -266.6111)
			(xy 92.040532 -266.611613) (xy 92.09186 -266.619749) (xy 92.141282 -266.635814) (xy 92.187584 -266.659412)
			(xy 92.229625 -266.689962) (xy 92.266369 -266.726712) (xy 92.296913 -266.768757) (xy 92.320504 -266.815062)
			(xy 92.336562 -266.864487) (xy 92.344691 -266.915816) (xy 92.344691 -266.967775) (xy 92.624403 -266.967775)
			(xy 92.624403 -266.915841) (xy 92.632528 -266.864546) (xy 92.648576 -266.815153) (xy 92.672154 -266.768879)
			(xy 92.70268 -266.726863) (xy 92.739403 -266.69014) (xy 92.781419 -266.659614) (xy 92.827693 -266.636036)
			(xy 92.877086 -266.619988) (xy 92.928381 -266.611863) (xy 92.980315 -266.611863) (xy 93.03161 -266.619988)
			(xy 93.081003 -266.636036) (xy 93.127277 -266.659614) (xy 93.169293 -266.69014) (xy 93.206016 -266.726863)
			(xy 93.236542 -266.768879) (xy 93.26012 -266.815153) (xy 93.276168 -266.864546) (xy 93.284293 -266.915841)
			(xy 93.284802 -266.941808) (xy 93.284293 -266.967775) (xy 93.564203 -266.967775) (xy 93.564203 -266.915841)
			(xy 93.572328 -266.864546) (xy 93.588376 -266.815153) (xy 93.611954 -266.768879) (xy 93.64248 -266.726863)
			(xy 93.679203 -266.69014) (xy 93.721219 -266.659614) (xy 93.767493 -266.636036) (xy 93.816886 -266.619988)
			(xy 93.868181 -266.611863) (xy 93.920115 -266.611863) (xy 93.97141 -266.619988) (xy 94.020803 -266.636036)
			(xy 94.067077 -266.659614) (xy 94.109093 -266.69014) (xy 94.145816 -266.726863) (xy 94.176342 -266.768879)
			(xy 94.19992 -266.815153) (xy 94.215968 -266.864546) (xy 94.224093 -266.915841) (xy 94.224602 -266.941808)
			(xy 94.224093 -266.967775) (xy 94.504003 -266.967775) (xy 94.504003 -266.915841) (xy 94.512128 -266.864546)
			(xy 94.528176 -266.815153) (xy 94.551754 -266.768879) (xy 94.58228 -266.726863) (xy 94.619003 -266.69014)
			(xy 94.661019 -266.659614) (xy 94.707293 -266.636036) (xy 94.756686 -266.619988) (xy 94.807981 -266.611863)
			(xy 94.859915 -266.611863) (xy 94.91121 -266.619988) (xy 94.960603 -266.636036) (xy 95.006877 -266.659614)
			(xy 95.048893 -266.69014) (xy 95.085616 -266.726863) (xy 95.116142 -266.768879) (xy 95.13972 -266.815153)
			(xy 95.155768 -266.864546) (xy 95.163893 -266.915841) (xy 95.164402 -266.941808) (xy 95.163893 -266.967775)
			(xy 95.443803 -266.967775) (xy 95.443803 -266.915841) (xy 95.451928 -266.864546) (xy 95.467976 -266.815153)
			(xy 95.491554 -266.768879) (xy 95.52208 -266.726863) (xy 95.558803 -266.69014) (xy 95.600819 -266.659614)
			(xy 95.647093 -266.636036) (xy 95.696486 -266.619988) (xy 95.747781 -266.611863) (xy 95.799715 -266.611863)
			(xy 95.85101 -266.619988) (xy 95.900403 -266.636036) (xy 95.946677 -266.659614) (xy 95.988693 -266.69014)
			(xy 96.025416 -266.726863) (xy 96.055942 -266.768879) (xy 96.07952 -266.815153) (xy 96.095568 -266.864546)
			(xy 96.103693 -266.915841) (xy 96.104202 -266.941808) (xy 96.103693 -266.967775) (xy 96.383603 -266.967775)
			(xy 96.383603 -266.915841) (xy 96.391728 -266.864546) (xy 96.407776 -266.815153) (xy 96.431354 -266.768879)
			(xy 96.46188 -266.726863) (xy 96.498603 -266.69014) (xy 96.540619 -266.659614) (xy 96.586893 -266.636036)
			(xy 96.636286 -266.619988) (xy 96.687581 -266.611863) (xy 96.739515 -266.611863) (xy 96.79081 -266.619988)
			(xy 96.840203 -266.636036) (xy 96.886477 -266.659614) (xy 96.928493 -266.69014) (xy 96.965216 -266.726863)
			(xy 96.995742 -266.768879) (xy 97.01932 -266.815153) (xy 97.035368 -266.864546) (xy 97.043493 -266.915841)
			(xy 97.044002 -266.941808) (xy 97.043493 -266.967775) (xy 97.323149 -266.967775) (xy 97.323149 -266.915841)
			(xy 97.331274 -266.864546) (xy 97.347322 -266.815153) (xy 97.3709 -266.768879) (xy 97.401426 -266.726863)
			(xy 97.438149 -266.69014) (xy 97.480165 -266.659614) (xy 97.526439 -266.636036) (xy 97.575832 -266.619988)
			(xy 97.627127 -266.611863) (xy 97.679061 -266.611863) (xy 97.730356 -266.619988) (xy 97.779749 -266.636036)
			(xy 97.826023 -266.659614) (xy 97.868039 -266.69014) (xy 97.904762 -266.726863) (xy 97.935288 -266.768879)
			(xy 97.958866 -266.815153) (xy 97.974914 -266.864546) (xy 97.983039 -266.915841) (xy 97.983548 -266.941808)
			(xy 97.983039 -266.967775) (xy 98.263203 -266.967775) (xy 98.263203 -266.915841) (xy 98.271328 -266.864546)
			(xy 98.287376 -266.815153) (xy 98.310954 -266.768879) (xy 98.34148 -266.726863) (xy 98.378203 -266.69014)
			(xy 98.420219 -266.659614) (xy 98.466493 -266.636036) (xy 98.515886 -266.619988) (xy 98.567181 -266.611863)
			(xy 98.619115 -266.611863) (xy 98.67041 -266.619988) (xy 98.719803 -266.636036) (xy 98.766077 -266.659614)
			(xy 98.808093 -266.69014) (xy 98.844816 -266.726863) (xy 98.875342 -266.768879) (xy 98.89892 -266.815153)
			(xy 98.914968 -266.864546) (xy 98.923093 -266.915841) (xy 98.923602 -266.941808) (xy 98.923093 -266.967775)
			(xy 99.203003 -266.967775) (xy 99.203003 -266.915841) (xy 99.211128 -266.864546) (xy 99.227176 -266.815153)
			(xy 99.250754 -266.768879) (xy 99.28128 -266.726863) (xy 99.318003 -266.69014) (xy 99.360019 -266.659614)
			(xy 99.406293 -266.636036) (xy 99.455686 -266.619988) (xy 99.506981 -266.611863) (xy 99.558915 -266.611863)
			(xy 99.61021 -266.619988) (xy 99.659603 -266.636036) (xy 99.705877 -266.659614) (xy 99.747893 -266.69014)
			(xy 99.784616 -266.726863) (xy 99.815142 -266.768879) (xy 99.83872 -266.815153) (xy 99.854768 -266.864546)
			(xy 99.862893 -266.915841) (xy 99.863402 -266.941808) (xy 99.862893 -266.967775) (xy 100.142803 -266.967775)
			(xy 100.142803 -266.915841) (xy 100.150928 -266.864546) (xy 100.166976 -266.815153) (xy 100.190554 -266.768879)
			(xy 100.22108 -266.726863) (xy 100.257803 -266.69014) (xy 100.299819 -266.659614) (xy 100.346093 -266.636036)
			(xy 100.395486 -266.619988) (xy 100.446781 -266.611863) (xy 100.498715 -266.611863) (xy 100.55001 -266.619988)
			(xy 100.599403 -266.636036) (xy 100.645677 -266.659614) (xy 100.687693 -266.69014) (xy 100.724416 -266.726863)
			(xy 100.754942 -266.768879) (xy 100.77852 -266.815153) (xy 100.794568 -266.864546) (xy 100.802693 -266.915841)
			(xy 100.803202 -266.941808) (xy 100.802693 -266.967775) (xy 101.082603 -266.967775) (xy 101.082603 -266.915841)
			(xy 101.090728 -266.864546) (xy 101.106776 -266.815153) (xy 101.130354 -266.768879) (xy 101.16088 -266.726863)
			(xy 101.197603 -266.69014) (xy 101.239619 -266.659614) (xy 101.285893 -266.636036) (xy 101.335286 -266.619988)
			(xy 101.386581 -266.611863) (xy 101.438515 -266.611863) (xy 101.48981 -266.619988) (xy 101.539203 -266.636036)
			(xy 101.585477 -266.659614) (xy 101.627493 -266.69014) (xy 101.664216 -266.726863) (xy 101.694742 -266.768879)
			(xy 101.71832 -266.815153) (xy 101.734368 -266.864546) (xy 101.742493 -266.915841) (xy 101.743002 -266.941808)
			(xy 101.742493 -266.967775) (xy 102.022403 -266.967775) (xy 102.022403 -266.915841) (xy 102.030528 -266.864546)
			(xy 102.046576 -266.815153) (xy 102.070154 -266.768879) (xy 102.10068 -266.726863) (xy 102.137403 -266.69014)
			(xy 102.179419 -266.659614) (xy 102.225693 -266.636036) (xy 102.275086 -266.619988) (xy 102.326381 -266.611863)
			(xy 102.378315 -266.611863) (xy 102.42961 -266.619988) (xy 102.479003 -266.636036) (xy 102.525277 -266.659614)
			(xy 102.567293 -266.69014) (xy 102.604016 -266.726863) (xy 102.634542 -266.768879) (xy 102.65812 -266.815153)
			(xy 102.674168 -266.864546) (xy 102.682293 -266.915841) (xy 102.682802 -266.941808) (xy 102.682293 -266.967775)
			(xy 102.962203 -266.967775) (xy 102.962203 -266.915841) (xy 102.970328 -266.864546) (xy 102.986376 -266.815153)
			(xy 103.009954 -266.768879) (xy 103.04048 -266.726863) (xy 103.077203 -266.69014) (xy 103.119219 -266.659614)
			(xy 103.165493 -266.636036) (xy 103.214886 -266.619988) (xy 103.266181 -266.611863) (xy 103.318115 -266.611863)
			(xy 103.36941 -266.619988) (xy 103.418803 -266.636036) (xy 103.465077 -266.659614) (xy 103.507093 -266.69014)
			(xy 103.543816 -266.726863) (xy 103.574342 -266.768879) (xy 103.59792 -266.815153) (xy 103.613968 -266.864546)
			(xy 103.622093 -266.915841) (xy 103.622602 -266.941808) (xy 103.622093 -266.967775) (xy 103.613968 -267.01907)
			(xy 103.59792 -267.068463) (xy 103.574342 -267.114737) (xy 103.543816 -267.156753) (xy 103.507093 -267.193476)
			(xy 103.465077 -267.224002) (xy 103.418803 -267.24758) (xy 103.36941 -267.263628) (xy 103.318115 -267.271753)
			(xy 103.266181 -267.271753) (xy 103.214886 -267.263628) (xy 103.165493 -267.24758) (xy 103.119219 -267.224002)
			(xy 103.077203 -267.193476) (xy 103.04048 -267.156753) (xy 103.009954 -267.114737) (xy 102.986376 -267.068463)
			(xy 102.970328 -267.01907) (xy 102.962203 -266.967775) (xy 102.682293 -266.967775) (xy 102.674168 -267.01907)
			(xy 102.65812 -267.068463) (xy 102.634542 -267.114737) (xy 102.604016 -267.156753) (xy 102.567293 -267.193476)
			(xy 102.525277 -267.224002) (xy 102.479003 -267.24758) (xy 102.42961 -267.263628) (xy 102.378315 -267.271753)
			(xy 102.326381 -267.271753) (xy 102.275086 -267.263628) (xy 102.225693 -267.24758) (xy 102.179419 -267.224002)
			(xy 102.137403 -267.193476) (xy 102.10068 -267.156753) (xy 102.070154 -267.114737) (xy 102.046576 -267.068463)
			(xy 102.030528 -267.01907) (xy 102.022403 -266.967775) (xy 101.742493 -266.967775) (xy 101.734368 -267.01907)
			(xy 101.71832 -267.068463) (xy 101.694742 -267.114737) (xy 101.664216 -267.156753) (xy 101.627493 -267.193476)
			(xy 101.585477 -267.224002) (xy 101.539203 -267.24758) (xy 101.48981 -267.263628) (xy 101.438515 -267.271753)
			(xy 101.386581 -267.271753) (xy 101.335286 -267.263628) (xy 101.285893 -267.24758) (xy 101.239619 -267.224002)
			(xy 101.197603 -267.193476) (xy 101.16088 -267.156753) (xy 101.130354 -267.114737) (xy 101.106776 -267.068463)
			(xy 101.090728 -267.01907) (xy 101.082603 -266.967775) (xy 100.802693 -266.967775) (xy 100.794568 -267.01907)
			(xy 100.77852 -267.068463) (xy 100.754942 -267.114737) (xy 100.724416 -267.156753) (xy 100.687693 -267.193476)
			(xy 100.645677 -267.224002) (xy 100.599403 -267.24758) (xy 100.55001 -267.263628) (xy 100.498715 -267.271753)
			(xy 100.446781 -267.271753) (xy 100.395486 -267.263628) (xy 100.346093 -267.24758) (xy 100.299819 -267.224002)
			(xy 100.257803 -267.193476) (xy 100.22108 -267.156753) (xy 100.190554 -267.114737) (xy 100.166976 -267.068463)
			(xy 100.150928 -267.01907) (xy 100.142803 -266.967775) (xy 99.862893 -266.967775) (xy 99.854768 -267.01907)
			(xy 99.83872 -267.068463) (xy 99.815142 -267.114737) (xy 99.784616 -267.156753) (xy 99.747893 -267.193476)
			(xy 99.705877 -267.224002) (xy 99.659603 -267.24758) (xy 99.61021 -267.263628) (xy 99.558915 -267.271753)
			(xy 99.506981 -267.271753) (xy 99.455686 -267.263628) (xy 99.406293 -267.24758) (xy 99.360019 -267.224002)
			(xy 99.318003 -267.193476) (xy 99.28128 -267.156753) (xy 99.250754 -267.114737) (xy 99.227176 -267.068463)
			(xy 99.211128 -267.01907) (xy 99.203003 -266.967775) (xy 98.923093 -266.967775) (xy 98.914968 -267.01907)
			(xy 98.89892 -267.068463) (xy 98.875342 -267.114737) (xy 98.844816 -267.156753) (xy 98.808093 -267.193476)
			(xy 98.766077 -267.224002) (xy 98.719803 -267.24758) (xy 98.67041 -267.263628) (xy 98.619115 -267.271753)
			(xy 98.567181 -267.271753) (xy 98.515886 -267.263628) (xy 98.466493 -267.24758) (xy 98.420219 -267.224002)
			(xy 98.378203 -267.193476) (xy 98.34148 -267.156753) (xy 98.310954 -267.114737) (xy 98.287376 -267.068463)
			(xy 98.271328 -267.01907) (xy 98.263203 -266.967775) (xy 97.983039 -266.967775) (xy 97.974914 -267.01907)
			(xy 97.958866 -267.068463) (xy 97.935288 -267.114737) (xy 97.904762 -267.156753) (xy 97.868039 -267.193476)
			(xy 97.826023 -267.224002) (xy 97.779749 -267.24758) (xy 97.730356 -267.263628) (xy 97.679061 -267.271753)
			(xy 97.627127 -267.271753) (xy 97.575832 -267.263628) (xy 97.526439 -267.24758) (xy 97.480165 -267.224002)
			(xy 97.438149 -267.193476) (xy 97.401426 -267.156753) (xy 97.3709 -267.114737) (xy 97.347322 -267.068463)
			(xy 97.331274 -267.01907) (xy 97.323149 -266.967775) (xy 97.043493 -266.967775) (xy 97.035368 -267.01907)
			(xy 97.01932 -267.068463) (xy 96.995742 -267.114737) (xy 96.965216 -267.156753) (xy 96.928493 -267.193476)
			(xy 96.886477 -267.224002) (xy 96.840203 -267.24758) (xy 96.79081 -267.263628) (xy 96.739515 -267.271753)
			(xy 96.687581 -267.271753) (xy 96.636286 -267.263628) (xy 96.586893 -267.24758) (xy 96.540619 -267.224002)
			(xy 96.498603 -267.193476) (xy 96.46188 -267.156753) (xy 96.431354 -267.114737) (xy 96.407776 -267.068463)
			(xy 96.391728 -267.01907) (xy 96.383603 -266.967775) (xy 96.103693 -266.967775) (xy 96.095568 -267.01907)
			(xy 96.07952 -267.068463) (xy 96.055942 -267.114737) (xy 96.025416 -267.156753) (xy 95.988693 -267.193476)
			(xy 95.946677 -267.224002) (xy 95.900403 -267.24758) (xy 95.85101 -267.263628) (xy 95.799715 -267.271753)
			(xy 95.747781 -267.271753) (xy 95.696486 -267.263628) (xy 95.647093 -267.24758) (xy 95.600819 -267.224002)
			(xy 95.558803 -267.193476) (xy 95.52208 -267.156753) (xy 95.491554 -267.114737) (xy 95.467976 -267.068463)
			(xy 95.451928 -267.01907) (xy 95.443803 -266.967775) (xy 95.163893 -266.967775) (xy 95.155768 -267.01907)
			(xy 95.13972 -267.068463) (xy 95.116142 -267.114737) (xy 95.085616 -267.156753) (xy 95.048893 -267.193476)
			(xy 95.006877 -267.224002) (xy 94.960603 -267.24758) (xy 94.91121 -267.263628) (xy 94.859915 -267.271753)
			(xy 94.807981 -267.271753) (xy 94.756686 -267.263628) (xy 94.707293 -267.24758) (xy 94.661019 -267.224002)
			(xy 94.619003 -267.193476) (xy 94.58228 -267.156753) (xy 94.551754 -267.114737) (xy 94.528176 -267.068463)
			(xy 94.512128 -267.01907) (xy 94.504003 -266.967775) (xy 94.224093 -266.967775) (xy 94.215968 -267.01907)
			(xy 94.19992 -267.068463) (xy 94.176342 -267.114737) (xy 94.145816 -267.156753) (xy 94.109093 -267.193476)
			(xy 94.067077 -267.224002) (xy 94.020803 -267.24758) (xy 93.97141 -267.263628) (xy 93.920115 -267.271753)
			(xy 93.868181 -267.271753) (xy 93.816886 -267.263628) (xy 93.767493 -267.24758) (xy 93.721219 -267.224002)
			(xy 93.679203 -267.193476) (xy 93.64248 -267.156753) (xy 93.611954 -267.114737) (xy 93.588376 -267.068463)
			(xy 93.572328 -267.01907) (xy 93.564203 -266.967775) (xy 93.284293 -266.967775) (xy 93.276168 -267.01907)
			(xy 93.26012 -267.068463) (xy 93.236542 -267.114737) (xy 93.206016 -267.156753) (xy 93.169293 -267.193476)
			(xy 93.127277 -267.224002) (xy 93.081003 -267.24758) (xy 93.03161 -267.263628) (xy 92.980315 -267.271753)
			(xy 92.928381 -267.271753) (xy 92.877086 -267.263628) (xy 92.827693 -267.24758) (xy 92.781419 -267.224002)
			(xy 92.739403 -267.193476) (xy 92.70268 -267.156753) (xy 92.672154 -267.114737) (xy 92.648576 -267.068463)
			(xy 92.632528 -267.01907) (xy 92.624403 -266.967775) (xy 92.344691 -266.967775) (xy 92.344691 -266.967784)
			(xy 92.336562 -267.019113) (xy 92.320504 -267.068538) (xy 92.296913 -267.114843) (xy 92.266369 -267.156888)
			(xy 92.229625 -267.193638) (xy 92.187584 -267.224188) (xy 92.141282 -267.247786) (xy 92.09186 -267.263851)
			(xy 92.040532 -267.271987) (xy 92.014548 -267.272516) (xy 91.991674 -267.272133) (xy 91.946361 -267.265838)
			(xy 91.902347 -267.25336) (xy 91.860471 -267.234939) (xy 91.840812 -267.22324) (xy 91.840558 -267.222986)
			(xy 91.833071 -267.218801) (xy 91.816298 -267.215269) (xy 91.799315 -267.21759) (xy 91.791536 -267.221208)
			(xy 91.751658 -267.243306) (xy 91.713304 -267.264642) (xy 91.705725 -267.269284) (xy 91.694184 -267.282785)
			(xy 91.688038 -267.299449) (xy 91.68765 -267.30833) (xy 91.68765 -267.427964) (xy 91.712034 -267.470382)
			(xy 91.718638 -267.4747) (xy 91.740364 -267.48875) (xy 91.779564 -267.522514) (xy 91.81303 -267.56197)
			(xy 91.839945 -267.606154) (xy 91.859654 -267.653989) (xy 91.871676 -267.70431) (xy 91.875717 -267.755888)
			(xy 91.873685 -267.781845) (xy 92.154249 -267.781845) (xy 92.154249 -267.729911) (xy 92.162374 -267.678616)
			(xy 92.178422 -267.629223) (xy 92.202 -267.582949) (xy 92.232526 -267.540933) (xy 92.269249 -267.50421)
			(xy 92.311265 -267.473684) (xy 92.357539 -267.450106) (xy 92.406932 -267.434058) (xy 92.458227 -267.425933)
			(xy 92.510161 -267.425933) (xy 92.561456 -267.434058) (xy 92.610849 -267.450106) (xy 92.657123 -267.473684)
			(xy 92.699139 -267.50421) (xy 92.735862 -267.540933) (xy 92.766388 -267.582949) (xy 92.789966 -267.629223)
			(xy 92.806014 -267.678616) (xy 92.814139 -267.729911) (xy 92.814648 -267.755878) (xy 92.814139 -267.781845)
			(xy 93.094049 -267.781845) (xy 93.094049 -267.729911) (xy 93.102174 -267.678616) (xy 93.118222 -267.629223)
			(xy 93.1418 -267.582949) (xy 93.172326 -267.540933) (xy 93.209049 -267.50421) (xy 93.251065 -267.473684)
			(xy 93.297339 -267.450106) (xy 93.346732 -267.434058) (xy 93.398027 -267.425933) (xy 93.449961 -267.425933)
			(xy 93.501256 -267.434058) (xy 93.550649 -267.450106) (xy 93.596923 -267.473684) (xy 93.638939 -267.50421)
			(xy 93.675662 -267.540933) (xy 93.706188 -267.582949) (xy 93.729766 -267.629223) (xy 93.745814 -267.678616)
			(xy 93.753939 -267.729911) (xy 93.754448 -267.755878) (xy 93.753939 -267.781845) (xy 94.033849 -267.781845)
			(xy 94.033849 -267.729911) (xy 94.041974 -267.678616) (xy 94.058022 -267.629223) (xy 94.0816 -267.582949)
			(xy 94.112126 -267.540933) (xy 94.148849 -267.50421) (xy 94.190865 -267.473684) (xy 94.237139 -267.450106)
			(xy 94.286532 -267.434058) (xy 94.337827 -267.425933) (xy 94.389761 -267.425933) (xy 94.441056 -267.434058)
			(xy 94.490449 -267.450106) (xy 94.536723 -267.473684) (xy 94.578739 -267.50421) (xy 94.615462 -267.540933)
			(xy 94.645988 -267.582949) (xy 94.669566 -267.629223) (xy 94.685614 -267.678616) (xy 94.693739 -267.729911)
			(xy 94.694248 -267.755878) (xy 94.693739 -267.781845) (xy 94.973649 -267.781845) (xy 94.973649 -267.729911)
			(xy 94.981774 -267.678616) (xy 94.997822 -267.629223) (xy 95.0214 -267.582949) (xy 95.051926 -267.540933)
			(xy 95.088649 -267.50421) (xy 95.130665 -267.473684) (xy 95.176939 -267.450106) (xy 95.226332 -267.434058)
			(xy 95.277627 -267.425933) (xy 95.329561 -267.425933) (xy 95.380856 -267.434058) (xy 95.430249 -267.450106)
			(xy 95.476523 -267.473684) (xy 95.518539 -267.50421) (xy 95.555262 -267.540933) (xy 95.585788 -267.582949)
			(xy 95.609366 -267.629223) (xy 95.625414 -267.678616) (xy 95.633539 -267.729911) (xy 95.634048 -267.755878)
			(xy 95.633539 -267.781845) (xy 95.913449 -267.781845) (xy 95.913449 -267.729911) (xy 95.921574 -267.678616)
			(xy 95.937622 -267.629223) (xy 95.9612 -267.582949) (xy 95.991726 -267.540933) (xy 96.028449 -267.50421)
			(xy 96.070465 -267.473684) (xy 96.116739 -267.450106) (xy 96.166132 -267.434058) (xy 96.217427 -267.425933)
			(xy 96.269361 -267.425933) (xy 96.320656 -267.434058) (xy 96.370049 -267.450106) (xy 96.416323 -267.473684)
			(xy 96.458339 -267.50421) (xy 96.495062 -267.540933) (xy 96.525588 -267.582949) (xy 96.549166 -267.629223)
			(xy 96.565214 -267.678616) (xy 96.573339 -267.729911) (xy 96.573848 -267.755878) (xy 96.573339 -267.781845)
			(xy 96.853503 -267.781845) (xy 96.853503 -267.729911) (xy 96.861628 -267.678616) (xy 96.877676 -267.629223)
			(xy 96.901254 -267.582949) (xy 96.93178 -267.540933) (xy 96.968503 -267.50421) (xy 97.010519 -267.473684)
			(xy 97.056793 -267.450106) (xy 97.106186 -267.434058) (xy 97.157481 -267.425933) (xy 97.209415 -267.425933)
			(xy 97.26071 -267.434058) (xy 97.310103 -267.450106) (xy 97.356377 -267.473684) (xy 97.398393 -267.50421)
			(xy 97.435116 -267.540933) (xy 97.465642 -267.582949) (xy 97.48922 -267.629223) (xy 97.505268 -267.678616)
			(xy 97.513393 -267.729911) (xy 97.513902 -267.755878) (xy 97.513393 -267.781845) (xy 97.793049 -267.781845)
			(xy 97.793049 -267.729911) (xy 97.801174 -267.678616) (xy 97.817222 -267.629223) (xy 97.8408 -267.582949)
			(xy 97.871326 -267.540933) (xy 97.908049 -267.50421) (xy 97.950065 -267.473684) (xy 97.996339 -267.450106)
			(xy 98.045732 -267.434058) (xy 98.097027 -267.425933) (xy 98.148961 -267.425933) (xy 98.200256 -267.434058)
			(xy 98.249649 -267.450106) (xy 98.295923 -267.473684) (xy 98.337939 -267.50421) (xy 98.374662 -267.540933)
			(xy 98.405188 -267.582949) (xy 98.428766 -267.629223) (xy 98.444814 -267.678616) (xy 98.452939 -267.729911)
			(xy 98.453448 -267.755878) (xy 98.452939 -267.781845) (xy 98.732849 -267.781845) (xy 98.732849 -267.729911)
			(xy 98.740974 -267.678616) (xy 98.757022 -267.629223) (xy 98.7806 -267.582949) (xy 98.811126 -267.540933)
			(xy 98.847849 -267.50421) (xy 98.889865 -267.473684) (xy 98.936139 -267.450106) (xy 98.985532 -267.434058)
			(xy 99.036827 -267.425933) (xy 99.088761 -267.425933) (xy 99.140056 -267.434058) (xy 99.189449 -267.450106)
			(xy 99.235723 -267.473684) (xy 99.277739 -267.50421) (xy 99.314462 -267.540933) (xy 99.344988 -267.582949)
			(xy 99.368566 -267.629223) (xy 99.384614 -267.678616) (xy 99.392739 -267.729911) (xy 99.393248 -267.755878)
			(xy 99.392739 -267.781845) (xy 99.672649 -267.781845) (xy 99.672649 -267.729911) (xy 99.680774 -267.678616)
			(xy 99.696822 -267.629223) (xy 99.7204 -267.582949) (xy 99.750926 -267.540933) (xy 99.787649 -267.50421)
			(xy 99.829665 -267.473684) (xy 99.875939 -267.450106) (xy 99.925332 -267.434058) (xy 99.976627 -267.425933)
			(xy 100.028561 -267.425933) (xy 100.079856 -267.434058) (xy 100.129249 -267.450106) (xy 100.175523 -267.473684)
			(xy 100.217539 -267.50421) (xy 100.254262 -267.540933) (xy 100.284788 -267.582949) (xy 100.308366 -267.629223)
			(xy 100.324414 -267.678616) (xy 100.332539 -267.729911) (xy 100.333048 -267.755878) (xy 100.332539 -267.781845)
			(xy 100.612449 -267.781845) (xy 100.612449 -267.729911) (xy 100.620574 -267.678616) (xy 100.636622 -267.629223)
			(xy 100.6602 -267.582949) (xy 100.690726 -267.540933) (xy 100.727449 -267.50421) (xy 100.769465 -267.473684)
			(xy 100.815739 -267.450106) (xy 100.865132 -267.434058) (xy 100.916427 -267.425933) (xy 100.968361 -267.425933)
			(xy 101.019656 -267.434058) (xy 101.069049 -267.450106) (xy 101.115323 -267.473684) (xy 101.157339 -267.50421)
			(xy 101.194062 -267.540933) (xy 101.224588 -267.582949) (xy 101.248166 -267.629223) (xy 101.264214 -267.678616)
			(xy 101.272339 -267.729911) (xy 101.272848 -267.755878) (xy 101.272339 -267.781845) (xy 101.552249 -267.781845)
			(xy 101.552249 -267.729911) (xy 101.560374 -267.678616) (xy 101.576422 -267.629223) (xy 101.6 -267.582949)
			(xy 101.630526 -267.540933) (xy 101.667249 -267.50421) (xy 101.709265 -267.473684) (xy 101.755539 -267.450106)
			(xy 101.804932 -267.434058) (xy 101.856227 -267.425933) (xy 101.908161 -267.425933) (xy 101.959456 -267.434058)
			(xy 102.008849 -267.450106) (xy 102.055123 -267.473684) (xy 102.097139 -267.50421) (xy 102.133862 -267.540933)
			(xy 102.164388 -267.582949) (xy 102.187966 -267.629223) (xy 102.204014 -267.678616) (xy 102.212139 -267.729911)
			(xy 102.212648 -267.755878) (xy 102.212139 -267.781845) (xy 102.492049 -267.781845) (xy 102.492049 -267.729911)
			(xy 102.500174 -267.678616) (xy 102.516222 -267.629223) (xy 102.5398 -267.582949) (xy 102.570326 -267.540933)
			(xy 102.607049 -267.50421) (xy 102.649065 -267.473684) (xy 102.695339 -267.450106) (xy 102.744732 -267.434058)
			(xy 102.796027 -267.425933) (xy 102.847961 -267.425933) (xy 102.899256 -267.434058) (xy 102.948649 -267.450106)
			(xy 102.994923 -267.473684) (xy 103.036939 -267.50421) (xy 103.073662 -267.540933) (xy 103.104188 -267.582949)
			(xy 103.127766 -267.629223) (xy 103.143814 -267.678616) (xy 103.151939 -267.729911) (xy 103.152448 -267.755878)
			(xy 103.151939 -267.781845) (xy 103.431849 -267.781845) (xy 103.431849 -267.729911) (xy 103.439974 -267.678616)
			(xy 103.456022 -267.629223) (xy 103.4796 -267.582949) (xy 103.510126 -267.540933) (xy 103.546849 -267.50421)
			(xy 103.588865 -267.473684) (xy 103.635139 -267.450106) (xy 103.684532 -267.434058) (xy 103.735827 -267.425933)
			(xy 103.787761 -267.425933) (xy 103.839056 -267.434058) (xy 103.888449 -267.450106) (xy 103.934723 -267.473684)
			(xy 103.976739 -267.50421) (xy 104.013462 -267.540933) (xy 104.043988 -267.582949) (xy 104.067566 -267.629223)
			(xy 104.083614 -267.678616) (xy 104.091739 -267.729911) (xy 104.092248 -267.755878) (xy 104.091739 -267.781845)
			(xy 104.083614 -267.83314) (xy 104.067566 -267.882533) (xy 104.043988 -267.928807) (xy 104.013462 -267.970823)
			(xy 103.976739 -268.007546) (xy 103.934723 -268.038072) (xy 103.888449 -268.06165) (xy 103.839056 -268.077698)
			(xy 103.787761 -268.085823) (xy 103.735827 -268.085823) (xy 103.684532 -268.077698) (xy 103.635139 -268.06165)
			(xy 103.588865 -268.038072) (xy 103.546849 -268.007546) (xy 103.510126 -267.970823) (xy 103.4796 -267.928807)
			(xy 103.456022 -267.882533) (xy 103.439974 -267.83314) (xy 103.431849 -267.781845) (xy 103.151939 -267.781845)
			(xy 103.143814 -267.83314) (xy 103.127766 -267.882533) (xy 103.104188 -267.928807) (xy 103.073662 -267.970823)
			(xy 103.036939 -268.007546) (xy 102.994923 -268.038072) (xy 102.948649 -268.06165) (xy 102.899256 -268.077698)
			(xy 102.847961 -268.085823) (xy 102.796027 -268.085823) (xy 102.744732 -268.077698) (xy 102.695339 -268.06165)
			(xy 102.649065 -268.038072) (xy 102.607049 -268.007546) (xy 102.570326 -267.970823) (xy 102.5398 -267.928807)
			(xy 102.516222 -267.882533) (xy 102.500174 -267.83314) (xy 102.492049 -267.781845) (xy 102.212139 -267.781845)
			(xy 102.204014 -267.83314) (xy 102.187966 -267.882533) (xy 102.164388 -267.928807) (xy 102.133862 -267.970823)
			(xy 102.097139 -268.007546) (xy 102.055123 -268.038072) (xy 102.008849 -268.06165) (xy 101.959456 -268.077698)
			(xy 101.908161 -268.085823) (xy 101.856227 -268.085823) (xy 101.804932 -268.077698) (xy 101.755539 -268.06165)
			(xy 101.709265 -268.038072) (xy 101.667249 -268.007546) (xy 101.630526 -267.970823) (xy 101.6 -267.928807)
			(xy 101.576422 -267.882533) (xy 101.560374 -267.83314) (xy 101.552249 -267.781845) (xy 101.272339 -267.781845)
			(xy 101.264214 -267.83314) (xy 101.248166 -267.882533) (xy 101.224588 -267.928807) (xy 101.194062 -267.970823)
			(xy 101.157339 -268.007546) (xy 101.115323 -268.038072) (xy 101.069049 -268.06165) (xy 101.019656 -268.077698)
			(xy 100.968361 -268.085823) (xy 100.916427 -268.085823) (xy 100.865132 -268.077698) (xy 100.815739 -268.06165)
			(xy 100.769465 -268.038072) (xy 100.727449 -268.007546) (xy 100.690726 -267.970823) (xy 100.6602 -267.928807)
			(xy 100.636622 -267.882533) (xy 100.620574 -267.83314) (xy 100.612449 -267.781845) (xy 100.332539 -267.781845)
			(xy 100.324414 -267.83314) (xy 100.308366 -267.882533) (xy 100.284788 -267.928807) (xy 100.254262 -267.970823)
			(xy 100.217539 -268.007546) (xy 100.175523 -268.038072) (xy 100.129249 -268.06165) (xy 100.079856 -268.077698)
			(xy 100.028561 -268.085823) (xy 99.976627 -268.085823) (xy 99.925332 -268.077698) (xy 99.875939 -268.06165)
			(xy 99.829665 -268.038072) (xy 99.787649 -268.007546) (xy 99.750926 -267.970823) (xy 99.7204 -267.928807)
			(xy 99.696822 -267.882533) (xy 99.680774 -267.83314) (xy 99.672649 -267.781845) (xy 99.392739 -267.781845)
			(xy 99.384614 -267.83314) (xy 99.368566 -267.882533) (xy 99.344988 -267.928807) (xy 99.314462 -267.970823)
			(xy 99.277739 -268.007546) (xy 99.235723 -268.038072) (xy 99.189449 -268.06165) (xy 99.140056 -268.077698)
			(xy 99.088761 -268.085823) (xy 99.036827 -268.085823) (xy 98.985532 -268.077698) (xy 98.936139 -268.06165)
			(xy 98.889865 -268.038072) (xy 98.847849 -268.007546) (xy 98.811126 -267.970823) (xy 98.7806 -267.928807)
			(xy 98.757022 -267.882533) (xy 98.740974 -267.83314) (xy 98.732849 -267.781845) (xy 98.452939 -267.781845)
			(xy 98.444814 -267.83314) (xy 98.428766 -267.882533) (xy 98.405188 -267.928807) (xy 98.374662 -267.970823)
			(xy 98.337939 -268.007546) (xy 98.295923 -268.038072) (xy 98.249649 -268.06165) (xy 98.200256 -268.077698)
			(xy 98.148961 -268.085823) (xy 98.097027 -268.085823) (xy 98.045732 -268.077698) (xy 97.996339 -268.06165)
			(xy 97.950065 -268.038072) (xy 97.908049 -268.007546) (xy 97.871326 -267.970823) (xy 97.8408 -267.928807)
			(xy 97.817222 -267.882533) (xy 97.801174 -267.83314) (xy 97.793049 -267.781845) (xy 97.513393 -267.781845)
			(xy 97.505268 -267.83314) (xy 97.48922 -267.882533) (xy 97.465642 -267.928807) (xy 97.435116 -267.970823)
			(xy 97.398393 -268.007546) (xy 97.356377 -268.038072) (xy 97.310103 -268.06165) (xy 97.26071 -268.077698)
			(xy 97.209415 -268.085823) (xy 97.157481 -268.085823) (xy 97.106186 -268.077698) (xy 97.056793 -268.06165)
			(xy 97.010519 -268.038072) (xy 96.968503 -268.007546) (xy 96.93178 -267.970823) (xy 96.901254 -267.928807)
			(xy 96.877676 -267.882533) (xy 96.861628 -267.83314) (xy 96.853503 -267.781845) (xy 96.573339 -267.781845)
			(xy 96.565214 -267.83314) (xy 96.549166 -267.882533) (xy 96.525588 -267.928807) (xy 96.495062 -267.970823)
			(xy 96.458339 -268.007546) (xy 96.416323 -268.038072) (xy 96.370049 -268.06165) (xy 96.320656 -268.077698)
			(xy 96.269361 -268.085823) (xy 96.217427 -268.085823) (xy 96.166132 -268.077698) (xy 96.116739 -268.06165)
			(xy 96.070465 -268.038072) (xy 96.028449 -268.007546) (xy 95.991726 -267.970823) (xy 95.9612 -267.928807)
			(xy 95.937622 -267.882533) (xy 95.921574 -267.83314) (xy 95.913449 -267.781845) (xy 95.633539 -267.781845)
			(xy 95.625414 -267.83314) (xy 95.609366 -267.882533) (xy 95.585788 -267.928807) (xy 95.555262 -267.970823)
			(xy 95.518539 -268.007546) (xy 95.476523 -268.038072) (xy 95.430249 -268.06165) (xy 95.380856 -268.077698)
			(xy 95.329561 -268.085823) (xy 95.277627 -268.085823) (xy 95.226332 -268.077698) (xy 95.176939 -268.06165)
			(xy 95.130665 -268.038072) (xy 95.088649 -268.007546) (xy 95.051926 -267.970823) (xy 95.0214 -267.928807)
			(xy 94.997822 -267.882533) (xy 94.981774 -267.83314) (xy 94.973649 -267.781845) (xy 94.693739 -267.781845)
			(xy 94.685614 -267.83314) (xy 94.669566 -267.882533) (xy 94.645988 -267.928807) (xy 94.615462 -267.970823)
			(xy 94.578739 -268.007546) (xy 94.536723 -268.038072) (xy 94.490449 -268.06165) (xy 94.441056 -268.077698)
			(xy 94.389761 -268.085823) (xy 94.337827 -268.085823) (xy 94.286532 -268.077698) (xy 94.237139 -268.06165)
			(xy 94.190865 -268.038072) (xy 94.148849 -268.007546) (xy 94.112126 -267.970823) (xy 94.0816 -267.928807)
			(xy 94.058022 -267.882533) (xy 94.041974 -267.83314) (xy 94.033849 -267.781845) (xy 93.753939 -267.781845)
			(xy 93.745814 -267.83314) (xy 93.729766 -267.882533) (xy 93.706188 -267.928807) (xy 93.675662 -267.970823)
			(xy 93.638939 -268.007546) (xy 93.596923 -268.038072) (xy 93.550649 -268.06165) (xy 93.501256 -268.077698)
			(xy 93.449961 -268.085823) (xy 93.398027 -268.085823) (xy 93.346732 -268.077698) (xy 93.297339 -268.06165)
			(xy 93.251065 -268.038072) (xy 93.209049 -268.007546) (xy 93.172326 -267.970823) (xy 93.1418 -267.928807)
			(xy 93.118222 -267.882533) (xy 93.102174 -267.83314) (xy 93.094049 -267.781845) (xy 92.814139 -267.781845)
			(xy 92.806014 -267.83314) (xy 92.789966 -267.882533) (xy 92.766388 -267.928807) (xy 92.735862 -267.970823)
			(xy 92.699139 -268.007546) (xy 92.657123 -268.038072) (xy 92.610849 -268.06165) (xy 92.561456 -268.077698)
			(xy 92.510161 -268.085823) (xy 92.458227 -268.085823) (xy 92.406932 -268.077698) (xy 92.357539 -268.06165)
			(xy 92.311265 -268.038072) (xy 92.269249 -268.007546) (xy 92.232526 -267.970823) (xy 92.202 -267.928807)
			(xy 92.178422 -267.882533) (xy 92.162374 -267.83314) (xy 92.154249 -267.781845) (xy 91.873685 -267.781845)
			(xy 91.871679 -267.807467) (xy 91.859661 -267.857789) (xy 91.839956 -267.905626) (xy 91.813043 -267.949812)
			(xy 91.77958 -267.989269) (xy 91.740383 -268.023036) (xy 91.718638 -268.037056) (xy 91.712034 -268.041374)
			(xy 91.68765 -268.083792) (xy 91.68765 -268.203172) (xy 91.688 -268.21206) (xy 91.694151 -268.228736)
			(xy 91.705701 -268.242247) (xy 91.713304 -268.24686) (xy 91.751658 -268.268196) (xy 91.791536 -268.290294)
			(xy 91.799315 -268.293905) (xy 91.816299 -268.296204) (xy 91.833076 -268.292705) (xy 91.840558 -268.288516)
			(xy 91.840812 -268.288262) (xy 91.860482 -268.276582) (xy 91.902354 -268.258155) (xy 91.946364 -268.24567)
			(xy 91.991675 -268.239363) (xy 92.014548 -268.238986) (xy 92.040533 -268.239499) (xy 92.091863 -268.247636)
			(xy 92.141288 -268.263701) (xy 92.187591 -268.2873) (xy 92.229634 -268.317851) (xy 92.26638 -268.354603)
			(xy 92.296925 -268.396649) (xy 92.320517 -268.442957) (xy 92.336575 -268.492384) (xy 92.344705 -268.543715)
			(xy 92.344705 -268.595661) (xy 92.624403 -268.595661) (xy 92.624403 -268.543727) (xy 92.632528 -268.492432)
			(xy 92.648576 -268.443039) (xy 92.672154 -268.396765) (xy 92.70268 -268.354749) (xy 92.739403 -268.318026)
			(xy 92.781419 -268.2875) (xy 92.827693 -268.263922) (xy 92.877086 -268.247874) (xy 92.928381 -268.239749)
			(xy 92.980315 -268.239749) (xy 93.03161 -268.247874) (xy 93.081003 -268.263922) (xy 93.127277 -268.2875)
			(xy 93.169293 -268.318026) (xy 93.206016 -268.354749) (xy 93.236542 -268.396765) (xy 93.26012 -268.443039)
			(xy 93.276168 -268.492432) (xy 93.284293 -268.543727) (xy 93.284802 -268.569694) (xy 93.284293 -268.595661)
			(xy 93.564203 -268.595661) (xy 93.564203 -268.543727) (xy 93.572328 -268.492432) (xy 93.588376 -268.443039)
			(xy 93.611954 -268.396765) (xy 93.64248 -268.354749) (xy 93.679203 -268.318026) (xy 93.721219 -268.2875)
			(xy 93.767493 -268.263922) (xy 93.816886 -268.247874) (xy 93.868181 -268.239749) (xy 93.920115 -268.239749)
			(xy 93.97141 -268.247874) (xy 94.020803 -268.263922) (xy 94.067077 -268.2875) (xy 94.109093 -268.318026)
			(xy 94.145816 -268.354749) (xy 94.176342 -268.396765) (xy 94.19992 -268.443039) (xy 94.215968 -268.492432)
			(xy 94.224093 -268.543727) (xy 94.224602 -268.569694) (xy 94.224093 -268.595661) (xy 94.503749 -268.595661)
			(xy 94.503749 -268.543727) (xy 94.511874 -268.492432) (xy 94.527922 -268.443039) (xy 94.5515 -268.396765)
			(xy 94.582026 -268.354749) (xy 94.618749 -268.318026) (xy 94.660765 -268.2875) (xy 94.707039 -268.263922)
			(xy 94.756432 -268.247874) (xy 94.807727 -268.239749) (xy 94.859661 -268.239749) (xy 94.910956 -268.247874)
			(xy 94.960349 -268.263922) (xy 95.006623 -268.2875) (xy 95.048639 -268.318026) (xy 95.085362 -268.354749)
			(xy 95.115888 -268.396765) (xy 95.139466 -268.443039) (xy 95.155514 -268.492432) (xy 95.163639 -268.543727)
			(xy 95.164148 -268.569694) (xy 95.163639 -268.595661) (xy 95.443803 -268.595661) (xy 95.443803 -268.543727)
			(xy 95.451928 -268.492432) (xy 95.467976 -268.443039) (xy 95.491554 -268.396765) (xy 95.52208 -268.354749)
			(xy 95.558803 -268.318026) (xy 95.600819 -268.2875) (xy 95.647093 -268.263922) (xy 95.696486 -268.247874)
			(xy 95.747781 -268.239749) (xy 95.799715 -268.239749) (xy 95.85101 -268.247874) (xy 95.900403 -268.263922)
			(xy 95.946677 -268.2875) (xy 95.988693 -268.318026) (xy 96.025416 -268.354749) (xy 96.055942 -268.396765)
			(xy 96.07952 -268.443039) (xy 96.095568 -268.492432) (xy 96.103693 -268.543727) (xy 96.104202 -268.569694)
			(xy 96.103693 -268.595661) (xy 96.383603 -268.595661) (xy 96.383603 -268.543727) (xy 96.391728 -268.492432)
			(xy 96.407776 -268.443039) (xy 96.431354 -268.396765) (xy 96.46188 -268.354749) (xy 96.498603 -268.318026)
			(xy 96.540619 -268.2875) (xy 96.586893 -268.263922) (xy 96.636286 -268.247874) (xy 96.687581 -268.239749)
			(xy 96.739515 -268.239749) (xy 96.79081 -268.247874) (xy 96.840203 -268.263922) (xy 96.886477 -268.2875)
			(xy 96.928493 -268.318026) (xy 96.965216 -268.354749) (xy 96.995742 -268.396765) (xy 97.01932 -268.443039)
			(xy 97.035368 -268.492432) (xy 97.043493 -268.543727) (xy 97.044002 -268.569694) (xy 97.043493 -268.595661)
			(xy 97.323403 -268.595661) (xy 97.323403 -268.543727) (xy 97.331528 -268.492432) (xy 97.347576 -268.443039)
			(xy 97.371154 -268.396765) (xy 97.40168 -268.354749) (xy 97.438403 -268.318026) (xy 97.480419 -268.2875)
			(xy 97.526693 -268.263922) (xy 97.576086 -268.247874) (xy 97.627381 -268.239749) (xy 97.679315 -268.239749)
			(xy 97.73061 -268.247874) (xy 97.780003 -268.263922) (xy 97.826277 -268.2875) (xy 97.868293 -268.318026)
			(xy 97.905016 -268.354749) (xy 97.935542 -268.396765) (xy 97.95912 -268.443039) (xy 97.975168 -268.492432)
			(xy 97.983293 -268.543727) (xy 97.983802 -268.569694) (xy 97.983293 -268.595661) (xy 98.263203 -268.595661)
			(xy 98.263203 -268.543727) (xy 98.271328 -268.492432) (xy 98.287376 -268.443039) (xy 98.310954 -268.396765)
			(xy 98.34148 -268.354749) (xy 98.378203 -268.318026) (xy 98.420219 -268.2875) (xy 98.466493 -268.263922)
			(xy 98.515886 -268.247874) (xy 98.567181 -268.239749) (xy 98.619115 -268.239749) (xy 98.67041 -268.247874)
			(xy 98.719803 -268.263922) (xy 98.766077 -268.2875) (xy 98.808093 -268.318026) (xy 98.844816 -268.354749)
			(xy 98.875342 -268.396765) (xy 98.89892 -268.443039) (xy 98.914968 -268.492432) (xy 98.923093 -268.543727)
			(xy 98.923602 -268.569694) (xy 98.923093 -268.595661) (xy 99.203003 -268.595661) (xy 99.203003 -268.543727)
			(xy 99.211128 -268.492432) (xy 99.227176 -268.443039) (xy 99.250754 -268.396765) (xy 99.28128 -268.354749)
			(xy 99.318003 -268.318026) (xy 99.360019 -268.2875) (xy 99.406293 -268.263922) (xy 99.455686 -268.247874)
			(xy 99.506981 -268.239749) (xy 99.558915 -268.239749) (xy 99.61021 -268.247874) (xy 99.659603 -268.263922)
			(xy 99.705877 -268.2875) (xy 99.747893 -268.318026) (xy 99.784616 -268.354749) (xy 99.815142 -268.396765)
			(xy 99.83872 -268.443039) (xy 99.854768 -268.492432) (xy 99.862893 -268.543727) (xy 99.863402 -268.569694)
			(xy 99.862893 -268.595661) (xy 100.142803 -268.595661) (xy 100.142803 -268.543727) (xy 100.150928 -268.492432)
			(xy 100.166976 -268.443039) (xy 100.190554 -268.396765) (xy 100.22108 -268.354749) (xy 100.257803 -268.318026)
			(xy 100.299819 -268.2875) (xy 100.346093 -268.263922) (xy 100.395486 -268.247874) (xy 100.446781 -268.239749)
			(xy 100.498715 -268.239749) (xy 100.55001 -268.247874) (xy 100.599403 -268.263922) (xy 100.645677 -268.2875)
			(xy 100.687693 -268.318026) (xy 100.724416 -268.354749) (xy 100.754942 -268.396765) (xy 100.77852 -268.443039)
			(xy 100.794568 -268.492432) (xy 100.802693 -268.543727) (xy 100.803202 -268.569694) (xy 100.802693 -268.595661)
			(xy 101.082349 -268.595661) (xy 101.082349 -268.543727) (xy 101.090474 -268.492432) (xy 101.106522 -268.443039)
			(xy 101.1301 -268.396765) (xy 101.160626 -268.354749) (xy 101.197349 -268.318026) (xy 101.239365 -268.2875)
			(xy 101.285639 -268.263922) (xy 101.335032 -268.247874) (xy 101.386327 -268.239749) (xy 101.438261 -268.239749)
			(xy 101.489556 -268.247874) (xy 101.538949 -268.263922) (xy 101.585223 -268.2875) (xy 101.627239 -268.318026)
			(xy 101.663962 -268.354749) (xy 101.694488 -268.396765) (xy 101.718066 -268.443039) (xy 101.734114 -268.492432)
			(xy 101.742239 -268.543727) (xy 101.742748 -268.569694) (xy 101.742239 -268.595661) (xy 102.022403 -268.595661)
			(xy 102.022403 -268.543727) (xy 102.030528 -268.492432) (xy 102.046576 -268.443039) (xy 102.070154 -268.396765)
			(xy 102.10068 -268.354749) (xy 102.137403 -268.318026) (xy 102.179419 -268.2875) (xy 102.225693 -268.263922)
			(xy 102.275086 -268.247874) (xy 102.326381 -268.239749) (xy 102.378315 -268.239749) (xy 102.42961 -268.247874)
			(xy 102.479003 -268.263922) (xy 102.525277 -268.2875) (xy 102.567293 -268.318026) (xy 102.604016 -268.354749)
			(xy 102.634542 -268.396765) (xy 102.65812 -268.443039) (xy 102.674168 -268.492432) (xy 102.682293 -268.543727)
			(xy 102.682802 -268.569694) (xy 102.682293 -268.595661) (xy 102.962203 -268.595661) (xy 102.962203 -268.543727)
			(xy 102.970328 -268.492432) (xy 102.986376 -268.443039) (xy 103.009954 -268.396765) (xy 103.04048 -268.354749)
			(xy 103.077203 -268.318026) (xy 103.119219 -268.2875) (xy 103.165493 -268.263922) (xy 103.214886 -268.247874)
			(xy 103.266181 -268.239749) (xy 103.318115 -268.239749) (xy 103.36941 -268.247874) (xy 103.418803 -268.263922)
			(xy 103.465077 -268.2875) (xy 103.507093 -268.318026) (xy 103.543816 -268.354749) (xy 103.574342 -268.396765)
			(xy 103.59792 -268.443039) (xy 103.613968 -268.492432) (xy 103.622093 -268.543727) (xy 103.622602 -268.569694)
			(xy 103.622093 -268.595661) (xy 103.902003 -268.595661) (xy 103.902003 -268.543727) (xy 103.910128 -268.492432)
			(xy 103.926176 -268.443039) (xy 103.949754 -268.396765) (xy 103.98028 -268.354749) (xy 104.017003 -268.318026)
			(xy 104.059019 -268.2875) (xy 104.105293 -268.263922) (xy 104.154686 -268.247874) (xy 104.205981 -268.239749)
			(xy 104.257915 -268.239749) (xy 104.30921 -268.247874) (xy 104.358603 -268.263922) (xy 104.404877 -268.2875)
			(xy 104.446893 -268.318026) (xy 104.483616 -268.354749) (xy 104.514142 -268.396765) (xy 104.53772 -268.443039)
			(xy 104.553768 -268.492432) (xy 104.561893 -268.543727) (xy 104.562402 -268.569694) (xy 104.561893 -268.595661)
			(xy 104.841803 -268.595661) (xy 104.841803 -268.543727) (xy 104.849928 -268.492432) (xy 104.865976 -268.443039)
			(xy 104.889554 -268.396765) (xy 104.92008 -268.354749) (xy 104.956803 -268.318026) (xy 104.998819 -268.2875)
			(xy 105.045093 -268.263922) (xy 105.094486 -268.247874) (xy 105.145781 -268.239749) (xy 105.197715 -268.239749)
			(xy 105.24901 -268.247874) (xy 105.298403 -268.263922) (xy 105.344677 -268.2875) (xy 105.386693 -268.318026)
			(xy 105.423416 -268.354749) (xy 105.453942 -268.396765) (xy 105.47752 -268.443039) (xy 105.493568 -268.492432)
			(xy 105.501693 -268.543727) (xy 105.502202 -268.569694) (xy 105.501693 -268.595661) (xy 105.781603 -268.595661)
			(xy 105.781603 -268.543727) (xy 105.789728 -268.492432) (xy 105.805776 -268.443039) (xy 105.829354 -268.396765)
			(xy 105.85988 -268.354749) (xy 105.896603 -268.318026) (xy 105.938619 -268.2875) (xy 105.984893 -268.263922)
			(xy 106.034286 -268.247874) (xy 106.085581 -268.239749) (xy 106.137515 -268.239749) (xy 106.18881 -268.247874)
			(xy 106.238203 -268.263922) (xy 106.284477 -268.2875) (xy 106.326493 -268.318026) (xy 106.363216 -268.354749)
			(xy 106.393742 -268.396765) (xy 106.41732 -268.443039) (xy 106.433368 -268.492432) (xy 106.441493 -268.543727)
			(xy 106.442002 -268.569694) (xy 106.441493 -268.595661) (xy 106.721403 -268.595661) (xy 106.721403 -268.543727)
			(xy 106.729528 -268.492432) (xy 106.745576 -268.443039) (xy 106.769154 -268.396765) (xy 106.79968 -268.354749)
			(xy 106.836403 -268.318026) (xy 106.878419 -268.2875) (xy 106.924693 -268.263922) (xy 106.974086 -268.247874)
			(xy 107.025381 -268.239749) (xy 107.077315 -268.239749) (xy 107.12861 -268.247874) (xy 107.178003 -268.263922)
			(xy 107.224277 -268.2875) (xy 107.266293 -268.318026) (xy 107.303016 -268.354749) (xy 107.333542 -268.396765)
			(xy 107.35712 -268.443039) (xy 107.373168 -268.492432) (xy 107.381293 -268.543727) (xy 107.381802 -268.569694)
			(xy 107.381293 -268.595661) (xy 107.661203 -268.595661) (xy 107.661203 -268.543727) (xy 107.669328 -268.492432)
			(xy 107.685376 -268.443039) (xy 107.708954 -268.396765) (xy 107.73948 -268.354749) (xy 107.776203 -268.318026)
			(xy 107.818219 -268.2875) (xy 107.864493 -268.263922) (xy 107.913886 -268.247874) (xy 107.965181 -268.239749)
			(xy 108.017115 -268.239749) (xy 108.06841 -268.247874) (xy 108.117803 -268.263922) (xy 108.164077 -268.2875)
			(xy 108.206093 -268.318026) (xy 108.242816 -268.354749) (xy 108.273342 -268.396765) (xy 108.29692 -268.443039)
			(xy 108.312968 -268.492432) (xy 108.321093 -268.543727) (xy 108.321602 -268.569694) (xy 108.321093 -268.595661)
			(xy 108.600749 -268.595661) (xy 108.600749 -268.543727) (xy 108.608874 -268.492432) (xy 108.624922 -268.443039)
			(xy 108.6485 -268.396765) (xy 108.679026 -268.354749) (xy 108.715749 -268.318026) (xy 108.757765 -268.2875)
			(xy 108.804039 -268.263922) (xy 108.853432 -268.247874) (xy 108.904727 -268.239749) (xy 108.956661 -268.239749)
			(xy 109.007956 -268.247874) (xy 109.057349 -268.263922) (xy 109.103623 -268.2875) (xy 109.145639 -268.318026)
			(xy 109.182362 -268.354749) (xy 109.212888 -268.396765) (xy 109.236466 -268.443039) (xy 109.252514 -268.492432)
			(xy 109.260639 -268.543727) (xy 109.261148 -268.569694) (xy 109.260639 -268.595661) (xy 109.540549 -268.595661)
			(xy 109.540549 -268.543727) (xy 109.548674 -268.492432) (xy 109.564722 -268.443039) (xy 109.5883 -268.396765)
			(xy 109.618826 -268.354749) (xy 109.655549 -268.318026) (xy 109.697565 -268.2875) (xy 109.743839 -268.263922)
			(xy 109.793232 -268.247874) (xy 109.844527 -268.239749) (xy 109.896461 -268.239749) (xy 109.947756 -268.247874)
			(xy 109.997149 -268.263922) (xy 110.043423 -268.2875) (xy 110.085439 -268.318026) (xy 110.122162 -268.354749)
			(xy 110.152688 -268.396765) (xy 110.176266 -268.443039) (xy 110.192314 -268.492432) (xy 110.200439 -268.543727)
			(xy 110.200948 -268.569694) (xy 110.200439 -268.595661) (xy 110.480603 -268.595661) (xy 110.480603 -268.543727)
			(xy 110.488728 -268.492432) (xy 110.504776 -268.443039) (xy 110.528354 -268.396765) (xy 110.55888 -268.354749)
			(xy 110.595603 -268.318026) (xy 110.637619 -268.2875) (xy 110.683893 -268.263922) (xy 110.733286 -268.247874)
			(xy 110.784581 -268.239749) (xy 110.836515 -268.239749) (xy 110.88781 -268.247874) (xy 110.937203 -268.263922)
			(xy 110.983477 -268.2875) (xy 111.025493 -268.318026) (xy 111.062216 -268.354749) (xy 111.092742 -268.396765)
			(xy 111.11632 -268.443039) (xy 111.132368 -268.492432) (xy 111.140493 -268.543727) (xy 111.141002 -268.569694)
			(xy 111.140493 -268.595661) (xy 111.420149 -268.595661) (xy 111.420149 -268.543727) (xy 111.428274 -268.492432)
			(xy 111.444322 -268.443039) (xy 111.4679 -268.396765) (xy 111.498426 -268.354749) (xy 111.535149 -268.318026)
			(xy 111.577165 -268.2875) (xy 111.623439 -268.263922) (xy 111.672832 -268.247874) (xy 111.724127 -268.239749)
			(xy 111.776061 -268.239749) (xy 111.827356 -268.247874) (xy 111.876749 -268.263922) (xy 111.923023 -268.2875)
			(xy 111.965039 -268.318026) (xy 112.001762 -268.354749) (xy 112.032288 -268.396765) (xy 112.055866 -268.443039)
			(xy 112.071914 -268.492432) (xy 112.080039 -268.543727) (xy 112.080548 -268.569694) (xy 112.080039 -268.595661)
			(xy 112.359949 -268.595661) (xy 112.359949 -268.543727) (xy 112.368074 -268.492432) (xy 112.384122 -268.443039)
			(xy 112.4077 -268.396765) (xy 112.438226 -268.354749) (xy 112.474949 -268.318026) (xy 112.516965 -268.2875)
			(xy 112.563239 -268.263922) (xy 112.612632 -268.247874) (xy 112.663927 -268.239749) (xy 112.715861 -268.239749)
			(xy 112.767156 -268.247874) (xy 112.816549 -268.263922) (xy 112.862823 -268.2875) (xy 112.904839 -268.318026)
			(xy 112.941562 -268.354749) (xy 112.972088 -268.396765) (xy 112.995666 -268.443039) (xy 113.011714 -268.492432)
			(xy 113.019839 -268.543727) (xy 113.020348 -268.569694) (xy 113.019839 -268.595661) (xy 113.299749 -268.595661)
			(xy 113.299749 -268.543727) (xy 113.307874 -268.492432) (xy 113.323922 -268.443039) (xy 113.3475 -268.396765)
			(xy 113.378026 -268.354749) (xy 113.414749 -268.318026) (xy 113.456765 -268.2875) (xy 113.503039 -268.263922)
			(xy 113.552432 -268.247874) (xy 113.603727 -268.239749) (xy 113.655661 -268.239749) (xy 113.706956 -268.247874)
			(xy 113.756349 -268.263922) (xy 113.802623 -268.2875) (xy 113.844639 -268.318026) (xy 113.881362 -268.354749)
			(xy 113.911888 -268.396765) (xy 113.935466 -268.443039) (xy 113.951514 -268.492432) (xy 113.959639 -268.543727)
			(xy 113.960148 -268.569694) (xy 113.959639 -268.595661) (xy 113.951514 -268.646956) (xy 113.935466 -268.696349)
			(xy 113.911888 -268.742623) (xy 113.881362 -268.784639) (xy 113.844639 -268.821362) (xy 113.802623 -268.851888)
			(xy 113.756349 -268.875466) (xy 113.706956 -268.891514) (xy 113.655661 -268.899639) (xy 113.603727 -268.899639)
			(xy 113.552432 -268.891514) (xy 113.503039 -268.875466) (xy 113.456765 -268.851888) (xy 113.414749 -268.821362)
			(xy 113.378026 -268.784639) (xy 113.3475 -268.742623) (xy 113.323922 -268.696349) (xy 113.307874 -268.646956)
			(xy 113.299749 -268.595661) (xy 113.019839 -268.595661) (xy 113.011714 -268.646956) (xy 112.995666 -268.696349)
			(xy 112.972088 -268.742623) (xy 112.941562 -268.784639) (xy 112.904839 -268.821362) (xy 112.862823 -268.851888)
			(xy 112.816549 -268.875466) (xy 112.767156 -268.891514) (xy 112.715861 -268.899639) (xy 112.663927 -268.899639)
			(xy 112.612632 -268.891514) (xy 112.563239 -268.875466) (xy 112.516965 -268.851888) (xy 112.474949 -268.821362)
			(xy 112.438226 -268.784639) (xy 112.4077 -268.742623) (xy 112.384122 -268.696349) (xy 112.368074 -268.646956)
			(xy 112.359949 -268.595661) (xy 112.080039 -268.595661) (xy 112.071914 -268.646956) (xy 112.055866 -268.696349)
			(xy 112.032288 -268.742623) (xy 112.001762 -268.784639) (xy 111.965039 -268.821362) (xy 111.923023 -268.851888)
			(xy 111.876749 -268.875466) (xy 111.827356 -268.891514) (xy 111.776061 -268.899639) (xy 111.724127 -268.899639)
			(xy 111.672832 -268.891514) (xy 111.623439 -268.875466) (xy 111.577165 -268.851888) (xy 111.535149 -268.821362)
			(xy 111.498426 -268.784639) (xy 111.4679 -268.742623) (xy 111.444322 -268.696349) (xy 111.428274 -268.646956)
			(xy 111.420149 -268.595661) (xy 111.140493 -268.595661) (xy 111.132368 -268.646956) (xy 111.11632 -268.696349)
			(xy 111.092742 -268.742623) (xy 111.062216 -268.784639) (xy 111.025493 -268.821362) (xy 110.983477 -268.851888)
			(xy 110.937203 -268.875466) (xy 110.88781 -268.891514) (xy 110.836515 -268.899639) (xy 110.784581 -268.899639)
			(xy 110.733286 -268.891514) (xy 110.683893 -268.875466) (xy 110.637619 -268.851888) (xy 110.595603 -268.821362)
			(xy 110.55888 -268.784639) (xy 110.528354 -268.742623) (xy 110.504776 -268.696349) (xy 110.488728 -268.646956)
			(xy 110.480603 -268.595661) (xy 110.200439 -268.595661) (xy 110.192314 -268.646956) (xy 110.176266 -268.696349)
			(xy 110.152688 -268.742623) (xy 110.122162 -268.784639) (xy 110.085439 -268.821362) (xy 110.043423 -268.851888)
			(xy 109.997149 -268.875466) (xy 109.947756 -268.891514) (xy 109.896461 -268.899639) (xy 109.844527 -268.899639)
			(xy 109.793232 -268.891514) (xy 109.743839 -268.875466) (xy 109.697565 -268.851888) (xy 109.655549 -268.821362)
			(xy 109.618826 -268.784639) (xy 109.5883 -268.742623) (xy 109.564722 -268.696349) (xy 109.548674 -268.646956)
			(xy 109.540549 -268.595661) (xy 109.260639 -268.595661) (xy 109.252514 -268.646956) (xy 109.236466 -268.696349)
			(xy 109.212888 -268.742623) (xy 109.182362 -268.784639) (xy 109.145639 -268.821362) (xy 109.103623 -268.851888)
			(xy 109.057349 -268.875466) (xy 109.007956 -268.891514) (xy 108.956661 -268.899639) (xy 108.904727 -268.899639)
			(xy 108.853432 -268.891514) (xy 108.804039 -268.875466) (xy 108.757765 -268.851888) (xy 108.715749 -268.821362)
			(xy 108.679026 -268.784639) (xy 108.6485 -268.742623) (xy 108.624922 -268.696349) (xy 108.608874 -268.646956)
			(xy 108.600749 -268.595661) (xy 108.321093 -268.595661) (xy 108.312968 -268.646956) (xy 108.29692 -268.696349)
			(xy 108.273342 -268.742623) (xy 108.242816 -268.784639) (xy 108.206093 -268.821362) (xy 108.164077 -268.851888)
			(xy 108.117803 -268.875466) (xy 108.06841 -268.891514) (xy 108.017115 -268.899639) (xy 107.965181 -268.899639)
			(xy 107.913886 -268.891514) (xy 107.864493 -268.875466) (xy 107.818219 -268.851888) (xy 107.776203 -268.821362)
			(xy 107.73948 -268.784639) (xy 107.708954 -268.742623) (xy 107.685376 -268.696349) (xy 107.669328 -268.646956)
			(xy 107.661203 -268.595661) (xy 107.381293 -268.595661) (xy 107.373168 -268.646956) (xy 107.35712 -268.696349)
			(xy 107.333542 -268.742623) (xy 107.303016 -268.784639) (xy 107.266293 -268.821362) (xy 107.224277 -268.851888)
			(xy 107.178003 -268.875466) (xy 107.12861 -268.891514) (xy 107.077315 -268.899639) (xy 107.025381 -268.899639)
			(xy 106.974086 -268.891514) (xy 106.924693 -268.875466) (xy 106.878419 -268.851888) (xy 106.836403 -268.821362)
			(xy 106.79968 -268.784639) (xy 106.769154 -268.742623) (xy 106.745576 -268.696349) (xy 106.729528 -268.646956)
			(xy 106.721403 -268.595661) (xy 106.441493 -268.595661) (xy 106.433368 -268.646956) (xy 106.41732 -268.696349)
			(xy 106.393742 -268.742623) (xy 106.363216 -268.784639) (xy 106.326493 -268.821362) (xy 106.284477 -268.851888)
			(xy 106.238203 -268.875466) (xy 106.18881 -268.891514) (xy 106.137515 -268.899639) (xy 106.085581 -268.899639)
			(xy 106.034286 -268.891514) (xy 105.984893 -268.875466) (xy 105.938619 -268.851888) (xy 105.896603 -268.821362)
			(xy 105.85988 -268.784639) (xy 105.829354 -268.742623) (xy 105.805776 -268.696349) (xy 105.789728 -268.646956)
			(xy 105.781603 -268.595661) (xy 105.501693 -268.595661) (xy 105.493568 -268.646956) (xy 105.47752 -268.696349)
			(xy 105.453942 -268.742623) (xy 105.423416 -268.784639) (xy 105.386693 -268.821362) (xy 105.344677 -268.851888)
			(xy 105.298403 -268.875466) (xy 105.24901 -268.891514) (xy 105.197715 -268.899639) (xy 105.145781 -268.899639)
			(xy 105.094486 -268.891514) (xy 105.045093 -268.875466) (xy 104.998819 -268.851888) (xy 104.956803 -268.821362)
			(xy 104.92008 -268.784639) (xy 104.889554 -268.742623) (xy 104.865976 -268.696349) (xy 104.849928 -268.646956)
			(xy 104.841803 -268.595661) (xy 104.561893 -268.595661) (xy 104.553768 -268.646956) (xy 104.53772 -268.696349)
			(xy 104.514142 -268.742623) (xy 104.483616 -268.784639) (xy 104.446893 -268.821362) (xy 104.404877 -268.851888)
			(xy 104.358603 -268.875466) (xy 104.30921 -268.891514) (xy 104.257915 -268.899639) (xy 104.205981 -268.899639)
			(xy 104.154686 -268.891514) (xy 104.105293 -268.875466) (xy 104.059019 -268.851888) (xy 104.017003 -268.821362)
			(xy 103.98028 -268.784639) (xy 103.949754 -268.742623) (xy 103.926176 -268.696349) (xy 103.910128 -268.646956)
			(xy 103.902003 -268.595661) (xy 103.622093 -268.595661) (xy 103.613968 -268.646956) (xy 103.59792 -268.696349)
			(xy 103.574342 -268.742623) (xy 103.543816 -268.784639) (xy 103.507093 -268.821362) (xy 103.465077 -268.851888)
			(xy 103.418803 -268.875466) (xy 103.36941 -268.891514) (xy 103.318115 -268.899639) (xy 103.266181 -268.899639)
			(xy 103.214886 -268.891514) (xy 103.165493 -268.875466) (xy 103.119219 -268.851888) (xy 103.077203 -268.821362)
			(xy 103.04048 -268.784639) (xy 103.009954 -268.742623) (xy 102.986376 -268.696349) (xy 102.970328 -268.646956)
			(xy 102.962203 -268.595661) (xy 102.682293 -268.595661) (xy 102.674168 -268.646956) (xy 102.65812 -268.696349)
			(xy 102.634542 -268.742623) (xy 102.604016 -268.784639) (xy 102.567293 -268.821362) (xy 102.525277 -268.851888)
			(xy 102.479003 -268.875466) (xy 102.42961 -268.891514) (xy 102.378315 -268.899639) (xy 102.326381 -268.899639)
			(xy 102.275086 -268.891514) (xy 102.225693 -268.875466) (xy 102.179419 -268.851888) (xy 102.137403 -268.821362)
			(xy 102.10068 -268.784639) (xy 102.070154 -268.742623) (xy 102.046576 -268.696349) (xy 102.030528 -268.646956)
			(xy 102.022403 -268.595661) (xy 101.742239 -268.595661) (xy 101.734114 -268.646956) (xy 101.718066 -268.696349)
			(xy 101.694488 -268.742623) (xy 101.663962 -268.784639) (xy 101.627239 -268.821362) (xy 101.585223 -268.851888)
			(xy 101.538949 -268.875466) (xy 101.489556 -268.891514) (xy 101.438261 -268.899639) (xy 101.386327 -268.899639)
			(xy 101.335032 -268.891514) (xy 101.285639 -268.875466) (xy 101.239365 -268.851888) (xy 101.197349 -268.821362)
			(xy 101.160626 -268.784639) (xy 101.1301 -268.742623) (xy 101.106522 -268.696349) (xy 101.090474 -268.646956)
			(xy 101.082349 -268.595661) (xy 100.802693 -268.595661) (xy 100.794568 -268.646956) (xy 100.77852 -268.696349)
			(xy 100.754942 -268.742623) (xy 100.724416 -268.784639) (xy 100.687693 -268.821362) (xy 100.645677 -268.851888)
			(xy 100.599403 -268.875466) (xy 100.55001 -268.891514) (xy 100.498715 -268.899639) (xy 100.446781 -268.899639)
			(xy 100.395486 -268.891514) (xy 100.346093 -268.875466) (xy 100.299819 -268.851888) (xy 100.257803 -268.821362)
			(xy 100.22108 -268.784639) (xy 100.190554 -268.742623) (xy 100.166976 -268.696349) (xy 100.150928 -268.646956)
			(xy 100.142803 -268.595661) (xy 99.862893 -268.595661) (xy 99.854768 -268.646956) (xy 99.83872 -268.696349)
			(xy 99.815142 -268.742623) (xy 99.784616 -268.784639) (xy 99.747893 -268.821362) (xy 99.705877 -268.851888)
			(xy 99.659603 -268.875466) (xy 99.61021 -268.891514) (xy 99.558915 -268.899639) (xy 99.506981 -268.899639)
			(xy 99.455686 -268.891514) (xy 99.406293 -268.875466) (xy 99.360019 -268.851888) (xy 99.318003 -268.821362)
			(xy 99.28128 -268.784639) (xy 99.250754 -268.742623) (xy 99.227176 -268.696349) (xy 99.211128 -268.646956)
			(xy 99.203003 -268.595661) (xy 98.923093 -268.595661) (xy 98.914968 -268.646956) (xy 98.89892 -268.696349)
			(xy 98.875342 -268.742623) (xy 98.844816 -268.784639) (xy 98.808093 -268.821362) (xy 98.766077 -268.851888)
			(xy 98.719803 -268.875466) (xy 98.67041 -268.891514) (xy 98.619115 -268.899639) (xy 98.567181 -268.899639)
			(xy 98.515886 -268.891514) (xy 98.466493 -268.875466) (xy 98.420219 -268.851888) (xy 98.378203 -268.821362)
			(xy 98.34148 -268.784639) (xy 98.310954 -268.742623) (xy 98.287376 -268.696349) (xy 98.271328 -268.646956)
			(xy 98.263203 -268.595661) (xy 97.983293 -268.595661) (xy 97.975168 -268.646956) (xy 97.95912 -268.696349)
			(xy 97.935542 -268.742623) (xy 97.905016 -268.784639) (xy 97.868293 -268.821362) (xy 97.826277 -268.851888)
			(xy 97.780003 -268.875466) (xy 97.73061 -268.891514) (xy 97.679315 -268.899639) (xy 97.627381 -268.899639)
			(xy 97.576086 -268.891514) (xy 97.526693 -268.875466) (xy 97.480419 -268.851888) (xy 97.438403 -268.821362)
			(xy 97.40168 -268.784639) (xy 97.371154 -268.742623) (xy 97.347576 -268.696349) (xy 97.331528 -268.646956)
			(xy 97.323403 -268.595661) (xy 97.043493 -268.595661) (xy 97.035368 -268.646956) (xy 97.01932 -268.696349)
			(xy 96.995742 -268.742623) (xy 96.965216 -268.784639) (xy 96.928493 -268.821362) (xy 96.886477 -268.851888)
			(xy 96.840203 -268.875466) (xy 96.79081 -268.891514) (xy 96.739515 -268.899639) (xy 96.687581 -268.899639)
			(xy 96.636286 -268.891514) (xy 96.586893 -268.875466) (xy 96.540619 -268.851888) (xy 96.498603 -268.821362)
			(xy 96.46188 -268.784639) (xy 96.431354 -268.742623) (xy 96.407776 -268.696349) (xy 96.391728 -268.646956)
			(xy 96.383603 -268.595661) (xy 96.103693 -268.595661) (xy 96.095568 -268.646956) (xy 96.07952 -268.696349)
			(xy 96.055942 -268.742623) (xy 96.025416 -268.784639) (xy 95.988693 -268.821362) (xy 95.946677 -268.851888)
			(xy 95.900403 -268.875466) (xy 95.85101 -268.891514) (xy 95.799715 -268.899639) (xy 95.747781 -268.899639)
			(xy 95.696486 -268.891514) (xy 95.647093 -268.875466) (xy 95.600819 -268.851888) (xy 95.558803 -268.821362)
			(xy 95.52208 -268.784639) (xy 95.491554 -268.742623) (xy 95.467976 -268.696349) (xy 95.451928 -268.646956)
			(xy 95.443803 -268.595661) (xy 95.163639 -268.595661) (xy 95.155514 -268.646956) (xy 95.139466 -268.696349)
			(xy 95.115888 -268.742623) (xy 95.085362 -268.784639) (xy 95.048639 -268.821362) (xy 95.006623 -268.851888)
			(xy 94.960349 -268.875466) (xy 94.910956 -268.891514) (xy 94.859661 -268.899639) (xy 94.807727 -268.899639)
			(xy 94.756432 -268.891514) (xy 94.707039 -268.875466) (xy 94.660765 -268.851888) (xy 94.618749 -268.821362)
			(xy 94.582026 -268.784639) (xy 94.5515 -268.742623) (xy 94.527922 -268.696349) (xy 94.511874 -268.646956)
			(xy 94.503749 -268.595661) (xy 94.224093 -268.595661) (xy 94.215968 -268.646956) (xy 94.19992 -268.696349)
			(xy 94.176342 -268.742623) (xy 94.145816 -268.784639) (xy 94.109093 -268.821362) (xy 94.067077 -268.851888)
			(xy 94.020803 -268.875466) (xy 93.97141 -268.891514) (xy 93.920115 -268.899639) (xy 93.868181 -268.899639)
			(xy 93.816886 -268.891514) (xy 93.767493 -268.875466) (xy 93.721219 -268.851888) (xy 93.679203 -268.821362)
			(xy 93.64248 -268.784639) (xy 93.611954 -268.742623) (xy 93.588376 -268.696349) (xy 93.572328 -268.646956)
			(xy 93.564203 -268.595661) (xy 93.284293 -268.595661) (xy 93.276168 -268.646956) (xy 93.26012 -268.696349)
			(xy 93.236542 -268.742623) (xy 93.206016 -268.784639) (xy 93.169293 -268.821362) (xy 93.127277 -268.851888)
			(xy 93.081003 -268.875466) (xy 93.03161 -268.891514) (xy 92.980315 -268.899639) (xy 92.928381 -268.899639)
			(xy 92.877086 -268.891514) (xy 92.827693 -268.875466) (xy 92.781419 -268.851888) (xy 92.739403 -268.821362)
			(xy 92.70268 -268.784639) (xy 92.672154 -268.742623) (xy 92.648576 -268.696349) (xy 92.632528 -268.646956)
			(xy 92.624403 -268.595661) (xy 92.344705 -268.595661) (xy 92.344705 -268.595685) (xy 92.336575 -268.647016)
			(xy 92.320517 -268.696443) (xy 92.296925 -268.742751) (xy 92.26638 -268.784797) (xy 92.229634 -268.821549)
			(xy 92.187591 -268.8521) (xy 92.141288 -268.875699) (xy 92.091863 -268.891764) (xy 92.040533 -268.899901)
			(xy 92.014548 -268.900402) (xy 91.991674 -268.900019) (xy 91.946361 -268.893723) (xy 91.902347 -268.881246)
			(xy 91.860472 -268.862824) (xy 91.840812 -268.851126) (xy 91.840558 -268.850872) (xy 91.83307 -268.846688)
			(xy 91.816298 -268.843157) (xy 91.799315 -268.845478) (xy 91.791536 -268.849094) (xy 91.751658 -268.871192)
			(xy 91.713304 -268.892528) (xy 91.705723 -268.897169) (xy 91.694178 -268.910669) (xy 91.688027 -268.927334)
			(xy 91.68765 -268.936216) (xy 91.68765 -269.055342) (xy 91.712034 -269.098014) (xy 91.722702 -269.104872)
			(xy 91.743953 -269.118994) (xy 91.782235 -269.152724) (xy 91.814879 -269.191937) (xy 91.84111 -269.235699)
			(xy 91.860304 -269.282973) (xy 91.872005 -269.332635) (xy 91.875937 -269.383505) (xy 91.873929 -269.409477)
			(xy 92.154249 -269.409477) (xy 92.154249 -269.357543) (xy 92.162374 -269.306248) (xy 92.178422 -269.256855)
			(xy 92.202 -269.210581) (xy 92.232526 -269.168565) (xy 92.269249 -269.131842) (xy 92.311265 -269.101316)
			(xy 92.357539 -269.077738) (xy 92.406932 -269.06169) (xy 92.458227 -269.053565) (xy 92.510161 -269.053565)
			(xy 92.561456 -269.06169) (xy 92.610849 -269.077738) (xy 92.657123 -269.101316) (xy 92.699139 -269.131842)
			(xy 92.735862 -269.168565) (xy 92.766388 -269.210581) (xy 92.789966 -269.256855) (xy 92.806014 -269.306248)
			(xy 92.814139 -269.357543) (xy 92.814648 -269.38351) (xy 92.814139 -269.409477) (xy 93.094049 -269.409477)
			(xy 93.094049 -269.357543) (xy 93.102174 -269.306248) (xy 93.118222 -269.256855) (xy 93.1418 -269.210581)
			(xy 93.172326 -269.168565) (xy 93.209049 -269.131842) (xy 93.251065 -269.101316) (xy 93.297339 -269.077738)
			(xy 93.346732 -269.06169) (xy 93.398027 -269.053565) (xy 93.449961 -269.053565) (xy 93.501256 -269.06169)
			(xy 93.550649 -269.077738) (xy 93.596923 -269.101316) (xy 93.638939 -269.131842) (xy 93.675662 -269.168565)
			(xy 93.706188 -269.210581) (xy 93.729766 -269.256855) (xy 93.745814 -269.306248) (xy 93.753939 -269.357543)
			(xy 93.754448 -269.38351) (xy 93.753939 -269.409477) (xy 94.033849 -269.409477) (xy 94.033849 -269.357543)
			(xy 94.041974 -269.306248) (xy 94.058022 -269.256855) (xy 94.0816 -269.210581) (xy 94.112126 -269.168565)
			(xy 94.148849 -269.131842) (xy 94.190865 -269.101316) (xy 94.237139 -269.077738) (xy 94.286532 -269.06169)
			(xy 94.337827 -269.053565) (xy 94.389761 -269.053565) (xy 94.441056 -269.06169) (xy 94.490449 -269.077738)
			(xy 94.536723 -269.101316) (xy 94.578739 -269.131842) (xy 94.615462 -269.168565) (xy 94.645988 -269.210581)
			(xy 94.669566 -269.256855) (xy 94.685614 -269.306248) (xy 94.693739 -269.357543) (xy 94.694248 -269.38351)
			(xy 94.693739 -269.409477) (xy 94.973649 -269.409477) (xy 94.973649 -269.357543) (xy 94.981774 -269.306248)
			(xy 94.997822 -269.256855) (xy 95.0214 -269.210581) (xy 95.051926 -269.168565) (xy 95.088649 -269.131842)
			(xy 95.130665 -269.101316) (xy 95.176939 -269.077738) (xy 95.226332 -269.06169) (xy 95.277627 -269.053565)
			(xy 95.329561 -269.053565) (xy 95.380856 -269.06169) (xy 95.430249 -269.077738) (xy 95.476523 -269.101316)
			(xy 95.518539 -269.131842) (xy 95.555262 -269.168565) (xy 95.585788 -269.210581) (xy 95.609366 -269.256855)
			(xy 95.625414 -269.306248) (xy 95.633539 -269.357543) (xy 95.634048 -269.38351) (xy 95.633539 -269.409477)
			(xy 95.913449 -269.409477) (xy 95.913449 -269.357543) (xy 95.921574 -269.306248) (xy 95.937622 -269.256855)
			(xy 95.9612 -269.210581) (xy 95.991726 -269.168565) (xy 96.028449 -269.131842) (xy 96.070465 -269.101316)
			(xy 96.116739 -269.077738) (xy 96.166132 -269.06169) (xy 96.217427 -269.053565) (xy 96.269361 -269.053565)
			(xy 96.320656 -269.06169) (xy 96.370049 -269.077738) (xy 96.416323 -269.101316) (xy 96.458339 -269.131842)
			(xy 96.495062 -269.168565) (xy 96.525588 -269.210581) (xy 96.549166 -269.256855) (xy 96.565214 -269.306248)
			(xy 96.573339 -269.357543) (xy 96.573848 -269.38351) (xy 96.573339 -269.409477) (xy 96.853249 -269.409477)
			(xy 96.853249 -269.357543) (xy 96.861374 -269.306248) (xy 96.877422 -269.256855) (xy 96.901 -269.210581)
			(xy 96.931526 -269.168565) (xy 96.968249 -269.131842) (xy 97.010265 -269.101316) (xy 97.056539 -269.077738)
			(xy 97.105932 -269.06169) (xy 97.157227 -269.053565) (xy 97.209161 -269.053565) (xy 97.260456 -269.06169)
			(xy 97.309849 -269.077738) (xy 97.356123 -269.101316) (xy 97.398139 -269.131842) (xy 97.434862 -269.168565)
			(xy 97.465388 -269.210581) (xy 97.488966 -269.256855) (xy 97.505014 -269.306248) (xy 97.513139 -269.357543)
			(xy 97.513648 -269.38351) (xy 97.513139 -269.409477) (xy 97.793303 -269.409477) (xy 97.793303 -269.357543)
			(xy 97.801428 -269.306248) (xy 97.817476 -269.256855) (xy 97.841054 -269.210581) (xy 97.87158 -269.168565)
			(xy 97.908303 -269.131842) (xy 97.950319 -269.101316) (xy 97.996593 -269.077738) (xy 98.045986 -269.06169)
			(xy 98.097281 -269.053565) (xy 98.149215 -269.053565) (xy 98.20051 -269.06169) (xy 98.249903 -269.077738)
			(xy 98.296177 -269.101316) (xy 98.338193 -269.131842) (xy 98.374916 -269.168565) (xy 98.405442 -269.210581)
			(xy 98.42902 -269.256855) (xy 98.445068 -269.306248) (xy 98.453193 -269.357543) (xy 98.453702 -269.38351)
			(xy 98.453193 -269.409477) (xy 98.732849 -269.409477) (xy 98.732849 -269.357543) (xy 98.740974 -269.306248)
			(xy 98.757022 -269.256855) (xy 98.7806 -269.210581) (xy 98.811126 -269.168565) (xy 98.847849 -269.131842)
			(xy 98.889865 -269.101316) (xy 98.936139 -269.077738) (xy 98.985532 -269.06169) (xy 99.036827 -269.053565)
			(xy 99.088761 -269.053565) (xy 99.140056 -269.06169) (xy 99.189449 -269.077738) (xy 99.235723 -269.101316)
			(xy 99.277739 -269.131842) (xy 99.314462 -269.168565) (xy 99.344988 -269.210581) (xy 99.368566 -269.256855)
			(xy 99.384614 -269.306248) (xy 99.392739 -269.357543) (xy 99.393248 -269.38351) (xy 99.392739 -269.409477)
			(xy 99.672649 -269.409477) (xy 99.672649 -269.357543) (xy 99.680774 -269.306248) (xy 99.696822 -269.256855)
			(xy 99.7204 -269.210581) (xy 99.750926 -269.168565) (xy 99.787649 -269.131842) (xy 99.829665 -269.101316)
			(xy 99.875939 -269.077738) (xy 99.925332 -269.06169) (xy 99.976627 -269.053565) (xy 100.028561 -269.053565)
			(xy 100.079856 -269.06169) (xy 100.129249 -269.077738) (xy 100.175523 -269.101316) (xy 100.217539 -269.131842)
			(xy 100.254262 -269.168565) (xy 100.284788 -269.210581) (xy 100.308366 -269.256855) (xy 100.324414 -269.306248)
			(xy 100.332539 -269.357543) (xy 100.333048 -269.38351) (xy 100.332539 -269.409477) (xy 100.612449 -269.409477)
			(xy 100.612449 -269.357543) (xy 100.620574 -269.306248) (xy 100.636622 -269.256855) (xy 100.6602 -269.210581)
			(xy 100.690726 -269.168565) (xy 100.727449 -269.131842) (xy 100.769465 -269.101316) (xy 100.815739 -269.077738)
			(xy 100.865132 -269.06169) (xy 100.916427 -269.053565) (xy 100.968361 -269.053565) (xy 101.019656 -269.06169)
			(xy 101.069049 -269.077738) (xy 101.115323 -269.101316) (xy 101.157339 -269.131842) (xy 101.194062 -269.168565)
			(xy 101.224588 -269.210581) (xy 101.248166 -269.256855) (xy 101.264214 -269.306248) (xy 101.272339 -269.357543)
			(xy 101.272848 -269.38351) (xy 101.272339 -269.409477) (xy 101.552757 -269.409477) (xy 101.552757 -269.357543)
			(xy 101.560882 -269.306248) (xy 101.57693 -269.256855) (xy 101.600508 -269.210581) (xy 101.631034 -269.168565)
			(xy 101.667757 -269.131842) (xy 101.709773 -269.101316) (xy 101.756047 -269.077738) (xy 101.80544 -269.06169)
			(xy 101.856735 -269.053565) (xy 101.908669 -269.053565) (xy 101.959964 -269.06169) (xy 102.009357 -269.077738)
			(xy 102.055631 -269.101316) (xy 102.097647 -269.131842) (xy 102.13437 -269.168565) (xy 102.164896 -269.210581)
			(xy 102.188474 -269.256855) (xy 102.204522 -269.306248) (xy 102.212647 -269.357543) (xy 102.213156 -269.38351)
			(xy 102.212647 -269.409477) (xy 102.492049 -269.409477) (xy 102.492049 -269.357543) (xy 102.500174 -269.306248)
			(xy 102.516222 -269.256855) (xy 102.5398 -269.210581) (xy 102.570326 -269.168565) (xy 102.607049 -269.131842)
			(xy 102.649065 -269.101316) (xy 102.695339 -269.077738) (xy 102.744732 -269.06169) (xy 102.796027 -269.053565)
			(xy 102.847961 -269.053565) (xy 102.899256 -269.06169) (xy 102.948649 -269.077738) (xy 102.994923 -269.101316)
			(xy 103.036939 -269.131842) (xy 103.073662 -269.168565) (xy 103.104188 -269.210581) (xy 103.127766 -269.256855)
			(xy 103.143814 -269.306248) (xy 103.151939 -269.357543) (xy 103.152448 -269.38351) (xy 103.151939 -269.409477)
			(xy 103.431849 -269.409477) (xy 103.431849 -269.357543) (xy 103.439974 -269.306248) (xy 103.456022 -269.256855)
			(xy 103.4796 -269.210581) (xy 103.510126 -269.168565) (xy 103.546849 -269.131842) (xy 103.588865 -269.101316)
			(xy 103.635139 -269.077738) (xy 103.684532 -269.06169) (xy 103.735827 -269.053565) (xy 103.787761 -269.053565)
			(xy 103.839056 -269.06169) (xy 103.888449 -269.077738) (xy 103.934723 -269.101316) (xy 103.976739 -269.131842)
			(xy 104.013462 -269.168565) (xy 104.043988 -269.210581) (xy 104.067566 -269.256855) (xy 104.083614 -269.306248)
			(xy 104.091739 -269.357543) (xy 104.092248 -269.38351) (xy 104.091739 -269.409477) (xy 104.371649 -269.409477)
			(xy 104.371649 -269.357543) (xy 104.379774 -269.306248) (xy 104.395822 -269.256855) (xy 104.4194 -269.210581)
			(xy 104.449926 -269.168565) (xy 104.486649 -269.131842) (xy 104.528665 -269.101316) (xy 104.574939 -269.077738)
			(xy 104.624332 -269.06169) (xy 104.675627 -269.053565) (xy 104.727561 -269.053565) (xy 104.778856 -269.06169)
			(xy 104.828249 -269.077738) (xy 104.874523 -269.101316) (xy 104.916539 -269.131842) (xy 104.953262 -269.168565)
			(xy 104.983788 -269.210581) (xy 105.007366 -269.256855) (xy 105.023414 -269.306248) (xy 105.031539 -269.357543)
			(xy 105.032048 -269.38351) (xy 105.031539 -269.409477) (xy 105.311449 -269.409477) (xy 105.311449 -269.357543)
			(xy 105.319574 -269.306248) (xy 105.335622 -269.256855) (xy 105.3592 -269.210581) (xy 105.389726 -269.168565)
			(xy 105.426449 -269.131842) (xy 105.468465 -269.101316) (xy 105.514739 -269.077738) (xy 105.564132 -269.06169)
			(xy 105.615427 -269.053565) (xy 105.667361 -269.053565) (xy 105.718656 -269.06169) (xy 105.768049 -269.077738)
			(xy 105.814323 -269.101316) (xy 105.856339 -269.131842) (xy 105.893062 -269.168565) (xy 105.923588 -269.210581)
			(xy 105.947166 -269.256855) (xy 105.963214 -269.306248) (xy 105.971339 -269.357543) (xy 105.971848 -269.38351)
			(xy 105.971339 -269.409477) (xy 106.251249 -269.409477) (xy 106.251249 -269.357543) (xy 106.259374 -269.306248)
			(xy 106.275422 -269.256855) (xy 106.299 -269.210581) (xy 106.329526 -269.168565) (xy 106.366249 -269.131842)
			(xy 106.408265 -269.101316) (xy 106.454539 -269.077738) (xy 106.503932 -269.06169) (xy 106.555227 -269.053565)
			(xy 106.607161 -269.053565) (xy 106.658456 -269.06169) (xy 106.707849 -269.077738) (xy 106.754123 -269.101316)
			(xy 106.796139 -269.131842) (xy 106.832862 -269.168565) (xy 106.863388 -269.210581) (xy 106.886966 -269.256855)
			(xy 106.903014 -269.306248) (xy 106.911139 -269.357543) (xy 106.911648 -269.38351) (xy 106.911139 -269.409477)
			(xy 107.191049 -269.409477) (xy 107.191049 -269.357543) (xy 107.199174 -269.306248) (xy 107.215222 -269.256855)
			(xy 107.2388 -269.210581) (xy 107.269326 -269.168565) (xy 107.306049 -269.131842) (xy 107.348065 -269.101316)
			(xy 107.394339 -269.077738) (xy 107.443732 -269.06169) (xy 107.495027 -269.053565) (xy 107.546961 -269.053565)
			(xy 107.598256 -269.06169) (xy 107.647649 -269.077738) (xy 107.693923 -269.101316) (xy 107.735939 -269.131842)
			(xy 107.772662 -269.168565) (xy 107.803188 -269.210581) (xy 107.826766 -269.256855) (xy 107.842814 -269.306248)
			(xy 107.850939 -269.357543) (xy 107.851448 -269.38351) (xy 107.850939 -269.409477) (xy 108.130849 -269.409477)
			(xy 108.130849 -269.357543) (xy 108.138974 -269.306248) (xy 108.155022 -269.256855) (xy 108.1786 -269.210581)
			(xy 108.209126 -269.168565) (xy 108.245849 -269.131842) (xy 108.287865 -269.101316) (xy 108.334139 -269.077738)
			(xy 108.383532 -269.06169) (xy 108.434827 -269.053565) (xy 108.486761 -269.053565) (xy 108.538056 -269.06169)
			(xy 108.587449 -269.077738) (xy 108.633723 -269.101316) (xy 108.675739 -269.131842) (xy 108.712462 -269.168565)
			(xy 108.742988 -269.210581) (xy 108.766566 -269.256855) (xy 108.782614 -269.306248) (xy 108.790739 -269.357543)
			(xy 108.791248 -269.38351) (xy 108.790739 -269.409477) (xy 109.070649 -269.409477) (xy 109.070649 -269.357543)
			(xy 109.078774 -269.306248) (xy 109.094822 -269.256855) (xy 109.1184 -269.210581) (xy 109.148926 -269.168565)
			(xy 109.185649 -269.131842) (xy 109.227665 -269.101316) (xy 109.273939 -269.077738) (xy 109.323332 -269.06169)
			(xy 109.374627 -269.053565) (xy 109.426561 -269.053565) (xy 109.477856 -269.06169) (xy 109.527249 -269.077738)
			(xy 109.573523 -269.101316) (xy 109.615539 -269.131842) (xy 109.652262 -269.168565) (xy 109.682788 -269.210581)
			(xy 109.706366 -269.256855) (xy 109.722414 -269.306248) (xy 109.730539 -269.357543) (xy 109.731048 -269.38351)
			(xy 109.730539 -269.409477) (xy 110.010449 -269.409477) (xy 110.010449 -269.357543) (xy 110.018574 -269.306248)
			(xy 110.034622 -269.256855) (xy 110.0582 -269.210581) (xy 110.088726 -269.168565) (xy 110.125449 -269.131842)
			(xy 110.167465 -269.101316) (xy 110.213739 -269.077738) (xy 110.263132 -269.06169) (xy 110.314427 -269.053565)
			(xy 110.366361 -269.053565) (xy 110.417656 -269.06169) (xy 110.467049 -269.077738) (xy 110.513323 -269.101316)
			(xy 110.555339 -269.131842) (xy 110.592062 -269.168565) (xy 110.622588 -269.210581) (xy 110.646166 -269.256855)
			(xy 110.662214 -269.306248) (xy 110.670339 -269.357543) (xy 110.670848 -269.38351) (xy 110.670339 -269.409477)
			(xy 110.950503 -269.409477) (xy 110.950503 -269.357543) (xy 110.958628 -269.306248) (xy 110.974676 -269.256855)
			(xy 110.998254 -269.210581) (xy 111.02878 -269.168565) (xy 111.065503 -269.131842) (xy 111.107519 -269.101316)
			(xy 111.153793 -269.077738) (xy 111.203186 -269.06169) (xy 111.254481 -269.053565) (xy 111.306415 -269.053565)
			(xy 111.35771 -269.06169) (xy 111.407103 -269.077738) (xy 111.453377 -269.101316) (xy 111.495393 -269.131842)
			(xy 111.532116 -269.168565) (xy 111.562642 -269.210581) (xy 111.58622 -269.256855) (xy 111.602268 -269.306248)
			(xy 111.610393 -269.357543) (xy 111.610902 -269.38351) (xy 111.610393 -269.409477) (xy 111.890303 -269.409477)
			(xy 111.890303 -269.357543) (xy 111.898428 -269.306248) (xy 111.914476 -269.256855) (xy 111.938054 -269.210581)
			(xy 111.96858 -269.168565) (xy 112.005303 -269.131842) (xy 112.047319 -269.101316) (xy 112.093593 -269.077738)
			(xy 112.142986 -269.06169) (xy 112.194281 -269.053565) (xy 112.246215 -269.053565) (xy 112.29751 -269.06169)
			(xy 112.346903 -269.077738) (xy 112.393177 -269.101316) (xy 112.435193 -269.131842) (xy 112.471916 -269.168565)
			(xy 112.502442 -269.210581) (xy 112.52602 -269.256855) (xy 112.542068 -269.306248) (xy 112.550193 -269.357543)
			(xy 112.550702 -269.38351) (xy 112.550193 -269.409477) (xy 112.829849 -269.409477) (xy 112.829849 -269.357543)
			(xy 112.837974 -269.306248) (xy 112.854022 -269.256855) (xy 112.8776 -269.210581) (xy 112.908126 -269.168565)
			(xy 112.944849 -269.131842) (xy 112.986865 -269.101316) (xy 113.033139 -269.077738) (xy 113.082532 -269.06169)
			(xy 113.133827 -269.053565) (xy 113.185761 -269.053565) (xy 113.237056 -269.06169) (xy 113.286449 -269.077738)
			(xy 113.332723 -269.101316) (xy 113.374739 -269.131842) (xy 113.411462 -269.168565) (xy 113.441988 -269.210581)
			(xy 113.465566 -269.256855) (xy 113.481614 -269.306248) (xy 113.489739 -269.357543) (xy 113.490248 -269.38351)
			(xy 113.489739 -269.409477) (xy 113.770157 -269.409477) (xy 113.770157 -269.357543) (xy 113.778282 -269.306248)
			(xy 113.79433 -269.256855) (xy 113.817908 -269.210581) (xy 113.848434 -269.168565) (xy 113.885157 -269.131842)
			(xy 113.927173 -269.101316) (xy 113.973447 -269.077738) (xy 114.02284 -269.06169) (xy 114.074135 -269.053565)
			(xy 114.126069 -269.053565) (xy 114.177364 -269.06169) (xy 114.226757 -269.077738) (xy 114.273031 -269.101316)
			(xy 114.315047 -269.131842) (xy 114.35177 -269.168565) (xy 114.382296 -269.210581) (xy 114.405874 -269.256855)
			(xy 114.421922 -269.306248) (xy 114.430047 -269.357543) (xy 114.430556 -269.38351) (xy 114.430047 -269.409477)
			(xy 114.421922 -269.460772) (xy 114.405874 -269.510165) (xy 114.382296 -269.556439) (xy 114.35177 -269.598455)
			(xy 114.315047 -269.635178) (xy 114.273031 -269.665704) (xy 114.226757 -269.689282) (xy 114.177364 -269.70533)
			(xy 114.126069 -269.713455) (xy 114.074135 -269.713455) (xy 114.02284 -269.70533) (xy 113.973447 -269.689282)
			(xy 113.927173 -269.665704) (xy 113.885157 -269.635178) (xy 113.848434 -269.598455) (xy 113.817908 -269.556439)
			(xy 113.79433 -269.510165) (xy 113.778282 -269.460772) (xy 113.770157 -269.409477) (xy 113.489739 -269.409477)
			(xy 113.481614 -269.460772) (xy 113.465566 -269.510165) (xy 113.441988 -269.556439) (xy 113.411462 -269.598455)
			(xy 113.374739 -269.635178) (xy 113.332723 -269.665704) (xy 113.286449 -269.689282) (xy 113.237056 -269.70533)
			(xy 113.185761 -269.713455) (xy 113.133827 -269.713455) (xy 113.082532 -269.70533) (xy 113.033139 -269.689282)
			(xy 112.986865 -269.665704) (xy 112.944849 -269.635178) (xy 112.908126 -269.598455) (xy 112.8776 -269.556439)
			(xy 112.854022 -269.510165) (xy 112.837974 -269.460772) (xy 112.829849 -269.409477) (xy 112.550193 -269.409477)
			(xy 112.542068 -269.460772) (xy 112.52602 -269.510165) (xy 112.502442 -269.556439) (xy 112.471916 -269.598455)
			(xy 112.435193 -269.635178) (xy 112.393177 -269.665704) (xy 112.346903 -269.689282) (xy 112.29751 -269.70533)
			(xy 112.246215 -269.713455) (xy 112.194281 -269.713455) (xy 112.142986 -269.70533) (xy 112.093593 -269.689282)
			(xy 112.047319 -269.665704) (xy 112.005303 -269.635178) (xy 111.96858 -269.598455) (xy 111.938054 -269.556439)
			(xy 111.914476 -269.510165) (xy 111.898428 -269.460772) (xy 111.890303 -269.409477) (xy 111.610393 -269.409477)
			(xy 111.602268 -269.460772) (xy 111.58622 -269.510165) (xy 111.562642 -269.556439) (xy 111.532116 -269.598455)
			(xy 111.495393 -269.635178) (xy 111.453377 -269.665704) (xy 111.407103 -269.689282) (xy 111.35771 -269.70533)
			(xy 111.306415 -269.713455) (xy 111.254481 -269.713455) (xy 111.203186 -269.70533) (xy 111.153793 -269.689282)
			(xy 111.107519 -269.665704) (xy 111.065503 -269.635178) (xy 111.02878 -269.598455) (xy 110.998254 -269.556439)
			(xy 110.974676 -269.510165) (xy 110.958628 -269.460772) (xy 110.950503 -269.409477) (xy 110.670339 -269.409477)
			(xy 110.662214 -269.460772) (xy 110.646166 -269.510165) (xy 110.622588 -269.556439) (xy 110.592062 -269.598455)
			(xy 110.555339 -269.635178) (xy 110.513323 -269.665704) (xy 110.467049 -269.689282) (xy 110.417656 -269.70533)
			(xy 110.366361 -269.713455) (xy 110.314427 -269.713455) (xy 110.263132 -269.70533) (xy 110.213739 -269.689282)
			(xy 110.167465 -269.665704) (xy 110.125449 -269.635178) (xy 110.088726 -269.598455) (xy 110.0582 -269.556439)
			(xy 110.034622 -269.510165) (xy 110.018574 -269.460772) (xy 110.010449 -269.409477) (xy 109.730539 -269.409477)
			(xy 109.722414 -269.460772) (xy 109.706366 -269.510165) (xy 109.682788 -269.556439) (xy 109.652262 -269.598455)
			(xy 109.615539 -269.635178) (xy 109.573523 -269.665704) (xy 109.527249 -269.689282) (xy 109.477856 -269.70533)
			(xy 109.426561 -269.713455) (xy 109.374627 -269.713455) (xy 109.323332 -269.70533) (xy 109.273939 -269.689282)
			(xy 109.227665 -269.665704) (xy 109.185649 -269.635178) (xy 109.148926 -269.598455) (xy 109.1184 -269.556439)
			(xy 109.094822 -269.510165) (xy 109.078774 -269.460772) (xy 109.070649 -269.409477) (xy 108.790739 -269.409477)
			(xy 108.782614 -269.460772) (xy 108.766566 -269.510165) (xy 108.742988 -269.556439) (xy 108.712462 -269.598455)
			(xy 108.675739 -269.635178) (xy 108.633723 -269.665704) (xy 108.587449 -269.689282) (xy 108.538056 -269.70533)
			(xy 108.486761 -269.713455) (xy 108.434827 -269.713455) (xy 108.383532 -269.70533) (xy 108.334139 -269.689282)
			(xy 108.287865 -269.665704) (xy 108.245849 -269.635178) (xy 108.209126 -269.598455) (xy 108.1786 -269.556439)
			(xy 108.155022 -269.510165) (xy 108.138974 -269.460772) (xy 108.130849 -269.409477) (xy 107.850939 -269.409477)
			(xy 107.842814 -269.460772) (xy 107.826766 -269.510165) (xy 107.803188 -269.556439) (xy 107.772662 -269.598455)
			(xy 107.735939 -269.635178) (xy 107.693923 -269.665704) (xy 107.647649 -269.689282) (xy 107.598256 -269.70533)
			(xy 107.546961 -269.713455) (xy 107.495027 -269.713455) (xy 107.443732 -269.70533) (xy 107.394339 -269.689282)
			(xy 107.348065 -269.665704) (xy 107.306049 -269.635178) (xy 107.269326 -269.598455) (xy 107.2388 -269.556439)
			(xy 107.215222 -269.510165) (xy 107.199174 -269.460772) (xy 107.191049 -269.409477) (xy 106.911139 -269.409477)
			(xy 106.903014 -269.460772) (xy 106.886966 -269.510165) (xy 106.863388 -269.556439) (xy 106.832862 -269.598455)
			(xy 106.796139 -269.635178) (xy 106.754123 -269.665704) (xy 106.707849 -269.689282) (xy 106.658456 -269.70533)
			(xy 106.607161 -269.713455) (xy 106.555227 -269.713455) (xy 106.503932 -269.70533) (xy 106.454539 -269.689282)
			(xy 106.408265 -269.665704) (xy 106.366249 -269.635178) (xy 106.329526 -269.598455) (xy 106.299 -269.556439)
			(xy 106.275422 -269.510165) (xy 106.259374 -269.460772) (xy 106.251249 -269.409477) (xy 105.971339 -269.409477)
			(xy 105.963214 -269.460772) (xy 105.947166 -269.510165) (xy 105.923588 -269.556439) (xy 105.893062 -269.598455)
			(xy 105.856339 -269.635178) (xy 105.814323 -269.665704) (xy 105.768049 -269.689282) (xy 105.718656 -269.70533)
			(xy 105.667361 -269.713455) (xy 105.615427 -269.713455) (xy 105.564132 -269.70533) (xy 105.514739 -269.689282)
			(xy 105.468465 -269.665704) (xy 105.426449 -269.635178) (xy 105.389726 -269.598455) (xy 105.3592 -269.556439)
			(xy 105.335622 -269.510165) (xy 105.319574 -269.460772) (xy 105.311449 -269.409477) (xy 105.031539 -269.409477)
			(xy 105.023414 -269.460772) (xy 105.007366 -269.510165) (xy 104.983788 -269.556439) (xy 104.953262 -269.598455)
			(xy 104.916539 -269.635178) (xy 104.874523 -269.665704) (xy 104.828249 -269.689282) (xy 104.778856 -269.70533)
			(xy 104.727561 -269.713455) (xy 104.675627 -269.713455) (xy 104.624332 -269.70533) (xy 104.574939 -269.689282)
			(xy 104.528665 -269.665704) (xy 104.486649 -269.635178) (xy 104.449926 -269.598455) (xy 104.4194 -269.556439)
			(xy 104.395822 -269.510165) (xy 104.379774 -269.460772) (xy 104.371649 -269.409477) (xy 104.091739 -269.409477)
			(xy 104.083614 -269.460772) (xy 104.067566 -269.510165) (xy 104.043988 -269.556439) (xy 104.013462 -269.598455)
			(xy 103.976739 -269.635178) (xy 103.934723 -269.665704) (xy 103.888449 -269.689282) (xy 103.839056 -269.70533)
			(xy 103.787761 -269.713455) (xy 103.735827 -269.713455) (xy 103.684532 -269.70533) (xy 103.635139 -269.689282)
			(xy 103.588865 -269.665704) (xy 103.546849 -269.635178) (xy 103.510126 -269.598455) (xy 103.4796 -269.556439)
			(xy 103.456022 -269.510165) (xy 103.439974 -269.460772) (xy 103.431849 -269.409477) (xy 103.151939 -269.409477)
			(xy 103.143814 -269.460772) (xy 103.127766 -269.510165) (xy 103.104188 -269.556439) (xy 103.073662 -269.598455)
			(xy 103.036939 -269.635178) (xy 102.994923 -269.665704) (xy 102.948649 -269.689282) (xy 102.899256 -269.70533)
			(xy 102.847961 -269.713455) (xy 102.796027 -269.713455) (xy 102.744732 -269.70533) (xy 102.695339 -269.689282)
			(xy 102.649065 -269.665704) (xy 102.607049 -269.635178) (xy 102.570326 -269.598455) (xy 102.5398 -269.556439)
			(xy 102.516222 -269.510165) (xy 102.500174 -269.460772) (xy 102.492049 -269.409477) (xy 102.212647 -269.409477)
			(xy 102.204522 -269.460772) (xy 102.188474 -269.510165) (xy 102.164896 -269.556439) (xy 102.13437 -269.598455)
			(xy 102.097647 -269.635178) (xy 102.055631 -269.665704) (xy 102.009357 -269.689282) (xy 101.959964 -269.70533)
			(xy 101.908669 -269.713455) (xy 101.856735 -269.713455) (xy 101.80544 -269.70533) (xy 101.756047 -269.689282)
			(xy 101.709773 -269.665704) (xy 101.667757 -269.635178) (xy 101.631034 -269.598455) (xy 101.600508 -269.556439)
			(xy 101.57693 -269.510165) (xy 101.560882 -269.460772) (xy 101.552757 -269.409477) (xy 101.272339 -269.409477)
			(xy 101.264214 -269.460772) (xy 101.248166 -269.510165) (xy 101.224588 -269.556439) (xy 101.194062 -269.598455)
			(xy 101.157339 -269.635178) (xy 101.115323 -269.665704) (xy 101.069049 -269.689282) (xy 101.019656 -269.70533)
			(xy 100.968361 -269.713455) (xy 100.916427 -269.713455) (xy 100.865132 -269.70533) (xy 100.815739 -269.689282)
			(xy 100.769465 -269.665704) (xy 100.727449 -269.635178) (xy 100.690726 -269.598455) (xy 100.6602 -269.556439)
			(xy 100.636622 -269.510165) (xy 100.620574 -269.460772) (xy 100.612449 -269.409477) (xy 100.332539 -269.409477)
			(xy 100.324414 -269.460772) (xy 100.308366 -269.510165) (xy 100.284788 -269.556439) (xy 100.254262 -269.598455)
			(xy 100.217539 -269.635178) (xy 100.175523 -269.665704) (xy 100.129249 -269.689282) (xy 100.079856 -269.70533)
			(xy 100.028561 -269.713455) (xy 99.976627 -269.713455) (xy 99.925332 -269.70533) (xy 99.875939 -269.689282)
			(xy 99.829665 -269.665704) (xy 99.787649 -269.635178) (xy 99.750926 -269.598455) (xy 99.7204 -269.556439)
			(xy 99.696822 -269.510165) (xy 99.680774 -269.460772) (xy 99.672649 -269.409477) (xy 99.392739 -269.409477)
			(xy 99.384614 -269.460772) (xy 99.368566 -269.510165) (xy 99.344988 -269.556439) (xy 99.314462 -269.598455)
			(xy 99.277739 -269.635178) (xy 99.235723 -269.665704) (xy 99.189449 -269.689282) (xy 99.140056 -269.70533)
			(xy 99.088761 -269.713455) (xy 99.036827 -269.713455) (xy 98.985532 -269.70533) (xy 98.936139 -269.689282)
			(xy 98.889865 -269.665704) (xy 98.847849 -269.635178) (xy 98.811126 -269.598455) (xy 98.7806 -269.556439)
			(xy 98.757022 -269.510165) (xy 98.740974 -269.460772) (xy 98.732849 -269.409477) (xy 98.453193 -269.409477)
			(xy 98.445068 -269.460772) (xy 98.42902 -269.510165) (xy 98.405442 -269.556439) (xy 98.374916 -269.598455)
			(xy 98.338193 -269.635178) (xy 98.296177 -269.665704) (xy 98.249903 -269.689282) (xy 98.20051 -269.70533)
			(xy 98.149215 -269.713455) (xy 98.097281 -269.713455) (xy 98.045986 -269.70533) (xy 97.996593 -269.689282)
			(xy 97.950319 -269.665704) (xy 97.908303 -269.635178) (xy 97.87158 -269.598455) (xy 97.841054 -269.556439)
			(xy 97.817476 -269.510165) (xy 97.801428 -269.460772) (xy 97.793303 -269.409477) (xy 97.513139 -269.409477)
			(xy 97.505014 -269.460772) (xy 97.488966 -269.510165) (xy 97.465388 -269.556439) (xy 97.434862 -269.598455)
			(xy 97.398139 -269.635178) (xy 97.356123 -269.665704) (xy 97.309849 -269.689282) (xy 97.260456 -269.70533)
			(xy 97.209161 -269.713455) (xy 97.157227 -269.713455) (xy 97.105932 -269.70533) (xy 97.056539 -269.689282)
			(xy 97.010265 -269.665704) (xy 96.968249 -269.635178) (xy 96.931526 -269.598455) (xy 96.901 -269.556439)
			(xy 96.877422 -269.510165) (xy 96.861374 -269.460772) (xy 96.853249 -269.409477) (xy 96.573339 -269.409477)
			(xy 96.565214 -269.460772) (xy 96.549166 -269.510165) (xy 96.525588 -269.556439) (xy 96.495062 -269.598455)
			(xy 96.458339 -269.635178) (xy 96.416323 -269.665704) (xy 96.370049 -269.689282) (xy 96.320656 -269.70533)
			(xy 96.269361 -269.713455) (xy 96.217427 -269.713455) (xy 96.166132 -269.70533) (xy 96.116739 -269.689282)
			(xy 96.070465 -269.665704) (xy 96.028449 -269.635178) (xy 95.991726 -269.598455) (xy 95.9612 -269.556439)
			(xy 95.937622 -269.510165) (xy 95.921574 -269.460772) (xy 95.913449 -269.409477) (xy 95.633539 -269.409477)
			(xy 95.625414 -269.460772) (xy 95.609366 -269.510165) (xy 95.585788 -269.556439) (xy 95.555262 -269.598455)
			(xy 95.518539 -269.635178) (xy 95.476523 -269.665704) (xy 95.430249 -269.689282) (xy 95.380856 -269.70533)
			(xy 95.329561 -269.713455) (xy 95.277627 -269.713455) (xy 95.226332 -269.70533) (xy 95.176939 -269.689282)
			(xy 95.130665 -269.665704) (xy 95.088649 -269.635178) (xy 95.051926 -269.598455) (xy 95.0214 -269.556439)
			(xy 94.997822 -269.510165) (xy 94.981774 -269.460772) (xy 94.973649 -269.409477) (xy 94.693739 -269.409477)
			(xy 94.685614 -269.460772) (xy 94.669566 -269.510165) (xy 94.645988 -269.556439) (xy 94.615462 -269.598455)
			(xy 94.578739 -269.635178) (xy 94.536723 -269.665704) (xy 94.490449 -269.689282) (xy 94.441056 -269.70533)
			(xy 94.389761 -269.713455) (xy 94.337827 -269.713455) (xy 94.286532 -269.70533) (xy 94.237139 -269.689282)
			(xy 94.190865 -269.665704) (xy 94.148849 -269.635178) (xy 94.112126 -269.598455) (xy 94.0816 -269.556439)
			(xy 94.058022 -269.510165) (xy 94.041974 -269.460772) (xy 94.033849 -269.409477) (xy 93.753939 -269.409477)
			(xy 93.745814 -269.460772) (xy 93.729766 -269.510165) (xy 93.706188 -269.556439) (xy 93.675662 -269.598455)
			(xy 93.638939 -269.635178) (xy 93.596923 -269.665704) (xy 93.550649 -269.689282) (xy 93.501256 -269.70533)
			(xy 93.449961 -269.713455) (xy 93.398027 -269.713455) (xy 93.346732 -269.70533) (xy 93.297339 -269.689282)
			(xy 93.251065 -269.665704) (xy 93.209049 -269.635178) (xy 93.172326 -269.598455) (xy 93.1418 -269.556439)
			(xy 93.118222 -269.510165) (xy 93.102174 -269.460772) (xy 93.094049 -269.409477) (xy 92.814139 -269.409477)
			(xy 92.806014 -269.460772) (xy 92.789966 -269.510165) (xy 92.766388 -269.556439) (xy 92.735862 -269.598455)
			(xy 92.699139 -269.635178) (xy 92.657123 -269.665704) (xy 92.610849 -269.689282) (xy 92.561456 -269.70533)
			(xy 92.510161 -269.713455) (xy 92.458227 -269.713455) (xy 92.406932 -269.70533) (xy 92.357539 -269.689282)
			(xy 92.311265 -269.665704) (xy 92.269249 -269.635178) (xy 92.232526 -269.598455) (xy 92.202 -269.556439)
			(xy 92.178422 -269.510165) (xy 92.162374 -269.460772) (xy 92.154249 -269.409477) (xy 91.873929 -269.409477)
			(xy 91.872004 -269.434375) (xy 91.860301 -269.484037) (xy 91.841105 -269.53131) (xy 91.814873 -269.575072)
			(xy 91.782227 -269.614283) (xy 91.743944 -269.648012) (xy 91.722702 -269.662148) (xy 91.712034 -269.669006)
			(xy 91.68765 -269.711678) (xy 91.68765 -269.830804) (xy 91.688005 -269.839689) (xy 91.694163 -269.856357)
			(xy 91.705715 -269.869859) (xy 91.713304 -269.874492) (xy 91.790012 -269.917164) (xy 91.795734 -269.920126)
			(xy 91.808209 -269.923334) (xy 91.81465 -269.923514) (xy 91.840304 -269.916148) (xy 91.845892 -269.912846)
			(xy 91.871546 -269.898426) (xy 91.926702 -269.877927) (xy 91.984618 -269.867525) (xy 92.01404 -269.866872)
			(xy 92.014294 -269.866872) (xy 92.040285 -269.867355) (xy 92.091628 -269.875486) (xy 92.141066 -269.891548)
			(xy 92.187383 -269.915147) (xy 92.229438 -269.945701) (xy 92.266195 -269.982458) (xy 92.29675 -270.024512)
			(xy 92.320349 -270.070829) (xy 92.336413 -270.120267) (xy 92.344545 -270.171609) (xy 92.344545 -270.223547)
			(xy 92.624403 -270.223547) (xy 92.624403 -270.171613) (xy 92.632528 -270.120318) (xy 92.648576 -270.070925)
			(xy 92.672154 -270.024651) (xy 92.70268 -269.982635) (xy 92.739403 -269.945912) (xy 92.781419 -269.915386)
			(xy 92.827693 -269.891808) (xy 92.877086 -269.87576) (xy 92.928381 -269.867635) (xy 92.980315 -269.867635)
			(xy 93.03161 -269.87576) (xy 93.081003 -269.891808) (xy 93.127277 -269.915386) (xy 93.169293 -269.945912)
			(xy 93.206016 -269.982635) (xy 93.236542 -270.024651) (xy 93.26012 -270.070925) (xy 93.276168 -270.120318)
			(xy 93.284293 -270.171613) (xy 93.284802 -270.19758) (xy 93.284293 -270.223547) (xy 93.564203 -270.223547)
			(xy 93.564203 -270.171613) (xy 93.572328 -270.120318) (xy 93.588376 -270.070925) (xy 93.611954 -270.024651)
			(xy 93.64248 -269.982635) (xy 93.679203 -269.945912) (xy 93.721219 -269.915386) (xy 93.767493 -269.891808)
			(xy 93.816886 -269.87576) (xy 93.868181 -269.867635) (xy 93.920115 -269.867635) (xy 93.97141 -269.87576)
			(xy 94.020803 -269.891808) (xy 94.067077 -269.915386) (xy 94.109093 -269.945912) (xy 94.145816 -269.982635)
			(xy 94.176342 -270.024651) (xy 94.19992 -270.070925) (xy 94.215968 -270.120318) (xy 94.224093 -270.171613)
			(xy 94.224602 -270.19758) (xy 94.224093 -270.223547) (xy 94.504003 -270.223547) (xy 94.504003 -270.171613)
			(xy 94.512128 -270.120318) (xy 94.528176 -270.070925) (xy 94.551754 -270.024651) (xy 94.58228 -269.982635)
			(xy 94.619003 -269.945912) (xy 94.661019 -269.915386) (xy 94.707293 -269.891808) (xy 94.756686 -269.87576)
			(xy 94.807981 -269.867635) (xy 94.859915 -269.867635) (xy 94.91121 -269.87576) (xy 94.960603 -269.891808)
			(xy 95.006877 -269.915386) (xy 95.048893 -269.945912) (xy 95.085616 -269.982635) (xy 95.116142 -270.024651)
			(xy 95.13972 -270.070925) (xy 95.155768 -270.120318) (xy 95.163893 -270.171613) (xy 95.164402 -270.19758)
			(xy 95.163893 -270.223547) (xy 95.443803 -270.223547) (xy 95.443803 -270.171613) (xy 95.451928 -270.120318)
			(xy 95.467976 -270.070925) (xy 95.491554 -270.024651) (xy 95.52208 -269.982635) (xy 95.558803 -269.945912)
			(xy 95.600819 -269.915386) (xy 95.647093 -269.891808) (xy 95.696486 -269.87576) (xy 95.747781 -269.867635)
			(xy 95.799715 -269.867635) (xy 95.85101 -269.87576) (xy 95.900403 -269.891808) (xy 95.946677 -269.915386)
			(xy 95.988693 -269.945912) (xy 96.025416 -269.982635) (xy 96.055942 -270.024651) (xy 96.07952 -270.070925)
			(xy 96.095568 -270.120318) (xy 96.103693 -270.171613) (xy 96.104202 -270.19758) (xy 96.103693 -270.223547)
			(xy 96.383603 -270.223547) (xy 96.383603 -270.171613) (xy 96.391728 -270.120318) (xy 96.407776 -270.070925)
			(xy 96.431354 -270.024651) (xy 96.46188 -269.982635) (xy 96.498603 -269.945912) (xy 96.540619 -269.915386)
			(xy 96.586893 -269.891808) (xy 96.636286 -269.87576) (xy 96.687581 -269.867635) (xy 96.739515 -269.867635)
			(xy 96.79081 -269.87576) (xy 96.840203 -269.891808) (xy 96.886477 -269.915386) (xy 96.928493 -269.945912)
			(xy 96.965216 -269.982635) (xy 96.995742 -270.024651) (xy 97.01932 -270.070925) (xy 97.035368 -270.120318)
			(xy 97.043493 -270.171613) (xy 97.044002 -270.19758) (xy 97.043493 -270.223547) (xy 97.323403 -270.223547)
			(xy 97.323403 -270.171613) (xy 97.331528 -270.120318) (xy 97.347576 -270.070925) (xy 97.371154 -270.024651)
			(xy 97.40168 -269.982635) (xy 97.438403 -269.945912) (xy 97.480419 -269.915386) (xy 97.526693 -269.891808)
			(xy 97.576086 -269.87576) (xy 97.627381 -269.867635) (xy 97.679315 -269.867635) (xy 97.73061 -269.87576)
			(xy 97.780003 -269.891808) (xy 97.826277 -269.915386) (xy 97.868293 -269.945912) (xy 97.905016 -269.982635)
			(xy 97.935542 -270.024651) (xy 97.95912 -270.070925) (xy 97.975168 -270.120318) (xy 97.983293 -270.171613)
			(xy 97.983802 -270.19758) (xy 97.983293 -270.223547) (xy 98.262949 -270.223547) (xy 98.262949 -270.171613)
			(xy 98.271074 -270.120318) (xy 98.287122 -270.070925) (xy 98.3107 -270.024651) (xy 98.341226 -269.982635)
			(xy 98.377949 -269.945912) (xy 98.419965 -269.915386) (xy 98.466239 -269.891808) (xy 98.515632 -269.87576)
			(xy 98.566927 -269.867635) (xy 98.618861 -269.867635) (xy 98.670156 -269.87576) (xy 98.719549 -269.891808)
			(xy 98.765823 -269.915386) (xy 98.807839 -269.945912) (xy 98.844562 -269.982635) (xy 98.875088 -270.024651)
			(xy 98.898666 -270.070925) (xy 98.914714 -270.120318) (xy 98.922839 -270.171613) (xy 98.923348 -270.19758)
			(xy 98.922839 -270.223547) (xy 99.203003 -270.223547) (xy 99.203003 -270.171613) (xy 99.211128 -270.120318)
			(xy 99.227176 -270.070925) (xy 99.250754 -270.024651) (xy 99.28128 -269.982635) (xy 99.318003 -269.945912)
			(xy 99.360019 -269.915386) (xy 99.406293 -269.891808) (xy 99.455686 -269.87576) (xy 99.506981 -269.867635)
			(xy 99.558915 -269.867635) (xy 99.61021 -269.87576) (xy 99.659603 -269.891808) (xy 99.705877 -269.915386)
			(xy 99.747893 -269.945912) (xy 99.784616 -269.982635) (xy 99.815142 -270.024651) (xy 99.83872 -270.070925)
			(xy 99.854768 -270.120318) (xy 99.862893 -270.171613) (xy 99.863402 -270.19758) (xy 99.862893 -270.223547)
			(xy 100.142803 -270.223547) (xy 100.142803 -270.171613) (xy 100.150928 -270.120318) (xy 100.166976 -270.070925)
			(xy 100.190554 -270.024651) (xy 100.22108 -269.982635) (xy 100.257803 -269.945912) (xy 100.299819 -269.915386)
			(xy 100.346093 -269.891808) (xy 100.395486 -269.87576) (xy 100.446781 -269.867635) (xy 100.498715 -269.867635)
			(xy 100.55001 -269.87576) (xy 100.599403 -269.891808) (xy 100.645677 -269.915386) (xy 100.687693 -269.945912)
			(xy 100.724416 -269.982635) (xy 100.754942 -270.024651) (xy 100.77852 -270.070925) (xy 100.794568 -270.120318)
			(xy 100.802693 -270.171613) (xy 100.803202 -270.19758) (xy 100.802693 -270.223547) (xy 101.082603 -270.223547)
			(xy 101.082603 -270.171613) (xy 101.090728 -270.120318) (xy 101.106776 -270.070925) (xy 101.130354 -270.024651)
			(xy 101.16088 -269.982635) (xy 101.197603 -269.945912) (xy 101.239619 -269.915386) (xy 101.285893 -269.891808)
			(xy 101.335286 -269.87576) (xy 101.386581 -269.867635) (xy 101.438515 -269.867635) (xy 101.48981 -269.87576)
			(xy 101.539203 -269.891808) (xy 101.585477 -269.915386) (xy 101.627493 -269.945912) (xy 101.664216 -269.982635)
			(xy 101.694742 -270.024651) (xy 101.71832 -270.070925) (xy 101.734368 -270.120318) (xy 101.742493 -270.171613)
			(xy 101.743002 -270.19758) (xy 101.742493 -270.223547) (xy 102.022403 -270.223547) (xy 102.022403 -270.171613)
			(xy 102.030528 -270.120318) (xy 102.046576 -270.070925) (xy 102.070154 -270.024651) (xy 102.10068 -269.982635)
			(xy 102.137403 -269.945912) (xy 102.179419 -269.915386) (xy 102.225693 -269.891808) (xy 102.275086 -269.87576)
			(xy 102.326381 -269.867635) (xy 102.378315 -269.867635) (xy 102.42961 -269.87576) (xy 102.479003 -269.891808)
			(xy 102.525277 -269.915386) (xy 102.567293 -269.945912) (xy 102.604016 -269.982635) (xy 102.634542 -270.024651)
			(xy 102.65812 -270.070925) (xy 102.674168 -270.120318) (xy 102.682293 -270.171613) (xy 102.682802 -270.19758)
			(xy 102.682293 -270.223547) (xy 102.962203 -270.223547) (xy 102.962203 -270.171613) (xy 102.970328 -270.120318)
			(xy 102.986376 -270.070925) (xy 103.009954 -270.024651) (xy 103.04048 -269.982635) (xy 103.077203 -269.945912)
			(xy 103.119219 -269.915386) (xy 103.165493 -269.891808) (xy 103.214886 -269.87576) (xy 103.266181 -269.867635)
			(xy 103.318115 -269.867635) (xy 103.36941 -269.87576) (xy 103.418803 -269.891808) (xy 103.465077 -269.915386)
			(xy 103.507093 -269.945912) (xy 103.543816 -269.982635) (xy 103.574342 -270.024651) (xy 103.59792 -270.070925)
			(xy 103.613968 -270.120318) (xy 103.622093 -270.171613) (xy 103.622602 -270.19758) (xy 103.622093 -270.223547)
			(xy 103.902003 -270.223547) (xy 103.902003 -270.171613) (xy 103.910128 -270.120318) (xy 103.926176 -270.070925)
			(xy 103.949754 -270.024651) (xy 103.98028 -269.982635) (xy 104.017003 -269.945912) (xy 104.059019 -269.915386)
			(xy 104.105293 -269.891808) (xy 104.154686 -269.87576) (xy 104.205981 -269.867635) (xy 104.257915 -269.867635)
			(xy 104.30921 -269.87576) (xy 104.358603 -269.891808) (xy 104.404877 -269.915386) (xy 104.446893 -269.945912)
			(xy 104.483616 -269.982635) (xy 104.514142 -270.024651) (xy 104.53772 -270.070925) (xy 104.553768 -270.120318)
			(xy 104.561893 -270.171613) (xy 104.562402 -270.19758) (xy 104.561893 -270.223547) (xy 104.841803 -270.223547)
			(xy 104.841803 -270.171613) (xy 104.849928 -270.120318) (xy 104.865976 -270.070925) (xy 104.889554 -270.024651)
			(xy 104.92008 -269.982635) (xy 104.956803 -269.945912) (xy 104.998819 -269.915386) (xy 105.045093 -269.891808)
			(xy 105.094486 -269.87576) (xy 105.145781 -269.867635) (xy 105.197715 -269.867635) (xy 105.24901 -269.87576)
			(xy 105.298403 -269.891808) (xy 105.344677 -269.915386) (xy 105.386693 -269.945912) (xy 105.423416 -269.982635)
			(xy 105.453942 -270.024651) (xy 105.47752 -270.070925) (xy 105.493568 -270.120318) (xy 105.501693 -270.171613)
			(xy 105.502202 -270.19758) (xy 105.501693 -270.223547) (xy 105.781603 -270.223547) (xy 105.781603 -270.171613)
			(xy 105.789728 -270.120318) (xy 105.805776 -270.070925) (xy 105.829354 -270.024651) (xy 105.85988 -269.982635)
			(xy 105.896603 -269.945912) (xy 105.938619 -269.915386) (xy 105.984893 -269.891808) (xy 106.034286 -269.87576)
			(xy 106.085581 -269.867635) (xy 106.137515 -269.867635) (xy 106.18881 -269.87576) (xy 106.238203 -269.891808)
			(xy 106.284477 -269.915386) (xy 106.326493 -269.945912) (xy 106.363216 -269.982635) (xy 106.393742 -270.024651)
			(xy 106.41732 -270.070925) (xy 106.433368 -270.120318) (xy 106.441493 -270.171613) (xy 106.442002 -270.19758)
			(xy 106.441493 -270.223547) (xy 106.721403 -270.223547) (xy 106.721403 -270.171613) (xy 106.729528 -270.120318)
			(xy 106.745576 -270.070925) (xy 106.769154 -270.024651) (xy 106.79968 -269.982635) (xy 106.836403 -269.945912)
			(xy 106.878419 -269.915386) (xy 106.924693 -269.891808) (xy 106.974086 -269.87576) (xy 107.025381 -269.867635)
			(xy 107.077315 -269.867635) (xy 107.12861 -269.87576) (xy 107.178003 -269.891808) (xy 107.224277 -269.915386)
			(xy 107.266293 -269.945912) (xy 107.303016 -269.982635) (xy 107.333542 -270.024651) (xy 107.35712 -270.070925)
			(xy 107.373168 -270.120318) (xy 107.381293 -270.171613) (xy 107.381802 -270.19758) (xy 107.381293 -270.223547)
			(xy 107.661203 -270.223547) (xy 107.661203 -270.171613) (xy 107.669328 -270.120318) (xy 107.685376 -270.070925)
			(xy 107.708954 -270.024651) (xy 107.73948 -269.982635) (xy 107.776203 -269.945912) (xy 107.818219 -269.915386)
			(xy 107.864493 -269.891808) (xy 107.913886 -269.87576) (xy 107.965181 -269.867635) (xy 108.017115 -269.867635)
			(xy 108.06841 -269.87576) (xy 108.117803 -269.891808) (xy 108.164077 -269.915386) (xy 108.206093 -269.945912)
			(xy 108.242816 -269.982635) (xy 108.273342 -270.024651) (xy 108.29692 -270.070925) (xy 108.312968 -270.120318)
			(xy 108.321093 -270.171613) (xy 108.321602 -270.19758) (xy 108.321093 -270.223547) (xy 108.600749 -270.223547)
			(xy 108.600749 -270.171613) (xy 108.608874 -270.120318) (xy 108.624922 -270.070925) (xy 108.6485 -270.024651)
			(xy 108.679026 -269.982635) (xy 108.715749 -269.945912) (xy 108.757765 -269.915386) (xy 108.804039 -269.891808)
			(xy 108.853432 -269.87576) (xy 108.904727 -269.867635) (xy 108.956661 -269.867635) (xy 109.007956 -269.87576)
			(xy 109.057349 -269.891808) (xy 109.103623 -269.915386) (xy 109.145639 -269.945912) (xy 109.182362 -269.982635)
			(xy 109.212888 -270.024651) (xy 109.236466 -270.070925) (xy 109.252514 -270.120318) (xy 109.260639 -270.171613)
			(xy 109.261148 -270.19758) (xy 109.260639 -270.223547) (xy 110.480603 -270.223547) (xy 110.480603 -270.171613)
			(xy 110.488728 -270.120318) (xy 110.504776 -270.070925) (xy 110.528354 -270.024651) (xy 110.55888 -269.982635)
			(xy 110.595603 -269.945912) (xy 110.637619 -269.915386) (xy 110.683893 -269.891808) (xy 110.733286 -269.87576)
			(xy 110.784581 -269.867635) (xy 110.836515 -269.867635) (xy 110.88781 -269.87576) (xy 110.937203 -269.891808)
			(xy 110.983477 -269.915386) (xy 111.025493 -269.945912) (xy 111.062216 -269.982635) (xy 111.092742 -270.024651)
			(xy 111.11632 -270.070925) (xy 111.132368 -270.120318) (xy 111.140493 -270.171613) (xy 111.141002 -270.19758)
			(xy 111.140493 -270.223547) (xy 111.420149 -270.223547) (xy 111.420149 -270.171613) (xy 111.428274 -270.120318)
			(xy 111.444322 -270.070925) (xy 111.4679 -270.024651) (xy 111.498426 -269.982635) (xy 111.535149 -269.945912)
			(xy 111.577165 -269.915386) (xy 111.623439 -269.891808) (xy 111.672832 -269.87576) (xy 111.724127 -269.867635)
			(xy 111.776061 -269.867635) (xy 111.827356 -269.87576) (xy 111.876749 -269.891808) (xy 111.923023 -269.915386)
			(xy 111.965039 -269.945912) (xy 112.001762 -269.982635) (xy 112.032288 -270.024651) (xy 112.055866 -270.070925)
			(xy 112.071914 -270.120318) (xy 112.080039 -270.171613) (xy 112.080548 -270.19758) (xy 112.080039 -270.223547)
			(xy 112.359949 -270.223547) (xy 112.359949 -270.171613) (xy 112.368074 -270.120318) (xy 112.384122 -270.070925)
			(xy 112.4077 -270.024651) (xy 112.438226 -269.982635) (xy 112.474949 -269.945912) (xy 112.516965 -269.915386)
			(xy 112.563239 -269.891808) (xy 112.612632 -269.87576) (xy 112.663927 -269.867635) (xy 112.715861 -269.867635)
			(xy 112.767156 -269.87576) (xy 112.816549 -269.891808) (xy 112.862823 -269.915386) (xy 112.904839 -269.945912)
			(xy 112.941562 -269.982635) (xy 112.972088 -270.024651) (xy 112.995666 -270.070925) (xy 113.011714 -270.120318)
			(xy 113.019839 -270.171613) (xy 113.020348 -270.19758) (xy 113.019839 -270.223547) (xy 113.299749 -270.223547)
			(xy 113.299749 -270.171613) (xy 113.307874 -270.120318) (xy 113.323922 -270.070925) (xy 113.3475 -270.024651)
			(xy 113.378026 -269.982635) (xy 113.414749 -269.945912) (xy 113.456765 -269.915386) (xy 113.503039 -269.891808)
			(xy 113.552432 -269.87576) (xy 113.603727 -269.867635) (xy 113.655661 -269.867635) (xy 113.706956 -269.87576)
			(xy 113.756349 -269.891808) (xy 113.802623 -269.915386) (xy 113.844639 -269.945912) (xy 113.881362 -269.982635)
			(xy 113.911888 -270.024651) (xy 113.935466 -270.070925) (xy 113.951514 -270.120318) (xy 113.959639 -270.171613)
			(xy 113.960148 -270.19758) (xy 113.959639 -270.223547) (xy 114.239549 -270.223547) (xy 114.239549 -270.171613)
			(xy 114.247674 -270.120318) (xy 114.263722 -270.070925) (xy 114.2873 -270.024651) (xy 114.317826 -269.982635)
			(xy 114.354549 -269.945912) (xy 114.396565 -269.915386) (xy 114.442839 -269.891808) (xy 114.492232 -269.87576)
			(xy 114.543527 -269.867635) (xy 114.595461 -269.867635) (xy 114.646756 -269.87576) (xy 114.696149 -269.891808)
			(xy 114.742423 -269.915386) (xy 114.784439 -269.945912) (xy 114.821162 -269.982635) (xy 114.851688 -270.024651)
			(xy 114.875266 -270.070925) (xy 114.891314 -270.120318) (xy 114.899439 -270.171613) (xy 114.899948 -270.19758)
			(xy 114.899439 -270.223547) (xy 115.179349 -270.223547) (xy 115.179349 -270.171613) (xy 115.187474 -270.120318)
			(xy 115.203522 -270.070925) (xy 115.2271 -270.024651) (xy 115.257626 -269.982635) (xy 115.294349 -269.945912)
			(xy 115.336365 -269.915386) (xy 115.382639 -269.891808) (xy 115.432032 -269.87576) (xy 115.483327 -269.867635)
			(xy 115.535261 -269.867635) (xy 115.586556 -269.87576) (xy 115.635949 -269.891808) (xy 115.682223 -269.915386)
			(xy 115.724239 -269.945912) (xy 115.760962 -269.982635) (xy 115.791488 -270.024651) (xy 115.815066 -270.070925)
			(xy 115.831114 -270.120318) (xy 115.839239 -270.171613) (xy 115.839748 -270.19758) (xy 115.839239 -270.223547)
			(xy 115.831114 -270.274842) (xy 115.815066 -270.324235) (xy 115.791488 -270.370509) (xy 115.760962 -270.412525)
			(xy 115.724239 -270.449248) (xy 115.682223 -270.479774) (xy 115.635949 -270.503352) (xy 115.586556 -270.5194)
			(xy 115.535261 -270.527525) (xy 115.483327 -270.527525) (xy 115.432032 -270.5194) (xy 115.382639 -270.503352)
			(xy 115.336365 -270.479774) (xy 115.294349 -270.449248) (xy 115.257626 -270.412525) (xy 115.2271 -270.370509)
			(xy 115.203522 -270.324235) (xy 115.187474 -270.274842) (xy 115.179349 -270.223547) (xy 114.899439 -270.223547)
			(xy 114.891314 -270.274842) (xy 114.875266 -270.324235) (xy 114.851688 -270.370509) (xy 114.821162 -270.412525)
			(xy 114.784439 -270.449248) (xy 114.742423 -270.479774) (xy 114.696149 -270.503352) (xy 114.646756 -270.5194)
			(xy 114.595461 -270.527525) (xy 114.543527 -270.527525) (xy 114.492232 -270.5194) (xy 114.442839 -270.503352)
			(xy 114.396565 -270.479774) (xy 114.354549 -270.449248) (xy 114.317826 -270.412525) (xy 114.2873 -270.370509)
			(xy 114.263722 -270.324235) (xy 114.247674 -270.274842) (xy 114.239549 -270.223547) (xy 113.959639 -270.223547)
			(xy 113.951514 -270.274842) (xy 113.935466 -270.324235) (xy 113.911888 -270.370509) (xy 113.881362 -270.412525)
			(xy 113.844639 -270.449248) (xy 113.802623 -270.479774) (xy 113.756349 -270.503352) (xy 113.706956 -270.5194)
			(xy 113.655661 -270.527525) (xy 113.603727 -270.527525) (xy 113.552432 -270.5194) (xy 113.503039 -270.503352)
			(xy 113.456765 -270.479774) (xy 113.414749 -270.449248) (xy 113.378026 -270.412525) (xy 113.3475 -270.370509)
			(xy 113.323922 -270.324235) (xy 113.307874 -270.274842) (xy 113.299749 -270.223547) (xy 113.019839 -270.223547)
			(xy 113.011714 -270.274842) (xy 112.995666 -270.324235) (xy 112.972088 -270.370509) (xy 112.941562 -270.412525)
			(xy 112.904839 -270.449248) (xy 112.862823 -270.479774) (xy 112.816549 -270.503352) (xy 112.767156 -270.5194)
			(xy 112.715861 -270.527525) (xy 112.663927 -270.527525) (xy 112.612632 -270.5194) (xy 112.563239 -270.503352)
			(xy 112.516965 -270.479774) (xy 112.474949 -270.449248) (xy 112.438226 -270.412525) (xy 112.4077 -270.370509)
			(xy 112.384122 -270.324235) (xy 112.368074 -270.274842) (xy 112.359949 -270.223547) (xy 112.080039 -270.223547)
			(xy 112.071914 -270.274842) (xy 112.055866 -270.324235) (xy 112.032288 -270.370509) (xy 112.001762 -270.412525)
			(xy 111.965039 -270.449248) (xy 111.923023 -270.479774) (xy 111.876749 -270.503352) (xy 111.827356 -270.5194)
			(xy 111.776061 -270.527525) (xy 111.724127 -270.527525) (xy 111.672832 -270.5194) (xy 111.623439 -270.503352)
			(xy 111.577165 -270.479774) (xy 111.535149 -270.449248) (xy 111.498426 -270.412525) (xy 111.4679 -270.370509)
			(xy 111.444322 -270.324235) (xy 111.428274 -270.274842) (xy 111.420149 -270.223547) (xy 111.140493 -270.223547)
			(xy 111.132368 -270.274842) (xy 111.11632 -270.324235) (xy 111.092742 -270.370509) (xy 111.062216 -270.412525)
			(xy 111.025493 -270.449248) (xy 110.983477 -270.479774) (xy 110.937203 -270.503352) (xy 110.88781 -270.5194)
			(xy 110.836515 -270.527525) (xy 110.784581 -270.527525) (xy 110.733286 -270.5194) (xy 110.683893 -270.503352)
			(xy 110.637619 -270.479774) (xy 110.595603 -270.449248) (xy 110.55888 -270.412525) (xy 110.528354 -270.370509)
			(xy 110.504776 -270.324235) (xy 110.488728 -270.274842) (xy 110.480603 -270.223547) (xy 109.260639 -270.223547)
			(xy 109.252514 -270.274842) (xy 109.236466 -270.324235) (xy 109.212888 -270.370509) (xy 109.182362 -270.412525)
			(xy 109.145639 -270.449248) (xy 109.103623 -270.479774) (xy 109.057349 -270.503352) (xy 109.007956 -270.5194)
			(xy 108.956661 -270.527525) (xy 108.904727 -270.527525) (xy 108.853432 -270.5194) (xy 108.804039 -270.503352)
			(xy 108.757765 -270.479774) (xy 108.715749 -270.449248) (xy 108.679026 -270.412525) (xy 108.6485 -270.370509)
			(xy 108.624922 -270.324235) (xy 108.608874 -270.274842) (xy 108.600749 -270.223547) (xy 108.321093 -270.223547)
			(xy 108.312968 -270.274842) (xy 108.29692 -270.324235) (xy 108.273342 -270.370509) (xy 108.242816 -270.412525)
			(xy 108.206093 -270.449248) (xy 108.164077 -270.479774) (xy 108.117803 -270.503352) (xy 108.06841 -270.5194)
			(xy 108.017115 -270.527525) (xy 107.965181 -270.527525) (xy 107.913886 -270.5194) (xy 107.864493 -270.503352)
			(xy 107.818219 -270.479774) (xy 107.776203 -270.449248) (xy 107.73948 -270.412525) (xy 107.708954 -270.370509)
			(xy 107.685376 -270.324235) (xy 107.669328 -270.274842) (xy 107.661203 -270.223547) (xy 107.381293 -270.223547)
			(xy 107.373168 -270.274842) (xy 107.35712 -270.324235) (xy 107.333542 -270.370509) (xy 107.303016 -270.412525)
			(xy 107.266293 -270.449248) (xy 107.224277 -270.479774) (xy 107.178003 -270.503352) (xy 107.12861 -270.5194)
			(xy 107.077315 -270.527525) (xy 107.025381 -270.527525) (xy 106.974086 -270.5194) (xy 106.924693 -270.503352)
			(xy 106.878419 -270.479774) (xy 106.836403 -270.449248) (xy 106.79968 -270.412525) (xy 106.769154 -270.370509)
			(xy 106.745576 -270.324235) (xy 106.729528 -270.274842) (xy 106.721403 -270.223547) (xy 106.441493 -270.223547)
			(xy 106.433368 -270.274842) (xy 106.41732 -270.324235) (xy 106.393742 -270.370509) (xy 106.363216 -270.412525)
			(xy 106.326493 -270.449248) (xy 106.284477 -270.479774) (xy 106.238203 -270.503352) (xy 106.18881 -270.5194)
			(xy 106.137515 -270.527525) (xy 106.085581 -270.527525) (xy 106.034286 -270.5194) (xy 105.984893 -270.503352)
			(xy 105.938619 -270.479774) (xy 105.896603 -270.449248) (xy 105.85988 -270.412525) (xy 105.829354 -270.370509)
			(xy 105.805776 -270.324235) (xy 105.789728 -270.274842) (xy 105.781603 -270.223547) (xy 105.501693 -270.223547)
			(xy 105.493568 -270.274842) (xy 105.47752 -270.324235) (xy 105.453942 -270.370509) (xy 105.423416 -270.412525)
			(xy 105.386693 -270.449248) (xy 105.344677 -270.479774) (xy 105.298403 -270.503352) (xy 105.24901 -270.5194)
			(xy 105.197715 -270.527525) (xy 105.145781 -270.527525) (xy 105.094486 -270.5194) (xy 105.045093 -270.503352)
			(xy 104.998819 -270.479774) (xy 104.956803 -270.449248) (xy 104.92008 -270.412525) (xy 104.889554 -270.370509)
			(xy 104.865976 -270.324235) (xy 104.849928 -270.274842) (xy 104.841803 -270.223547) (xy 104.561893 -270.223547)
			(xy 104.553768 -270.274842) (xy 104.53772 -270.324235) (xy 104.514142 -270.370509) (xy 104.483616 -270.412525)
			(xy 104.446893 -270.449248) (xy 104.404877 -270.479774) (xy 104.358603 -270.503352) (xy 104.30921 -270.5194)
			(xy 104.257915 -270.527525) (xy 104.205981 -270.527525) (xy 104.154686 -270.5194) (xy 104.105293 -270.503352)
			(xy 104.059019 -270.479774) (xy 104.017003 -270.449248) (xy 103.98028 -270.412525) (xy 103.949754 -270.370509)
			(xy 103.926176 -270.324235) (xy 103.910128 -270.274842) (xy 103.902003 -270.223547) (xy 103.622093 -270.223547)
			(xy 103.613968 -270.274842) (xy 103.59792 -270.324235) (xy 103.574342 -270.370509) (xy 103.543816 -270.412525)
			(xy 103.507093 -270.449248) (xy 103.465077 -270.479774) (xy 103.418803 -270.503352) (xy 103.36941 -270.5194)
			(xy 103.318115 -270.527525) (xy 103.266181 -270.527525) (xy 103.214886 -270.5194) (xy 103.165493 -270.503352)
			(xy 103.119219 -270.479774) (xy 103.077203 -270.449248) (xy 103.04048 -270.412525) (xy 103.009954 -270.370509)
			(xy 102.986376 -270.324235) (xy 102.970328 -270.274842) (xy 102.962203 -270.223547) (xy 102.682293 -270.223547)
			(xy 102.674168 -270.274842) (xy 102.65812 -270.324235) (xy 102.634542 -270.370509) (xy 102.604016 -270.412525)
			(xy 102.567293 -270.449248) (xy 102.525277 -270.479774) (xy 102.479003 -270.503352) (xy 102.42961 -270.5194)
			(xy 102.378315 -270.527525) (xy 102.326381 -270.527525) (xy 102.275086 -270.5194) (xy 102.225693 -270.503352)
			(xy 102.179419 -270.479774) (xy 102.137403 -270.449248) (xy 102.10068 -270.412525) (xy 102.070154 -270.370509)
			(xy 102.046576 -270.324235) (xy 102.030528 -270.274842) (xy 102.022403 -270.223547) (xy 101.742493 -270.223547)
			(xy 101.734368 -270.274842) (xy 101.71832 -270.324235) (xy 101.694742 -270.370509) (xy 101.664216 -270.412525)
			(xy 101.627493 -270.449248) (xy 101.585477 -270.479774) (xy 101.539203 -270.503352) (xy 101.48981 -270.5194)
			(xy 101.438515 -270.527525) (xy 101.386581 -270.527525) (xy 101.335286 -270.5194) (xy 101.285893 -270.503352)
			(xy 101.239619 -270.479774) (xy 101.197603 -270.449248) (xy 101.16088 -270.412525) (xy 101.130354 -270.370509)
			(xy 101.106776 -270.324235) (xy 101.090728 -270.274842) (xy 101.082603 -270.223547) (xy 100.802693 -270.223547)
			(xy 100.794568 -270.274842) (xy 100.77852 -270.324235) (xy 100.754942 -270.370509) (xy 100.724416 -270.412525)
			(xy 100.687693 -270.449248) (xy 100.645677 -270.479774) (xy 100.599403 -270.503352) (xy 100.55001 -270.5194)
			(xy 100.498715 -270.527525) (xy 100.446781 -270.527525) (xy 100.395486 -270.5194) (xy 100.346093 -270.503352)
			(xy 100.299819 -270.479774) (xy 100.257803 -270.449248) (xy 100.22108 -270.412525) (xy 100.190554 -270.370509)
			(xy 100.166976 -270.324235) (xy 100.150928 -270.274842) (xy 100.142803 -270.223547) (xy 99.862893 -270.223547)
			(xy 99.854768 -270.274842) (xy 99.83872 -270.324235) (xy 99.815142 -270.370509) (xy 99.784616 -270.412525)
			(xy 99.747893 -270.449248) (xy 99.705877 -270.479774) (xy 99.659603 -270.503352) (xy 99.61021 -270.5194)
			(xy 99.558915 -270.527525) (xy 99.506981 -270.527525) (xy 99.455686 -270.5194) (xy 99.406293 -270.503352)
			(xy 99.360019 -270.479774) (xy 99.318003 -270.449248) (xy 99.28128 -270.412525) (xy 99.250754 -270.370509)
			(xy 99.227176 -270.324235) (xy 99.211128 -270.274842) (xy 99.203003 -270.223547) (xy 98.922839 -270.223547)
			(xy 98.914714 -270.274842) (xy 98.898666 -270.324235) (xy 98.875088 -270.370509) (xy 98.844562 -270.412525)
			(xy 98.807839 -270.449248) (xy 98.765823 -270.479774) (xy 98.719549 -270.503352) (xy 98.670156 -270.5194)
			(xy 98.618861 -270.527525) (xy 98.566927 -270.527525) (xy 98.515632 -270.5194) (xy 98.466239 -270.503352)
			(xy 98.419965 -270.479774) (xy 98.377949 -270.449248) (xy 98.341226 -270.412525) (xy 98.3107 -270.370509)
			(xy 98.287122 -270.324235) (xy 98.271074 -270.274842) (xy 98.262949 -270.223547) (xy 97.983293 -270.223547)
			(xy 97.975168 -270.274842) (xy 97.95912 -270.324235) (xy 97.935542 -270.370509) (xy 97.905016 -270.412525)
			(xy 97.868293 -270.449248) (xy 97.826277 -270.479774) (xy 97.780003 -270.503352) (xy 97.73061 -270.5194)
			(xy 97.679315 -270.527525) (xy 97.627381 -270.527525) (xy 97.576086 -270.5194) (xy 97.526693 -270.503352)
			(xy 97.480419 -270.479774) (xy 97.438403 -270.449248) (xy 97.40168 -270.412525) (xy 97.371154 -270.370509)
			(xy 97.347576 -270.324235) (xy 97.331528 -270.274842) (xy 97.323403 -270.223547) (xy 97.043493 -270.223547)
			(xy 97.035368 -270.274842) (xy 97.01932 -270.324235) (xy 96.995742 -270.370509) (xy 96.965216 -270.412525)
			(xy 96.928493 -270.449248) (xy 96.886477 -270.479774) (xy 96.840203 -270.503352) (xy 96.79081 -270.5194)
			(xy 96.739515 -270.527525) (xy 96.687581 -270.527525) (xy 96.636286 -270.5194) (xy 96.586893 -270.503352)
			(xy 96.540619 -270.479774) (xy 96.498603 -270.449248) (xy 96.46188 -270.412525) (xy 96.431354 -270.370509)
			(xy 96.407776 -270.324235) (xy 96.391728 -270.274842) (xy 96.383603 -270.223547) (xy 96.103693 -270.223547)
			(xy 96.095568 -270.274842) (xy 96.07952 -270.324235) (xy 96.055942 -270.370509) (xy 96.025416 -270.412525)
			(xy 95.988693 -270.449248) (xy 95.946677 -270.479774) (xy 95.900403 -270.503352) (xy 95.85101 -270.5194)
			(xy 95.799715 -270.527525) (xy 95.747781 -270.527525) (xy 95.696486 -270.5194) (xy 95.647093 -270.503352)
			(xy 95.600819 -270.479774) (xy 95.558803 -270.449248) (xy 95.52208 -270.412525) (xy 95.491554 -270.370509)
			(xy 95.467976 -270.324235) (xy 95.451928 -270.274842) (xy 95.443803 -270.223547) (xy 95.163893 -270.223547)
			(xy 95.155768 -270.274842) (xy 95.13972 -270.324235) (xy 95.116142 -270.370509) (xy 95.085616 -270.412525)
			(xy 95.048893 -270.449248) (xy 95.006877 -270.479774) (xy 94.960603 -270.503352) (xy 94.91121 -270.5194)
			(xy 94.859915 -270.527525) (xy 94.807981 -270.527525) (xy 94.756686 -270.5194) (xy 94.707293 -270.503352)
			(xy 94.661019 -270.479774) (xy 94.619003 -270.449248) (xy 94.58228 -270.412525) (xy 94.551754 -270.370509)
			(xy 94.528176 -270.324235) (xy 94.512128 -270.274842) (xy 94.504003 -270.223547) (xy 94.224093 -270.223547)
			(xy 94.215968 -270.274842) (xy 94.19992 -270.324235) (xy 94.176342 -270.370509) (xy 94.145816 -270.412525)
			(xy 94.109093 -270.449248) (xy 94.067077 -270.479774) (xy 94.020803 -270.503352) (xy 93.97141 -270.5194)
			(xy 93.920115 -270.527525) (xy 93.868181 -270.527525) (xy 93.816886 -270.5194) (xy 93.767493 -270.503352)
			(xy 93.721219 -270.479774) (xy 93.679203 -270.449248) (xy 93.64248 -270.412525) (xy 93.611954 -270.370509)
			(xy 93.588376 -270.324235) (xy 93.572328 -270.274842) (xy 93.564203 -270.223547) (xy 93.284293 -270.223547)
			(xy 93.276168 -270.274842) (xy 93.26012 -270.324235) (xy 93.236542 -270.370509) (xy 93.206016 -270.412525)
			(xy 93.169293 -270.449248) (xy 93.127277 -270.479774) (xy 93.081003 -270.503352) (xy 93.03161 -270.5194)
			(xy 92.980315 -270.527525) (xy 92.928381 -270.527525) (xy 92.877086 -270.5194) (xy 92.827693 -270.503352)
			(xy 92.781419 -270.479774) (xy 92.739403 -270.449248) (xy 92.70268 -270.412525) (xy 92.672154 -270.370509)
			(xy 92.648576 -270.324235) (xy 92.632528 -270.274842) (xy 92.624403 -270.223547) (xy 92.344545 -270.223547)
			(xy 92.344545 -270.223591) (xy 92.336413 -270.274933) (xy 92.320349 -270.324371) (xy 92.29675 -270.370688)
			(xy 92.266195 -270.412742) (xy 92.229438 -270.449499) (xy 92.187383 -270.480053) (xy 92.141066 -270.503652)
			(xy 92.091628 -270.519714) (xy 92.040285 -270.527845) (xy 92.014294 -270.528288) (xy 92.01404 -270.528288)
			(xy 91.984621 -270.527623) (xy 91.926714 -270.51719) (xy 91.871553 -270.496716) (xy 91.845892 -270.482314)
			(xy 91.840304 -270.479012) (xy 91.81465 -270.471646) (xy 91.808208 -270.471813) (xy 91.795734 -270.475031)
			(xy 91.790012 -270.477996) (xy 91.713304 -270.520668) (xy 91.705716 -270.525306) (xy 91.694156 -270.538804)
			(xy 91.687986 -270.55547) (xy 91.68765 -270.564356) (xy 91.68765 -270.683482) (xy 91.712034 -270.7259)
			(xy 91.718638 -270.730218) (xy 91.740363 -270.744268) (xy 91.77956 -270.778032) (xy 91.813023 -270.817486)
			(xy 91.839936 -270.861669) (xy 91.859643 -270.909503) (xy 91.871662 -270.959822) (xy 91.875702 -271.011398)
			(xy 91.873669 -271.037363) (xy 92.154249 -271.037363) (xy 92.154249 -270.985429) (xy 92.162374 -270.934134)
			(xy 92.178422 -270.884741) (xy 92.202 -270.838467) (xy 92.232526 -270.796451) (xy 92.269249 -270.759728)
			(xy 92.311265 -270.729202) (xy 92.357539 -270.705624) (xy 92.406932 -270.689576) (xy 92.458227 -270.681451)
			(xy 92.510161 -270.681451) (xy 92.561456 -270.689576) (xy 92.610849 -270.705624) (xy 92.657123 -270.729202)
			(xy 92.699139 -270.759728) (xy 92.735862 -270.796451) (xy 92.766388 -270.838467) (xy 92.789966 -270.884741)
			(xy 92.806014 -270.934134) (xy 92.814139 -270.985429) (xy 92.814648 -271.011396) (xy 92.814139 -271.037363)
			(xy 93.094049 -271.037363) (xy 93.094049 -270.985429) (xy 93.102174 -270.934134) (xy 93.118222 -270.884741)
			(xy 93.1418 -270.838467) (xy 93.172326 -270.796451) (xy 93.209049 -270.759728) (xy 93.251065 -270.729202)
			(xy 93.297339 -270.705624) (xy 93.346732 -270.689576) (xy 93.398027 -270.681451) (xy 93.449961 -270.681451)
			(xy 93.501256 -270.689576) (xy 93.550649 -270.705624) (xy 93.596923 -270.729202) (xy 93.638939 -270.759728)
			(xy 93.675662 -270.796451) (xy 93.706188 -270.838467) (xy 93.729766 -270.884741) (xy 93.745814 -270.934134)
			(xy 93.753939 -270.985429) (xy 93.754448 -271.011396) (xy 93.753939 -271.037363) (xy 94.034103 -271.037363)
			(xy 94.034103 -270.985429) (xy 94.042228 -270.934134) (xy 94.058276 -270.884741) (xy 94.081854 -270.838467)
			(xy 94.11238 -270.796451) (xy 94.149103 -270.759728) (xy 94.191119 -270.729202) (xy 94.237393 -270.705624)
			(xy 94.286786 -270.689576) (xy 94.338081 -270.681451) (xy 94.390015 -270.681451) (xy 94.44131 -270.689576)
			(xy 94.490703 -270.705624) (xy 94.536977 -270.729202) (xy 94.578993 -270.759728) (xy 94.615716 -270.796451)
			(xy 94.646242 -270.838467) (xy 94.66982 -270.884741) (xy 94.685868 -270.934134) (xy 94.693993 -270.985429)
			(xy 94.694502 -271.011396) (xy 94.693993 -271.037363) (xy 94.973649 -271.037363) (xy 94.973649 -270.985429)
			(xy 94.981774 -270.934134) (xy 94.997822 -270.884741) (xy 95.0214 -270.838467) (xy 95.051926 -270.796451)
			(xy 95.088649 -270.759728) (xy 95.130665 -270.729202) (xy 95.176939 -270.705624) (xy 95.226332 -270.689576)
			(xy 95.277627 -270.681451) (xy 95.329561 -270.681451) (xy 95.380856 -270.689576) (xy 95.430249 -270.705624)
			(xy 95.476523 -270.729202) (xy 95.518539 -270.759728) (xy 95.555262 -270.796451) (xy 95.585788 -270.838467)
			(xy 95.609366 -270.884741) (xy 95.625414 -270.934134) (xy 95.633539 -270.985429) (xy 95.634048 -271.011396)
			(xy 95.633539 -271.037363) (xy 95.913449 -271.037363) (xy 95.913449 -270.985429) (xy 95.921574 -270.934134)
			(xy 95.937622 -270.884741) (xy 95.9612 -270.838467) (xy 95.991726 -270.796451) (xy 96.028449 -270.759728)
			(xy 96.070465 -270.729202) (xy 96.116739 -270.705624) (xy 96.166132 -270.689576) (xy 96.217427 -270.681451)
			(xy 96.269361 -270.681451) (xy 96.320656 -270.689576) (xy 96.370049 -270.705624) (xy 96.416323 -270.729202)
			(xy 96.458339 -270.759728) (xy 96.495062 -270.796451) (xy 96.525588 -270.838467) (xy 96.549166 -270.884741)
			(xy 96.565214 -270.934134) (xy 96.573339 -270.985429) (xy 96.573848 -271.011396) (xy 96.573339 -271.037363)
			(xy 96.853249 -271.037363) (xy 96.853249 -270.985429) (xy 96.861374 -270.934134) (xy 96.877422 -270.884741)
			(xy 96.901 -270.838467) (xy 96.931526 -270.796451) (xy 96.968249 -270.759728) (xy 97.010265 -270.729202)
			(xy 97.056539 -270.705624) (xy 97.105932 -270.689576) (xy 97.157227 -270.681451) (xy 97.209161 -270.681451)
			(xy 97.260456 -270.689576) (xy 97.309849 -270.705624) (xy 97.356123 -270.729202) (xy 97.398139 -270.759728)
			(xy 97.434862 -270.796451) (xy 97.465388 -270.838467) (xy 97.488966 -270.884741) (xy 97.505014 -270.934134)
			(xy 97.513139 -270.985429) (xy 97.513648 -271.011396) (xy 97.513139 -271.037363) (xy 97.793049 -271.037363)
			(xy 97.793049 -270.985429) (xy 97.801174 -270.934134) (xy 97.817222 -270.884741) (xy 97.8408 -270.838467)
			(xy 97.871326 -270.796451) (xy 97.908049 -270.759728) (xy 97.950065 -270.729202) (xy 97.996339 -270.705624)
			(xy 98.045732 -270.689576) (xy 98.097027 -270.681451) (xy 98.148961 -270.681451) (xy 98.200256 -270.689576)
			(xy 98.249649 -270.705624) (xy 98.295923 -270.729202) (xy 98.337939 -270.759728) (xy 98.374662 -270.796451)
			(xy 98.405188 -270.838467) (xy 98.428766 -270.884741) (xy 98.444814 -270.934134) (xy 98.452939 -270.985429)
			(xy 98.453448 -271.011396) (xy 98.452939 -271.037363) (xy 98.732849 -271.037363) (xy 98.732849 -270.985429)
			(xy 98.740974 -270.934134) (xy 98.757022 -270.884741) (xy 98.7806 -270.838467) (xy 98.811126 -270.796451)
			(xy 98.847849 -270.759728) (xy 98.889865 -270.729202) (xy 98.936139 -270.705624) (xy 98.985532 -270.689576)
			(xy 99.036827 -270.681451) (xy 99.088761 -270.681451) (xy 99.140056 -270.689576) (xy 99.189449 -270.705624)
			(xy 99.235723 -270.729202) (xy 99.277739 -270.759728) (xy 99.314462 -270.796451) (xy 99.344988 -270.838467)
			(xy 99.368566 -270.884741) (xy 99.384614 -270.934134) (xy 99.392739 -270.985429) (xy 99.393248 -271.011396)
			(xy 99.392739 -271.037363) (xy 99.672649 -271.037363) (xy 99.672649 -270.985429) (xy 99.680774 -270.934134)
			(xy 99.696822 -270.884741) (xy 99.7204 -270.838467) (xy 99.750926 -270.796451) (xy 99.787649 -270.759728)
			(xy 99.829665 -270.729202) (xy 99.875939 -270.705624) (xy 99.925332 -270.689576) (xy 99.976627 -270.681451)
			(xy 100.028561 -270.681451) (xy 100.079856 -270.689576) (xy 100.129249 -270.705624) (xy 100.175523 -270.729202)
			(xy 100.217539 -270.759728) (xy 100.254262 -270.796451) (xy 100.284788 -270.838467) (xy 100.308366 -270.884741)
			(xy 100.324414 -270.934134) (xy 100.332539 -270.985429) (xy 100.333048 -271.011396) (xy 100.332539 -271.037363)
			(xy 100.612703 -271.037363) (xy 100.612703 -270.985429) (xy 100.620828 -270.934134) (xy 100.636876 -270.884741)
			(xy 100.660454 -270.838467) (xy 100.69098 -270.796451) (xy 100.727703 -270.759728) (xy 100.769719 -270.729202)
			(xy 100.815993 -270.705624) (xy 100.865386 -270.689576) (xy 100.916681 -270.681451) (xy 100.968615 -270.681451)
			(xy 101.01991 -270.689576) (xy 101.069303 -270.705624) (xy 101.115577 -270.729202) (xy 101.157593 -270.759728)
			(xy 101.194316 -270.796451) (xy 101.224842 -270.838467) (xy 101.24842 -270.884741) (xy 101.264468 -270.934134)
			(xy 101.272593 -270.985429) (xy 101.273102 -271.011396) (xy 101.272593 -271.037363) (xy 101.552503 -271.037363)
			(xy 101.552503 -270.985429) (xy 101.560628 -270.934134) (xy 101.576676 -270.884741) (xy 101.600254 -270.838467)
			(xy 101.63078 -270.796451) (xy 101.667503 -270.759728) (xy 101.709519 -270.729202) (xy 101.755793 -270.705624)
			(xy 101.805186 -270.689576) (xy 101.856481 -270.681451) (xy 101.908415 -270.681451) (xy 101.95971 -270.689576)
			(xy 102.009103 -270.705624) (xy 102.055377 -270.729202) (xy 102.097393 -270.759728) (xy 102.134116 -270.796451)
			(xy 102.164642 -270.838467) (xy 102.18822 -270.884741) (xy 102.204268 -270.934134) (xy 102.212393 -270.985429)
			(xy 102.212902 -271.011396) (xy 102.212393 -271.037363) (xy 102.492049 -271.037363) (xy 102.492049 -270.985429)
			(xy 102.500174 -270.934134) (xy 102.516222 -270.884741) (xy 102.5398 -270.838467) (xy 102.570326 -270.796451)
			(xy 102.607049 -270.759728) (xy 102.649065 -270.729202) (xy 102.695339 -270.705624) (xy 102.744732 -270.689576)
			(xy 102.796027 -270.681451) (xy 102.847961 -270.681451) (xy 102.899256 -270.689576) (xy 102.948649 -270.705624)
			(xy 102.994923 -270.729202) (xy 103.036939 -270.759728) (xy 103.073662 -270.796451) (xy 103.104188 -270.838467)
			(xy 103.127766 -270.884741) (xy 103.143814 -270.934134) (xy 103.151939 -270.985429) (xy 103.152448 -271.011396)
			(xy 103.151939 -271.037363) (xy 103.431849 -271.037363) (xy 103.431849 -270.985429) (xy 103.439974 -270.934134)
			(xy 103.456022 -270.884741) (xy 103.4796 -270.838467) (xy 103.510126 -270.796451) (xy 103.546849 -270.759728)
			(xy 103.588865 -270.729202) (xy 103.635139 -270.705624) (xy 103.684532 -270.689576) (xy 103.735827 -270.681451)
			(xy 103.787761 -270.681451) (xy 103.839056 -270.689576) (xy 103.888449 -270.705624) (xy 103.934723 -270.729202)
			(xy 103.976739 -270.759728) (xy 104.013462 -270.796451) (xy 104.043988 -270.838467) (xy 104.067566 -270.884741)
			(xy 104.083614 -270.934134) (xy 104.091739 -270.985429) (xy 104.092248 -271.011396) (xy 104.091739 -271.037363)
			(xy 104.371649 -271.037363) (xy 104.371649 -270.985429) (xy 104.379774 -270.934134) (xy 104.395822 -270.884741)
			(xy 104.4194 -270.838467) (xy 104.449926 -270.796451) (xy 104.486649 -270.759728) (xy 104.528665 -270.729202)
			(xy 104.574939 -270.705624) (xy 104.624332 -270.689576) (xy 104.675627 -270.681451) (xy 104.727561 -270.681451)
			(xy 104.778856 -270.689576) (xy 104.828249 -270.705624) (xy 104.874523 -270.729202) (xy 104.916539 -270.759728)
			(xy 104.953262 -270.796451) (xy 104.983788 -270.838467) (xy 105.007366 -270.884741) (xy 105.023414 -270.934134)
			(xy 105.031539 -270.985429) (xy 105.032048 -271.011396) (xy 105.031539 -271.037363) (xy 105.311449 -271.037363)
			(xy 105.311449 -270.985429) (xy 105.319574 -270.934134) (xy 105.335622 -270.884741) (xy 105.3592 -270.838467)
			(xy 105.389726 -270.796451) (xy 105.426449 -270.759728) (xy 105.468465 -270.729202) (xy 105.514739 -270.705624)
			(xy 105.564132 -270.689576) (xy 105.615427 -270.681451) (xy 105.667361 -270.681451) (xy 105.718656 -270.689576)
			(xy 105.768049 -270.705624) (xy 105.814323 -270.729202) (xy 105.856339 -270.759728) (xy 105.893062 -270.796451)
			(xy 105.923588 -270.838467) (xy 105.947166 -270.884741) (xy 105.963214 -270.934134) (xy 105.971339 -270.985429)
			(xy 105.971848 -271.011396) (xy 105.971339 -271.037363) (xy 106.251249 -271.037363) (xy 106.251249 -270.985429)
			(xy 106.259374 -270.934134) (xy 106.275422 -270.884741) (xy 106.299 -270.838467) (xy 106.329526 -270.796451)
			(xy 106.366249 -270.759728) (xy 106.408265 -270.729202) (xy 106.454539 -270.705624) (xy 106.503932 -270.689576)
			(xy 106.555227 -270.681451) (xy 106.607161 -270.681451) (xy 106.658456 -270.689576) (xy 106.707849 -270.705624)
			(xy 106.754123 -270.729202) (xy 106.796139 -270.759728) (xy 106.832862 -270.796451) (xy 106.863388 -270.838467)
			(xy 106.886966 -270.884741) (xy 106.903014 -270.934134) (xy 106.911139 -270.985429) (xy 106.911648 -271.011396)
			(xy 106.911139 -271.037363) (xy 107.191049 -271.037363) (xy 107.191049 -270.985429) (xy 107.199174 -270.934134)
			(xy 107.215222 -270.884741) (xy 107.2388 -270.838467) (xy 107.269326 -270.796451) (xy 107.306049 -270.759728)
			(xy 107.348065 -270.729202) (xy 107.394339 -270.705624) (xy 107.443732 -270.689576) (xy 107.495027 -270.681451)
			(xy 107.546961 -270.681451) (xy 107.598256 -270.689576) (xy 107.647649 -270.705624) (xy 107.693923 -270.729202)
			(xy 107.735939 -270.759728) (xy 107.772662 -270.796451) (xy 107.803188 -270.838467) (xy 107.826766 -270.884741)
			(xy 107.842814 -270.934134) (xy 107.850939 -270.985429) (xy 107.851448 -271.011396) (xy 107.850939 -271.037363)
			(xy 108.130849 -271.037363) (xy 108.130849 -270.985429) (xy 108.138974 -270.934134) (xy 108.155022 -270.884741)
			(xy 108.1786 -270.838467) (xy 108.209126 -270.796451) (xy 108.245849 -270.759728) (xy 108.287865 -270.729202)
			(xy 108.334139 -270.705624) (xy 108.383532 -270.689576) (xy 108.434827 -270.681451) (xy 108.486761 -270.681451)
			(xy 108.538056 -270.689576) (xy 108.587449 -270.705624) (xy 108.633723 -270.729202) (xy 108.675739 -270.759728)
			(xy 108.712462 -270.796451) (xy 108.742988 -270.838467) (xy 108.766566 -270.884741) (xy 108.782614 -270.934134)
			(xy 108.790739 -270.985429) (xy 108.791248 -271.011396) (xy 108.790739 -271.037363) (xy 109.070649 -271.037363)
			(xy 109.070649 -270.985429) (xy 109.078774 -270.934134) (xy 109.094822 -270.884741) (xy 109.1184 -270.838467)
			(xy 109.148926 -270.796451) (xy 109.185649 -270.759728) (xy 109.227665 -270.729202) (xy 109.273939 -270.705624)
			(xy 109.323332 -270.689576) (xy 109.374627 -270.681451) (xy 109.426561 -270.681451) (xy 109.477856 -270.689576)
			(xy 109.527249 -270.705624) (xy 109.573523 -270.729202) (xy 109.615539 -270.759728) (xy 109.652262 -270.796451)
			(xy 109.682788 -270.838467) (xy 109.706366 -270.884741) (xy 109.722414 -270.934134) (xy 109.730539 -270.985429)
			(xy 109.731048 -271.011396) (xy 109.730539 -271.037363) (xy 110.010449 -271.037363) (xy 110.010449 -270.985429)
			(xy 110.018574 -270.934134) (xy 110.034622 -270.884741) (xy 110.0582 -270.838467) (xy 110.088726 -270.796451)
			(xy 110.125449 -270.759728) (xy 110.167465 -270.729202) (xy 110.213739 -270.705624) (xy 110.263132 -270.689576)
			(xy 110.314427 -270.681451) (xy 110.366361 -270.681451) (xy 110.417656 -270.689576) (xy 110.467049 -270.705624)
			(xy 110.513323 -270.729202) (xy 110.555339 -270.759728) (xy 110.592062 -270.796451) (xy 110.622588 -270.838467)
			(xy 110.646166 -270.884741) (xy 110.662214 -270.934134) (xy 110.670339 -270.985429) (xy 110.670848 -271.011396)
			(xy 110.670339 -271.037363) (xy 110.950503 -271.037363) (xy 110.950503 -270.985429) (xy 110.958628 -270.934134)
			(xy 110.974676 -270.884741) (xy 110.998254 -270.838467) (xy 111.02878 -270.796451) (xy 111.065503 -270.759728)
			(xy 111.107519 -270.729202) (xy 111.153793 -270.705624) (xy 111.203186 -270.689576) (xy 111.254481 -270.681451)
			(xy 111.306415 -270.681451) (xy 111.35771 -270.689576) (xy 111.407103 -270.705624) (xy 111.453377 -270.729202)
			(xy 111.495393 -270.759728) (xy 111.532116 -270.796451) (xy 111.562642 -270.838467) (xy 111.58622 -270.884741)
			(xy 111.602268 -270.934134) (xy 111.610393 -270.985429) (xy 111.610902 -271.011396) (xy 111.610393 -271.037363)
			(xy 111.890303 -271.037363) (xy 111.890303 -270.985429) (xy 111.898428 -270.934134) (xy 111.914476 -270.884741)
			(xy 111.938054 -270.838467) (xy 111.96858 -270.796451) (xy 112.005303 -270.759728) (xy 112.047319 -270.729202)
			(xy 112.093593 -270.705624) (xy 112.142986 -270.689576) (xy 112.194281 -270.681451) (xy 112.246215 -270.681451)
			(xy 112.29751 -270.689576) (xy 112.346903 -270.705624) (xy 112.393177 -270.729202) (xy 112.435193 -270.759728)
			(xy 112.471916 -270.796451) (xy 112.502442 -270.838467) (xy 112.52602 -270.884741) (xy 112.542068 -270.934134)
			(xy 112.550193 -270.985429) (xy 112.550702 -271.011396) (xy 112.550193 -271.037363) (xy 112.829849 -271.037363)
			(xy 112.829849 -270.985429) (xy 112.837974 -270.934134) (xy 112.854022 -270.884741) (xy 112.8776 -270.838467)
			(xy 112.908126 -270.796451) (xy 112.944849 -270.759728) (xy 112.986865 -270.729202) (xy 113.033139 -270.705624)
			(xy 113.082532 -270.689576) (xy 113.133827 -270.681451) (xy 113.185761 -270.681451) (xy 113.237056 -270.689576)
			(xy 113.286449 -270.705624) (xy 113.332723 -270.729202) (xy 113.374739 -270.759728) (xy 113.411462 -270.796451)
			(xy 113.441988 -270.838467) (xy 113.465566 -270.884741) (xy 113.481614 -270.934134) (xy 113.489739 -270.985429)
			(xy 113.490248 -271.011396) (xy 113.489739 -271.037363) (xy 113.769649 -271.037363) (xy 113.769649 -270.985429)
			(xy 113.777774 -270.934134) (xy 113.793822 -270.884741) (xy 113.8174 -270.838467) (xy 113.847926 -270.796451)
			(xy 113.884649 -270.759728) (xy 113.926665 -270.729202) (xy 113.972939 -270.705624) (xy 114.022332 -270.689576)
			(xy 114.073627 -270.681451) (xy 114.125561 -270.681451) (xy 114.176856 -270.689576) (xy 114.226249 -270.705624)
			(xy 114.272523 -270.729202) (xy 114.314539 -270.759728) (xy 114.351262 -270.796451) (xy 114.381788 -270.838467)
			(xy 114.405366 -270.884741) (xy 114.421414 -270.934134) (xy 114.429539 -270.985429) (xy 114.430048 -271.011396)
			(xy 114.429539 -271.037363) (xy 114.709449 -271.037363) (xy 114.709449 -270.985429) (xy 114.717574 -270.934134)
			(xy 114.733622 -270.884741) (xy 114.7572 -270.838467) (xy 114.787726 -270.796451) (xy 114.824449 -270.759728)
			(xy 114.866465 -270.729202) (xy 114.912739 -270.705624) (xy 114.962132 -270.689576) (xy 115.013427 -270.681451)
			(xy 115.065361 -270.681451) (xy 115.116656 -270.689576) (xy 115.166049 -270.705624) (xy 115.212323 -270.729202)
			(xy 115.254339 -270.759728) (xy 115.291062 -270.796451) (xy 115.321588 -270.838467) (xy 115.345166 -270.884741)
			(xy 115.361214 -270.934134) (xy 115.369339 -270.985429) (xy 115.369848 -271.011396) (xy 115.369339 -271.037363)
			(xy 115.649249 -271.037363) (xy 115.649249 -270.985429) (xy 115.657374 -270.934134) (xy 115.673422 -270.884741)
			(xy 115.697 -270.838467) (xy 115.727526 -270.796451) (xy 115.764249 -270.759728) (xy 115.806265 -270.729202)
			(xy 115.852539 -270.705624) (xy 115.901932 -270.689576) (xy 115.953227 -270.681451) (xy 116.005161 -270.681451)
			(xy 116.056456 -270.689576) (xy 116.105849 -270.705624) (xy 116.152123 -270.729202) (xy 116.194139 -270.759728)
			(xy 116.230862 -270.796451) (xy 116.261388 -270.838467) (xy 116.284966 -270.884741) (xy 116.301014 -270.934134)
			(xy 116.309139 -270.985429) (xy 116.309648 -271.011396) (xy 116.309139 -271.037363) (xy 116.301014 -271.088658)
			(xy 116.284966 -271.138051) (xy 116.261388 -271.184325) (xy 116.230862 -271.226341) (xy 116.194139 -271.263064)
			(xy 116.152123 -271.29359) (xy 116.105849 -271.317168) (xy 116.056456 -271.333216) (xy 116.005161 -271.341341)
			(xy 115.953227 -271.341341) (xy 115.901932 -271.333216) (xy 115.852539 -271.317168) (xy 115.806265 -271.29359)
			(xy 115.764249 -271.263064) (xy 115.727526 -271.226341) (xy 115.697 -271.184325) (xy 115.673422 -271.138051)
			(xy 115.657374 -271.088658) (xy 115.649249 -271.037363) (xy 115.369339 -271.037363) (xy 115.361214 -271.088658)
			(xy 115.345166 -271.138051) (xy 115.321588 -271.184325) (xy 115.291062 -271.226341) (xy 115.254339 -271.263064)
			(xy 115.212323 -271.29359) (xy 115.166049 -271.317168) (xy 115.116656 -271.333216) (xy 115.065361 -271.341341)
			(xy 115.013427 -271.341341) (xy 114.962132 -271.333216) (xy 114.912739 -271.317168) (xy 114.866465 -271.29359)
			(xy 114.824449 -271.263064) (xy 114.787726 -271.226341) (xy 114.7572 -271.184325) (xy 114.733622 -271.138051)
			(xy 114.717574 -271.088658) (xy 114.709449 -271.037363) (xy 114.429539 -271.037363) (xy 114.421414 -271.088658)
			(xy 114.405366 -271.138051) (xy 114.381788 -271.184325) (xy 114.351262 -271.226341) (xy 114.314539 -271.263064)
			(xy 114.272523 -271.29359) (xy 114.226249 -271.317168) (xy 114.176856 -271.333216) (xy 114.125561 -271.341341)
			(xy 114.073627 -271.341341) (xy 114.022332 -271.333216) (xy 113.972939 -271.317168) (xy 113.926665 -271.29359)
			(xy 113.884649 -271.263064) (xy 113.847926 -271.226341) (xy 113.8174 -271.184325) (xy 113.793822 -271.138051)
			(xy 113.777774 -271.088658) (xy 113.769649 -271.037363) (xy 113.489739 -271.037363) (xy 113.481614 -271.088658)
			(xy 113.465566 -271.138051) (xy 113.441988 -271.184325) (xy 113.411462 -271.226341) (xy 113.374739 -271.263064)
			(xy 113.332723 -271.29359) (xy 113.286449 -271.317168) (xy 113.237056 -271.333216) (xy 113.185761 -271.341341)
			(xy 113.133827 -271.341341) (xy 113.082532 -271.333216) (xy 113.033139 -271.317168) (xy 112.986865 -271.29359)
			(xy 112.944849 -271.263064) (xy 112.908126 -271.226341) (xy 112.8776 -271.184325) (xy 112.854022 -271.138051)
			(xy 112.837974 -271.088658) (xy 112.829849 -271.037363) (xy 112.550193 -271.037363) (xy 112.542068 -271.088658)
			(xy 112.52602 -271.138051) (xy 112.502442 -271.184325) (xy 112.471916 -271.226341) (xy 112.435193 -271.263064)
			(xy 112.393177 -271.29359) (xy 112.346903 -271.317168) (xy 112.29751 -271.333216) (xy 112.246215 -271.341341)
			(xy 112.194281 -271.341341) (xy 112.142986 -271.333216) (xy 112.093593 -271.317168) (xy 112.047319 -271.29359)
			(xy 112.005303 -271.263064) (xy 111.96858 -271.226341) (xy 111.938054 -271.184325) (xy 111.914476 -271.138051)
			(xy 111.898428 -271.088658) (xy 111.890303 -271.037363) (xy 111.610393 -271.037363) (xy 111.602268 -271.088658)
			(xy 111.58622 -271.138051) (xy 111.562642 -271.184325) (xy 111.532116 -271.226341) (xy 111.495393 -271.263064)
			(xy 111.453377 -271.29359) (xy 111.407103 -271.317168) (xy 111.35771 -271.333216) (xy 111.306415 -271.341341)
			(xy 111.254481 -271.341341) (xy 111.203186 -271.333216) (xy 111.153793 -271.317168) (xy 111.107519 -271.29359)
			(xy 111.065503 -271.263064) (xy 111.02878 -271.226341) (xy 110.998254 -271.184325) (xy 110.974676 -271.138051)
			(xy 110.958628 -271.088658) (xy 110.950503 -271.037363) (xy 110.670339 -271.037363) (xy 110.662214 -271.088658)
			(xy 110.646166 -271.138051) (xy 110.622588 -271.184325) (xy 110.592062 -271.226341) (xy 110.555339 -271.263064)
			(xy 110.513323 -271.29359) (xy 110.467049 -271.317168) (xy 110.417656 -271.333216) (xy 110.366361 -271.341341)
			(xy 110.314427 -271.341341) (xy 110.263132 -271.333216) (xy 110.213739 -271.317168) (xy 110.167465 -271.29359)
			(xy 110.125449 -271.263064) (xy 110.088726 -271.226341) (xy 110.0582 -271.184325) (xy 110.034622 -271.138051)
			(xy 110.018574 -271.088658) (xy 110.010449 -271.037363) (xy 109.730539 -271.037363) (xy 109.722414 -271.088658)
			(xy 109.706366 -271.138051) (xy 109.682788 -271.184325) (xy 109.652262 -271.226341) (xy 109.615539 -271.263064)
			(xy 109.573523 -271.29359) (xy 109.527249 -271.317168) (xy 109.477856 -271.333216) (xy 109.426561 -271.341341)
			(xy 109.374627 -271.341341) (xy 109.323332 -271.333216) (xy 109.273939 -271.317168) (xy 109.227665 -271.29359)
			(xy 109.185649 -271.263064) (xy 109.148926 -271.226341) (xy 109.1184 -271.184325) (xy 109.094822 -271.138051)
			(xy 109.078774 -271.088658) (xy 109.070649 -271.037363) (xy 108.790739 -271.037363) (xy 108.782614 -271.088658)
			(xy 108.766566 -271.138051) (xy 108.742988 -271.184325) (xy 108.712462 -271.226341) (xy 108.675739 -271.263064)
			(xy 108.633723 -271.29359) (xy 108.587449 -271.317168) (xy 108.538056 -271.333216) (xy 108.486761 -271.341341)
			(xy 108.434827 -271.341341) (xy 108.383532 -271.333216) (xy 108.334139 -271.317168) (xy 108.287865 -271.29359)
			(xy 108.245849 -271.263064) (xy 108.209126 -271.226341) (xy 108.1786 -271.184325) (xy 108.155022 -271.138051)
			(xy 108.138974 -271.088658) (xy 108.130849 -271.037363) (xy 107.850939 -271.037363) (xy 107.842814 -271.088658)
			(xy 107.826766 -271.138051) (xy 107.803188 -271.184325) (xy 107.772662 -271.226341) (xy 107.735939 -271.263064)
			(xy 107.693923 -271.29359) (xy 107.647649 -271.317168) (xy 107.598256 -271.333216) (xy 107.546961 -271.341341)
			(xy 107.495027 -271.341341) (xy 107.443732 -271.333216) (xy 107.394339 -271.317168) (xy 107.348065 -271.29359)
			(xy 107.306049 -271.263064) (xy 107.269326 -271.226341) (xy 107.2388 -271.184325) (xy 107.215222 -271.138051)
			(xy 107.199174 -271.088658) (xy 107.191049 -271.037363) (xy 106.911139 -271.037363) (xy 106.903014 -271.088658)
			(xy 106.886966 -271.138051) (xy 106.863388 -271.184325) (xy 106.832862 -271.226341) (xy 106.796139 -271.263064)
			(xy 106.754123 -271.29359) (xy 106.707849 -271.317168) (xy 106.658456 -271.333216) (xy 106.607161 -271.341341)
			(xy 106.555227 -271.341341) (xy 106.503932 -271.333216) (xy 106.454539 -271.317168) (xy 106.408265 -271.29359)
			(xy 106.366249 -271.263064) (xy 106.329526 -271.226341) (xy 106.299 -271.184325) (xy 106.275422 -271.138051)
			(xy 106.259374 -271.088658) (xy 106.251249 -271.037363) (xy 105.971339 -271.037363) (xy 105.963214 -271.088658)
			(xy 105.947166 -271.138051) (xy 105.923588 -271.184325) (xy 105.893062 -271.226341) (xy 105.856339 -271.263064)
			(xy 105.814323 -271.29359) (xy 105.768049 -271.317168) (xy 105.718656 -271.333216) (xy 105.667361 -271.341341)
			(xy 105.615427 -271.341341) (xy 105.564132 -271.333216) (xy 105.514739 -271.317168) (xy 105.468465 -271.29359)
			(xy 105.426449 -271.263064) (xy 105.389726 -271.226341) (xy 105.3592 -271.184325) (xy 105.335622 -271.138051)
			(xy 105.319574 -271.088658) (xy 105.311449 -271.037363) (xy 105.031539 -271.037363) (xy 105.023414 -271.088658)
			(xy 105.007366 -271.138051) (xy 104.983788 -271.184325) (xy 104.953262 -271.226341) (xy 104.916539 -271.263064)
			(xy 104.874523 -271.29359) (xy 104.828249 -271.317168) (xy 104.778856 -271.333216) (xy 104.727561 -271.341341)
			(xy 104.675627 -271.341341) (xy 104.624332 -271.333216) (xy 104.574939 -271.317168) (xy 104.528665 -271.29359)
			(xy 104.486649 -271.263064) (xy 104.449926 -271.226341) (xy 104.4194 -271.184325) (xy 104.395822 -271.138051)
			(xy 104.379774 -271.088658) (xy 104.371649 -271.037363) (xy 104.091739 -271.037363) (xy 104.083614 -271.088658)
			(xy 104.067566 -271.138051) (xy 104.043988 -271.184325) (xy 104.013462 -271.226341) (xy 103.976739 -271.263064)
			(xy 103.934723 -271.29359) (xy 103.888449 -271.317168) (xy 103.839056 -271.333216) (xy 103.787761 -271.341341)
			(xy 103.735827 -271.341341) (xy 103.684532 -271.333216) (xy 103.635139 -271.317168) (xy 103.588865 -271.29359)
			(xy 103.546849 -271.263064) (xy 103.510126 -271.226341) (xy 103.4796 -271.184325) (xy 103.456022 -271.138051)
			(xy 103.439974 -271.088658) (xy 103.431849 -271.037363) (xy 103.151939 -271.037363) (xy 103.143814 -271.088658)
			(xy 103.127766 -271.138051) (xy 103.104188 -271.184325) (xy 103.073662 -271.226341) (xy 103.036939 -271.263064)
			(xy 102.994923 -271.29359) (xy 102.948649 -271.317168) (xy 102.899256 -271.333216) (xy 102.847961 -271.341341)
			(xy 102.796027 -271.341341) (xy 102.744732 -271.333216) (xy 102.695339 -271.317168) (xy 102.649065 -271.29359)
			(xy 102.607049 -271.263064) (xy 102.570326 -271.226341) (xy 102.5398 -271.184325) (xy 102.516222 -271.138051)
			(xy 102.500174 -271.088658) (xy 102.492049 -271.037363) (xy 102.212393 -271.037363) (xy 102.204268 -271.088658)
			(xy 102.18822 -271.138051) (xy 102.164642 -271.184325) (xy 102.134116 -271.226341) (xy 102.097393 -271.263064)
			(xy 102.055377 -271.29359) (xy 102.009103 -271.317168) (xy 101.95971 -271.333216) (xy 101.908415 -271.341341)
			(xy 101.856481 -271.341341) (xy 101.805186 -271.333216) (xy 101.755793 -271.317168) (xy 101.709519 -271.29359)
			(xy 101.667503 -271.263064) (xy 101.63078 -271.226341) (xy 101.600254 -271.184325) (xy 101.576676 -271.138051)
			(xy 101.560628 -271.088658) (xy 101.552503 -271.037363) (xy 101.272593 -271.037363) (xy 101.264468 -271.088658)
			(xy 101.24842 -271.138051) (xy 101.224842 -271.184325) (xy 101.194316 -271.226341) (xy 101.157593 -271.263064)
			(xy 101.115577 -271.29359) (xy 101.069303 -271.317168) (xy 101.01991 -271.333216) (xy 100.968615 -271.341341)
			(xy 100.916681 -271.341341) (xy 100.865386 -271.333216) (xy 100.815993 -271.317168) (xy 100.769719 -271.29359)
			(xy 100.727703 -271.263064) (xy 100.69098 -271.226341) (xy 100.660454 -271.184325) (xy 100.636876 -271.138051)
			(xy 100.620828 -271.088658) (xy 100.612703 -271.037363) (xy 100.332539 -271.037363) (xy 100.324414 -271.088658)
			(xy 100.308366 -271.138051) (xy 100.284788 -271.184325) (xy 100.254262 -271.226341) (xy 100.217539 -271.263064)
			(xy 100.175523 -271.29359) (xy 100.129249 -271.317168) (xy 100.079856 -271.333216) (xy 100.028561 -271.341341)
			(xy 99.976627 -271.341341) (xy 99.925332 -271.333216) (xy 99.875939 -271.317168) (xy 99.829665 -271.29359)
			(xy 99.787649 -271.263064) (xy 99.750926 -271.226341) (xy 99.7204 -271.184325) (xy 99.696822 -271.138051)
			(xy 99.680774 -271.088658) (xy 99.672649 -271.037363) (xy 99.392739 -271.037363) (xy 99.384614 -271.088658)
			(xy 99.368566 -271.138051) (xy 99.344988 -271.184325) (xy 99.314462 -271.226341) (xy 99.277739 -271.263064)
			(xy 99.235723 -271.29359) (xy 99.189449 -271.317168) (xy 99.140056 -271.333216) (xy 99.088761 -271.341341)
			(xy 99.036827 -271.341341) (xy 98.985532 -271.333216) (xy 98.936139 -271.317168) (xy 98.889865 -271.29359)
			(xy 98.847849 -271.263064) (xy 98.811126 -271.226341) (xy 98.7806 -271.184325) (xy 98.757022 -271.138051)
			(xy 98.740974 -271.088658) (xy 98.732849 -271.037363) (xy 98.452939 -271.037363) (xy 98.444814 -271.088658)
			(xy 98.428766 -271.138051) (xy 98.405188 -271.184325) (xy 98.374662 -271.226341) (xy 98.337939 -271.263064)
			(xy 98.295923 -271.29359) (xy 98.249649 -271.317168) (xy 98.200256 -271.333216) (xy 98.148961 -271.341341)
			(xy 98.097027 -271.341341) (xy 98.045732 -271.333216) (xy 97.996339 -271.317168) (xy 97.950065 -271.29359)
			(xy 97.908049 -271.263064) (xy 97.871326 -271.226341) (xy 97.8408 -271.184325) (xy 97.817222 -271.138051)
			(xy 97.801174 -271.088658) (xy 97.793049 -271.037363) (xy 97.513139 -271.037363) (xy 97.505014 -271.088658)
			(xy 97.488966 -271.138051) (xy 97.465388 -271.184325) (xy 97.434862 -271.226341) (xy 97.398139 -271.263064)
			(xy 97.356123 -271.29359) (xy 97.309849 -271.317168) (xy 97.260456 -271.333216) (xy 97.209161 -271.341341)
			(xy 97.157227 -271.341341) (xy 97.105932 -271.333216) (xy 97.056539 -271.317168) (xy 97.010265 -271.29359)
			(xy 96.968249 -271.263064) (xy 96.931526 -271.226341) (xy 96.901 -271.184325) (xy 96.877422 -271.138051)
			(xy 96.861374 -271.088658) (xy 96.853249 -271.037363) (xy 96.573339 -271.037363) (xy 96.565214 -271.088658)
			(xy 96.549166 -271.138051) (xy 96.525588 -271.184325) (xy 96.495062 -271.226341) (xy 96.458339 -271.263064)
			(xy 96.416323 -271.29359) (xy 96.370049 -271.317168) (xy 96.320656 -271.333216) (xy 96.269361 -271.341341)
			(xy 96.217427 -271.341341) (xy 96.166132 -271.333216) (xy 96.116739 -271.317168) (xy 96.070465 -271.29359)
			(xy 96.028449 -271.263064) (xy 95.991726 -271.226341) (xy 95.9612 -271.184325) (xy 95.937622 -271.138051)
			(xy 95.921574 -271.088658) (xy 95.913449 -271.037363) (xy 95.633539 -271.037363) (xy 95.625414 -271.088658)
			(xy 95.609366 -271.138051) (xy 95.585788 -271.184325) (xy 95.555262 -271.226341) (xy 95.518539 -271.263064)
			(xy 95.476523 -271.29359) (xy 95.430249 -271.317168) (xy 95.380856 -271.333216) (xy 95.329561 -271.341341)
			(xy 95.277627 -271.341341) (xy 95.226332 -271.333216) (xy 95.176939 -271.317168) (xy 95.130665 -271.29359)
			(xy 95.088649 -271.263064) (xy 95.051926 -271.226341) (xy 95.0214 -271.184325) (xy 94.997822 -271.138051)
			(xy 94.981774 -271.088658) (xy 94.973649 -271.037363) (xy 94.693993 -271.037363) (xy 94.685868 -271.088658)
			(xy 94.66982 -271.138051) (xy 94.646242 -271.184325) (xy 94.615716 -271.226341) (xy 94.578993 -271.263064)
			(xy 94.536977 -271.29359) (xy 94.490703 -271.317168) (xy 94.44131 -271.333216) (xy 94.390015 -271.341341)
			(xy 94.338081 -271.341341) (xy 94.286786 -271.333216) (xy 94.237393 -271.317168) (xy 94.191119 -271.29359)
			(xy 94.149103 -271.263064) (xy 94.11238 -271.226341) (xy 94.081854 -271.184325) (xy 94.058276 -271.138051)
			(xy 94.042228 -271.088658) (xy 94.034103 -271.037363) (xy 93.753939 -271.037363) (xy 93.745814 -271.088658)
			(xy 93.729766 -271.138051) (xy 93.706188 -271.184325) (xy 93.675662 -271.226341) (xy 93.638939 -271.263064)
			(xy 93.596923 -271.29359) (xy 93.550649 -271.317168) (xy 93.501256 -271.333216) (xy 93.449961 -271.341341)
			(xy 93.398027 -271.341341) (xy 93.346732 -271.333216) (xy 93.297339 -271.317168) (xy 93.251065 -271.29359)
			(xy 93.209049 -271.263064) (xy 93.172326 -271.226341) (xy 93.1418 -271.184325) (xy 93.118222 -271.138051)
			(xy 93.102174 -271.088658) (xy 93.094049 -271.037363) (xy 92.814139 -271.037363) (xy 92.806014 -271.088658)
			(xy 92.789966 -271.138051) (xy 92.766388 -271.184325) (xy 92.735862 -271.226341) (xy 92.699139 -271.263064)
			(xy 92.657123 -271.29359) (xy 92.610849 -271.317168) (xy 92.561456 -271.333216) (xy 92.510161 -271.341341)
			(xy 92.458227 -271.341341) (xy 92.406932 -271.333216) (xy 92.357539 -271.317168) (xy 92.311265 -271.29359)
			(xy 92.269249 -271.263064) (xy 92.232526 -271.226341) (xy 92.202 -271.184325) (xy 92.178422 -271.138051)
			(xy 92.162374 -271.088658) (xy 92.154249 -271.037363) (xy 91.873669 -271.037363) (xy 91.871663 -271.062974)
			(xy 91.859644 -271.113293) (xy 91.839938 -271.161127) (xy 91.813025 -271.20531) (xy 91.779563 -271.244765)
			(xy 91.740366 -271.27853) (xy 91.718638 -271.292574) (xy 91.712034 -271.296892) (xy 91.68765 -271.33931)
			(xy 91.68765 -271.45869) (xy 91.688003 -271.467576) (xy 91.694158 -271.484248) (xy 91.705709 -271.497753)
			(xy 91.713304 -271.502378) (xy 91.751658 -271.523714) (xy 91.791536 -271.545812) (xy 91.799315 -271.549422)
			(xy 91.816299 -271.55172) (xy 91.833076 -271.548223) (xy 91.840558 -271.544034) (xy 91.840812 -271.54378)
			(xy 91.860482 -271.5321) (xy 91.902354 -271.513672) (xy 91.946364 -271.501185) (xy 91.991674 -271.494879)
			(xy 92.014548 -271.494504) (xy 92.040532 -271.495017) (xy 92.091859 -271.503153) (xy 92.141281 -271.519218)
			(xy 92.187582 -271.542816) (xy 92.229622 -271.573365) (xy 92.266366 -271.610114) (xy 92.29691 -271.652159)
			(xy 92.3205 -271.698463) (xy 92.336558 -271.747888) (xy 92.344687 -271.799216) (xy 92.344687 -271.851179)
			(xy 92.624403 -271.851179) (xy 92.624403 -271.799245) (xy 92.632528 -271.74795) (xy 92.648576 -271.698557)
			(xy 92.672154 -271.652283) (xy 92.70268 -271.610267) (xy 92.739403 -271.573544) (xy 92.781419 -271.543018)
			(xy 92.827693 -271.51944) (xy 92.877086 -271.503392) (xy 92.928381 -271.495267) (xy 92.980315 -271.495267)
			(xy 93.03161 -271.503392) (xy 93.081003 -271.51944) (xy 93.127277 -271.543018) (xy 93.169293 -271.573544)
			(xy 93.206016 -271.610267) (xy 93.236542 -271.652283) (xy 93.26012 -271.698557) (xy 93.276168 -271.74795)
			(xy 93.284293 -271.799245) (xy 93.284802 -271.825212) (xy 93.284293 -271.851179) (xy 93.564203 -271.851179)
			(xy 93.564203 -271.799245) (xy 93.572328 -271.74795) (xy 93.588376 -271.698557) (xy 93.611954 -271.652283)
			(xy 93.64248 -271.610267) (xy 93.679203 -271.573544) (xy 93.721219 -271.543018) (xy 93.767493 -271.51944)
			(xy 93.816886 -271.503392) (xy 93.868181 -271.495267) (xy 93.920115 -271.495267) (xy 93.97141 -271.503392)
			(xy 94.020803 -271.51944) (xy 94.067077 -271.543018) (xy 94.109093 -271.573544) (xy 94.145816 -271.610267)
			(xy 94.176342 -271.652283) (xy 94.19992 -271.698557) (xy 94.215968 -271.74795) (xy 94.224093 -271.799245)
			(xy 94.224602 -271.825212) (xy 94.224093 -271.851179) (xy 94.504003 -271.851179) (xy 94.504003 -271.799245)
			(xy 94.512128 -271.74795) (xy 94.528176 -271.698557) (xy 94.551754 -271.652283) (xy 94.58228 -271.610267)
			(xy 94.619003 -271.573544) (xy 94.661019 -271.543018) (xy 94.707293 -271.51944) (xy 94.756686 -271.503392)
			(xy 94.807981 -271.495267) (xy 94.859915 -271.495267) (xy 94.91121 -271.503392) (xy 94.960603 -271.51944)
			(xy 95.006877 -271.543018) (xy 95.048893 -271.573544) (xy 95.085616 -271.610267) (xy 95.116142 -271.652283)
			(xy 95.13972 -271.698557) (xy 95.155768 -271.74795) (xy 95.163893 -271.799245) (xy 95.164402 -271.825212)
			(xy 95.163893 -271.851179) (xy 95.443803 -271.851179) (xy 95.443803 -271.799245) (xy 95.451928 -271.74795)
			(xy 95.467976 -271.698557) (xy 95.491554 -271.652283) (xy 95.52208 -271.610267) (xy 95.558803 -271.573544)
			(xy 95.600819 -271.543018) (xy 95.647093 -271.51944) (xy 95.696486 -271.503392) (xy 95.747781 -271.495267)
			(xy 95.799715 -271.495267) (xy 95.85101 -271.503392) (xy 95.900403 -271.51944) (xy 95.946677 -271.543018)
			(xy 95.988693 -271.573544) (xy 96.025416 -271.610267) (xy 96.055942 -271.652283) (xy 96.07952 -271.698557)
			(xy 96.095568 -271.74795) (xy 96.103693 -271.799245) (xy 96.104202 -271.825212) (xy 96.103693 -271.851179)
			(xy 96.383603 -271.851179) (xy 96.383603 -271.799245) (xy 96.391728 -271.74795) (xy 96.407776 -271.698557)
			(xy 96.431354 -271.652283) (xy 96.46188 -271.610267) (xy 96.498603 -271.573544) (xy 96.540619 -271.543018)
			(xy 96.586893 -271.51944) (xy 96.636286 -271.503392) (xy 96.687581 -271.495267) (xy 96.739515 -271.495267)
			(xy 96.79081 -271.503392) (xy 96.840203 -271.51944) (xy 96.886477 -271.543018) (xy 96.928493 -271.573544)
			(xy 96.965216 -271.610267) (xy 96.995742 -271.652283) (xy 97.01932 -271.698557) (xy 97.035368 -271.74795)
			(xy 97.043493 -271.799245) (xy 97.044002 -271.825212) (xy 97.043493 -271.851179) (xy 97.323149 -271.851179)
			(xy 97.323149 -271.799245) (xy 97.331274 -271.74795) (xy 97.347322 -271.698557) (xy 97.3709 -271.652283)
			(xy 97.401426 -271.610267) (xy 97.438149 -271.573544) (xy 97.480165 -271.543018) (xy 97.526439 -271.51944)
			(xy 97.575832 -271.503392) (xy 97.627127 -271.495267) (xy 97.679061 -271.495267) (xy 97.730356 -271.503392)
			(xy 97.779749 -271.51944) (xy 97.826023 -271.543018) (xy 97.868039 -271.573544) (xy 97.904762 -271.610267)
			(xy 97.935288 -271.652283) (xy 97.958866 -271.698557) (xy 97.974914 -271.74795) (xy 97.983039 -271.799245)
			(xy 97.983548 -271.825212) (xy 97.983039 -271.851179) (xy 98.263203 -271.851179) (xy 98.263203 -271.799245)
			(xy 98.271328 -271.74795) (xy 98.287376 -271.698557) (xy 98.310954 -271.652283) (xy 98.34148 -271.610267)
			(xy 98.378203 -271.573544) (xy 98.420219 -271.543018) (xy 98.466493 -271.51944) (xy 98.515886 -271.503392)
			(xy 98.567181 -271.495267) (xy 98.619115 -271.495267) (xy 98.67041 -271.503392) (xy 98.719803 -271.51944)
			(xy 98.766077 -271.543018) (xy 98.808093 -271.573544) (xy 98.844816 -271.610267) (xy 98.875342 -271.652283)
			(xy 98.89892 -271.698557) (xy 98.914968 -271.74795) (xy 98.923093 -271.799245) (xy 98.923602 -271.825212)
			(xy 98.923093 -271.851179) (xy 99.203003 -271.851179) (xy 99.203003 -271.799245) (xy 99.211128 -271.74795)
			(xy 99.227176 -271.698557) (xy 99.250754 -271.652283) (xy 99.28128 -271.610267) (xy 99.318003 -271.573544)
			(xy 99.360019 -271.543018) (xy 99.406293 -271.51944) (xy 99.455686 -271.503392) (xy 99.506981 -271.495267)
			(xy 99.558915 -271.495267) (xy 99.61021 -271.503392) (xy 99.659603 -271.51944) (xy 99.705877 -271.543018)
			(xy 99.747893 -271.573544) (xy 99.784616 -271.610267) (xy 99.815142 -271.652283) (xy 99.83872 -271.698557)
			(xy 99.854768 -271.74795) (xy 99.862893 -271.799245) (xy 99.863402 -271.825212) (xy 99.862893 -271.851179)
			(xy 100.142803 -271.851179) (xy 100.142803 -271.799245) (xy 100.150928 -271.74795) (xy 100.166976 -271.698557)
			(xy 100.190554 -271.652283) (xy 100.22108 -271.610267) (xy 100.257803 -271.573544) (xy 100.299819 -271.543018)
			(xy 100.346093 -271.51944) (xy 100.395486 -271.503392) (xy 100.446781 -271.495267) (xy 100.498715 -271.495267)
			(xy 100.55001 -271.503392) (xy 100.599403 -271.51944) (xy 100.645677 -271.543018) (xy 100.687693 -271.573544)
			(xy 100.724416 -271.610267) (xy 100.754942 -271.652283) (xy 100.77852 -271.698557) (xy 100.794568 -271.74795)
			(xy 100.802693 -271.799245) (xy 100.803202 -271.825212) (xy 100.802693 -271.851179) (xy 101.082603 -271.851179)
			(xy 101.082603 -271.799245) (xy 101.090728 -271.74795) (xy 101.106776 -271.698557) (xy 101.130354 -271.652283)
			(xy 101.16088 -271.610267) (xy 101.197603 -271.573544) (xy 101.239619 -271.543018) (xy 101.285893 -271.51944)
			(xy 101.335286 -271.503392) (xy 101.386581 -271.495267) (xy 101.438515 -271.495267) (xy 101.48981 -271.503392)
			(xy 101.539203 -271.51944) (xy 101.585477 -271.543018) (xy 101.627493 -271.573544) (xy 101.664216 -271.610267)
			(xy 101.694742 -271.652283) (xy 101.71832 -271.698557) (xy 101.734368 -271.74795) (xy 101.742493 -271.799245)
			(xy 101.743002 -271.825212) (xy 101.742493 -271.851179) (xy 102.022403 -271.851179) (xy 102.022403 -271.799245)
			(xy 102.030528 -271.74795) (xy 102.046576 -271.698557) (xy 102.070154 -271.652283) (xy 102.10068 -271.610267)
			(xy 102.137403 -271.573544) (xy 102.179419 -271.543018) (xy 102.225693 -271.51944) (xy 102.275086 -271.503392)
			(xy 102.326381 -271.495267) (xy 102.378315 -271.495267) (xy 102.42961 -271.503392) (xy 102.479003 -271.51944)
			(xy 102.525277 -271.543018) (xy 102.567293 -271.573544) (xy 102.604016 -271.610267) (xy 102.634542 -271.652283)
			(xy 102.65812 -271.698557) (xy 102.674168 -271.74795) (xy 102.682293 -271.799245) (xy 102.682802 -271.825212)
			(xy 102.682293 -271.851179) (xy 102.962203 -271.851179) (xy 102.962203 -271.799245) (xy 102.970328 -271.74795)
			(xy 102.986376 -271.698557) (xy 103.009954 -271.652283) (xy 103.04048 -271.610267) (xy 103.077203 -271.573544)
			(xy 103.119219 -271.543018) (xy 103.165493 -271.51944) (xy 103.214886 -271.503392) (xy 103.266181 -271.495267)
			(xy 103.318115 -271.495267) (xy 103.36941 -271.503392) (xy 103.418803 -271.51944) (xy 103.465077 -271.543018)
			(xy 103.507093 -271.573544) (xy 103.543816 -271.610267) (xy 103.574342 -271.652283) (xy 103.59792 -271.698557)
			(xy 103.613968 -271.74795) (xy 103.622093 -271.799245) (xy 103.622602 -271.825212) (xy 103.622093 -271.851179)
			(xy 103.902003 -271.851179) (xy 103.902003 -271.799245) (xy 103.910128 -271.74795) (xy 103.926176 -271.698557)
			(xy 103.949754 -271.652283) (xy 103.98028 -271.610267) (xy 104.017003 -271.573544) (xy 104.059019 -271.543018)
			(xy 104.105293 -271.51944) (xy 104.154686 -271.503392) (xy 104.205981 -271.495267) (xy 104.257915 -271.495267)
			(xy 104.30921 -271.503392) (xy 104.358603 -271.51944) (xy 104.404877 -271.543018) (xy 104.446893 -271.573544)
			(xy 104.483616 -271.610267) (xy 104.514142 -271.652283) (xy 104.53772 -271.698557) (xy 104.553768 -271.74795)
			(xy 104.561893 -271.799245) (xy 104.562402 -271.825212) (xy 104.561893 -271.851179) (xy 104.841803 -271.851179)
			(xy 104.841803 -271.799245) (xy 104.849928 -271.74795) (xy 104.865976 -271.698557) (xy 104.889554 -271.652283)
			(xy 104.92008 -271.610267) (xy 104.956803 -271.573544) (xy 104.998819 -271.543018) (xy 105.045093 -271.51944)
			(xy 105.094486 -271.503392) (xy 105.145781 -271.495267) (xy 105.197715 -271.495267) (xy 105.24901 -271.503392)
			(xy 105.298403 -271.51944) (xy 105.344677 -271.543018) (xy 105.386693 -271.573544) (xy 105.423416 -271.610267)
			(xy 105.453942 -271.652283) (xy 105.47752 -271.698557) (xy 105.493568 -271.74795) (xy 105.501693 -271.799245)
			(xy 105.502202 -271.825212) (xy 105.501693 -271.851179) (xy 105.781603 -271.851179) (xy 105.781603 -271.799245)
			(xy 105.789728 -271.74795) (xy 105.805776 -271.698557) (xy 105.829354 -271.652283) (xy 105.85988 -271.610267)
			(xy 105.896603 -271.573544) (xy 105.938619 -271.543018) (xy 105.984893 -271.51944) (xy 106.034286 -271.503392)
			(xy 106.085581 -271.495267) (xy 106.137515 -271.495267) (xy 106.18881 -271.503392) (xy 106.238203 -271.51944)
			(xy 106.284477 -271.543018) (xy 106.326493 -271.573544) (xy 106.363216 -271.610267) (xy 106.393742 -271.652283)
			(xy 106.41732 -271.698557) (xy 106.433368 -271.74795) (xy 106.441493 -271.799245) (xy 106.442002 -271.825212)
			(xy 106.441493 -271.851179) (xy 106.721403 -271.851179) (xy 106.721403 -271.799245) (xy 106.729528 -271.74795)
			(xy 106.745576 -271.698557) (xy 106.769154 -271.652283) (xy 106.79968 -271.610267) (xy 106.836403 -271.573544)
			(xy 106.878419 -271.543018) (xy 106.924693 -271.51944) (xy 106.974086 -271.503392) (xy 107.025381 -271.495267)
			(xy 107.077315 -271.495267) (xy 107.12861 -271.503392) (xy 107.178003 -271.51944) (xy 107.224277 -271.543018)
			(xy 107.266293 -271.573544) (xy 107.303016 -271.610267) (xy 107.333542 -271.652283) (xy 107.35712 -271.698557)
			(xy 107.373168 -271.74795) (xy 107.381293 -271.799245) (xy 107.381802 -271.825212) (xy 107.381293 -271.851179)
			(xy 107.661203 -271.851179) (xy 107.661203 -271.799245) (xy 107.669328 -271.74795) (xy 107.685376 -271.698557)
			(xy 107.708954 -271.652283) (xy 107.73948 -271.610267) (xy 107.776203 -271.573544) (xy 107.818219 -271.543018)
			(xy 107.864493 -271.51944) (xy 107.913886 -271.503392) (xy 107.965181 -271.495267) (xy 108.017115 -271.495267)
			(xy 108.06841 -271.503392) (xy 108.117803 -271.51944) (xy 108.164077 -271.543018) (xy 108.206093 -271.573544)
			(xy 108.242816 -271.610267) (xy 108.273342 -271.652283) (xy 108.29692 -271.698557) (xy 108.312968 -271.74795)
			(xy 108.321093 -271.799245) (xy 108.321602 -271.825212) (xy 108.321093 -271.851179) (xy 108.601003 -271.851179)
			(xy 108.601003 -271.799245) (xy 108.609128 -271.74795) (xy 108.625176 -271.698557) (xy 108.648754 -271.652283)
			(xy 108.67928 -271.610267) (xy 108.716003 -271.573544) (xy 108.758019 -271.543018) (xy 108.804293 -271.51944)
			(xy 108.853686 -271.503392) (xy 108.904981 -271.495267) (xy 108.956915 -271.495267) (xy 109.00821 -271.503392)
			(xy 109.057603 -271.51944) (xy 109.103877 -271.543018) (xy 109.145893 -271.573544) (xy 109.182616 -271.610267)
			(xy 109.213142 -271.652283) (xy 109.23672 -271.698557) (xy 109.252768 -271.74795) (xy 109.260893 -271.799245)
			(xy 109.261402 -271.825212) (xy 109.260893 -271.851179) (xy 109.540295 -271.851179) (xy 109.540295 -271.799245)
			(xy 109.54842 -271.74795) (xy 109.564468 -271.698557) (xy 109.588046 -271.652283) (xy 109.618572 -271.610267)
			(xy 109.655295 -271.573544) (xy 109.697311 -271.543018) (xy 109.743585 -271.51944) (xy 109.792978 -271.503392)
			(xy 109.844273 -271.495267) (xy 109.896207 -271.495267) (xy 109.947502 -271.503392) (xy 109.996895 -271.51944)
			(xy 110.043169 -271.543018) (xy 110.085185 -271.573544) (xy 110.121908 -271.610267) (xy 110.152434 -271.652283)
			(xy 110.176012 -271.698557) (xy 110.19206 -271.74795) (xy 110.200185 -271.799245) (xy 110.200694 -271.825212)
			(xy 110.200185 -271.851179) (xy 110.480603 -271.851179) (xy 110.480603 -271.799245) (xy 110.488728 -271.74795)
			(xy 110.504776 -271.698557) (xy 110.528354 -271.652283) (xy 110.55888 -271.610267) (xy 110.595603 -271.573544)
			(xy 110.637619 -271.543018) (xy 110.683893 -271.51944) (xy 110.733286 -271.503392) (xy 110.784581 -271.495267)
			(xy 110.836515 -271.495267) (xy 110.88781 -271.503392) (xy 110.937203 -271.51944) (xy 110.983477 -271.543018)
			(xy 111.025493 -271.573544) (xy 111.062216 -271.610267) (xy 111.092742 -271.652283) (xy 111.11632 -271.698557)
			(xy 111.132368 -271.74795) (xy 111.140493 -271.799245) (xy 111.141002 -271.825212) (xy 111.140493 -271.851179)
			(xy 111.420149 -271.851179) (xy 111.420149 -271.799245) (xy 111.428274 -271.74795) (xy 111.444322 -271.698557)
			(xy 111.4679 -271.652283) (xy 111.498426 -271.610267) (xy 111.535149 -271.573544) (xy 111.577165 -271.543018)
			(xy 111.623439 -271.51944) (xy 111.672832 -271.503392) (xy 111.724127 -271.495267) (xy 111.776061 -271.495267)
			(xy 111.827356 -271.503392) (xy 111.876749 -271.51944) (xy 111.923023 -271.543018) (xy 111.965039 -271.573544)
			(xy 112.001762 -271.610267) (xy 112.032288 -271.652283) (xy 112.055866 -271.698557) (xy 112.071914 -271.74795)
			(xy 112.080039 -271.799245) (xy 112.080548 -271.825212) (xy 112.080039 -271.851179) (xy 112.359949 -271.851179)
			(xy 112.359949 -271.799245) (xy 112.368074 -271.74795) (xy 112.384122 -271.698557) (xy 112.4077 -271.652283)
			(xy 112.438226 -271.610267) (xy 112.474949 -271.573544) (xy 112.516965 -271.543018) (xy 112.563239 -271.51944)
			(xy 112.612632 -271.503392) (xy 112.663927 -271.495267) (xy 112.715861 -271.495267) (xy 112.767156 -271.503392)
			(xy 112.816549 -271.51944) (xy 112.862823 -271.543018) (xy 112.904839 -271.573544) (xy 112.941562 -271.610267)
			(xy 112.972088 -271.652283) (xy 112.995666 -271.698557) (xy 113.011714 -271.74795) (xy 113.019839 -271.799245)
			(xy 113.020348 -271.825212) (xy 113.019839 -271.851179) (xy 113.299749 -271.851179) (xy 113.299749 -271.799245)
			(xy 113.307874 -271.74795) (xy 113.323922 -271.698557) (xy 113.3475 -271.652283) (xy 113.378026 -271.610267)
			(xy 113.414749 -271.573544) (xy 113.456765 -271.543018) (xy 113.503039 -271.51944) (xy 113.552432 -271.503392)
			(xy 113.603727 -271.495267) (xy 113.655661 -271.495267) (xy 113.706956 -271.503392) (xy 113.756349 -271.51944)
			(xy 113.802623 -271.543018) (xy 113.844639 -271.573544) (xy 113.881362 -271.610267) (xy 113.911888 -271.652283)
			(xy 113.935466 -271.698557) (xy 113.951514 -271.74795) (xy 113.959639 -271.799245) (xy 113.960148 -271.825212)
			(xy 113.959639 -271.851179) (xy 114.239803 -271.851179) (xy 114.239803 -271.799245) (xy 114.247928 -271.74795)
			(xy 114.263976 -271.698557) (xy 114.287554 -271.652283) (xy 114.31808 -271.610267) (xy 114.354803 -271.573544)
			(xy 114.396819 -271.543018) (xy 114.443093 -271.51944) (xy 114.492486 -271.503392) (xy 114.543781 -271.495267)
			(xy 114.595715 -271.495267) (xy 114.64701 -271.503392) (xy 114.696403 -271.51944) (xy 114.742677 -271.543018)
			(xy 114.784693 -271.573544) (xy 114.821416 -271.610267) (xy 114.851942 -271.652283) (xy 114.87552 -271.698557)
			(xy 114.891568 -271.74795) (xy 114.899693 -271.799245) (xy 114.900202 -271.825212) (xy 114.899693 -271.851179)
			(xy 115.179603 -271.851179) (xy 115.179603 -271.799245) (xy 115.187728 -271.74795) (xy 115.203776 -271.698557)
			(xy 115.227354 -271.652283) (xy 115.25788 -271.610267) (xy 115.294603 -271.573544) (xy 115.336619 -271.543018)
			(xy 115.382893 -271.51944) (xy 115.432286 -271.503392) (xy 115.483581 -271.495267) (xy 115.535515 -271.495267)
			(xy 115.58681 -271.503392) (xy 115.636203 -271.51944) (xy 115.682477 -271.543018) (xy 115.724493 -271.573544)
			(xy 115.761216 -271.610267) (xy 115.791742 -271.652283) (xy 115.81532 -271.698557) (xy 115.831368 -271.74795)
			(xy 115.839493 -271.799245) (xy 115.840002 -271.825212) (xy 115.839493 -271.851179) (xy 116.118895 -271.851179)
			(xy 116.118895 -271.799245) (xy 116.12702 -271.74795) (xy 116.143068 -271.698557) (xy 116.166646 -271.652283)
			(xy 116.197172 -271.610267) (xy 116.233895 -271.573544) (xy 116.275911 -271.543018) (xy 116.322185 -271.51944)
			(xy 116.371578 -271.503392) (xy 116.422873 -271.495267) (xy 116.474807 -271.495267) (xy 116.526102 -271.503392)
			(xy 116.575495 -271.51944) (xy 116.621769 -271.543018) (xy 116.663785 -271.573544) (xy 116.700508 -271.610267)
			(xy 116.731034 -271.652283) (xy 116.754612 -271.698557) (xy 116.77066 -271.74795) (xy 116.778785 -271.799245)
			(xy 116.779294 -271.825212) (xy 116.778785 -271.851179) (xy 117.059203 -271.851179) (xy 117.059203 -271.799245)
			(xy 117.067328 -271.74795) (xy 117.083376 -271.698557) (xy 117.106954 -271.652283) (xy 117.13748 -271.610267)
			(xy 117.174203 -271.573544) (xy 117.216219 -271.543018) (xy 117.262493 -271.51944) (xy 117.311886 -271.503392)
			(xy 117.363181 -271.495267) (xy 117.415115 -271.495267) (xy 117.46641 -271.503392) (xy 117.515803 -271.51944)
			(xy 117.562077 -271.543018) (xy 117.604093 -271.573544) (xy 117.640816 -271.610267) (xy 117.671342 -271.652283)
			(xy 117.69492 -271.698557) (xy 117.710968 -271.74795) (xy 117.719093 -271.799245) (xy 117.719602 -271.825212)
			(xy 117.719093 -271.851179) (xy 117.998495 -271.851179) (xy 117.998495 -271.799245) (xy 118.00662 -271.74795)
			(xy 118.022668 -271.698557) (xy 118.046246 -271.652283) (xy 118.076772 -271.610267) (xy 118.113495 -271.573544)
			(xy 118.155511 -271.543018) (xy 118.201785 -271.51944) (xy 118.251178 -271.503392) (xy 118.302473 -271.495267)
			(xy 118.354407 -271.495267) (xy 118.405702 -271.503392) (xy 118.455095 -271.51944) (xy 118.501369 -271.543018)
			(xy 118.543385 -271.573544) (xy 118.580108 -271.610267) (xy 118.610634 -271.652283) (xy 118.634212 -271.698557)
			(xy 118.65026 -271.74795) (xy 118.658385 -271.799245) (xy 118.658894 -271.825212) (xy 118.658385 -271.851179)
			(xy 118.938295 -271.851179) (xy 118.938295 -271.799245) (xy 118.94642 -271.74795) (xy 118.962468 -271.698557)
			(xy 118.986046 -271.652283) (xy 119.016572 -271.610267) (xy 119.053295 -271.573544) (xy 119.095311 -271.543018)
			(xy 119.141585 -271.51944) (xy 119.190978 -271.503392) (xy 119.242273 -271.495267) (xy 119.294207 -271.495267)
			(xy 119.345502 -271.503392) (xy 119.394895 -271.51944) (xy 119.441169 -271.543018) (xy 119.483185 -271.573544)
			(xy 119.519908 -271.610267) (xy 119.550434 -271.652283) (xy 119.574012 -271.698557) (xy 119.59006 -271.74795)
			(xy 119.598185 -271.799245) (xy 119.598694 -271.825212) (xy 119.598185 -271.851179) (xy 119.878603 -271.851179)
			(xy 119.878603 -271.799245) (xy 119.886728 -271.74795) (xy 119.902776 -271.698557) (xy 119.926354 -271.652283)
			(xy 119.95688 -271.610267) (xy 119.993603 -271.573544) (xy 120.035619 -271.543018) (xy 120.081893 -271.51944)
			(xy 120.131286 -271.503392) (xy 120.182581 -271.495267) (xy 120.234515 -271.495267) (xy 120.28581 -271.503392)
			(xy 120.335203 -271.51944) (xy 120.381477 -271.543018) (xy 120.423493 -271.573544) (xy 120.460216 -271.610267)
			(xy 120.490742 -271.652283) (xy 120.51432 -271.698557) (xy 120.530368 -271.74795) (xy 120.538493 -271.799245)
			(xy 120.539002 -271.825212) (xy 120.538493 -271.851179) (xy 120.818403 -271.851179) (xy 120.818403 -271.799245)
			(xy 120.826528 -271.74795) (xy 120.842576 -271.698557) (xy 120.866154 -271.652283) (xy 120.89668 -271.610267)
			(xy 120.933403 -271.573544) (xy 120.975419 -271.543018) (xy 121.021693 -271.51944) (xy 121.071086 -271.503392)
			(xy 121.122381 -271.495267) (xy 121.174315 -271.495267) (xy 121.22561 -271.503392) (xy 121.275003 -271.51944)
			(xy 121.321277 -271.543018) (xy 121.363293 -271.573544) (xy 121.400016 -271.610267) (xy 121.430542 -271.652283)
			(xy 121.45412 -271.698557) (xy 121.470168 -271.74795) (xy 121.478293 -271.799245) (xy 121.478802 -271.825212)
			(xy 121.478293 -271.851179) (xy 121.758203 -271.851179) (xy 121.758203 -271.799245) (xy 121.766328 -271.74795)
			(xy 121.782376 -271.698557) (xy 121.805954 -271.652283) (xy 121.83648 -271.610267) (xy 121.873203 -271.573544)
			(xy 121.915219 -271.543018) (xy 121.961493 -271.51944) (xy 122.010886 -271.503392) (xy 122.062181 -271.495267)
			(xy 122.114115 -271.495267) (xy 122.16541 -271.503392) (xy 122.214803 -271.51944) (xy 122.261077 -271.543018)
			(xy 122.303093 -271.573544) (xy 122.339816 -271.610267) (xy 122.370342 -271.652283) (xy 122.39392 -271.698557)
			(xy 122.409968 -271.74795) (xy 122.418093 -271.799245) (xy 122.418602 -271.825212) (xy 122.418093 -271.851179)
			(xy 122.698003 -271.851179) (xy 122.698003 -271.799245) (xy 122.706128 -271.74795) (xy 122.722176 -271.698557)
			(xy 122.745754 -271.652283) (xy 122.77628 -271.610267) (xy 122.813003 -271.573544) (xy 122.855019 -271.543018)
			(xy 122.901293 -271.51944) (xy 122.950686 -271.503392) (xy 123.001981 -271.495267) (xy 123.053915 -271.495267)
			(xy 123.10521 -271.503392) (xy 123.154603 -271.51944) (xy 123.200877 -271.543018) (xy 123.242893 -271.573544)
			(xy 123.279616 -271.610267) (xy 123.310142 -271.652283) (xy 123.33372 -271.698557) (xy 123.349768 -271.74795)
			(xy 123.357893 -271.799245) (xy 123.358402 -271.825212) (xy 123.357893 -271.851179) (xy 123.637803 -271.851179)
			(xy 123.637803 -271.799245) (xy 123.645928 -271.74795) (xy 123.661976 -271.698557) (xy 123.685554 -271.652283)
			(xy 123.71608 -271.610267) (xy 123.752803 -271.573544) (xy 123.794819 -271.543018) (xy 123.841093 -271.51944)
			(xy 123.890486 -271.503392) (xy 123.941781 -271.495267) (xy 123.993715 -271.495267) (xy 124.04501 -271.503392)
			(xy 124.094403 -271.51944) (xy 124.140677 -271.543018) (xy 124.182693 -271.573544) (xy 124.219416 -271.610267)
			(xy 124.249942 -271.652283) (xy 124.27352 -271.698557) (xy 124.289568 -271.74795) (xy 124.297693 -271.799245)
			(xy 124.298202 -271.825212) (xy 124.297693 -271.851179) (xy 124.577603 -271.851179) (xy 124.577603 -271.799245)
			(xy 124.585728 -271.74795) (xy 124.601776 -271.698557) (xy 124.625354 -271.652283) (xy 124.65588 -271.610267)
			(xy 124.692603 -271.573544) (xy 124.734619 -271.543018) (xy 124.780893 -271.51944) (xy 124.830286 -271.503392)
			(xy 124.881581 -271.495267) (xy 124.933515 -271.495267) (xy 124.98481 -271.503392) (xy 125.034203 -271.51944)
			(xy 125.080477 -271.543018) (xy 125.122493 -271.573544) (xy 125.159216 -271.610267) (xy 125.189742 -271.652283)
			(xy 125.21332 -271.698557) (xy 125.229368 -271.74795) (xy 125.237493 -271.799245) (xy 125.238002 -271.825212)
			(xy 125.237493 -271.851179) (xy 125.517149 -271.851179) (xy 125.517149 -271.799245) (xy 125.525274 -271.74795)
			(xy 125.541322 -271.698557) (xy 125.5649 -271.652283) (xy 125.595426 -271.610267) (xy 125.632149 -271.573544)
			(xy 125.674165 -271.543018) (xy 125.720439 -271.51944) (xy 125.769832 -271.503392) (xy 125.821127 -271.495267)
			(xy 125.873061 -271.495267) (xy 125.924356 -271.503392) (xy 125.973749 -271.51944) (xy 126.020023 -271.543018)
			(xy 126.062039 -271.573544) (xy 126.098762 -271.610267) (xy 126.129288 -271.652283) (xy 126.152866 -271.698557)
			(xy 126.168914 -271.74795) (xy 126.177039 -271.799245) (xy 126.177548 -271.825212) (xy 126.177039 -271.851179)
			(xy 126.457203 -271.851179) (xy 126.457203 -271.799245) (xy 126.465328 -271.74795) (xy 126.481376 -271.698557)
			(xy 126.504954 -271.652283) (xy 126.53548 -271.610267) (xy 126.572203 -271.573544) (xy 126.614219 -271.543018)
			(xy 126.660493 -271.51944) (xy 126.709886 -271.503392) (xy 126.761181 -271.495267) (xy 126.813115 -271.495267)
			(xy 126.86441 -271.503392) (xy 126.913803 -271.51944) (xy 126.960077 -271.543018) (xy 127.002093 -271.573544)
			(xy 127.038816 -271.610267) (xy 127.069342 -271.652283) (xy 127.09292 -271.698557) (xy 127.108968 -271.74795)
			(xy 127.117093 -271.799245) (xy 127.117602 -271.825212) (xy 127.117093 -271.851179) (xy 127.397003 -271.851179)
			(xy 127.397003 -271.799245) (xy 127.405128 -271.74795) (xy 127.421176 -271.698557) (xy 127.444754 -271.652283)
			(xy 127.47528 -271.610267) (xy 127.512003 -271.573544) (xy 127.554019 -271.543018) (xy 127.600293 -271.51944)
			(xy 127.649686 -271.503392) (xy 127.700981 -271.495267) (xy 127.752915 -271.495267) (xy 127.80421 -271.503392)
			(xy 127.853603 -271.51944) (xy 127.899877 -271.543018) (xy 127.941893 -271.573544) (xy 127.978616 -271.610267)
			(xy 128.009142 -271.652283) (xy 128.03272 -271.698557) (xy 128.048768 -271.74795) (xy 128.056893 -271.799245)
			(xy 128.057402 -271.825212) (xy 128.056893 -271.851179) (xy 128.336803 -271.851179) (xy 128.336803 -271.799245)
			(xy 128.344928 -271.74795) (xy 128.360976 -271.698557) (xy 128.384554 -271.652283) (xy 128.41508 -271.610267)
			(xy 128.451803 -271.573544) (xy 128.493819 -271.543018) (xy 128.540093 -271.51944) (xy 128.589486 -271.503392)
			(xy 128.640781 -271.495267) (xy 128.692715 -271.495267) (xy 128.74401 -271.503392) (xy 128.793403 -271.51944)
			(xy 128.839677 -271.543018) (xy 128.881693 -271.573544) (xy 128.918416 -271.610267) (xy 128.948942 -271.652283)
			(xy 128.97252 -271.698557) (xy 128.988568 -271.74795) (xy 128.996693 -271.799245) (xy 128.997202 -271.825212)
			(xy 128.996693 -271.851179) (xy 129.276603 -271.851179) (xy 129.276603 -271.799245) (xy 129.284728 -271.74795)
			(xy 129.300776 -271.698557) (xy 129.324354 -271.652283) (xy 129.35488 -271.610267) (xy 129.391603 -271.573544)
			(xy 129.433619 -271.543018) (xy 129.479893 -271.51944) (xy 129.529286 -271.503392) (xy 129.580581 -271.495267)
			(xy 129.632515 -271.495267) (xy 129.68381 -271.503392) (xy 129.733203 -271.51944) (xy 129.779477 -271.543018)
			(xy 129.821493 -271.573544) (xy 129.858216 -271.610267) (xy 129.888742 -271.652283) (xy 129.91232 -271.698557)
			(xy 129.928368 -271.74795) (xy 129.936493 -271.799245) (xy 129.937002 -271.825212) (xy 129.936493 -271.851179)
			(xy 130.216403 -271.851179) (xy 130.216403 -271.799245) (xy 130.224528 -271.74795) (xy 130.240576 -271.698557)
			(xy 130.264154 -271.652283) (xy 130.29468 -271.610267) (xy 130.331403 -271.573544) (xy 130.373419 -271.543018)
			(xy 130.419693 -271.51944) (xy 130.469086 -271.503392) (xy 130.520381 -271.495267) (xy 130.572315 -271.495267)
			(xy 130.62361 -271.503392) (xy 130.673003 -271.51944) (xy 130.719277 -271.543018) (xy 130.761293 -271.573544)
			(xy 130.798016 -271.610267) (xy 130.828542 -271.652283) (xy 130.85212 -271.698557) (xy 130.868168 -271.74795)
			(xy 130.876293 -271.799245) (xy 130.876802 -271.825212) (xy 130.876293 -271.851179) (xy 130.868168 -271.902474)
			(xy 130.85212 -271.951867) (xy 130.828542 -271.998141) (xy 130.798016 -272.040157) (xy 130.761293 -272.07688)
			(xy 130.719277 -272.107406) (xy 130.673003 -272.130984) (xy 130.62361 -272.147032) (xy 130.572315 -272.155157)
			(xy 130.520381 -272.155157) (xy 130.469086 -272.147032) (xy 130.419693 -272.130984) (xy 130.373419 -272.107406)
			(xy 130.331403 -272.07688) (xy 130.29468 -272.040157) (xy 130.264154 -271.998141) (xy 130.240576 -271.951867)
			(xy 130.224528 -271.902474) (xy 130.216403 -271.851179) (xy 129.936493 -271.851179) (xy 129.928368 -271.902474)
			(xy 129.91232 -271.951867) (xy 129.888742 -271.998141) (xy 129.858216 -272.040157) (xy 129.821493 -272.07688)
			(xy 129.779477 -272.107406) (xy 129.733203 -272.130984) (xy 129.68381 -272.147032) (xy 129.632515 -272.155157)
			(xy 129.580581 -272.155157) (xy 129.529286 -272.147032) (xy 129.479893 -272.130984) (xy 129.433619 -272.107406)
			(xy 129.391603 -272.07688) (xy 129.35488 -272.040157) (xy 129.324354 -271.998141) (xy 129.300776 -271.951867)
			(xy 129.284728 -271.902474) (xy 129.276603 -271.851179) (xy 128.996693 -271.851179) (xy 128.988568 -271.902474)
			(xy 128.97252 -271.951867) (xy 128.948942 -271.998141) (xy 128.918416 -272.040157) (xy 128.881693 -272.07688)
			(xy 128.839677 -272.107406) (xy 128.793403 -272.130984) (xy 128.74401 -272.147032) (xy 128.692715 -272.155157)
			(xy 128.640781 -272.155157) (xy 128.589486 -272.147032) (xy 128.540093 -272.130984) (xy 128.493819 -272.107406)
			(xy 128.451803 -272.07688) (xy 128.41508 -272.040157) (xy 128.384554 -271.998141) (xy 128.360976 -271.951867)
			(xy 128.344928 -271.902474) (xy 128.336803 -271.851179) (xy 128.056893 -271.851179) (xy 128.048768 -271.902474)
			(xy 128.03272 -271.951867) (xy 128.009142 -271.998141) (xy 127.978616 -272.040157) (xy 127.941893 -272.07688)
			(xy 127.899877 -272.107406) (xy 127.853603 -272.130984) (xy 127.80421 -272.147032) (xy 127.752915 -272.155157)
			(xy 127.700981 -272.155157) (xy 127.649686 -272.147032) (xy 127.600293 -272.130984) (xy 127.554019 -272.107406)
			(xy 127.512003 -272.07688) (xy 127.47528 -272.040157) (xy 127.444754 -271.998141) (xy 127.421176 -271.951867)
			(xy 127.405128 -271.902474) (xy 127.397003 -271.851179) (xy 127.117093 -271.851179) (xy 127.108968 -271.902474)
			(xy 127.09292 -271.951867) (xy 127.069342 -271.998141) (xy 127.038816 -272.040157) (xy 127.002093 -272.07688)
			(xy 126.960077 -272.107406) (xy 126.913803 -272.130984) (xy 126.86441 -272.147032) (xy 126.813115 -272.155157)
			(xy 126.761181 -272.155157) (xy 126.709886 -272.147032) (xy 126.660493 -272.130984) (xy 126.614219 -272.107406)
			(xy 126.572203 -272.07688) (xy 126.53548 -272.040157) (xy 126.504954 -271.998141) (xy 126.481376 -271.951867)
			(xy 126.465328 -271.902474) (xy 126.457203 -271.851179) (xy 126.177039 -271.851179) (xy 126.168914 -271.902474)
			(xy 126.152866 -271.951867) (xy 126.129288 -271.998141) (xy 126.098762 -272.040157) (xy 126.062039 -272.07688)
			(xy 126.020023 -272.107406) (xy 125.973749 -272.130984) (xy 125.924356 -272.147032) (xy 125.873061 -272.155157)
			(xy 125.821127 -272.155157) (xy 125.769832 -272.147032) (xy 125.720439 -272.130984) (xy 125.674165 -272.107406)
			(xy 125.632149 -272.07688) (xy 125.595426 -272.040157) (xy 125.5649 -271.998141) (xy 125.541322 -271.951867)
			(xy 125.525274 -271.902474) (xy 125.517149 -271.851179) (xy 125.237493 -271.851179) (xy 125.229368 -271.902474)
			(xy 125.21332 -271.951867) (xy 125.189742 -271.998141) (xy 125.159216 -272.040157) (xy 125.122493 -272.07688)
			(xy 125.080477 -272.107406) (xy 125.034203 -272.130984) (xy 124.98481 -272.147032) (xy 124.933515 -272.155157)
			(xy 124.881581 -272.155157) (xy 124.830286 -272.147032) (xy 124.780893 -272.130984) (xy 124.734619 -272.107406)
			(xy 124.692603 -272.07688) (xy 124.65588 -272.040157) (xy 124.625354 -271.998141) (xy 124.601776 -271.951867)
			(xy 124.585728 -271.902474) (xy 124.577603 -271.851179) (xy 124.297693 -271.851179) (xy 124.289568 -271.902474)
			(xy 124.27352 -271.951867) (xy 124.249942 -271.998141) (xy 124.219416 -272.040157) (xy 124.182693 -272.07688)
			(xy 124.140677 -272.107406) (xy 124.094403 -272.130984) (xy 124.04501 -272.147032) (xy 123.993715 -272.155157)
			(xy 123.941781 -272.155157) (xy 123.890486 -272.147032) (xy 123.841093 -272.130984) (xy 123.794819 -272.107406)
			(xy 123.752803 -272.07688) (xy 123.71608 -272.040157) (xy 123.685554 -271.998141) (xy 123.661976 -271.951867)
			(xy 123.645928 -271.902474) (xy 123.637803 -271.851179) (xy 123.357893 -271.851179) (xy 123.349768 -271.902474)
			(xy 123.33372 -271.951867) (xy 123.310142 -271.998141) (xy 123.279616 -272.040157) (xy 123.242893 -272.07688)
			(xy 123.200877 -272.107406) (xy 123.154603 -272.130984) (xy 123.10521 -272.147032) (xy 123.053915 -272.155157)
			(xy 123.001981 -272.155157) (xy 122.950686 -272.147032) (xy 122.901293 -272.130984) (xy 122.855019 -272.107406)
			(xy 122.813003 -272.07688) (xy 122.77628 -272.040157) (xy 122.745754 -271.998141) (xy 122.722176 -271.951867)
			(xy 122.706128 -271.902474) (xy 122.698003 -271.851179) (xy 122.418093 -271.851179) (xy 122.409968 -271.902474)
			(xy 122.39392 -271.951867) (xy 122.370342 -271.998141) (xy 122.339816 -272.040157) (xy 122.303093 -272.07688)
			(xy 122.261077 -272.107406) (xy 122.214803 -272.130984) (xy 122.16541 -272.147032) (xy 122.114115 -272.155157)
			(xy 122.062181 -272.155157) (xy 122.010886 -272.147032) (xy 121.961493 -272.130984) (xy 121.915219 -272.107406)
			(xy 121.873203 -272.07688) (xy 121.83648 -272.040157) (xy 121.805954 -271.998141) (xy 121.782376 -271.951867)
			(xy 121.766328 -271.902474) (xy 121.758203 -271.851179) (xy 121.478293 -271.851179) (xy 121.470168 -271.902474)
			(xy 121.45412 -271.951867) (xy 121.430542 -271.998141) (xy 121.400016 -272.040157) (xy 121.363293 -272.07688)
			(xy 121.321277 -272.107406) (xy 121.275003 -272.130984) (xy 121.22561 -272.147032) (xy 121.174315 -272.155157)
			(xy 121.122381 -272.155157) (xy 121.071086 -272.147032) (xy 121.021693 -272.130984) (xy 120.975419 -272.107406)
			(xy 120.933403 -272.07688) (xy 120.89668 -272.040157) (xy 120.866154 -271.998141) (xy 120.842576 -271.951867)
			(xy 120.826528 -271.902474) (xy 120.818403 -271.851179) (xy 120.538493 -271.851179) (xy 120.530368 -271.902474)
			(xy 120.51432 -271.951867) (xy 120.490742 -271.998141) (xy 120.460216 -272.040157) (xy 120.423493 -272.07688)
			(xy 120.381477 -272.107406) (xy 120.335203 -272.130984) (xy 120.28581 -272.147032) (xy 120.234515 -272.155157)
			(xy 120.182581 -272.155157) (xy 120.131286 -272.147032) (xy 120.081893 -272.130984) (xy 120.035619 -272.107406)
			(xy 119.993603 -272.07688) (xy 119.95688 -272.040157) (xy 119.926354 -271.998141) (xy 119.902776 -271.951867)
			(xy 119.886728 -271.902474) (xy 119.878603 -271.851179) (xy 119.598185 -271.851179) (xy 119.59006 -271.902474)
			(xy 119.574012 -271.951867) (xy 119.550434 -271.998141) (xy 119.519908 -272.040157) (xy 119.483185 -272.07688)
			(xy 119.441169 -272.107406) (xy 119.394895 -272.130984) (xy 119.345502 -272.147032) (xy 119.294207 -272.155157)
			(xy 119.242273 -272.155157) (xy 119.190978 -272.147032) (xy 119.141585 -272.130984) (xy 119.095311 -272.107406)
			(xy 119.053295 -272.07688) (xy 119.016572 -272.040157) (xy 118.986046 -271.998141) (xy 118.962468 -271.951867)
			(xy 118.94642 -271.902474) (xy 118.938295 -271.851179) (xy 118.658385 -271.851179) (xy 118.65026 -271.902474)
			(xy 118.634212 -271.951867) (xy 118.610634 -271.998141) (xy 118.580108 -272.040157) (xy 118.543385 -272.07688)
			(xy 118.501369 -272.107406) (xy 118.455095 -272.130984) (xy 118.405702 -272.147032) (xy 118.354407 -272.155157)
			(xy 118.302473 -272.155157) (xy 118.251178 -272.147032) (xy 118.201785 -272.130984) (xy 118.155511 -272.107406)
			(xy 118.113495 -272.07688) (xy 118.076772 -272.040157) (xy 118.046246 -271.998141) (xy 118.022668 -271.951867)
			(xy 118.00662 -271.902474) (xy 117.998495 -271.851179) (xy 117.719093 -271.851179) (xy 117.710968 -271.902474)
			(xy 117.69492 -271.951867) (xy 117.671342 -271.998141) (xy 117.640816 -272.040157) (xy 117.604093 -272.07688)
			(xy 117.562077 -272.107406) (xy 117.515803 -272.130984) (xy 117.46641 -272.147032) (xy 117.415115 -272.155157)
			(xy 117.363181 -272.155157) (xy 117.311886 -272.147032) (xy 117.262493 -272.130984) (xy 117.216219 -272.107406)
			(xy 117.174203 -272.07688) (xy 117.13748 -272.040157) (xy 117.106954 -271.998141) (xy 117.083376 -271.951867)
			(xy 117.067328 -271.902474) (xy 117.059203 -271.851179) (xy 116.778785 -271.851179) (xy 116.77066 -271.902474)
			(xy 116.754612 -271.951867) (xy 116.731034 -271.998141) (xy 116.700508 -272.040157) (xy 116.663785 -272.07688)
			(xy 116.621769 -272.107406) (xy 116.575495 -272.130984) (xy 116.526102 -272.147032) (xy 116.474807 -272.155157)
			(xy 116.422873 -272.155157) (xy 116.371578 -272.147032) (xy 116.322185 -272.130984) (xy 116.275911 -272.107406)
			(xy 116.233895 -272.07688) (xy 116.197172 -272.040157) (xy 116.166646 -271.998141) (xy 116.143068 -271.951867)
			(xy 116.12702 -271.902474) (xy 116.118895 -271.851179) (xy 115.839493 -271.851179) (xy 115.831368 -271.902474)
			(xy 115.81532 -271.951867) (xy 115.791742 -271.998141) (xy 115.761216 -272.040157) (xy 115.724493 -272.07688)
			(xy 115.682477 -272.107406) (xy 115.636203 -272.130984) (xy 115.58681 -272.147032) (xy 115.535515 -272.155157)
			(xy 115.483581 -272.155157) (xy 115.432286 -272.147032) (xy 115.382893 -272.130984) (xy 115.336619 -272.107406)
			(xy 115.294603 -272.07688) (xy 115.25788 -272.040157) (xy 115.227354 -271.998141) (xy 115.203776 -271.951867)
			(xy 115.187728 -271.902474) (xy 115.179603 -271.851179) (xy 114.899693 -271.851179) (xy 114.891568 -271.902474)
			(xy 114.87552 -271.951867) (xy 114.851942 -271.998141) (xy 114.821416 -272.040157) (xy 114.784693 -272.07688)
			(xy 114.742677 -272.107406) (xy 114.696403 -272.130984) (xy 114.64701 -272.147032) (xy 114.595715 -272.155157)
			(xy 114.543781 -272.155157) (xy 114.492486 -272.147032) (xy 114.443093 -272.130984) (xy 114.396819 -272.107406)
			(xy 114.354803 -272.07688) (xy 114.31808 -272.040157) (xy 114.287554 -271.998141) (xy 114.263976 -271.951867)
			(xy 114.247928 -271.902474) (xy 114.239803 -271.851179) (xy 113.959639 -271.851179) (xy 113.951514 -271.902474)
			(xy 113.935466 -271.951867) (xy 113.911888 -271.998141) (xy 113.881362 -272.040157) (xy 113.844639 -272.07688)
			(xy 113.802623 -272.107406) (xy 113.756349 -272.130984) (xy 113.706956 -272.147032) (xy 113.655661 -272.155157)
			(xy 113.603727 -272.155157) (xy 113.552432 -272.147032) (xy 113.503039 -272.130984) (xy 113.456765 -272.107406)
			(xy 113.414749 -272.07688) (xy 113.378026 -272.040157) (xy 113.3475 -271.998141) (xy 113.323922 -271.951867)
			(xy 113.307874 -271.902474) (xy 113.299749 -271.851179) (xy 113.019839 -271.851179) (xy 113.011714 -271.902474)
			(xy 112.995666 -271.951867) (xy 112.972088 -271.998141) (xy 112.941562 -272.040157) (xy 112.904839 -272.07688)
			(xy 112.862823 -272.107406) (xy 112.816549 -272.130984) (xy 112.767156 -272.147032) (xy 112.715861 -272.155157)
			(xy 112.663927 -272.155157) (xy 112.612632 -272.147032) (xy 112.563239 -272.130984) (xy 112.516965 -272.107406)
			(xy 112.474949 -272.07688) (xy 112.438226 -272.040157) (xy 112.4077 -271.998141) (xy 112.384122 -271.951867)
			(xy 112.368074 -271.902474) (xy 112.359949 -271.851179) (xy 112.080039 -271.851179) (xy 112.071914 -271.902474)
			(xy 112.055866 -271.951867) (xy 112.032288 -271.998141) (xy 112.001762 -272.040157) (xy 111.965039 -272.07688)
			(xy 111.923023 -272.107406) (xy 111.876749 -272.130984) (xy 111.827356 -272.147032) (xy 111.776061 -272.155157)
			(xy 111.724127 -272.155157) (xy 111.672832 -272.147032) (xy 111.623439 -272.130984) (xy 111.577165 -272.107406)
			(xy 111.535149 -272.07688) (xy 111.498426 -272.040157) (xy 111.4679 -271.998141) (xy 111.444322 -271.951867)
			(xy 111.428274 -271.902474) (xy 111.420149 -271.851179) (xy 111.140493 -271.851179) (xy 111.132368 -271.902474)
			(xy 111.11632 -271.951867) (xy 111.092742 -271.998141) (xy 111.062216 -272.040157) (xy 111.025493 -272.07688)
			(xy 110.983477 -272.107406) (xy 110.937203 -272.130984) (xy 110.88781 -272.147032) (xy 110.836515 -272.155157)
			(xy 110.784581 -272.155157) (xy 110.733286 -272.147032) (xy 110.683893 -272.130984) (xy 110.637619 -272.107406)
			(xy 110.595603 -272.07688) (xy 110.55888 -272.040157) (xy 110.528354 -271.998141) (xy 110.504776 -271.951867)
			(xy 110.488728 -271.902474) (xy 110.480603 -271.851179) (xy 110.200185 -271.851179) (xy 110.19206 -271.902474)
			(xy 110.176012 -271.951867) (xy 110.152434 -271.998141) (xy 110.121908 -272.040157) (xy 110.085185 -272.07688)
			(xy 110.043169 -272.107406) (xy 109.996895 -272.130984) (xy 109.947502 -272.147032) (xy 109.896207 -272.155157)
			(xy 109.844273 -272.155157) (xy 109.792978 -272.147032) (xy 109.743585 -272.130984) (xy 109.697311 -272.107406)
			(xy 109.655295 -272.07688) (xy 109.618572 -272.040157) (xy 109.588046 -271.998141) (xy 109.564468 -271.951867)
			(xy 109.54842 -271.902474) (xy 109.540295 -271.851179) (xy 109.260893 -271.851179) (xy 109.252768 -271.902474)
			(xy 109.23672 -271.951867) (xy 109.213142 -271.998141) (xy 109.182616 -272.040157) (xy 109.145893 -272.07688)
			(xy 109.103877 -272.107406) (xy 109.057603 -272.130984) (xy 109.00821 -272.147032) (xy 108.956915 -272.155157)
			(xy 108.904981 -272.155157) (xy 108.853686 -272.147032) (xy 108.804293 -272.130984) (xy 108.758019 -272.107406)
			(xy 108.716003 -272.07688) (xy 108.67928 -272.040157) (xy 108.648754 -271.998141) (xy 108.625176 -271.951867)
			(xy 108.609128 -271.902474) (xy 108.601003 -271.851179) (xy 108.321093 -271.851179) (xy 108.312968 -271.902474)
			(xy 108.29692 -271.951867) (xy 108.273342 -271.998141) (xy 108.242816 -272.040157) (xy 108.206093 -272.07688)
			(xy 108.164077 -272.107406) (xy 108.117803 -272.130984) (xy 108.06841 -272.147032) (xy 108.017115 -272.155157)
			(xy 107.965181 -272.155157) (xy 107.913886 -272.147032) (xy 107.864493 -272.130984) (xy 107.818219 -272.107406)
			(xy 107.776203 -272.07688) (xy 107.73948 -272.040157) (xy 107.708954 -271.998141) (xy 107.685376 -271.951867)
			(xy 107.669328 -271.902474) (xy 107.661203 -271.851179) (xy 107.381293 -271.851179) (xy 107.373168 -271.902474)
			(xy 107.35712 -271.951867) (xy 107.333542 -271.998141) (xy 107.303016 -272.040157) (xy 107.266293 -272.07688)
			(xy 107.224277 -272.107406) (xy 107.178003 -272.130984) (xy 107.12861 -272.147032) (xy 107.077315 -272.155157)
			(xy 107.025381 -272.155157) (xy 106.974086 -272.147032) (xy 106.924693 -272.130984) (xy 106.878419 -272.107406)
			(xy 106.836403 -272.07688) (xy 106.79968 -272.040157) (xy 106.769154 -271.998141) (xy 106.745576 -271.951867)
			(xy 106.729528 -271.902474) (xy 106.721403 -271.851179) (xy 106.441493 -271.851179) (xy 106.433368 -271.902474)
			(xy 106.41732 -271.951867) (xy 106.393742 -271.998141) (xy 106.363216 -272.040157) (xy 106.326493 -272.07688)
			(xy 106.284477 -272.107406) (xy 106.238203 -272.130984) (xy 106.18881 -272.147032) (xy 106.137515 -272.155157)
			(xy 106.085581 -272.155157) (xy 106.034286 -272.147032) (xy 105.984893 -272.130984) (xy 105.938619 -272.107406)
			(xy 105.896603 -272.07688) (xy 105.85988 -272.040157) (xy 105.829354 -271.998141) (xy 105.805776 -271.951867)
			(xy 105.789728 -271.902474) (xy 105.781603 -271.851179) (xy 105.501693 -271.851179) (xy 105.493568 -271.902474)
			(xy 105.47752 -271.951867) (xy 105.453942 -271.998141) (xy 105.423416 -272.040157) (xy 105.386693 -272.07688)
			(xy 105.344677 -272.107406) (xy 105.298403 -272.130984) (xy 105.24901 -272.147032) (xy 105.197715 -272.155157)
			(xy 105.145781 -272.155157) (xy 105.094486 -272.147032) (xy 105.045093 -272.130984) (xy 104.998819 -272.107406)
			(xy 104.956803 -272.07688) (xy 104.92008 -272.040157) (xy 104.889554 -271.998141) (xy 104.865976 -271.951867)
			(xy 104.849928 -271.902474) (xy 104.841803 -271.851179) (xy 104.561893 -271.851179) (xy 104.553768 -271.902474)
			(xy 104.53772 -271.951867) (xy 104.514142 -271.998141) (xy 104.483616 -272.040157) (xy 104.446893 -272.07688)
			(xy 104.404877 -272.107406) (xy 104.358603 -272.130984) (xy 104.30921 -272.147032) (xy 104.257915 -272.155157)
			(xy 104.205981 -272.155157) (xy 104.154686 -272.147032) (xy 104.105293 -272.130984) (xy 104.059019 -272.107406)
			(xy 104.017003 -272.07688) (xy 103.98028 -272.040157) (xy 103.949754 -271.998141) (xy 103.926176 -271.951867)
			(xy 103.910128 -271.902474) (xy 103.902003 -271.851179) (xy 103.622093 -271.851179) (xy 103.613968 -271.902474)
			(xy 103.59792 -271.951867) (xy 103.574342 -271.998141) (xy 103.543816 -272.040157) (xy 103.507093 -272.07688)
			(xy 103.465077 -272.107406) (xy 103.418803 -272.130984) (xy 103.36941 -272.147032) (xy 103.318115 -272.155157)
			(xy 103.266181 -272.155157) (xy 103.214886 -272.147032) (xy 103.165493 -272.130984) (xy 103.119219 -272.107406)
			(xy 103.077203 -272.07688) (xy 103.04048 -272.040157) (xy 103.009954 -271.998141) (xy 102.986376 -271.951867)
			(xy 102.970328 -271.902474) (xy 102.962203 -271.851179) (xy 102.682293 -271.851179) (xy 102.674168 -271.902474)
			(xy 102.65812 -271.951867) (xy 102.634542 -271.998141) (xy 102.604016 -272.040157) (xy 102.567293 -272.07688)
			(xy 102.525277 -272.107406) (xy 102.479003 -272.130984) (xy 102.42961 -272.147032) (xy 102.378315 -272.155157)
			(xy 102.326381 -272.155157) (xy 102.275086 -272.147032) (xy 102.225693 -272.130984) (xy 102.179419 -272.107406)
			(xy 102.137403 -272.07688) (xy 102.10068 -272.040157) (xy 102.070154 -271.998141) (xy 102.046576 -271.951867)
			(xy 102.030528 -271.902474) (xy 102.022403 -271.851179) (xy 101.742493 -271.851179) (xy 101.734368 -271.902474)
			(xy 101.71832 -271.951867) (xy 101.694742 -271.998141) (xy 101.664216 -272.040157) (xy 101.627493 -272.07688)
			(xy 101.585477 -272.107406) (xy 101.539203 -272.130984) (xy 101.48981 -272.147032) (xy 101.438515 -272.155157)
			(xy 101.386581 -272.155157) (xy 101.335286 -272.147032) (xy 101.285893 -272.130984) (xy 101.239619 -272.107406)
			(xy 101.197603 -272.07688) (xy 101.16088 -272.040157) (xy 101.130354 -271.998141) (xy 101.106776 -271.951867)
			(xy 101.090728 -271.902474) (xy 101.082603 -271.851179) (xy 100.802693 -271.851179) (xy 100.794568 -271.902474)
			(xy 100.77852 -271.951867) (xy 100.754942 -271.998141) (xy 100.724416 -272.040157) (xy 100.687693 -272.07688)
			(xy 100.645677 -272.107406) (xy 100.599403 -272.130984) (xy 100.55001 -272.147032) (xy 100.498715 -272.155157)
			(xy 100.446781 -272.155157) (xy 100.395486 -272.147032) (xy 100.346093 -272.130984) (xy 100.299819 -272.107406)
			(xy 100.257803 -272.07688) (xy 100.22108 -272.040157) (xy 100.190554 -271.998141) (xy 100.166976 -271.951867)
			(xy 100.150928 -271.902474) (xy 100.142803 -271.851179) (xy 99.862893 -271.851179) (xy 99.854768 -271.902474)
			(xy 99.83872 -271.951867) (xy 99.815142 -271.998141) (xy 99.784616 -272.040157) (xy 99.747893 -272.07688)
			(xy 99.705877 -272.107406) (xy 99.659603 -272.130984) (xy 99.61021 -272.147032) (xy 99.558915 -272.155157)
			(xy 99.506981 -272.155157) (xy 99.455686 -272.147032) (xy 99.406293 -272.130984) (xy 99.360019 -272.107406)
			(xy 99.318003 -272.07688) (xy 99.28128 -272.040157) (xy 99.250754 -271.998141) (xy 99.227176 -271.951867)
			(xy 99.211128 -271.902474) (xy 99.203003 -271.851179) (xy 98.923093 -271.851179) (xy 98.914968 -271.902474)
			(xy 98.89892 -271.951867) (xy 98.875342 -271.998141) (xy 98.844816 -272.040157) (xy 98.808093 -272.07688)
			(xy 98.766077 -272.107406) (xy 98.719803 -272.130984) (xy 98.67041 -272.147032) (xy 98.619115 -272.155157)
			(xy 98.567181 -272.155157) (xy 98.515886 -272.147032) (xy 98.466493 -272.130984) (xy 98.420219 -272.107406)
			(xy 98.378203 -272.07688) (xy 98.34148 -272.040157) (xy 98.310954 -271.998141) (xy 98.287376 -271.951867)
			(xy 98.271328 -271.902474) (xy 98.263203 -271.851179) (xy 97.983039 -271.851179) (xy 97.974914 -271.902474)
			(xy 97.958866 -271.951867) (xy 97.935288 -271.998141) (xy 97.904762 -272.040157) (xy 97.868039 -272.07688)
			(xy 97.826023 -272.107406) (xy 97.779749 -272.130984) (xy 97.730356 -272.147032) (xy 97.679061 -272.155157)
			(xy 97.627127 -272.155157) (xy 97.575832 -272.147032) (xy 97.526439 -272.130984) (xy 97.480165 -272.107406)
			(xy 97.438149 -272.07688) (xy 97.401426 -272.040157) (xy 97.3709 -271.998141) (xy 97.347322 -271.951867)
			(xy 97.331274 -271.902474) (xy 97.323149 -271.851179) (xy 97.043493 -271.851179) (xy 97.035368 -271.902474)
			(xy 97.01932 -271.951867) (xy 96.995742 -271.998141) (xy 96.965216 -272.040157) (xy 96.928493 -272.07688)
			(xy 96.886477 -272.107406) (xy 96.840203 -272.130984) (xy 96.79081 -272.147032) (xy 96.739515 -272.155157)
			(xy 96.687581 -272.155157) (xy 96.636286 -272.147032) (xy 96.586893 -272.130984) (xy 96.540619 -272.107406)
			(xy 96.498603 -272.07688) (xy 96.46188 -272.040157) (xy 96.431354 -271.998141) (xy 96.407776 -271.951867)
			(xy 96.391728 -271.902474) (xy 96.383603 -271.851179) (xy 96.103693 -271.851179) (xy 96.095568 -271.902474)
			(xy 96.07952 -271.951867) (xy 96.055942 -271.998141) (xy 96.025416 -272.040157) (xy 95.988693 -272.07688)
			(xy 95.946677 -272.107406) (xy 95.900403 -272.130984) (xy 95.85101 -272.147032) (xy 95.799715 -272.155157)
			(xy 95.747781 -272.155157) (xy 95.696486 -272.147032) (xy 95.647093 -272.130984) (xy 95.600819 -272.107406)
			(xy 95.558803 -272.07688) (xy 95.52208 -272.040157) (xy 95.491554 -271.998141) (xy 95.467976 -271.951867)
			(xy 95.451928 -271.902474) (xy 95.443803 -271.851179) (xy 95.163893 -271.851179) (xy 95.155768 -271.902474)
			(xy 95.13972 -271.951867) (xy 95.116142 -271.998141) (xy 95.085616 -272.040157) (xy 95.048893 -272.07688)
			(xy 95.006877 -272.107406) (xy 94.960603 -272.130984) (xy 94.91121 -272.147032) (xy 94.859915 -272.155157)
			(xy 94.807981 -272.155157) (xy 94.756686 -272.147032) (xy 94.707293 -272.130984) (xy 94.661019 -272.107406)
			(xy 94.619003 -272.07688) (xy 94.58228 -272.040157) (xy 94.551754 -271.998141) (xy 94.528176 -271.951867)
			(xy 94.512128 -271.902474) (xy 94.504003 -271.851179) (xy 94.224093 -271.851179) (xy 94.215968 -271.902474)
			(xy 94.19992 -271.951867) (xy 94.176342 -271.998141) (xy 94.145816 -272.040157) (xy 94.109093 -272.07688)
			(xy 94.067077 -272.107406) (xy 94.020803 -272.130984) (xy 93.97141 -272.147032) (xy 93.920115 -272.155157)
			(xy 93.868181 -272.155157) (xy 93.816886 -272.147032) (xy 93.767493 -272.130984) (xy 93.721219 -272.107406)
			(xy 93.679203 -272.07688) (xy 93.64248 -272.040157) (xy 93.611954 -271.998141) (xy 93.588376 -271.951867)
			(xy 93.572328 -271.902474) (xy 93.564203 -271.851179) (xy 93.284293 -271.851179) (xy 93.276168 -271.902474)
			(xy 93.26012 -271.951867) (xy 93.236542 -271.998141) (xy 93.206016 -272.040157) (xy 93.169293 -272.07688)
			(xy 93.127277 -272.107406) (xy 93.081003 -272.130984) (xy 93.03161 -272.147032) (xy 92.980315 -272.155157)
			(xy 92.928381 -272.155157) (xy 92.877086 -272.147032) (xy 92.827693 -272.130984) (xy 92.781419 -272.107406)
			(xy 92.739403 -272.07688) (xy 92.70268 -272.040157) (xy 92.672154 -271.998141) (xy 92.648576 -271.951867)
			(xy 92.632528 -271.902474) (xy 92.624403 -271.851179) (xy 92.344687 -271.851179) (xy 92.344687 -271.851184)
			(xy 92.336558 -271.902512) (xy 92.3205 -271.951937) (xy 92.29691 -271.998241) (xy 92.266366 -272.040286)
			(xy 92.229622 -272.077035) (xy 92.187582 -272.107584) (xy 92.141281 -272.131182) (xy 92.091859 -272.147247)
			(xy 92.040532 -272.155383) (xy 92.014548 -272.15592) (xy 91.991674 -272.155537) (xy 91.946361 -272.149242)
			(xy 91.902347 -272.136765) (xy 91.860471 -272.118344) (xy 91.840812 -272.106644) (xy 91.840558 -272.10639)
			(xy 91.833071 -272.102205) (xy 91.816298 -272.098672) (xy 91.799315 -272.100994) (xy 91.791536 -272.104612)
			(xy 91.751658 -272.12671) (xy 91.713304 -272.148046) (xy 91.705714 -272.152683) (xy 91.694147 -272.16618)
			(xy 91.68797 -272.182847) (xy 91.68765 -272.191734) (xy 91.68765 -272.311368) (xy 91.712034 -272.353786)
			(xy 91.718638 -272.358104) (xy 91.740364 -272.372154) (xy 91.779563 -272.405918) (xy 91.813028 -272.445373)
			(xy 91.839943 -272.489557) (xy 91.859652 -272.537392) (xy 91.871673 -272.587712) (xy 91.875714 -272.639291)
			(xy 91.873682 -272.665249) (xy 92.154249 -272.665249) (xy 92.154249 -272.613315) (xy 92.162374 -272.56202)
			(xy 92.178422 -272.512627) (xy 92.202 -272.466353) (xy 92.232526 -272.424337) (xy 92.269249 -272.387614)
			(xy 92.311265 -272.357088) (xy 92.357539 -272.33351) (xy 92.406932 -272.317462) (xy 92.458227 -272.309337)
			(xy 92.510161 -272.309337) (xy 92.561456 -272.317462) (xy 92.610849 -272.33351) (xy 92.657123 -272.357088)
			(xy 92.699139 -272.387614) (xy 92.735862 -272.424337) (xy 92.766388 -272.466353) (xy 92.789966 -272.512627)
			(xy 92.806014 -272.56202) (xy 92.814139 -272.613315) (xy 92.814648 -272.639282) (xy 92.814139 -272.665249)
			(xy 93.094049 -272.665249) (xy 93.094049 -272.613315) (xy 93.102174 -272.56202) (xy 93.118222 -272.512627)
			(xy 93.1418 -272.466353) (xy 93.172326 -272.424337) (xy 93.209049 -272.387614) (xy 93.251065 -272.357088)
			(xy 93.297339 -272.33351) (xy 93.346732 -272.317462) (xy 93.398027 -272.309337) (xy 93.449961 -272.309337)
			(xy 93.501256 -272.317462) (xy 93.550649 -272.33351) (xy 93.596923 -272.357088) (xy 93.638939 -272.387614)
			(xy 93.675662 -272.424337) (xy 93.706188 -272.466353) (xy 93.729766 -272.512627) (xy 93.745814 -272.56202)
			(xy 93.753939 -272.613315) (xy 93.754448 -272.639282) (xy 93.753939 -272.665249) (xy 94.033849 -272.665249)
			(xy 94.033849 -272.613315) (xy 94.041974 -272.56202) (xy 94.058022 -272.512627) (xy 94.0816 -272.466353)
			(xy 94.112126 -272.424337) (xy 94.148849 -272.387614) (xy 94.190865 -272.357088) (xy 94.237139 -272.33351)
			(xy 94.286532 -272.317462) (xy 94.337827 -272.309337) (xy 94.389761 -272.309337) (xy 94.441056 -272.317462)
			(xy 94.490449 -272.33351) (xy 94.536723 -272.357088) (xy 94.578739 -272.387614) (xy 94.615462 -272.424337)
			(xy 94.645988 -272.466353) (xy 94.669566 -272.512627) (xy 94.685614 -272.56202) (xy 94.693739 -272.613315)
			(xy 94.694248 -272.639282) (xy 94.693739 -272.665249) (xy 94.973649 -272.665249) (xy 94.973649 -272.613315)
			(xy 94.981774 -272.56202) (xy 94.997822 -272.512627) (xy 95.0214 -272.466353) (xy 95.051926 -272.424337)
			(xy 95.088649 -272.387614) (xy 95.130665 -272.357088) (xy 95.176939 -272.33351) (xy 95.226332 -272.317462)
			(xy 95.277627 -272.309337) (xy 95.329561 -272.309337) (xy 95.380856 -272.317462) (xy 95.430249 -272.33351)
			(xy 95.476523 -272.357088) (xy 95.518539 -272.387614) (xy 95.555262 -272.424337) (xy 95.585788 -272.466353)
			(xy 95.609366 -272.512627) (xy 95.625414 -272.56202) (xy 95.633539 -272.613315) (xy 95.634048 -272.639282)
			(xy 95.633539 -272.665249) (xy 95.913449 -272.665249) (xy 95.913449 -272.613315) (xy 95.921574 -272.56202)
			(xy 95.937622 -272.512627) (xy 95.9612 -272.466353) (xy 95.991726 -272.424337) (xy 96.028449 -272.387614)
			(xy 96.070465 -272.357088) (xy 96.116739 -272.33351) (xy 96.166132 -272.317462) (xy 96.217427 -272.309337)
			(xy 96.269361 -272.309337) (xy 96.320656 -272.317462) (xy 96.370049 -272.33351) (xy 96.416323 -272.357088)
			(xy 96.458339 -272.387614) (xy 96.495062 -272.424337) (xy 96.525588 -272.466353) (xy 96.549166 -272.512627)
			(xy 96.565214 -272.56202) (xy 96.573339 -272.613315) (xy 96.573848 -272.639282) (xy 96.573339 -272.665249)
			(xy 96.853503 -272.665249) (xy 96.853503 -272.613315) (xy 96.861628 -272.56202) (xy 96.877676 -272.512627)
			(xy 96.901254 -272.466353) (xy 96.93178 -272.424337) (xy 96.968503 -272.387614) (xy 97.010519 -272.357088)
			(xy 97.056793 -272.33351) (xy 97.106186 -272.317462) (xy 97.157481 -272.309337) (xy 97.209415 -272.309337)
			(xy 97.26071 -272.317462) (xy 97.310103 -272.33351) (xy 97.356377 -272.357088) (xy 97.398393 -272.387614)
			(xy 97.435116 -272.424337) (xy 97.465642 -272.466353) (xy 97.48922 -272.512627) (xy 97.505268 -272.56202)
			(xy 97.513393 -272.613315) (xy 97.513902 -272.639282) (xy 97.513393 -272.665249) (xy 97.793049 -272.665249)
			(xy 97.793049 -272.613315) (xy 97.801174 -272.56202) (xy 97.817222 -272.512627) (xy 97.8408 -272.466353)
			(xy 97.871326 -272.424337) (xy 97.908049 -272.387614) (xy 97.950065 -272.357088) (xy 97.996339 -272.33351)
			(xy 98.045732 -272.317462) (xy 98.097027 -272.309337) (xy 98.148961 -272.309337) (xy 98.200256 -272.317462)
			(xy 98.249649 -272.33351) (xy 98.295923 -272.357088) (xy 98.337939 -272.387614) (xy 98.374662 -272.424337)
			(xy 98.405188 -272.466353) (xy 98.428766 -272.512627) (xy 98.444814 -272.56202) (xy 98.452939 -272.613315)
			(xy 98.453448 -272.639282) (xy 98.452939 -272.665249) (xy 98.732849 -272.665249) (xy 98.732849 -272.613315)
			(xy 98.740974 -272.56202) (xy 98.757022 -272.512627) (xy 98.7806 -272.466353) (xy 98.811126 -272.424337)
			(xy 98.847849 -272.387614) (xy 98.889865 -272.357088) (xy 98.936139 -272.33351) (xy 98.985532 -272.317462)
			(xy 99.036827 -272.309337) (xy 99.088761 -272.309337) (xy 99.140056 -272.317462) (xy 99.189449 -272.33351)
			(xy 99.235723 -272.357088) (xy 99.277739 -272.387614) (xy 99.314462 -272.424337) (xy 99.344988 -272.466353)
			(xy 99.368566 -272.512627) (xy 99.384614 -272.56202) (xy 99.392739 -272.613315) (xy 99.393248 -272.639282)
			(xy 99.392739 -272.665249) (xy 99.672649 -272.665249) (xy 99.672649 -272.613315) (xy 99.680774 -272.56202)
			(xy 99.696822 -272.512627) (xy 99.7204 -272.466353) (xy 99.750926 -272.424337) (xy 99.787649 -272.387614)
			(xy 99.829665 -272.357088) (xy 99.875939 -272.33351) (xy 99.925332 -272.317462) (xy 99.976627 -272.309337)
			(xy 100.028561 -272.309337) (xy 100.079856 -272.317462) (xy 100.129249 -272.33351) (xy 100.175523 -272.357088)
			(xy 100.217539 -272.387614) (xy 100.254262 -272.424337) (xy 100.284788 -272.466353) (xy 100.308366 -272.512627)
			(xy 100.324414 -272.56202) (xy 100.332539 -272.613315) (xy 100.333048 -272.639282) (xy 100.332539 -272.665249)
			(xy 100.612449 -272.665249) (xy 100.612449 -272.613315) (xy 100.620574 -272.56202) (xy 100.636622 -272.512627)
			(xy 100.6602 -272.466353) (xy 100.690726 -272.424337) (xy 100.727449 -272.387614) (xy 100.769465 -272.357088)
			(xy 100.815739 -272.33351) (xy 100.865132 -272.317462) (xy 100.916427 -272.309337) (xy 100.968361 -272.309337)
			(xy 101.019656 -272.317462) (xy 101.069049 -272.33351) (xy 101.115323 -272.357088) (xy 101.157339 -272.387614)
			(xy 101.194062 -272.424337) (xy 101.224588 -272.466353) (xy 101.248166 -272.512627) (xy 101.264214 -272.56202)
			(xy 101.272339 -272.613315) (xy 101.272848 -272.639282) (xy 101.272339 -272.665249) (xy 101.552249 -272.665249)
			(xy 101.552249 -272.613315) (xy 101.560374 -272.56202) (xy 101.576422 -272.512627) (xy 101.6 -272.466353)
			(xy 101.630526 -272.424337) (xy 101.667249 -272.387614) (xy 101.709265 -272.357088) (xy 101.755539 -272.33351)
			(xy 101.804932 -272.317462) (xy 101.856227 -272.309337) (xy 101.908161 -272.309337) (xy 101.959456 -272.317462)
			(xy 102.008849 -272.33351) (xy 102.055123 -272.357088) (xy 102.097139 -272.387614) (xy 102.133862 -272.424337)
			(xy 102.164388 -272.466353) (xy 102.187966 -272.512627) (xy 102.204014 -272.56202) (xy 102.212139 -272.613315)
			(xy 102.212648 -272.639282) (xy 102.212139 -272.665249) (xy 102.492049 -272.665249) (xy 102.492049 -272.613315)
			(xy 102.500174 -272.56202) (xy 102.516222 -272.512627) (xy 102.5398 -272.466353) (xy 102.570326 -272.424337)
			(xy 102.607049 -272.387614) (xy 102.649065 -272.357088) (xy 102.695339 -272.33351) (xy 102.744732 -272.317462)
			(xy 102.796027 -272.309337) (xy 102.847961 -272.309337) (xy 102.899256 -272.317462) (xy 102.948649 -272.33351)
			(xy 102.994923 -272.357088) (xy 103.036939 -272.387614) (xy 103.073662 -272.424337) (xy 103.104188 -272.466353)
			(xy 103.127766 -272.512627) (xy 103.143814 -272.56202) (xy 103.151939 -272.613315) (xy 103.152448 -272.639282)
			(xy 103.151939 -272.665249) (xy 103.431849 -272.665249) (xy 103.431849 -272.613315) (xy 103.439974 -272.56202)
			(xy 103.456022 -272.512627) (xy 103.4796 -272.466353) (xy 103.510126 -272.424337) (xy 103.546849 -272.387614)
			(xy 103.588865 -272.357088) (xy 103.635139 -272.33351) (xy 103.684532 -272.317462) (xy 103.735827 -272.309337)
			(xy 103.787761 -272.309337) (xy 103.839056 -272.317462) (xy 103.888449 -272.33351) (xy 103.934723 -272.357088)
			(xy 103.976739 -272.387614) (xy 104.013462 -272.424337) (xy 104.043988 -272.466353) (xy 104.067566 -272.512627)
			(xy 104.083614 -272.56202) (xy 104.091739 -272.613315) (xy 104.092248 -272.639282) (xy 104.091739 -272.665249)
			(xy 104.371649 -272.665249) (xy 104.371649 -272.613315) (xy 104.379774 -272.56202) (xy 104.395822 -272.512627)
			(xy 104.4194 -272.466353) (xy 104.449926 -272.424337) (xy 104.486649 -272.387614) (xy 104.528665 -272.357088)
			(xy 104.574939 -272.33351) (xy 104.624332 -272.317462) (xy 104.675627 -272.309337) (xy 104.727561 -272.309337)
			(xy 104.778856 -272.317462) (xy 104.828249 -272.33351) (xy 104.874523 -272.357088) (xy 104.916539 -272.387614)
			(xy 104.953262 -272.424337) (xy 104.983788 -272.466353) (xy 105.007366 -272.512627) (xy 105.023414 -272.56202)
			(xy 105.031539 -272.613315) (xy 105.032048 -272.639282) (xy 105.031539 -272.665249) (xy 105.311449 -272.665249)
			(xy 105.311449 -272.613315) (xy 105.319574 -272.56202) (xy 105.335622 -272.512627) (xy 105.3592 -272.466353)
			(xy 105.389726 -272.424337) (xy 105.426449 -272.387614) (xy 105.468465 -272.357088) (xy 105.514739 -272.33351)
			(xy 105.564132 -272.317462) (xy 105.615427 -272.309337) (xy 105.667361 -272.309337) (xy 105.718656 -272.317462)
			(xy 105.768049 -272.33351) (xy 105.814323 -272.357088) (xy 105.856339 -272.387614) (xy 105.893062 -272.424337)
			(xy 105.923588 -272.466353) (xy 105.947166 -272.512627) (xy 105.963214 -272.56202) (xy 105.971339 -272.613315)
			(xy 105.971848 -272.639282) (xy 105.971339 -272.665249) (xy 106.251249 -272.665249) (xy 106.251249 -272.613315)
			(xy 106.259374 -272.56202) (xy 106.275422 -272.512627) (xy 106.299 -272.466353) (xy 106.329526 -272.424337)
			(xy 106.366249 -272.387614) (xy 106.408265 -272.357088) (xy 106.454539 -272.33351) (xy 106.503932 -272.317462)
			(xy 106.555227 -272.309337) (xy 106.607161 -272.309337) (xy 106.658456 -272.317462) (xy 106.707849 -272.33351)
			(xy 106.754123 -272.357088) (xy 106.796139 -272.387614) (xy 106.832862 -272.424337) (xy 106.863388 -272.466353)
			(xy 106.886966 -272.512627) (xy 106.903014 -272.56202) (xy 106.911139 -272.613315) (xy 106.911648 -272.639282)
			(xy 106.911139 -272.665249) (xy 107.191049 -272.665249) (xy 107.191049 -272.613315) (xy 107.199174 -272.56202)
			(xy 107.215222 -272.512627) (xy 107.2388 -272.466353) (xy 107.269326 -272.424337) (xy 107.306049 -272.387614)
			(xy 107.348065 -272.357088) (xy 107.394339 -272.33351) (xy 107.443732 -272.317462) (xy 107.495027 -272.309337)
			(xy 107.546961 -272.309337) (xy 107.598256 -272.317462) (xy 107.647649 -272.33351) (xy 107.693923 -272.357088)
			(xy 107.735939 -272.387614) (xy 107.772662 -272.424337) (xy 107.803188 -272.466353) (xy 107.826766 -272.512627)
			(xy 107.842814 -272.56202) (xy 107.850939 -272.613315) (xy 107.851448 -272.639282) (xy 107.850939 -272.665249)
			(xy 108.130849 -272.665249) (xy 108.130849 -272.613315) (xy 108.138974 -272.56202) (xy 108.155022 -272.512627)
			(xy 108.1786 -272.466353) (xy 108.209126 -272.424337) (xy 108.245849 -272.387614) (xy 108.287865 -272.357088)
			(xy 108.334139 -272.33351) (xy 108.383532 -272.317462) (xy 108.434827 -272.309337) (xy 108.486761 -272.309337)
			(xy 108.538056 -272.317462) (xy 108.587449 -272.33351) (xy 108.633723 -272.357088) (xy 108.675739 -272.387614)
			(xy 108.712462 -272.424337) (xy 108.742988 -272.466353) (xy 108.766566 -272.512627) (xy 108.782614 -272.56202)
			(xy 108.790739 -272.613315) (xy 108.791248 -272.639282) (xy 108.790739 -272.665249) (xy 109.070649 -272.665249)
			(xy 109.070649 -272.613315) (xy 109.078774 -272.56202) (xy 109.094822 -272.512627) (xy 109.1184 -272.466353)
			(xy 109.148926 -272.424337) (xy 109.185649 -272.387614) (xy 109.227665 -272.357088) (xy 109.273939 -272.33351)
			(xy 109.323332 -272.317462) (xy 109.374627 -272.309337) (xy 109.426561 -272.309337) (xy 109.477856 -272.317462)
			(xy 109.527249 -272.33351) (xy 109.573523 -272.357088) (xy 109.615539 -272.387614) (xy 109.652262 -272.424337)
			(xy 109.682788 -272.466353) (xy 109.706366 -272.512627) (xy 109.722414 -272.56202) (xy 109.730539 -272.613315)
			(xy 109.731048 -272.639282) (xy 109.730539 -272.665249) (xy 110.010449 -272.665249) (xy 110.010449 -272.613315)
			(xy 110.018574 -272.56202) (xy 110.034622 -272.512627) (xy 110.0582 -272.466353) (xy 110.088726 -272.424337)
			(xy 110.125449 -272.387614) (xy 110.167465 -272.357088) (xy 110.213739 -272.33351) (xy 110.263132 -272.317462)
			(xy 110.314427 -272.309337) (xy 110.366361 -272.309337) (xy 110.417656 -272.317462) (xy 110.467049 -272.33351)
			(xy 110.513323 -272.357088) (xy 110.555339 -272.387614) (xy 110.592062 -272.424337) (xy 110.622588 -272.466353)
			(xy 110.646166 -272.512627) (xy 110.662214 -272.56202) (xy 110.670339 -272.613315) (xy 110.670848 -272.639282)
			(xy 110.670339 -272.665249) (xy 110.950503 -272.665249) (xy 110.950503 -272.613315) (xy 110.958628 -272.56202)
			(xy 110.974676 -272.512627) (xy 110.998254 -272.466353) (xy 111.02878 -272.424337) (xy 111.065503 -272.387614)
			(xy 111.107519 -272.357088) (xy 111.153793 -272.33351) (xy 111.203186 -272.317462) (xy 111.254481 -272.309337)
			(xy 111.306415 -272.309337) (xy 111.35771 -272.317462) (xy 111.407103 -272.33351) (xy 111.453377 -272.357088)
			(xy 111.495393 -272.387614) (xy 111.532116 -272.424337) (xy 111.562642 -272.466353) (xy 111.58622 -272.512627)
			(xy 111.602268 -272.56202) (xy 111.610393 -272.613315) (xy 111.610902 -272.639282) (xy 111.610393 -272.665249)
			(xy 111.890303 -272.665249) (xy 111.890303 -272.613315) (xy 111.898428 -272.56202) (xy 111.914476 -272.512627)
			(xy 111.938054 -272.466353) (xy 111.96858 -272.424337) (xy 112.005303 -272.387614) (xy 112.047319 -272.357088)
			(xy 112.093593 -272.33351) (xy 112.142986 -272.317462) (xy 112.194281 -272.309337) (xy 112.246215 -272.309337)
			(xy 112.29751 -272.317462) (xy 112.346903 -272.33351) (xy 112.393177 -272.357088) (xy 112.435193 -272.387614)
			(xy 112.471916 -272.424337) (xy 112.502442 -272.466353) (xy 112.52602 -272.512627) (xy 112.542068 -272.56202)
			(xy 112.550193 -272.613315) (xy 112.550702 -272.639282) (xy 112.550193 -272.665249) (xy 112.829849 -272.665249)
			(xy 112.829849 -272.613315) (xy 112.837974 -272.56202) (xy 112.854022 -272.512627) (xy 112.8776 -272.466353)
			(xy 112.908126 -272.424337) (xy 112.944849 -272.387614) (xy 112.986865 -272.357088) (xy 113.033139 -272.33351)
			(xy 113.082532 -272.317462) (xy 113.133827 -272.309337) (xy 113.185761 -272.309337) (xy 113.237056 -272.317462)
			(xy 113.286449 -272.33351) (xy 113.332723 -272.357088) (xy 113.374739 -272.387614) (xy 113.411462 -272.424337)
			(xy 113.441988 -272.466353) (xy 113.465566 -272.512627) (xy 113.481614 -272.56202) (xy 113.489739 -272.613315)
			(xy 113.490248 -272.639282) (xy 113.489739 -272.665249) (xy 113.769649 -272.665249) (xy 113.769649 -272.613315)
			(xy 113.777774 -272.56202) (xy 113.793822 -272.512627) (xy 113.8174 -272.466353) (xy 113.847926 -272.424337)
			(xy 113.884649 -272.387614) (xy 113.926665 -272.357088) (xy 113.972939 -272.33351) (xy 114.022332 -272.317462)
			(xy 114.073627 -272.309337) (xy 114.125561 -272.309337) (xy 114.176856 -272.317462) (xy 114.226249 -272.33351)
			(xy 114.272523 -272.357088) (xy 114.314539 -272.387614) (xy 114.351262 -272.424337) (xy 114.381788 -272.466353)
			(xy 114.405366 -272.512627) (xy 114.421414 -272.56202) (xy 114.429539 -272.613315) (xy 114.430048 -272.639282)
			(xy 114.429539 -272.665249) (xy 114.709449 -272.665249) (xy 114.709449 -272.613315) (xy 114.717574 -272.56202)
			(xy 114.733622 -272.512627) (xy 114.7572 -272.466353) (xy 114.787726 -272.424337) (xy 114.824449 -272.387614)
			(xy 114.866465 -272.357088) (xy 114.912739 -272.33351) (xy 114.962132 -272.317462) (xy 115.013427 -272.309337)
			(xy 115.065361 -272.309337) (xy 115.116656 -272.317462) (xy 115.166049 -272.33351) (xy 115.212323 -272.357088)
			(xy 115.254339 -272.387614) (xy 115.291062 -272.424337) (xy 115.321588 -272.466353) (xy 115.345166 -272.512627)
			(xy 115.361214 -272.56202) (xy 115.369339 -272.613315) (xy 115.369848 -272.639282) (xy 115.369339 -272.665249)
			(xy 115.649249 -272.665249) (xy 115.649249 -272.613315) (xy 115.657374 -272.56202) (xy 115.673422 -272.512627)
			(xy 115.697 -272.466353) (xy 115.727526 -272.424337) (xy 115.764249 -272.387614) (xy 115.806265 -272.357088)
			(xy 115.852539 -272.33351) (xy 115.901932 -272.317462) (xy 115.953227 -272.309337) (xy 116.005161 -272.309337)
			(xy 116.056456 -272.317462) (xy 116.105849 -272.33351) (xy 116.152123 -272.357088) (xy 116.194139 -272.387614)
			(xy 116.230862 -272.424337) (xy 116.261388 -272.466353) (xy 116.284966 -272.512627) (xy 116.301014 -272.56202)
			(xy 116.309139 -272.613315) (xy 116.309648 -272.639282) (xy 116.309139 -272.665249) (xy 116.589049 -272.665249)
			(xy 116.589049 -272.613315) (xy 116.597174 -272.56202) (xy 116.613222 -272.512627) (xy 116.6368 -272.466353)
			(xy 116.667326 -272.424337) (xy 116.704049 -272.387614) (xy 116.746065 -272.357088) (xy 116.792339 -272.33351)
			(xy 116.841732 -272.317462) (xy 116.893027 -272.309337) (xy 116.944961 -272.309337) (xy 116.996256 -272.317462)
			(xy 117.045649 -272.33351) (xy 117.091923 -272.357088) (xy 117.133939 -272.387614) (xy 117.170662 -272.424337)
			(xy 117.201188 -272.466353) (xy 117.224766 -272.512627) (xy 117.240814 -272.56202) (xy 117.248939 -272.613315)
			(xy 117.249448 -272.639282) (xy 117.248939 -272.665249) (xy 117.528849 -272.665249) (xy 117.528849 -272.613315)
			(xy 117.536974 -272.56202) (xy 117.553022 -272.512627) (xy 117.5766 -272.466353) (xy 117.607126 -272.424337)
			(xy 117.643849 -272.387614) (xy 117.685865 -272.357088) (xy 117.732139 -272.33351) (xy 117.781532 -272.317462)
			(xy 117.832827 -272.309337) (xy 117.884761 -272.309337) (xy 117.936056 -272.317462) (xy 117.985449 -272.33351)
			(xy 118.031723 -272.357088) (xy 118.073739 -272.387614) (xy 118.110462 -272.424337) (xy 118.140988 -272.466353)
			(xy 118.164566 -272.512627) (xy 118.180614 -272.56202) (xy 118.188739 -272.613315) (xy 118.189248 -272.639282)
			(xy 118.188739 -272.665249) (xy 118.468649 -272.665249) (xy 118.468649 -272.613315) (xy 118.476774 -272.56202)
			(xy 118.492822 -272.512627) (xy 118.5164 -272.466353) (xy 118.546926 -272.424337) (xy 118.583649 -272.387614)
			(xy 118.625665 -272.357088) (xy 118.671939 -272.33351) (xy 118.721332 -272.317462) (xy 118.772627 -272.309337)
			(xy 118.824561 -272.309337) (xy 118.875856 -272.317462) (xy 118.925249 -272.33351) (xy 118.971523 -272.357088)
			(xy 119.013539 -272.387614) (xy 119.050262 -272.424337) (xy 119.080788 -272.466353) (xy 119.104366 -272.512627)
			(xy 119.120414 -272.56202) (xy 119.128539 -272.613315) (xy 119.129048 -272.639282) (xy 119.128539 -272.665249)
			(xy 119.408449 -272.665249) (xy 119.408449 -272.613315) (xy 119.416574 -272.56202) (xy 119.432622 -272.512627)
			(xy 119.4562 -272.466353) (xy 119.486726 -272.424337) (xy 119.523449 -272.387614) (xy 119.565465 -272.357088)
			(xy 119.611739 -272.33351) (xy 119.661132 -272.317462) (xy 119.712427 -272.309337) (xy 119.764361 -272.309337)
			(xy 119.815656 -272.317462) (xy 119.865049 -272.33351) (xy 119.911323 -272.357088) (xy 119.953339 -272.387614)
			(xy 119.990062 -272.424337) (xy 120.020588 -272.466353) (xy 120.044166 -272.512627) (xy 120.060214 -272.56202)
			(xy 120.068339 -272.613315) (xy 120.068848 -272.639282) (xy 120.068339 -272.665249) (xy 120.348249 -272.665249)
			(xy 120.348249 -272.613315) (xy 120.356374 -272.56202) (xy 120.372422 -272.512627) (xy 120.396 -272.466353)
			(xy 120.426526 -272.424337) (xy 120.463249 -272.387614) (xy 120.505265 -272.357088) (xy 120.551539 -272.33351)
			(xy 120.600932 -272.317462) (xy 120.652227 -272.309337) (xy 120.704161 -272.309337) (xy 120.755456 -272.317462)
			(xy 120.804849 -272.33351) (xy 120.851123 -272.357088) (xy 120.893139 -272.387614) (xy 120.929862 -272.424337)
			(xy 120.960388 -272.466353) (xy 120.983966 -272.512627) (xy 121.000014 -272.56202) (xy 121.008139 -272.613315)
			(xy 121.008648 -272.639282) (xy 121.008139 -272.665249) (xy 121.288049 -272.665249) (xy 121.288049 -272.613315)
			(xy 121.296174 -272.56202) (xy 121.312222 -272.512627) (xy 121.3358 -272.466353) (xy 121.366326 -272.424337)
			(xy 121.403049 -272.387614) (xy 121.445065 -272.357088) (xy 121.491339 -272.33351) (xy 121.540732 -272.317462)
			(xy 121.592027 -272.309337) (xy 121.643961 -272.309337) (xy 121.695256 -272.317462) (xy 121.744649 -272.33351)
			(xy 121.790923 -272.357088) (xy 121.832939 -272.387614) (xy 121.869662 -272.424337) (xy 121.900188 -272.466353)
			(xy 121.923766 -272.512627) (xy 121.939814 -272.56202) (xy 121.947939 -272.613315) (xy 121.948448 -272.639282)
			(xy 121.947939 -272.665249) (xy 122.227849 -272.665249) (xy 122.227849 -272.613315) (xy 122.235974 -272.56202)
			(xy 122.252022 -272.512627) (xy 122.2756 -272.466353) (xy 122.306126 -272.424337) (xy 122.342849 -272.387614)
			(xy 122.384865 -272.357088) (xy 122.431139 -272.33351) (xy 122.480532 -272.317462) (xy 122.531827 -272.309337)
			(xy 122.583761 -272.309337) (xy 122.635056 -272.317462) (xy 122.684449 -272.33351) (xy 122.730723 -272.357088)
			(xy 122.772739 -272.387614) (xy 122.809462 -272.424337) (xy 122.839988 -272.466353) (xy 122.863566 -272.512627)
			(xy 122.879614 -272.56202) (xy 122.887739 -272.613315) (xy 122.888248 -272.639282) (xy 122.887739 -272.665249)
			(xy 123.167649 -272.665249) (xy 123.167649 -272.613315) (xy 123.175774 -272.56202) (xy 123.191822 -272.512627)
			(xy 123.2154 -272.466353) (xy 123.245926 -272.424337) (xy 123.282649 -272.387614) (xy 123.324665 -272.357088)
			(xy 123.370939 -272.33351) (xy 123.420332 -272.317462) (xy 123.471627 -272.309337) (xy 123.523561 -272.309337)
			(xy 123.574856 -272.317462) (xy 123.624249 -272.33351) (xy 123.670523 -272.357088) (xy 123.712539 -272.387614)
			(xy 123.749262 -272.424337) (xy 123.779788 -272.466353) (xy 123.803366 -272.512627) (xy 123.819414 -272.56202)
			(xy 123.827539 -272.613315) (xy 123.828048 -272.639282) (xy 123.827539 -272.665249) (xy 124.107449 -272.665249)
			(xy 124.107449 -272.613315) (xy 124.115574 -272.56202) (xy 124.131622 -272.512627) (xy 124.1552 -272.466353)
			(xy 124.185726 -272.424337) (xy 124.222449 -272.387614) (xy 124.264465 -272.357088) (xy 124.310739 -272.33351)
			(xy 124.360132 -272.317462) (xy 124.411427 -272.309337) (xy 124.463361 -272.309337) (xy 124.514656 -272.317462)
			(xy 124.564049 -272.33351) (xy 124.610323 -272.357088) (xy 124.652339 -272.387614) (xy 124.689062 -272.424337)
			(xy 124.719588 -272.466353) (xy 124.743166 -272.512627) (xy 124.759214 -272.56202) (xy 124.767339 -272.613315)
			(xy 124.767848 -272.639282) (xy 124.767339 -272.665249) (xy 125.047503 -272.665249) (xy 125.047503 -272.613315)
			(xy 125.055628 -272.56202) (xy 125.071676 -272.512627) (xy 125.095254 -272.466353) (xy 125.12578 -272.424337)
			(xy 125.162503 -272.387614) (xy 125.204519 -272.357088) (xy 125.250793 -272.33351) (xy 125.300186 -272.317462)
			(xy 125.351481 -272.309337) (xy 125.403415 -272.309337) (xy 125.45471 -272.317462) (xy 125.504103 -272.33351)
			(xy 125.550377 -272.357088) (xy 125.592393 -272.387614) (xy 125.629116 -272.424337) (xy 125.659642 -272.466353)
			(xy 125.68322 -272.512627) (xy 125.699268 -272.56202) (xy 125.707393 -272.613315) (xy 125.707902 -272.639282)
			(xy 125.707393 -272.665249) (xy 125.987049 -272.665249) (xy 125.987049 -272.613315) (xy 125.995174 -272.56202)
			(xy 126.011222 -272.512627) (xy 126.0348 -272.466353) (xy 126.065326 -272.424337) (xy 126.102049 -272.387614)
			(xy 126.144065 -272.357088) (xy 126.190339 -272.33351) (xy 126.239732 -272.317462) (xy 126.291027 -272.309337)
			(xy 126.342961 -272.309337) (xy 126.394256 -272.317462) (xy 126.443649 -272.33351) (xy 126.489923 -272.357088)
			(xy 126.531939 -272.387614) (xy 126.568662 -272.424337) (xy 126.599188 -272.466353) (xy 126.622766 -272.512627)
			(xy 126.638814 -272.56202) (xy 126.646939 -272.613315) (xy 126.647448 -272.639282) (xy 126.646939 -272.665249)
			(xy 126.926849 -272.665249) (xy 126.926849 -272.613315) (xy 126.934974 -272.56202) (xy 126.951022 -272.512627)
			(xy 126.9746 -272.466353) (xy 127.005126 -272.424337) (xy 127.041849 -272.387614) (xy 127.083865 -272.357088)
			(xy 127.130139 -272.33351) (xy 127.179532 -272.317462) (xy 127.230827 -272.309337) (xy 127.282761 -272.309337)
			(xy 127.334056 -272.317462) (xy 127.383449 -272.33351) (xy 127.429723 -272.357088) (xy 127.471739 -272.387614)
			(xy 127.508462 -272.424337) (xy 127.538988 -272.466353) (xy 127.562566 -272.512627) (xy 127.578614 -272.56202)
			(xy 127.586739 -272.613315) (xy 127.587248 -272.639282) (xy 127.586739 -272.665249) (xy 127.866649 -272.665249)
			(xy 127.866649 -272.613315) (xy 127.874774 -272.56202) (xy 127.890822 -272.512627) (xy 127.9144 -272.466353)
			(xy 127.944926 -272.424337) (xy 127.981649 -272.387614) (xy 128.023665 -272.357088) (xy 128.069939 -272.33351)
			(xy 128.119332 -272.317462) (xy 128.170627 -272.309337) (xy 128.222561 -272.309337) (xy 128.273856 -272.317462)
			(xy 128.323249 -272.33351) (xy 128.369523 -272.357088) (xy 128.411539 -272.387614) (xy 128.448262 -272.424337)
			(xy 128.478788 -272.466353) (xy 128.502366 -272.512627) (xy 128.518414 -272.56202) (xy 128.526539 -272.613315)
			(xy 128.527048 -272.639282) (xy 128.526539 -272.665249) (xy 128.806449 -272.665249) (xy 128.806449 -272.613315)
			(xy 128.814574 -272.56202) (xy 128.830622 -272.512627) (xy 128.8542 -272.466353) (xy 128.884726 -272.424337)
			(xy 128.921449 -272.387614) (xy 128.963465 -272.357088) (xy 129.009739 -272.33351) (xy 129.059132 -272.317462)
			(xy 129.110427 -272.309337) (xy 129.162361 -272.309337) (xy 129.213656 -272.317462) (xy 129.263049 -272.33351)
			(xy 129.309323 -272.357088) (xy 129.351339 -272.387614) (xy 129.388062 -272.424337) (xy 129.418588 -272.466353)
			(xy 129.442166 -272.512627) (xy 129.458214 -272.56202) (xy 129.466339 -272.613315) (xy 129.466848 -272.639282)
			(xy 129.466339 -272.665249) (xy 129.746249 -272.665249) (xy 129.746249 -272.613315) (xy 129.754374 -272.56202)
			(xy 129.770422 -272.512627) (xy 129.794 -272.466353) (xy 129.824526 -272.424337) (xy 129.861249 -272.387614)
			(xy 129.903265 -272.357088) (xy 129.949539 -272.33351) (xy 129.998932 -272.317462) (xy 130.050227 -272.309337)
			(xy 130.102161 -272.309337) (xy 130.153456 -272.317462) (xy 130.202849 -272.33351) (xy 130.249123 -272.357088)
			(xy 130.291139 -272.387614) (xy 130.327862 -272.424337) (xy 130.358388 -272.466353) (xy 130.381966 -272.512627)
			(xy 130.398014 -272.56202) (xy 130.406139 -272.613315) (xy 130.406648 -272.639282) (xy 130.406139 -272.665249)
			(xy 130.686049 -272.665249) (xy 130.686049 -272.613315) (xy 130.694174 -272.56202) (xy 130.710222 -272.512627)
			(xy 130.7338 -272.466353) (xy 130.764326 -272.424337) (xy 130.801049 -272.387614) (xy 130.843065 -272.357088)
			(xy 130.889339 -272.33351) (xy 130.938732 -272.317462) (xy 130.990027 -272.309337) (xy 131.041961 -272.309337)
			(xy 131.093256 -272.317462) (xy 131.142649 -272.33351) (xy 131.188923 -272.357088) (xy 131.230939 -272.387614)
			(xy 131.267662 -272.424337) (xy 131.298188 -272.466353) (xy 131.321766 -272.512627) (xy 131.337814 -272.56202)
			(xy 131.345939 -272.613315) (xy 131.346448 -272.639282) (xy 131.345939 -272.665249) (xy 131.337814 -272.716544)
			(xy 131.321766 -272.765937) (xy 131.298188 -272.812211) (xy 131.267662 -272.854227) (xy 131.230939 -272.89095)
			(xy 131.188923 -272.921476) (xy 131.142649 -272.945054) (xy 131.093256 -272.961102) (xy 131.041961 -272.969227)
			(xy 130.990027 -272.969227) (xy 130.938732 -272.961102) (xy 130.889339 -272.945054) (xy 130.843065 -272.921476)
			(xy 130.801049 -272.89095) (xy 130.764326 -272.854227) (xy 130.7338 -272.812211) (xy 130.710222 -272.765937)
			(xy 130.694174 -272.716544) (xy 130.686049 -272.665249) (xy 130.406139 -272.665249) (xy 130.398014 -272.716544)
			(xy 130.381966 -272.765937) (xy 130.358388 -272.812211) (xy 130.327862 -272.854227) (xy 130.291139 -272.89095)
			(xy 130.249123 -272.921476) (xy 130.202849 -272.945054) (xy 130.153456 -272.961102) (xy 130.102161 -272.969227)
			(xy 130.050227 -272.969227) (xy 129.998932 -272.961102) (xy 129.949539 -272.945054) (xy 129.903265 -272.921476)
			(xy 129.861249 -272.89095) (xy 129.824526 -272.854227) (xy 129.794 -272.812211) (xy 129.770422 -272.765937)
			(xy 129.754374 -272.716544) (xy 129.746249 -272.665249) (xy 129.466339 -272.665249) (xy 129.458214 -272.716544)
			(xy 129.442166 -272.765937) (xy 129.418588 -272.812211) (xy 129.388062 -272.854227) (xy 129.351339 -272.89095)
			(xy 129.309323 -272.921476) (xy 129.263049 -272.945054) (xy 129.213656 -272.961102) (xy 129.162361 -272.969227)
			(xy 129.110427 -272.969227) (xy 129.059132 -272.961102) (xy 129.009739 -272.945054) (xy 128.963465 -272.921476)
			(xy 128.921449 -272.89095) (xy 128.884726 -272.854227) (xy 128.8542 -272.812211) (xy 128.830622 -272.765937)
			(xy 128.814574 -272.716544) (xy 128.806449 -272.665249) (xy 128.526539 -272.665249) (xy 128.518414 -272.716544)
			(xy 128.502366 -272.765937) (xy 128.478788 -272.812211) (xy 128.448262 -272.854227) (xy 128.411539 -272.89095)
			(xy 128.369523 -272.921476) (xy 128.323249 -272.945054) (xy 128.273856 -272.961102) (xy 128.222561 -272.969227)
			(xy 128.170627 -272.969227) (xy 128.119332 -272.961102) (xy 128.069939 -272.945054) (xy 128.023665 -272.921476)
			(xy 127.981649 -272.89095) (xy 127.944926 -272.854227) (xy 127.9144 -272.812211) (xy 127.890822 -272.765937)
			(xy 127.874774 -272.716544) (xy 127.866649 -272.665249) (xy 127.586739 -272.665249) (xy 127.578614 -272.716544)
			(xy 127.562566 -272.765937) (xy 127.538988 -272.812211) (xy 127.508462 -272.854227) (xy 127.471739 -272.89095)
			(xy 127.429723 -272.921476) (xy 127.383449 -272.945054) (xy 127.334056 -272.961102) (xy 127.282761 -272.969227)
			(xy 127.230827 -272.969227) (xy 127.179532 -272.961102) (xy 127.130139 -272.945054) (xy 127.083865 -272.921476)
			(xy 127.041849 -272.89095) (xy 127.005126 -272.854227) (xy 126.9746 -272.812211) (xy 126.951022 -272.765937)
			(xy 126.934974 -272.716544) (xy 126.926849 -272.665249) (xy 126.646939 -272.665249) (xy 126.638814 -272.716544)
			(xy 126.622766 -272.765937) (xy 126.599188 -272.812211) (xy 126.568662 -272.854227) (xy 126.531939 -272.89095)
			(xy 126.489923 -272.921476) (xy 126.443649 -272.945054) (xy 126.394256 -272.961102) (xy 126.342961 -272.969227)
			(xy 126.291027 -272.969227) (xy 126.239732 -272.961102) (xy 126.190339 -272.945054) (xy 126.144065 -272.921476)
			(xy 126.102049 -272.89095) (xy 126.065326 -272.854227) (xy 126.0348 -272.812211) (xy 126.011222 -272.765937)
			(xy 125.995174 -272.716544) (xy 125.987049 -272.665249) (xy 125.707393 -272.665249) (xy 125.699268 -272.716544)
			(xy 125.68322 -272.765937) (xy 125.659642 -272.812211) (xy 125.629116 -272.854227) (xy 125.592393 -272.89095)
			(xy 125.550377 -272.921476) (xy 125.504103 -272.945054) (xy 125.45471 -272.961102) (xy 125.403415 -272.969227)
			(xy 125.351481 -272.969227) (xy 125.300186 -272.961102) (xy 125.250793 -272.945054) (xy 125.204519 -272.921476)
			(xy 125.162503 -272.89095) (xy 125.12578 -272.854227) (xy 125.095254 -272.812211) (xy 125.071676 -272.765937)
			(xy 125.055628 -272.716544) (xy 125.047503 -272.665249) (xy 124.767339 -272.665249) (xy 124.759214 -272.716544)
			(xy 124.743166 -272.765937) (xy 124.719588 -272.812211) (xy 124.689062 -272.854227) (xy 124.652339 -272.89095)
			(xy 124.610323 -272.921476) (xy 124.564049 -272.945054) (xy 124.514656 -272.961102) (xy 124.463361 -272.969227)
			(xy 124.411427 -272.969227) (xy 124.360132 -272.961102) (xy 124.310739 -272.945054) (xy 124.264465 -272.921476)
			(xy 124.222449 -272.89095) (xy 124.185726 -272.854227) (xy 124.1552 -272.812211) (xy 124.131622 -272.765937)
			(xy 124.115574 -272.716544) (xy 124.107449 -272.665249) (xy 123.827539 -272.665249) (xy 123.819414 -272.716544)
			(xy 123.803366 -272.765937) (xy 123.779788 -272.812211) (xy 123.749262 -272.854227) (xy 123.712539 -272.89095)
			(xy 123.670523 -272.921476) (xy 123.624249 -272.945054) (xy 123.574856 -272.961102) (xy 123.523561 -272.969227)
			(xy 123.471627 -272.969227) (xy 123.420332 -272.961102) (xy 123.370939 -272.945054) (xy 123.324665 -272.921476)
			(xy 123.282649 -272.89095) (xy 123.245926 -272.854227) (xy 123.2154 -272.812211) (xy 123.191822 -272.765937)
			(xy 123.175774 -272.716544) (xy 123.167649 -272.665249) (xy 122.887739 -272.665249) (xy 122.879614 -272.716544)
			(xy 122.863566 -272.765937) (xy 122.839988 -272.812211) (xy 122.809462 -272.854227) (xy 122.772739 -272.89095)
			(xy 122.730723 -272.921476) (xy 122.684449 -272.945054) (xy 122.635056 -272.961102) (xy 122.583761 -272.969227)
			(xy 122.531827 -272.969227) (xy 122.480532 -272.961102) (xy 122.431139 -272.945054) (xy 122.384865 -272.921476)
			(xy 122.342849 -272.89095) (xy 122.306126 -272.854227) (xy 122.2756 -272.812211) (xy 122.252022 -272.765937)
			(xy 122.235974 -272.716544) (xy 122.227849 -272.665249) (xy 121.947939 -272.665249) (xy 121.939814 -272.716544)
			(xy 121.923766 -272.765937) (xy 121.900188 -272.812211) (xy 121.869662 -272.854227) (xy 121.832939 -272.89095)
			(xy 121.790923 -272.921476) (xy 121.744649 -272.945054) (xy 121.695256 -272.961102) (xy 121.643961 -272.969227)
			(xy 121.592027 -272.969227) (xy 121.540732 -272.961102) (xy 121.491339 -272.945054) (xy 121.445065 -272.921476)
			(xy 121.403049 -272.89095) (xy 121.366326 -272.854227) (xy 121.3358 -272.812211) (xy 121.312222 -272.765937)
			(xy 121.296174 -272.716544) (xy 121.288049 -272.665249) (xy 121.008139 -272.665249) (xy 121.000014 -272.716544)
			(xy 120.983966 -272.765937) (xy 120.960388 -272.812211) (xy 120.929862 -272.854227) (xy 120.893139 -272.89095)
			(xy 120.851123 -272.921476) (xy 120.804849 -272.945054) (xy 120.755456 -272.961102) (xy 120.704161 -272.969227)
			(xy 120.652227 -272.969227) (xy 120.600932 -272.961102) (xy 120.551539 -272.945054) (xy 120.505265 -272.921476)
			(xy 120.463249 -272.89095) (xy 120.426526 -272.854227) (xy 120.396 -272.812211) (xy 120.372422 -272.765937)
			(xy 120.356374 -272.716544) (xy 120.348249 -272.665249) (xy 120.068339 -272.665249) (xy 120.060214 -272.716544)
			(xy 120.044166 -272.765937) (xy 120.020588 -272.812211) (xy 119.990062 -272.854227) (xy 119.953339 -272.89095)
			(xy 119.911323 -272.921476) (xy 119.865049 -272.945054) (xy 119.815656 -272.961102) (xy 119.764361 -272.969227)
			(xy 119.712427 -272.969227) (xy 119.661132 -272.961102) (xy 119.611739 -272.945054) (xy 119.565465 -272.921476)
			(xy 119.523449 -272.89095) (xy 119.486726 -272.854227) (xy 119.4562 -272.812211) (xy 119.432622 -272.765937)
			(xy 119.416574 -272.716544) (xy 119.408449 -272.665249) (xy 119.128539 -272.665249) (xy 119.120414 -272.716544)
			(xy 119.104366 -272.765937) (xy 119.080788 -272.812211) (xy 119.050262 -272.854227) (xy 119.013539 -272.89095)
			(xy 118.971523 -272.921476) (xy 118.925249 -272.945054) (xy 118.875856 -272.961102) (xy 118.824561 -272.969227)
			(xy 118.772627 -272.969227) (xy 118.721332 -272.961102) (xy 118.671939 -272.945054) (xy 118.625665 -272.921476)
			(xy 118.583649 -272.89095) (xy 118.546926 -272.854227) (xy 118.5164 -272.812211) (xy 118.492822 -272.765937)
			(xy 118.476774 -272.716544) (xy 118.468649 -272.665249) (xy 118.188739 -272.665249) (xy 118.180614 -272.716544)
			(xy 118.164566 -272.765937) (xy 118.140988 -272.812211) (xy 118.110462 -272.854227) (xy 118.073739 -272.89095)
			(xy 118.031723 -272.921476) (xy 117.985449 -272.945054) (xy 117.936056 -272.961102) (xy 117.884761 -272.969227)
			(xy 117.832827 -272.969227) (xy 117.781532 -272.961102) (xy 117.732139 -272.945054) (xy 117.685865 -272.921476)
			(xy 117.643849 -272.89095) (xy 117.607126 -272.854227) (xy 117.5766 -272.812211) (xy 117.553022 -272.765937)
			(xy 117.536974 -272.716544) (xy 117.528849 -272.665249) (xy 117.248939 -272.665249) (xy 117.240814 -272.716544)
			(xy 117.224766 -272.765937) (xy 117.201188 -272.812211) (xy 117.170662 -272.854227) (xy 117.133939 -272.89095)
			(xy 117.091923 -272.921476) (xy 117.045649 -272.945054) (xy 116.996256 -272.961102) (xy 116.944961 -272.969227)
			(xy 116.893027 -272.969227) (xy 116.841732 -272.961102) (xy 116.792339 -272.945054) (xy 116.746065 -272.921476)
			(xy 116.704049 -272.89095) (xy 116.667326 -272.854227) (xy 116.6368 -272.812211) (xy 116.613222 -272.765937)
			(xy 116.597174 -272.716544) (xy 116.589049 -272.665249) (xy 116.309139 -272.665249) (xy 116.301014 -272.716544)
			(xy 116.284966 -272.765937) (xy 116.261388 -272.812211) (xy 116.230862 -272.854227) (xy 116.194139 -272.89095)
			(xy 116.152123 -272.921476) (xy 116.105849 -272.945054) (xy 116.056456 -272.961102) (xy 116.005161 -272.969227)
			(xy 115.953227 -272.969227) (xy 115.901932 -272.961102) (xy 115.852539 -272.945054) (xy 115.806265 -272.921476)
			(xy 115.764249 -272.89095) (xy 115.727526 -272.854227) (xy 115.697 -272.812211) (xy 115.673422 -272.765937)
			(xy 115.657374 -272.716544) (xy 115.649249 -272.665249) (xy 115.369339 -272.665249) (xy 115.361214 -272.716544)
			(xy 115.345166 -272.765937) (xy 115.321588 -272.812211) (xy 115.291062 -272.854227) (xy 115.254339 -272.89095)
			(xy 115.212323 -272.921476) (xy 115.166049 -272.945054) (xy 115.116656 -272.961102) (xy 115.065361 -272.969227)
			(xy 115.013427 -272.969227) (xy 114.962132 -272.961102) (xy 114.912739 -272.945054) (xy 114.866465 -272.921476)
			(xy 114.824449 -272.89095) (xy 114.787726 -272.854227) (xy 114.7572 -272.812211) (xy 114.733622 -272.765937)
			(xy 114.717574 -272.716544) (xy 114.709449 -272.665249) (xy 114.429539 -272.665249) (xy 114.421414 -272.716544)
			(xy 114.405366 -272.765937) (xy 114.381788 -272.812211) (xy 114.351262 -272.854227) (xy 114.314539 -272.89095)
			(xy 114.272523 -272.921476) (xy 114.226249 -272.945054) (xy 114.176856 -272.961102) (xy 114.125561 -272.969227)
			(xy 114.073627 -272.969227) (xy 114.022332 -272.961102) (xy 113.972939 -272.945054) (xy 113.926665 -272.921476)
			(xy 113.884649 -272.89095) (xy 113.847926 -272.854227) (xy 113.8174 -272.812211) (xy 113.793822 -272.765937)
			(xy 113.777774 -272.716544) (xy 113.769649 -272.665249) (xy 113.489739 -272.665249) (xy 113.481614 -272.716544)
			(xy 113.465566 -272.765937) (xy 113.441988 -272.812211) (xy 113.411462 -272.854227) (xy 113.374739 -272.89095)
			(xy 113.332723 -272.921476) (xy 113.286449 -272.945054) (xy 113.237056 -272.961102) (xy 113.185761 -272.969227)
			(xy 113.133827 -272.969227) (xy 113.082532 -272.961102) (xy 113.033139 -272.945054) (xy 112.986865 -272.921476)
			(xy 112.944849 -272.89095) (xy 112.908126 -272.854227) (xy 112.8776 -272.812211) (xy 112.854022 -272.765937)
			(xy 112.837974 -272.716544) (xy 112.829849 -272.665249) (xy 112.550193 -272.665249) (xy 112.542068 -272.716544)
			(xy 112.52602 -272.765937) (xy 112.502442 -272.812211) (xy 112.471916 -272.854227) (xy 112.435193 -272.89095)
			(xy 112.393177 -272.921476) (xy 112.346903 -272.945054) (xy 112.29751 -272.961102) (xy 112.246215 -272.969227)
			(xy 112.194281 -272.969227) (xy 112.142986 -272.961102) (xy 112.093593 -272.945054) (xy 112.047319 -272.921476)
			(xy 112.005303 -272.89095) (xy 111.96858 -272.854227) (xy 111.938054 -272.812211) (xy 111.914476 -272.765937)
			(xy 111.898428 -272.716544) (xy 111.890303 -272.665249) (xy 111.610393 -272.665249) (xy 111.602268 -272.716544)
			(xy 111.58622 -272.765937) (xy 111.562642 -272.812211) (xy 111.532116 -272.854227) (xy 111.495393 -272.89095)
			(xy 111.453377 -272.921476) (xy 111.407103 -272.945054) (xy 111.35771 -272.961102) (xy 111.306415 -272.969227)
			(xy 111.254481 -272.969227) (xy 111.203186 -272.961102) (xy 111.153793 -272.945054) (xy 111.107519 -272.921476)
			(xy 111.065503 -272.89095) (xy 111.02878 -272.854227) (xy 110.998254 -272.812211) (xy 110.974676 -272.765937)
			(xy 110.958628 -272.716544) (xy 110.950503 -272.665249) (xy 110.670339 -272.665249) (xy 110.662214 -272.716544)
			(xy 110.646166 -272.765937) (xy 110.622588 -272.812211) (xy 110.592062 -272.854227) (xy 110.555339 -272.89095)
			(xy 110.513323 -272.921476) (xy 110.467049 -272.945054) (xy 110.417656 -272.961102) (xy 110.366361 -272.969227)
			(xy 110.314427 -272.969227) (xy 110.263132 -272.961102) (xy 110.213739 -272.945054) (xy 110.167465 -272.921476)
			(xy 110.125449 -272.89095) (xy 110.088726 -272.854227) (xy 110.0582 -272.812211) (xy 110.034622 -272.765937)
			(xy 110.018574 -272.716544) (xy 110.010449 -272.665249) (xy 109.730539 -272.665249) (xy 109.722414 -272.716544)
			(xy 109.706366 -272.765937) (xy 109.682788 -272.812211) (xy 109.652262 -272.854227) (xy 109.615539 -272.89095)
			(xy 109.573523 -272.921476) (xy 109.527249 -272.945054) (xy 109.477856 -272.961102) (xy 109.426561 -272.969227)
			(xy 109.374627 -272.969227) (xy 109.323332 -272.961102) (xy 109.273939 -272.945054) (xy 109.227665 -272.921476)
			(xy 109.185649 -272.89095) (xy 109.148926 -272.854227) (xy 109.1184 -272.812211) (xy 109.094822 -272.765937)
			(xy 109.078774 -272.716544) (xy 109.070649 -272.665249) (xy 108.790739 -272.665249) (xy 108.782614 -272.716544)
			(xy 108.766566 -272.765937) (xy 108.742988 -272.812211) (xy 108.712462 -272.854227) (xy 108.675739 -272.89095)
			(xy 108.633723 -272.921476) (xy 108.587449 -272.945054) (xy 108.538056 -272.961102) (xy 108.486761 -272.969227)
			(xy 108.434827 -272.969227) (xy 108.383532 -272.961102) (xy 108.334139 -272.945054) (xy 108.287865 -272.921476)
			(xy 108.245849 -272.89095) (xy 108.209126 -272.854227) (xy 108.1786 -272.812211) (xy 108.155022 -272.765937)
			(xy 108.138974 -272.716544) (xy 108.130849 -272.665249) (xy 107.850939 -272.665249) (xy 107.842814 -272.716544)
			(xy 107.826766 -272.765937) (xy 107.803188 -272.812211) (xy 107.772662 -272.854227) (xy 107.735939 -272.89095)
			(xy 107.693923 -272.921476) (xy 107.647649 -272.945054) (xy 107.598256 -272.961102) (xy 107.546961 -272.969227)
			(xy 107.495027 -272.969227) (xy 107.443732 -272.961102) (xy 107.394339 -272.945054) (xy 107.348065 -272.921476)
			(xy 107.306049 -272.89095) (xy 107.269326 -272.854227) (xy 107.2388 -272.812211) (xy 107.215222 -272.765937)
			(xy 107.199174 -272.716544) (xy 107.191049 -272.665249) (xy 106.911139 -272.665249) (xy 106.903014 -272.716544)
			(xy 106.886966 -272.765937) (xy 106.863388 -272.812211) (xy 106.832862 -272.854227) (xy 106.796139 -272.89095)
			(xy 106.754123 -272.921476) (xy 106.707849 -272.945054) (xy 106.658456 -272.961102) (xy 106.607161 -272.969227)
			(xy 106.555227 -272.969227) (xy 106.503932 -272.961102) (xy 106.454539 -272.945054) (xy 106.408265 -272.921476)
			(xy 106.366249 -272.89095) (xy 106.329526 -272.854227) (xy 106.299 -272.812211) (xy 106.275422 -272.765937)
			(xy 106.259374 -272.716544) (xy 106.251249 -272.665249) (xy 105.971339 -272.665249) (xy 105.963214 -272.716544)
			(xy 105.947166 -272.765937) (xy 105.923588 -272.812211) (xy 105.893062 -272.854227) (xy 105.856339 -272.89095)
			(xy 105.814323 -272.921476) (xy 105.768049 -272.945054) (xy 105.718656 -272.961102) (xy 105.667361 -272.969227)
			(xy 105.615427 -272.969227) (xy 105.564132 -272.961102) (xy 105.514739 -272.945054) (xy 105.468465 -272.921476)
			(xy 105.426449 -272.89095) (xy 105.389726 -272.854227) (xy 105.3592 -272.812211) (xy 105.335622 -272.765937)
			(xy 105.319574 -272.716544) (xy 105.311449 -272.665249) (xy 105.031539 -272.665249) (xy 105.023414 -272.716544)
			(xy 105.007366 -272.765937) (xy 104.983788 -272.812211) (xy 104.953262 -272.854227) (xy 104.916539 -272.89095)
			(xy 104.874523 -272.921476) (xy 104.828249 -272.945054) (xy 104.778856 -272.961102) (xy 104.727561 -272.969227)
			(xy 104.675627 -272.969227) (xy 104.624332 -272.961102) (xy 104.574939 -272.945054) (xy 104.528665 -272.921476)
			(xy 104.486649 -272.89095) (xy 104.449926 -272.854227) (xy 104.4194 -272.812211) (xy 104.395822 -272.765937)
			(xy 104.379774 -272.716544) (xy 104.371649 -272.665249) (xy 104.091739 -272.665249) (xy 104.083614 -272.716544)
			(xy 104.067566 -272.765937) (xy 104.043988 -272.812211) (xy 104.013462 -272.854227) (xy 103.976739 -272.89095)
			(xy 103.934723 -272.921476) (xy 103.888449 -272.945054) (xy 103.839056 -272.961102) (xy 103.787761 -272.969227)
			(xy 103.735827 -272.969227) (xy 103.684532 -272.961102) (xy 103.635139 -272.945054) (xy 103.588865 -272.921476)
			(xy 103.546849 -272.89095) (xy 103.510126 -272.854227) (xy 103.4796 -272.812211) (xy 103.456022 -272.765937)
			(xy 103.439974 -272.716544) (xy 103.431849 -272.665249) (xy 103.151939 -272.665249) (xy 103.143814 -272.716544)
			(xy 103.127766 -272.765937) (xy 103.104188 -272.812211) (xy 103.073662 -272.854227) (xy 103.036939 -272.89095)
			(xy 102.994923 -272.921476) (xy 102.948649 -272.945054) (xy 102.899256 -272.961102) (xy 102.847961 -272.969227)
			(xy 102.796027 -272.969227) (xy 102.744732 -272.961102) (xy 102.695339 -272.945054) (xy 102.649065 -272.921476)
			(xy 102.607049 -272.89095) (xy 102.570326 -272.854227) (xy 102.5398 -272.812211) (xy 102.516222 -272.765937)
			(xy 102.500174 -272.716544) (xy 102.492049 -272.665249) (xy 102.212139 -272.665249) (xy 102.204014 -272.716544)
			(xy 102.187966 -272.765937) (xy 102.164388 -272.812211) (xy 102.133862 -272.854227) (xy 102.097139 -272.89095)
			(xy 102.055123 -272.921476) (xy 102.008849 -272.945054) (xy 101.959456 -272.961102) (xy 101.908161 -272.969227)
			(xy 101.856227 -272.969227) (xy 101.804932 -272.961102) (xy 101.755539 -272.945054) (xy 101.709265 -272.921476)
			(xy 101.667249 -272.89095) (xy 101.630526 -272.854227) (xy 101.6 -272.812211) (xy 101.576422 -272.765937)
			(xy 101.560374 -272.716544) (xy 101.552249 -272.665249) (xy 101.272339 -272.665249) (xy 101.264214 -272.716544)
			(xy 101.248166 -272.765937) (xy 101.224588 -272.812211) (xy 101.194062 -272.854227) (xy 101.157339 -272.89095)
			(xy 101.115323 -272.921476) (xy 101.069049 -272.945054) (xy 101.019656 -272.961102) (xy 100.968361 -272.969227)
			(xy 100.916427 -272.969227) (xy 100.865132 -272.961102) (xy 100.815739 -272.945054) (xy 100.769465 -272.921476)
			(xy 100.727449 -272.89095) (xy 100.690726 -272.854227) (xy 100.6602 -272.812211) (xy 100.636622 -272.765937)
			(xy 100.620574 -272.716544) (xy 100.612449 -272.665249) (xy 100.332539 -272.665249) (xy 100.324414 -272.716544)
			(xy 100.308366 -272.765937) (xy 100.284788 -272.812211) (xy 100.254262 -272.854227) (xy 100.217539 -272.89095)
			(xy 100.175523 -272.921476) (xy 100.129249 -272.945054) (xy 100.079856 -272.961102) (xy 100.028561 -272.969227)
			(xy 99.976627 -272.969227) (xy 99.925332 -272.961102) (xy 99.875939 -272.945054) (xy 99.829665 -272.921476)
			(xy 99.787649 -272.89095) (xy 99.750926 -272.854227) (xy 99.7204 -272.812211) (xy 99.696822 -272.765937)
			(xy 99.680774 -272.716544) (xy 99.672649 -272.665249) (xy 99.392739 -272.665249) (xy 99.384614 -272.716544)
			(xy 99.368566 -272.765937) (xy 99.344988 -272.812211) (xy 99.314462 -272.854227) (xy 99.277739 -272.89095)
			(xy 99.235723 -272.921476) (xy 99.189449 -272.945054) (xy 99.140056 -272.961102) (xy 99.088761 -272.969227)
			(xy 99.036827 -272.969227) (xy 98.985532 -272.961102) (xy 98.936139 -272.945054) (xy 98.889865 -272.921476)
			(xy 98.847849 -272.89095) (xy 98.811126 -272.854227) (xy 98.7806 -272.812211) (xy 98.757022 -272.765937)
			(xy 98.740974 -272.716544) (xy 98.732849 -272.665249) (xy 98.452939 -272.665249) (xy 98.444814 -272.716544)
			(xy 98.428766 -272.765937) (xy 98.405188 -272.812211) (xy 98.374662 -272.854227) (xy 98.337939 -272.89095)
			(xy 98.295923 -272.921476) (xy 98.249649 -272.945054) (xy 98.200256 -272.961102) (xy 98.148961 -272.969227)
			(xy 98.097027 -272.969227) (xy 98.045732 -272.961102) (xy 97.996339 -272.945054) (xy 97.950065 -272.921476)
			(xy 97.908049 -272.89095) (xy 97.871326 -272.854227) (xy 97.8408 -272.812211) (xy 97.817222 -272.765937)
			(xy 97.801174 -272.716544) (xy 97.793049 -272.665249) (xy 97.513393 -272.665249) (xy 97.505268 -272.716544)
			(xy 97.48922 -272.765937) (xy 97.465642 -272.812211) (xy 97.435116 -272.854227) (xy 97.398393 -272.89095)
			(xy 97.356377 -272.921476) (xy 97.310103 -272.945054) (xy 97.26071 -272.961102) (xy 97.209415 -272.969227)
			(xy 97.157481 -272.969227) (xy 97.106186 -272.961102) (xy 97.056793 -272.945054) (xy 97.010519 -272.921476)
			(xy 96.968503 -272.89095) (xy 96.93178 -272.854227) (xy 96.901254 -272.812211) (xy 96.877676 -272.765937)
			(xy 96.861628 -272.716544) (xy 96.853503 -272.665249) (xy 96.573339 -272.665249) (xy 96.565214 -272.716544)
			(xy 96.549166 -272.765937) (xy 96.525588 -272.812211) (xy 96.495062 -272.854227) (xy 96.458339 -272.89095)
			(xy 96.416323 -272.921476) (xy 96.370049 -272.945054) (xy 96.320656 -272.961102) (xy 96.269361 -272.969227)
			(xy 96.217427 -272.969227) (xy 96.166132 -272.961102) (xy 96.116739 -272.945054) (xy 96.070465 -272.921476)
			(xy 96.028449 -272.89095) (xy 95.991726 -272.854227) (xy 95.9612 -272.812211) (xy 95.937622 -272.765937)
			(xy 95.921574 -272.716544) (xy 95.913449 -272.665249) (xy 95.633539 -272.665249) (xy 95.625414 -272.716544)
			(xy 95.609366 -272.765937) (xy 95.585788 -272.812211) (xy 95.555262 -272.854227) (xy 95.518539 -272.89095)
			(xy 95.476523 -272.921476) (xy 95.430249 -272.945054) (xy 95.380856 -272.961102) (xy 95.329561 -272.969227)
			(xy 95.277627 -272.969227) (xy 95.226332 -272.961102) (xy 95.176939 -272.945054) (xy 95.130665 -272.921476)
			(xy 95.088649 -272.89095) (xy 95.051926 -272.854227) (xy 95.0214 -272.812211) (xy 94.997822 -272.765937)
			(xy 94.981774 -272.716544) (xy 94.973649 -272.665249) (xy 94.693739 -272.665249) (xy 94.685614 -272.716544)
			(xy 94.669566 -272.765937) (xy 94.645988 -272.812211) (xy 94.615462 -272.854227) (xy 94.578739 -272.89095)
			(xy 94.536723 -272.921476) (xy 94.490449 -272.945054) (xy 94.441056 -272.961102) (xy 94.389761 -272.969227)
			(xy 94.337827 -272.969227) (xy 94.286532 -272.961102) (xy 94.237139 -272.945054) (xy 94.190865 -272.921476)
			(xy 94.148849 -272.89095) (xy 94.112126 -272.854227) (xy 94.0816 -272.812211) (xy 94.058022 -272.765937)
			(xy 94.041974 -272.716544) (xy 94.033849 -272.665249) (xy 93.753939 -272.665249) (xy 93.745814 -272.716544)
			(xy 93.729766 -272.765937) (xy 93.706188 -272.812211) (xy 93.675662 -272.854227) (xy 93.638939 -272.89095)
			(xy 93.596923 -272.921476) (xy 93.550649 -272.945054) (xy 93.501256 -272.961102) (xy 93.449961 -272.969227)
			(xy 93.398027 -272.969227) (xy 93.346732 -272.961102) (xy 93.297339 -272.945054) (xy 93.251065 -272.921476)
			(xy 93.209049 -272.89095) (xy 93.172326 -272.854227) (xy 93.1418 -272.812211) (xy 93.118222 -272.765937)
			(xy 93.102174 -272.716544) (xy 93.094049 -272.665249) (xy 92.814139 -272.665249) (xy 92.806014 -272.716544)
			(xy 92.789966 -272.765937) (xy 92.766388 -272.812211) (xy 92.735862 -272.854227) (xy 92.699139 -272.89095)
			(xy 92.657123 -272.921476) (xy 92.610849 -272.945054) (xy 92.561456 -272.961102) (xy 92.510161 -272.969227)
			(xy 92.458227 -272.969227) (xy 92.406932 -272.961102) (xy 92.357539 -272.945054) (xy 92.311265 -272.921476)
			(xy 92.269249 -272.89095) (xy 92.232526 -272.854227) (xy 92.202 -272.812211) (xy 92.178422 -272.765937)
			(xy 92.162374 -272.716544) (xy 92.154249 -272.665249) (xy 91.873682 -272.665249) (xy 91.871676 -272.690869)
			(xy 91.859657 -272.74119) (xy 91.839952 -272.789026) (xy 91.813039 -272.833211) (xy 91.779577 -272.872668)
			(xy 91.740379 -272.906435) (xy 91.718638 -272.92046) (xy 91.712034 -272.924778) (xy 91.68765 -272.967196)
			(xy 91.68765 -273.086576) (xy 91.688001 -273.095463) (xy 91.694153 -273.112139) (xy 91.705703 -273.125648)
			(xy 91.713304 -273.130264) (xy 91.751658 -273.1516) (xy 91.791536 -273.173698) (xy 91.799315 -273.177309)
			(xy 91.816299 -273.179607) (xy 91.833076 -273.176109) (xy 91.840558 -273.17192) (xy 91.840812 -273.171666)
			(xy 91.860482 -273.159986) (xy 91.902354 -273.141559) (xy 91.946364 -273.129073) (xy 91.991675 -273.122767)
			(xy 92.014548 -273.12239) (xy 92.040533 -273.122903) (xy 92.091862 -273.13104) (xy 92.141286 -273.147105)
			(xy 92.187589 -273.170704) (xy 92.229631 -273.201254) (xy 92.266377 -273.238005) (xy 92.296922 -273.280052)
			(xy 92.320513 -273.326358) (xy 92.336572 -273.375785) (xy 92.344701 -273.427115) (xy 92.344701 -273.479065)
			(xy 92.624403 -273.479065) (xy 92.624403 -273.427131) (xy 92.632528 -273.375836) (xy 92.648576 -273.326443)
			(xy 92.672154 -273.280169) (xy 92.70268 -273.238153) (xy 92.739403 -273.20143) (xy 92.781419 -273.170904)
			(xy 92.827693 -273.147326) (xy 92.877086 -273.131278) (xy 92.928381 -273.123153) (xy 92.980315 -273.123153)
			(xy 93.03161 -273.131278) (xy 93.081003 -273.147326) (xy 93.127277 -273.170904) (xy 93.169293 -273.20143)
			(xy 93.206016 -273.238153) (xy 93.236542 -273.280169) (xy 93.26012 -273.326443) (xy 93.276168 -273.375836)
			(xy 93.284293 -273.427131) (xy 93.284802 -273.453098) (xy 93.284293 -273.479065) (xy 93.564203 -273.479065)
			(xy 93.564203 -273.427131) (xy 93.572328 -273.375836) (xy 93.588376 -273.326443) (xy 93.611954 -273.280169)
			(xy 93.64248 -273.238153) (xy 93.679203 -273.20143) (xy 93.721219 -273.170904) (xy 93.767493 -273.147326)
			(xy 93.816886 -273.131278) (xy 93.868181 -273.123153) (xy 93.920115 -273.123153) (xy 93.97141 -273.131278)
			(xy 94.020803 -273.147326) (xy 94.067077 -273.170904) (xy 94.109093 -273.20143) (xy 94.145816 -273.238153)
			(xy 94.176342 -273.280169) (xy 94.19992 -273.326443) (xy 94.215968 -273.375836) (xy 94.224093 -273.427131)
			(xy 94.224602 -273.453098) (xy 94.224093 -273.479065) (xy 94.503749 -273.479065) (xy 94.503749 -273.427131)
			(xy 94.511874 -273.375836) (xy 94.527922 -273.326443) (xy 94.5515 -273.280169) (xy 94.582026 -273.238153)
			(xy 94.618749 -273.20143) (xy 94.660765 -273.170904) (xy 94.707039 -273.147326) (xy 94.756432 -273.131278)
			(xy 94.807727 -273.123153) (xy 94.859661 -273.123153) (xy 94.910956 -273.131278) (xy 94.960349 -273.147326)
			(xy 95.006623 -273.170904) (xy 95.048639 -273.20143) (xy 95.085362 -273.238153) (xy 95.115888 -273.280169)
			(xy 95.139466 -273.326443) (xy 95.155514 -273.375836) (xy 95.163639 -273.427131) (xy 95.164148 -273.453098)
			(xy 95.163639 -273.479065) (xy 95.443803 -273.479065) (xy 95.443803 -273.427131) (xy 95.451928 -273.375836)
			(xy 95.467976 -273.326443) (xy 95.491554 -273.280169) (xy 95.52208 -273.238153) (xy 95.558803 -273.20143)
			(xy 95.600819 -273.170904) (xy 95.647093 -273.147326) (xy 95.696486 -273.131278) (xy 95.747781 -273.123153)
			(xy 95.799715 -273.123153) (xy 95.85101 -273.131278) (xy 95.900403 -273.147326) (xy 95.946677 -273.170904)
			(xy 95.988693 -273.20143) (xy 96.025416 -273.238153) (xy 96.055942 -273.280169) (xy 96.07952 -273.326443)
			(xy 96.095568 -273.375836) (xy 96.103693 -273.427131) (xy 96.104202 -273.453098) (xy 96.103693 -273.479065)
			(xy 96.383603 -273.479065) (xy 96.383603 -273.427131) (xy 96.391728 -273.375836) (xy 96.407776 -273.326443)
			(xy 96.431354 -273.280169) (xy 96.46188 -273.238153) (xy 96.498603 -273.20143) (xy 96.540619 -273.170904)
			(xy 96.586893 -273.147326) (xy 96.636286 -273.131278) (xy 96.687581 -273.123153) (xy 96.739515 -273.123153)
			(xy 96.79081 -273.131278) (xy 96.840203 -273.147326) (xy 96.886477 -273.170904) (xy 96.928493 -273.20143)
			(xy 96.965216 -273.238153) (xy 96.995742 -273.280169) (xy 97.01932 -273.326443) (xy 97.035368 -273.375836)
			(xy 97.043493 -273.427131) (xy 97.044002 -273.453098) (xy 97.043493 -273.479065) (xy 97.323403 -273.479065)
			(xy 97.323403 -273.427131) (xy 97.331528 -273.375836) (xy 97.347576 -273.326443) (xy 97.371154 -273.280169)
			(xy 97.40168 -273.238153) (xy 97.438403 -273.20143) (xy 97.480419 -273.170904) (xy 97.526693 -273.147326)
			(xy 97.576086 -273.131278) (xy 97.627381 -273.123153) (xy 97.679315 -273.123153) (xy 97.73061 -273.131278)
			(xy 97.780003 -273.147326) (xy 97.826277 -273.170904) (xy 97.868293 -273.20143) (xy 97.905016 -273.238153)
			(xy 97.935542 -273.280169) (xy 97.95912 -273.326443) (xy 97.975168 -273.375836) (xy 97.983293 -273.427131)
			(xy 97.983802 -273.453098) (xy 97.983293 -273.479065) (xy 98.263203 -273.479065) (xy 98.263203 -273.427131)
			(xy 98.271328 -273.375836) (xy 98.287376 -273.326443) (xy 98.310954 -273.280169) (xy 98.34148 -273.238153)
			(xy 98.378203 -273.20143) (xy 98.420219 -273.170904) (xy 98.466493 -273.147326) (xy 98.515886 -273.131278)
			(xy 98.567181 -273.123153) (xy 98.619115 -273.123153) (xy 98.67041 -273.131278) (xy 98.719803 -273.147326)
			(xy 98.766077 -273.170904) (xy 98.808093 -273.20143) (xy 98.844816 -273.238153) (xy 98.875342 -273.280169)
			(xy 98.89892 -273.326443) (xy 98.914968 -273.375836) (xy 98.923093 -273.427131) (xy 98.923602 -273.453098)
			(xy 98.923093 -273.479065) (xy 99.203003 -273.479065) (xy 99.203003 -273.427131) (xy 99.211128 -273.375836)
			(xy 99.227176 -273.326443) (xy 99.250754 -273.280169) (xy 99.28128 -273.238153) (xy 99.318003 -273.20143)
			(xy 99.360019 -273.170904) (xy 99.406293 -273.147326) (xy 99.455686 -273.131278) (xy 99.506981 -273.123153)
			(xy 99.558915 -273.123153) (xy 99.61021 -273.131278) (xy 99.659603 -273.147326) (xy 99.705877 -273.170904)
			(xy 99.747893 -273.20143) (xy 99.784616 -273.238153) (xy 99.815142 -273.280169) (xy 99.83872 -273.326443)
			(xy 99.854768 -273.375836) (xy 99.862893 -273.427131) (xy 99.863402 -273.453098) (xy 99.862893 -273.479065)
			(xy 100.142803 -273.479065) (xy 100.142803 -273.427131) (xy 100.150928 -273.375836) (xy 100.166976 -273.326443)
			(xy 100.190554 -273.280169) (xy 100.22108 -273.238153) (xy 100.257803 -273.20143) (xy 100.299819 -273.170904)
			(xy 100.346093 -273.147326) (xy 100.395486 -273.131278) (xy 100.446781 -273.123153) (xy 100.498715 -273.123153)
			(xy 100.55001 -273.131278) (xy 100.599403 -273.147326) (xy 100.645677 -273.170904) (xy 100.687693 -273.20143)
			(xy 100.724416 -273.238153) (xy 100.754942 -273.280169) (xy 100.77852 -273.326443) (xy 100.794568 -273.375836)
			(xy 100.802693 -273.427131) (xy 100.803202 -273.453098) (xy 100.802693 -273.479065) (xy 101.082349 -273.479065)
			(xy 101.082349 -273.427131) (xy 101.090474 -273.375836) (xy 101.106522 -273.326443) (xy 101.1301 -273.280169)
			(xy 101.160626 -273.238153) (xy 101.197349 -273.20143) (xy 101.239365 -273.170904) (xy 101.285639 -273.147326)
			(xy 101.335032 -273.131278) (xy 101.386327 -273.123153) (xy 101.438261 -273.123153) (xy 101.489556 -273.131278)
			(xy 101.538949 -273.147326) (xy 101.585223 -273.170904) (xy 101.627239 -273.20143) (xy 101.663962 -273.238153)
			(xy 101.694488 -273.280169) (xy 101.718066 -273.326443) (xy 101.734114 -273.375836) (xy 101.742239 -273.427131)
			(xy 101.742748 -273.453098) (xy 101.742239 -273.479065) (xy 102.022403 -273.479065) (xy 102.022403 -273.427131)
			(xy 102.030528 -273.375836) (xy 102.046576 -273.326443) (xy 102.070154 -273.280169) (xy 102.10068 -273.238153)
			(xy 102.137403 -273.20143) (xy 102.179419 -273.170904) (xy 102.225693 -273.147326) (xy 102.275086 -273.131278)
			(xy 102.326381 -273.123153) (xy 102.378315 -273.123153) (xy 102.42961 -273.131278) (xy 102.479003 -273.147326)
			(xy 102.525277 -273.170904) (xy 102.567293 -273.20143) (xy 102.604016 -273.238153) (xy 102.634542 -273.280169)
			(xy 102.65812 -273.326443) (xy 102.674168 -273.375836) (xy 102.682293 -273.427131) (xy 102.682802 -273.453098)
			(xy 102.682293 -273.479065) (xy 102.961949 -273.479065) (xy 102.961949 -273.427131) (xy 102.970074 -273.375836)
			(xy 102.986122 -273.326443) (xy 103.0097 -273.280169) (xy 103.040226 -273.238153) (xy 103.076949 -273.20143)
			(xy 103.118965 -273.170904) (xy 103.165239 -273.147326) (xy 103.214632 -273.131278) (xy 103.265927 -273.123153)
			(xy 103.317861 -273.123153) (xy 103.369156 -273.131278) (xy 103.418549 -273.147326) (xy 103.464823 -273.170904)
			(xy 103.506839 -273.20143) (xy 103.543562 -273.238153) (xy 103.574088 -273.280169) (xy 103.597666 -273.326443)
			(xy 103.613714 -273.375836) (xy 103.621839 -273.427131) (xy 103.622348 -273.453098) (xy 103.621839 -273.479065)
			(xy 103.902003 -273.479065) (xy 103.902003 -273.427131) (xy 103.910128 -273.375836) (xy 103.926176 -273.326443)
			(xy 103.949754 -273.280169) (xy 103.98028 -273.238153) (xy 104.017003 -273.20143) (xy 104.059019 -273.170904)
			(xy 104.105293 -273.147326) (xy 104.154686 -273.131278) (xy 104.205981 -273.123153) (xy 104.257915 -273.123153)
			(xy 104.30921 -273.131278) (xy 104.358603 -273.147326) (xy 104.404877 -273.170904) (xy 104.446893 -273.20143)
			(xy 104.483616 -273.238153) (xy 104.514142 -273.280169) (xy 104.53772 -273.326443) (xy 104.553768 -273.375836)
			(xy 104.561893 -273.427131) (xy 104.562402 -273.453098) (xy 104.561893 -273.479065) (xy 105.781603 -273.479065)
			(xy 105.781603 -273.427131) (xy 105.789728 -273.375836) (xy 105.805776 -273.326443) (xy 105.829354 -273.280169)
			(xy 105.85988 -273.238153) (xy 105.896603 -273.20143) (xy 105.938619 -273.170904) (xy 105.984893 -273.147326)
			(xy 106.034286 -273.131278) (xy 106.085581 -273.123153) (xy 106.137515 -273.123153) (xy 106.18881 -273.131278)
			(xy 106.238203 -273.147326) (xy 106.284477 -273.170904) (xy 106.326493 -273.20143) (xy 106.363216 -273.238153)
			(xy 106.393742 -273.280169) (xy 106.41732 -273.326443) (xy 106.433368 -273.375836) (xy 106.441493 -273.427131)
			(xy 106.442002 -273.453098) (xy 106.441493 -273.479065) (xy 106.721403 -273.479065) (xy 106.721403 -273.427131)
			(xy 106.729528 -273.375836) (xy 106.745576 -273.326443) (xy 106.769154 -273.280169) (xy 106.79968 -273.238153)
			(xy 106.836403 -273.20143) (xy 106.878419 -273.170904) (xy 106.924693 -273.147326) (xy 106.974086 -273.131278)
			(xy 107.025381 -273.123153) (xy 107.077315 -273.123153) (xy 107.12861 -273.131278) (xy 107.178003 -273.147326)
			(xy 107.224277 -273.170904) (xy 107.266293 -273.20143) (xy 107.303016 -273.238153) (xy 107.333542 -273.280169)
			(xy 107.35712 -273.326443) (xy 107.373168 -273.375836) (xy 107.381293 -273.427131) (xy 107.381802 -273.453098)
			(xy 107.381293 -273.479065) (xy 107.661203 -273.479065) (xy 107.661203 -273.427131) (xy 107.669328 -273.375836)
			(xy 107.685376 -273.326443) (xy 107.708954 -273.280169) (xy 107.73948 -273.238153) (xy 107.776203 -273.20143)
			(xy 107.818219 -273.170904) (xy 107.864493 -273.147326) (xy 107.913886 -273.131278) (xy 107.965181 -273.123153)
			(xy 108.017115 -273.123153) (xy 108.06841 -273.131278) (xy 108.117803 -273.147326) (xy 108.164077 -273.170904)
			(xy 108.206093 -273.20143) (xy 108.242816 -273.238153) (xy 108.273342 -273.280169) (xy 108.29692 -273.326443)
			(xy 108.312968 -273.375836) (xy 108.321093 -273.427131) (xy 108.321602 -273.453098) (xy 108.321093 -273.479065)
			(xy 108.312968 -273.53036) (xy 108.29692 -273.579753) (xy 108.273342 -273.626027) (xy 108.242816 -273.668043)
			(xy 108.206093 -273.704766) (xy 108.164077 -273.735292) (xy 108.117803 -273.75887) (xy 108.06841 -273.774918)
			(xy 108.017115 -273.783043) (xy 107.965181 -273.783043) (xy 107.913886 -273.774918) (xy 107.864493 -273.75887)
			(xy 107.818219 -273.735292) (xy 107.776203 -273.704766) (xy 107.73948 -273.668043) (xy 107.708954 -273.626027)
			(xy 107.685376 -273.579753) (xy 107.669328 -273.53036) (xy 107.661203 -273.479065) (xy 107.381293 -273.479065)
			(xy 107.373168 -273.53036) (xy 107.35712 -273.579753) (xy 107.333542 -273.626027) (xy 107.303016 -273.668043)
			(xy 107.266293 -273.704766) (xy 107.224277 -273.735292) (xy 107.178003 -273.75887) (xy 107.12861 -273.774918)
			(xy 107.077315 -273.783043) (xy 107.025381 -273.783043) (xy 106.974086 -273.774918) (xy 106.924693 -273.75887)
			(xy 106.878419 -273.735292) (xy 106.836403 -273.704766) (xy 106.79968 -273.668043) (xy 106.769154 -273.626027)
			(xy 106.745576 -273.579753) (xy 106.729528 -273.53036) (xy 106.721403 -273.479065) (xy 106.441493 -273.479065)
			(xy 106.433368 -273.53036) (xy 106.41732 -273.579753) (xy 106.393742 -273.626027) (xy 106.363216 -273.668043)
			(xy 106.326493 -273.704766) (xy 106.284477 -273.735292) (xy 106.238203 -273.75887) (xy 106.18881 -273.774918)
			(xy 106.137515 -273.783043) (xy 106.085581 -273.783043) (xy 106.034286 -273.774918) (xy 105.984893 -273.75887)
			(xy 105.938619 -273.735292) (xy 105.896603 -273.704766) (xy 105.85988 -273.668043) (xy 105.829354 -273.626027)
			(xy 105.805776 -273.579753) (xy 105.789728 -273.53036) (xy 105.781603 -273.479065) (xy 104.561893 -273.479065)
			(xy 104.553768 -273.53036) (xy 104.53772 -273.579753) (xy 104.514142 -273.626027) (xy 104.483616 -273.668043)
			(xy 104.446893 -273.704766) (xy 104.404877 -273.735292) (xy 104.358603 -273.75887) (xy 104.30921 -273.774918)
			(xy 104.257915 -273.783043) (xy 104.205981 -273.783043) (xy 104.154686 -273.774918) (xy 104.105293 -273.75887)
			(xy 104.059019 -273.735292) (xy 104.017003 -273.704766) (xy 103.98028 -273.668043) (xy 103.949754 -273.626027)
			(xy 103.926176 -273.579753) (xy 103.910128 -273.53036) (xy 103.902003 -273.479065) (xy 103.621839 -273.479065)
			(xy 103.613714 -273.53036) (xy 103.597666 -273.579753) (xy 103.574088 -273.626027) (xy 103.543562 -273.668043)
			(xy 103.506839 -273.704766) (xy 103.464823 -273.735292) (xy 103.418549 -273.75887) (xy 103.369156 -273.774918)
			(xy 103.317861 -273.783043) (xy 103.265927 -273.783043) (xy 103.214632 -273.774918) (xy 103.165239 -273.75887)
			(xy 103.118965 -273.735292) (xy 103.076949 -273.704766) (xy 103.040226 -273.668043) (xy 103.0097 -273.626027)
			(xy 102.986122 -273.579753) (xy 102.970074 -273.53036) (xy 102.961949 -273.479065) (xy 102.682293 -273.479065)
			(xy 102.674168 -273.53036) (xy 102.65812 -273.579753) (xy 102.634542 -273.626027) (xy 102.604016 -273.668043)
			(xy 102.567293 -273.704766) (xy 102.525277 -273.735292) (xy 102.479003 -273.75887) (xy 102.42961 -273.774918)
			(xy 102.378315 -273.783043) (xy 102.326381 -273.783043) (xy 102.275086 -273.774918) (xy 102.225693 -273.75887)
			(xy 102.179419 -273.735292) (xy 102.137403 -273.704766) (xy 102.10068 -273.668043) (xy 102.070154 -273.626027)
			(xy 102.046576 -273.579753) (xy 102.030528 -273.53036) (xy 102.022403 -273.479065) (xy 101.742239 -273.479065)
			(xy 101.734114 -273.53036) (xy 101.718066 -273.579753) (xy 101.694488 -273.626027) (xy 101.663962 -273.668043)
			(xy 101.627239 -273.704766) (xy 101.585223 -273.735292) (xy 101.538949 -273.75887) (xy 101.489556 -273.774918)
			(xy 101.438261 -273.783043) (xy 101.386327 -273.783043) (xy 101.335032 -273.774918) (xy 101.285639 -273.75887)
			(xy 101.239365 -273.735292) (xy 101.197349 -273.704766) (xy 101.160626 -273.668043) (xy 101.1301 -273.626027)
			(xy 101.106522 -273.579753) (xy 101.090474 -273.53036) (xy 101.082349 -273.479065) (xy 100.802693 -273.479065)
			(xy 100.794568 -273.53036) (xy 100.77852 -273.579753) (xy 100.754942 -273.626027) (xy 100.724416 -273.668043)
			(xy 100.687693 -273.704766) (xy 100.645677 -273.735292) (xy 100.599403 -273.75887) (xy 100.55001 -273.774918)
			(xy 100.498715 -273.783043) (xy 100.446781 -273.783043) (xy 100.395486 -273.774918) (xy 100.346093 -273.75887)
			(xy 100.299819 -273.735292) (xy 100.257803 -273.704766) (xy 100.22108 -273.668043) (xy 100.190554 -273.626027)
			(xy 100.166976 -273.579753) (xy 100.150928 -273.53036) (xy 100.142803 -273.479065) (xy 99.862893 -273.479065)
			(xy 99.854768 -273.53036) (xy 99.83872 -273.579753) (xy 99.815142 -273.626027) (xy 99.784616 -273.668043)
			(xy 99.747893 -273.704766) (xy 99.705877 -273.735292) (xy 99.659603 -273.75887) (xy 99.61021 -273.774918)
			(xy 99.558915 -273.783043) (xy 99.506981 -273.783043) (xy 99.455686 -273.774918) (xy 99.406293 -273.75887)
			(xy 99.360019 -273.735292) (xy 99.318003 -273.704766) (xy 99.28128 -273.668043) (xy 99.250754 -273.626027)
			(xy 99.227176 -273.579753) (xy 99.211128 -273.53036) (xy 99.203003 -273.479065) (xy 98.923093 -273.479065)
			(xy 98.914968 -273.53036) (xy 98.89892 -273.579753) (xy 98.875342 -273.626027) (xy 98.844816 -273.668043)
			(xy 98.808093 -273.704766) (xy 98.766077 -273.735292) (xy 98.719803 -273.75887) (xy 98.67041 -273.774918)
			(xy 98.619115 -273.783043) (xy 98.567181 -273.783043) (xy 98.515886 -273.774918) (xy 98.466493 -273.75887)
			(xy 98.420219 -273.735292) (xy 98.378203 -273.704766) (xy 98.34148 -273.668043) (xy 98.310954 -273.626027)
			(xy 98.287376 -273.579753) (xy 98.271328 -273.53036) (xy 98.263203 -273.479065) (xy 97.983293 -273.479065)
			(xy 97.975168 -273.53036) (xy 97.95912 -273.579753) (xy 97.935542 -273.626027) (xy 97.905016 -273.668043)
			(xy 97.868293 -273.704766) (xy 97.826277 -273.735292) (xy 97.780003 -273.75887) (xy 97.73061 -273.774918)
			(xy 97.679315 -273.783043) (xy 97.627381 -273.783043) (xy 97.576086 -273.774918) (xy 97.526693 -273.75887)
			(xy 97.480419 -273.735292) (xy 97.438403 -273.704766) (xy 97.40168 -273.668043) (xy 97.371154 -273.626027)
			(xy 97.347576 -273.579753) (xy 97.331528 -273.53036) (xy 97.323403 -273.479065) (xy 97.043493 -273.479065)
			(xy 97.035368 -273.53036) (xy 97.01932 -273.579753) (xy 96.995742 -273.626027) (xy 96.965216 -273.668043)
			(xy 96.928493 -273.704766) (xy 96.886477 -273.735292) (xy 96.840203 -273.75887) (xy 96.79081 -273.774918)
			(xy 96.739515 -273.783043) (xy 96.687581 -273.783043) (xy 96.636286 -273.774918) (xy 96.586893 -273.75887)
			(xy 96.540619 -273.735292) (xy 96.498603 -273.704766) (xy 96.46188 -273.668043) (xy 96.431354 -273.626027)
			(xy 96.407776 -273.579753) (xy 96.391728 -273.53036) (xy 96.383603 -273.479065) (xy 96.103693 -273.479065)
			(xy 96.095568 -273.53036) (xy 96.07952 -273.579753) (xy 96.055942 -273.626027) (xy 96.025416 -273.668043)
			(xy 95.988693 -273.704766) (xy 95.946677 -273.735292) (xy 95.900403 -273.75887) (xy 95.85101 -273.774918)
			(xy 95.799715 -273.783043) (xy 95.747781 -273.783043) (xy 95.696486 -273.774918) (xy 95.647093 -273.75887)
			(xy 95.600819 -273.735292) (xy 95.558803 -273.704766) (xy 95.52208 -273.668043) (xy 95.491554 -273.626027)
			(xy 95.467976 -273.579753) (xy 95.451928 -273.53036) (xy 95.443803 -273.479065) (xy 95.163639 -273.479065)
			(xy 95.155514 -273.53036) (xy 95.139466 -273.579753) (xy 95.115888 -273.626027) (xy 95.085362 -273.668043)
			(xy 95.048639 -273.704766) (xy 95.006623 -273.735292) (xy 94.960349 -273.75887) (xy 94.910956 -273.774918)
			(xy 94.859661 -273.783043) (xy 94.807727 -273.783043) (xy 94.756432 -273.774918) (xy 94.707039 -273.75887)
			(xy 94.660765 -273.735292) (xy 94.618749 -273.704766) (xy 94.582026 -273.668043) (xy 94.5515 -273.626027)
			(xy 94.527922 -273.579753) (xy 94.511874 -273.53036) (xy 94.503749 -273.479065) (xy 94.224093 -273.479065)
			(xy 94.215968 -273.53036) (xy 94.19992 -273.579753) (xy 94.176342 -273.626027) (xy 94.145816 -273.668043)
			(xy 94.109093 -273.704766) (xy 94.067077 -273.735292) (xy 94.020803 -273.75887) (xy 93.97141 -273.774918)
			(xy 93.920115 -273.783043) (xy 93.868181 -273.783043) (xy 93.816886 -273.774918) (xy 93.767493 -273.75887)
			(xy 93.721219 -273.735292) (xy 93.679203 -273.704766) (xy 93.64248 -273.668043) (xy 93.611954 -273.626027)
			(xy 93.588376 -273.579753) (xy 93.572328 -273.53036) (xy 93.564203 -273.479065) (xy 93.284293 -273.479065)
			(xy 93.276168 -273.53036) (xy 93.26012 -273.579753) (xy 93.236542 -273.626027) (xy 93.206016 -273.668043)
			(xy 93.169293 -273.704766) (xy 93.127277 -273.735292) (xy 93.081003 -273.75887) (xy 93.03161 -273.774918)
			(xy 92.980315 -273.783043) (xy 92.928381 -273.783043) (xy 92.877086 -273.774918) (xy 92.827693 -273.75887)
			(xy 92.781419 -273.735292) (xy 92.739403 -273.704766) (xy 92.70268 -273.668043) (xy 92.672154 -273.626027)
			(xy 92.648576 -273.579753) (xy 92.632528 -273.53036) (xy 92.624403 -273.479065) (xy 92.344701 -273.479065)
			(xy 92.344701 -273.479085) (xy 92.336572 -273.530415) (xy 92.320513 -273.579842) (xy 92.296922 -273.626148)
			(xy 92.266377 -273.668195) (xy 92.229631 -273.704946) (xy 92.187589 -273.735496) (xy 92.141286 -273.759095)
			(xy 92.091862 -273.77516) (xy 92.040533 -273.783297) (xy 92.014548 -273.783806) (xy 91.991674 -273.783423)
			(xy 91.946361 -273.777127) (xy 91.902347 -273.76465) (xy 91.860472 -273.746228) (xy 91.840812 -273.73453)
			(xy 91.840558 -273.734276) (xy 91.83307 -273.730092) (xy 91.816298 -273.726561) (xy 91.799315 -273.728881)
			(xy 91.791536 -273.732498) (xy 91.751658 -273.754596) (xy 91.713304 -273.775932) (xy 91.705724 -273.780573)
			(xy 91.69418 -273.794074) (xy 91.688031 -273.810738) (xy 91.68765 -273.81962) (xy 91.68765 -273.938746)
			(xy 91.712034 -273.981418) (xy 91.722702 -273.988276) (xy 91.743952 -274.002398) (xy 91.782234 -274.036128)
			(xy 91.814877 -274.07534) (xy 91.841108 -274.119103) (xy 91.860301 -274.166376) (xy 91.872002 -274.216038)
			(xy 91.875933 -274.266908) (xy 91.873925 -274.292881) (xy 92.154249 -274.292881) (xy 92.154249 -274.240947)
			(xy 92.162374 -274.189652) (xy 92.178422 -274.140259) (xy 92.202 -274.093985) (xy 92.232526 -274.051969)
			(xy 92.269249 -274.015246) (xy 92.311265 -273.98472) (xy 92.357539 -273.961142) (xy 92.406932 -273.945094)
			(xy 92.458227 -273.936969) (xy 92.510161 -273.936969) (xy 92.561456 -273.945094) (xy 92.610849 -273.961142)
			(xy 92.657123 -273.98472) (xy 92.699139 -274.015246) (xy 92.735862 -274.051969) (xy 92.766388 -274.093985)
			(xy 92.789966 -274.140259) (xy 92.806014 -274.189652) (xy 92.814139 -274.240947) (xy 92.814648 -274.266914)
			(xy 92.814139 -274.292881) (xy 93.094049 -274.292881) (xy 93.094049 -274.240947) (xy 93.102174 -274.189652)
			(xy 93.118222 -274.140259) (xy 93.1418 -274.093985) (xy 93.172326 -274.051969) (xy 93.209049 -274.015246)
			(xy 93.251065 -273.98472) (xy 93.297339 -273.961142) (xy 93.346732 -273.945094) (xy 93.398027 -273.936969)
			(xy 93.449961 -273.936969) (xy 93.501256 -273.945094) (xy 93.550649 -273.961142) (xy 93.596923 -273.98472)
			(xy 93.638939 -274.015246) (xy 93.675662 -274.051969) (xy 93.706188 -274.093985) (xy 93.729766 -274.140259)
			(xy 93.745814 -274.189652) (xy 93.753939 -274.240947) (xy 93.754448 -274.266914) (xy 93.753939 -274.292881)
			(xy 94.033849 -274.292881) (xy 94.033849 -274.240947) (xy 94.041974 -274.189652) (xy 94.058022 -274.140259)
			(xy 94.0816 -274.093985) (xy 94.112126 -274.051969) (xy 94.148849 -274.015246) (xy 94.190865 -273.98472)
			(xy 94.237139 -273.961142) (xy 94.286532 -273.945094) (xy 94.337827 -273.936969) (xy 94.389761 -273.936969)
			(xy 94.441056 -273.945094) (xy 94.490449 -273.961142) (xy 94.536723 -273.98472) (xy 94.578739 -274.015246)
			(xy 94.615462 -274.051969) (xy 94.645988 -274.093985) (xy 94.669566 -274.140259) (xy 94.685614 -274.189652)
			(xy 94.693739 -274.240947) (xy 94.694248 -274.266914) (xy 94.693739 -274.292881) (xy 94.973649 -274.292881)
			(xy 94.973649 -274.240947) (xy 94.981774 -274.189652) (xy 94.997822 -274.140259) (xy 95.0214 -274.093985)
			(xy 95.051926 -274.051969) (xy 95.088649 -274.015246) (xy 95.130665 -273.98472) (xy 95.176939 -273.961142)
			(xy 95.226332 -273.945094) (xy 95.277627 -273.936969) (xy 95.329561 -273.936969) (xy 95.380856 -273.945094)
			(xy 95.430249 -273.961142) (xy 95.476523 -273.98472) (xy 95.518539 -274.015246) (xy 95.555262 -274.051969)
			(xy 95.585788 -274.093985) (xy 95.609366 -274.140259) (xy 95.625414 -274.189652) (xy 95.633539 -274.240947)
			(xy 95.634048 -274.266914) (xy 95.633539 -274.292881) (xy 95.913449 -274.292881) (xy 95.913449 -274.240947)
			(xy 95.921574 -274.189652) (xy 95.937622 -274.140259) (xy 95.9612 -274.093985) (xy 95.991726 -274.051969)
			(xy 96.028449 -274.015246) (xy 96.070465 -273.98472) (xy 96.116739 -273.961142) (xy 96.166132 -273.945094)
			(xy 96.217427 -273.936969) (xy 96.269361 -273.936969) (xy 96.320656 -273.945094) (xy 96.370049 -273.961142)
			(xy 96.416323 -273.98472) (xy 96.458339 -274.015246) (xy 96.495062 -274.051969) (xy 96.525588 -274.093985)
			(xy 96.549166 -274.140259) (xy 96.565214 -274.189652) (xy 96.573339 -274.240947) (xy 96.573848 -274.266914)
			(xy 96.573339 -274.292881) (xy 96.853249 -274.292881) (xy 96.853249 -274.240947) (xy 96.861374 -274.189652)
			(xy 96.877422 -274.140259) (xy 96.901 -274.093985) (xy 96.931526 -274.051969) (xy 96.968249 -274.015246)
			(xy 97.010265 -273.98472) (xy 97.056539 -273.961142) (xy 97.105932 -273.945094) (xy 97.157227 -273.936969)
			(xy 97.209161 -273.936969) (xy 97.260456 -273.945094) (xy 97.309849 -273.961142) (xy 97.356123 -273.98472)
			(xy 97.398139 -274.015246) (xy 97.434862 -274.051969) (xy 97.465388 -274.093985) (xy 97.488966 -274.140259)
			(xy 97.505014 -274.189652) (xy 97.513139 -274.240947) (xy 97.513648 -274.266914) (xy 97.513139 -274.292881)
			(xy 97.793049 -274.292881) (xy 97.793049 -274.240947) (xy 97.801174 -274.189652) (xy 97.817222 -274.140259)
			(xy 97.8408 -274.093985) (xy 97.871326 -274.051969) (xy 97.908049 -274.015246) (xy 97.950065 -273.98472)
			(xy 97.996339 -273.961142) (xy 98.045732 -273.945094) (xy 98.097027 -273.936969) (xy 98.148961 -273.936969)
			(xy 98.200256 -273.945094) (xy 98.249649 -273.961142) (xy 98.295923 -273.98472) (xy 98.337939 -274.015246)
			(xy 98.374662 -274.051969) (xy 98.405188 -274.093985) (xy 98.428766 -274.140259) (xy 98.444814 -274.189652)
			(xy 98.452939 -274.240947) (xy 98.453448 -274.266914) (xy 98.452939 -274.292881) (xy 98.732849 -274.292881)
			(xy 98.732849 -274.240947) (xy 98.740974 -274.189652) (xy 98.757022 -274.140259) (xy 98.7806 -274.093985)
			(xy 98.811126 -274.051969) (xy 98.847849 -274.015246) (xy 98.889865 -273.98472) (xy 98.936139 -273.961142)
			(xy 98.985532 -273.945094) (xy 99.036827 -273.936969) (xy 99.088761 -273.936969) (xy 99.140056 -273.945094)
			(xy 99.189449 -273.961142) (xy 99.235723 -273.98472) (xy 99.277739 -274.015246) (xy 99.314462 -274.051969)
			(xy 99.344988 -274.093985) (xy 99.368566 -274.140259) (xy 99.384614 -274.189652) (xy 99.392739 -274.240947)
			(xy 99.393248 -274.266914) (xy 99.392739 -274.292881) (xy 99.672649 -274.292881) (xy 99.672649 -274.240947)
			(xy 99.680774 -274.189652) (xy 99.696822 -274.140259) (xy 99.7204 -274.093985) (xy 99.750926 -274.051969)
			(xy 99.787649 -274.015246) (xy 99.829665 -273.98472) (xy 99.875939 -273.961142) (xy 99.925332 -273.945094)
			(xy 99.976627 -273.936969) (xy 100.028561 -273.936969) (xy 100.079856 -273.945094) (xy 100.129249 -273.961142)
			(xy 100.175523 -273.98472) (xy 100.217539 -274.015246) (xy 100.254262 -274.051969) (xy 100.284788 -274.093985)
			(xy 100.308366 -274.140259) (xy 100.324414 -274.189652) (xy 100.332539 -274.240947) (xy 100.333048 -274.266914)
			(xy 100.332539 -274.292881) (xy 100.612449 -274.292881) (xy 100.612449 -274.240947) (xy 100.620574 -274.189652)
			(xy 100.636622 -274.140259) (xy 100.6602 -274.093985) (xy 100.690726 -274.051969) (xy 100.727449 -274.015246)
			(xy 100.769465 -273.98472) (xy 100.815739 -273.961142) (xy 100.865132 -273.945094) (xy 100.916427 -273.936969)
			(xy 100.968361 -273.936969) (xy 101.019656 -273.945094) (xy 101.069049 -273.961142) (xy 101.115323 -273.98472)
			(xy 101.157339 -274.015246) (xy 101.194062 -274.051969) (xy 101.224588 -274.093985) (xy 101.248166 -274.140259)
			(xy 101.264214 -274.189652) (xy 101.272339 -274.240947) (xy 101.272848 -274.266914) (xy 101.272339 -274.292881)
			(xy 101.552249 -274.292881) (xy 101.552249 -274.240947) (xy 101.560374 -274.189652) (xy 101.576422 -274.140259)
			(xy 101.6 -274.093985) (xy 101.630526 -274.051969) (xy 101.667249 -274.015246) (xy 101.709265 -273.98472)
			(xy 101.755539 -273.961142) (xy 101.804932 -273.945094) (xy 101.856227 -273.936969) (xy 101.908161 -273.936969)
			(xy 101.959456 -273.945094) (xy 102.008849 -273.961142) (xy 102.055123 -273.98472) (xy 102.097139 -274.015246)
			(xy 102.133862 -274.051969) (xy 102.164388 -274.093985) (xy 102.187966 -274.140259) (xy 102.204014 -274.189652)
			(xy 102.212139 -274.240947) (xy 102.212648 -274.266914) (xy 102.212139 -274.292881) (xy 102.492049 -274.292881)
			(xy 102.492049 -274.240947) (xy 102.500174 -274.189652) (xy 102.516222 -274.140259) (xy 102.5398 -274.093985)
			(xy 102.570326 -274.051969) (xy 102.607049 -274.015246) (xy 102.649065 -273.98472) (xy 102.695339 -273.961142)
			(xy 102.744732 -273.945094) (xy 102.796027 -273.936969) (xy 102.847961 -273.936969) (xy 102.899256 -273.945094)
			(xy 102.948649 -273.961142) (xy 102.994923 -273.98472) (xy 103.036939 -274.015246) (xy 103.073662 -274.051969)
			(xy 103.104188 -274.093985) (xy 103.127766 -274.140259) (xy 103.143814 -274.189652) (xy 103.151939 -274.240947)
			(xy 103.152448 -274.266914) (xy 103.43134 -274.266914) (xy 103.431849 -274.240947) (xy 103.439974 -274.189652)
			(xy 103.456022 -274.140259) (xy 103.4796 -274.093985) (xy 103.510126 -274.051969) (xy 103.546849 -274.015246)
			(xy 103.588865 -273.98472) (xy 103.635139 -273.961142) (xy 103.684532 -273.945094) (xy 103.735827 -273.936969)
			(xy 103.787761 -273.936969) (xy 103.839056 -273.945094) (xy 103.888449 -273.961142) (xy 103.934723 -273.98472)
			(xy 103.976739 -274.015246) (xy 104.013462 -274.051969) (xy 104.043988 -274.093985) (xy 104.067566 -274.140259)
			(xy 104.083614 -274.189652) (xy 104.091739 -274.240947) (xy 104.092248 -274.266914) (xy 104.092248 -274.267168)
			(xy 104.091707 -274.292881) (xy 104.371649 -274.292881) (xy 104.371649 -274.240947) (xy 104.379774 -274.189652)
			(xy 104.395822 -274.140259) (xy 104.4194 -274.093985) (xy 104.449926 -274.051969) (xy 104.486649 -274.015246)
			(xy 104.528665 -273.98472) (xy 104.574939 -273.961142) (xy 104.624332 -273.945094) (xy 104.675627 -273.936969)
			(xy 104.727561 -273.936969) (xy 104.778856 -273.945094) (xy 104.828249 -273.961142) (xy 104.874523 -273.98472)
			(xy 104.916539 -274.015246) (xy 104.953262 -274.051969) (xy 104.983788 -274.093985) (xy 105.007366 -274.140259)
			(xy 105.023414 -274.189652) (xy 105.031539 -274.240947) (xy 105.032048 -274.266914) (xy 105.031539 -274.292881)
			(xy 106.251249 -274.292881) (xy 106.251249 -274.240947) (xy 106.259374 -274.189652) (xy 106.275422 -274.140259)
			(xy 106.299 -274.093985) (xy 106.329526 -274.051969) (xy 106.366249 -274.015246) (xy 106.408265 -273.98472)
			(xy 106.454539 -273.961142) (xy 106.503932 -273.945094) (xy 106.555227 -273.936969) (xy 106.607161 -273.936969)
			(xy 106.658456 -273.945094) (xy 106.707849 -273.961142) (xy 106.754123 -273.98472) (xy 106.796139 -274.015246)
			(xy 106.832862 -274.051969) (xy 106.863388 -274.093985) (xy 106.886966 -274.140259) (xy 106.903014 -274.189652)
			(xy 106.911139 -274.240947) (xy 106.911648 -274.266914) (xy 106.911139 -274.292881) (xy 106.903014 -274.344176)
			(xy 106.886966 -274.393569) (xy 106.863388 -274.439843) (xy 106.832862 -274.481859) (xy 106.796139 -274.518582)
			(xy 106.754123 -274.549108) (xy 106.707849 -274.572686) (xy 106.658456 -274.588734) (xy 106.607161 -274.596859)
			(xy 106.555227 -274.596859) (xy 106.503932 -274.588734) (xy 106.454539 -274.572686) (xy 106.408265 -274.549108)
			(xy 106.366249 -274.518582) (xy 106.329526 -274.481859) (xy 106.299 -274.439843) (xy 106.275422 -274.393569)
			(xy 106.259374 -274.344176) (xy 106.251249 -274.292881) (xy 105.031539 -274.292881) (xy 105.023414 -274.344176)
			(xy 105.007366 -274.393569) (xy 104.983788 -274.439843) (xy 104.953262 -274.481859) (xy 104.916539 -274.518582)
			(xy 104.874523 -274.549108) (xy 104.828249 -274.572686) (xy 104.778856 -274.588734) (xy 104.727561 -274.596859)
			(xy 104.675627 -274.596859) (xy 104.624332 -274.588734) (xy 104.574939 -274.572686) (xy 104.528665 -274.549108)
			(xy 104.486649 -274.518582) (xy 104.449926 -274.481859) (xy 104.4194 -274.439843) (xy 104.395822 -274.393569)
			(xy 104.379774 -274.344176) (xy 104.371649 -274.292881) (xy 104.091707 -274.292881) (xy 104.091664 -274.294949)
			(xy 104.082349 -274.349725) (xy 104.073706 -274.376134) (xy 104.065832 -274.398232) (xy 104.269794 -274.751546)
			(xy 104.292908 -274.755864) (xy 104.317824 -274.761057) (xy 104.365808 -274.778017) (xy 104.410626 -274.80213)
			(xy 104.45122 -274.832827) (xy 104.486629 -274.869382) (xy 104.516019 -274.910931) (xy 104.538694 -274.956494)
			(xy 104.554118 -275.004993) (xy 104.561928 -275.055284) (xy 104.562402 -275.08073) (xy 104.561893 -275.106697)
			(xy 104.553768 -275.157992) (xy 104.53772 -275.207385) (xy 104.514142 -275.253659) (xy 104.483616 -275.295675)
			(xy 104.446893 -275.332398) (xy 104.404877 -275.362924) (xy 104.358603 -275.386502) (xy 104.30921 -275.40255)
			(xy 104.257915 -275.410675) (xy 104.205981 -275.410675) (xy 104.154686 -275.40255) (xy 104.105293 -275.386502)
			(xy 104.059019 -275.362924) (xy 104.017003 -275.332398) (xy 103.98028 -275.295675) (xy 103.949754 -275.253659)
			(xy 103.926176 -275.207385) (xy 103.910128 -275.157992) (xy 103.902003 -275.106697) (xy 103.901494 -275.08073)
			(xy 103.902054 -275.052745) (xy 103.911499 -274.997577) (xy 103.92029 -274.971002) (xy 103.92791 -274.948904)
			(xy 103.724202 -274.596098) (xy 103.701342 -274.59178) (xy 103.676384 -274.586659) (xy 103.628321 -274.569761)
			(xy 103.58342 -274.545687) (xy 103.542746 -274.515007) (xy 103.507263 -274.478448) (xy 103.477811 -274.436877)
			(xy 103.455088 -274.391277) (xy 103.439633 -274.342731) (xy 103.431812 -274.292388) (xy 103.43134 -274.266914)
			(xy 103.152448 -274.266914) (xy 103.151939 -274.292881) (xy 103.143814 -274.344176) (xy 103.127766 -274.393569)
			(xy 103.104188 -274.439843) (xy 103.073662 -274.481859) (xy 103.036939 -274.518582) (xy 102.994923 -274.549108)
			(xy 102.948649 -274.572686) (xy 102.899256 -274.588734) (xy 102.847961 -274.596859) (xy 102.796027 -274.596859)
			(xy 102.744732 -274.588734) (xy 102.695339 -274.572686) (xy 102.649065 -274.549108) (xy 102.607049 -274.518582)
			(xy 102.570326 -274.481859) (xy 102.5398 -274.439843) (xy 102.516222 -274.393569) (xy 102.500174 -274.344176)
			(xy 102.492049 -274.292881) (xy 102.212139 -274.292881) (xy 102.204014 -274.344176) (xy 102.187966 -274.393569)
			(xy 102.164388 -274.439843) (xy 102.133862 -274.481859) (xy 102.097139 -274.518582) (xy 102.055123 -274.549108)
			(xy 102.008849 -274.572686) (xy 101.959456 -274.588734) (xy 101.908161 -274.596859) (xy 101.856227 -274.596859)
			(xy 101.804932 -274.588734) (xy 101.755539 -274.572686) (xy 101.709265 -274.549108) (xy 101.667249 -274.518582)
			(xy 101.630526 -274.481859) (xy 101.6 -274.439843) (xy 101.576422 -274.393569) (xy 101.560374 -274.344176)
			(xy 101.552249 -274.292881) (xy 101.272339 -274.292881) (xy 101.264214 -274.344176) (xy 101.248166 -274.393569)
			(xy 101.224588 -274.439843) (xy 101.194062 -274.481859) (xy 101.157339 -274.518582) (xy 101.115323 -274.549108)
			(xy 101.069049 -274.572686) (xy 101.019656 -274.588734) (xy 100.968361 -274.596859) (xy 100.916427 -274.596859)
			(xy 100.865132 -274.588734) (xy 100.815739 -274.572686) (xy 100.769465 -274.549108) (xy 100.727449 -274.518582)
			(xy 100.690726 -274.481859) (xy 100.6602 -274.439843) (xy 100.636622 -274.393569) (xy 100.620574 -274.344176)
			(xy 100.612449 -274.292881) (xy 100.332539 -274.292881) (xy 100.324414 -274.344176) (xy 100.308366 -274.393569)
			(xy 100.284788 -274.439843) (xy 100.254262 -274.481859) (xy 100.217539 -274.518582) (xy 100.175523 -274.549108)
			(xy 100.129249 -274.572686) (xy 100.079856 -274.588734) (xy 100.028561 -274.596859) (xy 99.976627 -274.596859)
			(xy 99.925332 -274.588734) (xy 99.875939 -274.572686) (xy 99.829665 -274.549108) (xy 99.787649 -274.518582)
			(xy 99.750926 -274.481859) (xy 99.7204 -274.439843) (xy 99.696822 -274.393569) (xy 99.680774 -274.344176)
			(xy 99.672649 -274.292881) (xy 99.392739 -274.292881) (xy 99.384614 -274.344176) (xy 99.368566 -274.393569)
			(xy 99.344988 -274.439843) (xy 99.314462 -274.481859) (xy 99.277739 -274.518582) (xy 99.235723 -274.549108)
			(xy 99.189449 -274.572686) (xy 99.140056 -274.588734) (xy 99.088761 -274.596859) (xy 99.036827 -274.596859)
			(xy 98.985532 -274.588734) (xy 98.936139 -274.572686) (xy 98.889865 -274.549108) (xy 98.847849 -274.518582)
			(xy 98.811126 -274.481859) (xy 98.7806 -274.439843) (xy 98.757022 -274.393569) (xy 98.740974 -274.344176)
			(xy 98.732849 -274.292881) (xy 98.452939 -274.292881) (xy 98.444814 -274.344176) (xy 98.428766 -274.393569)
			(xy 98.405188 -274.439843) (xy 98.374662 -274.481859) (xy 98.337939 -274.518582) (xy 98.295923 -274.549108)
			(xy 98.249649 -274.572686) (xy 98.200256 -274.588734) (xy 98.148961 -274.596859) (xy 98.097027 -274.596859)
			(xy 98.045732 -274.588734) (xy 97.996339 -274.572686) (xy 97.950065 -274.549108) (xy 97.908049 -274.518582)
			(xy 97.871326 -274.481859) (xy 97.8408 -274.439843) (xy 97.817222 -274.393569) (xy 97.801174 -274.344176)
			(xy 97.793049 -274.292881) (xy 97.513139 -274.292881) (xy 97.505014 -274.344176) (xy 97.488966 -274.393569)
			(xy 97.465388 -274.439843) (xy 97.434862 -274.481859) (xy 97.398139 -274.518582) (xy 97.356123 -274.549108)
			(xy 97.309849 -274.572686) (xy 97.260456 -274.588734) (xy 97.209161 -274.596859) (xy 97.157227 -274.596859)
			(xy 97.105932 -274.588734) (xy 97.056539 -274.572686) (xy 97.010265 -274.549108) (xy 96.968249 -274.518582)
			(xy 96.931526 -274.481859) (xy 96.901 -274.439843) (xy 96.877422 -274.393569) (xy 96.861374 -274.344176)
			(xy 96.853249 -274.292881) (xy 96.573339 -274.292881) (xy 96.565214 -274.344176) (xy 96.549166 -274.393569)
			(xy 96.525588 -274.439843) (xy 96.495062 -274.481859) (xy 96.458339 -274.518582) (xy 96.416323 -274.549108)
			(xy 96.370049 -274.572686) (xy 96.320656 -274.588734) (xy 96.269361 -274.596859) (xy 96.217427 -274.596859)
			(xy 96.166132 -274.588734) (xy 96.116739 -274.572686) (xy 96.070465 -274.549108) (xy 96.028449 -274.518582)
			(xy 95.991726 -274.481859) (xy 95.9612 -274.439843) (xy 95.937622 -274.393569) (xy 95.921574 -274.344176)
			(xy 95.913449 -274.292881) (xy 95.633539 -274.292881) (xy 95.625414 -274.344176) (xy 95.609366 -274.393569)
			(xy 95.585788 -274.439843) (xy 95.555262 -274.481859) (xy 95.518539 -274.518582) (xy 95.476523 -274.549108)
			(xy 95.430249 -274.572686) (xy 95.380856 -274.588734) (xy 95.329561 -274.596859) (xy 95.277627 -274.596859)
			(xy 95.226332 -274.588734) (xy 95.176939 -274.572686) (xy 95.130665 -274.549108) (xy 95.088649 -274.518582)
			(xy 95.051926 -274.481859) (xy 95.0214 -274.439843) (xy 94.997822 -274.393569) (xy 94.981774 -274.344176)
			(xy 94.973649 -274.292881) (xy 94.693739 -274.292881) (xy 94.685614 -274.344176) (xy 94.669566 -274.393569)
			(xy 94.645988 -274.439843) (xy 94.615462 -274.481859) (xy 94.578739 -274.518582) (xy 94.536723 -274.549108)
			(xy 94.490449 -274.572686) (xy 94.441056 -274.588734) (xy 94.389761 -274.596859) (xy 94.337827 -274.596859)
			(xy 94.286532 -274.588734) (xy 94.237139 -274.572686) (xy 94.190865 -274.549108) (xy 94.148849 -274.518582)
			(xy 94.112126 -274.481859) (xy 94.0816 -274.439843) (xy 94.058022 -274.393569) (xy 94.041974 -274.344176)
			(xy 94.033849 -274.292881) (xy 93.753939 -274.292881) (xy 93.745814 -274.344176) (xy 93.729766 -274.393569)
			(xy 93.706188 -274.439843) (xy 93.675662 -274.481859) (xy 93.638939 -274.518582) (xy 93.596923 -274.549108)
			(xy 93.550649 -274.572686) (xy 93.501256 -274.588734) (xy 93.449961 -274.596859) (xy 93.398027 -274.596859)
			(xy 93.346732 -274.588734) (xy 93.297339 -274.572686) (xy 93.251065 -274.549108) (xy 93.209049 -274.518582)
			(xy 93.172326 -274.481859) (xy 93.1418 -274.439843) (xy 93.118222 -274.393569) (xy 93.102174 -274.344176)
			(xy 93.094049 -274.292881) (xy 92.814139 -274.292881) (xy 92.806014 -274.344176) (xy 92.789966 -274.393569)
			(xy 92.766388 -274.439843) (xy 92.735862 -274.481859) (xy 92.699139 -274.518582) (xy 92.657123 -274.549108)
			(xy 92.610849 -274.572686) (xy 92.561456 -274.588734) (xy 92.510161 -274.596859) (xy 92.458227 -274.596859)
			(xy 92.406932 -274.588734) (xy 92.357539 -274.572686) (xy 92.311265 -274.549108) (xy 92.269249 -274.518582)
			(xy 92.232526 -274.481859) (xy 92.202 -274.439843) (xy 92.178422 -274.393569) (xy 92.162374 -274.344176)
			(xy 92.154249 -274.292881) (xy 91.873925 -274.292881) (xy 91.872 -274.317777) (xy 91.860297 -274.367438)
			(xy 91.841101 -274.414711) (xy 91.814869 -274.458472) (xy 91.782223 -274.497683) (xy 91.74394 -274.531411)
			(xy 91.722702 -274.545552) (xy 91.712034 -274.55241) (xy 91.68765 -274.595082) (xy 91.68765 -274.713954)
			(xy 91.687997 -274.722843) (xy 91.694144 -274.739524) (xy 91.705693 -274.75304) (xy 91.713304 -274.757642)
			(xy 91.790012 -274.800314) (xy 91.795735 -274.803274) (xy 91.808209 -274.806479) (xy 91.81465 -274.806664)
			(xy 91.840304 -274.799298) (xy 91.845892 -274.795996) (xy 91.871546 -274.781578) (xy 91.926703 -274.761082)
			(xy 91.984619 -274.750682) (xy 92.01404 -274.750022) (xy 92.014294 -274.750022) (xy 92.040281 -274.750505)
			(xy 92.091616 -274.758634) (xy 92.141047 -274.774695) (xy 92.187357 -274.79829) (xy 92.229405 -274.828839)
			(xy 92.266157 -274.86559) (xy 92.296707 -274.907638) (xy 92.320303 -274.953948) (xy 92.336364 -275.003378)
			(xy 92.344495 -275.054713) (xy 92.344495 -275.106687) (xy 92.344493 -275.106697) (xy 92.624403 -275.106697)
			(xy 92.624403 -275.054763) (xy 92.632528 -275.003468) (xy 92.648576 -274.954075) (xy 92.672154 -274.907801)
			(xy 92.70268 -274.865785) (xy 92.739403 -274.829062) (xy 92.781419 -274.798536) (xy 92.827693 -274.774958)
			(xy 92.877086 -274.75891) (xy 92.928381 -274.750785) (xy 92.980315 -274.750785) (xy 93.03161 -274.75891)
			(xy 93.081003 -274.774958) (xy 93.127277 -274.798536) (xy 93.169293 -274.829062) (xy 93.206016 -274.865785)
			(xy 93.236542 -274.907801) (xy 93.26012 -274.954075) (xy 93.276168 -275.003468) (xy 93.284293 -275.054763)
			(xy 93.284802 -275.08073) (xy 93.284293 -275.106697) (xy 93.564203 -275.106697) (xy 93.564203 -275.054763)
			(xy 93.572328 -275.003468) (xy 93.588376 -274.954075) (xy 93.611954 -274.907801) (xy 93.64248 -274.865785)
			(xy 93.679203 -274.829062) (xy 93.721219 -274.798536) (xy 93.767493 -274.774958) (xy 93.816886 -274.75891)
			(xy 93.868181 -274.750785) (xy 93.920115 -274.750785) (xy 93.97141 -274.75891) (xy 94.020803 -274.774958)
			(xy 94.067077 -274.798536) (xy 94.109093 -274.829062) (xy 94.145816 -274.865785) (xy 94.176342 -274.907801)
			(xy 94.19992 -274.954075) (xy 94.215968 -275.003468) (xy 94.224093 -275.054763) (xy 94.224602 -275.08073)
			(xy 94.224093 -275.106697) (xy 94.504003 -275.106697) (xy 94.504003 -275.054763) (xy 94.512128 -275.003468)
			(xy 94.528176 -274.954075) (xy 94.551754 -274.907801) (xy 94.58228 -274.865785) (xy 94.619003 -274.829062)
			(xy 94.661019 -274.798536) (xy 94.707293 -274.774958) (xy 94.756686 -274.75891) (xy 94.807981 -274.750785)
			(xy 94.859915 -274.750785) (xy 94.91121 -274.75891) (xy 94.960603 -274.774958) (xy 95.006877 -274.798536)
			(xy 95.048893 -274.829062) (xy 95.085616 -274.865785) (xy 95.116142 -274.907801) (xy 95.13972 -274.954075)
			(xy 95.155768 -275.003468) (xy 95.163893 -275.054763) (xy 95.164402 -275.08073) (xy 95.163893 -275.106697)
			(xy 95.443803 -275.106697) (xy 95.443803 -275.054763) (xy 95.451928 -275.003468) (xy 95.467976 -274.954075)
			(xy 95.491554 -274.907801) (xy 95.52208 -274.865785) (xy 95.558803 -274.829062) (xy 95.600819 -274.798536)
			(xy 95.647093 -274.774958) (xy 95.696486 -274.75891) (xy 95.747781 -274.750785) (xy 95.799715 -274.750785)
			(xy 95.85101 -274.75891) (xy 95.900403 -274.774958) (xy 95.946677 -274.798536) (xy 95.988693 -274.829062)
			(xy 96.025416 -274.865785) (xy 96.055942 -274.907801) (xy 96.07952 -274.954075) (xy 96.095568 -275.003468)
			(xy 96.103693 -275.054763) (xy 96.104202 -275.08073) (xy 96.103693 -275.106697) (xy 96.383603 -275.106697)
			(xy 96.383603 -275.054763) (xy 96.391728 -275.003468) (xy 96.407776 -274.954075) (xy 96.431354 -274.907801)
			(xy 96.46188 -274.865785) (xy 96.498603 -274.829062) (xy 96.540619 -274.798536) (xy 96.586893 -274.774958)
			(xy 96.636286 -274.75891) (xy 96.687581 -274.750785) (xy 96.739515 -274.750785) (xy 96.79081 -274.75891)
			(xy 96.840203 -274.774958) (xy 96.886477 -274.798536) (xy 96.928493 -274.829062) (xy 96.965216 -274.865785)
			(xy 96.995742 -274.907801) (xy 97.01932 -274.954075) (xy 97.035368 -275.003468) (xy 97.043493 -275.054763)
			(xy 97.044002 -275.08073) (xy 97.043493 -275.106697) (xy 97.323403 -275.106697) (xy 97.323403 -275.054763)
			(xy 97.331528 -275.003468) (xy 97.347576 -274.954075) (xy 97.371154 -274.907801) (xy 97.40168 -274.865785)
			(xy 97.438403 -274.829062) (xy 97.480419 -274.798536) (xy 97.526693 -274.774958) (xy 97.576086 -274.75891)
			(xy 97.627381 -274.750785) (xy 97.679315 -274.750785) (xy 97.73061 -274.75891) (xy 97.780003 -274.774958)
			(xy 97.826277 -274.798536) (xy 97.868293 -274.829062) (xy 97.905016 -274.865785) (xy 97.935542 -274.907801)
			(xy 97.95912 -274.954075) (xy 97.975168 -275.003468) (xy 97.983293 -275.054763) (xy 97.983802 -275.08073)
			(xy 97.983293 -275.106697) (xy 98.262949 -275.106697) (xy 98.262949 -275.054763) (xy 98.271074 -275.003468)
			(xy 98.287122 -274.954075) (xy 98.3107 -274.907801) (xy 98.341226 -274.865785) (xy 98.377949 -274.829062)
			(xy 98.419965 -274.798536) (xy 98.466239 -274.774958) (xy 98.515632 -274.75891) (xy 98.566927 -274.750785)
			(xy 98.618861 -274.750785) (xy 98.670156 -274.75891) (xy 98.719549 -274.774958) (xy 98.765823 -274.798536)
			(xy 98.807839 -274.829062) (xy 98.844562 -274.865785) (xy 98.875088 -274.907801) (xy 98.898666 -274.954075)
			(xy 98.914714 -275.003468) (xy 98.922839 -275.054763) (xy 98.923348 -275.08073) (xy 98.922839 -275.106697)
			(xy 99.203003 -275.106697) (xy 99.203003 -275.054763) (xy 99.211128 -275.003468) (xy 99.227176 -274.954075)
			(xy 99.250754 -274.907801) (xy 99.28128 -274.865785) (xy 99.318003 -274.829062) (xy 99.360019 -274.798536)
			(xy 99.406293 -274.774958) (xy 99.455686 -274.75891) (xy 99.506981 -274.750785) (xy 99.558915 -274.750785)
			(xy 99.61021 -274.75891) (xy 99.659603 -274.774958) (xy 99.705877 -274.798536) (xy 99.747893 -274.829062)
			(xy 99.784616 -274.865785) (xy 99.815142 -274.907801) (xy 99.83872 -274.954075) (xy 99.854768 -275.003468)
			(xy 99.862893 -275.054763) (xy 99.863402 -275.08073) (xy 99.862893 -275.106697) (xy 100.142803 -275.106697)
			(xy 100.142803 -275.054763) (xy 100.150928 -275.003468) (xy 100.166976 -274.954075) (xy 100.190554 -274.907801)
			(xy 100.22108 -274.865785) (xy 100.257803 -274.829062) (xy 100.299819 -274.798536) (xy 100.346093 -274.774958)
			(xy 100.395486 -274.75891) (xy 100.446781 -274.750785) (xy 100.498715 -274.750785) (xy 100.55001 -274.75891)
			(xy 100.599403 -274.774958) (xy 100.645677 -274.798536) (xy 100.687693 -274.829062) (xy 100.724416 -274.865785)
			(xy 100.754942 -274.907801) (xy 100.77852 -274.954075) (xy 100.794568 -275.003468) (xy 100.802693 -275.054763)
			(xy 100.803202 -275.08073) (xy 100.802694 -275.106669) (xy 102.022359 -275.106669) (xy 102.022359 -275.054731)
			(xy 102.030485 -275.003432) (xy 102.046536 -274.954035) (xy 102.070118 -274.907759) (xy 102.100649 -274.865741)
			(xy 102.137378 -274.829018) (xy 102.1794 -274.798493) (xy 102.22568 -274.774918) (xy 102.275078 -274.758873)
			(xy 102.326379 -274.750755) (xy 102.352348 -274.750276) (xy 102.377982 -274.750805) (xy 102.428635 -274.758722)
			(xy 102.477456 -274.774373) (xy 102.523271 -274.797381) (xy 102.564978 -274.827195) (xy 102.601577 -274.863097)
			(xy 102.61727 -274.883372) (xy 103.027226 -274.883372) (xy 103.042943 -274.863115) (xy 103.079534 -274.827204)
			(xy 103.121236 -274.797381) (xy 103.167045 -274.77436) (xy 103.215862 -274.758696) (xy 103.266514 -274.750764)
			(xy 103.292148 -274.750276) (xy 103.318115 -274.750729) (xy 103.369409 -274.75886) (xy 103.4188 -274.774914)
			(xy 103.465071 -274.798497) (xy 103.507084 -274.829027) (xy 103.543805 -274.865752) (xy 103.574328 -274.90777)
			(xy 103.597904 -274.954045) (xy 103.613951 -275.003438) (xy 103.622075 -275.054733) (xy 103.622075 -275.106667)
			(xy 103.613951 -275.157962) (xy 103.597904 -275.207355) (xy 103.574328 -275.25363) (xy 103.543805 -275.295648)
			(xy 103.507084 -275.332373) (xy 103.465071 -275.362903) (xy 103.4188 -275.386486) (xy 103.369409 -275.40254)
			(xy 103.318115 -275.410671) (xy 103.292148 -275.411184) (xy 103.266513 -275.410673) (xy 103.215858 -275.402755)
			(xy 103.167037 -275.387102) (xy 103.121221 -275.36409) (xy 103.079514 -275.334272) (xy 103.042918 -275.298365)
			(xy 103.027226 -275.278088) (xy 102.61727 -275.278088) (xy 102.601544 -275.298339) (xy 102.564956 -275.334251)
			(xy 102.523257 -275.364077) (xy 102.477449 -275.387099) (xy 102.428633 -275.402764) (xy 102.377982 -275.410696)
			(xy 102.352348 -275.411184) (xy 102.326379 -275.410645) (xy 102.275078 -275.402527) (xy 102.22568 -275.386482)
			(xy 102.1794 -275.362907) (xy 102.137378 -275.332382) (xy 102.100649 -275.295659) (xy 102.070118 -275.253641)
			(xy 102.046536 -275.207365) (xy 102.030485 -275.157968) (xy 102.022359 -275.106669) (xy 100.802694 -275.106669)
			(xy 100.802693 -275.106697) (xy 100.794568 -275.157992) (xy 100.77852 -275.207385) (xy 100.754942 -275.253659)
			(xy 100.724416 -275.295675) (xy 100.687693 -275.332398) (xy 100.645677 -275.362924) (xy 100.599403 -275.386502)
			(xy 100.55001 -275.40255) (xy 100.498715 -275.410675) (xy 100.446781 -275.410675) (xy 100.395486 -275.40255)
			(xy 100.346093 -275.386502) (xy 100.299819 -275.362924) (xy 100.257803 -275.332398) (xy 100.22108 -275.295675)
			(xy 100.190554 -275.253659) (xy 100.166976 -275.207385) (xy 100.150928 -275.157992) (xy 100.142803 -275.106697)
			(xy 99.862893 -275.106697) (xy 99.854768 -275.157992) (xy 99.83872 -275.207385) (xy 99.815142 -275.253659)
			(xy 99.784616 -275.295675) (xy 99.747893 -275.332398) (xy 99.705877 -275.362924) (xy 99.659603 -275.386502)
			(xy 99.61021 -275.40255) (xy 99.558915 -275.410675) (xy 99.506981 -275.410675) (xy 99.455686 -275.40255)
			(xy 99.406293 -275.386502) (xy 99.360019 -275.362924) (xy 99.318003 -275.332398) (xy 99.28128 -275.295675)
			(xy 99.250754 -275.253659) (xy 99.227176 -275.207385) (xy 99.211128 -275.157992) (xy 99.203003 -275.106697)
			(xy 98.922839 -275.106697) (xy 98.914714 -275.157992) (xy 98.898666 -275.207385) (xy 98.875088 -275.253659)
			(xy 98.844562 -275.295675) (xy 98.807839 -275.332398) (xy 98.765823 -275.362924) (xy 98.719549 -275.386502)
			(xy 98.670156 -275.40255) (xy 98.618861 -275.410675) (xy 98.566927 -275.410675) (xy 98.515632 -275.40255)
			(xy 98.466239 -275.386502) (xy 98.419965 -275.362924) (xy 98.377949 -275.332398) (xy 98.341226 -275.295675)
			(xy 98.3107 -275.253659) (xy 98.287122 -275.207385) (xy 98.271074 -275.157992) (xy 98.262949 -275.106697)
			(xy 97.983293 -275.106697) (xy 97.975168 -275.157992) (xy 97.95912 -275.207385) (xy 97.935542 -275.253659)
			(xy 97.905016 -275.295675) (xy 97.868293 -275.332398) (xy 97.826277 -275.362924) (xy 97.780003 -275.386502)
			(xy 97.73061 -275.40255) (xy 97.679315 -275.410675) (xy 97.627381 -275.410675) (xy 97.576086 -275.40255)
			(xy 97.526693 -275.386502) (xy 97.480419 -275.362924) (xy 97.438403 -275.332398) (xy 97.40168 -275.295675)
			(xy 97.371154 -275.253659) (xy 97.347576 -275.207385) (xy 97.331528 -275.157992) (xy 97.323403 -275.106697)
			(xy 97.043493 -275.106697) (xy 97.035368 -275.157992) (xy 97.01932 -275.207385) (xy 96.995742 -275.253659)
			(xy 96.965216 -275.295675) (xy 96.928493 -275.332398) (xy 96.886477 -275.362924) (xy 96.840203 -275.386502)
			(xy 96.79081 -275.40255) (xy 96.739515 -275.410675) (xy 96.687581 -275.410675) (xy 96.636286 -275.40255)
			(xy 96.586893 -275.386502) (xy 96.540619 -275.362924) (xy 96.498603 -275.332398) (xy 96.46188 -275.295675)
			(xy 96.431354 -275.253659) (xy 96.407776 -275.207385) (xy 96.391728 -275.157992) (xy 96.383603 -275.106697)
			(xy 96.103693 -275.106697) (xy 96.095568 -275.157992) (xy 96.07952 -275.207385) (xy 96.055942 -275.253659)
			(xy 96.025416 -275.295675) (xy 95.988693 -275.332398) (xy 95.946677 -275.362924) (xy 95.900403 -275.386502)
			(xy 95.85101 -275.40255) (xy 95.799715 -275.410675) (xy 95.747781 -275.410675) (xy 95.696486 -275.40255)
			(xy 95.647093 -275.386502) (xy 95.600819 -275.362924) (xy 95.558803 -275.332398) (xy 95.52208 -275.295675)
			(xy 95.491554 -275.253659) (xy 95.467976 -275.207385) (xy 95.451928 -275.157992) (xy 95.443803 -275.106697)
			(xy 95.163893 -275.106697) (xy 95.155768 -275.157992) (xy 95.13972 -275.207385) (xy 95.116142 -275.253659)
			(xy 95.085616 -275.295675) (xy 95.048893 -275.332398) (xy 95.006877 -275.362924) (xy 94.960603 -275.386502)
			(xy 94.91121 -275.40255) (xy 94.859915 -275.410675) (xy 94.807981 -275.410675) (xy 94.756686 -275.40255)
			(xy 94.707293 -275.386502) (xy 94.661019 -275.362924) (xy 94.619003 -275.332398) (xy 94.58228 -275.295675)
			(xy 94.551754 -275.253659) (xy 94.528176 -275.207385) (xy 94.512128 -275.157992) (xy 94.504003 -275.106697)
			(xy 94.224093 -275.106697) (xy 94.215968 -275.157992) (xy 94.19992 -275.207385) (xy 94.176342 -275.253659)
			(xy 94.145816 -275.295675) (xy 94.109093 -275.332398) (xy 94.067077 -275.362924) (xy 94.020803 -275.386502)
			(xy 93.97141 -275.40255) (xy 93.920115 -275.410675) (xy 93.868181 -275.410675) (xy 93.816886 -275.40255)
			(xy 93.767493 -275.386502) (xy 93.721219 -275.362924) (xy 93.679203 -275.332398) (xy 93.64248 -275.295675)
			(xy 93.611954 -275.253659) (xy 93.588376 -275.207385) (xy 93.572328 -275.157992) (xy 93.564203 -275.106697)
			(xy 93.284293 -275.106697) (xy 93.276168 -275.157992) (xy 93.26012 -275.207385) (xy 93.236542 -275.253659)
			(xy 93.206016 -275.295675) (xy 93.169293 -275.332398) (xy 93.127277 -275.362924) (xy 93.081003 -275.386502)
			(xy 93.03161 -275.40255) (xy 92.980315 -275.410675) (xy 92.928381 -275.410675) (xy 92.877086 -275.40255)
			(xy 92.827693 -275.386502) (xy 92.781419 -275.362924) (xy 92.739403 -275.332398) (xy 92.70268 -275.295675)
			(xy 92.672154 -275.253659) (xy 92.648576 -275.207385) (xy 92.632528 -275.157992) (xy 92.624403 -275.106697)
			(xy 92.344493 -275.106697) (xy 92.336364 -275.158022) (xy 92.320303 -275.207452) (xy 92.296707 -275.253762)
			(xy 92.266157 -275.29581) (xy 92.229405 -275.332561) (xy 92.187357 -275.36311) (xy 92.141047 -275.386705)
			(xy 92.091616 -275.402766) (xy 92.040281 -275.410895) (xy 92.014294 -275.411438) (xy 92.01404 -275.411438)
			(xy 91.984621 -275.410773) (xy 91.926715 -275.400339) (xy 91.871555 -275.379862) (xy 91.845892 -275.365464)
			(xy 91.840304 -275.362162) (xy 91.81465 -275.354796) (xy 91.808208 -275.354964) (xy 91.795736 -275.358185)
			(xy 91.790012 -275.361146) (xy 91.713304 -275.403818) (xy 91.705722 -275.408458) (xy 91.694174 -275.421958)
			(xy 91.68802 -275.438623) (xy 91.68765 -275.447506) (xy 91.68765 -275.566886) (xy 91.712034 -275.609304)
			(xy 91.718638 -275.613622) (xy 91.740362 -275.627672) (xy 91.779559 -275.661436) (xy 91.813021 -275.70089)
			(xy 91.839934 -275.745073) (xy 91.85964 -275.792906) (xy 91.871659 -275.843224) (xy 91.875698 -275.8948)
			(xy 91.873664 -275.920767) (xy 92.154249 -275.920767) (xy 92.154249 -275.868833) (xy 92.162374 -275.817538)
			(xy 92.178422 -275.768145) (xy 92.202 -275.721871) (xy 92.232526 -275.679855) (xy 92.269249 -275.643132)
			(xy 92.311265 -275.612606) (xy 92.357539 -275.589028) (xy 92.406932 -275.57298) (xy 92.458227 -275.564855)
			(xy 92.510161 -275.564855) (xy 92.561456 -275.57298) (xy 92.610849 -275.589028) (xy 92.657123 -275.612606)
			(xy 92.699139 -275.643132) (xy 92.735862 -275.679855) (xy 92.766388 -275.721871) (xy 92.789966 -275.768145)
			(xy 92.806014 -275.817538) (xy 92.814139 -275.868833) (xy 92.814648 -275.8948) (xy 92.814139 -275.920767)
			(xy 93.094049 -275.920767) (xy 93.094049 -275.868833) (xy 93.102174 -275.817538) (xy 93.118222 -275.768145)
			(xy 93.1418 -275.721871) (xy 93.172326 -275.679855) (xy 93.209049 -275.643132) (xy 93.251065 -275.612606)
			(xy 93.297339 -275.589028) (xy 93.346732 -275.57298) (xy 93.398027 -275.564855) (xy 93.449961 -275.564855)
			(xy 93.501256 -275.57298) (xy 93.550649 -275.589028) (xy 93.596923 -275.612606) (xy 93.638939 -275.643132)
			(xy 93.675662 -275.679855) (xy 93.706188 -275.721871) (xy 93.729766 -275.768145) (xy 93.745814 -275.817538)
			(xy 93.753939 -275.868833) (xy 93.754448 -275.8948) (xy 93.753939 -275.920767) (xy 94.034103 -275.920767)
			(xy 94.034103 -275.868833) (xy 94.042228 -275.817538) (xy 94.058276 -275.768145) (xy 94.081854 -275.721871)
			(xy 94.11238 -275.679855) (xy 94.149103 -275.643132) (xy 94.191119 -275.612606) (xy 94.237393 -275.589028)
			(xy 94.286786 -275.57298) (xy 94.338081 -275.564855) (xy 94.390015 -275.564855) (xy 94.44131 -275.57298)
			(xy 94.490703 -275.589028) (xy 94.536977 -275.612606) (xy 94.578993 -275.643132) (xy 94.615716 -275.679855)
			(xy 94.646242 -275.721871) (xy 94.66982 -275.768145) (xy 94.685868 -275.817538) (xy 94.693993 -275.868833)
			(xy 94.694502 -275.8948) (xy 94.693993 -275.920767) (xy 94.973649 -275.920767) (xy 94.973649 -275.868833)
			(xy 94.981774 -275.817538) (xy 94.997822 -275.768145) (xy 95.0214 -275.721871) (xy 95.051926 -275.679855)
			(xy 95.088649 -275.643132) (xy 95.130665 -275.612606) (xy 95.176939 -275.589028) (xy 95.226332 -275.57298)
			(xy 95.277627 -275.564855) (xy 95.329561 -275.564855) (xy 95.380856 -275.57298) (xy 95.430249 -275.589028)
			(xy 95.476523 -275.612606) (xy 95.518539 -275.643132) (xy 95.555262 -275.679855) (xy 95.585788 -275.721871)
			(xy 95.609366 -275.768145) (xy 95.625414 -275.817538) (xy 95.633539 -275.868833) (xy 95.634048 -275.8948)
			(xy 95.633539 -275.920767) (xy 95.913449 -275.920767) (xy 95.913449 -275.868833) (xy 95.921574 -275.817538)
			(xy 95.937622 -275.768145) (xy 95.9612 -275.721871) (xy 95.991726 -275.679855) (xy 96.028449 -275.643132)
			(xy 96.070465 -275.612606) (xy 96.116739 -275.589028) (xy 96.166132 -275.57298) (xy 96.217427 -275.564855)
			(xy 96.269361 -275.564855) (xy 96.320656 -275.57298) (xy 96.370049 -275.589028) (xy 96.416323 -275.612606)
			(xy 96.458339 -275.643132) (xy 96.495062 -275.679855) (xy 96.525588 -275.721871) (xy 96.549166 -275.768145)
			(xy 96.565214 -275.817538) (xy 96.573339 -275.868833) (xy 96.573848 -275.8948) (xy 96.573339 -275.920767)
			(xy 96.853249 -275.920767) (xy 96.853249 -275.868833) (xy 96.861374 -275.817538) (xy 96.877422 -275.768145)
			(xy 96.901 -275.721871) (xy 96.931526 -275.679855) (xy 96.968249 -275.643132) (xy 97.010265 -275.612606)
			(xy 97.056539 -275.589028) (xy 97.105932 -275.57298) (xy 97.157227 -275.564855) (xy 97.209161 -275.564855)
			(xy 97.260456 -275.57298) (xy 97.309849 -275.589028) (xy 97.356123 -275.612606) (xy 97.398139 -275.643132)
			(xy 97.434862 -275.679855) (xy 97.465388 -275.721871) (xy 97.488966 -275.768145) (xy 97.505014 -275.817538)
			(xy 97.513139 -275.868833) (xy 97.513648 -275.8948) (xy 97.513139 -275.920767) (xy 97.793049 -275.920767)
			(xy 97.793049 -275.868833) (xy 97.801174 -275.817538) (xy 97.817222 -275.768145) (xy 97.8408 -275.721871)
			(xy 97.871326 -275.679855) (xy 97.908049 -275.643132) (xy 97.950065 -275.612606) (xy 97.996339 -275.589028)
			(xy 98.045732 -275.57298) (xy 98.097027 -275.564855) (xy 98.148961 -275.564855) (xy 98.200256 -275.57298)
			(xy 98.249649 -275.589028) (xy 98.295923 -275.612606) (xy 98.337939 -275.643132) (xy 98.374662 -275.679855)
			(xy 98.405188 -275.721871) (xy 98.428766 -275.768145) (xy 98.444814 -275.817538) (xy 98.452939 -275.868833)
			(xy 98.453448 -275.8948) (xy 98.452939 -275.920767) (xy 98.732849 -275.920767) (xy 98.732849 -275.868833)
			(xy 98.740974 -275.817538) (xy 98.757022 -275.768145) (xy 98.7806 -275.721871) (xy 98.811126 -275.679855)
			(xy 98.847849 -275.643132) (xy 98.889865 -275.612606) (xy 98.936139 -275.589028) (xy 98.985532 -275.57298)
			(xy 99.036827 -275.564855) (xy 99.088761 -275.564855) (xy 99.140056 -275.57298) (xy 99.189449 -275.589028)
			(xy 99.235723 -275.612606) (xy 99.277739 -275.643132) (xy 99.314462 -275.679855) (xy 99.344988 -275.721871)
			(xy 99.368566 -275.768145) (xy 99.384614 -275.817538) (xy 99.392739 -275.868833) (xy 99.393248 -275.8948)
			(xy 99.392739 -275.920767) (xy 99.672649 -275.920767) (xy 99.672649 -275.868833) (xy 99.680774 -275.817538)
			(xy 99.696822 -275.768145) (xy 99.7204 -275.721871) (xy 99.750926 -275.679855) (xy 99.787649 -275.643132)
			(xy 99.829665 -275.612606) (xy 99.875939 -275.589028) (xy 99.925332 -275.57298) (xy 99.976627 -275.564855)
			(xy 100.028561 -275.564855) (xy 100.079856 -275.57298) (xy 100.129249 -275.589028) (xy 100.175523 -275.612606)
			(xy 100.217539 -275.643132) (xy 100.254262 -275.679855) (xy 100.284788 -275.721871) (xy 100.308366 -275.768145)
			(xy 100.324414 -275.817538) (xy 100.332539 -275.868833) (xy 100.333048 -275.8948) (xy 100.332539 -275.920767)
			(xy 100.612703 -275.920767) (xy 100.612703 -275.868833) (xy 100.620828 -275.817538) (xy 100.636876 -275.768145)
			(xy 100.660454 -275.721871) (xy 100.69098 -275.679855) (xy 100.727703 -275.643132) (xy 100.769719 -275.612606)
			(xy 100.815993 -275.589028) (xy 100.865386 -275.57298) (xy 100.916681 -275.564855) (xy 100.968615 -275.564855)
			(xy 101.01991 -275.57298) (xy 101.069303 -275.589028) (xy 101.115577 -275.612606) (xy 101.157593 -275.643132)
			(xy 101.194316 -275.679855) (xy 101.224842 -275.721871) (xy 101.24842 -275.768145) (xy 101.264468 -275.817538)
			(xy 101.272593 -275.868833) (xy 101.273102 -275.8948) (xy 101.272593 -275.920767) (xy 101.552249 -275.920767)
			(xy 101.552249 -275.868833) (xy 101.560374 -275.817538) (xy 101.576422 -275.768145) (xy 101.6 -275.721871)
			(xy 101.630526 -275.679855) (xy 101.667249 -275.643132) (xy 101.709265 -275.612606) (xy 101.755539 -275.589028)
			(xy 101.804932 -275.57298) (xy 101.856227 -275.564855) (xy 101.908161 -275.564855) (xy 101.959456 -275.57298)
			(xy 102.008849 -275.589028) (xy 102.055123 -275.612606) (xy 102.097139 -275.643132) (xy 102.133862 -275.679855)
			(xy 102.164388 -275.721871) (xy 102.187966 -275.768145) (xy 102.204014 -275.817538) (xy 102.212139 -275.868833)
			(xy 102.212648 -275.8948) (xy 102.212139 -275.920767) (xy 102.204014 -275.972062) (xy 102.187966 -276.021455)
			(xy 102.164388 -276.067729) (xy 102.133862 -276.109745) (xy 102.097139 -276.146468) (xy 102.055123 -276.176994)
			(xy 102.008849 -276.200572) (xy 101.959456 -276.21662) (xy 101.908161 -276.224745) (xy 101.856227 -276.224745)
			(xy 101.804932 -276.21662) (xy 101.755539 -276.200572) (xy 101.709265 -276.176994) (xy 101.667249 -276.146468)
			(xy 101.630526 -276.109745) (xy 101.6 -276.067729) (xy 101.576422 -276.021455) (xy 101.560374 -275.972062)
			(xy 101.552249 -275.920767) (xy 101.272593 -275.920767) (xy 101.264468 -275.972062) (xy 101.24842 -276.021455)
			(xy 101.224842 -276.067729) (xy 101.194316 -276.109745) (xy 101.157593 -276.146468) (xy 101.115577 -276.176994)
			(xy 101.069303 -276.200572) (xy 101.01991 -276.21662) (xy 100.968615 -276.224745) (xy 100.916681 -276.224745)
			(xy 100.865386 -276.21662) (xy 100.815993 -276.200572) (xy 100.769719 -276.176994) (xy 100.727703 -276.146468)
			(xy 100.69098 -276.109745) (xy 100.660454 -276.067729) (xy 100.636876 -276.021455) (xy 100.620828 -275.972062)
			(xy 100.612703 -275.920767) (xy 100.332539 -275.920767) (xy 100.324414 -275.972062) (xy 100.308366 -276.021455)
			(xy 100.284788 -276.067729) (xy 100.254262 -276.109745) (xy 100.217539 -276.146468) (xy 100.175523 -276.176994)
			(xy 100.129249 -276.200572) (xy 100.079856 -276.21662) (xy 100.028561 -276.224745) (xy 99.976627 -276.224745)
			(xy 99.925332 -276.21662) (xy 99.875939 -276.200572) (xy 99.829665 -276.176994) (xy 99.787649 -276.146468)
			(xy 99.750926 -276.109745) (xy 99.7204 -276.067729) (xy 99.696822 -276.021455) (xy 99.680774 -275.972062)
			(xy 99.672649 -275.920767) (xy 99.392739 -275.920767) (xy 99.384614 -275.972062) (xy 99.368566 -276.021455)
			(xy 99.344988 -276.067729) (xy 99.314462 -276.109745) (xy 99.277739 -276.146468) (xy 99.235723 -276.176994)
			(xy 99.189449 -276.200572) (xy 99.140056 -276.21662) (xy 99.088761 -276.224745) (xy 99.036827 -276.224745)
			(xy 98.985532 -276.21662) (xy 98.936139 -276.200572) (xy 98.889865 -276.176994) (xy 98.847849 -276.146468)
			(xy 98.811126 -276.109745) (xy 98.7806 -276.067729) (xy 98.757022 -276.021455) (xy 98.740974 -275.972062)
			(xy 98.732849 -275.920767) (xy 98.452939 -275.920767) (xy 98.444814 -275.972062) (xy 98.428766 -276.021455)
			(xy 98.405188 -276.067729) (xy 98.374662 -276.109745) (xy 98.337939 -276.146468) (xy 98.295923 -276.176994)
			(xy 98.249649 -276.200572) (xy 98.200256 -276.21662) (xy 98.148961 -276.224745) (xy 98.097027 -276.224745)
			(xy 98.045732 -276.21662) (xy 97.996339 -276.200572) (xy 97.950065 -276.176994) (xy 97.908049 -276.146468)
			(xy 97.871326 -276.109745) (xy 97.8408 -276.067729) (xy 97.817222 -276.021455) (xy 97.801174 -275.972062)
			(xy 97.793049 -275.920767) (xy 97.513139 -275.920767) (xy 97.505014 -275.972062) (xy 97.488966 -276.021455)
			(xy 97.465388 -276.067729) (xy 97.434862 -276.109745) (xy 97.398139 -276.146468) (xy 97.356123 -276.176994)
			(xy 97.309849 -276.200572) (xy 97.260456 -276.21662) (xy 97.209161 -276.224745) (xy 97.157227 -276.224745)
			(xy 97.105932 -276.21662) (xy 97.056539 -276.200572) (xy 97.010265 -276.176994) (xy 96.968249 -276.146468)
			(xy 96.931526 -276.109745) (xy 96.901 -276.067729) (xy 96.877422 -276.021455) (xy 96.861374 -275.972062)
			(xy 96.853249 -275.920767) (xy 96.573339 -275.920767) (xy 96.565214 -275.972062) (xy 96.549166 -276.021455)
			(xy 96.525588 -276.067729) (xy 96.495062 -276.109745) (xy 96.458339 -276.146468) (xy 96.416323 -276.176994)
			(xy 96.370049 -276.200572) (xy 96.320656 -276.21662) (xy 96.269361 -276.224745) (xy 96.217427 -276.224745)
			(xy 96.166132 -276.21662) (xy 96.116739 -276.200572) (xy 96.070465 -276.176994) (xy 96.028449 -276.146468)
			(xy 95.991726 -276.109745) (xy 95.9612 -276.067729) (xy 95.937622 -276.021455) (xy 95.921574 -275.972062)
			(xy 95.913449 -275.920767) (xy 95.633539 -275.920767) (xy 95.625414 -275.972062) (xy 95.609366 -276.021455)
			(xy 95.585788 -276.067729) (xy 95.555262 -276.109745) (xy 95.518539 -276.146468) (xy 95.476523 -276.176994)
			(xy 95.430249 -276.200572) (xy 95.380856 -276.21662) (xy 95.329561 -276.224745) (xy 95.277627 -276.224745)
			(xy 95.226332 -276.21662) (xy 95.176939 -276.200572) (xy 95.130665 -276.176994) (xy 95.088649 -276.146468)
			(xy 95.051926 -276.109745) (xy 95.0214 -276.067729) (xy 94.997822 -276.021455) (xy 94.981774 -275.972062)
			(xy 94.973649 -275.920767) (xy 94.693993 -275.920767) (xy 94.685868 -275.972062) (xy 94.66982 -276.021455)
			(xy 94.646242 -276.067729) (xy 94.615716 -276.109745) (xy 94.578993 -276.146468) (xy 94.536977 -276.176994)
			(xy 94.490703 -276.200572) (xy 94.44131 -276.21662) (xy 94.390015 -276.224745) (xy 94.338081 -276.224745)
			(xy 94.286786 -276.21662) (xy 94.237393 -276.200572) (xy 94.191119 -276.176994) (xy 94.149103 -276.146468)
			(xy 94.11238 -276.109745) (xy 94.081854 -276.067729) (xy 94.058276 -276.021455) (xy 94.042228 -275.972062)
			(xy 94.034103 -275.920767) (xy 93.753939 -275.920767) (xy 93.745814 -275.972062) (xy 93.729766 -276.021455)
			(xy 93.706188 -276.067729) (xy 93.675662 -276.109745) (xy 93.638939 -276.146468) (xy 93.596923 -276.176994)
			(xy 93.550649 -276.200572) (xy 93.501256 -276.21662) (xy 93.449961 -276.224745) (xy 93.398027 -276.224745)
			(xy 93.346732 -276.21662) (xy 93.297339 -276.200572) (xy 93.251065 -276.176994) (xy 93.209049 -276.146468)
			(xy 93.172326 -276.109745) (xy 93.1418 -276.067729) (xy 93.118222 -276.021455) (xy 93.102174 -275.972062)
			(xy 93.094049 -275.920767) (xy 92.814139 -275.920767) (xy 92.806014 -275.972062) (xy 92.789966 -276.021455)
			(xy 92.766388 -276.067729) (xy 92.735862 -276.109745) (xy 92.699139 -276.146468) (xy 92.657123 -276.176994)
			(xy 92.610849 -276.200572) (xy 92.561456 -276.21662) (xy 92.510161 -276.224745) (xy 92.458227 -276.224745)
			(xy 92.406932 -276.21662) (xy 92.357539 -276.200572) (xy 92.311265 -276.176994) (xy 92.269249 -276.146468)
			(xy 92.232526 -276.109745) (xy 92.202 -276.067729) (xy 92.178422 -276.021455) (xy 92.162374 -275.972062)
			(xy 92.154249 -275.920767) (xy 91.873664 -275.920767) (xy 91.871659 -275.946376) (xy 91.85964 -275.996694)
			(xy 91.839934 -276.044527) (xy 91.813021 -276.08871) (xy 91.779559 -276.128164) (xy 91.740362 -276.161928)
			(xy 91.718638 -276.175978) (xy 91.712034 -276.180296) (xy 91.68765 -276.222714) (xy 91.68765 -276.342094)
			(xy 91.688004 -276.35098) (xy 91.69416 -276.36765) (xy 91.705711 -276.381155) (xy 91.713304 -276.385782)
			(xy 91.751658 -276.407118) (xy 91.791536 -276.429216) (xy 91.799315 -276.432826) (xy 91.816299 -276.435123)
			(xy 91.833076 -276.431626) (xy 91.840558 -276.427438) (xy 91.840812 -276.427184) (xy 91.860482 -276.415503)
			(xy 91.902354 -276.397075) (xy 91.946364 -276.384589) (xy 91.991674 -276.378282) (xy 92.014548 -276.377908)
			(xy 92.040531 -276.378421) (xy 92.091858 -276.386557) (xy 92.141279 -276.402622) (xy 92.18758 -276.426219)
			(xy 92.22962 -276.456768) (xy 92.266363 -276.493517) (xy 92.296906 -276.535561) (xy 92.320497 -276.581865)
			(xy 92.336554 -276.631289) (xy 92.344683 -276.682616) (xy 92.344683 -276.734583) (xy 92.624403 -276.734583)
			(xy 92.624403 -276.682649) (xy 92.632528 -276.631354) (xy 92.648576 -276.581961) (xy 92.672154 -276.535687)
			(xy 92.70268 -276.493671) (xy 92.739403 -276.456948) (xy 92.781419 -276.426422) (xy 92.827693 -276.402844)
			(xy 92.877086 -276.386796) (xy 92.928381 -276.378671) (xy 92.980315 -276.378671) (xy 93.03161 -276.386796)
			(xy 93.081003 -276.402844) (xy 93.127277 -276.426422) (xy 93.169293 -276.456948) (xy 93.206016 -276.493671)
			(xy 93.236542 -276.535687) (xy 93.26012 -276.581961) (xy 93.276168 -276.631354) (xy 93.284293 -276.682649)
			(xy 93.284802 -276.708616) (xy 93.284293 -276.734583) (xy 93.564203 -276.734583) (xy 93.564203 -276.682649)
			(xy 93.572328 -276.631354) (xy 93.588376 -276.581961) (xy 93.611954 -276.535687) (xy 93.64248 -276.493671)
			(xy 93.679203 -276.456948) (xy 93.721219 -276.426422) (xy 93.767493 -276.402844) (xy 93.816886 -276.386796)
			(xy 93.868181 -276.378671) (xy 93.920115 -276.378671) (xy 93.97141 -276.386796) (xy 94.020803 -276.402844)
			(xy 94.067077 -276.426422) (xy 94.109093 -276.456948) (xy 94.145816 -276.493671) (xy 94.176342 -276.535687)
			(xy 94.19992 -276.581961) (xy 94.215968 -276.631354) (xy 94.224093 -276.682649) (xy 94.224602 -276.708616)
			(xy 94.224093 -276.734583) (xy 94.504003 -276.734583) (xy 94.504003 -276.682649) (xy 94.512128 -276.631354)
			(xy 94.528176 -276.581961) (xy 94.551754 -276.535687) (xy 94.58228 -276.493671) (xy 94.619003 -276.456948)
			(xy 94.661019 -276.426422) (xy 94.707293 -276.402844) (xy 94.756686 -276.386796) (xy 94.807981 -276.378671)
			(xy 94.859915 -276.378671) (xy 94.91121 -276.386796) (xy 94.960603 -276.402844) (xy 95.006877 -276.426422)
			(xy 95.048893 -276.456948) (xy 95.085616 -276.493671) (xy 95.116142 -276.535687) (xy 95.13972 -276.581961)
			(xy 95.155768 -276.631354) (xy 95.163893 -276.682649) (xy 95.164402 -276.708616) (xy 95.163893 -276.734583)
			(xy 95.443803 -276.734583) (xy 95.443803 -276.682649) (xy 95.451928 -276.631354) (xy 95.467976 -276.581961)
			(xy 95.491554 -276.535687) (xy 95.52208 -276.493671) (xy 95.558803 -276.456948) (xy 95.600819 -276.426422)
			(xy 95.647093 -276.402844) (xy 95.696486 -276.386796) (xy 95.747781 -276.378671) (xy 95.799715 -276.378671)
			(xy 95.85101 -276.386796) (xy 95.900403 -276.402844) (xy 95.946677 -276.426422) (xy 95.988693 -276.456948)
			(xy 96.025416 -276.493671) (xy 96.055942 -276.535687) (xy 96.07952 -276.581961) (xy 96.095568 -276.631354)
			(xy 96.103693 -276.682649) (xy 96.104202 -276.708616) (xy 96.103693 -276.734583) (xy 96.383603 -276.734583)
			(xy 96.383603 -276.682649) (xy 96.391728 -276.631354) (xy 96.407776 -276.581961) (xy 96.431354 -276.535687)
			(xy 96.46188 -276.493671) (xy 96.498603 -276.456948) (xy 96.540619 -276.426422) (xy 96.586893 -276.402844)
			(xy 96.636286 -276.386796) (xy 96.687581 -276.378671) (xy 96.739515 -276.378671) (xy 96.79081 -276.386796)
			(xy 96.840203 -276.402844) (xy 96.886477 -276.426422) (xy 96.928493 -276.456948) (xy 96.965216 -276.493671)
			(xy 96.995742 -276.535687) (xy 97.01932 -276.581961) (xy 97.035368 -276.631354) (xy 97.043493 -276.682649)
			(xy 97.044002 -276.708616) (xy 97.043493 -276.734583) (xy 97.323149 -276.734583) (xy 97.323149 -276.682649)
			(xy 97.331274 -276.631354) (xy 97.347322 -276.581961) (xy 97.3709 -276.535687) (xy 97.401426 -276.493671)
			(xy 97.438149 -276.456948) (xy 97.480165 -276.426422) (xy 97.526439 -276.402844) (xy 97.575832 -276.386796)
			(xy 97.627127 -276.378671) (xy 97.679061 -276.378671) (xy 97.730356 -276.386796) (xy 97.779749 -276.402844)
			(xy 97.826023 -276.426422) (xy 97.868039 -276.456948) (xy 97.904762 -276.493671) (xy 97.935288 -276.535687)
			(xy 97.958866 -276.581961) (xy 97.974914 -276.631354) (xy 97.983039 -276.682649) (xy 97.983548 -276.708616)
			(xy 97.983039 -276.734583) (xy 98.263203 -276.734583) (xy 98.263203 -276.682649) (xy 98.271328 -276.631354)
			(xy 98.287376 -276.581961) (xy 98.310954 -276.535687) (xy 98.34148 -276.493671) (xy 98.378203 -276.456948)
			(xy 98.420219 -276.426422) (xy 98.466493 -276.402844) (xy 98.515886 -276.386796) (xy 98.567181 -276.378671)
			(xy 98.619115 -276.378671) (xy 98.67041 -276.386796) (xy 98.719803 -276.402844) (xy 98.766077 -276.426422)
			(xy 98.808093 -276.456948) (xy 98.844816 -276.493671) (xy 98.875342 -276.535687) (xy 98.89892 -276.581961)
			(xy 98.914968 -276.631354) (xy 98.923093 -276.682649) (xy 98.923602 -276.708616) (xy 98.923093 -276.734583)
			(xy 99.203003 -276.734583) (xy 99.203003 -276.682649) (xy 99.211128 -276.631354) (xy 99.227176 -276.581961)
			(xy 99.250754 -276.535687) (xy 99.28128 -276.493671) (xy 99.318003 -276.456948) (xy 99.360019 -276.426422)
			(xy 99.406293 -276.402844) (xy 99.455686 -276.386796) (xy 99.506981 -276.378671) (xy 99.558915 -276.378671)
			(xy 99.61021 -276.386796) (xy 99.659603 -276.402844) (xy 99.705877 -276.426422) (xy 99.747893 -276.456948)
			(xy 99.784616 -276.493671) (xy 99.815142 -276.535687) (xy 99.83872 -276.581961) (xy 99.854768 -276.631354)
			(xy 99.862893 -276.682649) (xy 99.863402 -276.708616) (xy 99.862893 -276.734583) (xy 100.142803 -276.734583)
			(xy 100.142803 -276.682649) (xy 100.150928 -276.631354) (xy 100.166976 -276.581961) (xy 100.190554 -276.535687)
			(xy 100.22108 -276.493671) (xy 100.257803 -276.456948) (xy 100.299819 -276.426422) (xy 100.346093 -276.402844)
			(xy 100.395486 -276.386796) (xy 100.446781 -276.378671) (xy 100.498715 -276.378671) (xy 100.55001 -276.386796)
			(xy 100.599403 -276.402844) (xy 100.645677 -276.426422) (xy 100.687693 -276.456948) (xy 100.724416 -276.493671)
			(xy 100.754942 -276.535687) (xy 100.77852 -276.581961) (xy 100.794568 -276.631354) (xy 100.802693 -276.682649)
			(xy 100.803202 -276.708616) (xy 100.802693 -276.734583) (xy 101.082603 -276.734583) (xy 101.082603 -276.682649)
			(xy 101.090728 -276.631354) (xy 101.106776 -276.581961) (xy 101.130354 -276.535687) (xy 101.16088 -276.493671)
			(xy 101.197603 -276.456948) (xy 101.239619 -276.426422) (xy 101.285893 -276.402844) (xy 101.335286 -276.386796)
			(xy 101.386581 -276.378671) (xy 101.438515 -276.378671) (xy 101.48981 -276.386796) (xy 101.539203 -276.402844)
			(xy 101.585477 -276.426422) (xy 101.627493 -276.456948) (xy 101.664216 -276.493671) (xy 101.694742 -276.535687)
			(xy 101.71832 -276.581961) (xy 101.734368 -276.631354) (xy 101.742493 -276.682649) (xy 101.743002 -276.708616)
			(xy 102.02164 -276.708616) (xy 102.022056 -276.683163) (xy 102.029846 -276.632856) (xy 102.04526 -276.58434)
			(xy 102.067933 -276.538762) (xy 102.097328 -276.497201) (xy 102.13275 -276.46064) (xy 102.173361 -276.429945)
			(xy 102.218199 -276.405841) (xy 102.266203 -276.3889) (xy 102.291134 -276.38375) (xy 102.314248 -276.379432)
			(xy 102.517956 -276.026372) (xy 102.510336 -276.004274) (xy 102.501583 -275.977755) (xy 102.492139 -275.92272)
			(xy 102.49154 -275.8948) (xy 102.492049 -275.868833) (xy 102.500174 -275.817538) (xy 102.516222 -275.768145)
			(xy 102.5398 -275.721871) (xy 102.570326 -275.679855) (xy 102.607049 -275.643132) (xy 102.649065 -275.612606)
			(xy 102.695339 -275.589028) (xy 102.744732 -275.57298) (xy 102.796027 -275.564855) (xy 102.847961 -275.564855)
			(xy 102.899256 -275.57298) (xy 102.948649 -275.589028) (xy 102.994923 -275.612606) (xy 103.036939 -275.643132)
			(xy 103.073662 -275.679855) (xy 103.104188 -275.721871) (xy 103.127766 -275.768145) (xy 103.143814 -275.817538)
			(xy 103.151939 -275.868833) (xy 103.152448 -275.8948) (xy 103.151928 -275.92026) (xy 103.151849 -275.920767)
			(xy 103.431849 -275.920767) (xy 103.431849 -275.868833) (xy 103.439974 -275.817538) (xy 103.456022 -275.768145)
			(xy 103.4796 -275.721871) (xy 103.510126 -275.679855) (xy 103.546849 -275.643132) (xy 103.588865 -275.612606)
			(xy 103.635139 -275.589028) (xy 103.684532 -275.57298) (xy 103.735827 -275.564855) (xy 103.787761 -275.564855)
			(xy 103.839056 -275.57298) (xy 103.888449 -275.589028) (xy 103.934723 -275.612606) (xy 103.976739 -275.643132)
			(xy 104.013462 -275.679855) (xy 104.043988 -275.721871) (xy 104.067566 -275.768145) (xy 104.083614 -275.817538)
			(xy 104.091739 -275.868833) (xy 104.092248 -275.8948) (xy 104.37114 -275.8948) (xy 104.371632 -275.869349)
			(xy 104.37941 -275.819046) (xy 104.394812 -275.770532) (xy 104.417475 -275.724954) (xy 104.44686 -275.683392)
			(xy 104.482274 -275.64683) (xy 104.522876 -275.616133) (xy 104.567708 -275.592028) (xy 104.615706 -275.575085)
			(xy 104.640634 -275.569934) (xy 104.663748 -275.565616) (xy 104.86771 -275.212302) (xy 104.859836 -275.190204)
			(xy 104.851224 -275.163853) (xy 104.841903 -275.109208) (xy 104.841294 -275.081492) (xy 104.841294 -275.08073)
			(xy 104.841803 -275.054763) (xy 104.849928 -275.003468) (xy 104.865976 -274.954075) (xy 104.889554 -274.907801)
			(xy 104.92008 -274.865785) (xy 104.956803 -274.829062) (xy 104.998819 -274.798536) (xy 105.045093 -274.774958)
			(xy 105.094486 -274.75891) (xy 105.145781 -274.750785) (xy 105.197715 -274.750785) (xy 105.24901 -274.75891)
			(xy 105.298403 -274.774958) (xy 105.344677 -274.798536) (xy 105.386693 -274.829062) (xy 105.423416 -274.865785)
			(xy 105.453942 -274.907801) (xy 105.47752 -274.954075) (xy 105.493568 -275.003468) (xy 105.501693 -275.054763)
			(xy 105.502202 -275.08073) (xy 105.501746 -275.106193) (xy 105.501668 -275.106697) (xy 105.781349 -275.106697)
			(xy 105.781349 -275.054763) (xy 105.789474 -275.003468) (xy 105.805522 -274.954075) (xy 105.8291 -274.907801)
			(xy 105.859626 -274.865785) (xy 105.896349 -274.829062) (xy 105.938365 -274.798536) (xy 105.984639 -274.774958)
			(xy 106.034032 -274.75891) (xy 106.085327 -274.750785) (xy 106.137261 -274.750785) (xy 106.188556 -274.75891)
			(xy 106.237949 -274.774958) (xy 106.284223 -274.798536) (xy 106.326239 -274.829062) (xy 106.362962 -274.865785)
			(xy 106.393488 -274.907801) (xy 106.417066 -274.954075) (xy 106.433114 -275.003468) (xy 106.441239 -275.054763)
			(xy 106.441748 -275.08073) (xy 106.441239 -275.106697) (xy 106.721403 -275.106697) (xy 106.721403 -275.054763)
			(xy 106.729528 -275.003468) (xy 106.745576 -274.954075) (xy 106.769154 -274.907801) (xy 106.79968 -274.865785)
			(xy 106.836403 -274.829062) (xy 106.878419 -274.798536) (xy 106.924693 -274.774958) (xy 106.974086 -274.75891)
			(xy 107.025381 -274.750785) (xy 107.077315 -274.750785) (xy 107.12861 -274.75891) (xy 107.178003 -274.774958)
			(xy 107.224277 -274.798536) (xy 107.266293 -274.829062) (xy 107.303016 -274.865785) (xy 107.333542 -274.907801)
			(xy 107.35712 -274.954075) (xy 107.373168 -275.003468) (xy 107.381293 -275.054763) (xy 107.381802 -275.08073)
			(xy 107.381293 -275.106697) (xy 107.373168 -275.157992) (xy 107.35712 -275.207385) (xy 107.333542 -275.253659)
			(xy 107.303016 -275.295675) (xy 107.266293 -275.332398) (xy 107.224277 -275.362924) (xy 107.178003 -275.386502)
			(xy 107.12861 -275.40255) (xy 107.077315 -275.410675) (xy 107.025381 -275.410675) (xy 106.974086 -275.40255)
			(xy 106.924693 -275.386502) (xy 106.878419 -275.362924) (xy 106.836403 -275.332398) (xy 106.79968 -275.295675)
			(xy 106.769154 -275.253659) (xy 106.745576 -275.207385) (xy 106.729528 -275.157992) (xy 106.721403 -275.106697)
			(xy 106.441239 -275.106697) (xy 106.433114 -275.157992) (xy 106.417066 -275.207385) (xy 106.393488 -275.253659)
			(xy 106.362962 -275.295675) (xy 106.326239 -275.332398) (xy 106.284223 -275.362924) (xy 106.237949 -275.386502)
			(xy 106.188556 -275.40255) (xy 106.137261 -275.410675) (xy 106.085327 -275.410675) (xy 106.034032 -275.40255)
			(xy 105.984639 -275.386502) (xy 105.938365 -275.362924) (xy 105.896349 -275.332398) (xy 105.859626 -275.295675)
			(xy 105.8291 -275.253659) (xy 105.805522 -275.207385) (xy 105.789474 -275.157992) (xy 105.781349 -275.106697)
			(xy 105.501668 -275.106697) (xy 105.493943 -275.156518) (xy 105.478511 -275.205049) (xy 105.455815 -275.250638)
			(xy 105.426393 -275.292204) (xy 105.390941 -275.328765) (xy 105.3503 -275.359452) (xy 105.305431 -275.383541)
			(xy 105.257398 -275.40046) (xy 105.232454 -275.405596) (xy 105.20934 -275.409914) (xy 105.005632 -275.762974)
			(xy 105.013252 -275.785072) (xy 105.021982 -275.811663) (xy 105.031435 -275.86682) (xy 105.032048 -275.8948)
			(xy 105.031539 -275.920767) (xy 105.311703 -275.920767) (xy 105.311703 -275.868833) (xy 105.319828 -275.817538)
			(xy 105.335876 -275.768145) (xy 105.359454 -275.721871) (xy 105.38998 -275.679855) (xy 105.426703 -275.643132)
			(xy 105.468719 -275.612606) (xy 105.514993 -275.589028) (xy 105.564386 -275.57298) (xy 105.615681 -275.564855)
			(xy 105.667615 -275.564855) (xy 105.71891 -275.57298) (xy 105.768303 -275.589028) (xy 105.814577 -275.612606)
			(xy 105.856593 -275.643132) (xy 105.893316 -275.679855) (xy 105.923842 -275.721871) (xy 105.94742 -275.768145)
			(xy 105.963468 -275.817538) (xy 105.971593 -275.868833) (xy 105.972102 -275.8948) (xy 105.971593 -275.920767)
			(xy 106.251255 -275.920767) (xy 106.251255 -275.868833) (xy 106.259379 -275.817539) (xy 106.275428 -275.768147)
			(xy 106.299005 -275.721873) (xy 106.32953 -275.679857) (xy 106.366253 -275.643134) (xy 106.408268 -275.612608)
			(xy 106.454541 -275.58903) (xy 106.503933 -275.572981) (xy 106.555227 -275.564856) (xy 106.581194 -275.564346)
			(xy 106.606817 -275.564795) (xy 106.657446 -275.572725) (xy 106.706247 -275.588366) (xy 106.752053 -275.611343)
			(xy 106.793769 -275.641107) (xy 106.830398 -275.676946) (xy 106.846116 -275.697188) (xy 107.256072 -275.697188)
			(xy 107.271765 -275.676925) (xy 107.308388 -275.641075) (xy 107.350107 -275.611308) (xy 107.395921 -275.588339)
			(xy 107.444732 -275.572719) (xy 107.495369 -275.564821) (xy 107.520994 -275.564346) (xy 107.546964 -275.564828)
			(xy 107.598263 -275.572953) (xy 107.647661 -275.589002) (xy 107.693939 -275.612581) (xy 107.735959 -275.64311)
			(xy 107.772686 -275.679836) (xy 107.803216 -275.721856) (xy 107.826796 -275.768134) (xy 107.842846 -275.817531)
			(xy 107.850971 -275.86883) (xy 107.850971 -275.92077) (xy 107.842846 -275.972069) (xy 107.826796 -276.021466)
			(xy 107.803216 -276.067744) (xy 107.772686 -276.109764) (xy 107.735959 -276.14649) (xy 107.693939 -276.177019)
			(xy 107.647661 -276.200598) (xy 107.598263 -276.216647) (xy 107.546964 -276.224772) (xy 107.520994 -276.225254)
			(xy 107.495374 -276.224741) (xy 107.444748 -276.216825) (xy 107.395948 -276.201197) (xy 107.350141 -276.178232)
			(xy 107.308423 -276.148479) (xy 107.271792 -276.112649) (xy 107.256072 -276.092412) (xy 106.846116 -276.092412)
			(xy 106.830372 -276.112633) (xy 106.793759 -276.148486) (xy 106.752051 -276.178257) (xy 106.706247 -276.201233)
			(xy 106.657445 -276.216863) (xy 106.606816 -276.224772) (xy 106.581194 -276.225254) (xy 106.555227 -276.224744)
			(xy 106.503933 -276.216619) (xy 106.454541 -276.20057) (xy 106.408268 -276.176992) (xy 106.366253 -276.146466)
			(xy 106.32953 -276.109743) (xy 106.299005 -276.067727) (xy 106.275428 -276.021453) (xy 106.259379 -275.972061)
			(xy 106.251255 -275.920767) (xy 105.971593 -275.920767) (xy 105.963468 -275.972062) (xy 105.94742 -276.021455)
			(xy 105.923842 -276.067729) (xy 105.893316 -276.109745) (xy 105.856593 -276.146468) (xy 105.814577 -276.176994)
			(xy 105.768303 -276.200572) (xy 105.71891 -276.21662) (xy 105.667615 -276.224745) (xy 105.615681 -276.224745)
			(xy 105.564386 -276.21662) (xy 105.514993 -276.200572) (xy 105.468719 -276.176994) (xy 105.426703 -276.146468)
			(xy 105.38998 -276.109745) (xy 105.359454 -276.067729) (xy 105.335876 -276.021455) (xy 105.319828 -275.972062)
			(xy 105.311703 -275.920767) (xy 105.031539 -275.920767) (xy 105.023414 -275.972062) (xy 105.007366 -276.021455)
			(xy 104.983788 -276.067729) (xy 104.953262 -276.109745) (xy 104.916539 -276.146468) (xy 104.874523 -276.176994)
			(xy 104.828249 -276.200572) (xy 104.778856 -276.21662) (xy 104.727561 -276.224745) (xy 104.675627 -276.224745)
			(xy 104.624332 -276.21662) (xy 104.574939 -276.200572) (xy 104.528665 -276.176994) (xy 104.486649 -276.146468)
			(xy 104.449926 -276.109745) (xy 104.4194 -276.067729) (xy 104.395822 -276.021455) (xy 104.379774 -275.972062)
			(xy 104.371649 -275.920767) (xy 104.37114 -275.8948) (xy 104.092248 -275.8948) (xy 104.091739 -275.920767)
			(xy 104.083614 -275.972062) (xy 104.067566 -276.021455) (xy 104.043988 -276.067729) (xy 104.013462 -276.109745)
			(xy 103.976739 -276.146468) (xy 103.934723 -276.176994) (xy 103.888449 -276.200572) (xy 103.839056 -276.21662)
			(xy 103.787761 -276.224745) (xy 103.735827 -276.224745) (xy 103.684532 -276.21662) (xy 103.635139 -276.200572)
			(xy 103.588865 -276.176994) (xy 103.546849 -276.146468) (xy 103.510126 -276.109745) (xy 103.4796 -276.067729)
			(xy 103.456022 -276.021455) (xy 103.439974 -275.972062) (xy 103.431849 -275.920767) (xy 103.151849 -275.920767)
			(xy 103.14413 -275.97058) (xy 103.128705 -276.019108) (xy 103.106016 -276.064694) (xy 103.076602 -276.10626)
			(xy 103.041159 -276.142821) (xy 103.000526 -276.17351) (xy 102.955666 -276.197602) (xy 102.90764 -276.214526)
			(xy 102.8827 -276.219666) (xy 102.85984 -276.223984) (xy 102.656132 -276.57679) (xy 102.663752 -276.598888)
			(xy 102.672485 -276.625478) (xy 102.681936 -276.680636) (xy 102.682548 -276.708616) (xy 102.961694 -276.708616)
			(xy 102.962203 -276.682649) (xy 102.970328 -276.631354) (xy 102.986376 -276.581961) (xy 103.009954 -276.535687)
			(xy 103.04048 -276.493671) (xy 103.077203 -276.456948) (xy 103.119219 -276.426422) (xy 103.165493 -276.402844)
			(xy 103.214886 -276.386796) (xy 103.266181 -276.378671) (xy 103.318115 -276.378671) (xy 103.36941 -276.386796)
			(xy 103.418803 -276.402844) (xy 103.465077 -276.426422) (xy 103.507093 -276.456948) (xy 103.543816 -276.493671)
			(xy 103.574342 -276.535687) (xy 103.59792 -276.581961) (xy 103.613968 -276.631354) (xy 103.622093 -276.682649)
			(xy 103.622602 -276.708616) (xy 103.622093 -276.73457) (xy 103.901945 -276.73457) (xy 103.901945 -276.68263)
			(xy 103.910071 -276.631328) (xy 103.926123 -276.58193) (xy 103.949706 -276.535651) (xy 103.980238 -276.493632)
			(xy 104.016969 -276.456907) (xy 104.058992 -276.426381) (xy 104.105274 -276.402805) (xy 104.154675 -276.38676)
			(xy 104.205977 -276.378641) (xy 104.231948 -276.378162) (xy 104.257568 -276.378678) (xy 104.308192 -276.386599)
			(xy 104.35699 -276.402228) (xy 104.402796 -276.425193) (xy 104.444514 -276.454943) (xy 104.481148 -276.490769)
			(xy 104.49687 -276.511004) (xy 104.906826 -276.511004) (xy 104.92255 -276.490767) (xy 104.959166 -276.454914)
			(xy 105.000878 -276.425144) (xy 105.046686 -276.402171) (xy 105.095492 -276.386545) (xy 105.146125 -276.378641)
			(xy 105.171748 -276.378162) (xy 105.197714 -276.378643) (xy 105.249006 -276.386774) (xy 105.298394 -276.402827)
			(xy 105.344664 -276.426409) (xy 105.386675 -276.456937) (xy 105.423394 -276.493661) (xy 105.453916 -276.535677)
			(xy 105.477491 -276.58195) (xy 105.493538 -276.631341) (xy 105.501661 -276.682634) (xy 105.501661 -276.734566)
			(xy 105.501658 -276.734583) (xy 105.781349 -276.734583) (xy 105.781349 -276.682649) (xy 105.789474 -276.631354)
			(xy 105.805522 -276.581961) (xy 105.8291 -276.535687) (xy 105.859626 -276.493671) (xy 105.896349 -276.456948)
			(xy 105.938365 -276.426422) (xy 105.984639 -276.402844) (xy 106.034032 -276.386796) (xy 106.085327 -276.378671)
			(xy 106.137261 -276.378671) (xy 106.188556 -276.386796) (xy 106.237949 -276.402844) (xy 106.284223 -276.426422)
			(xy 106.326239 -276.456948) (xy 106.362962 -276.493671) (xy 106.393488 -276.535687) (xy 106.417066 -276.581961)
			(xy 106.433114 -276.631354) (xy 106.441239 -276.682649) (xy 106.441748 -276.708616) (xy 106.441239 -276.734583)
			(xy 106.433114 -276.785878) (xy 106.417066 -276.835271) (xy 106.393488 -276.881545) (xy 106.362962 -276.923561)
			(xy 106.326239 -276.960284) (xy 106.284223 -276.99081) (xy 106.237949 -277.014388) (xy 106.188556 -277.030436)
			(xy 106.137261 -277.038561) (xy 106.085327 -277.038561) (xy 106.034032 -277.030436) (xy 105.984639 -277.014388)
			(xy 105.938365 -276.99081) (xy 105.896349 -276.960284) (xy 105.859626 -276.923561) (xy 105.8291 -276.881545)
			(xy 105.805522 -276.835271) (xy 105.789474 -276.785878) (xy 105.781349 -276.734583) (xy 105.501658 -276.734583)
			(xy 105.493538 -276.785859) (xy 105.477491 -276.83525) (xy 105.453916 -276.881523) (xy 105.423394 -276.923539)
			(xy 105.386675 -276.960263) (xy 105.344664 -276.990791) (xy 105.298394 -277.014373) (xy 105.249006 -277.030426)
			(xy 105.197714 -277.038557) (xy 105.171748 -277.03907) (xy 105.146127 -277.038584) (xy 105.0955 -277.030661)
			(xy 105.0467 -277.015027) (xy 105.000894 -276.992057) (xy 104.959176 -276.9623) (xy 104.922545 -276.926467)
			(xy 104.906826 -276.906228) (xy 104.49687 -276.906228) (xy 104.481157 -276.926474) (xy 104.444538 -276.962325)
			(xy 104.402823 -276.992093) (xy 104.357013 -277.015064) (xy 104.308206 -277.030689) (xy 104.257572 -277.038592)
			(xy 104.231948 -277.03907) (xy 104.205977 -277.038559) (xy 104.154675 -277.03044) (xy 104.105274 -277.014395)
			(xy 104.058992 -276.990819) (xy 104.016969 -276.960293) (xy 103.980238 -276.923568) (xy 103.949706 -276.881549)
			(xy 103.926123 -276.83527) (xy 103.910071 -276.785872) (xy 103.901945 -276.73457) (xy 103.622093 -276.73457)
			(xy 103.622053 -276.736602) (xy 103.6126 -276.79177) (xy 103.603806 -276.818344) (xy 103.595932 -276.840442)
			(xy 103.79964 -277.193248) (xy 103.822754 -277.197566) (xy 103.847678 -277.202724) (xy 103.895662 -277.21969)
			(xy 103.940479 -277.243809) (xy 103.981072 -277.274511) (xy 104.01648 -277.31107) (xy 104.045868 -277.352624)
			(xy 104.068542 -277.39819) (xy 104.083965 -277.446692) (xy 104.091775 -277.496984) (xy 104.092248 -277.522432)
			(xy 104.091739 -277.548399) (xy 104.371649 -277.548399) (xy 104.371649 -277.496465) (xy 104.379774 -277.44517)
			(xy 104.395822 -277.395777) (xy 104.4194 -277.349503) (xy 104.449926 -277.307487) (xy 104.486649 -277.270764)
			(xy 104.528665 -277.240238) (xy 104.574939 -277.21666) (xy 104.624332 -277.200612) (xy 104.675627 -277.192487)
			(xy 104.727561 -277.192487) (xy 104.778856 -277.200612) (xy 104.828249 -277.21666) (xy 104.874523 -277.240238)
			(xy 104.916539 -277.270764) (xy 104.953262 -277.307487) (xy 104.983788 -277.349503) (xy 105.007366 -277.395777)
			(xy 105.023414 -277.44517) (xy 105.031539 -277.496465) (xy 105.032048 -277.522432) (xy 105.031539 -277.548399)
			(xy 105.311449 -277.548399) (xy 105.311449 -277.496465) (xy 105.319574 -277.44517) (xy 105.335622 -277.395777)
			(xy 105.3592 -277.349503) (xy 105.389726 -277.307487) (xy 105.426449 -277.270764) (xy 105.468465 -277.240238)
			(xy 105.514739 -277.21666) (xy 105.564132 -277.200612) (xy 105.615427 -277.192487) (xy 105.667361 -277.192487)
			(xy 105.718656 -277.200612) (xy 105.768049 -277.21666) (xy 105.814323 -277.240238) (xy 105.856339 -277.270764)
			(xy 105.893062 -277.307487) (xy 105.923588 -277.349503) (xy 105.947166 -277.395777) (xy 105.963214 -277.44517)
			(xy 105.971339 -277.496465) (xy 105.971848 -277.522432) (xy 106.25074 -277.522432) (xy 106.25117 -277.496979)
			(xy 106.258958 -277.446674) (xy 106.27437 -277.398158) (xy 106.297041 -277.35258) (xy 106.326434 -277.311018)
			(xy 106.361854 -277.274457) (xy 106.402464 -277.243761) (xy 106.4473 -277.219658) (xy 106.495304 -277.202716)
			(xy 106.520234 -277.197566) (xy 106.543348 -277.193248) (xy 106.74731 -276.839934) (xy 106.739436 -276.817836)
			(xy 106.730817 -276.791421) (xy 106.72149 -276.736649) (xy 106.720894 -276.70887) (xy 106.720894 -276.708616)
			(xy 106.721403 -276.682649) (xy 106.729528 -276.631354) (xy 106.745576 -276.581961) (xy 106.769154 -276.535687)
			(xy 106.79968 -276.493671) (xy 106.836403 -276.456948) (xy 106.878419 -276.426422) (xy 106.924693 -276.402844)
			(xy 106.974086 -276.386796) (xy 107.025381 -276.378671) (xy 107.077315 -276.378671) (xy 107.12861 -276.386796)
			(xy 107.178003 -276.402844) (xy 107.224277 -276.426422) (xy 107.266293 -276.456948) (xy 107.303016 -276.493671)
			(xy 107.333542 -276.535687) (xy 107.35712 -276.581961) (xy 107.373168 -276.631354) (xy 107.381293 -276.682649)
			(xy 107.381802 -276.708616) (xy 107.381295 -276.734088) (xy 107.373475 -276.784428) (xy 107.358022 -276.832971)
			(xy 107.335303 -276.878568) (xy 107.305855 -276.920138) (xy 107.270377 -276.956697) (xy 107.229708 -276.987378)
			(xy 107.184813 -277.011454) (xy 107.136755 -277.028356) (xy 107.1118 -277.033482) (xy 107.08894 -277.0378)
			(xy 106.885232 -277.390606) (xy 106.892852 -277.412704) (xy 106.901589 -277.439292) (xy 106.911037 -277.494451)
			(xy 106.911648 -277.522432) (xy 106.911139 -277.548399) (xy 106.903014 -277.599694) (xy 106.886966 -277.649087)
			(xy 106.863388 -277.695361) (xy 106.832862 -277.737377) (xy 106.796139 -277.7741) (xy 106.754123 -277.804626)
			(xy 106.707849 -277.828204) (xy 106.658456 -277.844252) (xy 106.607161 -277.852377) (xy 106.555227 -277.852377)
			(xy 106.503932 -277.844252) (xy 106.454539 -277.828204) (xy 106.408265 -277.804626) (xy 106.366249 -277.7741)
			(xy 106.329526 -277.737377) (xy 106.299 -277.695361) (xy 106.275422 -277.649087) (xy 106.259374 -277.599694)
			(xy 106.251249 -277.548399) (xy 106.25074 -277.522432) (xy 105.971848 -277.522432) (xy 105.971339 -277.548399)
			(xy 105.963214 -277.599694) (xy 105.947166 -277.649087) (xy 105.923588 -277.695361) (xy 105.893062 -277.737377)
			(xy 105.856339 -277.7741) (xy 105.814323 -277.804626) (xy 105.768049 -277.828204) (xy 105.718656 -277.844252)
			(xy 105.667361 -277.852377) (xy 105.615427 -277.852377) (xy 105.564132 -277.844252) (xy 105.514739 -277.828204)
			(xy 105.468465 -277.804626) (xy 105.426449 -277.7741) (xy 105.389726 -277.737377) (xy 105.3592 -277.695361)
			(xy 105.335622 -277.649087) (xy 105.319574 -277.599694) (xy 105.311449 -277.548399) (xy 105.031539 -277.548399)
			(xy 105.023414 -277.599694) (xy 105.007366 -277.649087) (xy 104.983788 -277.695361) (xy 104.953262 -277.737377)
			(xy 104.916539 -277.7741) (xy 104.874523 -277.804626) (xy 104.828249 -277.828204) (xy 104.778856 -277.844252)
			(xy 104.727561 -277.852377) (xy 104.675627 -277.852377) (xy 104.624332 -277.844252) (xy 104.574939 -277.828204)
			(xy 104.528665 -277.804626) (xy 104.486649 -277.7741) (xy 104.449926 -277.737377) (xy 104.4194 -277.695361)
			(xy 104.395822 -277.649087) (xy 104.379774 -277.599694) (xy 104.371649 -277.548399) (xy 104.091739 -277.548399)
			(xy 104.083614 -277.599694) (xy 104.067566 -277.649087) (xy 104.043988 -277.695361) (xy 104.013462 -277.737377)
			(xy 103.976739 -277.7741) (xy 103.934723 -277.804626) (xy 103.888449 -277.828204) (xy 103.839056 -277.844252)
			(xy 103.787761 -277.852377) (xy 103.735827 -277.852377) (xy 103.684532 -277.844252) (xy 103.635139 -277.828204)
			(xy 103.588865 -277.804626) (xy 103.546849 -277.7741) (xy 103.510126 -277.737377) (xy 103.4796 -277.695361)
			(xy 103.456022 -277.649087) (xy 103.439974 -277.599694) (xy 103.431849 -277.548399) (xy 103.43134 -277.522432)
			(xy 103.431899 -277.494446) (xy 103.441344 -277.439278) (xy 103.450136 -277.412704) (xy 103.457756 -277.390606)
			(xy 103.254048 -277.0378) (xy 103.231188 -277.033482) (xy 103.206259 -277.028343) (xy 103.158271 -277.011378)
			(xy 103.11345 -276.98726) (xy 103.072856 -276.956557) (xy 103.037446 -276.919995) (xy 103.008058 -276.878438)
			(xy 102.985386 -276.832868) (xy 102.969967 -276.784362) (xy 102.962164 -276.734065) (xy 102.961694 -276.708616)
			(xy 102.682548 -276.708616) (xy 102.682039 -276.734583) (xy 102.673914 -276.785878) (xy 102.657866 -276.835271)
			(xy 102.634288 -276.881545) (xy 102.603762 -276.923561) (xy 102.567039 -276.960284) (xy 102.525023 -276.99081)
			(xy 102.478749 -277.014388) (xy 102.429356 -277.030436) (xy 102.378061 -277.038561) (xy 102.326127 -277.038561)
			(xy 102.274832 -277.030436) (xy 102.225439 -277.014388) (xy 102.179165 -276.99081) (xy 102.137149 -276.960284)
			(xy 102.100426 -276.923561) (xy 102.0699 -276.881545) (xy 102.046322 -276.835271) (xy 102.030274 -276.785878)
			(xy 102.022149 -276.734583) (xy 102.02164 -276.708616) (xy 101.743002 -276.708616) (xy 101.742493 -276.734583)
			(xy 101.734368 -276.785878) (xy 101.71832 -276.835271) (xy 101.694742 -276.881545) (xy 101.664216 -276.923561)
			(xy 101.627493 -276.960284) (xy 101.585477 -276.99081) (xy 101.539203 -277.014388) (xy 101.48981 -277.030436)
			(xy 101.438515 -277.038561) (xy 101.386581 -277.038561) (xy 101.335286 -277.030436) (xy 101.285893 -277.014388)
			(xy 101.239619 -276.99081) (xy 101.197603 -276.960284) (xy 101.16088 -276.923561) (xy 101.130354 -276.881545)
			(xy 101.106776 -276.835271) (xy 101.090728 -276.785878) (xy 101.082603 -276.734583) (xy 100.802693 -276.734583)
			(xy 100.794568 -276.785878) (xy 100.77852 -276.835271) (xy 100.754942 -276.881545) (xy 100.724416 -276.923561)
			(xy 100.687693 -276.960284) (xy 100.645677 -276.99081) (xy 100.599403 -277.014388) (xy 100.55001 -277.030436)
			(xy 100.498715 -277.038561) (xy 100.446781 -277.038561) (xy 100.395486 -277.030436) (xy 100.346093 -277.014388)
			(xy 100.299819 -276.99081) (xy 100.257803 -276.960284) (xy 100.22108 -276.923561) (xy 100.190554 -276.881545)
			(xy 100.166976 -276.835271) (xy 100.150928 -276.785878) (xy 100.142803 -276.734583) (xy 99.862893 -276.734583)
			(xy 99.854768 -276.785878) (xy 99.83872 -276.835271) (xy 99.815142 -276.881545) (xy 99.784616 -276.923561)
			(xy 99.747893 -276.960284) (xy 99.705877 -276.99081) (xy 99.659603 -277.014388) (xy 99.61021 -277.030436)
			(xy 99.558915 -277.038561) (xy 99.506981 -277.038561) (xy 99.455686 -277.030436) (xy 99.406293 -277.014388)
			(xy 99.360019 -276.99081) (xy 99.318003 -276.960284) (xy 99.28128 -276.923561) (xy 99.250754 -276.881545)
			(xy 99.227176 -276.835271) (xy 99.211128 -276.785878) (xy 99.203003 -276.734583) (xy 98.923093 -276.734583)
			(xy 98.914968 -276.785878) (xy 98.89892 -276.835271) (xy 98.875342 -276.881545) (xy 98.844816 -276.923561)
			(xy 98.808093 -276.960284) (xy 98.766077 -276.99081) (xy 98.719803 -277.014388) (xy 98.67041 -277.030436)
			(xy 98.619115 -277.038561) (xy 98.567181 -277.038561) (xy 98.515886 -277.030436) (xy 98.466493 -277.014388)
			(xy 98.420219 -276.99081) (xy 98.378203 -276.960284) (xy 98.34148 -276.923561) (xy 98.310954 -276.881545)
			(xy 98.287376 -276.835271) (xy 98.271328 -276.785878) (xy 98.263203 -276.734583) (xy 97.983039 -276.734583)
			(xy 97.974914 -276.785878) (xy 97.958866 -276.835271) (xy 97.935288 -276.881545) (xy 97.904762 -276.923561)
			(xy 97.868039 -276.960284) (xy 97.826023 -276.99081) (xy 97.779749 -277.014388) (xy 97.730356 -277.030436)
			(xy 97.679061 -277.038561) (xy 97.627127 -277.038561) (xy 97.575832 -277.030436) (xy 97.526439 -277.014388)
			(xy 97.480165 -276.99081) (xy 97.438149 -276.960284) (xy 97.401426 -276.923561) (xy 97.3709 -276.881545)
			(xy 97.347322 -276.835271) (xy 97.331274 -276.785878) (xy 97.323149 -276.734583) (xy 97.043493 -276.734583)
			(xy 97.035368 -276.785878) (xy 97.01932 -276.835271) (xy 96.995742 -276.881545) (xy 96.965216 -276.923561)
			(xy 96.928493 -276.960284) (xy 96.886477 -276.99081) (xy 96.840203 -277.014388) (xy 96.79081 -277.030436)
			(xy 96.739515 -277.038561) (xy 96.687581 -277.038561) (xy 96.636286 -277.030436) (xy 96.586893 -277.014388)
			(xy 96.540619 -276.99081) (xy 96.498603 -276.960284) (xy 96.46188 -276.923561) (xy 96.431354 -276.881545)
			(xy 96.407776 -276.835271) (xy 96.391728 -276.785878) (xy 96.383603 -276.734583) (xy 96.103693 -276.734583)
			(xy 96.095568 -276.785878) (xy 96.07952 -276.835271) (xy 96.055942 -276.881545) (xy 96.025416 -276.923561)
			(xy 95.988693 -276.960284) (xy 95.946677 -276.99081) (xy 95.900403 -277.014388) (xy 95.85101 -277.030436)
			(xy 95.799715 -277.038561) (xy 95.747781 -277.038561) (xy 95.696486 -277.030436) (xy 95.647093 -277.014388)
			(xy 95.600819 -276.99081) (xy 95.558803 -276.960284) (xy 95.52208 -276.923561) (xy 95.491554 -276.881545)
			(xy 95.467976 -276.835271) (xy 95.451928 -276.785878) (xy 95.443803 -276.734583) (xy 95.163893 -276.734583)
			(xy 95.155768 -276.785878) (xy 95.13972 -276.835271) (xy 95.116142 -276.881545) (xy 95.085616 -276.923561)
			(xy 95.048893 -276.960284) (xy 95.006877 -276.99081) (xy 94.960603 -277.014388) (xy 94.91121 -277.030436)
			(xy 94.859915 -277.038561) (xy 94.807981 -277.038561) (xy 94.756686 -277.030436) (xy 94.707293 -277.014388)
			(xy 94.661019 -276.99081) (xy 94.619003 -276.960284) (xy 94.58228 -276.923561) (xy 94.551754 -276.881545)
			(xy 94.528176 -276.835271) (xy 94.512128 -276.785878) (xy 94.504003 -276.734583) (xy 94.224093 -276.734583)
			(xy 94.215968 -276.785878) (xy 94.19992 -276.835271) (xy 94.176342 -276.881545) (xy 94.145816 -276.923561)
			(xy 94.109093 -276.960284) (xy 94.067077 -276.99081) (xy 94.020803 -277.014388) (xy 93.97141 -277.030436)
			(xy 93.920115 -277.038561) (xy 93.868181 -277.038561) (xy 93.816886 -277.030436) (xy 93.767493 -277.014388)
			(xy 93.721219 -276.99081) (xy 93.679203 -276.960284) (xy 93.64248 -276.923561) (xy 93.611954 -276.881545)
			(xy 93.588376 -276.835271) (xy 93.572328 -276.785878) (xy 93.564203 -276.734583) (xy 93.284293 -276.734583)
			(xy 93.276168 -276.785878) (xy 93.26012 -276.835271) (xy 93.236542 -276.881545) (xy 93.206016 -276.923561)
			(xy 93.169293 -276.960284) (xy 93.127277 -276.99081) (xy 93.081003 -277.014388) (xy 93.03161 -277.030436)
			(xy 92.980315 -277.038561) (xy 92.928381 -277.038561) (xy 92.877086 -277.030436) (xy 92.827693 -277.014388)
			(xy 92.781419 -276.99081) (xy 92.739403 -276.960284) (xy 92.70268 -276.923561) (xy 92.672154 -276.881545)
			(xy 92.648576 -276.835271) (xy 92.632528 -276.785878) (xy 92.624403 -276.734583) (xy 92.344683 -276.734583)
			(xy 92.344683 -276.734584) (xy 92.336554 -276.785911) (xy 92.320497 -276.835335) (xy 92.296906 -276.881639)
			(xy 92.266363 -276.923683) (xy 92.22962 -276.960432) (xy 92.18758 -276.990981) (xy 92.141279 -277.014578)
			(xy 92.091858 -277.030643) (xy 92.040531 -277.038779) (xy 92.014548 -277.039324) (xy 91.991674 -277.038941)
			(xy 91.946361 -277.032646) (xy 91.902347 -277.020169) (xy 91.860471 -277.001748) (xy 91.840812 -276.990048)
			(xy 91.840558 -276.989794) (xy 91.833071 -276.985608) (xy 91.816298 -276.982076) (xy 91.799314 -276.984398)
			(xy 91.791536 -276.988016) (xy 91.751658 -277.010114) (xy 91.713304 -277.03145) (xy 91.705714 -277.036087)
			(xy 91.694149 -277.049584) (xy 91.687973 -277.066251) (xy 91.68765 -277.075138) (xy 91.68765 -277.194518)
			(xy 91.712034 -277.236936) (xy 91.718638 -277.241254) (xy 91.74036 -277.255304) (xy 91.779552 -277.289067)
			(xy 91.813009 -277.32852) (xy 91.839917 -277.3727) (xy 91.859619 -277.420531) (xy 91.871635 -277.470845)
			(xy 91.875671 -277.522417) (xy 91.873635 -277.548399) (xy 92.154249 -277.548399) (xy 92.154249 -277.496465)
			(xy 92.162374 -277.44517) (xy 92.178422 -277.395777) (xy 92.202 -277.349503) (xy 92.232526 -277.307487)
			(xy 92.269249 -277.270764) (xy 92.311265 -277.240238) (xy 92.357539 -277.21666) (xy 92.406932 -277.200612)
			(xy 92.458227 -277.192487) (xy 92.510161 -277.192487) (xy 92.561456 -277.200612) (xy 92.610849 -277.21666)
			(xy 92.657123 -277.240238) (xy 92.699139 -277.270764) (xy 92.735862 -277.307487) (xy 92.766388 -277.349503)
			(xy 92.789966 -277.395777) (xy 92.806014 -277.44517) (xy 92.814139 -277.496465) (xy 92.814648 -277.522432)
			(xy 92.814139 -277.548399) (xy 93.094049 -277.548399) (xy 93.094049 -277.496465) (xy 93.102174 -277.44517)
			(xy 93.118222 -277.395777) (xy 93.1418 -277.349503) (xy 93.172326 -277.307487) (xy 93.209049 -277.270764)
			(xy 93.251065 -277.240238) (xy 93.297339 -277.21666) (xy 93.346732 -277.200612) (xy 93.398027 -277.192487)
			(xy 93.449961 -277.192487) (xy 93.501256 -277.200612) (xy 93.550649 -277.21666) (xy 93.596923 -277.240238)
			(xy 93.638939 -277.270764) (xy 93.675662 -277.307487) (xy 93.706188 -277.349503) (xy 93.729766 -277.395777)
			(xy 93.745814 -277.44517) (xy 93.753939 -277.496465) (xy 93.754448 -277.522432) (xy 93.753939 -277.548399)
			(xy 94.033849 -277.548399) (xy 94.033849 -277.496465) (xy 94.041974 -277.44517) (xy 94.058022 -277.395777)
			(xy 94.0816 -277.349503) (xy 94.112126 -277.307487) (xy 94.148849 -277.270764) (xy 94.190865 -277.240238)
			(xy 94.237139 -277.21666) (xy 94.286532 -277.200612) (xy 94.337827 -277.192487) (xy 94.389761 -277.192487)
			(xy 94.441056 -277.200612) (xy 94.490449 -277.21666) (xy 94.536723 -277.240238) (xy 94.578739 -277.270764)
			(xy 94.615462 -277.307487) (xy 94.645988 -277.349503) (xy 94.669566 -277.395777) (xy 94.685614 -277.44517)
			(xy 94.693739 -277.496465) (xy 94.694248 -277.522432) (xy 94.693739 -277.548399) (xy 94.973649 -277.548399)
			(xy 94.973649 -277.496465) (xy 94.981774 -277.44517) (xy 94.997822 -277.395777) (xy 95.0214 -277.349503)
			(xy 95.051926 -277.307487) (xy 95.088649 -277.270764) (xy 95.130665 -277.240238) (xy 95.176939 -277.21666)
			(xy 95.226332 -277.200612) (xy 95.277627 -277.192487) (xy 95.329561 -277.192487) (xy 95.380856 -277.200612)
			(xy 95.430249 -277.21666) (xy 95.476523 -277.240238) (xy 95.518539 -277.270764) (xy 95.555262 -277.307487)
			(xy 95.585788 -277.349503) (xy 95.609366 -277.395777) (xy 95.625414 -277.44517) (xy 95.633539 -277.496465)
			(xy 95.634048 -277.522432) (xy 95.633539 -277.548399) (xy 95.913449 -277.548399) (xy 95.913449 -277.496465)
			(xy 95.921574 -277.44517) (xy 95.937622 -277.395777) (xy 95.9612 -277.349503) (xy 95.991726 -277.307487)
			(xy 96.028449 -277.270764) (xy 96.070465 -277.240238) (xy 96.116739 -277.21666) (xy 96.166132 -277.200612)
			(xy 96.217427 -277.192487) (xy 96.269361 -277.192487) (xy 96.320656 -277.200612) (xy 96.370049 -277.21666)
			(xy 96.416323 -277.240238) (xy 96.458339 -277.270764) (xy 96.495062 -277.307487) (xy 96.525588 -277.349503)
			(xy 96.549166 -277.395777) (xy 96.565214 -277.44517) (xy 96.573339 -277.496465) (xy 96.573848 -277.522432)
			(xy 96.573339 -277.548399) (xy 96.853249 -277.548399) (xy 96.853249 -277.496465) (xy 96.861374 -277.44517)
			(xy 96.877422 -277.395777) (xy 96.901 -277.349503) (xy 96.931526 -277.307487) (xy 96.968249 -277.270764)
			(xy 97.010265 -277.240238) (xy 97.056539 -277.21666) (xy 97.105932 -277.200612) (xy 97.157227 -277.192487)
			(xy 97.209161 -277.192487) (xy 97.260456 -277.200612) (xy 97.309849 -277.21666) (xy 97.356123 -277.240238)
			(xy 97.398139 -277.270764) (xy 97.434862 -277.307487) (xy 97.465388 -277.349503) (xy 97.488966 -277.395777)
			(xy 97.505014 -277.44517) (xy 97.513139 -277.496465) (xy 97.513648 -277.522432) (xy 97.513139 -277.548399)
			(xy 97.793049 -277.548399) (xy 97.793049 -277.496465) (xy 97.801174 -277.44517) (xy 97.817222 -277.395777)
			(xy 97.8408 -277.349503) (xy 97.871326 -277.307487) (xy 97.908049 -277.270764) (xy 97.950065 -277.240238)
			(xy 97.996339 -277.21666) (xy 98.045732 -277.200612) (xy 98.097027 -277.192487) (xy 98.148961 -277.192487)
			(xy 98.200256 -277.200612) (xy 98.249649 -277.21666) (xy 98.295923 -277.240238) (xy 98.337939 -277.270764)
			(xy 98.374662 -277.307487) (xy 98.405188 -277.349503) (xy 98.428766 -277.395777) (xy 98.444814 -277.44517)
			(xy 98.452939 -277.496465) (xy 98.453448 -277.522432) (xy 98.452939 -277.548399) (xy 98.732849 -277.548399)
			(xy 98.732849 -277.496465) (xy 98.740974 -277.44517) (xy 98.757022 -277.395777) (xy 98.7806 -277.349503)
			(xy 98.811126 -277.307487) (xy 98.847849 -277.270764) (xy 98.889865 -277.240238) (xy 98.936139 -277.21666)
			(xy 98.985532 -277.200612) (xy 99.036827 -277.192487) (xy 99.088761 -277.192487) (xy 99.140056 -277.200612)
			(xy 99.189449 -277.21666) (xy 99.235723 -277.240238) (xy 99.277739 -277.270764) (xy 99.314462 -277.307487)
			(xy 99.344988 -277.349503) (xy 99.368566 -277.395777) (xy 99.384614 -277.44517) (xy 99.392739 -277.496465)
			(xy 99.393248 -277.522432) (xy 99.392739 -277.548399) (xy 99.672649 -277.548399) (xy 99.672649 -277.496465)
			(xy 99.680774 -277.44517) (xy 99.696822 -277.395777) (xy 99.7204 -277.349503) (xy 99.750926 -277.307487)
			(xy 99.787649 -277.270764) (xy 99.829665 -277.240238) (xy 99.875939 -277.21666) (xy 99.925332 -277.200612)
			(xy 99.976627 -277.192487) (xy 100.028561 -277.192487) (xy 100.079856 -277.200612) (xy 100.129249 -277.21666)
			(xy 100.175523 -277.240238) (xy 100.217539 -277.270764) (xy 100.254262 -277.307487) (xy 100.284788 -277.349503)
			(xy 100.308366 -277.395777) (xy 100.324414 -277.44517) (xy 100.332539 -277.496465) (xy 100.333048 -277.522432)
			(xy 100.332539 -277.548399) (xy 100.612449 -277.548399) (xy 100.612449 -277.496465) (xy 100.620574 -277.44517)
			(xy 100.636622 -277.395777) (xy 100.6602 -277.349503) (xy 100.690726 -277.307487) (xy 100.727449 -277.270764)
			(xy 100.769465 -277.240238) (xy 100.815739 -277.21666) (xy 100.865132 -277.200612) (xy 100.916427 -277.192487)
			(xy 100.968361 -277.192487) (xy 101.019656 -277.200612) (xy 101.069049 -277.21666) (xy 101.115323 -277.240238)
			(xy 101.157339 -277.270764) (xy 101.194062 -277.307487) (xy 101.224588 -277.349503) (xy 101.248166 -277.395777)
			(xy 101.264214 -277.44517) (xy 101.272339 -277.496465) (xy 101.272848 -277.522432) (xy 101.272339 -277.548399)
			(xy 101.552503 -277.548399) (xy 101.552503 -277.496465) (xy 101.560628 -277.44517) (xy 101.576676 -277.395777)
			(xy 101.600254 -277.349503) (xy 101.63078 -277.307487) (xy 101.667503 -277.270764) (xy 101.709519 -277.240238)
			(xy 101.755793 -277.21666) (xy 101.805186 -277.200612) (xy 101.856481 -277.192487) (xy 101.908415 -277.192487)
			(xy 101.95971 -277.200612) (xy 102.009103 -277.21666) (xy 102.055377 -277.240238) (xy 102.097393 -277.270764)
			(xy 102.134116 -277.307487) (xy 102.164642 -277.349503) (xy 102.18822 -277.395777) (xy 102.204268 -277.44517)
			(xy 102.212393 -277.496465) (xy 102.212902 -277.522432) (xy 102.212393 -277.548399) (xy 102.204268 -277.599694)
			(xy 102.18822 -277.649087) (xy 102.164642 -277.695361) (xy 102.134116 -277.737377) (xy 102.097393 -277.7741)
			(xy 102.055377 -277.804626) (xy 102.009103 -277.828204) (xy 101.95971 -277.844252) (xy 101.908415 -277.852377)
			(xy 101.856481 -277.852377) (xy 101.805186 -277.844252) (xy 101.755793 -277.828204) (xy 101.709519 -277.804626)
			(xy 101.667503 -277.7741) (xy 101.63078 -277.737377) (xy 101.600254 -277.695361) (xy 101.576676 -277.649087)
			(xy 101.560628 -277.599694) (xy 101.552503 -277.548399) (xy 101.272339 -277.548399) (xy 101.264214 -277.599694)
			(xy 101.248166 -277.649087) (xy 101.224588 -277.695361) (xy 101.194062 -277.737377) (xy 101.157339 -277.7741)
			(xy 101.115323 -277.804626) (xy 101.069049 -277.828204) (xy 101.019656 -277.844252) (xy 100.968361 -277.852377)
			(xy 100.916427 -277.852377) (xy 100.865132 -277.844252) (xy 100.815739 -277.828204) (xy 100.769465 -277.804626)
			(xy 100.727449 -277.7741) (xy 100.690726 -277.737377) (xy 100.6602 -277.695361) (xy 100.636622 -277.649087)
			(xy 100.620574 -277.599694) (xy 100.612449 -277.548399) (xy 100.332539 -277.548399) (xy 100.324414 -277.599694)
			(xy 100.308366 -277.649087) (xy 100.284788 -277.695361) (xy 100.254262 -277.737377) (xy 100.217539 -277.7741)
			(xy 100.175523 -277.804626) (xy 100.129249 -277.828204) (xy 100.079856 -277.844252) (xy 100.028561 -277.852377)
			(xy 99.976627 -277.852377) (xy 99.925332 -277.844252) (xy 99.875939 -277.828204) (xy 99.829665 -277.804626)
			(xy 99.787649 -277.7741) (xy 99.750926 -277.737377) (xy 99.7204 -277.695361) (xy 99.696822 -277.649087)
			(xy 99.680774 -277.599694) (xy 99.672649 -277.548399) (xy 99.392739 -277.548399) (xy 99.384614 -277.599694)
			(xy 99.368566 -277.649087) (xy 99.344988 -277.695361) (xy 99.314462 -277.737377) (xy 99.277739 -277.7741)
			(xy 99.235723 -277.804626) (xy 99.189449 -277.828204) (xy 99.140056 -277.844252) (xy 99.088761 -277.852377)
			(xy 99.036827 -277.852377) (xy 98.985532 -277.844252) (xy 98.936139 -277.828204) (xy 98.889865 -277.804626)
			(xy 98.847849 -277.7741) (xy 98.811126 -277.737377) (xy 98.7806 -277.695361) (xy 98.757022 -277.649087)
			(xy 98.740974 -277.599694) (xy 98.732849 -277.548399) (xy 98.452939 -277.548399) (xy 98.444814 -277.599694)
			(xy 98.428766 -277.649087) (xy 98.405188 -277.695361) (xy 98.374662 -277.737377) (xy 98.337939 -277.7741)
			(xy 98.295923 -277.804626) (xy 98.249649 -277.828204) (xy 98.200256 -277.844252) (xy 98.148961 -277.852377)
			(xy 98.097027 -277.852377) (xy 98.045732 -277.844252) (xy 97.996339 -277.828204) (xy 97.950065 -277.804626)
			(xy 97.908049 -277.7741) (xy 97.871326 -277.737377) (xy 97.8408 -277.695361) (xy 97.817222 -277.649087)
			(xy 97.801174 -277.599694) (xy 97.793049 -277.548399) (xy 97.513139 -277.548399) (xy 97.505014 -277.599694)
			(xy 97.488966 -277.649087) (xy 97.465388 -277.695361) (xy 97.434862 -277.737377) (xy 97.398139 -277.7741)
			(xy 97.356123 -277.804626) (xy 97.309849 -277.828204) (xy 97.260456 -277.844252) (xy 97.209161 -277.852377)
			(xy 97.157227 -277.852377) (xy 97.105932 -277.844252) (xy 97.056539 -277.828204) (xy 97.010265 -277.804626)
			(xy 96.968249 -277.7741) (xy 96.931526 -277.737377) (xy 96.901 -277.695361) (xy 96.877422 -277.649087)
			(xy 96.861374 -277.599694) (xy 96.853249 -277.548399) (xy 96.573339 -277.548399) (xy 96.565214 -277.599694)
			(xy 96.549166 -277.649087) (xy 96.525588 -277.695361) (xy 96.495062 -277.737377) (xy 96.458339 -277.7741)
			(xy 96.416323 -277.804626) (xy 96.370049 -277.828204) (xy 96.320656 -277.844252) (xy 96.269361 -277.852377)
			(xy 96.217427 -277.852377) (xy 96.166132 -277.844252) (xy 96.116739 -277.828204) (xy 96.070465 -277.804626)
			(xy 96.028449 -277.7741) (xy 95.991726 -277.737377) (xy 95.9612 -277.695361) (xy 95.937622 -277.649087)
			(xy 95.921574 -277.599694) (xy 95.913449 -277.548399) (xy 95.633539 -277.548399) (xy 95.625414 -277.599694)
			(xy 95.609366 -277.649087) (xy 95.585788 -277.695361) (xy 95.555262 -277.737377) (xy 95.518539 -277.7741)
			(xy 95.476523 -277.804626) (xy 95.430249 -277.828204) (xy 95.380856 -277.844252) (xy 95.329561 -277.852377)
			(xy 95.277627 -277.852377) (xy 95.226332 -277.844252) (xy 95.176939 -277.828204) (xy 95.130665 -277.804626)
			(xy 95.088649 -277.7741) (xy 95.051926 -277.737377) (xy 95.0214 -277.695361) (xy 94.997822 -277.649087)
			(xy 94.981774 -277.599694) (xy 94.973649 -277.548399) (xy 94.693739 -277.548399) (xy 94.685614 -277.599694)
			(xy 94.669566 -277.649087) (xy 94.645988 -277.695361) (xy 94.615462 -277.737377) (xy 94.578739 -277.7741)
			(xy 94.536723 -277.804626) (xy 94.490449 -277.828204) (xy 94.441056 -277.844252) (xy 94.389761 -277.852377)
			(xy 94.337827 -277.852377) (xy 94.286532 -277.844252) (xy 94.237139 -277.828204) (xy 94.190865 -277.804626)
			(xy 94.148849 -277.7741) (xy 94.112126 -277.737377) (xy 94.0816 -277.695361) (xy 94.058022 -277.649087)
			(xy 94.041974 -277.599694) (xy 94.033849 -277.548399) (xy 93.753939 -277.548399) (xy 93.745814 -277.599694)
			(xy 93.729766 -277.649087) (xy 93.706188 -277.695361) (xy 93.675662 -277.737377) (xy 93.638939 -277.7741)
			(xy 93.596923 -277.804626) (xy 93.550649 -277.828204) (xy 93.501256 -277.844252) (xy 93.449961 -277.852377)
			(xy 93.398027 -277.852377) (xy 93.346732 -277.844252) (xy 93.297339 -277.828204) (xy 93.251065 -277.804626)
			(xy 93.209049 -277.7741) (xy 93.172326 -277.737377) (xy 93.1418 -277.695361) (xy 93.118222 -277.649087)
			(xy 93.102174 -277.599694) (xy 93.094049 -277.548399) (xy 92.814139 -277.548399) (xy 92.806014 -277.599694)
			(xy 92.789966 -277.649087) (xy 92.766388 -277.695361) (xy 92.735862 -277.737377) (xy 92.699139 -277.7741)
			(xy 92.657123 -277.804626) (xy 92.610849 -277.828204) (xy 92.561456 -277.844252) (xy 92.510161 -277.852377)
			(xy 92.458227 -277.852377) (xy 92.406932 -277.844252) (xy 92.357539 -277.828204) (xy 92.311265 -277.804626)
			(xy 92.269249 -277.7741) (xy 92.232526 -277.737377) (xy 92.202 -277.695361) (xy 92.178422 -277.649087)
			(xy 92.162374 -277.599694) (xy 92.154249 -277.548399) (xy 91.873635 -277.548399) (xy 91.87163 -277.573988)
			(xy 91.859609 -277.624302) (xy 91.839902 -277.67213) (xy 91.81299 -277.716308) (xy 91.779528 -277.755757)
			(xy 91.740333 -277.789516) (xy 91.718638 -277.80361) (xy 91.712034 -277.807928) (xy 91.68765 -277.850346)
			(xy 91.68765 -277.96998) (xy 91.688001 -277.978867) (xy 91.694154 -277.995541) (xy 91.705705 -278.00905)
			(xy 91.713304 -278.013668) (xy 91.751658 -278.035004) (xy 91.791536 -278.057102) (xy 91.799315 -278.060713)
			(xy 91.816299 -278.063011) (xy 91.833076 -278.059513) (xy 91.840558 -278.055324) (xy 91.840812 -278.05507)
			(xy 91.860482 -278.04339) (xy 91.902354 -278.024963) (xy 91.946364 -278.012477) (xy 91.991675 -278.00617)
			(xy 92.014548 -278.005794) (xy 92.040533 -278.006307) (xy 92.091861 -278.014444) (xy 92.141285 -278.030509)
			(xy 92.187587 -278.054107) (xy 92.229629 -278.084657) (xy 92.266374 -278.121408) (xy 92.296918 -278.163454)
			(xy 92.32051 -278.20976) (xy 92.336568 -278.259186) (xy 92.344697 -278.310515) (xy 92.344697 -278.362469)
			(xy 92.624403 -278.362469) (xy 92.624403 -278.310535) (xy 92.632528 -278.25924) (xy 92.648576 -278.209847)
			(xy 92.672154 -278.163573) (xy 92.70268 -278.121557) (xy 92.739403 -278.084834) (xy 92.781419 -278.054308)
			(xy 92.827693 -278.03073) (xy 92.877086 -278.014682) (xy 92.928381 -278.006557) (xy 92.980315 -278.006557)
			(xy 93.03161 -278.014682) (xy 93.081003 -278.03073) (xy 93.127277 -278.054308) (xy 93.169293 -278.084834)
			(xy 93.206016 -278.121557) (xy 93.236542 -278.163573) (xy 93.26012 -278.209847) (xy 93.276168 -278.25924)
			(xy 93.284293 -278.310535) (xy 93.284802 -278.336502) (xy 93.284293 -278.362469) (xy 93.564203 -278.362469)
			(xy 93.564203 -278.310535) (xy 93.572328 -278.25924) (xy 93.588376 -278.209847) (xy 93.611954 -278.163573)
			(xy 93.64248 -278.121557) (xy 93.679203 -278.084834) (xy 93.721219 -278.054308) (xy 93.767493 -278.03073)
			(xy 93.816886 -278.014682) (xy 93.868181 -278.006557) (xy 93.920115 -278.006557) (xy 93.97141 -278.014682)
			(xy 94.020803 -278.03073) (xy 94.067077 -278.054308) (xy 94.109093 -278.084834) (xy 94.145816 -278.121557)
			(xy 94.176342 -278.163573) (xy 94.19992 -278.209847) (xy 94.215968 -278.25924) (xy 94.224093 -278.310535)
			(xy 94.224602 -278.336502) (xy 94.224093 -278.362469) (xy 94.504003 -278.362469) (xy 94.504003 -278.310535)
			(xy 94.512128 -278.25924) (xy 94.528176 -278.209847) (xy 94.551754 -278.163573) (xy 94.58228 -278.121557)
			(xy 94.619003 -278.084834) (xy 94.661019 -278.054308) (xy 94.707293 -278.03073) (xy 94.756686 -278.014682)
			(xy 94.807981 -278.006557) (xy 94.859915 -278.006557) (xy 94.91121 -278.014682) (xy 94.960603 -278.03073)
			(xy 95.006877 -278.054308) (xy 95.048893 -278.084834) (xy 95.085616 -278.121557) (xy 95.116142 -278.163573)
			(xy 95.13972 -278.209847) (xy 95.155768 -278.25924) (xy 95.163893 -278.310535) (xy 95.164402 -278.336502)
			(xy 95.163893 -278.362469) (xy 97.323403 -278.362469) (xy 97.323403 -278.310535) (xy 97.331528 -278.25924)
			(xy 97.347576 -278.209847) (xy 97.371154 -278.163573) (xy 97.40168 -278.121557) (xy 97.438403 -278.084834)
			(xy 97.480419 -278.054308) (xy 97.526693 -278.03073) (xy 97.576086 -278.014682) (xy 97.627381 -278.006557)
			(xy 97.679315 -278.006557) (xy 97.73061 -278.014682) (xy 97.780003 -278.03073) (xy 97.826277 -278.054308)
			(xy 97.868293 -278.084834) (xy 97.905016 -278.121557) (xy 97.935542 -278.163573) (xy 97.95912 -278.209847)
			(xy 97.975168 -278.25924) (xy 97.983293 -278.310535) (xy 97.983802 -278.336502) (xy 97.983293 -278.362469)
			(xy 98.263203 -278.362469) (xy 98.263203 -278.310535) (xy 98.271328 -278.25924) (xy 98.287376 -278.209847)
			(xy 98.310954 -278.163573) (xy 98.34148 -278.121557) (xy 98.378203 -278.084834) (xy 98.420219 -278.054308)
			(xy 98.466493 -278.03073) (xy 98.515886 -278.014682) (xy 98.567181 -278.006557) (xy 98.619115 -278.006557)
			(xy 98.67041 -278.014682) (xy 98.719803 -278.03073) (xy 98.766077 -278.054308) (xy 98.808093 -278.084834)
			(xy 98.844816 -278.121557) (xy 98.875342 -278.163573) (xy 98.89892 -278.209847) (xy 98.914968 -278.25924)
			(xy 98.923093 -278.310535) (xy 98.923602 -278.336502) (xy 98.923093 -278.362469) (xy 99.203003 -278.362469)
			(xy 99.203003 -278.310535) (xy 99.211128 -278.25924) (xy 99.227176 -278.209847) (xy 99.250754 -278.163573)
			(xy 99.28128 -278.121557) (xy 99.318003 -278.084834) (xy 99.360019 -278.054308) (xy 99.406293 -278.03073)
			(xy 99.455686 -278.014682) (xy 99.506981 -278.006557) (xy 99.558915 -278.006557) (xy 99.61021 -278.014682)
			(xy 99.659603 -278.03073) (xy 99.705877 -278.054308) (xy 99.747893 -278.084834) (xy 99.784616 -278.121557)
			(xy 99.815142 -278.163573) (xy 99.83872 -278.209847) (xy 99.854768 -278.25924) (xy 99.862893 -278.310535)
			(xy 99.863402 -278.336502) (xy 99.862893 -278.362469) (xy 100.142803 -278.362469) (xy 100.142803 -278.310535)
			(xy 100.150928 -278.25924) (xy 100.166976 -278.209847) (xy 100.190554 -278.163573) (xy 100.22108 -278.121557)
			(xy 100.257803 -278.084834) (xy 100.299819 -278.054308) (xy 100.346093 -278.03073) (xy 100.395486 -278.014682)
			(xy 100.446781 -278.006557) (xy 100.498715 -278.006557) (xy 100.55001 -278.014682) (xy 100.599403 -278.03073)
			(xy 100.645677 -278.054308) (xy 100.687693 -278.084834) (xy 100.724416 -278.121557) (xy 100.754942 -278.163573)
			(xy 100.77852 -278.209847) (xy 100.794568 -278.25924) (xy 100.802693 -278.310535) (xy 100.803202 -278.336502)
			(xy 100.802693 -278.362469) (xy 101.082349 -278.362469) (xy 101.082349 -278.310535) (xy 101.090474 -278.25924)
			(xy 101.106522 -278.209847) (xy 101.1301 -278.163573) (xy 101.160626 -278.121557) (xy 101.197349 -278.084834)
			(xy 101.239365 -278.054308) (xy 101.285639 -278.03073) (xy 101.335032 -278.014682) (xy 101.386327 -278.006557)
			(xy 101.438261 -278.006557) (xy 101.489556 -278.014682) (xy 101.538949 -278.03073) (xy 101.585223 -278.054308)
			(xy 101.627239 -278.084834) (xy 101.663962 -278.121557) (xy 101.694488 -278.163573) (xy 101.718066 -278.209847)
			(xy 101.734114 -278.25924) (xy 101.742239 -278.310535) (xy 101.742748 -278.336502) (xy 101.742239 -278.362469)
			(xy 102.022403 -278.362469) (xy 102.022403 -278.310535) (xy 102.030528 -278.25924) (xy 102.046576 -278.209847)
			(xy 102.070154 -278.163573) (xy 102.10068 -278.121557) (xy 102.137403 -278.084834) (xy 102.179419 -278.054308)
			(xy 102.225693 -278.03073) (xy 102.275086 -278.014682) (xy 102.326381 -278.006557) (xy 102.378315 -278.006557)
			(xy 102.42961 -278.014682) (xy 102.479003 -278.03073) (xy 102.525277 -278.054308) (xy 102.567293 -278.084834)
			(xy 102.604016 -278.121557) (xy 102.634542 -278.163573) (xy 102.65812 -278.209847) (xy 102.674168 -278.25924)
			(xy 102.682293 -278.310535) (xy 102.682802 -278.336502) (xy 102.682293 -278.362469) (xy 102.962203 -278.362469)
			(xy 102.962203 -278.310535) (xy 102.970328 -278.25924) (xy 102.986376 -278.209847) (xy 103.009954 -278.163573)
			(xy 103.04048 -278.121557) (xy 103.077203 -278.084834) (xy 103.119219 -278.054308) (xy 103.165493 -278.03073)
			(xy 103.214886 -278.014682) (xy 103.266181 -278.006557) (xy 103.318115 -278.006557) (xy 103.36941 -278.014682)
			(xy 103.418803 -278.03073) (xy 103.465077 -278.054308) (xy 103.507093 -278.084834) (xy 103.543816 -278.121557)
			(xy 103.574342 -278.163573) (xy 103.59792 -278.209847) (xy 103.613968 -278.25924) (xy 103.622093 -278.310535)
			(xy 103.622602 -278.336502) (xy 103.622093 -278.362469) (xy 103.902003 -278.362469) (xy 103.902003 -278.310535)
			(xy 103.910128 -278.25924) (xy 103.926176 -278.209847) (xy 103.949754 -278.163573) (xy 103.98028 -278.121557)
			(xy 104.017003 -278.084834) (xy 104.059019 -278.054308) (xy 104.105293 -278.03073) (xy 104.154686 -278.014682)
			(xy 104.205981 -278.006557) (xy 104.257915 -278.006557) (xy 104.30921 -278.014682) (xy 104.358603 -278.03073)
			(xy 104.404877 -278.054308) (xy 104.446893 -278.084834) (xy 104.483616 -278.121557) (xy 104.514142 -278.163573)
			(xy 104.53772 -278.209847) (xy 104.553768 -278.25924) (xy 104.561893 -278.310535) (xy 104.562402 -278.336502)
			(xy 104.561893 -278.362469) (xy 104.841549 -278.362469) (xy 104.841549 -278.310535) (xy 104.849674 -278.25924)
			(xy 104.865722 -278.209847) (xy 104.8893 -278.163573) (xy 104.919826 -278.121557) (xy 104.956549 -278.084834)
			(xy 104.998565 -278.054308) (xy 105.044839 -278.03073) (xy 105.094232 -278.014682) (xy 105.145527 -278.006557)
			(xy 105.197461 -278.006557) (xy 105.248756 -278.014682) (xy 105.298149 -278.03073) (xy 105.344423 -278.054308)
			(xy 105.386439 -278.084834) (xy 105.423162 -278.121557) (xy 105.453688 -278.163573) (xy 105.477266 -278.209847)
			(xy 105.493314 -278.25924) (xy 105.501439 -278.310535) (xy 105.501948 -278.336502) (xy 105.501439 -278.362469)
			(xy 106.721403 -278.362469) (xy 106.721403 -278.310535) (xy 106.729528 -278.25924) (xy 106.745576 -278.209847)
			(xy 106.769154 -278.163573) (xy 106.79968 -278.121557) (xy 106.836403 -278.084834) (xy 106.878419 -278.054308)
			(xy 106.924693 -278.03073) (xy 106.974086 -278.014682) (xy 107.025381 -278.006557) (xy 107.077315 -278.006557)
			(xy 107.12861 -278.014682) (xy 107.178003 -278.03073) (xy 107.224277 -278.054308) (xy 107.266293 -278.084834)
			(xy 107.303016 -278.121557) (xy 107.333542 -278.163573) (xy 107.35712 -278.209847) (xy 107.373168 -278.25924)
			(xy 107.381293 -278.310535) (xy 107.381802 -278.336502) (xy 107.381293 -278.362469) (xy 107.373168 -278.413764)
			(xy 107.35712 -278.463157) (xy 107.333542 -278.509431) (xy 107.303016 -278.551447) (xy 107.266293 -278.58817)
			(xy 107.224277 -278.618696) (xy 107.178003 -278.642274) (xy 107.12861 -278.658322) (xy 107.077315 -278.666447)
			(xy 107.025381 -278.666447) (xy 106.974086 -278.658322) (xy 106.924693 -278.642274) (xy 106.878419 -278.618696)
			(xy 106.836403 -278.58817) (xy 106.79968 -278.551447) (xy 106.769154 -278.509431) (xy 106.745576 -278.463157)
			(xy 106.729528 -278.413764) (xy 106.721403 -278.362469) (xy 105.501439 -278.362469) (xy 105.493314 -278.413764)
			(xy 105.477266 -278.463157) (xy 105.453688 -278.509431) (xy 105.423162 -278.551447) (xy 105.386439 -278.58817)
			(xy 105.344423 -278.618696) (xy 105.298149 -278.642274) (xy 105.248756 -278.658322) (xy 105.197461 -278.666447)
			(xy 105.145527 -278.666447) (xy 105.094232 -278.658322) (xy 105.044839 -278.642274) (xy 104.998565 -278.618696)
			(xy 104.956549 -278.58817) (xy 104.919826 -278.551447) (xy 104.8893 -278.509431) (xy 104.865722 -278.463157)
			(xy 104.849674 -278.413764) (xy 104.841549 -278.362469) (xy 104.561893 -278.362469) (xy 104.553768 -278.413764)
			(xy 104.53772 -278.463157) (xy 104.514142 -278.509431) (xy 104.483616 -278.551447) (xy 104.446893 -278.58817)
			(xy 104.404877 -278.618696) (xy 104.358603 -278.642274) (xy 104.30921 -278.658322) (xy 104.257915 -278.666447)
			(xy 104.205981 -278.666447) (xy 104.154686 -278.658322) (xy 104.105293 -278.642274) (xy 104.059019 -278.618696)
			(xy 104.017003 -278.58817) (xy 103.98028 -278.551447) (xy 103.949754 -278.509431) (xy 103.926176 -278.463157)
			(xy 103.910128 -278.413764) (xy 103.902003 -278.362469) (xy 103.622093 -278.362469) (xy 103.613968 -278.413764)
			(xy 103.59792 -278.463157) (xy 103.574342 -278.509431) (xy 103.543816 -278.551447) (xy 103.507093 -278.58817)
			(xy 103.465077 -278.618696) (xy 103.418803 -278.642274) (xy 103.36941 -278.658322) (xy 103.318115 -278.666447)
			(xy 103.266181 -278.666447) (xy 103.214886 -278.658322) (xy 103.165493 -278.642274) (xy 103.119219 -278.618696)
			(xy 103.077203 -278.58817) (xy 103.04048 -278.551447) (xy 103.009954 -278.509431) (xy 102.986376 -278.463157)
			(xy 102.970328 -278.413764) (xy 102.962203 -278.362469) (xy 102.682293 -278.362469) (xy 102.674168 -278.413764)
			(xy 102.65812 -278.463157) (xy 102.634542 -278.509431) (xy 102.604016 -278.551447) (xy 102.567293 -278.58817)
			(xy 102.525277 -278.618696) (xy 102.479003 -278.642274) (xy 102.42961 -278.658322) (xy 102.378315 -278.666447)
			(xy 102.326381 -278.666447) (xy 102.275086 -278.658322) (xy 102.225693 -278.642274) (xy 102.179419 -278.618696)
			(xy 102.137403 -278.58817) (xy 102.10068 -278.551447) (xy 102.070154 -278.509431) (xy 102.046576 -278.463157)
			(xy 102.030528 -278.413764) (xy 102.022403 -278.362469) (xy 101.742239 -278.362469) (xy 101.734114 -278.413764)
			(xy 101.718066 -278.463157) (xy 101.694488 -278.509431) (xy 101.663962 -278.551447) (xy 101.627239 -278.58817)
			(xy 101.585223 -278.618696) (xy 101.538949 -278.642274) (xy 101.489556 -278.658322) (xy 101.438261 -278.666447)
			(xy 101.386327 -278.666447) (xy 101.335032 -278.658322) (xy 101.285639 -278.642274) (xy 101.239365 -278.618696)
			(xy 101.197349 -278.58817) (xy 101.160626 -278.551447) (xy 101.1301 -278.509431) (xy 101.106522 -278.463157)
			(xy 101.090474 -278.413764) (xy 101.082349 -278.362469) (xy 100.802693 -278.362469) (xy 100.794568 -278.413764)
			(xy 100.77852 -278.463157) (xy 100.754942 -278.509431) (xy 100.724416 -278.551447) (xy 100.687693 -278.58817)
			(xy 100.645677 -278.618696) (xy 100.599403 -278.642274) (xy 100.55001 -278.658322) (xy 100.498715 -278.666447)
			(xy 100.446781 -278.666447) (xy 100.395486 -278.658322) (xy 100.346093 -278.642274) (xy 100.299819 -278.618696)
			(xy 100.257803 -278.58817) (xy 100.22108 -278.551447) (xy 100.190554 -278.509431) (xy 100.166976 -278.463157)
			(xy 100.150928 -278.413764) (xy 100.142803 -278.362469) (xy 99.862893 -278.362469) (xy 99.854768 -278.413764)
			(xy 99.83872 -278.463157) (xy 99.815142 -278.509431) (xy 99.784616 -278.551447) (xy 99.747893 -278.58817)
			(xy 99.705877 -278.618696) (xy 99.659603 -278.642274) (xy 99.61021 -278.658322) (xy 99.558915 -278.666447)
			(xy 99.506981 -278.666447) (xy 99.455686 -278.658322) (xy 99.406293 -278.642274) (xy 99.360019 -278.618696)
			(xy 99.318003 -278.58817) (xy 99.28128 -278.551447) (xy 99.250754 -278.509431) (xy 99.227176 -278.463157)
			(xy 99.211128 -278.413764) (xy 99.203003 -278.362469) (xy 98.923093 -278.362469) (xy 98.914968 -278.413764)
			(xy 98.89892 -278.463157) (xy 98.875342 -278.509431) (xy 98.844816 -278.551447) (xy 98.808093 -278.58817)
			(xy 98.766077 -278.618696) (xy 98.719803 -278.642274) (xy 98.67041 -278.658322) (xy 98.619115 -278.666447)
			(xy 98.567181 -278.666447) (xy 98.515886 -278.658322) (xy 98.466493 -278.642274) (xy 98.420219 -278.618696)
			(xy 98.378203 -278.58817) (xy 98.34148 -278.551447) (xy 98.310954 -278.509431) (xy 98.287376 -278.463157)
			(xy 98.271328 -278.413764) (xy 98.263203 -278.362469) (xy 97.983293 -278.362469) (xy 97.975168 -278.413764)
			(xy 97.95912 -278.463157) (xy 97.935542 -278.509431) (xy 97.905016 -278.551447) (xy 97.868293 -278.58817)
			(xy 97.826277 -278.618696) (xy 97.780003 -278.642274) (xy 97.73061 -278.658322) (xy 97.679315 -278.666447)
			(xy 97.627381 -278.666447) (xy 97.576086 -278.658322) (xy 97.526693 -278.642274) (xy 97.480419 -278.618696)
			(xy 97.438403 -278.58817) (xy 97.40168 -278.551447) (xy 97.371154 -278.509431) (xy 97.347576 -278.463157)
			(xy 97.331528 -278.413764) (xy 97.323403 -278.362469) (xy 95.163893 -278.362469) (xy 95.155768 -278.413764)
			(xy 95.13972 -278.463157) (xy 95.116142 -278.509431) (xy 95.085616 -278.551447) (xy 95.048893 -278.58817)
			(xy 95.006877 -278.618696) (xy 94.960603 -278.642274) (xy 94.91121 -278.658322) (xy 94.859915 -278.666447)
			(xy 94.807981 -278.666447) (xy 94.756686 -278.658322) (xy 94.707293 -278.642274) (xy 94.661019 -278.618696)
			(xy 94.619003 -278.58817) (xy 94.58228 -278.551447) (xy 94.551754 -278.509431) (xy 94.528176 -278.463157)
			(xy 94.512128 -278.413764) (xy 94.504003 -278.362469) (xy 94.224093 -278.362469) (xy 94.215968 -278.413764)
			(xy 94.19992 -278.463157) (xy 94.176342 -278.509431) (xy 94.145816 -278.551447) (xy 94.109093 -278.58817)
			(xy 94.067077 -278.618696) (xy 94.020803 -278.642274) (xy 93.97141 -278.658322) (xy 93.920115 -278.666447)
			(xy 93.868181 -278.666447) (xy 93.816886 -278.658322) (xy 93.767493 -278.642274) (xy 93.721219 -278.618696)
			(xy 93.679203 -278.58817) (xy 93.64248 -278.551447) (xy 93.611954 -278.509431) (xy 93.588376 -278.463157)
			(xy 93.572328 -278.413764) (xy 93.564203 -278.362469) (xy 93.284293 -278.362469) (xy 93.276168 -278.413764)
			(xy 93.26012 -278.463157) (xy 93.236542 -278.509431) (xy 93.206016 -278.551447) (xy 93.169293 -278.58817)
			(xy 93.127277 -278.618696) (xy 93.081003 -278.642274) (xy 93.03161 -278.658322) (xy 92.980315 -278.666447)
			(xy 92.928381 -278.666447) (xy 92.877086 -278.658322) (xy 92.827693 -278.642274) (xy 92.781419 -278.618696)
			(xy 92.739403 -278.58817) (xy 92.70268 -278.551447) (xy 92.672154 -278.509431) (xy 92.648576 -278.463157)
			(xy 92.632528 -278.413764) (xy 92.624403 -278.362469) (xy 92.344697 -278.362469) (xy 92.344697 -278.362485)
			(xy 92.336568 -278.413814) (xy 92.32051 -278.46324) (xy 92.296918 -278.509546) (xy 92.266374 -278.551592)
			(xy 92.229629 -278.588343) (xy 92.187587 -278.618893) (xy 92.141285 -278.642491) (xy 92.091861 -278.658556)
			(xy 92.040533 -278.666693) (xy 92.014548 -278.66721) (xy 91.988491 -278.666725) (xy 91.937021 -278.658559)
			(xy 91.887469 -278.642422) (xy 91.841061 -278.618713) (xy 91.798946 -278.588019) (xy 91.762166 -278.551099)
			(xy 91.731631 -278.508868) (xy 91.7194 -278.485854) (xy 91.717622 -278.482552) (xy 91.6813 -278.455374)
			(xy 91.597988 -278.441912) (xy 91.586746 -278.44127) (xy 91.565505 -278.44865) (xy 91.557094 -278.456136)
			(xy 90.946732 -279.066498) (xy 90.940048 -279.07368) (xy 90.932444 -279.09175) (xy 90.932 -279.10155)
			(xy 90.932508 -279.108154) (xy 90.932762 -279.109678) (xy 90.933943 -279.119797) (xy 90.935212 -279.140131)
			(xy 90.935302 -279.150318) (xy 90.934791 -279.176285) (xy 91.214449 -279.176285) (xy 91.214449 -279.124351)
			(xy 91.222574 -279.073056) (xy 91.238622 -279.023663) (xy 91.2622 -278.977389) (xy 91.292726 -278.935373)
			(xy 91.329449 -278.89865) (xy 91.371465 -278.868124) (xy 91.417739 -278.844546) (xy 91.467132 -278.828498)
			(xy 91.518427 -278.820373) (xy 91.570361 -278.820373) (xy 91.621656 -278.828498) (xy 91.671049 -278.844546)
			(xy 91.717323 -278.868124) (xy 91.759339 -278.89865) (xy 91.796062 -278.935373) (xy 91.826588 -278.977389)
			(xy 91.850166 -279.023663) (xy 91.866214 -279.073056) (xy 91.874339 -279.124351) (xy 91.874848 -279.150318)
			(xy 91.874339 -279.176285) (xy 92.154249 -279.176285) (xy 92.154249 -279.124351) (xy 92.162374 -279.073056)
			(xy 92.178422 -279.023663) (xy 92.202 -278.977389) (xy 92.232526 -278.935373) (xy 92.269249 -278.89865)
			(xy 92.311265 -278.868124) (xy 92.357539 -278.844546) (xy 92.406932 -278.828498) (xy 92.458227 -278.820373)
			(xy 92.510161 -278.820373) (xy 92.561456 -278.828498) (xy 92.610849 -278.844546) (xy 92.657123 -278.868124)
			(xy 92.699139 -278.89865) (xy 92.735862 -278.935373) (xy 92.766388 -278.977389) (xy 92.789966 -279.023663)
			(xy 92.806014 -279.073056) (xy 92.814139 -279.124351) (xy 92.814648 -279.150318) (xy 92.814139 -279.176285)
			(xy 93.094049 -279.176285) (xy 93.094049 -279.124351) (xy 93.102174 -279.073056) (xy 93.118222 -279.023663)
			(xy 93.1418 -278.977389) (xy 93.172326 -278.935373) (xy 93.209049 -278.89865) (xy 93.251065 -278.868124)
			(xy 93.297339 -278.844546) (xy 93.346732 -278.828498) (xy 93.398027 -278.820373) (xy 93.449961 -278.820373)
			(xy 93.501256 -278.828498) (xy 93.550649 -278.844546) (xy 93.596923 -278.868124) (xy 93.638939 -278.89865)
			(xy 93.675662 -278.935373) (xy 93.706188 -278.977389) (xy 93.729766 -279.023663) (xy 93.745814 -279.073056)
			(xy 93.753939 -279.124351) (xy 93.754448 -279.150318) (xy 93.753939 -279.176285) (xy 94.034103 -279.176285)
			(xy 94.034103 -279.124351) (xy 94.042228 -279.073056) (xy 94.058276 -279.023663) (xy 94.081854 -278.977389)
			(xy 94.11238 -278.935373) (xy 94.149103 -278.89865) (xy 94.191119 -278.868124) (xy 94.237393 -278.844546)
			(xy 94.286786 -278.828498) (xy 94.338081 -278.820373) (xy 94.390015 -278.820373) (xy 94.44131 -278.828498)
			(xy 94.490703 -278.844546) (xy 94.536977 -278.868124) (xy 94.578993 -278.89865) (xy 94.615716 -278.935373)
			(xy 94.646242 -278.977389) (xy 94.66982 -279.023663) (xy 94.685868 -279.073056) (xy 94.693993 -279.124351)
			(xy 94.694502 -279.150318) (xy 94.693993 -279.176285) (xy 94.973649 -279.176285) (xy 94.973649 -279.124351)
			(xy 94.981774 -279.073056) (xy 94.997822 -279.023663) (xy 95.0214 -278.977389) (xy 95.051926 -278.935373)
			(xy 95.088649 -278.89865) (xy 95.130665 -278.868124) (xy 95.176939 -278.844546) (xy 95.226332 -278.828498)
			(xy 95.277627 -278.820373) (xy 95.329561 -278.820373) (xy 95.380856 -278.828498) (xy 95.430249 -278.844546)
			(xy 95.476523 -278.868124) (xy 95.518539 -278.89865) (xy 95.555262 -278.935373) (xy 95.585788 -278.977389)
			(xy 95.609366 -279.023663) (xy 95.625414 -279.073056) (xy 95.633539 -279.124351) (xy 95.634048 -279.150318)
			(xy 95.633539 -279.176285) (xy 95.913449 -279.176285) (xy 95.913449 -279.124351) (xy 95.921574 -279.073056)
			(xy 95.937622 -279.023663) (xy 95.9612 -278.977389) (xy 95.991726 -278.935373) (xy 96.028449 -278.89865)
			(xy 96.070465 -278.868124) (xy 96.116739 -278.844546) (xy 96.166132 -278.828498) (xy 96.217427 -278.820373)
			(xy 96.269361 -278.820373) (xy 96.320656 -278.828498) (xy 96.370049 -278.844546) (xy 96.416323 -278.868124)
			(xy 96.458339 -278.89865) (xy 96.495062 -278.935373) (xy 96.525588 -278.977389) (xy 96.549166 -279.023663)
			(xy 96.565214 -279.073056) (xy 96.573339 -279.124351) (xy 96.573848 -279.150318) (xy 96.573339 -279.176285)
			(xy 97.793303 -279.176285) (xy 97.793303 -279.124351) (xy 97.801428 -279.073056) (xy 97.817476 -279.023663)
			(xy 97.841054 -278.977389) (xy 97.87158 -278.935373) (xy 97.908303 -278.89865) (xy 97.950319 -278.868124)
			(xy 97.996593 -278.844546) (xy 98.045986 -278.828498) (xy 98.097281 -278.820373) (xy 98.149215 -278.820373)
			(xy 98.20051 -278.828498) (xy 98.249903 -278.844546) (xy 98.296177 -278.868124) (xy 98.338193 -278.89865)
			(xy 98.374916 -278.935373) (xy 98.405442 -278.977389) (xy 98.42902 -279.023663) (xy 98.445068 -279.073056)
			(xy 98.453193 -279.124351) (xy 98.453702 -279.150318) (xy 98.453193 -279.176285) (xy 98.732849 -279.176285)
			(xy 98.732849 -279.124351) (xy 98.740974 -279.073056) (xy 98.757022 -279.023663) (xy 98.7806 -278.977389)
			(xy 98.811126 -278.935373) (xy 98.847849 -278.89865) (xy 98.889865 -278.868124) (xy 98.936139 -278.844546)
			(xy 98.985532 -278.828498) (xy 99.036827 -278.820373) (xy 99.088761 -278.820373) (xy 99.140056 -278.828498)
			(xy 99.189449 -278.844546) (xy 99.235723 -278.868124) (xy 99.277739 -278.89865) (xy 99.314462 -278.935373)
			(xy 99.344988 -278.977389) (xy 99.368566 -279.023663) (xy 99.384614 -279.073056) (xy 99.392739 -279.124351)
			(xy 99.393248 -279.150318) (xy 99.392739 -279.176285) (xy 99.672649 -279.176285) (xy 99.672649 -279.124351)
			(xy 99.680774 -279.073056) (xy 99.696822 -279.023663) (xy 99.7204 -278.977389) (xy 99.750926 -278.935373)
			(xy 99.787649 -278.89865) (xy 99.829665 -278.868124) (xy 99.875939 -278.844546) (xy 99.925332 -278.828498)
			(xy 99.976627 -278.820373) (xy 100.028561 -278.820373) (xy 100.079856 -278.828498) (xy 100.129249 -278.844546)
			(xy 100.175523 -278.868124) (xy 100.217539 -278.89865) (xy 100.254262 -278.935373) (xy 100.284788 -278.977389)
			(xy 100.308366 -279.023663) (xy 100.324414 -279.073056) (xy 100.332539 -279.124351) (xy 100.333048 -279.150318)
			(xy 100.332539 -279.176285) (xy 100.612703 -279.176285) (xy 100.612703 -279.124351) (xy 100.620828 -279.073056)
			(xy 100.636876 -279.023663) (xy 100.660454 -278.977389) (xy 100.69098 -278.935373) (xy 100.727703 -278.89865)
			(xy 100.769719 -278.868124) (xy 100.815993 -278.844546) (xy 100.865386 -278.828498) (xy 100.916681 -278.820373)
			(xy 100.968615 -278.820373) (xy 101.01991 -278.828498) (xy 101.069303 -278.844546) (xy 101.115577 -278.868124)
			(xy 101.157593 -278.89865) (xy 101.194316 -278.935373) (xy 101.224842 -278.977389) (xy 101.24842 -279.023663)
			(xy 101.264468 -279.073056) (xy 101.272593 -279.124351) (xy 101.273102 -279.150318) (xy 101.55174 -279.150318)
			(xy 101.552249 -279.124351) (xy 101.560374 -279.073056) (xy 101.576422 -279.023663) (xy 101.6 -278.977389)
			(xy 101.630526 -278.935373) (xy 101.667249 -278.89865) (xy 101.709265 -278.868124) (xy 101.755539 -278.844546)
			(xy 101.804932 -278.828498) (xy 101.856227 -278.820373) (xy 101.908161 -278.820373) (xy 101.959456 -278.828498)
			(xy 102.008849 -278.844546) (xy 102.055123 -278.868124) (xy 102.097139 -278.89865) (xy 102.133862 -278.935373)
			(xy 102.164388 -278.977389) (xy 102.187966 -279.023663) (xy 102.204014 -279.073056) (xy 102.212139 -279.124351)
			(xy 102.212648 -279.150318) (xy 102.212648 -279.150572) (xy 102.212109 -279.176266) (xy 102.492073 -279.176266)
			(xy 102.492073 -279.124334) (xy 102.500197 -279.073043) (xy 102.516244 -279.023653) (xy 102.53982 -278.977382)
			(xy 102.570344 -278.935369) (xy 102.607065 -278.898648) (xy 102.649077 -278.868123) (xy 102.695348 -278.844547)
			(xy 102.744737 -278.828498) (xy 102.796029 -278.820374) (xy 102.821994 -278.819864) (xy 102.847629 -278.820365)
			(xy 102.898283 -278.828288) (xy 102.947104 -278.843945) (xy 102.992919 -278.866959) (xy 103.034626 -278.896777)
			(xy 103.071223 -278.932684) (xy 103.086916 -278.95296) (xy 103.496872 -278.95296) (xy 103.512559 -278.932678)
			(xy 103.549157 -278.89677) (xy 103.590865 -278.866949) (xy 103.63668 -278.843933) (xy 103.685502 -278.828274)
			(xy 103.736158 -278.820349) (xy 103.761794 -278.819864) (xy 103.787765 -278.82031) (xy 103.839068 -278.828435)
			(xy 103.888468 -278.844485) (xy 103.934749 -278.868066) (xy 103.976771 -278.898596) (xy 104.0135 -278.935324)
			(xy 104.044031 -278.977346) (xy 104.067612 -279.023627) (xy 104.083663 -279.073026) (xy 104.091789 -279.124329)
			(xy 104.091789 -279.176271) (xy 104.091787 -279.176285) (xy 104.371649 -279.176285) (xy 104.371649 -279.124351)
			(xy 104.379774 -279.073056) (xy 104.395822 -279.023663) (xy 104.4194 -278.977389) (xy 104.449926 -278.935373)
			(xy 104.486649 -278.89865) (xy 104.528665 -278.868124) (xy 104.574939 -278.844546) (xy 104.624332 -278.828498)
			(xy 104.675627 -278.820373) (xy 104.727561 -278.820373) (xy 104.778856 -278.828498) (xy 104.828249 -278.844546)
			(xy 104.874523 -278.868124) (xy 104.916539 -278.89865) (xy 104.953262 -278.935373) (xy 104.983788 -278.977389)
			(xy 105.007366 -279.023663) (xy 105.023414 -279.073056) (xy 105.031539 -279.124351) (xy 105.032048 -279.150318)
			(xy 105.031539 -279.176285) (xy 105.311703 -279.176285) (xy 105.311703 -279.124351) (xy 105.319828 -279.073056)
			(xy 105.335876 -279.023663) (xy 105.359454 -278.977389) (xy 105.38998 -278.935373) (xy 105.426703 -278.89865)
			(xy 105.468719 -278.868124) (xy 105.514993 -278.844546) (xy 105.564386 -278.828498) (xy 105.615681 -278.820373)
			(xy 105.667615 -278.820373) (xy 105.71891 -278.828498) (xy 105.768303 -278.844546) (xy 105.814577 -278.868124)
			(xy 105.856593 -278.89865) (xy 105.893316 -278.935373) (xy 105.923842 -278.977389) (xy 105.94742 -279.023663)
			(xy 105.963468 -279.073056) (xy 105.971593 -279.124351) (xy 105.972102 -279.150318) (xy 105.971593 -279.176285)
			(xy 106.251503 -279.176285) (xy 106.251503 -279.124351) (xy 106.259628 -279.073056) (xy 106.275676 -279.023663)
			(xy 106.299254 -278.977389) (xy 106.32978 -278.935373) (xy 106.366503 -278.89865) (xy 106.408519 -278.868124)
			(xy 106.454793 -278.844546) (xy 106.504186 -278.828498) (xy 106.555481 -278.820373) (xy 106.607415 -278.820373)
			(xy 106.65871 -278.828498) (xy 106.708103 -278.844546) (xy 106.754377 -278.868124) (xy 106.796393 -278.89865)
			(xy 106.833116 -278.935373) (xy 106.863642 -278.977389) (xy 106.88722 -279.023663) (xy 106.903268 -279.073056)
			(xy 106.911393 -279.124351) (xy 106.911902 -279.150318) (xy 106.911393 -279.176285) (xy 106.903268 -279.22758)
			(xy 106.88722 -279.276973) (xy 106.863642 -279.323247) (xy 106.833116 -279.365263) (xy 106.796393 -279.401986)
			(xy 106.754377 -279.432512) (xy 106.708103 -279.45609) (xy 106.65871 -279.472138) (xy 106.607415 -279.480263)
			(xy 106.555481 -279.480263) (xy 106.504186 -279.472138) (xy 106.454793 -279.45609) (xy 106.408519 -279.432512)
			(xy 106.366503 -279.401986) (xy 106.32978 -279.365263) (xy 106.299254 -279.323247) (xy 106.275676 -279.276973)
			(xy 106.259628 -279.22758) (xy 106.251503 -279.176285) (xy 105.971593 -279.176285) (xy 105.963468 -279.22758)
			(xy 105.94742 -279.276973) (xy 105.923842 -279.323247) (xy 105.893316 -279.365263) (xy 105.856593 -279.401986)
			(xy 105.814577 -279.432512) (xy 105.768303 -279.45609) (xy 105.71891 -279.472138) (xy 105.667615 -279.480263)
			(xy 105.615681 -279.480263) (xy 105.564386 -279.472138) (xy 105.514993 -279.45609) (xy 105.468719 -279.432512)
			(xy 105.426703 -279.401986) (xy 105.38998 -279.365263) (xy 105.359454 -279.323247) (xy 105.335876 -279.276973)
			(xy 105.319828 -279.22758) (xy 105.311703 -279.176285) (xy 105.031539 -279.176285) (xy 105.023414 -279.22758)
			(xy 105.007366 -279.276973) (xy 104.983788 -279.323247) (xy 104.953262 -279.365263) (xy 104.916539 -279.401986)
			(xy 104.874523 -279.432512) (xy 104.828249 -279.45609) (xy 104.778856 -279.472138) (xy 104.727561 -279.480263)
			(xy 104.675627 -279.480263) (xy 104.624332 -279.472138) (xy 104.574939 -279.45609) (xy 104.528665 -279.432512)
			(xy 104.486649 -279.401986) (xy 104.449926 -279.365263) (xy 104.4194 -279.323247) (xy 104.395822 -279.276973)
			(xy 104.379774 -279.22758) (xy 104.371649 -279.176285) (xy 104.091787 -279.176285) (xy 104.083663 -279.227574)
			(xy 104.067612 -279.276973) (xy 104.044031 -279.323254) (xy 104.0135 -279.365276) (xy 103.976771 -279.402004)
			(xy 103.934749 -279.432534) (xy 103.888468 -279.456115) (xy 103.839068 -279.472165) (xy 103.787765 -279.48029)
			(xy 103.761794 -279.480772) (xy 103.736157 -279.480305) (xy 103.6855 -279.472379) (xy 103.636677 -279.456717)
			(xy 103.590862 -279.433696) (xy 103.549157 -279.40387) (xy 103.512562 -279.367956) (xy 103.496872 -279.347676)
			(xy 103.086916 -279.347676) (xy 103.071219 -279.36795) (xy 103.034625 -279.403862) (xy 102.99292 -279.433685)
			(xy 102.947106 -279.456703) (xy 102.898285 -279.472363) (xy 102.84763 -279.480288) (xy 102.821994 -279.480772)
			(xy 102.796029 -279.480226) (xy 102.744737 -279.472102) (xy 102.695348 -279.456053) (xy 102.649077 -279.432477)
			(xy 102.607065 -279.401952) (xy 102.570344 -279.365231) (xy 102.53982 -279.323218) (xy 102.516244 -279.276947)
			(xy 102.500197 -279.227557) (xy 102.492073 -279.176266) (xy 102.212109 -279.176266) (xy 102.212065 -279.178353)
			(xy 102.202749 -279.233129) (xy 102.194106 -279.259538) (xy 102.186232 -279.281636) (xy 102.390194 -279.63495)
			(xy 102.413308 -279.639268) (xy 102.438225 -279.644457) (xy 102.486209 -279.661417) (xy 102.531028 -279.685531)
			(xy 102.571621 -279.716228) (xy 102.607031 -279.752783) (xy 102.63642 -279.794333) (xy 102.659095 -279.839897)
			(xy 102.674519 -279.888397) (xy 102.682329 -279.938687) (xy 102.682802 -279.964134) (xy 102.682293 -279.990101)
			(xy 102.961949 -279.990101) (xy 102.961949 -279.938167) (xy 102.970074 -279.886872) (xy 102.986122 -279.837479)
			(xy 103.0097 -279.791205) (xy 103.040226 -279.749189) (xy 103.076949 -279.712466) (xy 103.118965 -279.68194)
			(xy 103.165239 -279.658362) (xy 103.214632 -279.642314) (xy 103.265927 -279.634189) (xy 103.317861 -279.634189)
			(xy 103.369156 -279.642314) (xy 103.418549 -279.658362) (xy 103.464823 -279.68194) (xy 103.506839 -279.712466)
			(xy 103.543562 -279.749189) (xy 103.574088 -279.791205) (xy 103.597666 -279.837479) (xy 103.613714 -279.886872)
			(xy 103.621839 -279.938167) (xy 103.622348 -279.964134) (xy 103.621839 -279.990101) (xy 103.902003 -279.990101)
			(xy 103.902003 -279.938167) (xy 103.910128 -279.886872) (xy 103.926176 -279.837479) (xy 103.949754 -279.791205)
			(xy 103.98028 -279.749189) (xy 104.017003 -279.712466) (xy 104.059019 -279.68194) (xy 104.105293 -279.658362)
			(xy 104.154686 -279.642314) (xy 104.205981 -279.634189) (xy 104.257915 -279.634189) (xy 104.30921 -279.642314)
			(xy 104.358603 -279.658362) (xy 104.404877 -279.68194) (xy 104.446893 -279.712466) (xy 104.483616 -279.749189)
			(xy 104.514142 -279.791205) (xy 104.53772 -279.837479) (xy 104.553768 -279.886872) (xy 104.561893 -279.938167)
			(xy 104.562402 -279.964134) (xy 104.561893 -279.990101) (xy 104.553768 -280.041396) (xy 104.53772 -280.090789)
			(xy 104.514142 -280.137063) (xy 104.483616 -280.179079) (xy 104.446893 -280.215802) (xy 104.404877 -280.246328)
			(xy 104.358603 -280.269906) (xy 104.30921 -280.285954) (xy 104.257915 -280.294079) (xy 104.205981 -280.294079)
			(xy 104.154686 -280.285954) (xy 104.105293 -280.269906) (xy 104.059019 -280.246328) (xy 104.017003 -280.215802)
			(xy 103.98028 -280.179079) (xy 103.949754 -280.137063) (xy 103.926176 -280.090789) (xy 103.910128 -280.041396)
			(xy 103.902003 -279.990101) (xy 103.621839 -279.990101) (xy 103.613714 -280.041396) (xy 103.597666 -280.090789)
			(xy 103.574088 -280.137063) (xy 103.543562 -280.179079) (xy 103.506839 -280.215802) (xy 103.464823 -280.246328)
			(xy 103.418549 -280.269906) (xy 103.369156 -280.285954) (xy 103.317861 -280.294079) (xy 103.265927 -280.294079)
			(xy 103.214632 -280.285954) (xy 103.165239 -280.269906) (xy 103.118965 -280.246328) (xy 103.076949 -280.215802)
			(xy 103.040226 -280.179079) (xy 103.0097 -280.137063) (xy 102.986122 -280.090789) (xy 102.970074 -280.041396)
			(xy 102.961949 -279.990101) (xy 102.682293 -279.990101) (xy 102.674168 -280.041396) (xy 102.65812 -280.090789)
			(xy 102.634542 -280.137063) (xy 102.604016 -280.179079) (xy 102.567293 -280.215802) (xy 102.525277 -280.246328)
			(xy 102.479003 -280.269906) (xy 102.42961 -280.285954) (xy 102.378315 -280.294079) (xy 102.326381 -280.294079)
			(xy 102.275086 -280.285954) (xy 102.225693 -280.269906) (xy 102.179419 -280.246328) (xy 102.137403 -280.215802)
			(xy 102.10068 -280.179079) (xy 102.070154 -280.137063) (xy 102.046576 -280.090789) (xy 102.030528 -280.041396)
			(xy 102.022403 -279.990101) (xy 102.021894 -279.964134) (xy 102.022455 -279.936149) (xy 102.0319 -279.880981)
			(xy 102.04069 -279.854406) (xy 102.04831 -279.832308) (xy 101.844602 -279.479502) (xy 101.821742 -279.475184)
			(xy 101.796785 -279.470059) (xy 101.748722 -279.453162) (xy 101.703821 -279.429088) (xy 101.663148 -279.398409)
			(xy 101.627665 -279.36185) (xy 101.598212 -279.320279) (xy 101.575489 -279.27468) (xy 101.560034 -279.226134)
			(xy 101.552212 -279.175791) (xy 101.55174 -279.150318) (xy 101.273102 -279.150318) (xy 101.272593 -279.176285)
			(xy 101.264468 -279.22758) (xy 101.24842 -279.276973) (xy 101.224842 -279.323247) (xy 101.194316 -279.365263)
			(xy 101.157593 -279.401986) (xy 101.115577 -279.432512) (xy 101.069303 -279.45609) (xy 101.01991 -279.472138)
			(xy 100.968615 -279.480263) (xy 100.916681 -279.480263) (xy 100.865386 -279.472138) (xy 100.815993 -279.45609)
			(xy 100.769719 -279.432512) (xy 100.727703 -279.401986) (xy 100.69098 -279.365263) (xy 100.660454 -279.323247)
			(xy 100.636876 -279.276973) (xy 100.620828 -279.22758) (xy 100.612703 -279.176285) (xy 100.332539 -279.176285)
			(xy 100.324414 -279.22758) (xy 100.308366 -279.276973) (xy 100.284788 -279.323247) (xy 100.254262 -279.365263)
			(xy 100.217539 -279.401986) (xy 100.175523 -279.432512) (xy 100.129249 -279.45609) (xy 100.079856 -279.472138)
			(xy 100.028561 -279.480263) (xy 99.976627 -279.480263) (xy 99.925332 -279.472138) (xy 99.875939 -279.45609)
			(xy 99.829665 -279.432512) (xy 99.787649 -279.401986) (xy 99.750926 -279.365263) (xy 99.7204 -279.323247)
			(xy 99.696822 -279.276973) (xy 99.680774 -279.22758) (xy 99.672649 -279.176285) (xy 99.392739 -279.176285)
			(xy 99.384614 -279.22758) (xy 99.368566 -279.276973) (xy 99.344988 -279.323247) (xy 99.314462 -279.365263)
			(xy 99.277739 -279.401986) (xy 99.235723 -279.432512) (xy 99.189449 -279.45609) (xy 99.140056 -279.472138)
			(xy 99.088761 -279.480263) (xy 99.036827 -279.480263) (xy 98.985532 -279.472138) (xy 98.936139 -279.45609)
			(xy 98.889865 -279.432512) (xy 98.847849 -279.401986) (xy 98.811126 -279.365263) (xy 98.7806 -279.323247)
			(xy 98.757022 -279.276973) (xy 98.740974 -279.22758) (xy 98.732849 -279.176285) (xy 98.453193 -279.176285)
			(xy 98.445068 -279.22758) (xy 98.42902 -279.276973) (xy 98.405442 -279.323247) (xy 98.374916 -279.365263)
			(xy 98.338193 -279.401986) (xy 98.296177 -279.432512) (xy 98.249903 -279.45609) (xy 98.20051 -279.472138)
			(xy 98.149215 -279.480263) (xy 98.097281 -279.480263) (xy 98.045986 -279.472138) (xy 97.996593 -279.45609)
			(xy 97.950319 -279.432512) (xy 97.908303 -279.401986) (xy 97.87158 -279.365263) (xy 97.841054 -279.323247)
			(xy 97.817476 -279.276973) (xy 97.801428 -279.22758) (xy 97.793303 -279.176285) (xy 96.573339 -279.176285)
			(xy 96.565214 -279.22758) (xy 96.549166 -279.276973) (xy 96.525588 -279.323247) (xy 96.495062 -279.365263)
			(xy 96.458339 -279.401986) (xy 96.416323 -279.432512) (xy 96.370049 -279.45609) (xy 96.320656 -279.472138)
			(xy 96.269361 -279.480263) (xy 96.217427 -279.480263) (xy 96.166132 -279.472138) (xy 96.116739 -279.45609)
			(xy 96.070465 -279.432512) (xy 96.028449 -279.401986) (xy 95.991726 -279.365263) (xy 95.9612 -279.323247)
			(xy 95.937622 -279.276973) (xy 95.921574 -279.22758) (xy 95.913449 -279.176285) (xy 95.633539 -279.176285)
			(xy 95.625414 -279.22758) (xy 95.609366 -279.276973) (xy 95.585788 -279.323247) (xy 95.555262 -279.365263)
			(xy 95.518539 -279.401986) (xy 95.476523 -279.432512) (xy 95.430249 -279.45609) (xy 95.380856 -279.472138)
			(xy 95.329561 -279.480263) (xy 95.277627 -279.480263) (xy 95.226332 -279.472138) (xy 95.176939 -279.45609)
			(xy 95.130665 -279.432512) (xy 95.088649 -279.401986) (xy 95.051926 -279.365263) (xy 95.0214 -279.323247)
			(xy 94.997822 -279.276973) (xy 94.981774 -279.22758) (xy 94.973649 -279.176285) (xy 94.693993 -279.176285)
			(xy 94.685868 -279.22758) (xy 94.66982 -279.276973) (xy 94.646242 -279.323247) (xy 94.615716 -279.365263)
			(xy 94.578993 -279.401986) (xy 94.536977 -279.432512) (xy 94.490703 -279.45609) (xy 94.44131 -279.472138)
			(xy 94.390015 -279.480263) (xy 94.338081 -279.480263) (xy 94.286786 -279.472138) (xy 94.237393 -279.45609)
			(xy 94.191119 -279.432512) (xy 94.149103 -279.401986) (xy 94.11238 -279.365263) (xy 94.081854 -279.323247)
			(xy 94.058276 -279.276973) (xy 94.042228 -279.22758) (xy 94.034103 -279.176285) (xy 93.753939 -279.176285)
			(xy 93.745814 -279.22758) (xy 93.729766 -279.276973) (xy 93.706188 -279.323247) (xy 93.675662 -279.365263)
			(xy 93.638939 -279.401986) (xy 93.596923 -279.432512) (xy 93.550649 -279.45609) (xy 93.501256 -279.472138)
			(xy 93.449961 -279.480263) (xy 93.398027 -279.480263) (xy 93.346732 -279.472138) (xy 93.297339 -279.45609)
			(xy 93.251065 -279.432512) (xy 93.209049 -279.401986) (xy 93.172326 -279.365263) (xy 93.1418 -279.323247)
			(xy 93.118222 -279.276973) (xy 93.102174 -279.22758) (xy 93.094049 -279.176285) (xy 92.814139 -279.176285)
			(xy 92.806014 -279.22758) (xy 92.789966 -279.276973) (xy 92.766388 -279.323247) (xy 92.735862 -279.365263)
			(xy 92.699139 -279.401986) (xy 92.657123 -279.432512) (xy 92.610849 -279.45609) (xy 92.561456 -279.472138)
			(xy 92.510161 -279.480263) (xy 92.458227 -279.480263) (xy 92.406932 -279.472138) (xy 92.357539 -279.45609)
			(xy 92.311265 -279.432512) (xy 92.269249 -279.401986) (xy 92.232526 -279.365263) (xy 92.202 -279.323247)
			(xy 92.178422 -279.276973) (xy 92.162374 -279.22758) (xy 92.154249 -279.176285) (xy 91.874339 -279.176285)
			(xy 91.866214 -279.22758) (xy 91.850166 -279.276973) (xy 91.826588 -279.323247) (xy 91.796062 -279.365263)
			(xy 91.759339 -279.401986) (xy 91.717323 -279.432512) (xy 91.671049 -279.45609) (xy 91.621656 -279.472138)
			(xy 91.570361 -279.480263) (xy 91.518427 -279.480263) (xy 91.467132 -279.472138) (xy 91.417739 -279.45609)
			(xy 91.371465 -279.432512) (xy 91.329449 -279.401986) (xy 91.292726 -279.365263) (xy 91.2622 -279.323247)
			(xy 91.238622 -279.276973) (xy 91.222574 -279.22758) (xy 91.214449 -279.176285) (xy 90.934791 -279.176285)
			(xy 90.934791 -279.176304) (xy 90.926658 -279.227636) (xy 90.910596 -279.277064) (xy 90.886999 -279.32337)
			(xy 90.856449 -279.365416) (xy 90.819697 -279.402164) (xy 90.77765 -279.432711) (xy 90.731342 -279.456305)
			(xy 90.681913 -279.472364) (xy 90.63058 -279.480493) (xy 90.604594 -279.481026) (xy 90.594407 -279.480943)
			(xy 90.574072 -279.479674) (xy 90.563954 -279.478486) (xy 90.56243 -279.478232) (xy 90.555826 -279.477724)
			(xy 90.54605 -279.478288) (xy 90.528013 -279.485862) (xy 90.520774 -279.492456) (xy 90.413332 -279.599898)
			(xy 90.407025 -279.606775) (xy 90.399578 -279.62387) (xy 90.398854 -279.633172) (xy 90.397584 -279.661874)
			(xy 90.395806 -279.703022) (xy 90.40749 -279.735026) (xy 90.410284 -279.738582) (xy 90.425451 -279.757747)
			(xy 90.450945 -279.799444) (xy 90.470496 -279.844237) (xy 90.483737 -279.891282) (xy 90.490418 -279.939697)
			(xy 90.490802 -279.964134) (xy 90.49029 -279.990101) (xy 91.684603 -279.990101) (xy 91.684603 -279.938167)
			(xy 91.692728 -279.886872) (xy 91.708776 -279.837479) (xy 91.732354 -279.791205) (xy 91.76288 -279.749189)
			(xy 91.799603 -279.712466) (xy 91.841619 -279.68194) (xy 91.887893 -279.658362) (xy 91.937286 -279.642314)
			(xy 91.988581 -279.634189) (xy 92.040515 -279.634189) (xy 92.09181 -279.642314) (xy 92.141203 -279.658362)
			(xy 92.187477 -279.68194) (xy 92.229493 -279.712466) (xy 92.266216 -279.749189) (xy 92.296742 -279.791205)
			(xy 92.32032 -279.837479) (xy 92.336368 -279.886872) (xy 92.344493 -279.938167) (xy 92.345002 -279.964134)
			(xy 92.344493 -279.990101) (xy 92.624403 -279.990101) (xy 92.624403 -279.938167) (xy 92.632528 -279.886872)
			(xy 92.648576 -279.837479) (xy 92.672154 -279.791205) (xy 92.70268 -279.749189) (xy 92.739403 -279.712466)
			(xy 92.781419 -279.68194) (xy 92.827693 -279.658362) (xy 92.877086 -279.642314) (xy 92.928381 -279.634189)
			(xy 92.980315 -279.634189) (xy 93.03161 -279.642314) (xy 93.081003 -279.658362) (xy 93.127277 -279.68194)
			(xy 93.169293 -279.712466) (xy 93.206016 -279.749189) (xy 93.236542 -279.791205) (xy 93.26012 -279.837479)
			(xy 93.276168 -279.886872) (xy 93.284293 -279.938167) (xy 93.284802 -279.964134) (xy 93.284293 -279.990101)
			(xy 94.503749 -279.990101) (xy 94.503749 -279.938167) (xy 94.511874 -279.886872) (xy 94.527922 -279.837479)
			(xy 94.5515 -279.791205) (xy 94.582026 -279.749189) (xy 94.618749 -279.712466) (xy 94.660765 -279.68194)
			(xy 94.707039 -279.658362) (xy 94.756432 -279.642314) (xy 94.807727 -279.634189) (xy 94.859661 -279.634189)
			(xy 94.910956 -279.642314) (xy 94.960349 -279.658362) (xy 95.006623 -279.68194) (xy 95.048639 -279.712466)
			(xy 95.085362 -279.749189) (xy 95.115888 -279.791205) (xy 95.139466 -279.837479) (xy 95.155514 -279.886872)
			(xy 95.163639 -279.938167) (xy 95.164148 -279.964134) (xy 95.163639 -279.990101) (xy 95.443803 -279.990101)
			(xy 95.443803 -279.938167) (xy 95.451928 -279.886872) (xy 95.467976 -279.837479) (xy 95.491554 -279.791205)
			(xy 95.52208 -279.749189) (xy 95.558803 -279.712466) (xy 95.600819 -279.68194) (xy 95.647093 -279.658362)
			(xy 95.696486 -279.642314) (xy 95.747781 -279.634189) (xy 95.799715 -279.634189) (xy 95.85101 -279.642314)
			(xy 95.900403 -279.658362) (xy 95.946677 -279.68194) (xy 95.988693 -279.712466) (xy 96.025416 -279.749189)
			(xy 96.055942 -279.791205) (xy 96.07952 -279.837479) (xy 96.095568 -279.886872) (xy 96.103693 -279.938167)
			(xy 96.104202 -279.964134) (xy 96.383094 -279.964134) (xy 96.383603 -279.938167) (xy 96.391728 -279.886872)
			(xy 96.407776 -279.837479) (xy 96.431354 -279.791205) (xy 96.46188 -279.749189) (xy 96.498603 -279.712466)
			(xy 96.540619 -279.68194) (xy 96.586893 -279.658362) (xy 96.636286 -279.642314) (xy 96.687581 -279.634189)
			(xy 96.739515 -279.634189) (xy 96.79081 -279.642314) (xy 96.840203 -279.658362) (xy 96.886477 -279.68194)
			(xy 96.928493 -279.712466) (xy 96.965216 -279.749189) (xy 96.995742 -279.791205) (xy 97.01932 -279.837479)
			(xy 97.035368 -279.886872) (xy 97.043493 -279.938167) (xy 97.044002 -279.964134) (xy 97.044002 -279.964388)
			(xy 97.043491 -279.990101) (xy 97.323403 -279.990101) (xy 97.323403 -279.938167) (xy 97.331528 -279.886872)
			(xy 97.347576 -279.837479) (xy 97.371154 -279.791205) (xy 97.40168 -279.749189) (xy 97.438403 -279.712466)
			(xy 97.480419 -279.68194) (xy 97.526693 -279.658362) (xy 97.576086 -279.642314) (xy 97.627381 -279.634189)
			(xy 97.679315 -279.634189) (xy 97.73061 -279.642314) (xy 97.780003 -279.658362) (xy 97.826277 -279.68194)
			(xy 97.868293 -279.712466) (xy 97.905016 -279.749189) (xy 97.935542 -279.791205) (xy 97.95912 -279.837479)
			(xy 97.975168 -279.886872) (xy 97.983293 -279.938167) (xy 97.983802 -279.964134) (xy 97.983293 -279.990101)
			(xy 98.263203 -279.990101) (xy 98.263203 -279.938167) (xy 98.271328 -279.886872) (xy 98.287376 -279.837479)
			(xy 98.310954 -279.791205) (xy 98.34148 -279.749189) (xy 98.378203 -279.712466) (xy 98.420219 -279.68194)
			(xy 98.466493 -279.658362) (xy 98.515886 -279.642314) (xy 98.567181 -279.634189) (xy 98.619115 -279.634189)
			(xy 98.67041 -279.642314) (xy 98.719803 -279.658362) (xy 98.766077 -279.68194) (xy 98.808093 -279.712466)
			(xy 98.844816 -279.749189) (xy 98.875342 -279.791205) (xy 98.89892 -279.837479) (xy 98.914968 -279.886872)
			(xy 98.923093 -279.938167) (xy 98.923602 -279.964134) (xy 98.923093 -279.990101) (xy 100.142803 -279.990101)
			(xy 100.142803 -279.938167) (xy 100.150928 -279.886872) (xy 100.166976 -279.837479) (xy 100.190554 -279.791205)
			(xy 100.22108 -279.749189) (xy 100.257803 -279.712466) (xy 100.299819 -279.68194) (xy 100.346093 -279.658362)
			(xy 100.395486 -279.642314) (xy 100.446781 -279.634189) (xy 100.498715 -279.634189) (xy 100.55001 -279.642314)
			(xy 100.599403 -279.658362) (xy 100.645677 -279.68194) (xy 100.687693 -279.712466) (xy 100.724416 -279.749189)
			(xy 100.754942 -279.791205) (xy 100.77852 -279.837479) (xy 100.794568 -279.886872) (xy 100.802693 -279.938167)
			(xy 100.803202 -279.964134) (xy 100.802693 -279.990101) (xy 101.082603 -279.990101) (xy 101.082603 -279.938167)
			(xy 101.090728 -279.886872) (xy 101.106776 -279.837479) (xy 101.130354 -279.791205) (xy 101.16088 -279.749189)
			(xy 101.197603 -279.712466) (xy 101.239619 -279.68194) (xy 101.285893 -279.658362) (xy 101.335286 -279.642314)
			(xy 101.386581 -279.634189) (xy 101.438515 -279.634189) (xy 101.48981 -279.642314) (xy 101.539203 -279.658362)
			(xy 101.585477 -279.68194) (xy 101.627493 -279.712466) (xy 101.664216 -279.749189) (xy 101.694742 -279.791205)
			(xy 101.71832 -279.837479) (xy 101.734368 -279.886872) (xy 101.742493 -279.938167) (xy 101.743002 -279.964134)
			(xy 101.742493 -279.990101) (xy 101.734368 -280.041396) (xy 101.71832 -280.090789) (xy 101.694742 -280.137063)
			(xy 101.664216 -280.179079) (xy 101.627493 -280.215802) (xy 101.585477 -280.246328) (xy 101.539203 -280.269906)
			(xy 101.48981 -280.285954) (xy 101.438515 -280.294079) (xy 101.386581 -280.294079) (xy 101.335286 -280.285954)
			(xy 101.285893 -280.269906) (xy 101.239619 -280.246328) (xy 101.197603 -280.215802) (xy 101.16088 -280.179079)
			(xy 101.130354 -280.137063) (xy 101.106776 -280.090789) (xy 101.090728 -280.041396) (xy 101.082603 -279.990101)
			(xy 100.802693 -279.990101) (xy 100.794568 -280.041396) (xy 100.77852 -280.090789) (xy 100.754942 -280.137063)
			(xy 100.724416 -280.179079) (xy 100.687693 -280.215802) (xy 100.645677 -280.246328) (xy 100.599403 -280.269906)
			(xy 100.55001 -280.285954) (xy 100.498715 -280.294079) (xy 100.446781 -280.294079) (xy 100.395486 -280.285954)
			(xy 100.346093 -280.269906) (xy 100.299819 -280.246328) (xy 100.257803 -280.215802) (xy 100.22108 -280.179079)
			(xy 100.190554 -280.137063) (xy 100.166976 -280.090789) (xy 100.150928 -280.041396) (xy 100.142803 -279.990101)
			(xy 98.923093 -279.990101) (xy 98.914968 -280.041396) (xy 98.89892 -280.090789) (xy 98.875342 -280.137063)
			(xy 98.844816 -280.179079) (xy 98.808093 -280.215802) (xy 98.766077 -280.246328) (xy 98.719803 -280.269906)
			(xy 98.67041 -280.285954) (xy 98.619115 -280.294079) (xy 98.567181 -280.294079) (xy 98.515886 -280.285954)
			(xy 98.466493 -280.269906) (xy 98.420219 -280.246328) (xy 98.378203 -280.215802) (xy 98.34148 -280.179079)
			(xy 98.310954 -280.137063) (xy 98.287376 -280.090789) (xy 98.271328 -280.041396) (xy 98.263203 -279.990101)
			(xy 97.983293 -279.990101) (xy 97.975168 -280.041396) (xy 97.95912 -280.090789) (xy 97.935542 -280.137063)
			(xy 97.905016 -280.179079) (xy 97.868293 -280.215802) (xy 97.826277 -280.246328) (xy 97.780003 -280.269906)
			(xy 97.73061 -280.285954) (xy 97.679315 -280.294079) (xy 97.627381 -280.294079) (xy 97.576086 -280.285954)
			(xy 97.526693 -280.269906) (xy 97.480419 -280.246328) (xy 97.438403 -280.215802) (xy 97.40168 -280.179079)
			(xy 97.371154 -280.137063) (xy 97.347576 -280.090789) (xy 97.331528 -280.041396) (xy 97.323403 -279.990101)
			(xy 97.043491 -279.990101) (xy 97.043446 -279.992374) (xy 97.033998 -280.047542) (xy 97.025206 -280.074116)
			(xy 97.017332 -280.096214) (xy 97.22104 -280.44902) (xy 97.244154 -280.453338) (xy 97.269072 -280.458522)
			(xy 97.317054 -280.475487) (xy 97.36187 -280.499603) (xy 97.402461 -280.530302) (xy 97.437869 -280.566858)
			(xy 97.467258 -280.608407) (xy 97.489934 -280.65397) (xy 97.50536 -280.702468) (xy 97.513173 -280.752758)
			(xy 97.513648 -280.778204) (xy 97.513139 -280.804171) (xy 97.505014 -280.855466) (xy 97.488966 -280.904859)
			(xy 97.465388 -280.951133) (xy 97.434862 -280.993149) (xy 97.398139 -281.029872) (xy 97.356123 -281.060398)
			(xy 97.309849 -281.083976) (xy 97.260456 -281.100024) (xy 97.209161 -281.108149) (xy 97.157227 -281.108149)
			(xy 97.105932 -281.100024) (xy 97.056539 -281.083976) (xy 97.010265 -281.060398) (xy 96.968249 -281.029872)
			(xy 96.931526 -280.993149) (xy 96.901 -280.951133) (xy 96.877422 -280.904859) (xy 96.861374 -280.855466)
			(xy 96.853249 -280.804171) (xy 96.85274 -280.778204) (xy 96.853292 -280.750218) (xy 96.862742 -280.69505)
			(xy 96.871536 -280.668476) (xy 96.879156 -280.646378) (xy 96.675448 -280.293318) (xy 96.652334 -280.289)
			(xy 96.627429 -280.283804) (xy 96.579472 -280.266825) (xy 96.534684 -280.242698) (xy 96.494122 -280.211993)
			(xy 96.458743 -280.175435) (xy 96.429385 -280.133888) (xy 96.406739 -280.088332) (xy 96.391342 -280.039845)
			(xy 96.383557 -279.989571) (xy 96.383094 -279.964134) (xy 96.104202 -279.964134) (xy 96.103693 -279.990101)
			(xy 96.095568 -280.041396) (xy 96.07952 -280.090789) (xy 96.055942 -280.137063) (xy 96.025416 -280.179079)
			(xy 95.988693 -280.215802) (xy 95.946677 -280.246328) (xy 95.900403 -280.269906) (xy 95.85101 -280.285954)
			(xy 95.799715 -280.294079) (xy 95.747781 -280.294079) (xy 95.696486 -280.285954) (xy 95.647093 -280.269906)
			(xy 95.600819 -280.246328) (xy 95.558803 -280.215802) (xy 95.52208 -280.179079) (xy 95.491554 -280.137063)
			(xy 95.467976 -280.090789) (xy 95.451928 -280.041396) (xy 95.443803 -279.990101) (xy 95.163639 -279.990101)
			(xy 95.155514 -280.041396) (xy 95.139466 -280.090789) (xy 95.115888 -280.137063) (xy 95.085362 -280.179079)
			(xy 95.048639 -280.215802) (xy 95.006623 -280.246328) (xy 94.960349 -280.269906) (xy 94.910956 -280.285954)
			(xy 94.859661 -280.294079) (xy 94.807727 -280.294079) (xy 94.756432 -280.285954) (xy 94.707039 -280.269906)
			(xy 94.660765 -280.246328) (xy 94.618749 -280.215802) (xy 94.582026 -280.179079) (xy 94.5515 -280.137063)
			(xy 94.527922 -280.090789) (xy 94.511874 -280.041396) (xy 94.503749 -279.990101) (xy 93.284293 -279.990101)
			(xy 93.276168 -280.041396) (xy 93.26012 -280.090789) (xy 93.236542 -280.137063) (xy 93.206016 -280.179079)
			(xy 93.169293 -280.215802) (xy 93.127277 -280.246328) (xy 93.081003 -280.269906) (xy 93.03161 -280.285954)
			(xy 92.980315 -280.294079) (xy 92.928381 -280.294079) (xy 92.877086 -280.285954) (xy 92.827693 -280.269906)
			(xy 92.781419 -280.246328) (xy 92.739403 -280.215802) (xy 92.70268 -280.179079) (xy 92.672154 -280.137063)
			(xy 92.648576 -280.090789) (xy 92.632528 -280.041396) (xy 92.624403 -279.990101) (xy 92.344493 -279.990101)
			(xy 92.336368 -280.041396) (xy 92.32032 -280.090789) (xy 92.296742 -280.137063) (xy 92.266216 -280.179079)
			(xy 92.229493 -280.215802) (xy 92.187477 -280.246328) (xy 92.141203 -280.269906) (xy 92.09181 -280.285954)
			(xy 92.040515 -280.294079) (xy 91.988581 -280.294079) (xy 91.937286 -280.285954) (xy 91.887893 -280.269906)
			(xy 91.841619 -280.246328) (xy 91.799603 -280.215802) (xy 91.76288 -280.179079) (xy 91.732354 -280.137063)
			(xy 91.708776 -280.090789) (xy 91.692728 -280.041396) (xy 91.684603 -279.990101) (xy 90.49029 -279.990101)
			(xy 90.49025 -279.992115) (xy 90.481491 -280.047388) (xy 90.464194 -280.10061) (xy 90.438784 -280.150471)
			(xy 90.405887 -280.195744) (xy 90.366313 -280.235313) (xy 90.321037 -280.268205) (xy 90.271173 -280.293609)
			(xy 90.217949 -280.310901) (xy 90.162675 -280.319654) (xy 90.134694 -280.320242) (xy 90.110258 -280.319839)
			(xy 90.061845 -280.313157) (xy 90.0148 -280.29992) (xy 89.970006 -280.280377) (xy 89.928303 -280.254893)
			(xy 89.909142 -280.239724) (xy 89.905586 -280.23693) (xy 89.873582 -280.225246) (xy 89.832434 -280.227024)
			(xy 89.803732 -280.228294) (xy 89.794447 -280.229101) (xy 89.777369 -280.23652) (xy 89.770458 -280.242772)
			(xy 89.738708 -280.274522) (xy 89.730412 -280.283815) (xy 89.72336 -280.307673) (xy 89.725246 -280.319988)
			(xy 89.735152 -280.362914) (xy 89.745058 -280.40457) (xy 89.747376 -280.412718) (xy 89.756566 -280.426938)
			(xy 89.769913 -280.437354) (xy 89.777824 -280.440384) (xy 89.777824 -280.440638) (xy 89.804005 -280.449947)
			(xy 89.85333 -280.47553) (xy 89.898078 -280.50847) (xy 89.937161 -280.547965) (xy 89.969629 -280.593057)
			(xy 89.994693 -280.642647) (xy 90.011743 -280.69553) (xy 90.020365 -280.750422) (xy 90.020902 -280.778204)
			(xy 90.020451 -280.803816) (xy 90.0204 -280.804171) (xy 90.274649 -280.804171) (xy 90.274649 -280.752237)
			(xy 90.282774 -280.700942) (xy 90.298822 -280.651549) (xy 90.3224 -280.605275) (xy 90.352926 -280.563259)
			(xy 90.389649 -280.526536) (xy 90.431665 -280.49601) (xy 90.477939 -280.472432) (xy 90.527332 -280.456384)
			(xy 90.578627 -280.448259) (xy 90.630561 -280.448259) (xy 90.681856 -280.456384) (xy 90.731249 -280.472432)
			(xy 90.777523 -280.49601) (xy 90.819539 -280.526536) (xy 90.856262 -280.563259) (xy 90.886788 -280.605275)
			(xy 90.910366 -280.651549) (xy 90.926414 -280.700942) (xy 90.934539 -280.752237) (xy 90.935048 -280.778204)
			(xy 92.153994 -280.778204) (xy 92.154503 -280.752237) (xy 92.162628 -280.700942) (xy 92.178676 -280.651549)
			(xy 92.202254 -280.605275) (xy 92.23278 -280.563259) (xy 92.269503 -280.526536) (xy 92.311519 -280.49601)
			(xy 92.357793 -280.472432) (xy 92.407186 -280.456384) (xy 92.458481 -280.448259) (xy 92.510415 -280.448259)
			(xy 92.56171 -280.456384) (xy 92.611103 -280.472432) (xy 92.657377 -280.49601) (xy 92.699393 -280.526536)
			(xy 92.736116 -280.563259) (xy 92.766642 -280.605275) (xy 92.79022 -280.651549) (xy 92.806268 -280.700942)
			(xy 92.814393 -280.752237) (xy 92.814902 -280.778204) (xy 92.814902 -280.778458) (xy 92.814385 -280.804171)
			(xy 94.034103 -280.804171) (xy 94.034103 -280.752237) (xy 94.042228 -280.700942) (xy 94.058276 -280.651549)
			(xy 94.081854 -280.605275) (xy 94.11238 -280.563259) (xy 94.149103 -280.526536) (xy 94.191119 -280.49601)
			(xy 94.237393 -280.472432) (xy 94.286786 -280.456384) (xy 94.338081 -280.448259) (xy 94.390015 -280.448259)
			(xy 94.44131 -280.456384) (xy 94.490703 -280.472432) (xy 94.536977 -280.49601) (xy 94.578993 -280.526536)
			(xy 94.615716 -280.563259) (xy 94.646242 -280.605275) (xy 94.66982 -280.651549) (xy 94.685868 -280.700942)
			(xy 94.693993 -280.752237) (xy 94.694502 -280.778204) (xy 94.693993 -280.804167) (xy 94.973659 -280.804167)
			(xy 94.973659 -280.752233) (xy 94.981783 -280.70094) (xy 94.997831 -280.651548) (xy 95.021408 -280.605275)
			(xy 95.051934 -280.56326) (xy 95.088656 -280.526537) (xy 95.13067 -280.496011) (xy 95.176943 -280.472434)
			(xy 95.226334 -280.456385) (xy 95.277627 -280.44826) (xy 95.303594 -280.44775) (xy 95.329217 -280.448197)
			(xy 95.379846 -280.456128) (xy 95.428647 -280.471768) (xy 95.474453 -280.494746) (xy 95.516169 -280.52451)
			(xy 95.552798 -280.56035) (xy 95.568516 -280.580592) (xy 95.978726 -280.580592) (xy 95.994447 -280.560352)
			(xy 96.031064 -280.5245) (xy 96.072777 -280.494731) (xy 96.118586 -280.471758) (xy 96.167392 -280.456133)
			(xy 96.218025 -280.448229) (xy 96.243648 -280.44775) (xy 96.269613 -280.448255) (xy 96.320903 -280.456385)
			(xy 96.37029 -280.472438) (xy 96.416557 -280.496019) (xy 96.458567 -280.526546) (xy 96.495285 -280.563269)
			(xy 96.525806 -280.605284) (xy 96.54938 -280.651555) (xy 96.565426 -280.700944) (xy 96.573549 -280.752235)
			(xy 96.573549 -280.804165) (xy 96.565426 -280.855456) (xy 96.54938 -280.904845) (xy 96.525806 -280.951116)
			(xy 96.495285 -280.993131) (xy 96.458567 -281.029854) (xy 96.416557 -281.060381) (xy 96.37029 -281.083962)
			(xy 96.320903 -281.100015) (xy 96.269613 -281.108145) (xy 96.243648 -281.108658) (xy 96.218026 -281.108177)
			(xy 96.167399 -281.100253) (xy 96.118599 -281.084619) (xy 96.072793 -281.061648) (xy 96.031075 -281.03189)
			(xy 95.994445 -280.996055) (xy 95.978726 -280.975816) (xy 95.568516 -280.975816) (xy 95.552773 -280.996038)
			(xy 95.51616 -281.03189) (xy 95.474452 -281.061661) (xy 95.428647 -281.084637) (xy 95.379845 -281.100267)
			(xy 95.329216 -281.108176) (xy 95.303594 -281.108658) (xy 95.277627 -281.10814) (xy 95.226334 -281.100015)
			(xy 95.176943 -281.083966) (xy 95.13067 -281.060389) (xy 95.088656 -281.029863) (xy 95.051934 -280.99314)
			(xy 95.021408 -280.951125) (xy 94.997831 -280.904852) (xy 94.981783 -280.85546) (xy 94.973659 -280.804167)
			(xy 94.693993 -280.804167) (xy 94.693993 -280.804171) (xy 94.685868 -280.855466) (xy 94.66982 -280.904859)
			(xy 94.646242 -280.951133) (xy 94.615716 -280.993149) (xy 94.578993 -281.029872) (xy 94.536977 -281.060398)
			(xy 94.490703 -281.083976) (xy 94.44131 -281.100024) (xy 94.390015 -281.108149) (xy 94.338081 -281.108149)
			(xy 94.286786 -281.100024) (xy 94.237393 -281.083976) (xy 94.191119 -281.060398) (xy 94.149103 -281.029872)
			(xy 94.11238 -280.993149) (xy 94.081854 -280.951133) (xy 94.058276 -280.904859) (xy 94.042228 -280.855466)
			(xy 94.034103 -280.804171) (xy 92.814385 -280.804171) (xy 92.814339 -280.806443) (xy 92.804896 -280.861611)
			(xy 92.796106 -280.888186) (xy 92.788232 -280.910284) (xy 92.99194 -281.262836) (xy 93.015054 -281.267154)
			(xy 93.039975 -281.272323) (xy 93.087958 -281.289289) (xy 93.132775 -281.313407) (xy 93.173367 -281.344107)
			(xy 93.208776 -281.380665) (xy 93.238164 -281.422217) (xy 93.260838 -281.467781) (xy 93.276263 -281.516282)
			(xy 93.284074 -281.566573) (xy 93.284548 -281.59202) (xy 93.284039 -281.617987) (xy 93.275914 -281.669282)
			(xy 93.259866 -281.718675) (xy 93.236288 -281.764949) (xy 93.205762 -281.806965) (xy 93.169039 -281.843688)
			(xy 93.127023 -281.874214) (xy 93.080749 -281.897792) (xy 93.031356 -281.91384) (xy 92.980061 -281.921965)
			(xy 92.928127 -281.921965) (xy 92.876832 -281.91384) (xy 92.827439 -281.897792) (xy 92.781165 -281.874214)
			(xy 92.739149 -281.843688) (xy 92.702426 -281.806965) (xy 92.6719 -281.764949) (xy 92.648322 -281.718675)
			(xy 92.632274 -281.669282) (xy 92.624149 -281.617987) (xy 92.62364 -281.59202) (xy 92.624259 -281.564103)
			(xy 92.633714 -281.509073) (xy 92.642436 -281.482546) (xy 92.650056 -281.460448) (xy 92.446348 -281.107388)
			(xy 92.423234 -281.10307) (xy 92.398322 -281.097902) (xy 92.350363 -281.080921) (xy 92.305574 -281.056792)
			(xy 92.26501 -281.026083) (xy 92.229632 -280.989522) (xy 92.200274 -280.94797) (xy 92.177631 -280.902411)
			(xy 92.162236 -280.85392) (xy 92.154454 -280.803642) (xy 92.153994 -280.778204) (xy 90.935048 -280.778204)
			(xy 90.934539 -280.804171) (xy 90.926414 -280.855466) (xy 90.910366 -280.904859) (xy 90.886788 -280.951133)
			(xy 90.856262 -280.993149) (xy 90.819539 -281.029872) (xy 90.777523 -281.060398) (xy 90.731249 -281.083976)
			(xy 90.681856 -281.100024) (xy 90.630561 -281.108149) (xy 90.578627 -281.108149) (xy 90.527332 -281.100024)
			(xy 90.477939 -281.083976) (xy 90.431665 -281.060398) (xy 90.389649 -281.029872) (xy 90.352926 -280.993149)
			(xy 90.3224 -280.951133) (xy 90.298822 -280.904859) (xy 90.282774 -280.855466) (xy 90.274649 -280.804171)
			(xy 90.0204 -280.804171) (xy 90.0131 -280.85451) (xy 89.998566 -280.903629) (xy 89.977148 -280.950161)
			(xy 89.949286 -280.993145) (xy 89.915557 -281.031697) (xy 89.876654 -281.065022) (xy 89.83338 -281.092431)
			(xy 89.786627 -281.113362) (xy 89.737359 -281.127381) (xy 89.712038 -281.131264) (xy 89.6874 -281.134566)
			(xy 89.499186 -281.460194) (xy 89.506806 -281.482292) (xy 89.515598 -281.508867) (xy 89.525044 -281.564034)
			(xy 89.525602 -281.59202) (xy 89.525093 -281.617987) (xy 89.804749 -281.617987) (xy 89.804749 -281.566053)
			(xy 89.812874 -281.514758) (xy 89.828922 -281.465365) (xy 89.8525 -281.419091) (xy 89.883026 -281.377075)
			(xy 89.919749 -281.340352) (xy 89.961765 -281.309826) (xy 90.008039 -281.286248) (xy 90.057432 -281.2702)
			(xy 90.108727 -281.262075) (xy 90.160661 -281.262075) (xy 90.211956 -281.2702) (xy 90.261349 -281.286248)
			(xy 90.307623 -281.309826) (xy 90.349639 -281.340352) (xy 90.386362 -281.377075) (xy 90.416888 -281.419091)
			(xy 90.440466 -281.465365) (xy 90.456514 -281.514758) (xy 90.464639 -281.566053) (xy 90.465148 -281.59202)
			(xy 90.464639 -281.617965) (xy 90.744575 -281.617965) (xy 90.744575 -281.566035) (xy 90.752699 -281.514743)
			(xy 90.768746 -281.465354) (xy 90.792322 -281.419084) (xy 90.822846 -281.37707) (xy 90.859566 -281.34035)
			(xy 90.901578 -281.309825) (xy 90.947849 -281.286248) (xy 90.997237 -281.2702) (xy 91.048529 -281.262076)
			(xy 91.074494 -281.261566) (xy 91.100115 -281.262047) (xy 91.150741 -281.269975) (xy 91.19954 -281.285611)
			(xy 91.245345 -281.308582) (xy 91.287063 -281.338339) (xy 91.323695 -281.374171) (xy 91.339416 -281.394408)
			(xy 91.749372 -281.394408) (xy 91.76507 -281.374149) (xy 91.801691 -281.338298) (xy 91.843409 -281.30853)
			(xy 91.889222 -281.285561) (xy 91.938033 -281.269939) (xy 91.988669 -281.262041) (xy 92.014294 -281.261566)
			(xy 92.040265 -281.262008) (xy 92.091568 -281.270133) (xy 92.140968 -281.286184) (xy 92.18725 -281.309764)
			(xy 92.229272 -281.340295) (xy 92.266001 -281.377023) (xy 92.296533 -281.419045) (xy 92.320114 -281.465326)
			(xy 92.336165 -281.514726) (xy 92.344291 -281.566029) (xy 92.344291 -281.617971) (xy 92.336165 -281.669274)
			(xy 92.320114 -281.718674) (xy 92.296533 -281.764955) (xy 92.266001 -281.806977) (xy 92.229272 -281.843705)
			(xy 92.18725 -281.874236) (xy 92.140968 -281.897816) (xy 92.091568 -281.913867) (xy 92.040265 -281.921992)
			(xy 92.014294 -281.922474) (xy 91.988674 -281.921953) (xy 91.938049 -281.914037) (xy 91.88925 -281.89841)
			(xy 91.843443 -281.875447) (xy 91.801725 -281.845696) (xy 91.765092 -281.809868) (xy 91.749372 -281.789632)
			(xy 91.339416 -281.789632) (xy 91.323677 -281.809857) (xy 91.287063 -281.845709) (xy 91.245353 -281.875479)
			(xy 91.199548 -281.898454) (xy 91.150746 -281.914083) (xy 91.100116 -281.921992) (xy 91.074494 -281.922474)
			(xy 91.048529 -281.921924) (xy 90.997237 -281.9138) (xy 90.947849 -281.897752) (xy 90.901578 -281.874175)
			(xy 90.859566 -281.84365) (xy 90.822846 -281.80693) (xy 90.792322 -281.764916) (xy 90.768746 -281.718646)
			(xy 90.752699 -281.669257) (xy 90.744575 -281.617965) (xy 90.464639 -281.617965) (xy 90.464639 -281.617987)
			(xy 90.456514 -281.669282) (xy 90.440466 -281.718675) (xy 90.416888 -281.764949) (xy 90.386362 -281.806965)
			(xy 90.349639 -281.843688) (xy 90.307623 -281.874214) (xy 90.261349 -281.897792) (xy 90.211956 -281.91384)
			(xy 90.160661 -281.921965) (xy 90.108727 -281.921965) (xy 90.057432 -281.91384) (xy 90.008039 -281.897792)
			(xy 89.961765 -281.874214) (xy 89.919749 -281.843688) (xy 89.883026 -281.806965) (xy 89.8525 -281.764949)
			(xy 89.828922 -281.718675) (xy 89.812874 -281.669282) (xy 89.804749 -281.617987) (xy 89.525093 -281.617987)
			(xy 89.516968 -281.669282) (xy 89.50092 -281.718675) (xy 89.477342 -281.764949) (xy 89.446816 -281.806965)
			(xy 89.410093 -281.843688) (xy 89.368077 -281.874214) (xy 89.321803 -281.897792) (xy 89.27241 -281.91384)
			(xy 89.221115 -281.921965) (xy 89.169181 -281.921965) (xy 89.117886 -281.91384) (xy 89.068493 -281.897792)
			(xy 89.022219 -281.874214) (xy 88.980203 -281.843688) (xy 88.94348 -281.806965) (xy 88.912954 -281.764949)
			(xy 88.889376 -281.718675) (xy 88.873328 -281.669282) (xy 88.865203 -281.617987) (xy 88.864694 -281.59202)
			(xy 88.865168 -281.566574) (xy 88.87298 -281.516285) (xy 88.888405 -281.467786) (xy 88.91108 -281.422225)
			(xy 88.94047 -281.380676) (xy 88.97588 -281.344122) (xy 89.016473 -281.313426) (xy 89.06129 -281.289313)
			(xy 89.109274 -281.272353) (xy 89.134188 -281.267154) (xy 89.157302 -281.262836) (xy 89.345262 -280.937208)
			(xy 89.338404 -280.920444) (xy 89.327228 -280.891234) (xy 89.326974 -280.891234) (xy 89.323996 -280.883292)
			(xy 89.313606 -280.869899) (xy 89.299328 -280.860764) (xy 89.29116 -280.858468) (xy 89.249504 -280.848816)
			(xy 89.206578 -280.838656) (xy 89.194264 -280.836773) (xy 89.170404 -280.843823) (xy 89.161112 -280.852118)
			(xy 88.825578 -281.187652) (xy 88.821514 -281.197304) (xy 88.801548 -281.245147) (xy 88.753976 -281.337265)
			(xy 88.698085 -281.424586) (xy 88.634355 -281.506362) (xy 88.599264 -281.544522) (xy 88.585548 -281.578812)
			(xy 88.585802 -281.588972) (xy 88.585802 -281.59202) (xy 88.585291 -281.618006) (xy 88.577158 -281.669338)
			(xy 88.561095 -281.718765) (xy 88.537498 -281.765071) (xy 88.506948 -281.807116) (xy 88.470197 -281.843865)
			(xy 88.428149 -281.874412) (xy 88.381841 -281.898005) (xy 88.332412 -281.914064) (xy 88.28108 -281.922193)
			(xy 88.255094 -281.922728) (xy 88.254586 -281.922728) (xy 88.228351 -281.922228) (xy 88.17654 -281.913937)
			(xy 88.151462 -281.906218) (xy 88.147652 -281.904948) (xy 88.131396 -281.902154) (xy 88.121621 -281.902722)
			(xy 88.103585 -281.910296) (xy 88.096344 -281.916886) (xy 88.018366 -281.994864) (xy 88.011962 -282.001903)
			(xy 88.004535 -282.019405) (xy 88.003888 -282.0289) (xy 88.004904 -282.070302) (xy 88.00592 -282.104592)
			(xy 88.006577 -282.113805) (xy 88.013611 -282.130865) (xy 88.019636 -282.137866) (xy 88.022684 -282.140406)
			(xy 88.040998 -282.157378) (xy 88.073171 -282.19556) (xy 88.099702 -282.237859) (xy 88.12007 -282.283447)
			(xy 88.133877 -282.33143) (xy 88.140854 -282.380871) (xy 88.141302 -282.405836) (xy 88.140924 -282.42908)
			(xy 88.140571 -282.431769) (xy 88.395265 -282.431769) (xy 88.395265 -282.379831) (xy 88.403391 -282.328533)
			(xy 88.419442 -282.279138) (xy 88.443023 -282.232862) (xy 88.473554 -282.190845) (xy 88.510282 -282.154122)
			(xy 88.552303 -282.123598) (xy 88.598582 -282.100023) (xy 88.64798 -282.083979) (xy 88.699279 -282.075861)
			(xy 88.725248 -282.075382) (xy 88.750868 -282.07589) (xy 88.801493 -282.083811) (xy 88.850292 -282.099442)
			(xy 88.896098 -282.122408) (xy 88.937816 -282.15216) (xy 88.974449 -282.187988) (xy 88.99017 -282.208224)
			(xy 89.400126 -282.208224) (xy 89.415828 -282.18797) (xy 89.452452 -282.152122) (xy 89.494169 -282.122356)
			(xy 89.539981 -282.099387) (xy 89.588789 -282.083763) (xy 89.639424 -282.07586) (xy 89.665048 -282.075382)
			(xy 89.691016 -282.075823) (xy 89.74231 -282.083954) (xy 89.791702 -282.100009) (xy 89.837974 -282.123592)
			(xy 89.879988 -282.154122) (xy 89.916709 -282.190849) (xy 89.947234 -282.232867) (xy 89.97081 -282.279143)
			(xy 89.986857 -282.328536) (xy 89.994981 -282.379832) (xy 89.994981 -282.431768) (xy 89.994975 -282.431803)
			(xy 90.274903 -282.431803) (xy 90.274903 -282.379869) (xy 90.283028 -282.328574) (xy 90.299076 -282.279181)
			(xy 90.322654 -282.232907) (xy 90.35318 -282.190891) (xy 90.389903 -282.154168) (xy 90.431919 -282.123642)
			(xy 90.478193 -282.100064) (xy 90.527586 -282.084016) (xy 90.578881 -282.075891) (xy 90.630815 -282.075891)
			(xy 90.68211 -282.084016) (xy 90.731503 -282.100064) (xy 90.777777 -282.123642) (xy 90.819793 -282.154168)
			(xy 90.856516 -282.190891) (xy 90.887042 -282.232907) (xy 90.91062 -282.279181) (xy 90.926668 -282.328574)
			(xy 90.934793 -282.379869) (xy 90.935302 -282.405836) (xy 90.934793 -282.431803) (xy 90.926668 -282.483098)
			(xy 90.91062 -282.532491) (xy 90.887042 -282.578765) (xy 90.856516 -282.620781) (xy 90.819793 -282.657504)
			(xy 90.777777 -282.68803) (xy 90.731503 -282.711608) (xy 90.68211 -282.727656) (xy 90.630815 -282.735781)
			(xy 90.578881 -282.735781) (xy 90.527586 -282.727656) (xy 90.478193 -282.711608) (xy 90.431919 -282.68803)
			(xy 90.389903 -282.657504) (xy 90.35318 -282.620781) (xy 90.322654 -282.578765) (xy 90.299076 -282.532491)
			(xy 90.283028 -282.483098) (xy 90.274903 -282.431803) (xy 89.994975 -282.431803) (xy 89.986857 -282.483064)
			(xy 89.97081 -282.532457) (xy 89.947234 -282.578733) (xy 89.916709 -282.620752) (xy 89.879988 -282.657478)
			(xy 89.837974 -282.688008) (xy 89.791702 -282.711591) (xy 89.74231 -282.727646) (xy 89.691016 -282.735777)
			(xy 89.665048 -282.73629) (xy 89.639427 -282.735796) (xy 89.588801 -282.727874) (xy 89.540002 -282.712241)
			(xy 89.494196 -282.689272) (xy 89.452478 -282.659517) (xy 89.415846 -282.623685) (xy 89.400126 -282.603448)
			(xy 88.99017 -282.603448) (xy 88.974463 -282.623698) (xy 88.937841 -282.659548) (xy 88.896125 -282.689315)
			(xy 88.850314 -282.712285) (xy 88.801506 -282.727909) (xy 88.750872 -282.735812) (xy 88.725248 -282.73629)
			(xy 88.699279 -282.735739) (xy 88.64798 -282.727621) (xy 88.598582 -282.711577) (xy 88.552303 -282.688002)
			(xy 88.510282 -282.657478) (xy 88.473554 -282.620755) (xy 88.443023 -282.578738) (xy 88.419442 -282.532462)
			(xy 88.403391 -282.483067) (xy 88.395265 -282.431769) (xy 88.140571 -282.431769) (xy 88.134875 -282.475174)
			(xy 88.122884 -282.52009) (xy 88.114378 -282.541726) (xy 88.104726 -282.56484) (xy 88.29294 -282.890722)
			(xy 88.316054 -282.89504) (xy 88.340983 -282.900191) (xy 88.388982 -282.917132) (xy 88.433814 -282.941237)
			(xy 88.474418 -282.971933) (xy 88.509832 -283.008496) (xy 88.539218 -283.050058) (xy 88.561881 -283.095636)
			(xy 88.577283 -283.144151) (xy 88.58506 -283.194455) (xy 88.585548 -283.219906) (xy 88.585039 -283.245873)
			(xy 88.864949 -283.245873) (xy 88.864949 -283.193939) (xy 88.873074 -283.142644) (xy 88.889122 -283.093251)
			(xy 88.9127 -283.046977) (xy 88.943226 -283.004961) (xy 88.979949 -282.968238) (xy 89.021965 -282.937712)
			(xy 89.068239 -282.914134) (xy 89.117632 -282.898086) (xy 89.168927 -282.889961) (xy 89.220861 -282.889961)
			(xy 89.272156 -282.898086) (xy 89.321549 -282.914134) (xy 89.367823 -282.937712) (xy 89.409839 -282.968238)
			(xy 89.446562 -283.004961) (xy 89.477088 -283.046977) (xy 89.500666 -283.093251) (xy 89.516714 -283.142644)
			(xy 89.524839 -283.193939) (xy 89.525348 -283.219906) (xy 89.524839 -283.245873) (xy 89.804749 -283.245873)
			(xy 89.804749 -283.193939) (xy 89.812874 -283.142644) (xy 89.828922 -283.093251) (xy 89.8525 -283.046977)
			(xy 89.883026 -283.004961) (xy 89.919749 -282.968238) (xy 89.961765 -282.937712) (xy 90.008039 -282.914134)
			(xy 90.057432 -282.898086) (xy 90.108727 -282.889961) (xy 90.160661 -282.889961) (xy 90.211956 -282.898086)
			(xy 90.261349 -282.914134) (xy 90.307623 -282.937712) (xy 90.349639 -282.968238) (xy 90.386362 -283.004961)
			(xy 90.416888 -283.046977) (xy 90.440466 -283.093251) (xy 90.456514 -283.142644) (xy 90.464639 -283.193939)
			(xy 90.465148 -283.219906) (xy 90.74404 -283.219906) (xy 90.744538 -283.194455) (xy 90.752315 -283.144153)
			(xy 90.767716 -283.095638) (xy 90.790378 -283.050061) (xy 90.819762 -283.008499) (xy 90.855175 -282.971936)
			(xy 90.895777 -282.941239) (xy 90.940608 -282.917134) (xy 90.988606 -282.900191) (xy 91.013534 -282.89504)
			(xy 91.036648 -282.890722) (xy 91.24061 -282.537408) (xy 91.23299 -282.51531) (xy 91.224247 -282.488788)
			(xy 91.214796 -282.433755) (xy 91.214194 -282.405836) (xy 91.214703 -282.379869) (xy 91.222828 -282.328574)
			(xy 91.238876 -282.279181) (xy 91.262454 -282.232907) (xy 91.29298 -282.190891) (xy 91.329703 -282.154168)
			(xy 91.371719 -282.123642) (xy 91.417993 -282.100064) (xy 91.467386 -282.084016) (xy 91.518681 -282.075891)
			(xy 91.570615 -282.075891) (xy 91.62191 -282.084016) (xy 91.671303 -282.100064) (xy 91.717577 -282.123642)
			(xy 91.759593 -282.154168) (xy 91.796316 -282.190891) (xy 91.826842 -282.232907) (xy 91.85042 -282.279181)
			(xy 91.866468 -282.328574) (xy 91.874593 -282.379869) (xy 91.875102 -282.405836) (xy 91.874652 -282.431299)
			(xy 91.874574 -282.431803) (xy 92.154503 -282.431803) (xy 92.154503 -282.379869) (xy 92.162628 -282.328574)
			(xy 92.178676 -282.279181) (xy 92.202254 -282.232907) (xy 92.23278 -282.190891) (xy 92.269503 -282.154168)
			(xy 92.311519 -282.123642) (xy 92.357793 -282.100064) (xy 92.407186 -282.084016) (xy 92.458481 -282.075891)
			(xy 92.510415 -282.075891) (xy 92.56171 -282.084016) (xy 92.611103 -282.100064) (xy 92.657377 -282.123642)
			(xy 92.699393 -282.154168) (xy 92.736116 -282.190891) (xy 92.766642 -282.232907) (xy 92.79022 -282.279181)
			(xy 92.806268 -282.328574) (xy 92.814393 -282.379869) (xy 92.814902 -282.405836) (xy 93.093794 -282.405836)
			(xy 93.094265 -282.380385) (xy 93.102051 -282.330083) (xy 93.11746 -282.28157) (xy 93.140126 -282.235995)
			(xy 93.169515 -282.194434) (xy 93.204929 -282.157873) (xy 93.245532 -282.127176) (xy 93.290363 -282.103069)
			(xy 93.33836 -282.086123) (xy 93.363288 -282.08097) (xy 93.386402 -282.076652) (xy 93.59011 -281.723846)
			(xy 93.582236 -281.701748) (xy 93.573511 -281.675156) (xy 93.564055 -281.62) (xy 93.56344 -281.59202)
			(xy 93.563949 -281.566053) (xy 93.572074 -281.514758) (xy 93.588122 -281.465365) (xy 93.6117 -281.419091)
			(xy 93.642226 -281.377075) (xy 93.678949 -281.340352) (xy 93.720965 -281.309826) (xy 93.767239 -281.286248)
			(xy 93.816632 -281.2702) (xy 93.867927 -281.262075) (xy 93.919861 -281.262075) (xy 93.971156 -281.2702)
			(xy 94.020549 -281.286248) (xy 94.066823 -281.309826) (xy 94.108839 -281.340352) (xy 94.145562 -281.377075)
			(xy 94.176088 -281.419091) (xy 94.199666 -281.465365) (xy 94.215714 -281.514758) (xy 94.223839 -281.566053)
			(xy 94.224348 -281.59202) (xy 94.223883 -281.617472) (xy 94.223803 -281.617987) (xy 94.503749 -281.617987)
			(xy 94.503749 -281.566053) (xy 94.511874 -281.514758) (xy 94.527922 -281.465365) (xy 94.5515 -281.419091)
			(xy 94.582026 -281.377075) (xy 94.618749 -281.340352) (xy 94.660765 -281.309826) (xy 94.707039 -281.286248)
			(xy 94.756432 -281.2702) (xy 94.807727 -281.262075) (xy 94.859661 -281.262075) (xy 94.910956 -281.2702)
			(xy 94.960349 -281.286248) (xy 95.006623 -281.309826) (xy 95.048639 -281.340352) (xy 95.085362 -281.377075)
			(xy 95.115888 -281.419091) (xy 95.139466 -281.465365) (xy 95.155514 -281.514758) (xy 95.163639 -281.566053)
			(xy 95.164148 -281.59202) (xy 95.163639 -281.617987) (xy 95.155514 -281.669282) (xy 95.139466 -281.718675)
			(xy 95.115888 -281.764949) (xy 95.085362 -281.806965) (xy 95.048639 -281.843688) (xy 95.006623 -281.874214)
			(xy 94.960349 -281.897792) (xy 94.910956 -281.91384) (xy 94.859661 -281.921965) (xy 94.807727 -281.921965)
			(xy 94.756432 -281.91384) (xy 94.707039 -281.897792) (xy 94.660765 -281.874214) (xy 94.618749 -281.843688)
			(xy 94.582026 -281.806965) (xy 94.5515 -281.764949) (xy 94.527922 -281.718675) (xy 94.511874 -281.669282)
			(xy 94.503749 -281.617987) (xy 94.223803 -281.617987) (xy 94.216102 -281.667777) (xy 94.200697 -281.716292)
			(xy 94.178031 -281.761871) (xy 94.148642 -281.803433) (xy 94.113225 -281.839994) (xy 94.072619 -281.870691)
			(xy 94.027785 -281.894795) (xy 93.979783 -281.911736) (xy 93.954854 -281.916886) (xy 93.931994 -281.921204)
			(xy 93.728286 -282.27401) (xy 93.735906 -282.296108) (xy 93.744646 -282.322696) (xy 93.754092 -282.377855)
			(xy 93.754702 -282.405836) (xy 93.754193 -282.431803) (xy 94.034103 -282.431803) (xy 94.034103 -282.379869)
			(xy 94.042228 -282.328574) (xy 94.058276 -282.279181) (xy 94.081854 -282.232907) (xy 94.11238 -282.190891)
			(xy 94.149103 -282.154168) (xy 94.191119 -282.123642) (xy 94.237393 -282.100064) (xy 94.286786 -282.084016)
			(xy 94.338081 -282.075891) (xy 94.390015 -282.075891) (xy 94.44131 -282.084016) (xy 94.490703 -282.100064)
			(xy 94.536977 -282.123642) (xy 94.578993 -282.154168) (xy 94.615716 -282.190891) (xy 94.646242 -282.232907)
			(xy 94.66982 -282.279181) (xy 94.685868 -282.328574) (xy 94.693993 -282.379869) (xy 94.694502 -282.405836)
			(xy 94.97314 -282.405836) (xy 94.973574 -282.380383) (xy 94.981361 -282.330078) (xy 94.996772 -282.281562)
			(xy 95.019443 -282.235984) (xy 95.048836 -282.194422) (xy 95.084256 -282.157861) (xy 95.124864 -282.127166)
			(xy 95.169701 -282.103062) (xy 95.217704 -282.08612) (xy 95.242634 -282.08097) (xy 95.265748 -282.076652)
			(xy 95.46971 -281.723338) (xy 95.461836 -281.70124) (xy 95.453218 -281.674825) (xy 95.443891 -281.620053)
			(xy 95.443294 -281.592274) (xy 95.443294 -281.59202) (xy 95.443803 -281.566053) (xy 95.451928 -281.514758)
			(xy 95.467976 -281.465365) (xy 95.491554 -281.419091) (xy 95.52208 -281.377075) (xy 95.558803 -281.340352)
			(xy 95.600819 -281.309826) (xy 95.647093 -281.286248) (xy 95.696486 -281.2702) (xy 95.747781 -281.262075)
			(xy 95.799715 -281.262075) (xy 95.85101 -281.2702) (xy 95.900403 -281.286248) (xy 95.946677 -281.309826)
			(xy 95.988693 -281.340352) (xy 96.025416 -281.377075) (xy 96.055942 -281.419091) (xy 96.07952 -281.465365)
			(xy 96.095568 -281.514758) (xy 96.103693 -281.566053) (xy 96.104202 -281.59202) (xy 96.103699 -281.617492)
			(xy 96.103622 -281.617987) (xy 96.383603 -281.617987) (xy 96.383603 -281.566053) (xy 96.391728 -281.514758)
			(xy 96.407776 -281.465365) (xy 96.431354 -281.419091) (xy 96.46188 -281.377075) (xy 96.498603 -281.340352)
			(xy 96.540619 -281.309826) (xy 96.586893 -281.286248) (xy 96.636286 -281.2702) (xy 96.687581 -281.262075)
			(xy 96.739515 -281.262075) (xy 96.79081 -281.2702) (xy 96.840203 -281.286248) (xy 96.886477 -281.309826)
			(xy 96.928493 -281.340352) (xy 96.965216 -281.377075) (xy 96.995742 -281.419091) (xy 97.01932 -281.465365)
			(xy 97.035368 -281.514758) (xy 97.043493 -281.566053) (xy 97.044002 -281.59202) (xy 97.322894 -281.59202)
			(xy 97.323351 -281.566569) (xy 97.331139 -281.516266) (xy 97.34655 -281.467753) (xy 97.369218 -281.422177)
			(xy 97.398609 -281.380617) (xy 97.434025 -281.344056) (xy 97.474629 -281.313359) (xy 97.519461 -281.289253)
			(xy 97.56746 -281.272307) (xy 97.592388 -281.267154) (xy 97.615502 -281.262836) (xy 97.81921 -280.91003)
			(xy 97.811336 -280.887932) (xy 97.802607 -280.861341) (xy 97.793154 -280.806184) (xy 97.79254 -280.778204)
			(xy 97.793049 -280.752237) (xy 97.801174 -280.700942) (xy 97.817222 -280.651549) (xy 97.8408 -280.605275)
			(xy 97.871326 -280.563259) (xy 97.908049 -280.526536) (xy 97.950065 -280.49601) (xy 97.996339 -280.472432)
			(xy 98.045732 -280.456384) (xy 98.097027 -280.448259) (xy 98.148961 -280.448259) (xy 98.200256 -280.456384)
			(xy 98.249649 -280.472432) (xy 98.295923 -280.49601) (xy 98.337939 -280.526536) (xy 98.374662 -280.563259)
			(xy 98.405188 -280.605275) (xy 98.428766 -280.651549) (xy 98.444814 -280.700942) (xy 98.452939 -280.752237)
			(xy 98.453448 -280.778204) (xy 98.452969 -280.803655) (xy 98.452889 -280.804171) (xy 98.732849 -280.804171)
			(xy 98.732849 -280.752237) (xy 98.740974 -280.700942) (xy 98.757022 -280.651549) (xy 98.7806 -280.605275)
			(xy 98.811126 -280.563259) (xy 98.847849 -280.526536) (xy 98.889865 -280.49601) (xy 98.936139 -280.472432)
			(xy 98.985532 -280.456384) (xy 99.036827 -280.448259) (xy 99.088761 -280.448259) (xy 99.140056 -280.456384)
			(xy 99.189449 -280.472432) (xy 99.235723 -280.49601) (xy 99.277739 -280.526536) (xy 99.314462 -280.563259)
			(xy 99.344988 -280.605275) (xy 99.368566 -280.651549) (xy 99.384614 -280.700942) (xy 99.392739 -280.752237)
			(xy 99.393248 -280.778204) (xy 100.61194 -280.778204) (xy 100.612449 -280.752237) (xy 100.620574 -280.700942)
			(xy 100.636622 -280.651549) (xy 100.6602 -280.605275) (xy 100.690726 -280.563259) (xy 100.727449 -280.526536)
			(xy 100.769465 -280.49601) (xy 100.815739 -280.472432) (xy 100.865132 -280.456384) (xy 100.916427 -280.448259)
			(xy 100.968361 -280.448259) (xy 101.019656 -280.456384) (xy 101.069049 -280.472432) (xy 101.115323 -280.49601)
			(xy 101.157339 -280.526536) (xy 101.194062 -280.563259) (xy 101.224588 -280.605275) (xy 101.248166 -280.651549)
			(xy 101.264214 -280.700942) (xy 101.272339 -280.752237) (xy 101.272848 -280.778204) (xy 101.272848 -280.778458)
			(xy 101.272306 -280.804171) (xy 101.552249 -280.804171) (xy 101.552249 -280.752237) (xy 101.560374 -280.700942)
			(xy 101.576422 -280.651549) (xy 101.6 -280.605275) (xy 101.630526 -280.563259) (xy 101.667249 -280.526536)
			(xy 101.709265 -280.49601) (xy 101.755539 -280.472432) (xy 101.804932 -280.456384) (xy 101.856227 -280.448259)
			(xy 101.908161 -280.448259) (xy 101.959456 -280.456384) (xy 102.008849 -280.472432) (xy 102.055123 -280.49601)
			(xy 102.097139 -280.526536) (xy 102.133862 -280.563259) (xy 102.164388 -280.605275) (xy 102.187966 -280.651549)
			(xy 102.204014 -280.700942) (xy 102.212139 -280.752237) (xy 102.212648 -280.778204) (xy 102.212139 -280.804171)
			(xy 102.492303 -280.804171) (xy 102.492303 -280.752237) (xy 102.500428 -280.700942) (xy 102.516476 -280.651549)
			(xy 102.540054 -280.605275) (xy 102.57058 -280.563259) (xy 102.607303 -280.526536) (xy 102.649319 -280.49601)
			(xy 102.695593 -280.472432) (xy 102.744986 -280.456384) (xy 102.796281 -280.448259) (xy 102.848215 -280.448259)
			(xy 102.89951 -280.456384) (xy 102.948903 -280.472432) (xy 102.995177 -280.49601) (xy 103.037193 -280.526536)
			(xy 103.073916 -280.563259) (xy 103.104442 -280.605275) (xy 103.12802 -280.651549) (xy 103.144068 -280.700942)
			(xy 103.152193 -280.752237) (xy 103.152702 -280.778204) (xy 103.43134 -280.778204) (xy 103.431849 -280.752237)
			(xy 103.439974 -280.700942) (xy 103.456022 -280.651549) (xy 103.4796 -280.605275) (xy 103.510126 -280.563259)
			(xy 103.546849 -280.526536) (xy 103.588865 -280.49601) (xy 103.635139 -280.472432) (xy 103.684532 -280.456384)
			(xy 103.735827 -280.448259) (xy 103.787761 -280.448259) (xy 103.839056 -280.456384) (xy 103.888449 -280.472432)
			(xy 103.934723 -280.49601) (xy 103.976739 -280.526536) (xy 104.013462 -280.563259) (xy 104.043988 -280.605275)
			(xy 104.067566 -280.651549) (xy 104.083614 -280.700942) (xy 104.091739 -280.752237) (xy 104.092248 -280.778204)
			(xy 104.37114 -280.778204) (xy 104.371636 -280.752753) (xy 104.379413 -280.70245) (xy 104.394815 -280.653936)
			(xy 104.417477 -280.608358) (xy 104.446862 -280.566796) (xy 104.482275 -280.530234) (xy 104.522877 -280.499537)
			(xy 104.567708 -280.475432) (xy 104.615706 -280.458489) (xy 104.640634 -280.453338) (xy 104.663748 -280.44902)
			(xy 104.86771 -280.095706) (xy 104.859836 -280.073608) (xy 104.851225 -280.047256) (xy 104.841904 -279.992612)
			(xy 104.841294 -279.964896) (xy 104.841294 -279.964134) (xy 104.841803 -279.938167) (xy 104.849928 -279.886872)
			(xy 104.865976 -279.837479) (xy 104.889554 -279.791205) (xy 104.92008 -279.749189) (xy 104.956803 -279.712466)
			(xy 104.998819 -279.68194) (xy 105.045093 -279.658362) (xy 105.094486 -279.642314) (xy 105.145781 -279.634189)
			(xy 105.197715 -279.634189) (xy 105.24901 -279.642314) (xy 105.298403 -279.658362) (xy 105.344677 -279.68194)
			(xy 105.386693 -279.712466) (xy 105.423416 -279.749189) (xy 105.453942 -279.791205) (xy 105.47752 -279.837479)
			(xy 105.493568 -279.886872) (xy 105.501693 -279.938167) (xy 105.502202 -279.964134) (xy 105.50175 -279.989597)
			(xy 105.501672 -279.990101) (xy 105.781603 -279.990101) (xy 105.781603 -279.938167) (xy 105.789728 -279.886872)
			(xy 105.805776 -279.837479) (xy 105.829354 -279.791205) (xy 105.85988 -279.749189) (xy 105.896603 -279.712466)
			(xy 105.938619 -279.68194) (xy 105.984893 -279.658362) (xy 106.034286 -279.642314) (xy 106.085581 -279.634189)
			(xy 106.137515 -279.634189) (xy 106.18881 -279.642314) (xy 106.238203 -279.658362) (xy 106.284477 -279.68194)
			(xy 106.326493 -279.712466) (xy 106.363216 -279.749189) (xy 106.393742 -279.791205) (xy 106.41732 -279.837479)
			(xy 106.433368 -279.886872) (xy 106.441493 -279.938167) (xy 106.442002 -279.964134) (xy 106.441493 -279.990101)
			(xy 106.433368 -280.041396) (xy 106.41732 -280.090789) (xy 106.393742 -280.137063) (xy 106.363216 -280.179079)
			(xy 106.326493 -280.215802) (xy 106.284477 -280.246328) (xy 106.238203 -280.269906) (xy 106.18881 -280.285954)
			(xy 106.137515 -280.294079) (xy 106.085581 -280.294079) (xy 106.034286 -280.285954) (xy 105.984893 -280.269906)
			(xy 105.938619 -280.246328) (xy 105.896603 -280.215802) (xy 105.85988 -280.179079) (xy 105.829354 -280.137063)
			(xy 105.805776 -280.090789) (xy 105.789728 -280.041396) (xy 105.781603 -279.990101) (xy 105.501672 -279.990101)
			(xy 105.493946 -280.039922) (xy 105.478513 -280.088453) (xy 105.455817 -280.134042) (xy 105.426394 -280.175609)
			(xy 105.390942 -280.212169) (xy 105.350301 -280.242856) (xy 105.305432 -280.266945) (xy 105.257398 -280.283864)
			(xy 105.232454 -280.289) (xy 105.20934 -280.293318) (xy 105.005632 -280.646378) (xy 105.013252 -280.668476)
			(xy 105.021982 -280.695066) (xy 105.031435 -280.750224) (xy 105.032048 -280.778204) (xy 105.031539 -280.804171)
			(xy 105.023414 -280.855466) (xy 105.007366 -280.904859) (xy 104.983788 -280.951133) (xy 104.953262 -280.993149)
			(xy 104.916539 -281.029872) (xy 104.874523 -281.060398) (xy 104.828249 -281.083976) (xy 104.778856 -281.100024)
			(xy 104.727561 -281.108149) (xy 104.675627 -281.108149) (xy 104.624332 -281.100024) (xy 104.574939 -281.083976)
			(xy 104.528665 -281.060398) (xy 104.486649 -281.029872) (xy 104.449926 -280.993149) (xy 104.4194 -280.951133)
			(xy 104.395822 -280.904859) (xy 104.379774 -280.855466) (xy 104.371649 -280.804171) (xy 104.37114 -280.778204)
			(xy 104.092248 -280.778204) (xy 104.092248 -280.778458) (xy 104.091662 -280.806239) (xy 104.082348 -280.861015)
			(xy 104.073706 -280.887424) (xy 104.065832 -280.909522) (xy 104.269794 -281.262836) (xy 104.292908 -281.267154)
			(xy 104.317822 -281.272356) (xy 104.365805 -281.289316) (xy 104.410623 -281.313428) (xy 104.451216 -281.344123)
			(xy 104.486626 -281.380677) (xy 104.516015 -281.422225) (xy 104.538691 -281.467787) (xy 104.554116 -281.516285)
			(xy 104.561928 -281.566574) (xy 104.562402 -281.59202) (xy 104.561893 -281.617987) (xy 104.841803 -281.617987)
			(xy 104.841803 -281.566053) (xy 104.849928 -281.514758) (xy 104.865976 -281.465365) (xy 104.889554 -281.419091)
			(xy 104.92008 -281.377075) (xy 104.956803 -281.340352) (xy 104.998819 -281.309826) (xy 105.045093 -281.286248)
			(xy 105.094486 -281.2702) (xy 105.145781 -281.262075) (xy 105.197715 -281.262075) (xy 105.24901 -281.2702)
			(xy 105.298403 -281.286248) (xy 105.344677 -281.309826) (xy 105.386693 -281.340352) (xy 105.423416 -281.377075)
			(xy 105.453942 -281.419091) (xy 105.47752 -281.465365) (xy 105.493568 -281.514758) (xy 105.501693 -281.566053)
			(xy 105.502202 -281.59202) (xy 105.501693 -281.617987) (xy 105.493568 -281.669282) (xy 105.47752 -281.718675)
			(xy 105.453942 -281.764949) (xy 105.423416 -281.806965) (xy 105.386693 -281.843688) (xy 105.344677 -281.874214)
			(xy 105.298403 -281.897792) (xy 105.24901 -281.91384) (xy 105.197715 -281.921965) (xy 105.145781 -281.921965)
			(xy 105.094486 -281.91384) (xy 105.045093 -281.897792) (xy 104.998819 -281.874214) (xy 104.956803 -281.843688)
			(xy 104.92008 -281.806965) (xy 104.889554 -281.764949) (xy 104.865976 -281.718675) (xy 104.849928 -281.669282)
			(xy 104.841803 -281.617987) (xy 104.561893 -281.617987) (xy 104.553768 -281.669282) (xy 104.53772 -281.718675)
			(xy 104.514142 -281.764949) (xy 104.483616 -281.806965) (xy 104.446893 -281.843688) (xy 104.404877 -281.874214)
			(xy 104.358603 -281.897792) (xy 104.30921 -281.91384) (xy 104.257915 -281.921965) (xy 104.205981 -281.921965)
			(xy 104.154686 -281.91384) (xy 104.105293 -281.897792) (xy 104.059019 -281.874214) (xy 104.017003 -281.843688)
			(xy 103.98028 -281.806965) (xy 103.949754 -281.764949) (xy 103.926176 -281.718675) (xy 103.910128 -281.669282)
			(xy 103.902003 -281.617987) (xy 103.901494 -281.59202) (xy 103.902052 -281.564034) (xy 103.911499 -281.508867)
			(xy 103.92029 -281.482292) (xy 103.92791 -281.460194) (xy 103.724202 -281.107388) (xy 103.701342 -281.10307)
			(xy 103.676382 -281.097959) (xy 103.628318 -281.08106) (xy 103.583417 -281.056985) (xy 103.542742 -281.026304)
			(xy 103.507259 -280.989744) (xy 103.477808 -280.948171) (xy 103.455085 -280.90257) (xy 103.439631 -280.854022)
			(xy 103.431811 -280.803678) (xy 103.43134 -280.778204) (xy 103.152702 -280.778204) (xy 103.152193 -280.804171)
			(xy 103.144068 -280.855466) (xy 103.12802 -280.904859) (xy 103.104442 -280.951133) (xy 103.073916 -280.993149)
			(xy 103.037193 -281.029872) (xy 102.995177 -281.060398) (xy 102.948903 -281.083976) (xy 102.89951 -281.100024)
			(xy 102.848215 -281.108149) (xy 102.796281 -281.108149) (xy 102.744986 -281.100024) (xy 102.695593 -281.083976)
			(xy 102.649319 -281.060398) (xy 102.607303 -281.029872) (xy 102.57058 -280.993149) (xy 102.540054 -280.951133)
			(xy 102.516476 -280.904859) (xy 102.500428 -280.855466) (xy 102.492303 -280.804171) (xy 102.212139 -280.804171)
			(xy 102.204014 -280.855466) (xy 102.187966 -280.904859) (xy 102.164388 -280.951133) (xy 102.133862 -280.993149)
			(xy 102.097139 -281.029872) (xy 102.055123 -281.060398) (xy 102.008849 -281.083976) (xy 101.959456 -281.100024)
			(xy 101.908161 -281.108149) (xy 101.856227 -281.108149) (xy 101.804932 -281.100024) (xy 101.755539 -281.083976)
			(xy 101.709265 -281.060398) (xy 101.667249 -281.029872) (xy 101.630526 -280.993149) (xy 101.6 -280.951133)
			(xy 101.576422 -280.904859) (xy 101.560374 -280.855466) (xy 101.552249 -280.804171) (xy 101.272306 -280.804171)
			(xy 101.272262 -280.806239) (xy 101.262948 -280.861015) (xy 101.254306 -280.887424) (xy 101.246432 -280.909522)
			(xy 101.450394 -281.262836) (xy 101.473508 -281.267154) (xy 101.498422 -281.272356) (xy 101.546405 -281.289316)
			(xy 101.591223 -281.313428) (xy 101.631816 -281.344123) (xy 101.667226 -281.380677) (xy 101.696615 -281.422225)
			(xy 101.719291 -281.467787) (xy 101.734716 -281.516285) (xy 101.742528 -281.566574) (xy 101.743002 -281.59202)
			(xy 101.742493 -281.617987) (xy 101.734368 -281.669282) (xy 101.71832 -281.718675) (xy 101.694742 -281.764949)
			(xy 101.664216 -281.806965) (xy 101.627493 -281.843688) (xy 101.585477 -281.874214) (xy 101.539203 -281.897792)
			(xy 101.48981 -281.91384) (xy 101.438515 -281.921965) (xy 101.386581 -281.921965) (xy 101.335286 -281.91384)
			(xy 101.285893 -281.897792) (xy 101.239619 -281.874214) (xy 101.197603 -281.843688) (xy 101.16088 -281.806965)
			(xy 101.130354 -281.764949) (xy 101.106776 -281.718675) (xy 101.090728 -281.669282) (xy 101.082603 -281.617987)
			(xy 101.082094 -281.59202) (xy 101.082652 -281.564034) (xy 101.092099 -281.508867) (xy 101.10089 -281.482292)
			(xy 101.10851 -281.460194) (xy 100.904802 -281.107388) (xy 100.881942 -281.10307) (xy 100.856982 -281.097959)
			(xy 100.808918 -281.08106) (xy 100.764017 -281.056985) (xy 100.723342 -281.026304) (xy 100.687859 -280.989744)
			(xy 100.658408 -280.948171) (xy 100.635685 -280.90257) (xy 100.620231 -280.854022) (xy 100.612411 -280.803678)
			(xy 100.61194 -280.778204) (xy 99.393248 -280.778204) (xy 99.392739 -280.804171) (xy 99.384614 -280.855466)
			(xy 99.368566 -280.904859) (xy 99.344988 -280.951133) (xy 99.314462 -280.993149) (xy 99.277739 -281.029872)
			(xy 99.235723 -281.060398) (xy 99.189449 -281.083976) (xy 99.140056 -281.100024) (xy 99.088761 -281.108149)
			(xy 99.036827 -281.108149) (xy 98.985532 -281.100024) (xy 98.936139 -281.083976) (xy 98.889865 -281.060398)
			(xy 98.847849 -281.029872) (xy 98.811126 -280.993149) (xy 98.7806 -280.951133) (xy 98.757022 -280.904859)
			(xy 98.740974 -280.855466) (xy 98.732849 -280.804171) (xy 98.452889 -280.804171) (xy 98.44519 -280.853959)
			(xy 98.429787 -280.902475) (xy 98.407123 -280.948053) (xy 98.377736 -280.989615) (xy 98.342321 -281.026177)
			(xy 98.301716 -281.056874) (xy 98.256883 -281.080978) (xy 98.208883 -281.097919) (xy 98.183954 -281.10307)
			(xy 98.161094 -281.107388) (xy 97.957386 -281.460194) (xy 97.965006 -281.482292) (xy 97.973742 -281.508881)
			(xy 97.983191 -281.56404) (xy 97.983802 -281.59202) (xy 97.983293 -281.617987) (xy 98.263203 -281.617987)
			(xy 98.263203 -281.566053) (xy 98.271328 -281.514758) (xy 98.287376 -281.465365) (xy 98.310954 -281.419091)
			(xy 98.34148 -281.377075) (xy 98.378203 -281.340352) (xy 98.420219 -281.309826) (xy 98.466493 -281.286248)
			(xy 98.515886 -281.2702) (xy 98.567181 -281.262075) (xy 98.619115 -281.262075) (xy 98.67041 -281.2702)
			(xy 98.719803 -281.286248) (xy 98.766077 -281.309826) (xy 98.808093 -281.340352) (xy 98.844816 -281.377075)
			(xy 98.875342 -281.419091) (xy 98.89892 -281.465365) (xy 98.914968 -281.514758) (xy 98.923093 -281.566053)
			(xy 98.923602 -281.59202) (xy 98.923093 -281.61797) (xy 99.202949 -281.61797) (xy 99.202949 -281.56603)
			(xy 99.211075 -281.514729) (xy 99.227127 -281.465332) (xy 99.250709 -281.419054) (xy 99.281241 -281.377035)
			(xy 99.317971 -281.34031) (xy 99.359995 -281.309784) (xy 99.406276 -281.286208) (xy 99.455676 -281.270164)
			(xy 99.506978 -281.262045) (xy 99.532948 -281.261566) (xy 99.558568 -281.26208) (xy 99.609192 -281.270001)
			(xy 99.65799 -281.285631) (xy 99.703796 -281.308596) (xy 99.745515 -281.338347) (xy 99.782148 -281.374173)
			(xy 99.79787 -281.394408) (xy 100.207826 -281.394408) (xy 100.223551 -281.374171) (xy 100.260167 -281.338319)
			(xy 100.301879 -281.308549) (xy 100.347687 -281.285575) (xy 100.396492 -281.269949) (xy 100.447125 -281.262045)
			(xy 100.472748 -281.261566) (xy 100.498714 -281.262039) (xy 100.550007 -281.27017) (xy 100.599396 -281.286224)
			(xy 100.645666 -281.309805) (xy 100.687678 -281.340334) (xy 100.724397 -281.377059) (xy 100.75492 -281.419075)
			(xy 100.778495 -281.465349) (xy 100.794542 -281.51474) (xy 100.802665 -281.566034) (xy 100.802665 -281.617966)
			(xy 100.794542 -281.66926) (xy 100.778495 -281.718651) (xy 100.75492 -281.764925) (xy 100.724397 -281.806941)
			(xy 100.687678 -281.843666) (xy 100.645666 -281.874195) (xy 100.599396 -281.897776) (xy 100.550007 -281.91383)
			(xy 100.498714 -281.921961) (xy 100.472748 -281.922474) (xy 100.447127 -281.921987) (xy 100.3965 -281.914064)
			(xy 100.3477 -281.89843) (xy 100.301894 -281.87546) (xy 100.260177 -281.845703) (xy 100.223545 -281.80987)
			(xy 100.207826 -281.789632) (xy 99.79787 -281.789632) (xy 99.782158 -281.809879) (xy 99.745538 -281.845729)
			(xy 99.703823 -281.875497) (xy 99.658013 -281.898468) (xy 99.609206 -281.914093) (xy 99.558572 -281.921996)
			(xy 99.532948 -281.922474) (xy 99.506978 -281.921955) (xy 99.455676 -281.913836) (xy 99.406276 -281.897792)
			(xy 99.359995 -281.874216) (xy 99.317971 -281.84369) (xy 99.281241 -281.806965) (xy 99.250709 -281.764946)
			(xy 99.227127 -281.718668) (xy 99.211075 -281.669271) (xy 99.202949 -281.61797) (xy 98.923093 -281.61797)
			(xy 98.923093 -281.617987) (xy 98.914968 -281.669282) (xy 98.89892 -281.718675) (xy 98.875342 -281.764949)
			(xy 98.844816 -281.806965) (xy 98.808093 -281.843688) (xy 98.766077 -281.874214) (xy 98.719803 -281.897792)
			(xy 98.67041 -281.91384) (xy 98.619115 -281.921965) (xy 98.567181 -281.921965) (xy 98.515886 -281.91384)
			(xy 98.466493 -281.897792) (xy 98.420219 -281.874214) (xy 98.378203 -281.843688) (xy 98.34148 -281.806965)
			(xy 98.310954 -281.764949) (xy 98.287376 -281.718675) (xy 98.271328 -281.669282) (xy 98.263203 -281.617987)
			(xy 97.983293 -281.617987) (xy 97.975168 -281.669282) (xy 97.95912 -281.718675) (xy 97.935542 -281.764949)
			(xy 97.905016 -281.806965) (xy 97.868293 -281.843688) (xy 97.826277 -281.874214) (xy 97.780003 -281.897792)
			(xy 97.73061 -281.91384) (xy 97.679315 -281.921965) (xy 97.627381 -281.921965) (xy 97.576086 -281.91384)
			(xy 97.526693 -281.897792) (xy 97.480419 -281.874214) (xy 97.438403 -281.843688) (xy 97.40168 -281.806965)
			(xy 97.371154 -281.764949) (xy 97.347576 -281.718675) (xy 97.331528 -281.669282) (xy 97.323403 -281.617987)
			(xy 97.322894 -281.59202) (xy 97.044002 -281.59202) (xy 97.043493 -281.617987) (xy 97.035368 -281.669282)
			(xy 97.01932 -281.718675) (xy 96.995742 -281.764949) (xy 96.965216 -281.806965) (xy 96.928493 -281.843688)
			(xy 96.886477 -281.874214) (xy 96.840203 -281.897792) (xy 96.79081 -281.91384) (xy 96.739515 -281.921965)
			(xy 96.687581 -281.921965) (xy 96.636286 -281.91384) (xy 96.586893 -281.897792) (xy 96.540619 -281.874214)
			(xy 96.498603 -281.843688) (xy 96.46188 -281.806965) (xy 96.431354 -281.764949) (xy 96.407776 -281.718675)
			(xy 96.391728 -281.669282) (xy 96.383603 -281.617987) (xy 96.103622 -281.617987) (xy 96.095878 -281.667832)
			(xy 96.080425 -281.716375) (xy 96.057705 -281.761972) (xy 96.028257 -281.803542) (xy 95.992778 -281.840101)
			(xy 95.952109 -281.870782) (xy 95.907214 -281.894859) (xy 95.859155 -281.91176) (xy 95.8342 -281.916886)
			(xy 95.81134 -281.921204) (xy 95.607632 -282.27401) (xy 95.615252 -282.296108) (xy 95.62399 -282.322696)
			(xy 95.633438 -282.377855) (xy 95.634048 -282.405836) (xy 95.91294 -282.405836) (xy 95.913449 -282.379869)
			(xy 95.921574 -282.328574) (xy 95.937622 -282.279181) (xy 95.9612 -282.232907) (xy 95.991726 -282.190891)
			(xy 96.028449 -282.154168) (xy 96.070465 -282.123642) (xy 96.116739 -282.100064) (xy 96.166132 -282.084016)
			(xy 96.217427 -282.075891) (xy 96.269361 -282.075891) (xy 96.320656 -282.084016) (xy 96.370049 -282.100064)
			(xy 96.416323 -282.123642) (xy 96.458339 -282.154168) (xy 96.495062 -282.190891) (xy 96.525588 -282.232907)
			(xy 96.549166 -282.279181) (xy 96.565214 -282.328574) (xy 96.573339 -282.379869) (xy 96.573848 -282.405836)
			(xy 96.573848 -282.406598) (xy 96.573316 -282.431764) (xy 96.853291 -282.431764) (xy 96.853291 -282.379836)
			(xy 96.861414 -282.328547) (xy 96.877461 -282.27916) (xy 96.901036 -282.232892) (xy 96.931558 -282.190881)
			(xy 96.968276 -282.154162) (xy 97.010287 -282.123639) (xy 97.056555 -282.100063) (xy 97.105941 -282.084016)
			(xy 97.15723 -282.075892) (xy 97.183194 -282.075382) (xy 97.208815 -282.075856) (xy 97.259442 -282.083785)
			(xy 97.308241 -282.099422) (xy 97.354047 -282.122394) (xy 97.395764 -282.152153) (xy 97.432396 -282.187986)
			(xy 97.448116 -282.208224) (xy 97.858072 -282.208224) (xy 97.873747 -282.187948) (xy 97.910376 -282.152101)
			(xy 97.952099 -282.122338) (xy 97.997917 -282.099372) (xy 98.04673 -282.083754) (xy 98.097368 -282.075857)
			(xy 98.122994 -282.075382) (xy 98.148966 -282.075792) (xy 98.200272 -282.083918) (xy 98.249675 -282.099969)
			(xy 98.295958 -282.123551) (xy 98.337983 -282.154083) (xy 98.374714 -282.190813) (xy 98.405246 -282.232837)
			(xy 98.428829 -282.27912) (xy 98.444881 -282.328522) (xy 98.453007 -282.379828) (xy 98.453007 -282.431772)
			(xy 98.453002 -282.431803) (xy 98.732849 -282.431803) (xy 98.732849 -282.379869) (xy 98.740974 -282.328574)
			(xy 98.757022 -282.279181) (xy 98.7806 -282.232907) (xy 98.811126 -282.190891) (xy 98.847849 -282.154168)
			(xy 98.889865 -282.123642) (xy 98.936139 -282.100064) (xy 98.985532 -282.084016) (xy 99.036827 -282.075891)
			(xy 99.088761 -282.075891) (xy 99.140056 -282.084016) (xy 99.189449 -282.100064) (xy 99.235723 -282.123642)
			(xy 99.277739 -282.154168) (xy 99.314462 -282.190891) (xy 99.344988 -282.232907) (xy 99.368566 -282.279181)
			(xy 99.384614 -282.328574) (xy 99.392739 -282.379869) (xy 99.393248 -282.405836) (xy 99.392739 -282.431803)
			(xy 99.384614 -282.483098) (xy 99.368566 -282.532491) (xy 99.344988 -282.578765) (xy 99.314462 -282.620781)
			(xy 99.277739 -282.657504) (xy 99.235723 -282.68803) (xy 99.189449 -282.711608) (xy 99.140056 -282.727656)
			(xy 99.088761 -282.735781) (xy 99.036827 -282.735781) (xy 98.985532 -282.727656) (xy 98.936139 -282.711608)
			(xy 98.889865 -282.68803) (xy 98.847849 -282.657504) (xy 98.811126 -282.620781) (xy 98.7806 -282.578765)
			(xy 98.757022 -282.532491) (xy 98.740974 -282.483098) (xy 98.732849 -282.431803) (xy 98.453002 -282.431803)
			(xy 98.444881 -282.483078) (xy 98.428829 -282.53248) (xy 98.405246 -282.578763) (xy 98.374714 -282.620787)
			(xy 98.337983 -282.657517) (xy 98.295958 -282.688049) (xy 98.249675 -282.711631) (xy 98.200272 -282.727682)
			(xy 98.148966 -282.735808) (xy 98.122994 -282.73629) (xy 98.097374 -282.735763) (xy 98.04675 -282.727847)
			(xy 97.997951 -282.712221) (xy 97.952145 -282.689259) (xy 97.910426 -282.659509) (xy 97.873793 -282.623683)
			(xy 97.858072 -282.603448) (xy 97.448116 -282.603448) (xy 97.432382 -282.623676) (xy 97.395766 -282.659527)
			(xy 97.354055 -282.689296) (xy 97.308249 -282.712271) (xy 97.259447 -282.7279) (xy 97.208816 -282.735808)
			(xy 97.183194 -282.73629) (xy 97.15723 -282.735708) (xy 97.105941 -282.727584) (xy 97.056555 -282.711537)
			(xy 97.010287 -282.687961) (xy 96.968276 -282.657438) (xy 96.931558 -282.620719) (xy 96.901036 -282.578708)
			(xy 96.877461 -282.53244) (xy 96.861414 -282.483053) (xy 96.853291 -282.431764) (xy 96.573316 -282.431764)
			(xy 96.573262 -282.434316) (xy 96.563937 -282.488963) (xy 96.555306 -282.51531) (xy 96.547432 -282.537408)
			(xy 96.751394 -282.890722) (xy 96.774508 -282.89504) (xy 96.799419 -282.900255) (xy 96.847401 -282.917214)
			(xy 96.892218 -282.941325) (xy 96.932811 -282.972019) (xy 96.96822 -283.008571) (xy 96.99761 -283.050117)
			(xy 97.020287 -283.095677) (xy 97.035714 -283.144173) (xy 97.043527 -283.194461) (xy 97.044002 -283.219906)
			(xy 97.043493 -283.245873) (xy 97.323149 -283.245873) (xy 97.323149 -283.193939) (xy 97.331274 -283.142644)
			(xy 97.347322 -283.093251) (xy 97.3709 -283.046977) (xy 97.401426 -283.004961) (xy 97.438149 -282.968238)
			(xy 97.480165 -282.937712) (xy 97.526439 -282.914134) (xy 97.575832 -282.898086) (xy 97.627127 -282.889961)
			(xy 97.679061 -282.889961) (xy 97.730356 -282.898086) (xy 97.779749 -282.914134) (xy 97.826023 -282.937712)
			(xy 97.868039 -282.968238) (xy 97.904762 -283.004961) (xy 97.935288 -283.046977) (xy 97.958866 -283.093251)
			(xy 97.974914 -283.142644) (xy 97.983039 -283.193939) (xy 97.983548 -283.219906) (xy 97.983039 -283.245873)
			(xy 98.262949 -283.245873) (xy 98.262949 -283.193939) (xy 98.271074 -283.142644) (xy 98.287122 -283.093251)
			(xy 98.3107 -283.046977) (xy 98.341226 -283.004961) (xy 98.377949 -282.968238) (xy 98.419965 -282.937712)
			(xy 98.466239 -282.914134) (xy 98.515632 -282.898086) (xy 98.566927 -282.889961) (xy 98.618861 -282.889961)
			(xy 98.670156 -282.898086) (xy 98.719549 -282.914134) (xy 98.765823 -282.937712) (xy 98.807839 -282.968238)
			(xy 98.844562 -283.004961) (xy 98.875088 -283.046977) (xy 98.898666 -283.093251) (xy 98.914714 -283.142644)
			(xy 98.922839 -283.193939) (xy 98.923348 -283.219906) (xy 99.202494 -283.219906) (xy 99.203029 -283.194457)
			(xy 99.210805 -283.144158) (xy 99.226204 -283.095647) (xy 99.248861 -283.050071) (xy 99.278241 -283.008511)
			(xy 99.313649 -282.971948) (xy 99.354245 -282.94125) (xy 99.39907 -282.917142) (xy 99.447063 -282.900194)
			(xy 99.471988 -282.89504) (xy 99.495102 -282.890722) (xy 99.69881 -282.537916) (xy 99.690936 -282.515818)
			(xy 99.682204 -282.489228) (xy 99.672752 -282.43407) (xy 99.67214 -282.40609) (xy 99.67214 -282.405836)
			(xy 99.672649 -282.379869) (xy 99.680774 -282.328574) (xy 99.696822 -282.279181) (xy 99.7204 -282.232907)
			(xy 99.750926 -282.190891) (xy 99.787649 -282.154168) (xy 99.829665 -282.123642) (xy 99.875939 -282.100064)
			(xy 99.925332 -282.084016) (xy 99.976627 -282.075891) (xy 100.028561 -282.075891) (xy 100.079856 -282.084016)
			(xy 100.129249 -282.100064) (xy 100.175523 -282.123642) (xy 100.217539 -282.154168) (xy 100.254262 -282.190891)
			(xy 100.284788 -282.232907) (xy 100.308366 -282.279181) (xy 100.324414 -282.328574) (xy 100.332539 -282.379869)
			(xy 100.333048 -282.405836) (xy 100.332513 -282.431267) (xy 100.33243 -282.431803) (xy 100.612449 -282.431803)
			(xy 100.612449 -282.379869) (xy 100.620574 -282.328574) (xy 100.636622 -282.279181) (xy 100.6602 -282.232907)
			(xy 100.690726 -282.190891) (xy 100.727449 -282.154168) (xy 100.769465 -282.123642) (xy 100.815739 -282.100064)
			(xy 100.865132 -282.084016) (xy 100.916427 -282.075891) (xy 100.968361 -282.075891) (xy 101.019656 -282.084016)
			(xy 101.069049 -282.100064) (xy 101.115323 -282.123642) (xy 101.157339 -282.154168) (xy 101.194062 -282.190891)
			(xy 101.224588 -282.232907) (xy 101.248166 -282.279181) (xy 101.264214 -282.328574) (xy 101.272339 -282.379869)
			(xy 101.272848 -282.405836) (xy 101.55174 -282.405836) (xy 101.552174 -282.380383) (xy 101.559961 -282.330078)
			(xy 101.575372 -282.281562) (xy 101.598043 -282.235984) (xy 101.627436 -282.194422) (xy 101.662856 -282.157861)
			(xy 101.703464 -282.127166) (xy 101.748301 -282.103062) (xy 101.796304 -282.08612) (xy 101.821234 -282.08097)
			(xy 101.844348 -282.076652) (xy 102.04831 -281.723338) (xy 102.040436 -281.70124) (xy 102.031818 -281.674825)
			(xy 102.022491 -281.620053) (xy 102.021894 -281.592274) (xy 102.021894 -281.59202) (xy 102.022403 -281.566053)
			(xy 102.030528 -281.514758) (xy 102.046576 -281.465365) (xy 102.070154 -281.419091) (xy 102.10068 -281.377075)
			(xy 102.137403 -281.340352) (xy 102.179419 -281.309826) (xy 102.225693 -281.286248) (xy 102.275086 -281.2702)
			(xy 102.326381 -281.262075) (xy 102.378315 -281.262075) (xy 102.42961 -281.2702) (xy 102.479003 -281.286248)
			(xy 102.525277 -281.309826) (xy 102.567293 -281.340352) (xy 102.604016 -281.377075) (xy 102.634542 -281.419091)
			(xy 102.65812 -281.465365) (xy 102.674168 -281.514758) (xy 102.682293 -281.566053) (xy 102.682802 -281.59202)
			(xy 102.682299 -281.617492) (xy 102.682222 -281.617987) (xy 102.961949 -281.617987) (xy 102.961949 -281.566053)
			(xy 102.970074 -281.514758) (xy 102.986122 -281.465365) (xy 103.0097 -281.419091) (xy 103.040226 -281.377075)
			(xy 103.076949 -281.340352) (xy 103.118965 -281.309826) (xy 103.165239 -281.286248) (xy 103.214632 -281.2702)
			(xy 103.265927 -281.262075) (xy 103.317861 -281.262075) (xy 103.369156 -281.2702) (xy 103.418549 -281.286248)
			(xy 103.464823 -281.309826) (xy 103.506839 -281.340352) (xy 103.543562 -281.377075) (xy 103.574088 -281.419091)
			(xy 103.597666 -281.465365) (xy 103.613714 -281.514758) (xy 103.621839 -281.566053) (xy 103.622348 -281.59202)
			(xy 103.621839 -281.617987) (xy 103.613714 -281.669282) (xy 103.597666 -281.718675) (xy 103.574088 -281.764949)
			(xy 103.543562 -281.806965) (xy 103.506839 -281.843688) (xy 103.464823 -281.874214) (xy 103.418549 -281.897792)
			(xy 103.369156 -281.91384) (xy 103.317861 -281.921965) (xy 103.265927 -281.921965) (xy 103.214632 -281.91384)
			(xy 103.165239 -281.897792) (xy 103.118965 -281.874214) (xy 103.076949 -281.843688) (xy 103.040226 -281.806965)
			(xy 103.0097 -281.764949) (xy 102.986122 -281.718675) (xy 102.970074 -281.669282) (xy 102.961949 -281.617987)
			(xy 102.682222 -281.617987) (xy 102.674478 -281.667832) (xy 102.659025 -281.716375) (xy 102.636305 -281.761972)
			(xy 102.606857 -281.803542) (xy 102.571378 -281.840101) (xy 102.530709 -281.870782) (xy 102.485814 -281.894859)
			(xy 102.437755 -281.91176) (xy 102.4128 -281.916886) (xy 102.38994 -281.921204) (xy 102.186232 -282.27401)
			(xy 102.193852 -282.296108) (xy 102.20259 -282.322696) (xy 102.212038 -282.377855) (xy 102.212648 -282.405836)
			(xy 102.212139 -282.431803) (xy 102.492303 -282.431803) (xy 102.492303 -282.379869) (xy 102.500428 -282.328574)
			(xy 102.516476 -282.279181) (xy 102.540054 -282.232907) (xy 102.57058 -282.190891) (xy 102.607303 -282.154168)
			(xy 102.649319 -282.123642) (xy 102.695593 -282.100064) (xy 102.744986 -282.084016) (xy 102.796281 -282.075891)
			(xy 102.848215 -282.075891) (xy 102.89951 -282.084016) (xy 102.948903 -282.100064) (xy 102.995177 -282.123642)
			(xy 103.037193 -282.154168) (xy 103.073916 -282.190891) (xy 103.104442 -282.232907) (xy 103.12802 -282.279181)
			(xy 103.144068 -282.328574) (xy 103.152193 -282.379869) (xy 103.152702 -282.405836) (xy 103.152193 -282.431803)
			(xy 103.144068 -282.483098) (xy 103.12802 -282.532491) (xy 103.104442 -282.578765) (xy 103.073916 -282.620781)
			(xy 103.037193 -282.657504) (xy 102.995177 -282.68803) (xy 102.948903 -282.711608) (xy 102.89951 -282.727656)
			(xy 102.848215 -282.735781) (xy 102.796281 -282.735781) (xy 102.744986 -282.727656) (xy 102.695593 -282.711608)
			(xy 102.649319 -282.68803) (xy 102.607303 -282.657504) (xy 102.57058 -282.620781) (xy 102.540054 -282.578765)
			(xy 102.516476 -282.532491) (xy 102.500428 -282.483098) (xy 102.492303 -282.431803) (xy 102.212139 -282.431803)
			(xy 102.204014 -282.483098) (xy 102.187966 -282.532491) (xy 102.164388 -282.578765) (xy 102.133862 -282.620781)
			(xy 102.097139 -282.657504) (xy 102.055123 -282.68803) (xy 102.008849 -282.711608) (xy 101.959456 -282.727656)
			(xy 101.908161 -282.735781) (xy 101.856227 -282.735781) (xy 101.804932 -282.727656) (xy 101.755539 -282.711608)
			(xy 101.709265 -282.68803) (xy 101.667249 -282.657504) (xy 101.630526 -282.620781) (xy 101.6 -282.578765)
			(xy 101.576422 -282.532491) (xy 101.560374 -282.483098) (xy 101.552249 -282.431803) (xy 101.55174 -282.405836)
			(xy 101.272848 -282.405836) (xy 101.272339 -282.431803) (xy 101.264214 -282.483098) (xy 101.248166 -282.532491)
			(xy 101.224588 -282.578765) (xy 101.194062 -282.620781) (xy 101.157339 -282.657504) (xy 101.115323 -282.68803)
			(xy 101.069049 -282.711608) (xy 101.019656 -282.727656) (xy 100.968361 -282.735781) (xy 100.916427 -282.735781)
			(xy 100.865132 -282.727656) (xy 100.815739 -282.711608) (xy 100.769465 -282.68803) (xy 100.727449 -282.657504)
			(xy 100.690726 -282.620781) (xy 100.6602 -282.578765) (xy 100.636622 -282.532491) (xy 100.620574 -282.483098)
			(xy 100.612449 -282.431803) (xy 100.33243 -282.431803) (xy 100.324707 -282.481526) (xy 100.3093 -282.529997)
			(xy 100.286655 -282.57554) (xy 100.257306 -282.617079) (xy 100.221945 -282.653637) (xy 100.181404 -282.684351)
			(xy 100.13664 -282.708498) (xy 100.088707 -282.725508) (xy 100.063808 -282.730702) (xy 100.040694 -282.73502)
			(xy 99.836986 -283.08808) (xy 99.844606 -283.110178) (xy 99.853339 -283.136768) (xy 99.862789 -283.191926)
			(xy 99.863402 -283.219906) (xy 99.862893 -283.245873) (xy 100.142549 -283.245873) (xy 100.142549 -283.193939)
			(xy 100.150674 -283.142644) (xy 100.166722 -283.093251) (xy 100.1903 -283.046977) (xy 100.220826 -283.004961)
			(xy 100.257549 -282.968238) (xy 100.299565 -282.937712) (xy 100.345839 -282.914134) (xy 100.395232 -282.898086)
			(xy 100.446527 -282.889961) (xy 100.498461 -282.889961) (xy 100.549756 -282.898086) (xy 100.599149 -282.914134)
			(xy 100.645423 -282.937712) (xy 100.687439 -282.968238) (xy 100.724162 -283.004961) (xy 100.754688 -283.046977)
			(xy 100.778266 -283.093251) (xy 100.794314 -283.142644) (xy 100.802439 -283.193939) (xy 100.802948 -283.219906)
			(xy 100.802439 -283.245871) (xy 101.082535 -283.245871) (xy 101.082535 -283.193929) (xy 101.090661 -283.142626)
			(xy 101.106714 -283.093226) (xy 101.130297 -283.046946) (xy 101.160831 -283.004926) (xy 101.197562 -282.968199)
			(xy 101.239587 -282.937672) (xy 101.285871 -282.914095) (xy 101.335273 -282.89805) (xy 101.386577 -282.889931)
			(xy 101.412548 -282.889452) (xy 101.438184 -282.889951) (xy 101.48884 -282.89787) (xy 101.537662 -282.913524)
			(xy 101.583478 -282.936539) (xy 101.625184 -282.966359) (xy 101.661779 -283.002269) (xy 101.67747 -283.022548)
			(xy 102.087426 -283.022548) (xy 102.103137 -283.002286) (xy 102.13973 -282.966377) (xy 102.181433 -282.936554)
			(xy 102.227244 -282.913535) (xy 102.276062 -282.897871) (xy 102.326714 -282.88994) (xy 102.352348 -282.889452)
			(xy 102.378313 -282.889953) (xy 102.429603 -282.898083) (xy 102.47899 -282.914136) (xy 102.525259 -282.937717)
			(xy 102.567269 -282.968245) (xy 102.603986 -283.004968) (xy 102.634508 -283.046982) (xy 102.658082 -283.093254)
			(xy 102.674128 -283.142643) (xy 102.682251 -283.193935) (xy 102.682251 -283.245865) (xy 102.68225 -283.245873)
			(xy 102.961949 -283.245873) (xy 102.961949 -283.193939) (xy 102.970074 -283.142644) (xy 102.986122 -283.093251)
			(xy 103.0097 -283.046977) (xy 103.040226 -283.004961) (xy 103.076949 -282.968238) (xy 103.118965 -282.937712)
			(xy 103.165239 -282.914134) (xy 103.214632 -282.898086) (xy 103.265927 -282.889961) (xy 103.317861 -282.889961)
			(xy 103.369156 -282.898086) (xy 103.418549 -282.914134) (xy 103.464823 -282.937712) (xy 103.506839 -282.968238)
			(xy 103.543562 -283.004961) (xy 103.574088 -283.046977) (xy 103.597666 -283.093251) (xy 103.613714 -283.142644)
			(xy 103.621839 -283.193939) (xy 103.622348 -283.219906) (xy 103.621839 -283.245873) (xy 103.613714 -283.297168)
			(xy 103.597666 -283.346561) (xy 103.574088 -283.392835) (xy 103.543562 -283.434851) (xy 103.506839 -283.471574)
			(xy 103.464823 -283.5021) (xy 103.418549 -283.525678) (xy 103.369156 -283.541726) (xy 103.317861 -283.549851)
			(xy 103.265927 -283.549851) (xy 103.214632 -283.541726) (xy 103.165239 -283.525678) (xy 103.118965 -283.5021)
			(xy 103.076949 -283.471574) (xy 103.040226 -283.434851) (xy 103.0097 -283.392835) (xy 102.986122 -283.346561)
			(xy 102.970074 -283.297168) (xy 102.961949 -283.245873) (xy 102.68225 -283.245873) (xy 102.674128 -283.297157)
			(xy 102.658082 -283.346546) (xy 102.634508 -283.392818) (xy 102.603986 -283.434832) (xy 102.567269 -283.471555)
			(xy 102.525259 -283.502083) (xy 102.47899 -283.525664) (xy 102.429603 -283.541717) (xy 102.378313 -283.549847)
			(xy 102.352348 -283.55036) (xy 102.326713 -283.549859) (xy 102.276057 -283.54194) (xy 102.227234 -283.526286)
			(xy 102.181419 -283.503272) (xy 102.139712 -283.473451) (xy 102.103117 -283.437542) (xy 102.087426 -283.417264)
			(xy 101.67747 -283.417264) (xy 101.661765 -283.437531) (xy 101.62517 -283.473439) (xy 101.583466 -283.50326)
			(xy 101.537654 -283.526279) (xy 101.488835 -283.541942) (xy 101.438183 -283.549872) (xy 101.412548 -283.55036)
			(xy 101.386577 -283.549869) (xy 101.335273 -283.54175) (xy 101.285871 -283.525705) (xy 101.239587 -283.502128)
			(xy 101.197562 -283.471601) (xy 101.160831 -283.434874) (xy 101.130297 -283.392854) (xy 101.106714 -283.346574)
			(xy 101.090661 -283.297174) (xy 101.082535 -283.245871) (xy 100.802439 -283.245871) (xy 100.802439 -283.245873)
			(xy 100.794314 -283.297168) (xy 100.778266 -283.346561) (xy 100.754688 -283.392835) (xy 100.724162 -283.434851)
			(xy 100.687439 -283.471574) (xy 100.645423 -283.5021) (xy 100.599149 -283.525678) (xy 100.549756 -283.541726)
			(xy 100.498461 -283.549851) (xy 100.446527 -283.549851) (xy 100.395232 -283.541726) (xy 100.345839 -283.525678)
			(xy 100.299565 -283.5021) (xy 100.257549 -283.471574) (xy 100.220826 -283.434851) (xy 100.1903 -283.392835)
			(xy 100.166722 -283.346561) (xy 100.150674 -283.297168) (xy 100.142549 -283.245873) (xy 99.862893 -283.245873)
			(xy 99.854768 -283.297168) (xy 99.83872 -283.346561) (xy 99.815142 -283.392835) (xy 99.784616 -283.434851)
			(xy 99.747893 -283.471574) (xy 99.705877 -283.5021) (xy 99.659603 -283.525678) (xy 99.61021 -283.541726)
			(xy 99.558915 -283.549851) (xy 99.506981 -283.549851) (xy 99.455686 -283.541726) (xy 99.406293 -283.525678)
			(xy 99.360019 -283.5021) (xy 99.318003 -283.471574) (xy 99.28128 -283.434851) (xy 99.250754 -283.392835)
			(xy 99.227176 -283.346561) (xy 99.211128 -283.297168) (xy 99.203003 -283.245873) (xy 99.202494 -283.219906)
			(xy 98.923348 -283.219906) (xy 98.922839 -283.245873) (xy 98.914714 -283.297168) (xy 98.898666 -283.346561)
			(xy 98.875088 -283.392835) (xy 98.844562 -283.434851) (xy 98.807839 -283.471574) (xy 98.765823 -283.5021)
			(xy 98.719549 -283.525678) (xy 98.670156 -283.541726) (xy 98.618861 -283.549851) (xy 98.566927 -283.549851)
			(xy 98.515632 -283.541726) (xy 98.466239 -283.525678) (xy 98.419965 -283.5021) (xy 98.377949 -283.471574)
			(xy 98.341226 -283.434851) (xy 98.3107 -283.392835) (xy 98.287122 -283.346561) (xy 98.271074 -283.297168)
			(xy 98.262949 -283.245873) (xy 97.983039 -283.245873) (xy 97.974914 -283.297168) (xy 97.958866 -283.346561)
			(xy 97.935288 -283.392835) (xy 97.904762 -283.434851) (xy 97.868039 -283.471574) (xy 97.826023 -283.5021)
			(xy 97.779749 -283.525678) (xy 97.730356 -283.541726) (xy 97.679061 -283.549851) (xy 97.627127 -283.549851)
			(xy 97.575832 -283.541726) (xy 97.526439 -283.525678) (xy 97.480165 -283.5021) (xy 97.438149 -283.471574)
			(xy 97.401426 -283.434851) (xy 97.3709 -283.392835) (xy 97.347322 -283.346561) (xy 97.331274 -283.297168)
			(xy 97.323149 -283.245873) (xy 97.043493 -283.245873) (xy 97.035368 -283.297168) (xy 97.01932 -283.346561)
			(xy 96.995742 -283.392835) (xy 96.965216 -283.434851) (xy 96.928493 -283.471574) (xy 96.886477 -283.5021)
			(xy 96.840203 -283.525678) (xy 96.79081 -283.541726) (xy 96.739515 -283.549851) (xy 96.687581 -283.549851)
			(xy 96.636286 -283.541726) (xy 96.586893 -283.525678) (xy 96.540619 -283.5021) (xy 96.498603 -283.471574)
			(xy 96.46188 -283.434851) (xy 96.431354 -283.392835) (xy 96.407776 -283.346561) (xy 96.391728 -283.297168)
			(xy 96.383603 -283.245873) (xy 96.383094 -283.219906) (xy 96.383649 -283.19192) (xy 96.393097 -283.136752)
			(xy 96.40189 -283.110178) (xy 96.40951 -283.08808) (xy 96.205802 -282.73502) (xy 96.182688 -282.730702)
			(xy 96.157745 -282.725572) (xy 96.109721 -282.708639) (xy 96.064862 -282.684541) (xy 96.024229 -282.653849)
			(xy 95.988783 -282.617288) (xy 95.959363 -282.575725) (xy 95.936666 -282.530141) (xy 95.921227 -282.481616)
			(xy 95.913412 -282.431297) (xy 95.91294 -282.405836) (xy 95.634048 -282.405836) (xy 95.633539 -282.431803)
			(xy 95.625414 -282.483098) (xy 95.609366 -282.532491) (xy 95.585788 -282.578765) (xy 95.555262 -282.620781)
			(xy 95.518539 -282.657504) (xy 95.476523 -282.68803) (xy 95.430249 -282.711608) (xy 95.380856 -282.727656)
			(xy 95.329561 -282.735781) (xy 95.277627 -282.735781) (xy 95.226332 -282.727656) (xy 95.176939 -282.711608)
			(xy 95.130665 -282.68803) (xy 95.088649 -282.657504) (xy 95.051926 -282.620781) (xy 95.0214 -282.578765)
			(xy 94.997822 -282.532491) (xy 94.981774 -282.483098) (xy 94.973649 -282.431803) (xy 94.97314 -282.405836)
			(xy 94.694502 -282.405836) (xy 94.693993 -282.431803) (xy 94.685868 -282.483098) (xy 94.66982 -282.532491)
			(xy 94.646242 -282.578765) (xy 94.615716 -282.620781) (xy 94.578993 -282.657504) (xy 94.536977 -282.68803)
			(xy 94.490703 -282.711608) (xy 94.44131 -282.727656) (xy 94.390015 -282.735781) (xy 94.338081 -282.735781)
			(xy 94.286786 -282.727656) (xy 94.237393 -282.711608) (xy 94.191119 -282.68803) (xy 94.149103 -282.657504)
			(xy 94.11238 -282.620781) (xy 94.081854 -282.578765) (xy 94.058276 -282.532491) (xy 94.042228 -282.483098)
			(xy 94.034103 -282.431803) (xy 93.754193 -282.431803) (xy 93.746068 -282.483098) (xy 93.73002 -282.532491)
			(xy 93.706442 -282.578765) (xy 93.675916 -282.620781) (xy 93.639193 -282.657504) (xy 93.597177 -282.68803)
			(xy 93.550903 -282.711608) (xy 93.50151 -282.727656) (xy 93.450215 -282.735781) (xy 93.398281 -282.735781)
			(xy 93.346986 -282.727656) (xy 93.297593 -282.711608) (xy 93.251319 -282.68803) (xy 93.209303 -282.657504)
			(xy 93.17258 -282.620781) (xy 93.142054 -282.578765) (xy 93.118476 -282.532491) (xy 93.102428 -282.483098)
			(xy 93.094303 -282.431803) (xy 93.093794 -282.405836) (xy 92.814902 -282.405836) (xy 92.814393 -282.431803)
			(xy 92.806268 -282.483098) (xy 92.79022 -282.532491) (xy 92.766642 -282.578765) (xy 92.736116 -282.620781)
			(xy 92.699393 -282.657504) (xy 92.657377 -282.68803) (xy 92.611103 -282.711608) (xy 92.56171 -282.727656)
			(xy 92.510415 -282.735781) (xy 92.458481 -282.735781) (xy 92.407186 -282.727656) (xy 92.357793 -282.711608)
			(xy 92.311519 -282.68803) (xy 92.269503 -282.657504) (xy 92.23278 -282.620781) (xy 92.202254 -282.578765)
			(xy 92.178676 -282.532491) (xy 92.162628 -282.483098) (xy 92.154503 -282.431803) (xy 91.874574 -282.431803)
			(xy 91.866848 -282.481624) (xy 91.851414 -282.530155) (xy 91.828718 -282.575744) (xy 91.799295 -282.617311)
			(xy 91.763843 -282.653871) (xy 91.723201 -282.684559) (xy 91.678332 -282.708647) (xy 91.630298 -282.725566)
			(xy 91.605354 -282.730702) (xy 91.58224 -282.73502) (xy 91.378532 -283.08808) (xy 91.386152 -283.110178)
			(xy 91.394883 -283.136768) (xy 91.404335 -283.191926) (xy 91.404948 -283.219906) (xy 91.404439 -283.245873)
			(xy 91.684349 -283.245873) (xy 91.684349 -283.193939) (xy 91.692474 -283.142644) (xy 91.708522 -283.093251)
			(xy 91.7321 -283.046977) (xy 91.762626 -283.004961) (xy 91.799349 -282.968238) (xy 91.841365 -282.937712)
			(xy 91.887639 -282.914134) (xy 91.937032 -282.898086) (xy 91.988327 -282.889961) (xy 92.040261 -282.889961)
			(xy 92.091556 -282.898086) (xy 92.140949 -282.914134) (xy 92.187223 -282.937712) (xy 92.229239 -282.968238)
			(xy 92.265962 -283.004961) (xy 92.296488 -283.046977) (xy 92.320066 -283.093251) (xy 92.336114 -283.142644)
			(xy 92.344239 -283.193939) (xy 92.344748 -283.219906) (xy 92.344239 -283.245866) (xy 92.624161 -283.245866)
			(xy 92.624161 -283.193934) (xy 92.632285 -283.14264) (xy 92.648333 -283.093249) (xy 92.67191 -283.046976)
			(xy 92.702435 -283.004961) (xy 92.739157 -282.968239) (xy 92.781171 -282.937713) (xy 92.827443 -282.914135)
			(xy 92.876834 -282.898087) (xy 92.928128 -282.889962) (xy 92.954094 -282.889452) (xy 92.979731 -282.889918)
			(xy 93.030388 -282.897843) (xy 93.079212 -282.913505) (xy 93.125027 -282.936525) (xy 93.166733 -282.966352)
			(xy 93.203326 -283.002267) (xy 93.219016 -283.022548) (xy 93.628972 -283.022548) (xy 93.644656 -283.002264)
			(xy 93.681255 -282.966356) (xy 93.722963 -282.936536) (xy 93.768779 -282.91352) (xy 93.817602 -282.897862)
			(xy 93.868258 -282.889937) (xy 93.893894 -282.889452) (xy 93.919864 -282.889922) (xy 93.971165 -282.898047)
			(xy 94.020563 -282.914096) (xy 94.066842 -282.937676) (xy 94.108863 -282.968205) (xy 94.145591 -283.004932)
			(xy 94.176121 -283.046952) (xy 94.199701 -283.093231) (xy 94.215752 -283.142629) (xy 94.223877 -283.19393)
			(xy 94.223877 -283.24587) (xy 94.223877 -283.245873) (xy 94.503749 -283.245873) (xy 94.503749 -283.193939)
			(xy 94.511874 -283.142644) (xy 94.527922 -283.093251) (xy 94.5515 -283.046977) (xy 94.582026 -283.004961)
			(xy 94.618749 -282.968238) (xy 94.660765 -282.937712) (xy 94.707039 -282.914134) (xy 94.756432 -282.898086)
			(xy 94.807727 -282.889961) (xy 94.859661 -282.889961) (xy 94.910956 -282.898086) (xy 94.960349 -282.914134)
			(xy 95.006623 -282.937712) (xy 95.048639 -282.968238) (xy 95.085362 -283.004961) (xy 95.115888 -283.046977)
			(xy 95.139466 -283.093251) (xy 95.155514 -283.142644) (xy 95.163639 -283.193939) (xy 95.164148 -283.219906)
			(xy 95.163639 -283.245873) (xy 95.443549 -283.245873) (xy 95.443549 -283.193939) (xy 95.451674 -283.142644)
			(xy 95.467722 -283.093251) (xy 95.4913 -283.046977) (xy 95.521826 -283.004961) (xy 95.558549 -282.968238)
			(xy 95.600565 -282.937712) (xy 95.646839 -282.914134) (xy 95.696232 -282.898086) (xy 95.747527 -282.889961)
			(xy 95.799461 -282.889961) (xy 95.850756 -282.898086) (xy 95.900149 -282.914134) (xy 95.946423 -282.937712)
			(xy 95.988439 -282.968238) (xy 96.025162 -283.004961) (xy 96.055688 -283.046977) (xy 96.079266 -283.093251)
			(xy 96.095314 -283.142644) (xy 96.103439 -283.193939) (xy 96.103948 -283.219906) (xy 96.103439 -283.245873)
			(xy 96.095314 -283.297168) (xy 96.079266 -283.346561) (xy 96.055688 -283.392835) (xy 96.025162 -283.434851)
			(xy 95.988439 -283.471574) (xy 95.946423 -283.5021) (xy 95.900149 -283.525678) (xy 95.850756 -283.541726)
			(xy 95.799461 -283.549851) (xy 95.747527 -283.549851) (xy 95.696232 -283.541726) (xy 95.646839 -283.525678)
			(xy 95.600565 -283.5021) (xy 95.558549 -283.471574) (xy 95.521826 -283.434851) (xy 95.4913 -283.392835)
			(xy 95.467722 -283.346561) (xy 95.451674 -283.297168) (xy 95.443549 -283.245873) (xy 95.163639 -283.245873)
			(xy 95.155514 -283.297168) (xy 95.139466 -283.346561) (xy 95.115888 -283.392835) (xy 95.085362 -283.434851)
			(xy 95.048639 -283.471574) (xy 95.006623 -283.5021) (xy 94.960349 -283.525678) (xy 94.910956 -283.541726)
			(xy 94.859661 -283.549851) (xy 94.807727 -283.549851) (xy 94.756432 -283.541726) (xy 94.707039 -283.525678)
			(xy 94.660765 -283.5021) (xy 94.618749 -283.471574) (xy 94.582026 -283.434851) (xy 94.5515 -283.392835)
			(xy 94.527922 -283.346561) (xy 94.511874 -283.297168) (xy 94.503749 -283.245873) (xy 94.223877 -283.245873)
			(xy 94.215752 -283.297171) (xy 94.199701 -283.346569) (xy 94.176121 -283.392848) (xy 94.145591 -283.434868)
			(xy 94.108863 -283.471595) (xy 94.066842 -283.502124) (xy 94.020563 -283.525704) (xy 93.971165 -283.541753)
			(xy 93.919864 -283.549878) (xy 93.893894 -283.55036) (xy 93.868257 -283.549898) (xy 93.8176 -283.541971)
			(xy 93.768776 -283.526309) (xy 93.722961 -283.503287) (xy 93.681256 -283.47346) (xy 93.644662 -283.437545)
			(xy 93.628972 -283.417264) (xy 93.219016 -283.417264) (xy 93.203342 -283.437557) (xy 93.166741 -283.473463)
			(xy 93.12503 -283.503282) (xy 93.079212 -283.526296) (xy 93.030388 -283.541953) (xy 92.979731 -283.549876)
			(xy 92.954094 -283.55036) (xy 92.928128 -283.549838) (xy 92.876834 -283.541713) (xy 92.827443 -283.525665)
			(xy 92.781171 -283.502087) (xy 92.739157 -283.471561) (xy 92.702435 -283.434839) (xy 92.67191 -283.392824)
			(xy 92.648333 -283.346551) (xy 92.632285 -283.29716) (xy 92.624161 -283.245866) (xy 92.344239 -283.245866)
			(xy 92.344239 -283.245873) (xy 92.336114 -283.297168) (xy 92.320066 -283.346561) (xy 92.296488 -283.392835)
			(xy 92.265962 -283.434851) (xy 92.229239 -283.471574) (xy 92.187223 -283.5021) (xy 92.140949 -283.525678)
			(xy 92.091556 -283.541726) (xy 92.040261 -283.549851) (xy 91.988327 -283.549851) (xy 91.937032 -283.541726)
			(xy 91.887639 -283.525678) (xy 91.841365 -283.5021) (xy 91.799349 -283.471574) (xy 91.762626 -283.434851)
			(xy 91.7321 -283.392835) (xy 91.708522 -283.346561) (xy 91.692474 -283.297168) (xy 91.684349 -283.245873)
			(xy 91.404439 -283.245873) (xy 91.396314 -283.297168) (xy 91.380266 -283.346561) (xy 91.356688 -283.392835)
			(xy 91.326162 -283.434851) (xy 91.289439 -283.471574) (xy 91.247423 -283.5021) (xy 91.201149 -283.525678)
			(xy 91.151756 -283.541726) (xy 91.100461 -283.549851) (xy 91.048527 -283.549851) (xy 90.997232 -283.541726)
			(xy 90.947839 -283.525678) (xy 90.901565 -283.5021) (xy 90.859549 -283.471574) (xy 90.822826 -283.434851)
			(xy 90.7923 -283.392835) (xy 90.768722 -283.346561) (xy 90.752674 -283.297168) (xy 90.744549 -283.245873)
			(xy 90.74404 -283.219906) (xy 90.465148 -283.219906) (xy 90.464639 -283.245873) (xy 90.456514 -283.297168)
			(xy 90.440466 -283.346561) (xy 90.416888 -283.392835) (xy 90.386362 -283.434851) (xy 90.349639 -283.471574)
			(xy 90.307623 -283.5021) (xy 90.261349 -283.525678) (xy 90.211956 -283.541726) (xy 90.160661 -283.549851)
			(xy 90.108727 -283.549851) (xy 90.057432 -283.541726) (xy 90.008039 -283.525678) (xy 89.961765 -283.5021)
			(xy 89.919749 -283.471574) (xy 89.883026 -283.434851) (xy 89.8525 -283.392835) (xy 89.828922 -283.346561)
			(xy 89.812874 -283.297168) (xy 89.804749 -283.245873) (xy 89.524839 -283.245873) (xy 89.516714 -283.297168)
			(xy 89.500666 -283.346561) (xy 89.477088 -283.392835) (xy 89.446562 -283.434851) (xy 89.409839 -283.471574)
			(xy 89.367823 -283.5021) (xy 89.321549 -283.525678) (xy 89.272156 -283.541726) (xy 89.220861 -283.549851)
			(xy 89.168927 -283.549851) (xy 89.117632 -283.541726) (xy 89.068239 -283.525678) (xy 89.021965 -283.5021)
			(xy 88.979949 -283.471574) (xy 88.943226 -283.434851) (xy 88.9127 -283.392835) (xy 88.889122 -283.346561)
			(xy 88.873074 -283.297168) (xy 88.864949 -283.245873) (xy 88.585039 -283.245873) (xy 88.576914 -283.297168)
			(xy 88.560866 -283.346561) (xy 88.537288 -283.392835) (xy 88.506762 -283.434851) (xy 88.470039 -283.471574)
			(xy 88.428023 -283.5021) (xy 88.381749 -283.525678) (xy 88.332356 -283.541726) (xy 88.281061 -283.549851)
			(xy 88.229127 -283.549851) (xy 88.177832 -283.541726) (xy 88.128439 -283.525678) (xy 88.082165 -283.5021)
			(xy 88.040149 -283.471574) (xy 88.003426 -283.434851) (xy 87.9729 -283.392835) (xy 87.949322 -283.346561)
			(xy 87.933274 -283.297168) (xy 87.925149 -283.245873) (xy 87.92464 -283.219906) (xy 87.925253 -283.191926)
			(xy 87.934705 -283.136768) (xy 87.943436 -283.110178) (xy 87.951056 -283.08808) (xy 87.762842 -282.762198)
			(xy 87.738204 -282.758896) (xy 87.713235 -282.755128) (xy 87.664623 -282.74146) (xy 87.61843 -282.721062)
			(xy 87.575582 -282.694343) (xy 87.536938 -282.661839) (xy 87.519764 -282.643326) (xy 87.517224 -282.640278)
			(xy 87.510275 -282.634174) (xy 87.493182 -282.627144) (xy 87.48395 -282.626562) (xy 87.44966 -282.625546)
			(xy 87.408258 -282.62453) (xy 87.398766 -282.625182) (xy 87.381268 -282.632615) (xy 87.374222 -282.639008)
			(xy 87.292434 -282.720796) (xy 87.286099 -282.727714) (xy 87.278645 -282.744913) (xy 87.277994 -282.763646)
			(xy 87.28075 -282.772612) (xy 87.310468 -282.857956) (xy 87.320882 -282.887928) (xy 87.352632 -282.891484)
			(xy 87.379187 -282.895018) (xy 87.430743 -282.909562) (xy 87.479279 -282.932231) (xy 87.523521 -282.962433)
			(xy 87.562312 -282.999377) (xy 87.594636 -283.042094) (xy 87.619645 -283.089466) (xy 87.636685 -283.140252)
			(xy 87.645309 -283.193122) (xy 87.645748 -283.219906) (xy 87.645239 -283.245873) (xy 87.637114 -283.297168)
			(xy 87.621066 -283.346561) (xy 87.597488 -283.392835) (xy 87.566962 -283.434851) (xy 87.530239 -283.471574)
			(xy 87.488223 -283.5021) (xy 87.441949 -283.525678) (xy 87.392556 -283.541726) (xy 87.341261 -283.549851)
			(xy 87.289327 -283.549851) (xy 87.238032 -283.541726) (xy 87.188639 -283.525678) (xy 87.142365 -283.5021)
			(xy 87.100349 -283.471574) (xy 87.063626 -283.434851) (xy 87.0331 -283.392835) (xy 87.009522 -283.346561)
			(xy 86.993474 -283.297168) (xy 86.985349 -283.245873) (xy 86.98484 -283.219906) (xy 86.985356 -283.19317)
			(xy 86.993969 -283.140395) (xy 87.010973 -283.089698) (xy 87.035922 -283.042402) (xy 87.051642 -283.02077)
			(xy 87.059771 -283.009243) (xy 87.069951 -282.98295) (xy 87.072549 -282.954875) (xy 87.067365 -282.927161)
			(xy 87.054797 -282.901922) (xy 87.035802 -282.881085) (xy 87.011831 -282.866241) (xy 86.984713 -282.858522)
			(xy 86.970616 -282.857956) (xy 86.720172 -282.857956) (xy 86.706059 -282.858404) (xy 86.678908 -282.866115)
			(xy 86.654907 -282.880967) (xy 86.635892 -282.901825) (xy 86.623316 -282.927093) (xy 86.61814 -282.954839)
			(xy 86.620762 -282.982941) (xy 86.630981 -283.009251) (xy 86.639146 -283.02077) (xy 86.65486 -283.042408)
			(xy 86.679816 -283.0897) (xy 86.696825 -283.140395) (xy 86.705441 -283.19317) (xy 86.705948 -283.219906)
			(xy 86.705438 -283.245873) (xy 86.697313 -283.297167) (xy 86.681264 -283.346558) (xy 86.657686 -283.392831)
			(xy 86.627159 -283.434845) (xy 86.590436 -283.471567) (xy 86.54842 -283.502092) (xy 86.502147 -283.525669)
			(xy 86.452755 -283.541716) (xy 86.401461 -283.549839) (xy 86.375494 -283.55036) (xy 86.349717 -283.549865)
			(xy 86.298787 -283.541861) (xy 86.249717 -283.526046) (xy 86.203698 -283.502805) (xy 86.161845 -283.472702)
			(xy 86.125172 -283.436466) (xy 86.09457 -283.394976) (xy 86.070781 -283.349238) (xy 86.05438 -283.300361)
			(xy 86.049612 -283.275024) (xy 86.046851 -283.261377) (xy 86.034944 -283.236218) (xy 86.016689 -283.215205)
			(xy 85.99344 -283.199899) (xy 85.966924 -283.191435) (xy 85.939107 -283.190441) (xy 85.912054 -283.19699)
			(xy 85.887773 -283.210598) (xy 85.877654 -283.22016) (xy 85.73262 -283.365194) (xy 85.729064 -283.372306)
			(xy 85.716959 -283.394558) (xy 85.687024 -283.435418) (xy 85.651206 -283.471235) (xy 85.610344 -283.501168)
			(xy 85.588094 -283.513276) (xy 85.580982 -283.516832) (xy 85.469476 -283.628338) (xy 85.469476 -284.033722)
			(xy 86.515194 -284.033722) (xy 86.515703 -284.007755) (xy 86.523828 -283.95646) (xy 86.539876 -283.907067)
			(xy 86.563454 -283.860793) (xy 86.59398 -283.818777) (xy 86.630703 -283.782054) (xy 86.672719 -283.751528)
			(xy 86.718993 -283.72795) (xy 86.768386 -283.711902) (xy 86.819681 -283.703777) (xy 86.871615 -283.703777)
			(xy 86.92291 -283.711902) (xy 86.972303 -283.72795) (xy 87.018577 -283.751528) (xy 87.060593 -283.782054)
			(xy 87.097316 -283.818777) (xy 87.127842 -283.860793) (xy 87.15142 -283.907067) (xy 87.167468 -283.95646)
			(xy 87.175593 -284.007755) (xy 87.176102 -284.033722) (xy 87.175594 -284.059689) (xy 87.455249 -284.059689)
			(xy 87.455249 -284.007755) (xy 87.463374 -283.95646) (xy 87.479422 -283.907067) (xy 87.503 -283.860793)
			(xy 87.533526 -283.818777) (xy 87.570249 -283.782054) (xy 87.612265 -283.751528) (xy 87.658539 -283.72795)
			(xy 87.707932 -283.711902) (xy 87.759227 -283.703777) (xy 87.811161 -283.703777) (xy 87.862456 -283.711902)
			(xy 87.911849 -283.72795) (xy 87.958123 -283.751528) (xy 88.000139 -283.782054) (xy 88.036862 -283.818777)
			(xy 88.067388 -283.860793) (xy 88.090966 -283.907067) (xy 88.107014 -283.95646) (xy 88.115139 -284.007755)
			(xy 88.115648 -284.033722) (xy 88.115139 -284.059689) (xy 88.395303 -284.059689) (xy 88.395303 -284.007755)
			(xy 88.403428 -283.95646) (xy 88.419476 -283.907067) (xy 88.443054 -283.860793) (xy 88.47358 -283.818777)
			(xy 88.510303 -283.782054) (xy 88.552319 -283.751528) (xy 88.598593 -283.72795) (xy 88.647986 -283.711902)
			(xy 88.699281 -283.703777) (xy 88.751215 -283.703777) (xy 88.80251 -283.711902) (xy 88.851903 -283.72795)
			(xy 88.898177 -283.751528) (xy 88.940193 -283.782054) (xy 88.976916 -283.818777) (xy 89.007442 -283.860793)
			(xy 89.03102 -283.907067) (xy 89.047068 -283.95646) (xy 89.055193 -284.007755) (xy 89.055702 -284.033722)
			(xy 89.055193 -284.059689) (xy 89.047068 -284.110984) (xy 89.03102 -284.160377) (xy 89.007442 -284.206651)
			(xy 88.976916 -284.248667) (xy 88.940193 -284.28539) (xy 88.898177 -284.315916) (xy 88.851903 -284.339494)
			(xy 88.80251 -284.355542) (xy 88.751215 -284.363667) (xy 88.699281 -284.363667) (xy 88.647986 -284.355542)
			(xy 88.598593 -284.339494) (xy 88.552319 -284.315916) (xy 88.510303 -284.28539) (xy 88.47358 -284.248667)
			(xy 88.443054 -284.206651) (xy 88.419476 -284.160377) (xy 88.403428 -284.110984) (xy 88.395303 -284.059689)
			(xy 88.115139 -284.059689) (xy 88.107014 -284.110984) (xy 88.090966 -284.160377) (xy 88.067388 -284.206651)
			(xy 88.036862 -284.248667) (xy 88.000139 -284.28539) (xy 87.958123 -284.315916) (xy 87.911849 -284.339494)
			(xy 87.862456 -284.355542) (xy 87.811161 -284.363667) (xy 87.759227 -284.363667) (xy 87.707932 -284.355542)
			(xy 87.658539 -284.339494) (xy 87.612265 -284.315916) (xy 87.570249 -284.28539) (xy 87.533526 -284.248667)
			(xy 87.503 -284.206651) (xy 87.479422 -284.160377) (xy 87.463374 -284.110984) (xy 87.455249 -284.059689)
			(xy 87.175594 -284.059689) (xy 87.175555 -284.061708) (xy 87.166101 -284.116876) (xy 87.157306 -284.14345)
			(xy 87.149686 -284.165548) (xy 87.353394 -284.518354) (xy 87.376254 -284.522672) (xy 87.401179 -284.527824)
			(xy 87.449164 -284.544791) (xy 87.493981 -284.568911) (xy 87.534574 -284.599613) (xy 87.569982 -284.636173)
			(xy 87.59937 -284.677727) (xy 87.622043 -284.723294) (xy 87.637467 -284.771797) (xy 87.645275 -284.82209)
			(xy 87.645748 -284.847538) (xy 87.645239 -284.873505) (xy 87.637114 -284.9248) (xy 87.621066 -284.974193)
			(xy 87.597488 -285.020467) (xy 87.566962 -285.062483) (xy 87.530239 -285.099206) (xy 87.488223 -285.129732)
			(xy 87.441949 -285.15331) (xy 87.392556 -285.169358) (xy 87.341261 -285.177483) (xy 87.289327 -285.177483)
			(xy 87.238032 -285.169358) (xy 87.188639 -285.15331) (xy 87.142365 -285.129732) (xy 87.100349 -285.099206)
			(xy 87.063626 -285.062483) (xy 87.0331 -285.020467) (xy 87.009522 -284.974193) (xy 86.993474 -284.9248)
			(xy 86.985349 -284.873505) (xy 86.98484 -284.847538) (xy 86.9854 -284.819552) (xy 86.994845 -284.764385)
			(xy 87.003636 -284.73781) (xy 87.011256 -284.715712) (xy 86.807548 -284.362906) (xy 86.784688 -284.358588)
			(xy 86.759761 -284.353443) (xy 86.711773 -284.336479) (xy 86.666953 -284.312361) (xy 86.626358 -284.281659)
			(xy 86.590948 -284.245098) (xy 86.56156 -284.203541) (xy 86.538888 -284.157972) (xy 86.523468 -284.109467)
			(xy 86.515664 -284.059171) (xy 86.515194 -284.033722) (xy 85.469476 -284.033722) (xy 85.469476 -284.366208)
			(xy 85.61705 -284.513782) (xy 85.638386 -284.554676) (xy 85.640926 -284.556454) (xy 85.664626 -284.573906)
			(xy 85.706493 -284.615268) (xy 85.724238 -284.63875) (xy 85.732112 -284.65018) (xy 86.110572 -284.65018)
			(xy 86.126264 -284.629902) (xy 86.16286 -284.593992) (xy 86.204566 -284.564171) (xy 86.250381 -284.541153)
			(xy 86.299203 -284.525494) (xy 86.349858 -284.517568) (xy 86.375494 -284.517084) (xy 86.401461 -284.517566)
			(xy 86.452755 -284.52569) (xy 86.502146 -284.541737) (xy 86.548419 -284.565314) (xy 86.590435 -284.595839)
			(xy 86.627157 -284.632561) (xy 86.657683 -284.674575) (xy 86.681261 -284.720848) (xy 86.697309 -284.77024)
			(xy 86.705433 -284.821533) (xy 86.705433 -284.873467) (xy 86.697309 -284.92476) (xy 86.681261 -284.974152)
			(xy 86.657683 -285.020425) (xy 86.627157 -285.062439) (xy 86.590435 -285.099161) (xy 86.548419 -285.129686)
			(xy 86.502146 -285.153263) (xy 86.452755 -285.16931) (xy 86.401461 -285.177434) (xy 86.375494 -285.177992)
			(xy 86.349859 -285.177507) (xy 86.299204 -285.169581) (xy 86.250383 -285.153921) (xy 86.20457 -285.130902)
			(xy 86.162865 -285.101079) (xy 86.126271 -285.065168) (xy 86.110572 -285.044896) (xy 85.732112 -285.044896)
			(xy 85.724238 -285.056326) (xy 85.7065 -285.079814) (xy 85.664633 -285.121178) (xy 85.640926 -285.138622)
			(xy 85.638386 -285.1404) (xy 85.61705 -285.181294) (xy 85.61705 -285.27375) (xy 85.617378 -285.282199)
			(xy 85.622943 -285.298154) (xy 85.633439 -285.311397) (xy 85.640418 -285.316168) (xy 85.680804 -285.341314)
			(xy 85.714586 -285.362396) (xy 85.720228 -285.365417) (xy 85.732574 -285.368775) (xy 85.73897 -285.369)
			(xy 85.760814 -285.36392) (xy 85.76564 -285.361634) (xy 85.787579 -285.351873) (xy 85.833573 -285.338081)
			(xy 85.881078 -285.331089) (xy 85.905086 -285.330646) (xy 85.905594 -285.330646) (xy 85.931587 -285.331129)
			(xy 85.982934 -285.33926) (xy 86.032376 -285.355324) (xy 86.078696 -285.378925) (xy 86.120754 -285.409481)
			(xy 86.157515 -285.446241) (xy 86.188072 -285.488299) (xy 86.211673 -285.534619) (xy 86.227738 -285.584061)
			(xy 86.235871 -285.635407) (xy 86.235871 -285.687321) (xy 86.515449 -285.687321) (xy 86.515449 -285.635387)
			(xy 86.523574 -285.584092) (xy 86.539622 -285.534699) (xy 86.5632 -285.488425) (xy 86.593726 -285.446409)
			(xy 86.630449 -285.409686) (xy 86.672465 -285.37916) (xy 86.718739 -285.355582) (xy 86.768132 -285.339534)
			(xy 86.819427 -285.331409) (xy 86.871361 -285.331409) (xy 86.922656 -285.339534) (xy 86.972049 -285.355582)
			(xy 87.018323 -285.37916) (xy 87.060339 -285.409686) (xy 87.097062 -285.446409) (xy 87.127588 -285.488425)
			(xy 87.151166 -285.534699) (xy 87.167214 -285.584092) (xy 87.175339 -285.635387) (xy 87.175848 -285.661354)
			(xy 87.45474 -285.661354) (xy 87.45519 -285.635902) (xy 87.462975 -285.585597) (xy 87.478383 -285.537081)
			(xy 87.501051 -285.491504) (xy 87.530442 -285.449942) (xy 87.565861 -285.413381) (xy 87.606468 -285.382684)
			(xy 87.651303 -285.35858) (xy 87.699304 -285.341639) (xy 87.724234 -285.336488) (xy 87.747348 -285.33217)
			(xy 87.951056 -284.97911) (xy 87.943436 -284.957012) (xy 87.934692 -284.93049) (xy 87.925242 -284.875457)
			(xy 87.92464 -284.847538) (xy 87.925149 -284.821571) (xy 87.933274 -284.770276) (xy 87.949322 -284.720883)
			(xy 87.9729 -284.674609) (xy 88.003426 -284.632593) (xy 88.040149 -284.59587) (xy 88.082165 -284.565344)
			(xy 88.128439 -284.541766) (xy 88.177832 -284.525718) (xy 88.229127 -284.517593) (xy 88.281061 -284.517593)
			(xy 88.332356 -284.525718) (xy 88.381749 -284.541766) (xy 88.428023 -284.565344) (xy 88.470039 -284.59587)
			(xy 88.506762 -284.632593) (xy 88.537288 -284.674609) (xy 88.560866 -284.720883) (xy 88.576914 -284.770276)
			(xy 88.585039 -284.821571) (xy 88.585548 -284.847538) (xy 88.5851 -284.87299) (xy 88.577317 -284.923296)
			(xy 88.561908 -284.971812) (xy 88.53924 -285.017391) (xy 88.509849 -285.058952) (xy 88.47443 -285.095514)
			(xy 88.433823 -285.12621) (xy 88.388987 -285.150313) (xy 88.340984 -285.167254) (xy 88.316054 -285.172404)
			(xy 88.29294 -285.176722) (xy 88.089232 -285.529782) (xy 88.096852 -285.55188) (xy 88.105593 -285.578402)
			(xy 88.115045 -285.633435) (xy 88.115648 -285.661354) (xy 88.115139 -285.687321) (xy 88.107014 -285.738616)
			(xy 88.090966 -285.788009) (xy 88.067388 -285.834283) (xy 88.036862 -285.876299) (xy 88.000139 -285.913022)
			(xy 87.958123 -285.943548) (xy 87.911849 -285.967126) (xy 87.862456 -285.983174) (xy 87.811161 -285.991299)
			(xy 87.759227 -285.991299) (xy 87.707932 -285.983174) (xy 87.658539 -285.967126) (xy 87.612265 -285.943548)
			(xy 87.570249 -285.913022) (xy 87.533526 -285.876299) (xy 87.503 -285.834283) (xy 87.479422 -285.788009)
			(xy 87.463374 -285.738616) (xy 87.455249 -285.687321) (xy 87.45474 -285.661354) (xy 87.175848 -285.661354)
			(xy 87.175339 -285.687321) (xy 87.167214 -285.738616) (xy 87.151166 -285.788009) (xy 87.127588 -285.834283)
			(xy 87.097062 -285.876299) (xy 87.060339 -285.913022) (xy 87.018323 -285.943548) (xy 86.972049 -285.967126)
			(xy 86.922656 -285.983174) (xy 86.871361 -285.991299) (xy 86.819427 -285.991299) (xy 86.768132 -285.983174)
			(xy 86.718739 -285.967126) (xy 86.672465 -285.943548) (xy 86.630449 -285.913022) (xy 86.593726 -285.876299)
			(xy 86.5632 -285.834283) (xy 86.539622 -285.788009) (xy 86.523574 -285.738616) (xy 86.515449 -285.687321)
			(xy 86.235871 -285.687321) (xy 86.235871 -285.687393) (xy 86.227738 -285.738739) (xy 86.211673 -285.788181)
			(xy 86.188072 -285.834501) (xy 86.157515 -285.876559) (xy 86.120754 -285.913319) (xy 86.078696 -285.943875)
			(xy 86.032376 -285.967476) (xy 85.982934 -285.98354) (xy 85.931587 -285.991671) (xy 85.905594 -285.992062)
			(xy 85.905086 -285.992062) (xy 85.881077 -285.991616) (xy 85.83357 -285.984634) (xy 85.787574 -285.970847)
			(xy 85.76564 -285.961074) (xy 85.760814 -285.958788) (xy 85.73897 -285.953708) (xy 85.732577 -285.953963)
			(xy 85.72023 -285.9573) (xy 85.714586 -285.960312) (xy 85.680804 -285.981394) (xy 85.640418 -286.00654)
			(xy 85.63343 -286.01131) (xy 85.622891 -286.024533) (xy 85.617333 -286.040503) (xy 85.61705 -286.048958)
			(xy 85.61705 -286.141668) (xy 85.638386 -286.182562) (xy 85.640926 -286.18434) (xy 85.662088 -286.199831)
			(xy 85.700053 -286.236011) (xy 85.732302 -286.277368) (xy 85.758137 -286.323006) (xy 85.777 -286.371941)
			(xy 85.788483 -286.423112) (xy 85.792337 -286.475414) (xy 85.792336 -286.475424) (xy 86.04504 -286.475424)
			(xy 86.045549 -286.449457) (xy 86.053674 -286.398162) (xy 86.069722 -286.348769) (xy 86.0933 -286.302495)
			(xy 86.123826 -286.260479) (xy 86.160549 -286.223756) (xy 86.202565 -286.19323) (xy 86.248839 -286.169652)
			(xy 86.298232 -286.153604) (xy 86.349527 -286.145479) (xy 86.401461 -286.145479) (xy 86.452756 -286.153604)
			(xy 86.502149 -286.169652) (xy 86.548423 -286.19323) (xy 86.590439 -286.223756) (xy 86.627162 -286.260479)
			(xy 86.657688 -286.302495) (xy 86.681266 -286.348769) (xy 86.697314 -286.398162) (xy 86.705439 -286.449457)
			(xy 86.705948 -286.475424) (xy 86.705315 -286.50334) (xy 86.69587 -286.558371) (xy 86.687152 -286.584898)
			(xy 86.679532 -286.606996) (xy 86.883494 -286.960056) (xy 86.906354 -286.964374) (xy 86.93128 -286.969524)
			(xy 86.979264 -286.986491) (xy 87.024082 -287.010611) (xy 87.064675 -287.041314) (xy 87.100083 -287.077874)
			(xy 87.129471 -287.119429) (xy 87.152144 -287.164995) (xy 87.167567 -287.213498) (xy 87.175375 -287.263792)
			(xy 87.175848 -287.28924) (xy 87.175339 -287.315207) (xy 87.167214 -287.366502) (xy 87.151166 -287.415895)
			(xy 87.127588 -287.462169) (xy 87.097062 -287.504185) (xy 87.060339 -287.540908) (xy 87.018323 -287.571434)
			(xy 86.972049 -287.595012) (xy 86.922656 -287.61106) (xy 86.871361 -287.619185) (xy 86.819427 -287.619185)
			(xy 86.768132 -287.61106) (xy 86.718739 -287.595012) (xy 86.672465 -287.571434) (xy 86.630449 -287.540908)
			(xy 86.593726 -287.504185) (xy 86.5632 -287.462169) (xy 86.539622 -287.415895) (xy 86.523574 -287.366502)
			(xy 86.515449 -287.315207) (xy 86.51494 -287.28924) (xy 86.515564 -287.261323) (xy 86.525015 -287.206293)
			(xy 86.533736 -287.179766) (xy 86.541356 -287.157668) (xy 86.337394 -286.804608) (xy 86.314534 -286.80029)
			(xy 86.289599 -286.795182) (xy 86.241611 -286.778211) (xy 86.196792 -286.754086) (xy 86.156198 -286.723378)
			(xy 86.12079 -286.686813) (xy 86.091404 -286.645253) (xy 86.068733 -286.59968) (xy 86.053314 -286.551172)
			(xy 86.04551 -286.500874) (xy 86.04504 -286.475424) (xy 85.792336 -286.475424) (xy 85.788479 -286.527716)
			(xy 85.776992 -286.578886) (xy 85.758126 -286.627819) (xy 85.732287 -286.673455) (xy 85.700035 -286.714809)
			(xy 85.662067 -286.750986) (xy 85.640926 -286.766508) (xy 85.638386 -286.768286) (xy 85.61705 -286.80918)
			(xy 85.61705 -288.719006) (xy 85.617555 -288.728761) (xy 85.624988 -288.746805) (xy 85.631528 -288.754058)
			(xy 85.754972 -288.877502) (xy 85.762223 -288.884051) (xy 85.780265 -288.891493) (xy 85.790024 -288.89198)
		)
		(stroke
			(width 0)
			(type solid)
		)
		(fill yes)
		(layer "In2.Cu")
		(net "PVCCFA_EHV_FIVRA_CPU1")
	)
	(gr_line
		(start 292.05555 -161.281364)
		(end 291.884608 -161.281364)
		(stroke
			(width 0.07366)
			(type default)
		)
		(layer "In2.Cu")
	)
	(gr_line
		(start 292.170612 -160.605724)
		(end 291.689028 -161.087308)
		(stroke
			(width 0.07366)
			(type default)
		)
		(layer "In2.Cu")
	)
	(gr_line
		(start 292.364668 -160.972246)
		(end 292.05555 -161.281364)
		(stroke
			(width 0.07366)
			(type default)
		)
		(layer "In2.Cu")
	)
	(gr_line
		(start 292.364668 -160.801304)
		(end 292.364668 -160.972246)
		(stroke
			(width 0.07366)
			(type default)
		)
		(layer "In2.Cu")
	)
	(gr_line
		(start 292.845998 -160.490916)
		(end 292.675056 -160.490916)
		(stroke
			(width 0.07366)
			(type default)
		)
		(layer "In2.Cu")
	)
	(gr_line
		(start 292.96106 -159.815276)
		(end 292.479476 -160.29686)
		(stroke
			(width 0.07366)
			(type default)
		)
		(layer "In2.Cu")
	)
	(gr_line
		(start 293.155116 -160.181798)
		(end 292.845998 -160.490916)
		(stroke
			(width 0.07366)
			(type default)
		)
		(layer "In2.Cu")
	)
	(gr_line
		(start 293.155116 -160.010856)
		(end 293.155116 -160.181798)
		(stroke
			(width 0.07366)
			(type default)
		)
		(layer "In2.Cu")
	)
	(gr_line
		(start 293.25062 -162.395408)
		(end 292.95598 -162.100768)
		(stroke
			(width 0.07366)
			(type default)
		)
		(layer "In2.Cu")
	)
	(gr_line
		(start 293.52494 -162.395408)
		(end 293.81958 -162.100768)
		(stroke
			(width 0.07366)
			(type default)
		)
		(layer "In2.Cu")
	)
	(gr_line
		(start 294.58793 -159.03829)
		(end 294.430196 -158.972758)
		(stroke
			(width 0.07366)
			(type default)
		)
		(layer "In2.Cu")
	)
	(gr_line
		(start 294.952928 -158.458154)
		(end 294.32377 -158.718758)
		(stroke
			(width 0.07366)
			(type default)
		)
		(layer "In2.Cu")
	)
	(gr_line
		(start 294.99179 -158.871158)
		(end 294.58793 -159.03829)
		(stroke
			(width 0.07366)
			(type default)
		)
		(layer "In2.Cu")
	)
	(gr_line
		(start 295.057322 -158.71317)
		(end 294.99179 -158.871158)
		(stroke
			(width 0.07366)
			(type default)
		)
		(layer "In2.Cu")
	)
	(gr_line
		(start 295.11244 -163.096448)
		(end 295.40708 -163.391088)
		(stroke
			(width 0.07366)
			(type default)
		)
		(layer "In2.Cu")
	)
	(gr_line
		(start 295.620694 -158.610554)
		(end 295.462706 -158.545022)
		(stroke
			(width 0.07366)
			(type default)
		)
		(layer "In2.Cu")
	)
	(gr_line
		(start 295.97604 -163.096448)
		(end 295.6814 -163.391088)
		(stroke
			(width 0.07366)
			(type default)
		)
		(layer "In2.Cu")
	)
	(gr_line
		(start 295.985438 -158.030164)
		(end 295.35628 -158.290768)
		(stroke
			(width 0.07366)
			(type default)
		)
		(layer "In2.Cu")
	)
	(gr_line
		(start 296.024554 -158.443422)
		(end 295.620694 -158.610554)
		(stroke
			(width 0.07366)
			(type default)
		)
		(layer "In2.Cu")
	)
	(gr_line
		(start 296.090086 -158.28518)
		(end 296.024554 -158.443422)
		(stroke
			(width 0.07366)
			(type default)
		)
		(layer "In2.Cu")
	)
	(gr_line
		(start 296.653458 -158.182818)
		(end 296.49547 -158.117286)
		(stroke
			(width 0.07366)
			(type default)
		)
		(layer "In2.Cu")
	)
	(gr_line
		(start 297.018202 -157.602428)
		(end 296.389044 -157.863032)
		(stroke
			(width 0.07366)
			(type default)
		)
		(layer "In2.Cu")
	)
	(gr_line
		(start 297.057318 -158.015686)
		(end 296.653458 -158.182818)
		(stroke
			(width 0.07366)
			(type default)
		)
		(layer "In2.Cu")
	)
	(gr_line
		(start 297.12285 -157.857444)
		(end 297.057318 -158.015686)
		(stroke
			(width 0.07366)
			(type default)
		)
		(layer "In2.Cu")
	)
	(gr_line
		(start 297.13428 -161.506408)
		(end 297.13428 -161.557208)
		(stroke
			(width 0.07366)
			(type default)
		)
		(layer "In2.Cu")
	)
	(gr_line
		(start 297.48099 -161.159698)
		(end 297.13428 -161.506408)
		(stroke
			(width 0.07366)
			(type default)
		)
		(layer "In2.Cu")
	)
	(gr_line
		(start 297.686222 -157.755082)
		(end 297.528234 -157.68955)
		(stroke
			(width 0.07366)
			(type default)
		)
		(layer "In2.Cu")
	)
	(gr_line
		(start 297.75658 -161.315908)
		(end 297.99788 -161.557208)
		(stroke
			(width 0.07366)
			(type default)
		)
		(layer "In2.Cu")
	)
	(gr_line
		(start 297.75658 -161.158428)
		(end 297.75658 -161.315908)
		(stroke
			(width 0.07366)
			(type default)
		)
		(layer "In2.Cu")
	)
	(gr_line
		(start 298.050966 -157.174692)
		(end 297.421808 -157.435296)
		(stroke
			(width 0.07366)
			(type default)
		)
		(layer "In2.Cu")
	)
	(gr_line
		(start 298.090082 -157.58795)
		(end 297.686222 -157.755082)
		(stroke
			(width 0.07366)
			(type default)
		)
		(layer "In2.Cu")
	)
	(gr_line
		(start 298.155614 -157.429708)
		(end 298.090082 -157.58795)
		(stroke
			(width 0.07366)
			(type default)
		)
		(layer "In2.Cu")
	)
	(gr_line
		(start 298.718986 -157.327346)
		(end 298.560998 -157.261814)
		(stroke
			(width 0.07366)
			(type default)
		)
		(layer "In2.Cu")
	)
	(gr_line
		(start 299.083984 -156.746956)
		(end 298.454572 -157.00756)
		(stroke
			(width 0.07366)
			(type default)
		)
		(layer "In2.Cu")
	)
	(gr_line
		(start 299.122846 -157.160214)
		(end 298.718986 -157.327346)
		(stroke
			(width 0.07366)
			(type default)
		)
		(layer "In2.Cu")
	)
	(gr_line
		(start 299.188378 -157.001972)
		(end 299.122846 -157.160214)
		(stroke
			(width 0.07366)
			(type default)
		)
		(layer "In2.Cu")
	)
	(gr_line
		(start 299.188886 -157.000448)
		(end 299.188886 -157.000702)
		(stroke
			(width 0.07366)
			(type default)
		)
		(layer "In2.Cu")
	)
	(gr_line
		(start 299.968158 -156.812488)
		(end 299.806868 -156.745686)
		(stroke
			(width 0.07366)
			(type default)
		)
		(layer "In2.Cu")
	)
	(gr_line
		(start 300.329854 -156.230828)
		(end 299.700442 -156.491432)
		(stroke
			(width 0.07366)
			(type default)
		)
		(layer "In2.Cu")
	)
	(gr_line
		(start 300.367192 -156.647134)
		(end 299.968158 -156.812488)
		(stroke
			(width 0.07366)
			(type default)
		)
		(layer "In2.Cu")
	)
	(gr_line
		(start 300.433994 -156.485844)
		(end 300.367192 -156.647134)
		(stroke
			(width 0.07366)
			(type default)
		)
		(layer "In2.Cu")
	)
	(gr_line
		(start 342.544654 -137.36193)
		(end 342.544908 -137.36193)
		(stroke
			(width 0.07366)
			(type default)
		)
		(layer "In2.Cu")
	)
	(gr_line
		(start 342.80856 -137.437876)
		(end 342.805766 -137.447274)
		(stroke
			(width 0.07366)
			(type default)
		)
		(layer "In2.Cu")
	)
	(gr_line
		(start 343.550494 -50.329592)
		(end 343.82202 -50.173382)
		(stroke
			(width 0.04445)
			(type default)
		)
		(layer "In2.Cu")
	)
	(gr_line
		(start 343.82202 -50.173382)
		(end 343.84615 -50.083974)
		(stroke
			(width 0.04445)
			(type default)
		)
		(layer "In2.Cu")
	)
	(gr_arc
		(start 343.837768 -50.0634)
		(mid 343.841856 -50.073729)
		(end 343.84615 -50.083974)
		(stroke
			(width 0.04445)
			(type default)
		)
		(layer "In2.Cu")
	)
	(gr_line
		(start 344.094308 -50.015902)
		(end 344.016076 -49.994566)
		(stroke
			(width 0.04445)
			(type default)
		)
		(layer "In2.Cu")
	)
	(gr_line
		(start 344.3351 -49.294796)
		(end 344.345514 -49.294796)
		(stroke
			(width 0.04445)
			(type default)
		)
		(layer "In2.Cu")
	)
	(gr_line
		(start 344.36431 -51.739546)
		(end 344.36431 -51.420522)
		(stroke
			(width 0.04445)
			(type default)
		)
		(layer "In2.Cu")
	)
	(gr_line
		(start 344.36431 -51.420522)
		(end 344.594434 -51.190398)
		(stroke
			(width 0.04445)
			(type default)
		)
		(layer "In2.Cu")
	)
	(gr_line
		(start 344.36431 -50.799746)
		(end 344.563446 -50.998882)
		(stroke
			(width 0.04445)
			(type default)
		)
		(layer "In2.Cu")
	)
	(gr_line
		(start 344.365834 -49.859692)
		(end 344.094308 -50.015902)
		(stroke
			(width 0.04445)
			(type default)
		)
		(layer "In2.Cu")
	)
	(gr_line
		(start 344.383614 -49.484788)
		(end 344.394028 -49.484788)
		(stroke
			(width 0.04445)
			(type default)
		)
		(layer "In2.Cu")
	)
	(gr_line
		(start 344.563446 -50.998882)
		(end 344.595704 -50.998882)
		(stroke
			(width 0.04445)
			(type default)
		)
		(layer "In2.Cu")
	)
	(gr_arc
		(start 344.77706 -48.991012)
		(mid 344.777568 -48.990504)
		(end 344.778076 -48.989996)
		(stroke
			(width 0.04445)
			(type default)
		)
		(layer "In2.Cu")
	)
	(gr_line
		(start 345.28125 -131.690872)
		(end 345.329764 -131.32562)
		(stroke
			(width 0.07366)
			(type default)
		)
		(layer "In2.Cu")
	)
	(gr_line
		(start 345.329764 -131.32562)
		(end 345.491308 -131.202176)
		(stroke
			(width 0.07366)
			(type default)
		)
		(layer "In2.Cu")
	)
	(gr_line
		(start 345.404694 -131.852162)
		(end 345.28125 -131.690872)
		(stroke
			(width 0.07366)
			(type default)
		)
		(layer "In2.Cu")
	)
	(gr_line
		(start 345.470734 -130.266948)
		(end 345.519248 -129.901696)
		(stroke
			(width 0.07366)
			(type default)
		)
		(layer "In2.Cu")
	)
	(gr_line
		(start 345.519248 -129.901696)
		(end 345.680538 -129.778252)
		(stroke
			(width 0.07366)
			(type default)
		)
		(layer "In2.Cu")
	)
	(gr_line
		(start 345.594178 -130.428238)
		(end 345.470734 -130.266948)
		(stroke
			(width 0.07366)
			(type default)
		)
		(layer "In2.Cu")
	)
	(gr_line
		(start 345.63431 -51.189382)
		(end 345.67622 -51.231292)
		(stroke
			(width 0.04445)
			(type default)
		)
		(layer "In2.Cu")
	)
	(gr_line
		(start 345.63431 -50.998882)
		(end 345.67622 -50.956972)
		(stroke
			(width 0.04445)
			(type default)
		)
		(layer "In2.Cu")
	)
	(gr_line
		(start 345.66352 -128.818386)
		(end 345.712034 -128.45288)
		(stroke
			(width 0.07366)
			(type default)
		)
		(layer "In2.Cu")
	)
	(gr_line
		(start 345.67241 -49.078642)
		(end 345.71432 -49.120552)
		(stroke
			(width 0.04445)
			(type default)
		)
		(layer "In2.Cu")
	)
	(gr_line
		(start 345.67241 -48.888142)
		(end 345.71432 -48.846232)
		(stroke
			(width 0.04445)
			(type default)
		)
		(layer "In2.Cu")
	)
	(gr_line
		(start 345.67622 -51.231292)
		(end 345.698318 -51.231292)
		(stroke
			(width 0.04445)
			(type default)
		)
		(layer "In2.Cu")
	)
	(gr_line
		(start 345.67622 -50.956972)
		(end 345.698318 -50.956972)
		(stroke
			(width 0.04445)
			(type default)
		)
		(layer "In2.Cu")
	)
	(gr_line
		(start 345.677744 -131.8895)
		(end 345.764612 -131.237228)
		(stroke
			(width 0.07366)
			(type default)
		)
		(layer "In2.Cu")
	)
	(gr_line
		(start 345.682062 -129.777236)
		(end 345.681554 -129.777236)
		(stroke
			(width 0.07366)
			(type default)
		)
		(layer "In2.Cu")
	)
	(gr_line
		(start 345.712034 -128.45288)
		(end 345.873324 -128.329944)
		(stroke
			(width 0.07366)
			(type default)
		)
		(layer "In2.Cu")
	)
	(gr_line
		(start 345.71432 -49.120552)
		(end 345.736418 -49.120552)
		(stroke
			(width 0.04445)
			(type default)
		)
		(layer "In2.Cu")
	)
	(gr_line
		(start 345.71432 -48.846232)
		(end 345.736418 -48.846232)
		(stroke
			(width 0.04445)
			(type default)
		)
		(layer "In2.Cu")
	)
	(gr_line
		(start 345.78671 -128.979422)
		(end 345.66352 -128.818386)
		(stroke
			(width 0.07366)
			(type default)
		)
		(layer "In2.Cu")
	)
	(gr_line
		(start 345.867228 -130.465576)
		(end 345.953842 -129.813558)
		(stroke
			(width 0.07366)
			(type default)
		)
		(layer "In2.Cu")
	)
	(gr_line
		(start 345.874594 -128.32842)
		(end 345.87434 -128.328674)
		(stroke
			(width 0.07366)
			(type default)
		)
		(layer "In2.Cu")
	)
	(gr_line
		(start 345.874848 -128.328674)
		(end 345.87434 -128.328674)
		(stroke
			(width 0.07366)
			(type default)
		)
		(layer "In2.Cu")
	)
	(gr_line
		(start 345.902026 -127.025654)
		(end 345.95054 -126.660402)
		(stroke
			(width 0.07366)
			(type default)
		)
		(layer "In2.Cu")
	)
	(gr_line
		(start 345.95054 -126.660402)
		(end 346.111576 -126.537212)
		(stroke
			(width 0.07366)
			(type default)
		)
		(layer "In2.Cu")
	)
	(gr_line
		(start 346.025216 -127.186944)
		(end 345.902026 -127.025654)
		(stroke
			(width 0.07366)
			(type default)
		)
		(layer "In2.Cu")
	)
	(gr_line
		(start 346.025978 -127.188468)
		(end 346.026486 -127.188468)
		(stroke
			(width 0.07366)
			(type default)
		)
		(layer "In2.Cu")
	)
	(gr_line
		(start 346.05976 -129.017014)
		(end 346.146628 -128.364488)
		(stroke
			(width 0.07366)
			(type default)
		)
		(layer "In2.Cu")
	)
	(gr_line
		(start 346.113354 -126.535942)
		(end 346.112846 -126.535942)
		(stroke
			(width 0.07366)
			(type default)
		)
		(layer "In2.Cu")
	)
	(gr_line
		(start 346.179902 -124.93625)
		(end 346.228416 -124.570744)
		(stroke
			(width 0.07366)
			(type default)
		)
		(layer "In2.Cu")
	)
	(gr_line
		(start 346.228416 -124.570744)
		(end 346.389452 -124.448062)
		(stroke
			(width 0.07366)
			(type default)
		)
		(layer "In2.Cu")
	)
	(gr_line
		(start 346.248482 -49.742598)
		(end 346.5576 -50.051716)
		(stroke
			(width 0.07366)
			(type default)
		)
		(layer "In2.Cu")
	)
	(gr_line
		(start 346.248482 -49.571656)
		(end 346.248482 -49.742598)
		(stroke
			(width 0.07366)
			(type default)
		)
		(layer "In2.Cu")
	)
	(gr_line
		(start 346.298266 -127.224536)
		(end 346.385134 -126.571248)
		(stroke
			(width 0.07366)
			(type default)
		)
		(layer "In2.Cu")
	)
	(gr_line
		(start 346.303092 -125.097286)
		(end 346.179902 -124.93625)
		(stroke
			(width 0.07366)
			(type default)
		)
		(layer "In2.Cu")
	)
	(gr_line
		(start 346.365576 -123.54179)
		(end 346.41409 -123.176284)
		(stroke
			(width 0.07366)
			(type default)
		)
		(layer "In2.Cu")
	)
	(gr_line
		(start 346.390976 -124.446792)
		(end 346.391484 -124.446538)
		(stroke
			(width 0.07366)
			(type default)
		)
		(layer "In2.Cu")
	)
	(gr_line
		(start 346.391484 -124.446538)
		(end 346.390722 -124.446538)
		(stroke
			(width 0.07366)
			(type default)
		)
		(layer "In2.Cu")
	)
	(gr_line
		(start 346.41409 -123.176284)
		(end 346.575126 -123.053602)
		(stroke
			(width 0.07366)
			(type default)
		)
		(layer "In2.Cu")
	)
	(gr_line
		(start 346.442538 -49.376076)
		(end 346.924122 -49.85766)
		(stroke
			(width 0.07366)
			(type default)
		)
		(layer "In2.Cu")
	)
	(gr_line
		(start 346.488766 -123.702572)
		(end 346.365576 -123.54179)
		(stroke
			(width 0.07366)
			(type default)
		)
		(layer "In2.Cu")
	)
	(gr_line
		(start 346.489528 -123.70435)
		(end 346.490036 -123.70435)
		(stroke
			(width 0.07366)
			(type default)
		)
		(layer "In2.Cu")
	)
	(gr_line
		(start 346.541598 -122.21972)
		(end 346.590366 -121.854214)
		(stroke
			(width 0.07366)
			(type default)
		)
		(layer "In2.Cu")
	)
	(gr_line
		(start 346.5576 -50.051716)
		(end 346.728542 -50.051716)
		(stroke
			(width 0.07366)
			(type default)
		)
		(layer "In2.Cu")
	)
	(gr_line
		(start 346.576142 -125.134624)
		(end 346.66301 -124.482098)
		(stroke
			(width 0.07366)
			(type default)
		)
		(layer "In2.Cu")
	)
	(gr_line
		(start 346.576396 -123.052586)
		(end 346.577158 -123.052078)
		(stroke
			(width 0.07366)
			(type default)
		)
		(layer "In2.Cu")
	)
	(gr_line
		(start 346.577158 -123.052078)
		(end 346.57665 -123.052078)
		(stroke
			(width 0.07366)
			(type default)
		)
		(layer "In2.Cu")
	)
	(gr_line
		(start 346.590366 -121.854214)
		(end 346.750894 -121.731786)
		(stroke
			(width 0.07366)
			(type default)
		)
		(layer "In2.Cu")
	)
	(gr_line
		(start 346.664534 -122.380248)
		(end 346.541598 -122.21972)
		(stroke
			(width 0.07366)
			(type default)
		)
		(layer "In2.Cu")
	)
	(gr_line
		(start 346.66555 -122.38228)
		(end 346.666058 -122.38228)
		(stroke
			(width 0.07366)
			(type default)
		)
		(layer "In2.Cu")
	)
	(gr_line
		(start 346.666058 -122.38228)
		(end 346.665804 -122.381772)
		(stroke
			(width 0.07366)
			(type default)
		)
		(layer "In2.Cu")
	)
	(gr_line
		(start 346.727018 -120.828308)
		(end 346.775532 -120.463056)
		(stroke
			(width 0.07366)
			(type default)
		)
		(layer "In2.Cu")
	)
	(gr_line
		(start 346.752164 -121.73077)
		(end 346.75318 -121.730008)
		(stroke
			(width 0.07366)
			(type default)
		)
		(layer "In2.Cu")
	)
	(gr_line
		(start 346.75318 -121.730008)
		(end 346.752164 -121.730008)
		(stroke
			(width 0.07366)
			(type default)
		)
		(layer "In2.Cu")
	)
	(gr_line
		(start 346.761816 -123.740418)
		(end 346.84843 -123.088146)
		(stroke
			(width 0.07366)
			(type default)
		)
		(layer "In2.Cu")
	)
	(gr_line
		(start 346.775532 -120.463056)
		(end 346.935806 -120.340374)
		(stroke
			(width 0.07366)
			(type default)
		)
		(layer "In2.Cu")
	)
	(gr_line
		(start 346.8497 -120.988836)
		(end 346.727018 -120.828308)
		(stroke
			(width 0.07366)
			(type default)
		)
		(layer "In2.Cu")
	)
	(gr_line
		(start 346.850716 -120.991122)
		(end 346.851478 -120.991122)
		(stroke
			(width 0.07366)
			(type default)
		)
		(layer "In2.Cu")
	)
	(gr_line
		(start 346.851478 -120.991122)
		(end 346.850716 -120.990106)
		(stroke
			(width 0.07366)
			(type default)
		)
		(layer "In2.Cu")
	)
	(gr_line
		(start 346.93733 -120.339358)
		(end 346.938346 -120.338596)
		(stroke
			(width 0.07366)
			(type default)
		)
		(layer "In2.Cu")
	)
	(gr_line
		(start 346.937584 -122.418348)
		(end 347.024198 -121.76633)
		(stroke
			(width 0.07366)
			(type default)
		)
		(layer "In2.Cu")
	)
	(gr_line
		(start 346.938346 -120.338596)
		(end 346.93733 -120.338596)
		(stroke
			(width 0.07366)
			(type default)
		)
		(layer "In2.Cu")
	)
	(gr_line
		(start 346.96908 -54.61508)
		(end 347.08973 -54.73573)
		(stroke
			(width 0.07366)
			(type default)
		)
		(layer "In2.Cu")
	)
	(gr_line
		(start 346.96908 -54.1782)
		(end 346.96908 -54.61508)
		(stroke
			(width 0.07366)
			(type default)
		)
		(layer "In2.Cu")
	)
	(gr_line
		(start 346.96908 -53.49748)
		(end 347.08973 -53.61813)
		(stroke
			(width 0.07366)
			(type default)
		)
		(layer "In2.Cu")
	)
	(gr_line
		(start 346.96908 -53.0606)
		(end 346.96908 -53.49748)
		(stroke
			(width 0.07366)
			(type default)
		)
		(layer "In2.Cu")
	)
	(gr_line
		(start 346.96908 -52.37988)
		(end 347.08973 -52.50053)
		(stroke
			(width 0.07366)
			(type default)
		)
		(layer "In2.Cu")
	)
	(gr_line
		(start 346.96908 -51.943)
		(end 346.96908 -52.37988)
		(stroke
			(width 0.07366)
			(type default)
		)
		(layer "In2.Cu")
	)
	(gr_line
		(start 346.96908 -51.26228)
		(end 347.08973 -51.38293)
		(stroke
			(width 0.07366)
			(type default)
		)
		(layer "In2.Cu")
	)
	(gr_line
		(start 346.96908 -50.8254)
		(end 346.96908 -51.26228)
		(stroke
			(width 0.07366)
			(type default)
		)
		(layer "In2.Cu")
	)
	(gr_line
		(start 347.08973 -54.05755)
		(end 346.96908 -54.1782)
		(stroke
			(width 0.07366)
			(type default)
		)
		(layer "In2.Cu")
	)
	(gr_line
		(start 347.08973 -52.93995)
		(end 346.96908 -53.0606)
		(stroke
			(width 0.07366)
			(type default)
		)
		(layer "In2.Cu")
	)
	(gr_line
		(start 347.08973 -51.82235)
		(end 346.96908 -51.943)
		(stroke
			(width 0.07366)
			(type default)
		)
		(layer "In2.Cu")
	)
	(gr_line
		(start 347.08973 -50.70475)
		(end 346.96908 -50.8254)
		(stroke
			(width 0.07366)
			(type default)
		)
		(layer "In2.Cu")
	)
	(gr_line
		(start 347.122496 -121.027444)
		(end 347.209364 -120.374664)
		(stroke
			(width 0.07366)
			(type default)
		)
		(layer "In2.Cu")
	)
	(gr_line
		(start 347.36532 -54.05628)
		(end 347.36532 -54.737)
		(stroke
			(width 0.07366)
			(type default)
		)
		(layer "In2.Cu")
	)
	(gr_line
		(start 347.36532 -52.93868)
		(end 347.36532 -53.6194)
		(stroke
			(width 0.07366)
			(type default)
		)
		(layer "In2.Cu")
	)
	(gr_line
		(start 347.36532 -51.82108)
		(end 347.36532 -52.5018)
		(stroke
			(width 0.07366)
			(type default)
		)
		(layer "In2.Cu")
	)
	(gr_line
		(start 347.36532 -50.70348)
		(end 347.36532 -51.3842)
		(stroke
			(width 0.07366)
			(type default)
		)
		(layer "In2.Cu")
	)
	(gr_line
		(start 347.538294 -63.110872)
		(end 347.55455 -63.547498)
		(stroke
			(width 0.07366)
			(type default)
		)
		(layer "In2.Cu")
	)
	(gr_line
		(start 347.55455 -63.547498)
		(end 347.679772 -63.66383)
		(stroke
			(width 0.07366)
			(type default)
		)
		(layer "In2.Cu")
	)
	(gr_line
		(start 347.57995 -64.22771)
		(end 347.596206 -64.66459)
		(stroke
			(width 0.07366)
			(type default)
		)
		(layer "In2.Cu")
	)
	(gr_line
		(start 347.596206 -64.66459)
		(end 347.721428 -64.780668)
		(stroke
			(width 0.07366)
			(type default)
		)
		(layer "In2.Cu")
	)
	(gr_line
		(start 347.621606 -65.344548)
		(end 347.637862 -65.781428)
		(stroke
			(width 0.07366)
			(type default)
		)
		(layer "In2.Cu")
	)
	(gr_line
		(start 347.637862 -65.781428)
		(end 347.763084 -65.897252)
		(stroke
			(width 0.07366)
			(type default)
		)
		(layer "In2.Cu")
	)
	(gr_line
		(start 347.654626 -62.985396)
		(end 347.538294 -63.110872)
		(stroke
			(width 0.07366)
			(type default)
		)
		(layer "In2.Cu")
	)
	(gr_line
		(start 347.696282 -64.102234)
		(end 347.57995 -64.22771)
		(stroke
			(width 0.07366)
			(type default)
		)
		(layer "In2.Cu")
	)
	(gr_line
		(start 347.737684 -65.219072)
		(end 347.621606 -65.344548)
		(stroke
			(width 0.07366)
			(type default)
		)
		(layer "In2.Cu")
	)
	(gr_line
		(start 347.929962 -62.97422)
		(end 347.955362 -63.654686)
		(stroke
			(width 0.07366)
			(type default)
		)
		(layer "In2.Cu")
	)
	(gr_line
		(start 347.971618 -64.091058)
		(end 347.997018 -64.771524)
		(stroke
			(width 0.07366)
			(type default)
		)
		(layer "In2.Cu")
	)
	(gr_line
		(start 348.013274 -65.207896)
		(end 348.03842 -65.888362)
		(stroke
			(width 0.07366)
			(type default)
		)
		(layer "In2.Cu")
	)
	(gr_line
		(start 356.14483 -61.490606)
		(end 355.85019 -61.195966)
		(stroke
			(width 0.07366)
			(type default)
		)
		(layer "In2.Cu")
	)
	(gr_line
		(start 356.41915 -61.490606)
		(end 356.71379 -61.195966)
		(stroke
			(width 0.07366)
			(type default)
		)
		(layer "In2.Cu")
	)
	(gr_poly
		(pts
			(xy 230.38054 -434.93182)
			(arc
				(start 230.38054 -423.45102)
				(mid 230.404693 -423.329504)
				(end 230.473504 -423.226484)
			)
			(arc
				(start 232.980484 -420.719504)
				(mid 233.083516 -420.650723)
				(end 233.20502 -420.62654)
			)
			(xy 270.36522 -420.62654)
			(arc
				(start 275.456396 -415.535364)
				(mid 275.559428 -415.466583)
				(end 275.680932 -415.4424)
			)
			(xy 279.79624 -415.4424) (xy 280.19756 -415.04108) (xy 280.19756 -408.29992) (xy 279.96896 -408.07132)
			(xy 239.84458 -408.07132)
			(arc
				(start 233.163364 -414.752536)
				(mid 233.060332 -414.821317)
				(end 232.938828 -414.8455)
			)
			(xy 207.34528 -414.8455) (xy 206.49184 -415.69894) (xy 206.49184 -435.39156) (xy 207.63484 -436.53456)
			(xy 228.7778 -436.53456)
		)
		(stroke
			(width 0)
			(type solid)
		)
		(fill yes)
		(layer "In3.Cu")
		(net "P12V_PSU")
	)
	(gr_poly
		(pts
			(xy 531.7998 -462.520284) (xy 531.855607 -462.519775) (xy 531.96691 -462.511434) (xy 532.077278 -462.494798)
			(xy 532.186094 -462.469962) (xy 532.29275 -462.437062) (xy 532.396649 -462.396285) (xy 532.49721 -462.347857)
			(xy 532.593871 -462.292049) (xy 532.686092 -462.229174) (xy 532.773355 -462.159583) (xy 532.855174 -462.083666)
			(xy 532.931091 -462.001846) (xy 533.000681 -461.914582) (xy 533.063556 -461.822361) (xy 533.119362 -461.7257)
			(xy 533.16779 -461.625138) (xy 533.208566 -461.521239) (xy 533.241465 -461.414583) (xy 533.266301 -461.305766)
			(xy 533.282935 -461.195398) (xy 533.291275 -461.084095) (xy 533.291796 -461.028288) (xy 533.291796 -455.0283)
			(xy 533.291274 -454.972493) (xy 533.282933 -454.861191) (xy 533.266298 -454.750824) (xy 533.241462 -454.642008)
			(xy 533.208563 -454.535353) (xy 533.167786 -454.431454) (xy 533.119358 -454.330893) (xy 533.063551 -454.234233)
			(xy 533.000677 -454.142013) (xy 532.931086 -454.054749) (xy 532.85517 -453.97293) (xy 532.773351 -453.897014)
			(xy 532.686087 -453.827423) (xy 532.593867 -453.764549) (xy 532.497207 -453.708742) (xy 532.396646 -453.660314)
			(xy 532.292747 -453.619537) (xy 532.186092 -453.586638) (xy 532.077276 -453.561802) (xy 531.966909 -453.545167)
			(xy 531.855607 -453.536826) (xy 531.7998 -453.536304) (xy 516.019796 -453.536304) (xy 515.949442 -453.535811)
			(xy 515.808956 -453.527921) (xy 515.669133 -453.512166) (xy 515.530414 -453.488597) (xy 515.393234 -453.457286)
			(xy 515.258026 -453.418334) (xy 515.125215 -453.371861) (xy 514.995218 -453.318014) (xy 514.868445 -453.256963)
			(xy 514.745294 -453.188901) (xy 514.626154 -453.11404) (xy 514.511398 -453.032616) (xy 514.401389 -452.944887)
			(xy 514.296471 -452.851127) (xy 514.196976 -452.751632) (xy 514.103216 -452.646714) (xy 514.015486 -452.536705)
			(xy 513.934063 -452.421949) (xy 513.859201 -452.302809) (xy 513.791138 -452.179659) (xy 513.730087 -452.052886)
			(xy 513.676241 -451.922889) (xy 513.629768 -451.790078) (xy 513.590815 -451.65487) (xy 513.559504 -451.51769)
			(xy 513.535934 -451.378971) (xy 513.520179 -451.239148) (xy 513.512289 -451.098662) (xy 513.5118 -451.028308)
			(xy 513.5118 -312.408316) (xy 513.512284 -312.337962) (xy 513.520173 -312.197474) (xy 513.535926 -312.05765)
			(xy 513.559495 -311.91893) (xy 513.590805 -311.781749) (xy 513.629757 -311.646539) (xy 513.676229 -311.513726)
			(xy 513.730076 -311.383728) (xy 513.791126 -311.256954) (xy 513.859189 -311.133802) (xy 513.93405 -311.01466)
			(xy 514.015474 -310.899903) (xy 514.103203 -310.789893) (xy 514.196964 -310.684974) (xy 514.296459 -310.585477)
			(xy 514.401377 -310.491716) (xy 514.511387 -310.403986) (xy 514.626144 -310.322561) (xy 514.745285 -310.247699)
			(xy 514.868436 -310.179635) (xy 514.99521 -310.118584) (xy 515.125208 -310.064737) (xy 515.25802 -310.018263)
			(xy 515.393229 -309.97931) (xy 515.53041 -309.947999) (xy 515.669131 -309.924429) (xy 515.808954 -309.908674)
			(xy 515.949442 -309.900784) (xy 516.019796 -309.90032) (xy 531.7998 -309.90032) (xy 531.855607 -309.899798)
			(xy 531.96691 -309.891457) (xy 532.077278 -309.874822) (xy 532.186094 -309.849986) (xy 532.292751 -309.817087)
			(xy 532.39665 -309.77631) (xy 532.497211 -309.727883) (xy 532.593873 -309.672076) (xy 532.686094 -309.609202)
			(xy 532.773358 -309.539612) (xy 532.855178 -309.463695) (xy 532.931096 -309.381876) (xy 533.000687 -309.294613)
			(xy 533.063563 -309.202393) (xy 533.119372 -309.105733) (xy 533.167801 -309.005172) (xy 533.208579 -308.901273)
			(xy 533.24148 -308.794618) (xy 533.266318 -308.685802) (xy 533.282955 -308.575434) (xy 533.291297 -308.464131)
			(xy 533.291796 -308.408324) (xy 533.291796 10.40003) (xy 533.291273 10.455836) (xy 533.28293 10.567137)
			(xy 533.266293 10.677502) (xy 533.241455 10.786316) (xy 533.208555 10.89297) (xy 533.167777 10.996866)
			(xy 533.119348 11.097425) (xy 533.063541 11.194084) (xy 533.000666 11.286302) (xy 532.931076 11.373563)
			(xy 532.855159 11.45538) (xy 532.77334 11.531295) (xy 532.686078 11.600884) (xy 532.593858 11.663757)
			(xy 532.497199 11.719562) (xy 532.396639 11.767989) (xy 532.292741 11.808765) (xy 532.186087 11.841663)
			(xy 532.077273 11.866499) (xy 531.966907 11.883134) (xy 531.855606 11.891474) (xy 531.7998 11.892026)
			(xy 475.799912 11.892026) (xy 475.744104 11.891505) (xy 475.632801 11.883165) (xy 475.522432 11.86653)
			(xy 475.413615 11.841695) (xy 475.306958 11.808796) (xy 475.203057 11.76802) (xy 475.102495 11.719593)
			(xy 475.005832 11.663786) (xy 474.91361 11.600912) (xy 474.826345 11.531322) (xy 474.744524 11.455406)
			(xy 474.668605 11.373587) (xy 474.599013 11.286323) (xy 474.536136 11.194103) (xy 474.480327 11.097442)
			(xy 474.431897 10.996881) (xy 474.391117 10.892982) (xy 474.358216 10.786326) (xy 474.333378 10.677509)
			(xy 474.31674 10.567141) (xy 474.308397 10.455838) (xy 474.307916 10.40003) (xy 474.307916 7.335466)
			(xy 526.704041 7.335466) (xy 526.704041 7.464606) (xy 526.711991 7.593501) (xy 526.727861 7.721661)
			(xy 526.75159 7.848602) (xy 526.783089 7.973841) (xy 526.822238 8.096904) (xy 526.868889 8.217323)
			(xy 526.922864 8.334642) (xy 526.983959 8.448416) (xy 527.051942 8.558213) (xy 527.126556 8.663616)
			(xy 527.207517 8.764226) (xy 527.294517 8.859661) (xy 527.387228 8.94956) (xy 527.485298 9.033581)
			(xy 527.588353 9.111405) (xy 527.696004 9.182737) (xy 527.807843 9.247307) (xy 527.923444 9.304869)
			(xy 528.042369 9.355206) (xy 528.164168 9.398126) (xy 528.288378 9.433467) (xy 528.414527 9.461094)
			(xy 528.542139 9.480903) (xy 528.670728 9.492819) (xy 528.799806 9.496796) (xy 528.928884 9.492819)
			(xy 529.057473 9.480903) (xy 529.185085 9.461094) (xy 529.311234 9.433467) (xy 529.435444 9.398126)
			(xy 529.557243 9.355206) (xy 529.676168 9.304869) (xy 529.791769 9.247307) (xy 529.903608 9.182737)
			(xy 530.011259 9.111405) (xy 530.114314 9.033581) (xy 530.212384 8.94956) (xy 530.305095 8.859661)
			(xy 530.392095 8.764226) (xy 530.473056 8.663616) (xy 530.54767 8.558213) (xy 530.615653 8.448416)
			(xy 530.676748 8.334642) (xy 530.730723 8.217323) (xy 530.777374 8.096904) (xy 530.816523 7.973841)
			(xy 530.848022 7.848602) (xy 530.871751 7.721661) (xy 530.887621 7.593501) (xy 530.895571 7.464606)
			(xy 530.896068 7.400036) (xy 530.895571 7.335466) (xy 530.887621 7.206571) (xy 530.871751 7.078411)
			(xy 530.848022 6.95147) (xy 530.816523 6.826231) (xy 530.777374 6.703168) (xy 530.730723 6.582749)
			(xy 530.676748 6.46543) (xy 530.615653 6.351656) (xy 530.54767 6.241859) (xy 530.473056 6.136456)
			(xy 530.392095 6.035846) (xy 530.305095 5.940411) (xy 530.212384 5.850512) (xy 530.114314 5.766491)
			(xy 530.011259 5.688667) (xy 529.903608 5.617335) (xy 529.791769 5.552765) (xy 529.676168 5.495203)
			(xy 529.557243 5.444866) (xy 529.435444 5.401946) (xy 529.311234 5.366605) (xy 529.185085 5.338978)
			(xy 529.057473 5.319169) (xy 528.928884 5.307253) (xy 528.799806 5.303277) (xy 528.670728 5.307253)
			(xy 528.542139 5.319169) (xy 528.414527 5.338978) (xy 528.288378 5.366605) (xy 528.164168 5.401946)
			(xy 528.042369 5.444866) (xy 527.923444 5.495203) (xy 527.807843 5.552765) (xy 527.696004 5.617335)
			(xy 527.588353 5.688667) (xy 527.485298 5.766491) (xy 527.387228 5.850512) (xy 527.294517 5.940411)
			(xy 527.207517 6.035846) (xy 527.126556 6.136456) (xy 527.051942 6.241859) (xy 526.983959 6.351656)
			(xy 526.922864 6.46543) (xy 526.868889 6.582749) (xy 526.822238 6.703168) (xy 526.783089 6.826231)
			(xy 526.75159 6.95147) (xy 526.727861 7.078411) (xy 526.711991 7.206571) (xy 526.704041 7.335466)
			(xy 474.307916 7.335466) (xy 474.307916 -77.67193) (xy 474.307428 -77.765094) (xy 474.299715 -77.951262)
			(xy 474.284317 -78.136953) (xy 474.261258 -78.321849) (xy 474.23058 -78.505634) (xy 474.192333 -78.687994)
			(xy 474.146584 -78.868619) (xy 474.093411 -79.047199) (xy 474.032904 -79.223429) (xy 473.965167 -79.397008)
			(xy 473.890315 -79.56764) (xy 473.808477 -79.735034) (xy 473.719792 -79.898903) (xy 473.624411 -80.058968)
			(xy 473.522498 -80.214955) (xy 473.414227 -80.366597) (xy 473.299782 -80.513637) (xy 473.17936 -80.655821)
			(xy 473.053165 -80.792909) (xy 472.987624 -80.859122) (xy 471.245184 -82.601562) (xy 471.207836 -82.63956)
			(xy 471.138049 -82.720082) (xy 471.074185 -82.805378) (xy 471.01657 -82.895014) (xy 470.965496 -82.988531)
			(xy 470.921226 -83.085455) (xy 470.883983 -83.18529) (xy 470.853958 -83.287527) (xy 470.831304 -83.391646)
			(xy 470.816136 -83.497117) (xy 470.808532 -83.6034) (xy 470.80805 -83.656678) (xy 470.80805 -404.871936)
			(xy 470.807562 -404.9651) (xy 470.799849 -405.151268) (xy 470.78445 -405.336959) (xy 470.761392 -405.521855)
			(xy 470.730713 -405.70564) (xy 470.692467 -405.888001) (xy 470.646718 -406.068625) (xy 470.593544 -406.247205)
			(xy 470.533038 -406.423435) (xy 470.465301 -406.597015) (xy 470.39045 -406.767647) (xy 470.308612 -406.935041)
			(xy 470.219927 -407.098911) (xy 470.124547 -407.258976) (xy 470.022634 -407.414963) (xy 469.914363 -407.566606)
			(xy 469.799919 -407.713645) (xy 469.679497 -407.855831) (xy 469.553302 -407.992919) (xy 469.487758 -408.059128)
			(xy 468.244936 -409.30195) (xy 468.207612 -409.339964) (xy 468.137859 -409.4205) (xy 468.074028 -409.505805)
			(xy 468.016443 -409.595446) (xy 467.965398 -409.688966) (xy 467.921153 -409.785888) (xy 467.883933 -409.885719)
			(xy 467.853928 -409.98795) (xy 467.831291 -410.092061) (xy 467.816137 -410.197522) (xy 467.808543 -410.303794)
			(xy 467.808056 -410.357066) (xy 467.808056 -439.989976) (xy 467.808577 -440.045784) (xy 467.816916 -440.157089)
			(xy 467.83355 -440.267459) (xy 467.858385 -440.376277) (xy 467.891282 -440.482936) (xy 467.932058 -440.586837)
			(xy 467.980485 -440.687401) (xy 468.036291 -440.784065) (xy 468.099165 -440.876289) (xy 468.168754 -440.963556)
			(xy 468.244671 -441.045378) (xy 468.32649 -441.121299) (xy 468.413753 -441.190893) (xy 468.505974 -441.253771)
			(xy 468.602635 -441.309582) (xy 468.703197 -441.358013) (xy 468.807096 -441.398794) (xy 468.913753 -441.431697)
			(xy 469.02257 -441.456537) (xy 469.13294 -441.473176) (xy 469.244244 -441.48152) (xy 469.300052 -441.481972)
			(xy 471.79992 -441.481972) (xy 471.870274 -441.482466) (xy 472.01076 -441.490356) (xy 472.150582 -441.506112)
			(xy 472.289302 -441.529682) (xy 472.426481 -441.560993) (xy 472.561689 -441.599946) (xy 472.6945 -441.646419)
			(xy 472.824497 -441.700266) (xy 472.95127 -441.761317) (xy 473.07442 -441.82938) (xy 473.19356 -441.904241)
			(xy 473.308316 -441.985664) (xy 473.418325 -442.073394) (xy 473.523243 -442.167153) (xy 473.622738 -442.266648)
			(xy 473.716499 -442.371565) (xy 473.804229 -442.481575) (xy 473.885652 -442.59633) (xy 473.960514 -442.71547)
			(xy 474.028578 -442.83862) (xy 474.089629 -442.965392) (xy 474.143476 -443.095389) (xy 474.18995 -443.2282)
			(xy 474.228904 -443.363407) (xy 474.260216 -443.500587) (xy 474.283787 -443.639306) (xy 474.299543 -443.779128)
			(xy 474.307434 -443.919614) (xy 474.307916 -443.989968) (xy 474.307916 -458.092864) (xy 526.704041 -458.092864)
			(xy 526.704041 -457.963724) (xy 526.711991 -457.834829) (xy 526.727861 -457.706669) (xy 526.75159 -457.579728)
			(xy 526.783089 -457.454489) (xy 526.822238 -457.331426) (xy 526.868889 -457.211007) (xy 526.922864 -457.093688)
			(xy 526.983959 -456.979914) (xy 527.051942 -456.870117) (xy 527.126556 -456.764714) (xy 527.207517 -456.664104)
			(xy 527.294517 -456.568669) (xy 527.387228 -456.47877) (xy 527.485298 -456.394749) (xy 527.588353 -456.316925)
			(xy 527.696004 -456.245593) (xy 527.807843 -456.181023) (xy 527.923444 -456.123461) (xy 528.042369 -456.073124)
			(xy 528.164168 -456.030204) (xy 528.288378 -455.994863) (xy 528.414527 -455.967236) (xy 528.542139 -455.947427)
			(xy 528.670728 -455.935511) (xy 528.799806 -455.931535) (xy 528.928884 -455.935511) (xy 529.057473 -455.947427)
			(xy 529.185085 -455.967236) (xy 529.311234 -455.994863) (xy 529.435444 -456.030204) (xy 529.557243 -456.073124)
			(xy 529.676168 -456.123461) (xy 529.791769 -456.181023) (xy 529.903608 -456.245593) (xy 530.011259 -456.316925)
			(xy 530.114314 -456.394749) (xy 530.212384 -456.47877) (xy 530.305095 -456.568669) (xy 530.392095 -456.664104)
			(xy 530.473056 -456.764714) (xy 530.54767 -456.870117) (xy 530.615653 -456.979914) (xy 530.676748 -457.093688)
			(xy 530.730723 -457.211007) (xy 530.777374 -457.331426) (xy 530.816523 -457.454489) (xy 530.848022 -457.579728)
			(xy 530.871751 -457.706669) (xy 530.887621 -457.834829) (xy 530.895571 -457.963724) (xy 530.896068 -458.028294)
			(xy 530.895571 -458.092864) (xy 530.887621 -458.221759) (xy 530.871751 -458.349919) (xy 530.848022 -458.47686)
			(xy 530.816523 -458.602099) (xy 530.777374 -458.725162) (xy 530.730723 -458.845581) (xy 530.676748 -458.9629)
			(xy 530.615653 -459.076674) (xy 530.54767 -459.186471) (xy 530.473056 -459.291874) (xy 530.392095 -459.392484)
			(xy 530.305095 -459.487919) (xy 530.212384 -459.577818) (xy 530.114314 -459.661839) (xy 530.011259 -459.739663)
			(xy 529.903608 -459.810995) (xy 529.791769 -459.875565) (xy 529.676168 -459.933127) (xy 529.557243 -459.983464)
			(xy 529.435444 -460.026384) (xy 529.311234 -460.061725) (xy 529.185085 -460.089352) (xy 529.057473 -460.109161)
			(xy 528.928884 -460.121077) (xy 528.799806 -460.125054) (xy 528.670728 -460.121077) (xy 528.542139 -460.109161)
			(xy 528.414527 -460.089352) (xy 528.288378 -460.061725) (xy 528.164168 -460.026384) (xy 528.042369 -459.983464)
			(xy 527.923444 -459.933127) (xy 527.807843 -459.875565) (xy 527.696004 -459.810995) (xy 527.588353 -459.739663)
			(xy 527.485298 -459.661839) (xy 527.387228 -459.577818) (xy 527.294517 -459.487919) (xy 527.207517 -459.392484)
			(xy 527.126556 -459.291874) (xy 527.051942 -459.186471) (xy 526.983959 -459.076674) (xy 526.922864 -458.9629)
			(xy 526.868889 -458.845581) (xy 526.822238 -458.725162) (xy 526.783089 -458.602099) (xy 526.75159 -458.47686)
			(xy 526.727861 -458.349919) (xy 526.711991 -458.221759) (xy 526.704041 -458.092864) (xy 474.307916 -458.092864)
			(xy 474.307916 -461.028288) (xy 474.308425 -461.084096) (xy 474.316765 -461.195399) (xy 474.3334 -461.305768)
			(xy 474.358236 -461.414584) (xy 474.391134 -461.521241) (xy 474.431912 -461.625141) (xy 474.480339 -461.725703)
			(xy 474.536147 -461.822365) (xy 474.599022 -461.914586) (xy 474.668612 -462.00185) (xy 474.74453 -462.08367)
			(xy 474.82635 -462.159588) (xy 474.913614 -462.229178) (xy 475.005835 -462.292053) (xy 475.102497 -462.347861)
			(xy 475.203059 -462.396288) (xy 475.306959 -462.437066) (xy 475.413616 -462.469964) (xy 475.522432 -462.4948)
			(xy 475.632801 -462.511435) (xy 475.744104 -462.519775) (xy 475.799912 -462.520284)
		)
		(stroke
			(width 0)
			(type solid)
		)
		(fill yes)
		(layer "In3.Cu")
		(net "T1_GND")
	)
	(gr_poly
		(pts
			(xy 256.292096 -31.120588) (xy 256.292096 -11.780012) (xy 256.29258 -11.709658) (xy 256.300469 -11.56917)
			(xy 256.316223 -11.429347) (xy 256.339792 -11.290626) (xy 256.371101 -11.153445) (xy 256.410054 -11.018236)
			(xy 256.456527 -10.885423) (xy 256.510373 -10.755425) (xy 256.571423 -10.628651) (xy 256.639486 -10.505499)
			(xy 256.714347 -10.386357) (xy 256.795771 -10.2716) (xy 256.883501 -10.16159) (xy 256.977261 -10.056671)
			(xy 257.076757 -9.957175) (xy 257.181674 -9.863414) (xy 257.291684 -9.775683) (xy 257.406441 -9.694258)
			(xy 257.525582 -9.619396) (xy 257.648733 -9.551333) (xy 257.775507 -9.490281) (xy 257.905504 -9.436434)
			(xy 258.038317 -9.38996) (xy 258.173526 -9.351006) (xy 258.310706 -9.319695) (xy 258.449427 -9.296125)
			(xy 258.589251 -9.280371) (xy 258.729738 -9.272481) (xy 258.800092 -9.272016) (xy 383.601976 -9.272016)
			(xy 383.657784 -9.271508) (xy 383.769089 -9.263168) (xy 383.879459 -9.246534) (xy 383.988278 -9.221699)
			(xy 384.094936 -9.188801) (xy 384.198838 -9.148025) (xy 384.299402 -9.099598) (xy 384.396066 -9.043791)
			(xy 384.488289 -8.980916) (xy 384.575555 -8.911326) (xy 384.657377 -8.835408) (xy 384.733297 -8.753588)
			(xy 384.80289 -8.666324) (xy 384.865767 -8.574103) (xy 384.921577 -8.477441) (xy 384.970007 -8.376878)
			(xy 385.010787 -8.272978) (xy 385.043688 -8.16632) (xy 385.068526 -8.057503) (xy 385.085163 -7.947133)
			(xy 385.093506 -7.835828) (xy 385.093972 -7.78002) (xy 385.093972 0.999998) (xy 385.094465 1.070352)
			(xy 385.102355 1.210839) (xy 385.118109 1.350662) (xy 385.141678 1.489383) (xy 385.172988 1.626563)
			(xy 385.211941 1.761772) (xy 385.258413 1.894584) (xy 385.312259 2.024582) (xy 385.37331 2.151356)
			(xy 385.441373 2.274507) (xy 385.516233 2.393649) (xy 385.597656 2.508405) (xy 385.685386 2.618416)
			(xy 385.779146 2.723335) (xy 385.878641 2.822831) (xy 385.983558 2.916592) (xy 386.093567 3.004323)
			(xy 386.208323 3.085748) (xy 386.327463 3.16061) (xy 386.450614 3.228674) (xy 386.577387 3.289727)
			(xy 386.707384 3.343575) (xy 386.840195 3.390049) (xy 386.975404 3.429003) (xy 387.112584 3.460315)
			(xy 387.251304 3.483887) (xy 387.391127 3.499643) (xy 387.531614 3.507534) (xy 387.601968 3.507994)
			(xy 456.202034 3.507994) (xy 456.272387 3.5075) (xy 456.412872 3.499608) (xy 456.552693 3.483853)
			(xy 456.691411 3.460282) (xy 456.828589 3.42897) (xy 456.963796 3.390016) (xy 457.096605 3.343542)
			(xy 457.226601 3.289695) (xy 457.353372 3.228644) (xy 457.476521 3.16058) (xy 457.595659 3.085719)
			(xy 457.710413 3.004295) (xy 457.820421 2.916565) (xy 457.925337 2.822806) (xy 458.02483 2.723311)
			(xy 458.118589 2.618393) (xy 458.206317 2.508384) (xy 458.287739 2.393629) (xy 458.362598 2.27449)
			(xy 458.43066 2.15134) (xy 458.49171 2.024568) (xy 458.545555 1.894572) (xy 458.592027 1.761761)
			(xy 458.630979 1.626554) (xy 458.662289 1.489376) (xy 458.685858 1.350658) (xy 458.701612 1.210836)
			(xy 458.709501 1.070351) (xy 458.71003 0.999998) (xy 458.71003 -7.78002) (xy 458.71054 -7.835827)
			(xy 458.718882 -7.947128) (xy 458.735519 -8.057494) (xy 458.760357 -8.166309) (xy 458.793257 -8.272963)
			(xy 458.834035 -8.37686) (xy 458.882464 -8.47742) (xy 458.938272 -8.574079) (xy 459.001148 -8.666297)
			(xy 459.070739 -8.753559) (xy 459.146656 -8.835376) (xy 459.228476 -8.911291) (xy 459.31574 -8.98088)
			(xy 459.40796 -9.043752) (xy 459.504621 -9.099557) (xy 459.605182 -9.147983) (xy 459.70908 -9.188758)
			(xy 459.815736 -9.221655) (xy 459.924551 -9.24649) (xy 460.034918 -9.263123) (xy 460.146219 -9.271462)
			(xy 460.202026 -9.272016) (xy 464.327748 -9.272016) (xy 464.332574 -9.271) (xy 464.357024 -9.266474)
			(xy 464.406516 -9.261643) (xy 464.43138 -9.261348) (xy 464.456244 -9.26164) (xy 464.505735 -9.266479)
			(xy 464.530186 -9.271) (xy 464.535012 -9.272016) (xy 469.799924 -9.272016) (xy 469.855731 -9.271493)
			(xy 469.967032 -9.263151) (xy 470.077399 -9.246514) (xy 470.186213 -9.221677) (xy 470.292868 -9.188777)
			(xy 470.396765 -9.147999) (xy 470.497325 -9.099571) (xy 470.593985 -9.043764) (xy 470.686204 -8.980889)
			(xy 470.773467 -8.911299) (xy 470.855285 -8.835382) (xy 470.931202 -8.753564) (xy 471.000791 -8.666301)
			(xy 471.063666 -8.574082) (xy 471.119473 -8.477422) (xy 471.167901 -8.376862) (xy 471.208678 -8.272964)
			(xy 471.241578 -8.166309) (xy 471.266415 -8.057495) (xy 471.283051 -7.947128) (xy 471.291394 -7.835827)
			(xy 471.29192 -7.78002) (xy 471.29192 10.40003) (xy 471.291397 10.455837) (xy 471.283054 10.567138)
			(xy 471.266417 10.677504) (xy 471.241579 10.786319) (xy 471.208679 10.892973) (xy 471.167901 10.99687)
			(xy 471.119473 11.09743) (xy 471.063666 11.194089) (xy 471.000791 11.286308) (xy 470.931201 11.373571)
			(xy 470.855284 11.455389) (xy 470.773466 11.531305) (xy 470.686203 11.600895) (xy 470.593984 11.663769)
			(xy 470.497324 11.719576) (xy 470.396765 11.768004) (xy 470.292867 11.808781) (xy 470.186213 11.841681)
			(xy 470.077398 11.866518) (xy 469.967032 11.883155) (xy 469.855731 11.891497) (xy 469.799924 11.892026)
			(xy 1.999996 11.892026) (xy 1.944189 11.891504) (xy 1.832887 11.883163) (xy 1.72252 11.866527) (xy 1.613705 11.841691)
			(xy 1.50705 11.808792) (xy 1.403151 11.768014) (xy 1.302591 11.719587) (xy 1.20593 11.66378) (xy 1.113711 11.600905)
			(xy 1.026448 11.531315) (xy 0.944629 11.455398) (xy 0.868712 11.373579) (xy 0.799122 11.286316) (xy 0.736248 11.194096)
			(xy 0.680441 11.097436) (xy 0.632014 10.996875) (xy 0.591237 10.892977) (xy 0.558338 10.786321) (xy 0.533502 10.677506)
			(xy 0.516867 10.567139) (xy 0.508526 10.455837) (xy 0.508 10.40003) (xy 0.508 7.335466) (xy 2.904225 7.335466)
			(xy 2.904225 7.464606) (xy 2.912175 7.593501) (xy 2.928045 7.721661) (xy 2.951774 7.848602) (xy 2.983273 7.973841)
			(xy 3.022422 8.096904) (xy 3.069073 8.217323) (xy 3.123048 8.334642) (xy 3.184143 8.448416) (xy 3.252126 8.558213)
			(xy 3.32674 8.663616) (xy 3.407701 8.764226) (xy 3.494701 8.859661) (xy 3.587412 8.94956) (xy 3.685482 9.033581)
			(xy 3.788537 9.111405) (xy 3.896188 9.182737) (xy 4.008027 9.247307) (xy 4.123628 9.304869) (xy 4.242553 9.355206)
			(xy 4.364352 9.398126) (xy 4.488562 9.433467) (xy 4.614711 9.461094) (xy 4.742323 9.480903) (xy 4.870912 9.492819)
			(xy 4.99999 9.496796) (xy 5.129068 9.492819) (xy 5.257657 9.480903) (xy 5.385269 9.461094) (xy 5.511418 9.433467)
			(xy 5.635628 9.398126) (xy 5.757427 9.355206) (xy 5.876352 9.304869) (xy 5.991953 9.247307) (xy 6.020338 9.230919)
			(xy 256.921241 9.230919) (xy 256.921241 9.316669) (xy 256.929153 9.402052) (xy 256.944909 9.486342)
			(xy 256.968376 9.568818) (xy 256.999352 9.648777) (xy 257.037574 9.725537) (xy 257.082715 9.798443)
			(xy 257.134391 9.866872) (xy 257.19216 9.930242) (xy 257.25553 9.988011) (xy 257.323959 10.039687)
			(xy 257.396865 10.084828) (xy 257.473625 10.12305) (xy 257.553584 10.154026) (xy 257.63606 10.177493)
			(xy 257.72035 10.193249) (xy 257.805733 10.201161) (xy 257.891483 10.201161) (xy 257.976866 10.193249)
			(xy 258.061156 10.177493) (xy 258.143632 10.154026) (xy 258.223591 10.12305) (xy 258.300351 10.084828)
			(xy 258.373257 10.039687) (xy 258.441686 9.988011) (xy 258.505056 9.930242) (xy 258.562825 9.866872)
			(xy 258.614501 9.798443) (xy 258.659642 9.725537) (xy 258.697864 9.648777) (xy 258.72884 9.568818)
			(xy 258.752307 9.486342) (xy 258.768063 9.402052) (xy 258.775975 9.316669) (xy 258.77647 9.273794)
			(xy 258.775975 9.230919) (xy 263.271241 9.230919) (xy 263.271241 9.316669) (xy 263.279153 9.402052)
			(xy 263.294909 9.486342) (xy 263.318376 9.568818) (xy 263.349352 9.648777) (xy 263.387574 9.725537)
			(xy 263.432715 9.798443) (xy 263.484391 9.866872) (xy 263.54216 9.930242) (xy 263.60553 9.988011)
			(xy 263.673959 10.039687) (xy 263.746865 10.084828) (xy 263.823625 10.12305) (xy 263.903584 10.154026)
			(xy 263.98606 10.177493) (xy 264.07035 10.193249) (xy 264.155733 10.201161) (xy 264.241483 10.201161)
			(xy 264.326866 10.193249) (xy 264.411156 10.177493) (xy 264.493632 10.154026) (xy 264.573591 10.12305)
			(xy 264.650351 10.084828) (xy 264.723257 10.039687) (xy 264.791686 9.988011) (xy 264.855056 9.930242)
			(xy 264.912825 9.866872) (xy 264.964501 9.798443) (xy 265.009642 9.725537) (xy 265.047864 9.648777)
			(xy 265.07884 9.568818) (xy 265.102307 9.486342) (xy 265.118063 9.402052) (xy 265.125975 9.316669)
			(xy 265.12647 9.273794) (xy 265.125975 9.230919) (xy 324.845921 9.230919) (xy 324.845921 9.316669)
			(xy 324.853833 9.402052) (xy 324.869589 9.486342) (xy 324.893056 9.568818) (xy 324.924032 9.648777)
			(xy 324.962254 9.725537) (xy 325.007395 9.798443) (xy 325.059071 9.866872) (xy 325.11684 9.930242)
			(xy 325.18021 9.988011) (xy 325.248639 10.039687) (xy 325.321545 10.084828) (xy 325.398305 10.12305)
			(xy 325.478264 10.154026) (xy 325.56074 10.177493) (xy 325.64503 10.193249) (xy 325.730413 10.201161)
			(xy 325.816163 10.201161) (xy 325.901546 10.193249) (xy 325.985836 10.177493) (xy 326.068312 10.154026)
			(xy 326.148271 10.12305) (xy 326.225031 10.084828) (xy 326.297937 10.039687) (xy 326.366366 9.988011)
			(xy 326.429736 9.930242) (xy 326.487505 9.866872) (xy 326.539181 9.798443) (xy 326.584322 9.725537)
			(xy 326.622544 9.648777) (xy 326.65352 9.568818) (xy 326.676987 9.486342) (xy 326.692743 9.402052)
			(xy 326.700655 9.316669) (xy 326.70115 9.273794) (xy 326.700655 9.230919) (xy 331.195921 9.230919)
			(xy 331.195921 9.316669) (xy 331.203833 9.402052) (xy 331.219589 9.486342) (xy 331.243056 9.568818)
			(xy 331.274032 9.648777) (xy 331.312254 9.725537) (xy 331.357395 9.798443) (xy 331.409071 9.866872)
			(xy 331.46684 9.930242) (xy 331.53021 9.988011) (xy 331.598639 10.039687) (xy 331.671545 10.084828)
			(xy 331.748305 10.12305) (xy 331.828264 10.154026) (xy 331.91074 10.177493) (xy 331.99503 10.193249)
			(xy 332.080413 10.201161) (xy 332.166163 10.201161) (xy 332.251546 10.193249) (xy 332.335836 10.177493)
			(xy 332.418312 10.154026) (xy 332.498271 10.12305) (xy 332.575031 10.084828) (xy 332.647937 10.039687)
			(xy 332.716366 9.988011) (xy 332.779736 9.930242) (xy 332.837505 9.866872) (xy 332.889181 9.798443)
			(xy 332.934322 9.725537) (xy 332.972544 9.648777) (xy 333.00352 9.568818) (xy 333.026987 9.486342)
			(xy 333.042743 9.402052) (xy 333.050655 9.316669) (xy 333.05115 9.273794) (xy 333.050655 9.230919)
			(xy 335.488267 9.230919) (xy 335.488267 9.316669) (xy 335.496179 9.402052) (xy 335.511935 9.486342)
			(xy 335.535402 9.568818) (xy 335.566378 9.648777) (xy 335.6046 9.725537) (xy 335.649741 9.798443)
			(xy 335.701417 9.866872) (xy 335.759186 9.930242) (xy 335.822556 9.988011) (xy 335.890985 10.039687)
			(xy 335.963891 10.084828) (xy 336.040651 10.12305) (xy 336.12061 10.154026) (xy 336.203086 10.177493)
			(xy 336.287376 10.193249) (xy 336.372759 10.201161) (xy 336.458509 10.201161) (xy 336.543892 10.193249)
			(xy 336.628182 10.177493) (xy 336.710658 10.154026) (xy 336.790617 10.12305) (xy 336.867377 10.084828)
			(xy 336.940283 10.039687) (xy 337.008712 9.988011) (xy 337.072082 9.930242) (xy 337.129851 9.866872)
			(xy 337.181527 9.798443) (xy 337.226668 9.725537) (xy 337.26489 9.648777) (xy 337.295866 9.568818)
			(xy 337.319333 9.486342) (xy 337.335089 9.402052) (xy 337.343001 9.316669) (xy 337.343496 9.273794)
			(xy 337.343001 9.230919) (xy 341.838267 9.230919) (xy 341.838267 9.316669) (xy 341.846179 9.402052)
			(xy 341.861935 9.486342) (xy 341.885402 9.568818) (xy 341.916378 9.648777) (xy 341.9546 9.725537)
			(xy 341.999741 9.798443) (xy 342.051417 9.866872) (xy 342.109186 9.930242) (xy 342.172556 9.988011)
			(xy 342.240985 10.039687) (xy 342.313891 10.084828) (xy 342.390651 10.12305) (xy 342.47061 10.154026)
			(xy 342.553086 10.177493) (xy 342.637376 10.193249) (xy 342.722759 10.201161) (xy 342.808509 10.201161)
			(xy 342.893892 10.193249) (xy 342.978182 10.177493) (xy 343.060658 10.154026) (xy 343.140617 10.12305)
			(xy 343.217377 10.084828) (xy 343.290283 10.039687) (xy 343.358712 9.988011) (xy 343.422082 9.930242)
			(xy 343.479851 9.866872) (xy 343.531527 9.798443) (xy 343.576668 9.725537) (xy 343.61489 9.648777)
			(xy 343.645866 9.568818) (xy 343.669333 9.486342) (xy 343.685089 9.402052) (xy 343.693001 9.316669)
			(xy 343.693496 9.273794) (xy 343.693001 9.230919) (xy 373.705107 9.230919) (xy 373.705107 9.316669)
			(xy 373.713019 9.402052) (xy 373.728775 9.486342) (xy 373.752242 9.568818) (xy 373.783218 9.648777)
			(xy 373.82144 9.725537) (xy 373.866581 9.798443) (xy 373.918257 9.866872) (xy 373.976026 9.930242)
			(xy 374.039396 9.988011) (xy 374.107825 10.039687) (xy 374.180731 10.084828) (xy 374.257491 10.12305)
			(xy 374.33745 10.154026) (xy 374.419926 10.177493) (xy 374.504216 10.193249) (xy 374.589599 10.201161)
			(xy 374.675349 10.201161) (xy 374.760732 10.193249) (xy 374.845022 10.177493) (xy 374.927498 10.154026)
			(xy 375.007457 10.12305) (xy 375.084217 10.084828) (xy 375.157123 10.039687) (xy 375.225552 9.988011)
			(xy 375.288922 9.930242) (xy 375.346691 9.866872) (xy 375.398367 9.798443) (xy 375.443508 9.725537)
			(xy 375.48173 9.648777) (xy 375.512706 9.568818) (xy 375.536173 9.486342) (xy 375.551929 9.402052)
			(xy 375.559841 9.316669) (xy 375.560336 9.273794) (xy 375.559841 9.230919) (xy 380.055107 9.230919)
			(xy 380.055107 9.316669) (xy 380.063019 9.402052) (xy 380.078775 9.486342) (xy 380.102242 9.568818)
			(xy 380.133218 9.648777) (xy 380.17144 9.725537) (xy 380.216581 9.798443) (xy 380.268257 9.866872)
			(xy 380.326026 9.930242) (xy 380.389396 9.988011) (xy 380.457825 10.039687) (xy 380.530731 10.084828)
			(xy 380.607491 10.12305) (xy 380.68745 10.154026) (xy 380.769926 10.177493) (xy 380.854216 10.193249)
			(xy 380.939599 10.201161) (xy 381.025349 10.201161) (xy 381.110732 10.193249) (xy 381.195022 10.177493)
			(xy 381.277498 10.154026) (xy 381.357457 10.12305) (xy 381.434217 10.084828) (xy 381.507123 10.039687)
			(xy 381.575552 9.988011) (xy 381.638922 9.930242) (xy 381.696691 9.866872) (xy 381.748367 9.798443)
			(xy 381.793508 9.725537) (xy 381.83173 9.648777) (xy 381.862706 9.568818) (xy 381.886173 9.486342)
			(xy 381.901929 9.402052) (xy 381.909841 9.316669) (xy 381.910336 9.273794) (xy 381.909841 9.230919)
			(xy 381.901929 9.145536) (xy 381.886173 9.061246) (xy 381.862706 8.97877) (xy 381.83173 8.898811)
			(xy 381.793508 8.822051) (xy 381.748367 8.749145) (xy 381.696691 8.680716) (xy 381.638922 8.617346)
			(xy 381.575552 8.559577) (xy 381.507123 8.507901) (xy 381.434217 8.46276) (xy 381.357457 8.424538)
			(xy 381.277498 8.393562) (xy 381.195022 8.370095) (xy 381.110732 8.354339) (xy 381.025349 8.346427)
			(xy 380.939599 8.346427) (xy 380.854216 8.354339) (xy 380.769926 8.370095) (xy 380.68745 8.393562)
			(xy 380.607491 8.424538) (xy 380.530731 8.46276) (xy 380.457825 8.507901) (xy 380.389396 8.559577)
			(xy 380.326026 8.617346) (xy 380.268257 8.680716) (xy 380.216581 8.749145) (xy 380.17144 8.822051)
			(xy 380.133218 8.898811) (xy 380.102242 8.97877) (xy 380.078775 9.061246) (xy 380.063019 9.145536)
			(xy 380.055107 9.230919) (xy 375.559841 9.230919) (xy 375.551929 9.145536) (xy 375.536173 9.061246)
			(xy 375.512706 8.97877) (xy 375.48173 8.898811) (xy 375.443508 8.822051) (xy 375.398367 8.749145)
			(xy 375.346691 8.680716) (xy 375.288922 8.617346) (xy 375.225552 8.559577) (xy 375.157123 8.507901)
			(xy 375.084217 8.46276) (xy 375.007457 8.424538) (xy 374.927498 8.393562) (xy 374.845022 8.370095)
			(xy 374.760732 8.354339) (xy 374.675349 8.346427) (xy 374.589599 8.346427) (xy 374.504216 8.354339)
			(xy 374.419926 8.370095) (xy 374.33745 8.393562) (xy 374.257491 8.424538) (xy 374.180731 8.46276)
			(xy 374.107825 8.507901) (xy 374.039396 8.559577) (xy 373.976026 8.617346) (xy 373.918257 8.680716)
			(xy 373.866581 8.749145) (xy 373.82144 8.822051) (xy 373.783218 8.898811) (xy 373.752242 8.97877)
			(xy 373.728775 9.061246) (xy 373.713019 9.145536) (xy 373.705107 9.230919) (xy 343.693001 9.230919)
			(xy 343.685089 9.145536) (xy 343.669333 9.061246) (xy 343.645866 8.97877) (xy 343.61489 8.898811)
			(xy 343.576668 8.822051) (xy 343.531527 8.749145) (xy 343.479851 8.680716) (xy 343.422082 8.617346)
			(xy 343.358712 8.559577) (xy 343.290283 8.507901) (xy 343.217377 8.46276) (xy 343.140617 8.424538)
			(xy 343.060658 8.393562) (xy 342.978182 8.370095) (xy 342.893892 8.354339) (xy 342.808509 8.346427)
			(xy 342.722759 8.346427) (xy 342.637376 8.354339) (xy 342.553086 8.370095) (xy 342.47061 8.393562)
			(xy 342.390651 8.424538) (xy 342.313891 8.46276) (xy 342.240985 8.507901) (xy 342.172556 8.559577)
			(xy 342.109186 8.617346) (xy 342.051417 8.680716) (xy 341.999741 8.749145) (xy 341.9546 8.822051)
			(xy 341.916378 8.898811) (xy 341.885402 8.97877) (xy 341.861935 9.061246) (xy 341.846179 9.145536)
			(xy 341.838267 9.230919) (xy 337.343001 9.230919) (xy 337.335089 9.145536) (xy 337.319333 9.061246)
			(xy 337.295866 8.97877) (xy 337.26489 8.898811) (xy 337.226668 8.822051) (xy 337.181527 8.749145)
			(xy 337.129851 8.680716) (xy 337.072082 8.617346) (xy 337.008712 8.559577) (xy 336.940283 8.507901)
			(xy 336.867377 8.46276) (xy 336.790617 8.424538) (xy 336.710658 8.393562) (xy 336.628182 8.370095)
			(xy 336.543892 8.354339) (xy 336.458509 8.346427) (xy 336.372759 8.346427) (xy 336.287376 8.354339)
			(xy 336.203086 8.370095) (xy 336.12061 8.393562) (xy 336.040651 8.424538) (xy 335.963891 8.46276)
			(xy 335.890985 8.507901) (xy 335.822556 8.559577) (xy 335.759186 8.617346) (xy 335.701417 8.680716)
			(xy 335.649741 8.749145) (xy 335.6046 8.822051) (xy 335.566378 8.898811) (xy 335.535402 8.97877)
			(xy 335.511935 9.061246) (xy 335.496179 9.145536) (xy 335.488267 9.230919) (xy 333.050655 9.230919)
			(xy 333.042743 9.145536) (xy 333.026987 9.061246) (xy 333.00352 8.97877) (xy 332.972544 8.898811)
			(xy 332.934322 8.822051) (xy 332.889181 8.749145) (xy 332.837505 8.680716) (xy 332.779736 8.617346)
			(xy 332.716366 8.559577) (xy 332.647937 8.507901) (xy 332.575031 8.46276) (xy 332.498271 8.424538)
			(xy 332.418312 8.393562) (xy 332.335836 8.370095) (xy 332.251546 8.354339) (xy 332.166163 8.346427)
			(xy 332.080413 8.346427) (xy 331.99503 8.354339) (xy 331.91074 8.370095) (xy 331.828264 8.393562)
			(xy 331.748305 8.424538) (xy 331.671545 8.46276) (xy 331.598639 8.507901) (xy 331.53021 8.559577)
			(xy 331.46684 8.617346) (xy 331.409071 8.680716) (xy 331.357395 8.749145) (xy 331.312254 8.822051)
			(xy 331.274032 8.898811) (xy 331.243056 8.97877) (xy 331.219589 9.061246) (xy 331.203833 9.145536)
			(xy 331.195921 9.230919) (xy 326.700655 9.230919) (xy 326.692743 9.145536) (xy 326.676987 9.061246)
			(xy 326.65352 8.97877) (xy 326.622544 8.898811) (xy 326.584322 8.822051) (xy 326.539181 8.749145)
			(xy 326.487505 8.680716) (xy 326.429736 8.617346) (xy 326.366366 8.559577) (xy 326.297937 8.507901)
			(xy 326.225031 8.46276) (xy 326.148271 8.424538) (xy 326.068312 8.393562) (xy 325.985836 8.370095)
			(xy 325.901546 8.354339) (xy 325.816163 8.346427) (xy 325.730413 8.346427) (xy 325.64503 8.354339)
			(xy 325.56074 8.370095) (xy 325.478264 8.393562) (xy 325.398305 8.424538) (xy 325.321545 8.46276)
			(xy 325.248639 8.507901) (xy 325.18021 8.559577) (xy 325.11684 8.617346) (xy 325.059071 8.680716)
			(xy 325.007395 8.749145) (xy 324.962254 8.822051) (xy 324.924032 8.898811) (xy 324.893056 8.97877)
			(xy 324.869589 9.061246) (xy 324.853833 9.145536) (xy 324.845921 9.230919) (xy 265.125975 9.230919)
			(xy 265.118063 9.145536) (xy 265.102307 9.061246) (xy 265.07884 8.97877) (xy 265.047864 8.898811)
			(xy 265.009642 8.822051) (xy 264.964501 8.749145) (xy 264.912825 8.680716) (xy 264.855056 8.617346)
			(xy 264.791686 8.559577) (xy 264.723257 8.507901) (xy 264.650351 8.46276) (xy 264.573591 8.424538)
			(xy 264.493632 8.393562) (xy 264.411156 8.370095) (xy 264.326866 8.354339) (xy 264.241483 8.346427)
			(xy 264.155733 8.346427) (xy 264.07035 8.354339) (xy 263.98606 8.370095) (xy 263.903584 8.393562)
			(xy 263.823625 8.424538) (xy 263.746865 8.46276) (xy 263.673959 8.507901) (xy 263.60553 8.559577)
			(xy 263.54216 8.617346) (xy 263.484391 8.680716) (xy 263.432715 8.749145) (xy 263.387574 8.822051)
			(xy 263.349352 8.898811) (xy 263.318376 8.97877) (xy 263.294909 9.061246) (xy 263.279153 9.145536)
			(xy 263.271241 9.230919) (xy 258.775975 9.230919) (xy 258.768063 9.145536) (xy 258.752307 9.061246)
			(xy 258.72884 8.97877) (xy 258.697864 8.898811) (xy 258.659642 8.822051) (xy 258.614501 8.749145)
			(xy 258.562825 8.680716) (xy 258.505056 8.617346) (xy 258.441686 8.559577) (xy 258.373257 8.507901)
			(xy 258.300351 8.46276) (xy 258.223591 8.424538) (xy 258.143632 8.393562) (xy 258.061156 8.370095)
			(xy 257.976866 8.354339) (xy 257.891483 8.346427) (xy 257.805733 8.346427) (xy 257.72035 8.354339)
			(xy 257.63606 8.370095) (xy 257.553584 8.393562) (xy 257.473625 8.424538) (xy 257.396865 8.46276)
			(xy 257.323959 8.507901) (xy 257.25553 8.559577) (xy 257.19216 8.617346) (xy 257.134391 8.680716)
			(xy 257.082715 8.749145) (xy 257.037574 8.822051) (xy 256.999352 8.898811) (xy 256.968376 8.97877)
			(xy 256.944909 9.061246) (xy 256.929153 9.145536) (xy 256.921241 9.230919) (xy 6.020338 9.230919)
			(xy 6.103792 9.182737) (xy 6.211443 9.111405) (xy 6.314498 9.033581) (xy 6.412568 8.94956) (xy 6.505279 8.859661)
			(xy 6.592279 8.764226) (xy 6.67324 8.663616) (xy 6.747854 8.558213) (xy 6.815837 8.448416) (xy 6.876932 8.334642)
			(xy 6.930907 8.217323) (xy 6.977558 8.096904) (xy 7.016707 7.973841) (xy 7.048206 7.848602) (xy 7.071935 7.721661)
			(xy 7.087805 7.593501) (xy 7.095755 7.464606) (xy 7.096252 7.400036) (xy 7.095755 7.335466) (xy 7.087805 7.206571)
			(xy 7.071935 7.078411) (xy 7.048206 6.95147) (xy 7.016707 6.826231) (xy 6.977558 6.703168) (xy 6.97173 6.688125)
			(xy 178.335673 6.688125) (xy 178.335673 6.773875) (xy 178.343585 6.859258) (xy 178.359341 6.943548)
			(xy 178.382808 7.026024) (xy 178.413784 7.105983) (xy 178.452006 7.182743) (xy 178.497147 7.255649)
			(xy 178.548823 7.324078) (xy 178.606592 7.387448) (xy 178.669962 7.445217) (xy 178.738391 7.496893)
			(xy 178.811297 7.542034) (xy 178.888057 7.580256) (xy 178.968016 7.611232) (xy 179.050492 7.634699)
			(xy 179.134782 7.650455) (xy 179.220165 7.658367) (xy 179.305915 7.658367) (xy 179.391298 7.650455)
			(xy 179.475588 7.634699) (xy 179.558064 7.611232) (xy 179.638023 7.580256) (xy 179.714783 7.542034)
			(xy 179.787689 7.496893) (xy 179.856118 7.445217) (xy 179.919488 7.387448) (xy 179.977257 7.324078)
			(xy 180.028933 7.255649) (xy 180.074074 7.182743) (xy 180.112296 7.105983) (xy 180.143272 7.026024)
			(xy 180.166739 6.943548) (xy 180.182495 6.859258) (xy 180.190407 6.773875) (xy 180.190902 6.731)
			(xy 180.190407 6.688125) (xy 184.685673 6.688125) (xy 184.685673 6.773875) (xy 184.693585 6.859258)
			(xy 184.709341 6.943548) (xy 184.732808 7.026024) (xy 184.763784 7.105983) (xy 184.802006 7.182743)
			(xy 184.847147 7.255649) (xy 184.898823 7.324078) (xy 184.956592 7.387448) (xy 185.019962 7.445217)
			(xy 185.088391 7.496893) (xy 185.161297 7.542034) (xy 185.238057 7.580256) (xy 185.318016 7.611232)
			(xy 185.400492 7.634699) (xy 185.484782 7.650455) (xy 185.570165 7.658367) (xy 185.655915 7.658367)
			(xy 185.741298 7.650455) (xy 185.825588 7.634699) (xy 185.908064 7.611232) (xy 185.988023 7.580256)
			(xy 186.064783 7.542034) (xy 186.137689 7.496893) (xy 186.206118 7.445217) (xy 186.269488 7.387448)
			(xy 186.327257 7.324078) (xy 186.378933 7.255649) (xy 186.424074 7.182743) (xy 186.462296 7.105983)
			(xy 186.493272 7.026024) (xy 186.516739 6.943548) (xy 186.532495 6.859258) (xy 186.540407 6.773875)
			(xy 186.540902 6.731) (xy 186.540407 6.688125) (xy 246.260353 6.688125) (xy 246.260353 6.773875)
			(xy 246.268265 6.859258) (xy 246.284021 6.943548) (xy 246.307488 7.026024) (xy 246.338464 7.105983)
			(xy 246.376686 7.182743) (xy 246.421827 7.255649) (xy 246.473503 7.324078) (xy 246.531272 7.387448)
			(xy 246.594642 7.445217) (xy 246.663071 7.496893) (xy 246.735977 7.542034) (xy 246.812737 7.580256)
			(xy 246.892696 7.611232) (xy 246.975172 7.634699) (xy 247.059462 7.650455) (xy 247.144845 7.658367)
			(xy 247.230595 7.658367) (xy 247.315978 7.650455) (xy 247.400268 7.634699) (xy 247.482744 7.611232)
			(xy 247.562703 7.580256) (xy 247.639463 7.542034) (xy 247.712369 7.496893) (xy 247.780798 7.445217)
			(xy 247.844168 7.387448) (xy 247.901937 7.324078) (xy 247.953613 7.255649) (xy 247.998754 7.182743)
			(xy 248.036976 7.105983) (xy 248.067952 7.026024) (xy 248.091419 6.943548) (xy 248.107175 6.859258)
			(xy 248.115087 6.773875) (xy 248.115582 6.731) (xy 248.115087 6.688125) (xy 252.610353 6.688125)
			(xy 252.610353 6.773875) (xy 252.618265 6.859258) (xy 252.634021 6.943548) (xy 252.657488 7.026024)
			(xy 252.688464 7.105983) (xy 252.726686 7.182743) (xy 252.771827 7.255649) (xy 252.823503 7.324078)
			(xy 252.881272 7.387448) (xy 252.944642 7.445217) (xy 253.013071 7.496893) (xy 253.085977 7.542034)
			(xy 253.162737 7.580256) (xy 253.242696 7.611232) (xy 253.325172 7.634699) (xy 253.409462 7.650455)
			(xy 253.494845 7.658367) (xy 253.580595 7.658367) (xy 253.665978 7.650455) (xy 253.750268 7.634699)
			(xy 253.832744 7.611232) (xy 253.912703 7.580256) (xy 253.989463 7.542034) (xy 254.062369 7.496893)
			(xy 254.130798 7.445217) (xy 254.194168 7.387448) (xy 254.251937 7.324078) (xy 254.303613 7.255649)
			(xy 254.348754 7.182743) (xy 254.386976 7.105983) (xy 254.417952 7.026024) (xy 254.441419 6.943548)
			(xy 254.457175 6.859258) (xy 254.465087 6.773875) (xy 254.465582 6.731) (xy 254.465119 6.690919)
			(xy 256.921241 6.690919) (xy 256.921241 6.776669) (xy 256.929153 6.862052) (xy 256.944909 6.946342)
			(xy 256.968376 7.028818) (xy 256.999352 7.108777) (xy 257.037574 7.185537) (xy 257.082715 7.258443)
			(xy 257.134391 7.326872) (xy 257.19216 7.390242) (xy 257.25553 7.448011) (xy 257.323959 7.499687)
			(xy 257.396865 7.544828) (xy 257.473625 7.58305) (xy 257.553584 7.614026) (xy 257.63606 7.637493)
			(xy 257.72035 7.653249) (xy 257.805733 7.661161) (xy 257.891483 7.661161) (xy 257.976866 7.653249)
			(xy 258.061156 7.637493) (xy 258.143632 7.614026) (xy 258.223591 7.58305) (xy 258.245794 7.571994)
			(xy 261.85622 7.571994) (xy 261.85622 8.435594) (xy 261.856706 8.462863) (xy 261.864468 8.516847)
			(xy 261.879833 8.569177) (xy 261.90249 8.618787) (xy 261.931976 8.664668) (xy 261.967691 8.705885)
			(xy 262.008908 8.7416) (xy 262.054789 8.771086) (xy 262.104399 8.793743) (xy 262.156729 8.809108)
			(xy 262.210713 8.81687) (xy 262.265251 8.81687) (xy 262.319235 8.809108) (xy 262.371565 8.793743)
			(xy 262.421175 8.771086) (xy 262.467056 8.7416) (xy 262.508273 8.705885) (xy 262.543988 8.664668)
			(xy 262.573474 8.618787) (xy 262.596131 8.569177) (xy 262.611496 8.516847) (xy 262.619258 8.462863)
			(xy 262.619744 8.435594) (xy 262.619744 7.571994) (xy 262.619258 7.544725) (xy 262.611496 7.490741)
			(xy 262.596131 7.438411) (xy 262.573474 7.388801) (xy 262.543988 7.34292) (xy 262.508273 7.301703)
			(xy 262.467056 7.265988) (xy 262.421175 7.236502) (xy 262.371565 7.213845) (xy 262.319235 7.19848)
			(xy 262.265251 7.190718) (xy 262.210713 7.190718) (xy 262.156729 7.19848) (xy 262.104399 7.213845)
			(xy 262.054789 7.236502) (xy 262.008908 7.265988) (xy 261.967691 7.301703) (xy 261.931976 7.34292)
			(xy 261.90249 7.388801) (xy 261.879833 7.438411) (xy 261.864468 7.490741) (xy 261.856706 7.544725)
			(xy 261.85622 7.571994) (xy 258.245794 7.571994) (xy 258.300351 7.544828) (xy 258.373257 7.499687)
			(xy 258.441686 7.448011) (xy 258.505056 7.390242) (xy 258.562825 7.326872) (xy 258.614501 7.258443)
			(xy 258.659642 7.185537) (xy 258.697864 7.108777) (xy 258.72884 7.028818) (xy 258.752307 6.946342)
			(xy 258.768063 6.862052) (xy 258.775975 6.776669) (xy 258.77647 6.733794) (xy 258.775975 6.690919)
			(xy 263.271241 6.690919) (xy 263.271241 6.776669) (xy 263.279153 6.862052) (xy 263.294909 6.946342)
			(xy 263.318376 7.028818) (xy 263.349352 7.108777) (xy 263.387574 7.185537) (xy 263.432715 7.258443)
			(xy 263.484391 7.326872) (xy 263.54216 7.390242) (xy 263.60553 7.448011) (xy 263.673959 7.499687)
			(xy 263.746865 7.544828) (xy 263.823625 7.58305) (xy 263.903584 7.614026) (xy 263.98606 7.637493)
			(xy 264.07035 7.653249) (xy 264.155733 7.661161) (xy 264.241483 7.661161) (xy 264.326866 7.653249)
			(xy 264.411156 7.637493) (xy 264.493632 7.614026) (xy 264.573591 7.58305) (xy 264.650351 7.544828)
			(xy 264.723257 7.499687) (xy 264.791686 7.448011) (xy 264.855056 7.390242) (xy 264.912825 7.326872)
			(xy 264.964501 7.258443) (xy 265.009642 7.185537) (xy 265.047864 7.108777) (xy 265.07884 7.028818)
			(xy 265.102307 6.946342) (xy 265.118063 6.862052) (xy 265.125975 6.776669) (xy 265.12647 6.733794)
			(xy 265.125975 6.690919) (xy 324.845921 6.690919) (xy 324.845921 6.776669) (xy 324.853833 6.862052)
			(xy 324.869589 6.946342) (xy 324.893056 7.028818) (xy 324.924032 7.108777) (xy 324.962254 7.185537)
			(xy 325.007395 7.258443) (xy 325.059071 7.326872) (xy 325.11684 7.390242) (xy 325.18021 7.448011)
			(xy 325.248639 7.499687) (xy 325.321545 7.544828) (xy 325.398305 7.58305) (xy 325.478264 7.614026)
			(xy 325.56074 7.637493) (xy 325.64503 7.653249) (xy 325.730413 7.661161) (xy 325.816163 7.661161)
			(xy 325.901546 7.653249) (xy 325.985836 7.637493) (xy 326.068312 7.614026) (xy 326.148271 7.58305)
			(xy 326.170474 7.571994) (xy 327.352152 7.571994) (xy 327.352152 8.435594) (xy 327.352638 8.462863)
			(xy 327.3604 8.516847) (xy 327.375765 8.569177) (xy 327.398422 8.618787) (xy 327.427908 8.664668)
			(xy 327.463623 8.705885) (xy 327.50484 8.7416) (xy 327.550721 8.771086) (xy 327.600331 8.793743)
			(xy 327.652661 8.809108) (xy 327.706645 8.81687) (xy 327.761183 8.81687) (xy 327.815167 8.809108)
			(xy 327.867497 8.793743) (xy 327.917107 8.771086) (xy 327.962988 8.7416) (xy 328.004205 8.705885)
			(xy 328.03992 8.664668) (xy 328.069406 8.618787) (xy 328.092063 8.569177) (xy 328.107428 8.516847)
			(xy 328.11519 8.462863) (xy 328.115676 8.435594) (xy 328.115676 7.571994) (xy 328.11519 7.544725)
			(xy 328.107428 7.490741) (xy 328.092063 7.438411) (xy 328.069406 7.388801) (xy 328.03992 7.34292)
			(xy 328.004205 7.301703) (xy 327.962988 7.265988) (xy 327.917107 7.236502) (xy 327.867497 7.213845)
			(xy 327.815167 7.19848) (xy 327.761183 7.190718) (xy 327.706645 7.190718) (xy 327.652661 7.19848)
			(xy 327.600331 7.213845) (xy 327.550721 7.236502) (xy 327.50484 7.265988) (xy 327.463623 7.301703)
			(xy 327.427908 7.34292) (xy 327.398422 7.388801) (xy 327.375765 7.438411) (xy 327.3604 7.490741)
			(xy 327.352638 7.544725) (xy 327.352152 7.571994) (xy 326.170474 7.571994) (xy 326.225031 7.544828)
			(xy 326.297937 7.499687) (xy 326.366366 7.448011) (xy 326.429736 7.390242) (xy 326.487505 7.326872)
			(xy 326.539181 7.258443) (xy 326.584322 7.185537) (xy 326.622544 7.108777) (xy 326.65352 7.028818)
			(xy 326.676987 6.946342) (xy 326.692743 6.862052) (xy 326.700655 6.776669) (xy 326.70115 6.733794)
			(xy 326.700655 6.690919) (xy 331.195921 6.690919) (xy 331.195921 6.776669) (xy 331.203833 6.862052)
			(xy 331.219589 6.946342) (xy 331.243056 7.028818) (xy 331.274032 7.108777) (xy 331.312254 7.185537)
			(xy 331.357395 7.258443) (xy 331.409071 7.326872) (xy 331.46684 7.390242) (xy 331.53021 7.448011)
			(xy 331.598639 7.499687) (xy 331.671545 7.544828) (xy 331.748305 7.58305) (xy 331.828264 7.614026)
			(xy 331.91074 7.637493) (xy 331.99503 7.653249) (xy 332.080413 7.661161) (xy 332.166163 7.661161)
			(xy 332.251546 7.653249) (xy 332.335836 7.637493) (xy 332.418312 7.614026) (xy 332.498271 7.58305)
			(xy 332.575031 7.544828) (xy 332.647937 7.499687) (xy 332.716366 7.448011) (xy 332.779736 7.390242)
			(xy 332.837505 7.326872) (xy 332.889181 7.258443) (xy 332.934322 7.185537) (xy 332.972544 7.108777)
			(xy 333.00352 7.028818) (xy 333.026987 6.946342) (xy 333.042743 6.862052) (xy 333.050655 6.776669)
			(xy 333.05115 6.733794) (xy 333.050655 6.690919) (xy 335.488267 6.690919) (xy 335.488267 6.776669)
			(xy 335.496179 6.862052) (xy 335.511935 6.946342) (xy 335.535402 7.028818) (xy 335.566378 7.108777)
			(xy 335.6046 7.185537) (xy 335.649741 7.258443) (xy 335.701417 7.326872) (xy 335.759186 7.390242)
			(xy 335.822556 7.448011) (xy 335.890985 7.499687) (xy 335.963891 7.544828) (xy 336.040651 7.58305)
			(xy 336.12061 7.614026) (xy 336.203086 7.637493) (xy 336.287376 7.653249) (xy 336.372759 7.661161)
			(xy 336.458509 7.661161) (xy 336.543892 7.653249) (xy 336.628182 7.637493) (xy 336.710658 7.614026)
			(xy 336.790617 7.58305) (xy 336.81282 7.571994) (xy 340.4235 7.571994) (xy 340.4235 8.435594) (xy 340.423986 8.462845)
			(xy 340.431742 8.516793) (xy 340.447097 8.569088) (xy 340.469739 8.618665) (xy 340.499205 8.664515)
			(xy 340.534896 8.705706) (xy 340.576087 8.741397) (xy 340.621937 8.770863) (xy 340.671514 8.793505)
			(xy 340.723809 8.80886) (xy 340.777757 8.816616) (xy 340.832259 8.816616) (xy 340.886207 8.80886)
			(xy 340.938502 8.793505) (xy 340.988079 8.770863) (xy 341.033929 8.741397) (xy 341.07512 8.705706)
			(xy 341.110811 8.664515) (xy 341.140277 8.618665) (xy 341.162919 8.569088) (xy 341.178274 8.516793)
			(xy 341.18603 8.462845) (xy 341.186516 8.435594) (xy 341.186516 7.571994) (xy 341.18603 7.544743)
			(xy 341.178274 7.490795) (xy 341.162919 7.4385) (xy 341.140277 7.388923) (xy 341.110811 7.343073)
			(xy 341.07512 7.301882) (xy 341.033929 7.266191) (xy 340.988079 7.236725) (xy 340.938502 7.214083)
			(xy 340.886207 7.198728) (xy 340.832259 7.190972) (xy 340.777757 7.190972) (xy 340.723809 7.198728)
			(xy 340.671514 7.214083) (xy 340.621937 7.236725) (xy 340.576087 7.266191) (xy 340.534896 7.301882)
			(xy 340.499205 7.343073) (xy 340.469739 7.388923) (xy 340.447097 7.4385) (xy 340.431742 7.490795)
			(xy 340.423986 7.544743) (xy 340.4235 7.571994) (xy 336.81282 7.571994) (xy 336.867377 7.544828)
			(xy 336.940283 7.499687) (xy 337.008712 7.448011) (xy 337.072082 7.390242) (xy 337.129851 7.326872)
			(xy 337.181527 7.258443) (xy 337.226668 7.185537) (xy 337.26489 7.108777) (xy 337.295866 7.028818)
			(xy 337.319333 6.946342) (xy 337.335089 6.862052) (xy 337.343001 6.776669) (xy 337.343496 6.733794)
			(xy 337.343001 6.690919) (xy 341.838267 6.690919) (xy 341.838267 6.776669) (xy 341.846179 6.862052)
			(xy 341.861935 6.946342) (xy 341.885402 7.028818) (xy 341.916378 7.108777) (xy 341.9546 7.185537)
			(xy 341.999741 7.258443) (xy 342.051417 7.326872) (xy 342.109186 7.390242) (xy 342.172556 7.448011)
			(xy 342.240985 7.499687) (xy 342.313891 7.544828) (xy 342.390651 7.58305) (xy 342.47061 7.614026)
			(xy 342.553086 7.637493) (xy 342.637376 7.653249) (xy 342.722759 7.661161) (xy 342.808509 7.661161)
			(xy 342.893892 7.653249) (xy 342.978182 7.637493) (xy 343.060658 7.614026) (xy 343.140617 7.58305)
			(xy 343.217377 7.544828) (xy 343.290283 7.499687) (xy 343.358712 7.448011) (xy 343.422082 7.390242)
			(xy 343.479851 7.326872) (xy 343.531527 7.258443) (xy 343.576668 7.185537) (xy 343.61489 7.108777)
			(xy 343.645866 7.028818) (xy 343.669333 6.946342) (xy 343.685089 6.862052) (xy 343.693001 6.776669)
			(xy 343.693496 6.733794) (xy 343.693001 6.690919) (xy 373.705107 6.690919) (xy 373.705107 6.776669)
			(xy 373.713019 6.862052) (xy 373.728775 6.946342) (xy 373.752242 7.028818) (xy 373.783218 7.108777)
			(xy 373.82144 7.185537) (xy 373.866581 7.258443) (xy 373.918257 7.326872) (xy 373.976026 7.390242)
			(xy 374.039396 7.448011) (xy 374.107825 7.499687) (xy 374.180731 7.544828) (xy 374.257491 7.58305)
			(xy 374.33745 7.614026) (xy 374.419926 7.637493) (xy 374.504216 7.653249) (xy 374.589599 7.661161)
			(xy 374.675349 7.661161) (xy 374.760732 7.653249) (xy 374.845022 7.637493) (xy 374.927498 7.614026)
			(xy 375.007457 7.58305) (xy 375.02966 7.571994) (xy 376.211592 7.571994) (xy 376.211592 8.435594)
			(xy 376.212078 8.462845) (xy 376.219834 8.516793) (xy 376.235189 8.569088) (xy 376.257831 8.618665)
			(xy 376.287297 8.664515) (xy 376.322988 8.705706) (xy 376.364179 8.741397) (xy 376.410029 8.770863)
			(xy 376.459606 8.793505) (xy 376.511901 8.80886) (xy 376.565849 8.816616) (xy 376.620351 8.816616)
			(xy 376.674299 8.80886) (xy 376.726594 8.793505) (xy 376.776171 8.770863) (xy 376.822021 8.741397)
			(xy 376.863212 8.705706) (xy 376.898903 8.664515) (xy 376.928369 8.618665) (xy 376.951011 8.569088)
			(xy 376.966366 8.516793) (xy 376.974122 8.462845) (xy 376.974608 8.435594) (xy 376.974608 7.571994)
			(xy 376.974122 7.544743) (xy 376.966366 7.490795) (xy 376.951011 7.4385) (xy 376.928369 7.388923)
			(xy 376.898903 7.343073) (xy 376.863212 7.301882) (xy 376.822021 7.266191) (xy 376.776171 7.236725)
			(xy 376.726594 7.214083) (xy 376.674299 7.198728) (xy 376.620351 7.190972) (xy 376.565849 7.190972)
			(xy 376.511901 7.198728) (xy 376.459606 7.214083) (xy 376.410029 7.236725) (xy 376.364179 7.266191)
			(xy 376.322988 7.301882) (xy 376.287297 7.343073) (xy 376.257831 7.388923) (xy 376.235189 7.4385)
			(xy 376.219834 7.490795) (xy 376.212078 7.544743) (xy 376.211592 7.571994) (xy 375.02966 7.571994)
			(xy 375.084217 7.544828) (xy 375.157123 7.499687) (xy 375.225552 7.448011) (xy 375.288922 7.390242)
			(xy 375.346691 7.326872) (xy 375.398367 7.258443) (xy 375.443508 7.185537) (xy 375.48173 7.108777)
			(xy 375.512706 7.028818) (xy 375.536173 6.946342) (xy 375.551929 6.862052) (xy 375.559841 6.776669)
			(xy 375.560336 6.733794) (xy 375.559841 6.690919) (xy 380.055107 6.690919) (xy 380.055107 6.776669)
			(xy 380.063019 6.862052) (xy 380.078775 6.946342) (xy 380.102242 7.028818) (xy 380.133218 7.108777)
			(xy 380.17144 7.185537) (xy 380.216581 7.258443) (xy 380.268257 7.326872) (xy 380.326026 7.390242)
			(xy 380.389396 7.448011) (xy 380.457825 7.499687) (xy 380.530731 7.544828) (xy 380.607491 7.58305)
			(xy 380.68745 7.614026) (xy 380.769926 7.637493) (xy 380.854216 7.653249) (xy 380.939599 7.661161)
			(xy 381.025349 7.661161) (xy 381.110732 7.653249) (xy 381.195022 7.637493) (xy 381.277498 7.614026)
			(xy 381.357457 7.58305) (xy 381.434217 7.544828) (xy 381.507123 7.499687) (xy 381.575552 7.448011)
			(xy 381.638922 7.390242) (xy 381.688857 7.335466) (xy 464.704165 7.335466) (xy 464.704165 7.464606)
			(xy 464.712115 7.593501) (xy 464.727985 7.721661) (xy 464.751714 7.848602) (xy 464.783213 7.973841)
			(xy 464.822362 8.096904) (xy 464.869013 8.217323) (xy 464.922988 8.334642) (xy 464.984083 8.448416)
			(xy 465.052066 8.558213) (xy 465.12668 8.663616) (xy 465.207641 8.764226) (xy 465.294641 8.859661)
			(xy 465.387352 8.94956) (xy 465.485422 9.033581) (xy 465.588477 9.111405) (xy 465.696128 9.182737)
			(xy 465.807967 9.247307) (xy 465.923568 9.304869) (xy 466.042493 9.355206) (xy 466.164292 9.398126)
			(xy 466.288502 9.433467) (xy 466.414651 9.461094) (xy 466.542263 9.480903) (xy 466.670852 9.492819)
			(xy 466.79993 9.496796) (xy 466.929008 9.492819) (xy 467.057597 9.480903) (xy 467.185209 9.461094)
			(xy 467.311358 9.433467) (xy 467.435568 9.398126) (xy 467.557367 9.355206) (xy 467.676292 9.304869)
			(xy 467.791893 9.247307) (xy 467.903732 9.182737) (xy 468.011383 9.111405) (xy 468.114438 9.033581)
			(xy 468.212508 8.94956) (xy 468.305219 8.859661) (xy 468.392219 8.764226) (xy 468.47318 8.663616)
			(xy 468.547794 8.558213) (xy 468.615777 8.448416) (xy 468.676872 8.334642) (xy 468.730847 8.217323)
			(xy 468.777498 8.096904) (xy 468.816647 7.973841) (xy 468.848146 7.848602) (xy 468.871875 7.721661)
			(xy 468.887745 7.593501) (xy 468.895695 7.464606) (xy 468.896192 7.400036) (xy 468.895695 7.335466)
			(xy 468.887745 7.206571) (xy 468.871875 7.078411) (xy 468.848146 6.95147) (xy 468.816647 6.826231)
			(xy 468.777498 6.703168) (xy 468.730847 6.582749) (xy 468.676872 6.46543) (xy 468.615777 6.351656)
			(xy 468.547794 6.241859) (xy 468.47318 6.136456) (xy 468.392219 6.035846) (xy 468.305219 5.940411)
			(xy 468.212508 5.850512) (xy 468.114438 5.766491) (xy 468.011383 5.688667) (xy 467.903732 5.617335)
			(xy 467.791893 5.552765) (xy 467.676292 5.495203) (xy 467.557367 5.444866) (xy 467.435568 5.401946)
			(xy 467.311358 5.366605) (xy 467.185209 5.338978) (xy 467.057597 5.319169) (xy 466.929008 5.307253)
			(xy 466.79993 5.303277) (xy 466.670852 5.307253) (xy 466.542263 5.319169) (xy 466.414651 5.338978)
			(xy 466.288502 5.366605) (xy 466.164292 5.401946) (xy 466.042493 5.444866) (xy 465.923568 5.495203)
			(xy 465.807967 5.552765) (xy 465.696128 5.617335) (xy 465.588477 5.688667) (xy 465.485422 5.766491)
			(xy 465.387352 5.850512) (xy 465.294641 5.940411) (xy 465.207641 6.035846) (xy 465.12668 6.136456)
			(xy 465.052066 6.241859) (xy 464.984083 6.351656) (xy 464.922988 6.46543) (xy 464.869013 6.582749)
			(xy 464.822362 6.703168) (xy 464.783213 6.826231) (xy 464.751714 6.95147) (xy 464.727985 7.078411)
			(xy 464.712115 7.206571) (xy 464.704165 7.335466) (xy 381.688857 7.335466) (xy 381.696691 7.326872)
			(xy 381.748367 7.258443) (xy 381.793508 7.185537) (xy 381.83173 7.108777) (xy 381.862706 7.028818)
			(xy 381.886173 6.946342) (xy 381.901929 6.862052) (xy 381.909841 6.776669) (xy 381.910336 6.733794)
			(xy 381.909841 6.690919) (xy 381.901929 6.605536) (xy 381.886173 6.521246) (xy 381.862706 6.43877)
			(xy 381.83173 6.358811) (xy 381.793508 6.282051) (xy 381.748367 6.209145) (xy 381.696691 6.140716)
			(xy 381.638922 6.077346) (xy 381.575552 6.019577) (xy 381.507123 5.967901) (xy 381.434217 5.92276)
			(xy 381.357457 5.884538) (xy 381.277498 5.853562) (xy 381.195022 5.830095) (xy 381.110732 5.814339)
			(xy 381.025349 5.806427) (xy 380.939599 5.806427) (xy 380.854216 5.814339) (xy 380.769926 5.830095)
			(xy 380.68745 5.853562) (xy 380.607491 5.884538) (xy 380.530731 5.92276) (xy 380.457825 5.967901)
			(xy 380.389396 6.019577) (xy 380.326026 6.077346) (xy 380.268257 6.140716) (xy 380.216581 6.209145)
			(xy 380.17144 6.282051) (xy 380.133218 6.358811) (xy 380.102242 6.43877) (xy 380.078775 6.521246)
			(xy 380.063019 6.605536) (xy 380.055107 6.690919) (xy 375.559841 6.690919) (xy 375.551929 6.605536)
			(xy 375.536173 6.521246) (xy 375.512706 6.43877) (xy 375.48173 6.358811) (xy 375.443508 6.282051)
			(xy 375.398367 6.209145) (xy 375.346691 6.140716) (xy 375.288922 6.077346) (xy 375.225552 6.019577)
			(xy 375.157123 5.967901) (xy 375.084217 5.92276) (xy 375.007457 5.884538) (xy 374.927498 5.853562)
			(xy 374.845022 5.830095) (xy 374.760732 5.814339) (xy 374.675349 5.806427) (xy 374.589599 5.806427)
			(xy 374.504216 5.814339) (xy 374.419926 5.830095) (xy 374.33745 5.853562) (xy 374.257491 5.884538)
			(xy 374.180731 5.92276) (xy 374.107825 5.967901) (xy 374.039396 6.019577) (xy 373.976026 6.077346)
			(xy 373.918257 6.140716) (xy 373.866581 6.209145) (xy 373.82144 6.282051) (xy 373.783218 6.358811)
			(xy 373.752242 6.43877) (xy 373.728775 6.521246) (xy 373.713019 6.605536) (xy 373.705107 6.690919)
			(xy 343.693001 6.690919) (xy 343.685089 6.605536) (xy 343.669333 6.521246) (xy 343.645866 6.43877)
			(xy 343.61489 6.358811) (xy 343.576668 6.282051) (xy 343.531527 6.209145) (xy 343.479851 6.140716)
			(xy 343.422082 6.077346) (xy 343.358712 6.019577) (xy 343.290283 5.967901) (xy 343.217377 5.92276)
			(xy 343.140617 5.884538) (xy 343.060658 5.853562) (xy 342.978182 5.830095) (xy 342.893892 5.814339)
			(xy 342.808509 5.806427) (xy 342.722759 5.806427) (xy 342.637376 5.814339) (xy 342.553086 5.830095)
			(xy 342.47061 5.853562) (xy 342.390651 5.884538) (xy 342.313891 5.92276) (xy 342.240985 5.967901)
			(xy 342.172556 6.019577) (xy 342.109186 6.077346) (xy 342.051417 6.140716) (xy 341.999741 6.209145)
			(xy 341.9546 6.282051) (xy 341.916378 6.358811) (xy 341.885402 6.43877) (xy 341.861935 6.521246)
			(xy 341.846179 6.605536) (xy 341.838267 6.690919) (xy 337.343001 6.690919) (xy 337.335089 6.605536)
			(xy 337.319333 6.521246) (xy 337.295866 6.43877) (xy 337.26489 6.358811) (xy 337.226668 6.282051)
			(xy 337.181527 6.209145) (xy 337.129851 6.140716) (xy 337.072082 6.077346) (xy 337.008712 6.019577)
			(xy 336.940283 5.967901) (xy 336.867377 5.92276) (xy 336.790617 5.884538) (xy 336.710658 5.853562)
			(xy 336.628182 5.830095) (xy 336.543892 5.814339) (xy 336.458509 5.806427) (xy 336.372759 5.806427)
			(xy 336.287376 5.814339) (xy 336.203086 5.830095) (xy 336.12061 5.853562) (xy 336.040651 5.884538)
			(xy 335.963891 5.92276) (xy 335.890985 5.967901) (xy 335.822556 6.019577) (xy 335.759186 6.077346)
			(xy 335.701417 6.140716) (xy 335.649741 6.209145) (xy 335.6046 6.282051) (xy 335.566378 6.358811)
			(xy 335.535402 6.43877) (xy 335.511935 6.521246) (xy 335.496179 6.605536) (xy 335.488267 6.690919)
			(xy 333.050655 6.690919) (xy 333.042743 6.605536) (xy 333.026987 6.521246) (xy 333.00352 6.43877)
			(xy 332.972544 6.358811) (xy 332.934322 6.282051) (xy 332.889181 6.209145) (xy 332.837505 6.140716)
			(xy 332.779736 6.077346) (xy 332.716366 6.019577) (xy 332.647937 5.967901) (xy 332.575031 5.92276)
			(xy 332.498271 5.884538) (xy 332.418312 5.853562) (xy 332.335836 5.830095) (xy 332.251546 5.814339)
			(xy 332.166163 5.806427) (xy 332.080413 5.806427) (xy 331.99503 5.814339) (xy 331.91074 5.830095)
			(xy 331.828264 5.853562) (xy 331.748305 5.884538) (xy 331.671545 5.92276) (xy 331.598639 5.967901)
			(xy 331.53021 6.019577) (xy 331.46684 6.077346) (xy 331.409071 6.140716) (xy 331.357395 6.209145)
			(xy 331.312254 6.282051) (xy 331.274032 6.358811) (xy 331.243056 6.43877) (xy 331.219589 6.521246)
			(xy 331.203833 6.605536) (xy 331.195921 6.690919) (xy 326.700655 6.690919) (xy 326.692743 6.605536)
			(xy 326.676987 6.521246) (xy 326.65352 6.43877) (xy 326.622544 6.358811) (xy 326.584322 6.282051)
			(xy 326.539181 6.209145) (xy 326.487505 6.140716) (xy 326.429736 6.077346) (xy 326.366366 6.019577)
			(xy 326.297937 5.967901) (xy 326.225031 5.92276) (xy 326.148271 5.884538) (xy 326.068312 5.853562)
			(xy 325.985836 5.830095) (xy 325.901546 5.814339) (xy 325.816163 5.806427) (xy 325.730413 5.806427)
			(xy 325.64503 5.814339) (xy 325.56074 5.830095) (xy 325.478264 5.853562) (xy 325.398305 5.884538)
			(xy 325.321545 5.92276) (xy 325.248639 5.967901) (xy 325.18021 6.019577) (xy 325.11684 6.077346)
			(xy 325.059071 6.140716) (xy 325.007395 6.209145) (xy 324.962254 6.282051) (xy 324.924032 6.358811)
			(xy 324.893056 6.43877) (xy 324.869589 6.521246) (xy 324.853833 6.605536) (xy 324.845921 6.690919)
			(xy 265.125975 6.690919) (xy 265.118063 6.605536) (xy 265.102307 6.521246) (xy 265.07884 6.43877)
			(xy 265.047864 6.358811) (xy 265.009642 6.282051) (xy 264.964501 6.209145) (xy 264.912825 6.140716)
			(xy 264.855056 6.077346) (xy 264.791686 6.019577) (xy 264.723257 5.967901) (xy 264.650351 5.92276)
			(xy 264.573591 5.884538) (xy 264.493632 5.853562) (xy 264.411156 5.830095) (xy 264.326866 5.814339)
			(xy 264.241483 5.806427) (xy 264.155733 5.806427) (xy 264.07035 5.814339) (xy 263.98606 5.830095)
			(xy 263.903584 5.853562) (xy 263.823625 5.884538) (xy 263.746865 5.92276) (xy 263.673959 5.967901)
			(xy 263.60553 6.019577) (xy 263.54216 6.077346) (xy 263.484391 6.140716) (xy 263.432715 6.209145)
			(xy 263.387574 6.282051) (xy 263.349352 6.358811) (xy 263.318376 6.43877) (xy 263.294909 6.521246)
			(xy 263.279153 6.605536) (xy 263.271241 6.690919) (xy 258.775975 6.690919) (xy 258.768063 6.605536)
			(xy 258.752307 6.521246) (xy 258.72884 6.43877) (xy 258.697864 6.358811) (xy 258.659642 6.282051)
			(xy 258.614501 6.209145) (xy 258.562825 6.140716) (xy 258.505056 6.077346) (xy 258.441686 6.019577)
			(xy 258.373257 5.967901) (xy 258.300351 5.92276) (xy 258.223591 5.884538) (xy 258.143632 5.853562)
			(xy 258.061156 5.830095) (xy 257.976866 5.814339) (xy 257.891483 5.806427) (xy 257.805733 5.806427)
			(xy 257.72035 5.814339) (xy 257.63606 5.830095) (xy 257.553584 5.853562) (xy 257.473625 5.884538)
			(xy 257.396865 5.92276) (xy 257.323959 5.967901) (xy 257.25553 6.019577) (xy 257.19216 6.077346)
			(xy 257.134391 6.140716) (xy 257.082715 6.209145) (xy 257.037574 6.282051) (xy 256.999352 6.358811)
			(xy 256.968376 6.43877) (xy 256.944909 6.521246) (xy 256.929153 6.605536) (xy 256.921241 6.690919)
			(xy 254.465119 6.690919) (xy 254.465087 6.688125) (xy 254.457175 6.602742) (xy 254.441419 6.518452)
			(xy 254.417952 6.435976) (xy 254.386976 6.356017) (xy 254.348754 6.279257) (xy 254.303613 6.206351)
			(xy 254.251937 6.137922) (xy 254.194168 6.074552) (xy 254.130798 6.016783) (xy 254.062369 5.965107)
			(xy 253.989463 5.919966) (xy 253.912703 5.881744) (xy 253.832744 5.850768) (xy 253.750268 5.827301)
			(xy 253.665978 5.811545) (xy 253.580595 5.803633) (xy 253.494845 5.803633) (xy 253.409462 5.811545)
			(xy 253.325172 5.827301) (xy 253.242696 5.850768) (xy 253.162737 5.881744) (xy 253.085977 5.919966)
			(xy 253.013071 5.965107) (xy 252.944642 6.016783) (xy 252.881272 6.074552) (xy 252.823503 6.137922)
			(xy 252.771827 6.206351) (xy 252.726686 6.279257) (xy 252.688464 6.356017) (xy 252.657488 6.435976)
			(xy 252.634021 6.518452) (xy 252.618265 6.602742) (xy 252.610353 6.688125) (xy 248.115087 6.688125)
			(xy 248.107175 6.602742) (xy 248.091419 6.518452) (xy 248.067952 6.435976) (xy 248.036976 6.356017)
			(xy 247.998754 6.279257) (xy 247.953613 6.206351) (xy 247.901937 6.137922) (xy 247.844168 6.074552)
			(xy 247.780798 6.016783) (xy 247.712369 5.965107) (xy 247.639463 5.919966) (xy 247.562703 5.881744)
			(xy 247.482744 5.850768) (xy 247.400268 5.827301) (xy 247.315978 5.811545) (xy 247.230595 5.803633)
			(xy 247.144845 5.803633) (xy 247.059462 5.811545) (xy 246.975172 5.827301) (xy 246.892696 5.850768)
			(xy 246.812737 5.881744) (xy 246.735977 5.919966) (xy 246.663071 5.965107) (xy 246.594642 6.016783)
			(xy 246.531272 6.074552) (xy 246.473503 6.137922) (xy 246.421827 6.206351) (xy 246.376686 6.279257)
			(xy 246.338464 6.356017) (xy 246.307488 6.435976) (xy 246.284021 6.518452) (xy 246.268265 6.602742)
			(xy 246.260353 6.688125) (xy 186.540407 6.688125) (xy 186.532495 6.602742) (xy 186.516739 6.518452)
			(xy 186.493272 6.435976) (xy 186.462296 6.356017) (xy 186.424074 6.279257) (xy 186.378933 6.206351)
			(xy 186.327257 6.137922) (xy 186.269488 6.074552) (xy 186.206118 6.016783) (xy 186.137689 5.965107)
			(xy 186.064783 5.919966) (xy 185.988023 5.881744) (xy 185.908064 5.850768) (xy 185.825588 5.827301)
			(xy 185.741298 5.811545) (xy 185.655915 5.803633) (xy 185.570165 5.803633) (xy 185.484782 5.811545)
			(xy 185.400492 5.827301) (xy 185.318016 5.850768) (xy 185.238057 5.881744) (xy 185.161297 5.919966)
			(xy 185.088391 5.965107) (xy 185.019962 6.016783) (xy 184.956592 6.074552) (xy 184.898823 6.137922)
			(xy 184.847147 6.206351) (xy 184.802006 6.279257) (xy 184.763784 6.356017) (xy 184.732808 6.435976)
			(xy 184.709341 6.518452) (xy 184.693585 6.602742) (xy 184.685673 6.688125) (xy 180.190407 6.688125)
			(xy 180.182495 6.602742) (xy 180.166739 6.518452) (xy 180.143272 6.435976) (xy 180.112296 6.356017)
			(xy 180.074074 6.279257) (xy 180.028933 6.206351) (xy 179.977257 6.137922) (xy 179.919488 6.074552)
			(xy 179.856118 6.016783) (xy 179.787689 5.965107) (xy 179.714783 5.919966) (xy 179.638023 5.881744)
			(xy 179.558064 5.850768) (xy 179.475588 5.827301) (xy 179.391298 5.811545) (xy 179.305915 5.803633)
			(xy 179.220165 5.803633) (xy 179.134782 5.811545) (xy 179.050492 5.827301) (xy 178.968016 5.850768)
			(xy 178.888057 5.881744) (xy 178.811297 5.919966) (xy 178.738391 5.965107) (xy 178.669962 6.016783)
			(xy 178.606592 6.074552) (xy 178.548823 6.137922) (xy 178.497147 6.206351) (xy 178.452006 6.279257)
			(xy 178.413784 6.356017) (xy 178.382808 6.435976) (xy 178.359341 6.518452) (xy 178.343585 6.602742)
			(xy 178.335673 6.688125) (xy 6.97173 6.688125) (xy 6.930907 6.582749) (xy 6.876932 6.46543) (xy 6.815837 6.351656)
			(xy 6.747854 6.241859) (xy 6.67324 6.136456) (xy 6.592279 6.035846) (xy 6.505279 5.940411) (xy 6.412568 5.850512)
			(xy 6.314498 5.766491) (xy 6.211443 5.688667) (xy 6.103792 5.617335) (xy 5.991953 5.552765) (xy 5.876352 5.495203)
			(xy 5.757427 5.444866) (xy 5.635628 5.401946) (xy 5.511418 5.366605) (xy 5.385269 5.338978) (xy 5.257657 5.319169)
			(xy 5.129068 5.307253) (xy 4.99999 5.303277) (xy 4.870912 5.307253) (xy 4.742323 5.319169) (xy 4.614711 5.338978)
			(xy 4.488562 5.366605) (xy 4.364352 5.401946) (xy 4.242553 5.444866) (xy 4.123628 5.495203) (xy 4.008027 5.552765)
			(xy 3.896188 5.617335) (xy 3.788537 5.688667) (xy 3.685482 5.766491) (xy 3.587412 5.850512) (xy 3.494701 5.940411)
			(xy 3.407701 6.035846) (xy 3.32674 6.136456) (xy 3.252126 6.241859) (xy 3.184143 6.351656) (xy 3.123048 6.46543)
			(xy 3.069073 6.582749) (xy 3.022422 6.703168) (xy 2.983273 6.826231) (xy 2.951774 6.95147) (xy 2.928045 7.078411)
			(xy 2.912175 7.206571) (xy 2.904225 7.335466) (xy 0.508 7.335466) (xy 0.508 4.148125) (xy 178.335673 4.148125)
			(xy 178.335673 4.233875) (xy 178.343585 4.319258) (xy 178.359341 4.403548) (xy 178.382808 4.486024)
			(xy 178.413784 4.565983) (xy 178.452006 4.642743) (xy 178.497147 4.715649) (xy 178.548823 4.784078)
			(xy 178.606592 4.847448) (xy 178.669962 4.905217) (xy 178.738391 4.956893) (xy 178.811297 5.002034)
			(xy 178.888057 5.040256) (xy 178.968016 5.071232) (xy 179.050492 5.094699) (xy 179.134782 5.110455)
			(xy 179.220165 5.118367) (xy 179.305915 5.118367) (xy 179.391298 5.110455) (xy 179.475588 5.094699)
			(xy 179.558064 5.071232) (xy 179.638023 5.040256) (xy 179.660226 5.0292) (xy 183.270652 5.0292) (xy 183.270652 5.8928)
			(xy 183.271138 5.920069) (xy 183.2789 5.974053) (xy 183.294265 6.026383) (xy 183.316922 6.075993)
			(xy 183.346408 6.121874) (xy 183.382123 6.163091) (xy 183.42334 6.198806) (xy 183.469221 6.228292)
			(xy 183.518831 6.250949) (xy 183.571161 6.266314) (xy 183.625145 6.274076) (xy 183.679683 6.274076)
			(xy 183.733667 6.266314) (xy 183.785997 6.250949) (xy 183.835607 6.228292) (xy 183.881488 6.198806)
			(xy 183.922705 6.163091) (xy 183.95842 6.121874) (xy 183.987906 6.075993) (xy 184.010563 6.026383)
			(xy 184.025928 5.974053) (xy 184.03369 5.920069) (xy 184.034176 5.8928) (xy 184.034176 5.0292) (xy 184.03369 5.001931)
			(xy 184.025928 4.947947) (xy 184.010563 4.895617) (xy 183.987906 4.846007) (xy 183.95842 4.800126)
			(xy 183.922705 4.758909) (xy 183.881488 4.723194) (xy 183.835607 4.693708) (xy 183.785997 4.671051)
			(xy 183.733667 4.655686) (xy 183.679683 4.647924) (xy 183.625145 4.647924) (xy 183.571161 4.655686)
			(xy 183.518831 4.671051) (xy 183.469221 4.693708) (xy 183.42334 4.723194) (xy 183.382123 4.758909)
			(xy 183.346408 4.800126) (xy 183.316922 4.846007) (xy 183.294265 4.895617) (xy 183.2789 4.947947)
			(xy 183.271138 5.001931) (xy 183.270652 5.0292) (xy 179.660226 5.0292) (xy 179.714783 5.002034) (xy 179.787689 4.956893)
			(xy 179.856118 4.905217) (xy 179.919488 4.847448) (xy 179.977257 4.784078) (xy 180.028933 4.715649)
			(xy 180.074074 4.642743) (xy 180.112296 4.565983) (xy 180.143272 4.486024) (xy 180.166739 4.403548)
			(xy 180.182495 4.319258) (xy 180.190407 4.233875) (xy 180.190902 4.191) (xy 180.190407 4.148125)
			(xy 184.685673 4.148125) (xy 184.685673 4.233875) (xy 184.693585 4.319258) (xy 184.709341 4.403548)
			(xy 184.732808 4.486024) (xy 184.763784 4.565983) (xy 184.802006 4.642743) (xy 184.847147 4.715649)
			(xy 184.898823 4.784078) (xy 184.956592 4.847448) (xy 185.019962 4.905217) (xy 185.088391 4.956893)
			(xy 185.161297 5.002034) (xy 185.238057 5.040256) (xy 185.318016 5.071232) (xy 185.400492 5.094699)
			(xy 185.484782 5.110455) (xy 185.570165 5.118367) (xy 185.655915 5.118367) (xy 185.741298 5.110455)
			(xy 185.825588 5.094699) (xy 185.908064 5.071232) (xy 185.988023 5.040256) (xy 186.064783 5.002034)
			(xy 186.137689 4.956893) (xy 186.206118 4.905217) (xy 186.269488 4.847448) (xy 186.327257 4.784078)
			(xy 186.378933 4.715649) (xy 186.424074 4.642743) (xy 186.462296 4.565983) (xy 186.493272 4.486024)
			(xy 186.516739 4.403548) (xy 186.532495 4.319258) (xy 186.540407 4.233875) (xy 186.540902 4.191)
			(xy 186.540407 4.148125) (xy 246.260353 4.148125) (xy 246.260353 4.233875) (xy 246.268265 4.319258)
			(xy 246.284021 4.403548) (xy 246.307488 4.486024) (xy 246.338464 4.565983) (xy 246.376686 4.642743)
			(xy 246.421827 4.715649) (xy 246.473503 4.784078) (xy 246.531272 4.847448) (xy 246.594642 4.905217)
			(xy 246.663071 4.956893) (xy 246.735977 5.002034) (xy 246.812737 5.040256) (xy 246.892696 5.071232)
			(xy 246.975172 5.094699) (xy 247.059462 5.110455) (xy 247.144845 5.118367) (xy 247.230595 5.118367)
			(xy 247.315978 5.110455) (xy 247.400268 5.094699) (xy 247.482744 5.071232) (xy 247.562703 5.040256)
			(xy 247.584906 5.0292) (xy 248.766584 5.0292) (xy 248.766584 5.8928) (xy 248.76707 5.920069) (xy 248.774832 5.974053)
			(xy 248.790197 6.026383) (xy 248.812854 6.075993) (xy 248.84234 6.121874) (xy 248.878055 6.163091)
			(xy 248.919272 6.198806) (xy 248.965153 6.228292) (xy 249.014763 6.250949) (xy 249.067093 6.266314)
			(xy 249.121077 6.274076) (xy 249.175615 6.274076) (xy 249.229599 6.266314) (xy 249.281929 6.250949)
			(xy 249.331539 6.228292) (xy 249.37742 6.198806) (xy 249.418637 6.163091) (xy 249.454352 6.121874)
			(xy 249.483838 6.075993) (xy 249.506495 6.026383) (xy 249.52186 5.974053) (xy 249.529622 5.920069)
			(xy 249.530108 5.8928) (xy 249.530108 5.0292) (xy 249.529622 5.001931) (xy 249.52186 4.947947) (xy 249.506495 4.895617)
			(xy 249.483838 4.846007) (xy 249.454352 4.800126) (xy 249.418637 4.758909) (xy 249.37742 4.723194)
			(xy 249.331539 4.693708) (xy 249.281929 4.671051) (xy 249.229599 4.655686) (xy 249.175615 4.647924)
			(xy 249.121077 4.647924) (xy 249.067093 4.655686) (xy 249.014763 4.671051) (xy 248.965153 4.693708)
			(xy 248.919272 4.723194) (xy 248.878055 4.758909) (xy 248.84234 4.800126) (xy 248.812854 4.846007)
			(xy 248.790197 4.895617) (xy 248.774832 4.947947) (xy 248.76707 5.001931) (xy 248.766584 5.0292)
			(xy 247.584906 5.0292) (xy 247.639463 5.002034) (xy 247.712369 4.956893) (xy 247.780798 4.905217)
			(xy 247.844168 4.847448) (xy 247.901937 4.784078) (xy 247.953613 4.715649) (xy 247.998754 4.642743)
			(xy 248.036976 4.565983) (xy 248.067952 4.486024) (xy 248.091419 4.403548) (xy 248.107175 4.319258)
			(xy 248.115087 4.233875) (xy 248.115582 4.191) (xy 248.115087 4.148125) (xy 252.610353 4.148125)
			(xy 252.610353 4.233875) (xy 252.618265 4.319258) (xy 252.634021 4.403548) (xy 252.657488 4.486024)
			(xy 252.688464 4.565983) (xy 252.726686 4.642743) (xy 252.771827 4.715649) (xy 252.823503 4.784078)
			(xy 252.881272 4.847448) (xy 252.944642 4.905217) (xy 253.013071 4.956893) (xy 253.085977 5.002034)
			(xy 253.162737 5.040256) (xy 253.242696 5.071232) (xy 253.325172 5.094699) (xy 253.409462 5.110455)
			(xy 253.494845 5.118367) (xy 253.580595 5.118367) (xy 253.665978 5.110455) (xy 253.750268 5.094699)
			(xy 253.832744 5.071232) (xy 253.912703 5.040256) (xy 253.989463 5.002034) (xy 254.062369 4.956893)
			(xy 254.130798 4.905217) (xy 254.194168 4.847448) (xy 254.251937 4.784078) (xy 254.303613 4.715649)
			(xy 254.348754 4.642743) (xy 254.386976 4.565983) (xy 254.417952 4.486024) (xy 254.441419 4.403548)
			(xy 254.457175 4.319258) (xy 254.465087 4.233875) (xy 254.465582 4.191) (xy 254.465119 4.150919)
			(xy 256.921241 4.150919) (xy 256.921241 4.236669) (xy 256.929153 4.322052) (xy 256.944909 4.406342)
			(xy 256.968376 4.488818) (xy 256.999352 4.568777) (xy 257.037574 4.645537) (xy 257.082715 4.718443)
			(xy 257.134391 4.786872) (xy 257.19216 4.850242) (xy 257.25553 4.908011) (xy 257.323959 4.959687)
			(xy 257.396865 5.004828) (xy 257.473625 5.04305) (xy 257.553584 5.074026) (xy 257.63606 5.097493)
			(xy 257.72035 5.113249) (xy 257.805733 5.121161) (xy 257.891483 5.121161) (xy 257.976866 5.113249)
			(xy 258.061156 5.097493) (xy 258.143632 5.074026) (xy 258.223591 5.04305) (xy 258.245794 5.031994)
			(xy 261.85622 5.031994) (xy 261.85622 5.895594) (xy 261.856706 5.922863) (xy 261.864468 5.976847)
			(xy 261.879833 6.029177) (xy 261.90249 6.078787) (xy 261.931976 6.124668) (xy 261.967691 6.165885)
			(xy 262.008908 6.2016) (xy 262.054789 6.231086) (xy 262.104399 6.253743) (xy 262.156729 6.269108)
			(xy 262.210713 6.27687) (xy 262.265251 6.27687) (xy 262.319235 6.269108) (xy 262.371565 6.253743)
			(xy 262.421175 6.231086) (xy 262.467056 6.2016) (xy 262.508273 6.165885) (xy 262.543988 6.124668)
			(xy 262.573474 6.078787) (xy 262.596131 6.029177) (xy 262.611496 5.976847) (xy 262.619258 5.922863)
			(xy 262.619744 5.895594) (xy 262.619744 5.031994) (xy 262.619258 5.004725) (xy 262.611496 4.950741)
			(xy 262.596131 4.898411) (xy 262.573474 4.848801) (xy 262.543988 4.80292) (xy 262.508273 4.761703)
			(xy 262.467056 4.725988) (xy 262.421175 4.696502) (xy 262.371565 4.673845) (xy 262.319235 4.65848)
			(xy 262.265251 4.650718) (xy 262.210713 4.650718) (xy 262.156729 4.65848) (xy 262.104399 4.673845)
			(xy 262.054789 4.696502) (xy 262.008908 4.725988) (xy 261.967691 4.761703) (xy 261.931976 4.80292)
			(xy 261.90249 4.848801) (xy 261.879833 4.898411) (xy 261.864468 4.950741) (xy 261.856706 5.004725)
			(xy 261.85622 5.031994) (xy 258.245794 5.031994) (xy 258.300351 5.004828) (xy 258.373257 4.959687)
			(xy 258.441686 4.908011) (xy 258.505056 4.850242) (xy 258.562825 4.786872) (xy 258.614501 4.718443)
			(xy 258.659642 4.645537) (xy 258.697864 4.568777) (xy 258.72884 4.488818) (xy 258.752307 4.406342)
			(xy 258.768063 4.322052) (xy 258.775975 4.236669) (xy 258.77647 4.193794) (xy 258.775975 4.150919)
			(xy 263.271241 4.150919) (xy 263.271241 4.236669) (xy 263.279153 4.322052) (xy 263.294909 4.406342)
			(xy 263.318376 4.488818) (xy 263.349352 4.568777) (xy 263.387574 4.645537) (xy 263.432715 4.718443)
			(xy 263.484391 4.786872) (xy 263.54216 4.850242) (xy 263.60553 4.908011) (xy 263.673959 4.959687)
			(xy 263.746865 5.004828) (xy 263.823625 5.04305) (xy 263.903584 5.074026) (xy 263.98606 5.097493)
			(xy 264.07035 5.113249) (xy 264.155733 5.121161) (xy 264.241483 5.121161) (xy 264.326866 5.113249)
			(xy 264.411156 5.097493) (xy 264.493632 5.074026) (xy 264.573591 5.04305) (xy 264.650351 5.004828)
			(xy 264.723257 4.959687) (xy 264.791686 4.908011) (xy 264.855056 4.850242) (xy 264.912825 4.786872)
			(xy 264.964501 4.718443) (xy 265.009642 4.645537) (xy 265.047864 4.568777) (xy 265.07884 4.488818)
			(xy 265.102307 4.406342) (xy 265.118063 4.322052) (xy 265.125975 4.236669) (xy 265.12647 4.193794)
			(xy 265.125975 4.150919) (xy 324.845921 4.150919) (xy 324.845921 4.236669) (xy 324.853833 4.322052)
			(xy 324.869589 4.406342) (xy 324.893056 4.488818) (xy 324.924032 4.568777) (xy 324.962254 4.645537)
			(xy 325.007395 4.718443) (xy 325.059071 4.786872) (xy 325.11684 4.850242) (xy 325.18021 4.908011)
			(xy 325.248639 4.959687) (xy 325.321545 5.004828) (xy 325.398305 5.04305) (xy 325.478264 5.074026)
			(xy 325.56074 5.097493) (xy 325.64503 5.113249) (xy 325.730413 5.121161) (xy 325.816163 5.121161)
			(xy 325.901546 5.113249) (xy 325.985836 5.097493) (xy 326.068312 5.074026) (xy 326.148271 5.04305)
			(xy 326.170474 5.031994) (xy 327.352152 5.031994) (xy 327.352152 5.895594) (xy 327.352638 5.922863)
			(xy 327.3604 5.976847) (xy 327.375765 6.029177) (xy 327.398422 6.078787) (xy 327.427908 6.124668)
			(xy 327.463623 6.165885) (xy 327.50484 6.2016) (xy 327.550721 6.231086) (xy 327.600331 6.253743)
			(xy 327.652661 6.269108) (xy 327.706645 6.27687) (xy 327.761183 6.27687) (xy 327.815167 6.269108)
			(xy 327.867497 6.253743) (xy 327.917107 6.231086) (xy 327.962988 6.2016) (xy 328.004205 6.165885)
			(xy 328.03992 6.124668) (xy 328.069406 6.078787) (xy 328.092063 6.029177) (xy 328.107428 5.976847)
			(xy 328.11519 5.922863) (xy 328.115676 5.895594) (xy 328.115676 5.031994) (xy 328.11519 5.004725)
			(xy 328.107428 4.950741) (xy 328.092063 4.898411) (xy 328.069406 4.848801) (xy 328.03992 4.80292)
			(xy 328.004205 4.761703) (xy 327.962988 4.725988) (xy 327.917107 4.696502) (xy 327.867497 4.673845)
			(xy 327.815167 4.65848) (xy 327.761183 4.650718) (xy 327.706645 4.650718) (xy 327.652661 4.65848)
			(xy 327.600331 4.673845) (xy 327.550721 4.696502) (xy 327.50484 4.725988) (xy 327.463623 4.761703)
			(xy 327.427908 4.80292) (xy 327.398422 4.848801) (xy 327.375765 4.898411) (xy 327.3604 4.950741)
			(xy 327.352638 5.004725) (xy 327.352152 5.031994) (xy 326.170474 5.031994) (xy 326.225031 5.004828)
			(xy 326.297937 4.959687) (xy 326.366366 4.908011) (xy 326.429736 4.850242) (xy 326.487505 4.786872)
			(xy 326.539181 4.718443) (xy 326.584322 4.645537) (xy 326.622544 4.568777) (xy 326.65352 4.488818)
			(xy 326.676987 4.406342) (xy 326.692743 4.322052) (xy 326.700655 4.236669) (xy 326.70115 4.193794)
			(xy 326.700655 4.150919) (xy 331.195921 4.150919) (xy 331.195921 4.236669) (xy 331.203833 4.322052)
			(xy 331.219589 4.406342) (xy 331.243056 4.488818) (xy 331.274032 4.568777) (xy 331.312254 4.645537)
			(xy 331.357395 4.718443) (xy 331.409071 4.786872) (xy 331.46684 4.850242) (xy 331.53021 4.908011)
			(xy 331.598639 4.959687) (xy 331.671545 5.004828) (xy 331.748305 5.04305) (xy 331.828264 5.074026)
			(xy 331.91074 5.097493) (xy 331.99503 5.113249) (xy 332.080413 5.121161) (xy 332.166163 5.121161)
			(xy 332.251546 5.113249) (xy 332.335836 5.097493) (xy 332.418312 5.074026) (xy 332.498271 5.04305)
			(xy 332.575031 5.004828) (xy 332.647937 4.959687) (xy 332.716366 4.908011) (xy 332.779736 4.850242)
			(xy 332.837505 4.786872) (xy 332.889181 4.718443) (xy 332.934322 4.645537) (xy 332.972544 4.568777)
			(xy 333.00352 4.488818) (xy 333.026987 4.406342) (xy 333.042743 4.322052) (xy 333.050655 4.236669)
			(xy 333.05115 4.193794) (xy 333.050655 4.150919) (xy 335.488267 4.150919) (xy 335.488267 4.236669)
			(xy 335.496179 4.322052) (xy 335.511935 4.406342) (xy 335.535402 4.488818) (xy 335.566378 4.568777)
			(xy 335.6046 4.645537) (xy 335.649741 4.718443) (xy 335.701417 4.786872) (xy 335.759186 4.850242)
			(xy 335.822556 4.908011) (xy 335.890985 4.959687) (xy 335.963891 5.004828) (xy 336.040651 5.04305)
			(xy 336.12061 5.074026) (xy 336.203086 5.097493) (xy 336.287376 5.113249) (xy 336.372759 5.121161)
			(xy 336.458509 5.121161) (xy 336.543892 5.113249) (xy 336.628182 5.097493) (xy 336.710658 5.074026)
			(xy 336.790617 5.04305) (xy 336.81282 5.031994) (xy 340.4235 5.031994) (xy 340.4235 5.895594) (xy 340.423986 5.922845)
			(xy 340.431742 5.976793) (xy 340.447097 6.029088) (xy 340.469739 6.078665) (xy 340.499205 6.124515)
			(xy 340.534896 6.165706) (xy 340.576087 6.201397) (xy 340.621937 6.230863) (xy 340.671514 6.253505)
			(xy 340.723809 6.26886) (xy 340.777757 6.276616) (xy 340.832259 6.276616) (xy 340.886207 6.26886)
			(xy 340.938502 6.253505) (xy 340.988079 6.230863) (xy 341.033929 6.201397) (xy 341.07512 6.165706)
			(xy 341.110811 6.124515) (xy 341.140277 6.078665) (xy 341.162919 6.029088) (xy 341.178274 5.976793)
			(xy 341.18603 5.922845) (xy 341.186516 5.895594) (xy 341.186516 5.031994) (xy 341.18603 5.004743)
			(xy 341.178274 4.950795) (xy 341.162919 4.8985) (xy 341.140277 4.848923) (xy 341.110811 4.803073)
			(xy 341.07512 4.761882) (xy 341.033929 4.726191) (xy 340.988079 4.696725) (xy 340.938502 4.674083)
			(xy 340.886207 4.658728) (xy 340.832259 4.650972) (xy 340.777757 4.650972) (xy 340.723809 4.658728)
			(xy 340.671514 4.674083) (xy 340.621937 4.696725) (xy 340.576087 4.726191) (xy 340.534896 4.761882)
			(xy 340.499205 4.803073) (xy 340.469739 4.848923) (xy 340.447097 4.8985) (xy 340.431742 4.950795)
			(xy 340.423986 5.004743) (xy 340.4235 5.031994) (xy 336.81282 5.031994) (xy 336.867377 5.004828)
			(xy 336.940283 4.959687) (xy 337.008712 4.908011) (xy 337.072082 4.850242) (xy 337.129851 4.786872)
			(xy 337.181527 4.718443) (xy 337.226668 4.645537) (xy 337.26489 4.568777) (xy 337.295866 4.488818)
			(xy 337.319333 4.406342) (xy 337.335089 4.322052) (xy 337.343001 4.236669) (xy 337.343496 4.193794)
			(xy 337.343001 4.150919) (xy 341.838267 4.150919) (xy 341.838267 4.236669) (xy 341.846179 4.322052)
			(xy 341.861935 4.406342) (xy 341.885402 4.488818) (xy 341.916378 4.568777) (xy 341.9546 4.645537)
			(xy 341.999741 4.718443) (xy 342.051417 4.786872) (xy 342.109186 4.850242) (xy 342.172556 4.908011)
			(xy 342.240985 4.959687) (xy 342.313891 5.004828) (xy 342.390651 5.04305) (xy 342.47061 5.074026)
			(xy 342.553086 5.097493) (xy 342.637376 5.113249) (xy 342.722759 5.121161) (xy 342.808509 5.121161)
			(xy 342.893892 5.113249) (xy 342.978182 5.097493) (xy 343.060658 5.074026) (xy 343.140617 5.04305)
			(xy 343.217377 5.004828) (xy 343.290283 4.959687) (xy 343.358712 4.908011) (xy 343.422082 4.850242)
			(xy 343.479851 4.786872) (xy 343.531527 4.718443) (xy 343.576668 4.645537) (xy 343.61489 4.568777)
			(xy 343.645866 4.488818) (xy 343.669333 4.406342) (xy 343.685089 4.322052) (xy 343.693001 4.236669)
			(xy 343.693496 4.193794) (xy 343.693001 4.150919) (xy 373.705107 4.150919) (xy 373.705107 4.236669)
			(xy 373.713019 4.322052) (xy 373.728775 4.406342) (xy 373.752242 4.488818) (xy 373.783218 4.568777)
			(xy 373.82144 4.645537) (xy 373.866581 4.718443) (xy 373.918257 4.786872) (xy 373.976026 4.850242)
			(xy 374.039396 4.908011) (xy 374.107825 4.959687) (xy 374.180731 5.004828) (xy 374.257491 5.04305)
			(xy 374.33745 5.074026) (xy 374.419926 5.097493) (xy 374.504216 5.113249) (xy 374.589599 5.121161)
			(xy 374.675349 5.121161) (xy 374.760732 5.113249) (xy 374.845022 5.097493) (xy 374.927498 5.074026)
			(xy 375.007457 5.04305) (xy 375.02966 5.031994) (xy 376.211592 5.031994) (xy 376.211592 5.895594)
			(xy 376.212078 5.922845) (xy 376.219834 5.976793) (xy 376.235189 6.029088) (xy 376.257831 6.078665)
			(xy 376.287297 6.124515) (xy 376.322988 6.165706) (xy 376.364179 6.201397) (xy 376.410029 6.230863)
			(xy 376.459606 6.253505) (xy 376.511901 6.26886) (xy 376.565849 6.276616) (xy 376.620351 6.276616)
			(xy 376.674299 6.26886) (xy 376.726594 6.253505) (xy 376.776171 6.230863) (xy 376.822021 6.201397)
			(xy 376.863212 6.165706) (xy 376.898903 6.124515) (xy 376.928369 6.078665) (xy 376.951011 6.029088)
			(xy 376.966366 5.976793) (xy 376.974122 5.922845) (xy 376.974608 5.895594) (xy 376.974608 5.031994)
			(xy 376.974122 5.004743) (xy 376.966366 4.950795) (xy 376.951011 4.8985) (xy 376.928369 4.848923)
			(xy 376.898903 4.803073) (xy 376.863212 4.761882) (xy 376.822021 4.726191) (xy 376.776171 4.696725)
			(xy 376.726594 4.674083) (xy 376.674299 4.658728) (xy 376.620351 4.650972) (xy 376.565849 4.650972)
			(xy 376.511901 4.658728) (xy 376.459606 4.674083) (xy 376.410029 4.696725) (xy 376.364179 4.726191)
			(xy 376.322988 4.761882) (xy 376.287297 4.803073) (xy 376.257831 4.848923) (xy 376.235189 4.8985)
			(xy 376.219834 4.950795) (xy 376.212078 5.004743) (xy 376.211592 5.031994) (xy 375.02966 5.031994)
			(xy 375.084217 5.004828) (xy 375.157123 4.959687) (xy 375.225552 4.908011) (xy 375.288922 4.850242)
			(xy 375.346691 4.786872) (xy 375.398367 4.718443) (xy 375.443508 4.645537) (xy 375.48173 4.568777)
			(xy 375.512706 4.488818) (xy 375.536173 4.406342) (xy 375.551929 4.322052) (xy 375.559841 4.236669)
			(xy 375.560336 4.193794) (xy 375.559841 4.150919) (xy 380.055107 4.150919) (xy 380.055107 4.236669)
			(xy 380.063019 4.322052) (xy 380.078775 4.406342) (xy 380.102242 4.488818) (xy 380.133218 4.568777)
			(xy 380.17144 4.645537) (xy 380.216581 4.718443) (xy 380.268257 4.786872) (xy 380.326026 4.850242)
			(xy 380.389396 4.908011) (xy 380.457825 4.959687) (xy 380.530731 5.004828) (xy 380.607491 5.04305)
			(xy 380.68745 5.074026) (xy 380.769926 5.097493) (xy 380.854216 5.113249) (xy 380.939599 5.121161)
			(xy 381.025349 5.121161) (xy 381.110732 5.113249) (xy 381.195022 5.097493) (xy 381.277498 5.074026)
			(xy 381.357457 5.04305) (xy 381.434217 5.004828) (xy 381.507123 4.959687) (xy 381.575552 4.908011)
			(xy 381.638922 4.850242) (xy 381.696691 4.786872) (xy 381.748367 4.718443) (xy 381.793508 4.645537)
			(xy 381.83173 4.568777) (xy 381.862706 4.488818) (xy 381.886173 4.406342) (xy 381.901929 4.322052)
			(xy 381.909841 4.236669) (xy 381.910336 4.193794) (xy 381.909841 4.150919) (xy 381.901929 4.065536)
			(xy 381.886173 3.981246) (xy 381.862706 3.89877) (xy 381.83173 3.818811) (xy 381.793508 3.742051)
			(xy 381.748367 3.669145) (xy 381.696691 3.600716) (xy 381.638922 3.537346) (xy 381.575552 3.479577)
			(xy 381.507123 3.427901) (xy 381.434217 3.38276) (xy 381.357457 3.344538) (xy 381.277498 3.313562)
			(xy 381.195022 3.290095) (xy 381.110732 3.274339) (xy 381.025349 3.266427) (xy 380.939599 3.266427)
			(xy 380.854216 3.274339) (xy 380.769926 3.290095) (xy 380.68745 3.313562) (xy 380.607491 3.344538)
			(xy 380.530731 3.38276) (xy 380.457825 3.427901) (xy 380.389396 3.479577) (xy 380.326026 3.537346)
			(xy 380.268257 3.600716) (xy 380.216581 3.669145) (xy 380.17144 3.742051) (xy 380.133218 3.818811)
			(xy 380.102242 3.89877) (xy 380.078775 3.981246) (xy 380.063019 4.065536) (xy 380.055107 4.150919)
			(xy 375.559841 4.150919) (xy 375.551929 4.065536) (xy 375.536173 3.981246) (xy 375.512706 3.89877)
			(xy 375.48173 3.818811) (xy 375.443508 3.742051) (xy 375.398367 3.669145) (xy 375.346691 3.600716)
			(xy 375.288922 3.537346) (xy 375.225552 3.479577) (xy 375.157123 3.427901) (xy 375.084217 3.38276)
			(xy 375.007457 3.344538) (xy 374.927498 3.313562) (xy 374.845022 3.290095) (xy 374.760732 3.274339)
			(xy 374.675349 3.266427) (xy 374.589599 3.266427) (xy 374.504216 3.274339) (xy 374.419926 3.290095)
			(xy 374.33745 3.313562) (xy 374.257491 3.344538) (xy 374.180731 3.38276) (xy 374.107825 3.427901)
			(xy 374.039396 3.479577) (xy 373.976026 3.537346) (xy 373.918257 3.600716) (xy 373.866581 3.669145)
			(xy 373.82144 3.742051) (xy 373.783218 3.818811) (xy 373.752242 3.89877) (xy 373.728775 3.981246)
			(xy 373.713019 4.065536) (xy 373.705107 4.150919) (xy 343.693001 4.150919) (xy 343.685089 4.065536)
			(xy 343.669333 3.981246) (xy 343.645866 3.89877) (xy 343.61489 3.818811) (xy 343.576668 3.742051)
			(xy 343.531527 3.669145) (xy 343.479851 3.600716) (xy 343.422082 3.537346) (xy 343.358712 3.479577)
			(xy 343.290283 3.427901) (xy 343.217377 3.38276) (xy 343.140617 3.344538) (xy 343.060658 3.313562)
			(xy 342.978182 3.290095) (xy 342.893892 3.274339) (xy 342.808509 3.266427) (xy 342.722759 3.266427)
			(xy 342.637376 3.274339) (xy 342.553086 3.290095) (xy 342.47061 3.313562) (xy 342.390651 3.344538)
			(xy 342.313891 3.38276) (xy 342.240985 3.427901) (xy 342.172556 3.479577) (xy 342.109186 3.537346)
			(xy 342.051417 3.600716) (xy 341.999741 3.669145) (xy 341.9546 3.742051) (xy 341.916378 3.818811)
			(xy 341.885402 3.89877) (xy 341.861935 3.981246) (xy 341.846179 4.065536) (xy 341.838267 4.150919)
			(xy 337.343001 4.150919) (xy 337.335089 4.065536) (xy 337.319333 3.981246) (xy 337.295866 3.89877)
			(xy 337.26489 3.818811) (xy 337.226668 3.742051) (xy 337.181527 3.669145) (xy 337.129851 3.600716)
			(xy 337.072082 3.537346) (xy 337.008712 3.479577) (xy 336.940283 3.427901) (xy 336.867377 3.38276)
			(xy 336.790617 3.344538) (xy 336.710658 3.313562) (xy 336.628182 3.290095) (xy 336.543892 3.274339)
			(xy 336.458509 3.266427) (xy 336.372759 3.266427) (xy 336.287376 3.274339) (xy 336.203086 3.290095)
			(xy 336.12061 3.313562) (xy 336.040651 3.344538) (xy 335.963891 3.38276) (xy 335.890985 3.427901)
			(xy 335.822556 3.479577) (xy 335.759186 3.537346) (xy 335.701417 3.600716) (xy 335.649741 3.669145)
			(xy 335.6046 3.742051) (xy 335.566378 3.818811) (xy 335.535402 3.89877) (xy 335.511935 3.981246)
			(xy 335.496179 4.065536) (xy 335.488267 4.150919) (xy 333.050655 4.150919) (xy 333.042743 4.065536)
			(xy 333.026987 3.981246) (xy 333.00352 3.89877) (xy 332.972544 3.818811) (xy 332.934322 3.742051)
			(xy 332.889181 3.669145) (xy 332.837505 3.600716) (xy 332.779736 3.537346) (xy 332.716366 3.479577)
			(xy 332.647937 3.427901) (xy 332.575031 3.38276) (xy 332.498271 3.344538) (xy 332.418312 3.313562)
			(xy 332.335836 3.290095) (xy 332.251546 3.274339) (xy 332.166163 3.266427) (xy 332.080413 3.266427)
			(xy 331.99503 3.274339) (xy 331.91074 3.290095) (xy 331.828264 3.313562) (xy 331.748305 3.344538)
			(xy 331.671545 3.38276) (xy 331.598639 3.427901) (xy 331.53021 3.479577) (xy 331.46684 3.537346)
			(xy 331.409071 3.600716) (xy 331.357395 3.669145) (xy 331.312254 3.742051) (xy 331.274032 3.818811)
			(xy 331.243056 3.89877) (xy 331.219589 3.981246) (xy 331.203833 4.065536) (xy 331.195921 4.150919)
			(xy 326.700655 4.150919) (xy 326.692743 4.065536) (xy 326.676987 3.981246) (xy 326.65352 3.89877)
			(xy 326.622544 3.818811) (xy 326.584322 3.742051) (xy 326.539181 3.669145) (xy 326.487505 3.600716)
			(xy 326.429736 3.537346) (xy 326.366366 3.479577) (xy 326.297937 3.427901) (xy 326.225031 3.38276)
			(xy 326.148271 3.344538) (xy 326.068312 3.313562) (xy 325.985836 3.290095) (xy 325.901546 3.274339)
			(xy 325.816163 3.266427) (xy 325.730413 3.266427) (xy 325.64503 3.274339) (xy 325.56074 3.290095)
			(xy 325.478264 3.313562) (xy 325.398305 3.344538) (xy 325.321545 3.38276) (xy 325.248639 3.427901)
			(xy 325.18021 3.479577) (xy 325.11684 3.537346) (xy 325.059071 3.600716) (xy 325.007395 3.669145)
			(xy 324.962254 3.742051) (xy 324.924032 3.818811) (xy 324.893056 3.89877) (xy 324.869589 3.981246)
			(xy 324.853833 4.065536) (xy 324.845921 4.150919) (xy 265.125975 4.150919) (xy 265.118063 4.065536)
			(xy 265.102307 3.981246) (xy 265.07884 3.89877) (xy 265.047864 3.818811) (xy 265.009642 3.742051)
			(xy 264.964501 3.669145) (xy 264.912825 3.600716) (xy 264.855056 3.537346) (xy 264.791686 3.479577)
			(xy 264.723257 3.427901) (xy 264.650351 3.38276) (xy 264.573591 3.344538) (xy 264.493632 3.313562)
			(xy 264.411156 3.290095) (xy 264.326866 3.274339) (xy 264.241483 3.266427) (xy 264.155733 3.266427)
			(xy 264.07035 3.274339) (xy 263.98606 3.290095) (xy 263.903584 3.313562) (xy 263.823625 3.344538)
			(xy 263.746865 3.38276) (xy 263.673959 3.427901) (xy 263.60553 3.479577) (xy 263.54216 3.537346)
			(xy 263.484391 3.600716) (xy 263.432715 3.669145) (xy 263.387574 3.742051) (xy 263.349352 3.818811)
			(xy 263.318376 3.89877) (xy 263.294909 3.981246) (xy 263.279153 4.065536) (xy 263.271241 4.150919)
			(xy 258.775975 4.150919) (xy 258.768063 4.065536) (xy 258.752307 3.981246) (xy 258.72884 3.89877)
			(xy 258.697864 3.818811) (xy 258.659642 3.742051) (xy 258.614501 3.669145) (xy 258.562825 3.600716)
			(xy 258.505056 3.537346) (xy 258.441686 3.479577) (xy 258.373257 3.427901) (xy 258.300351 3.38276)
			(xy 258.223591 3.344538) (xy 258.143632 3.313562) (xy 258.061156 3.290095) (xy 257.976866 3.274339)
			(xy 257.891483 3.266427) (xy 257.805733 3.266427) (xy 257.72035 3.274339) (xy 257.63606 3.290095)
			(xy 257.553584 3.313562) (xy 257.473625 3.344538) (xy 257.396865 3.38276) (xy 257.323959 3.427901)
			(xy 257.25553 3.479577) (xy 257.19216 3.537346) (xy 257.134391 3.600716) (xy 257.082715 3.669145)
			(xy 257.037574 3.742051) (xy 256.999352 3.818811) (xy 256.968376 3.89877) (xy 256.944909 3.981246)
			(xy 256.929153 4.065536) (xy 256.921241 4.150919) (xy 254.465119 4.150919) (xy 254.465087 4.148125)
			(xy 254.457175 4.062742) (xy 254.441419 3.978452) (xy 254.417952 3.895976) (xy 254.386976 3.816017)
			(xy 254.348754 3.739257) (xy 254.303613 3.666351) (xy 254.251937 3.597922) (xy 254.194168 3.534552)
			(xy 254.130798 3.476783) (xy 254.062369 3.425107) (xy 253.989463 3.379966) (xy 253.912703 3.341744)
			(xy 253.832744 3.310768) (xy 253.750268 3.287301) (xy 253.665978 3.271545) (xy 253.580595 3.263633)
			(xy 253.494845 3.263633) (xy 253.409462 3.271545) (xy 253.325172 3.287301) (xy 253.242696 3.310768)
			(xy 253.162737 3.341744) (xy 253.085977 3.379966) (xy 253.013071 3.425107) (xy 252.944642 3.476783)
			(xy 252.881272 3.534552) (xy 252.823503 3.597922) (xy 252.771827 3.666351) (xy 252.726686 3.739257)
			(xy 252.688464 3.816017) (xy 252.657488 3.895976) (xy 252.634021 3.978452) (xy 252.618265 4.062742)
			(xy 252.610353 4.148125) (xy 248.115087 4.148125) (xy 248.107175 4.062742) (xy 248.091419 3.978452)
			(xy 248.067952 3.895976) (xy 248.036976 3.816017) (xy 247.998754 3.739257) (xy 247.953613 3.666351)
			(xy 247.901937 3.597922) (xy 247.844168 3.534552) (xy 247.780798 3.476783) (xy 247.712369 3.425107)
			(xy 247.639463 3.379966) (xy 247.562703 3.341744) (xy 247.482744 3.310768) (xy 247.400268 3.287301)
			(xy 247.315978 3.271545) (xy 247.230595 3.263633) (xy 247.144845 3.263633) (xy 247.059462 3.271545)
			(xy 246.975172 3.287301) (xy 246.892696 3.310768) (xy 246.812737 3.341744) (xy 246.735977 3.379966)
			(xy 246.663071 3.425107) (xy 246.594642 3.476783) (xy 246.531272 3.534552) (xy 246.473503 3.597922)
			(xy 246.421827 3.666351) (xy 246.376686 3.739257) (xy 246.338464 3.816017) (xy 246.307488 3.895976)
			(xy 246.284021 3.978452) (xy 246.268265 4.062742) (xy 246.260353 4.148125) (xy 186.540407 4.148125)
			(xy 186.532495 4.062742) (xy 186.516739 3.978452) (xy 186.493272 3.895976) (xy 186.462296 3.816017)
			(xy 186.424074 3.739257) (xy 186.378933 3.666351) (xy 186.327257 3.597922) (xy 186.269488 3.534552)
			(xy 186.206118 3.476783) (xy 186.137689 3.425107) (xy 186.064783 3.379966) (xy 185.988023 3.341744)
			(xy 185.908064 3.310768) (xy 185.825588 3.287301) (xy 185.741298 3.271545) (xy 185.655915 3.263633)
			(xy 185.570165 3.263633) (xy 185.484782 3.271545) (xy 185.400492 3.287301) (xy 185.318016 3.310768)
			(xy 185.238057 3.341744) (xy 185.161297 3.379966) (xy 185.088391 3.425107) (xy 185.019962 3.476783)
			(xy 184.956592 3.534552) (xy 184.898823 3.597922) (xy 184.847147 3.666351) (xy 184.802006 3.739257)
			(xy 184.763784 3.816017) (xy 184.732808 3.895976) (xy 184.709341 3.978452) (xy 184.693585 4.062742)
			(xy 184.685673 4.148125) (xy 180.190407 4.148125) (xy 180.182495 4.062742) (xy 180.166739 3.978452)
			(xy 180.143272 3.895976) (xy 180.112296 3.816017) (xy 180.074074 3.739257) (xy 180.028933 3.666351)
			(xy 179.977257 3.597922) (xy 179.919488 3.534552) (xy 179.856118 3.476783) (xy 179.787689 3.425107)
			(xy 179.714783 3.379966) (xy 179.638023 3.341744) (xy 179.558064 3.310768) (xy 179.475588 3.287301)
			(xy 179.391298 3.271545) (xy 179.305915 3.263633) (xy 179.220165 3.263633) (xy 179.134782 3.271545)
			(xy 179.050492 3.287301) (xy 178.968016 3.310768) (xy 178.888057 3.341744) (xy 178.811297 3.379966)
			(xy 178.738391 3.425107) (xy 178.669962 3.476783) (xy 178.606592 3.534552) (xy 178.548823 3.597922)
			(xy 178.497147 3.666351) (xy 178.452006 3.739257) (xy 178.413784 3.816017) (xy 178.382808 3.895976)
			(xy 178.359341 3.978452) (xy 178.343585 4.062742) (xy 178.335673 4.148125) (xy 0.508 4.148125) (xy 0.508 -7.78002)
			(xy 0.508522 -7.835827) (xy 0.516863 -7.947129) (xy 0.533498 -8.057497) (xy 0.558334 -8.166312) (xy 0.591233 -8.272968)
			(xy 0.63201 -8.376867) (xy 0.680438 -8.477428) (xy 0.736245 -8.574088) (xy 0.799119 -8.666308) (xy 0.868709 -8.753572)
			(xy 0.944626 -8.835391) (xy 1.026445 -8.911308) (xy 1.113708 -8.980898) (xy 1.205928 -9.043773) (xy 1.302589 -9.09958)
			(xy 1.40315 -9.148008) (xy 1.507048 -9.188786) (xy 1.613704 -9.221685) (xy 1.722519 -9.246521) (xy 1.832887 -9.263157)
			(xy 1.944189 -9.271498) (xy 1.999996 -9.272016) (xy 9.10209 -9.272016) (xy 9.157898 -9.271495) (xy 9.269201 -9.263154)
			(xy 9.379569 -9.24652) (xy 9.488386 -9.221684) (xy 9.595043 -9.188786) (xy 9.698942 -9.148009) (xy 9.799505 -9.099582)
			(xy 9.896167 -9.043775) (xy 9.988388 -8.980901) (xy 10.075653 -8.911311) (xy 10.157473 -8.835394)
			(xy 10.233392 -8.753575) (xy 10.302983 -8.666312) (xy 10.365859 -8.574092) (xy 10.421668 -8.477431)
			(xy 10.470097 -8.37687) (xy 10.510876 -8.272971) (xy 10.543776 -8.166315) (xy 10.568614 -8.057499)
			(xy 10.585251 -7.94713) (xy 10.593594 -7.835828) (xy 10.594086 -7.78002) (xy 10.594086 0.999998)
			(xy 10.59457 1.070352) (xy 10.60246 1.210839) (xy 10.618214 1.350662) (xy 10.641783 1.489382) (xy 10.673094 1.626562)
			(xy 10.712047 1.761771) (xy 10.758519 1.894583) (xy 10.812366 2.02458) (xy 10.873417 2.151354) (xy 10.94148 2.274505)
			(xy 11.016341 2.393646) (xy 11.097765 2.508402) (xy 11.185495 2.618411) (xy 11.279255 2.723329) (xy 11.378751 2.822825)
			(xy 11.483669 2.916585) (xy 11.593678 3.004315) (xy 11.708434 3.085739) (xy 11.827575 3.1606) (xy 11.950726 3.228663)
			(xy 12.0775 3.289714) (xy 12.207497 3.343561) (xy 12.340309 3.390033) (xy 12.475518 3.428986) (xy 12.612698 3.460297)
			(xy 12.751418 3.483866) (xy 12.891241 3.49962) (xy 13.031728 3.50751) (xy 13.102082 3.507994) (xy 81.701894 3.507994)
			(xy 81.772248 3.50751) (xy 81.912735 3.499621) (xy 82.052558 3.483867) (xy 82.191278 3.460297) (xy 82.328459 3.428987)
			(xy 82.463668 3.390034) (xy 82.59648 3.343562) (xy 82.726477 3.289715) (xy 82.853251 3.228664) (xy 82.976402 3.160601)
			(xy 83.095543 3.08574) (xy 83.2103 3.004317) (xy 83.32031 2.916587) (xy 83.425228 2.822826) (xy 83.524724 2.723331)
			(xy 83.618484 2.618413) (xy 83.706214 2.508403) (xy 83.787638 2.393647) (xy 83.862499 2.274506) (xy 83.930563 2.151355)
			(xy 83.991614 2.024581) (xy 84.04546 1.894584) (xy 84.091933 1.761772) (xy 84.130886 1.626563) (xy 84.135094 1.608125)
			(xy 178.335673 1.608125) (xy 178.335673 1.693875) (xy 178.343585 1.779258) (xy 178.359341 1.863548)
			(xy 178.382808 1.946024) (xy 178.413784 2.025983) (xy 178.452006 2.102743) (xy 178.497147 2.175649)
			(xy 178.548823 2.244078) (xy 178.606592 2.307448) (xy 178.669962 2.365217) (xy 178.738391 2.416893)
			(xy 178.811297 2.462034) (xy 178.888057 2.500256) (xy 178.968016 2.531232) (xy 179.050492 2.554699)
			(xy 179.134782 2.570455) (xy 179.220165 2.578367) (xy 179.305915 2.578367) (xy 179.391298 2.570455)
			(xy 179.475588 2.554699) (xy 179.558064 2.531232) (xy 179.638023 2.500256) (xy 179.660226 2.4892)
			(xy 183.270652 2.4892) (xy 183.270652 3.3528) (xy 183.271138 3.380069) (xy 183.2789 3.434053) (xy 183.294265 3.486383)
			(xy 183.316922 3.535993) (xy 183.346408 3.581874) (xy 183.382123 3.623091) (xy 183.42334 3.658806)
			(xy 183.469221 3.688292) (xy 183.518831 3.710949) (xy 183.571161 3.726314) (xy 183.625145 3.734076)
			(xy 183.679683 3.734076) (xy 183.733667 3.726314) (xy 183.785997 3.710949) (xy 183.835607 3.688292)
			(xy 183.881488 3.658806) (xy 183.922705 3.623091) (xy 183.95842 3.581874) (xy 183.987906 3.535993)
			(xy 184.010563 3.486383) (xy 184.025928 3.434053) (xy 184.03369 3.380069) (xy 184.034176 3.3528)
			(xy 184.034176 2.4892) (xy 184.03369 2.461931) (xy 184.025928 2.407947) (xy 184.010563 2.355617)
			(xy 183.987906 2.306007) (xy 183.95842 2.260126) (xy 183.922705 2.218909) (xy 183.881488 2.183194)
			(xy 183.835607 2.153708) (xy 183.785997 2.131051) (xy 183.733667 2.115686) (xy 183.679683 2.107924)
			(xy 183.625145 2.107924) (xy 183.571161 2.115686) (xy 183.518831 2.131051) (xy 183.469221 2.153708)
			(xy 183.42334 2.183194) (xy 183.382123 2.218909) (xy 183.346408 2.260126) (xy 183.316922 2.306007)
			(xy 183.294265 2.355617) (xy 183.2789 2.407947) (xy 183.271138 2.461931) (xy 183.270652 2.4892) (xy 179.660226 2.4892)
			(xy 179.714783 2.462034) (xy 179.787689 2.416893) (xy 179.856118 2.365217) (xy 179.919488 2.307448)
			(xy 179.977257 2.244078) (xy 180.028933 2.175649) (xy 180.074074 2.102743) (xy 180.112296 2.025983)
			(xy 180.143272 1.946024) (xy 180.166739 1.863548) (xy 180.182495 1.779258) (xy 180.190407 1.693875)
			(xy 180.190902 1.651) (xy 180.190407 1.608125) (xy 184.685673 1.608125) (xy 184.685673 1.693875)
			(xy 184.693585 1.779258) (xy 184.709341 1.863548) (xy 184.732808 1.946024) (xy 184.763784 2.025983)
			(xy 184.802006 2.102743) (xy 184.847147 2.175649) (xy 184.898823 2.244078) (xy 184.956592 2.307448)
			(xy 185.019962 2.365217) (xy 185.088391 2.416893) (xy 185.161297 2.462034) (xy 185.238057 2.500256)
			(xy 185.318016 2.531232) (xy 185.400492 2.554699) (xy 185.484782 2.570455) (xy 185.570165 2.578367)
			(xy 185.655915 2.578367) (xy 185.741298 2.570455) (xy 185.825588 2.554699) (xy 185.908064 2.531232)
			(xy 185.988023 2.500256) (xy 186.064783 2.462034) (xy 186.137689 2.416893) (xy 186.206118 2.365217)
			(xy 186.269488 2.307448) (xy 186.327257 2.244078) (xy 186.378933 2.175649) (xy 186.424074 2.102743)
			(xy 186.462296 2.025983) (xy 186.493272 1.946024) (xy 186.516739 1.863548) (xy 186.532495 1.779258)
			(xy 186.540407 1.693875) (xy 186.540902 1.651) (xy 186.540407 1.608125) (xy 246.260353 1.608125)
			(xy 246.260353 1.693875) (xy 246.268265 1.779258) (xy 246.284021 1.863548) (xy 246.307488 1.946024)
			(xy 246.338464 2.025983) (xy 246.376686 2.102743) (xy 246.421827 2.175649) (xy 246.473503 2.244078)
			(xy 246.531272 2.307448) (xy 246.594642 2.365217) (xy 246.663071 2.416893) (xy 246.735977 2.462034)
			(xy 246.812737 2.500256) (xy 246.892696 2.531232) (xy 246.975172 2.554699) (xy 247.059462 2.570455)
			(xy 247.144845 2.578367) (xy 247.230595 2.578367) (xy 247.315978 2.570455) (xy 247.400268 2.554699)
			(xy 247.482744 2.531232) (xy 247.562703 2.500256) (xy 247.584906 2.4892) (xy 248.766584 2.4892) (xy 248.766584 3.3528)
			(xy 248.76707 3.380069) (xy 248.774832 3.434053) (xy 248.790197 3.486383) (xy 248.812854 3.535993)
			(xy 248.84234 3.581874) (xy 248.878055 3.623091) (xy 248.919272 3.658806) (xy 248.965153 3.688292)
			(xy 249.014763 3.710949) (xy 249.067093 3.726314) (xy 249.121077 3.734076) (xy 249.175615 3.734076)
			(xy 249.229599 3.726314) (xy 249.281929 3.710949) (xy 249.331539 3.688292) (xy 249.37742 3.658806)
			(xy 249.418637 3.623091) (xy 249.454352 3.581874) (xy 249.483838 3.535993) (xy 249.506495 3.486383)
			(xy 249.52186 3.434053) (xy 249.529622 3.380069) (xy 249.530108 3.3528) (xy 249.530108 2.4892) (xy 249.529622 2.461931)
			(xy 249.52186 2.407947) (xy 249.506495 2.355617) (xy 249.483838 2.306007) (xy 249.454352 2.260126)
			(xy 249.418637 2.218909) (xy 249.37742 2.183194) (xy 249.331539 2.153708) (xy 249.281929 2.131051)
			(xy 249.229599 2.115686) (xy 249.175615 2.107924) (xy 249.121077 2.107924) (xy 249.067093 2.115686)
			(xy 249.014763 2.131051) (xy 248.965153 2.153708) (xy 248.919272 2.183194) (xy 248.878055 2.218909)
			(xy 248.84234 2.260126) (xy 248.812854 2.306007) (xy 248.790197 2.355617) (xy 248.774832 2.407947)
			(xy 248.76707 2.461931) (xy 248.766584 2.4892) (xy 247.584906 2.4892) (xy 247.639463 2.462034) (xy 247.712369 2.416893)
			(xy 247.780798 2.365217) (xy 247.844168 2.307448) (xy 247.901937 2.244078) (xy 247.953613 2.175649)
			(xy 247.998754 2.102743) (xy 248.036976 2.025983) (xy 248.067952 1.946024) (xy 248.091419 1.863548)
			(xy 248.107175 1.779258) (xy 248.115087 1.693875) (xy 248.115582 1.651) (xy 248.115087 1.608125)
			(xy 252.610353 1.608125) (xy 252.610353 1.693875) (xy 252.618265 1.779258) (xy 252.634021 1.863548)
			(xy 252.657488 1.946024) (xy 252.688464 2.025983) (xy 252.726686 2.102743) (xy 252.771827 2.175649)
			(xy 252.823503 2.244078) (xy 252.881272 2.307448) (xy 252.944642 2.365217) (xy 253.013071 2.416893)
			(xy 253.085977 2.462034) (xy 253.162737 2.500256) (xy 253.242696 2.531232) (xy 253.325172 2.554699)
			(xy 253.409462 2.570455) (xy 253.494845 2.578367) (xy 253.580595 2.578367) (xy 253.665978 2.570455)
			(xy 253.750268 2.554699) (xy 253.832744 2.531232) (xy 253.912703 2.500256) (xy 253.989463 2.462034)
			(xy 254.062369 2.416893) (xy 254.130798 2.365217) (xy 254.194168 2.307448) (xy 254.251937 2.244078)
			(xy 254.303613 2.175649) (xy 254.348754 2.102743) (xy 254.386976 2.025983) (xy 254.417952 1.946024)
			(xy 254.441419 1.863548) (xy 254.457175 1.779258) (xy 254.465087 1.693875) (xy 254.465582 1.651)
			(xy 254.465119 1.610919) (xy 256.921241 1.610919) (xy 256.921241 1.696669) (xy 256.929153 1.782052)
			(xy 256.944909 1.866342) (xy 256.968376 1.948818) (xy 256.999352 2.028777) (xy 257.037574 2.105537)
			(xy 257.082715 2.178443) (xy 257.134391 2.246872) (xy 257.19216 2.310242) (xy 257.25553 2.368011)
			(xy 257.323959 2.419687) (xy 257.396865 2.464828) (xy 257.473625 2.50305) (xy 257.553584 2.534026)
			(xy 257.63606 2.557493) (xy 257.72035 2.573249) (xy 257.805733 2.581161) (xy 257.891483 2.581161)
			(xy 257.976866 2.573249) (xy 258.061156 2.557493) (xy 258.143632 2.534026) (xy 258.223591 2.50305)
			(xy 258.245794 2.491994) (xy 261.85622 2.491994) (xy 261.85622 3.355594) (xy 261.856706 3.382863)
			(xy 261.864468 3.436847) (xy 261.879833 3.489177) (xy 261.90249 3.538787) (xy 261.931976 3.584668)
			(xy 261.967691 3.625885) (xy 262.008908 3.6616) (xy 262.054789 3.691086) (xy 262.104399 3.713743)
			(xy 262.156729 3.729108) (xy 262.210713 3.73687) (xy 262.265251 3.73687) (xy 262.319235 3.729108)
			(xy 262.371565 3.713743) (xy 262.421175 3.691086) (xy 262.467056 3.6616) (xy 262.508273 3.625885)
			(xy 262.543988 3.584668) (xy 262.573474 3.538787) (xy 262.596131 3.489177) (xy 262.611496 3.436847)
			(xy 262.619258 3.382863) (xy 262.619744 3.355594) (xy 262.619744 2.491994) (xy 262.619258 2.464725)
			(xy 262.611496 2.410741) (xy 262.596131 2.358411) (xy 262.573474 2.308801) (xy 262.543988 2.26292)
			(xy 262.508273 2.221703) (xy 262.467056 2.185988) (xy 262.421175 2.156502) (xy 262.371565 2.133845)
			(xy 262.319235 2.11848) (xy 262.265251 2.110718) (xy 262.210713 2.110718) (xy 262.156729 2.11848)
			(xy 262.104399 2.133845) (xy 262.054789 2.156502) (xy 262.008908 2.185988) (xy 261.967691 2.221703)
			(xy 261.931976 2.26292) (xy 261.90249 2.308801) (xy 261.879833 2.358411) (xy 261.864468 2.410741)
			(xy 261.856706 2.464725) (xy 261.85622 2.491994) (xy 258.245794 2.491994) (xy 258.300351 2.464828)
			(xy 258.373257 2.419687) (xy 258.441686 2.368011) (xy 258.505056 2.310242) (xy 258.562825 2.246872)
			(xy 258.614501 2.178443) (xy 258.659642 2.105537) (xy 258.697864 2.028777) (xy 258.72884 1.948818)
			(xy 258.752307 1.866342) (xy 258.768063 1.782052) (xy 258.775975 1.696669) (xy 258.77647 1.653794)
			(xy 258.775975 1.610919) (xy 263.271241 1.610919) (xy 263.271241 1.696669) (xy 263.279153 1.782052)
			(xy 263.294909 1.866342) (xy 263.318376 1.948818) (xy 263.349352 2.028777) (xy 263.387574 2.105537)
			(xy 263.432715 2.178443) (xy 263.484391 2.246872) (xy 263.54216 2.310242) (xy 263.60553 2.368011)
			(xy 263.673959 2.419687) (xy 263.746865 2.464828) (xy 263.823625 2.50305) (xy 263.903584 2.534026)
			(xy 263.98606 2.557493) (xy 264.07035 2.573249) (xy 264.155733 2.581161) (xy 264.241483 2.581161)
			(xy 264.326866 2.573249) (xy 264.411156 2.557493) (xy 264.493632 2.534026) (xy 264.573591 2.50305)
			(xy 264.650351 2.464828) (xy 264.723257 2.419687) (xy 264.791686 2.368011) (xy 264.855056 2.310242)
			(xy 264.912825 2.246872) (xy 264.964501 2.178443) (xy 265.009642 2.105537) (xy 265.047864 2.028777)
			(xy 265.07884 1.948818) (xy 265.102307 1.866342) (xy 265.118063 1.782052) (xy 265.125975 1.696669)
			(xy 265.12647 1.653794) (xy 265.125975 1.610919) (xy 324.845921 1.610919) (xy 324.845921 1.696669)
			(xy 324.853833 1.782052) (xy 324.869589 1.866342) (xy 324.893056 1.948818) (xy 324.924032 2.028777)
			(xy 324.962254 2.105537) (xy 325.007395 2.178443) (xy 325.059071 2.246872) (xy 325.11684 2.310242)
			(xy 325.18021 2.368011) (xy 325.248639 2.419687) (xy 325.321545 2.464828) (xy 325.398305 2.50305)
			(xy 325.478264 2.534026) (xy 325.56074 2.557493) (xy 325.64503 2.573249) (xy 325.730413 2.581161)
			(xy 325.816163 2.581161) (xy 325.901546 2.573249) (xy 325.985836 2.557493) (xy 326.068312 2.534026)
			(xy 326.148271 2.50305) (xy 326.170474 2.491994) (xy 327.352152 2.491994) (xy 327.352152 3.355594)
			(xy 327.352638 3.382863) (xy 327.3604 3.436847) (xy 327.375765 3.489177) (xy 327.398422 3.538787)
			(xy 327.427908 3.584668) (xy 327.463623 3.625885) (xy 327.50484 3.6616) (xy 327.550721 3.691086)
			(xy 327.600331 3.713743) (xy 327.652661 3.729108) (xy 327.706645 3.73687) (xy 327.761183 3.73687)
			(xy 327.815167 3.729108) (xy 327.867497 3.713743) (xy 327.917107 3.691086) (xy 327.962988 3.6616)
			(xy 328.004205 3.625885) (xy 328.03992 3.584668) (xy 328.069406 3.538787) (xy 328.092063 3.489177)
			(xy 328.107428 3.436847) (xy 328.11519 3.382863) (xy 328.115676 3.355594) (xy 328.115676 2.491994)
			(xy 328.11519 2.464725) (xy 328.107428 2.410741) (xy 328.092063 2.358411) (xy 328.069406 2.308801)
			(xy 328.03992 2.26292) (xy 328.004205 2.221703) (xy 327.962988 2.185988) (xy 327.917107 2.156502)
			(xy 327.867497 2.133845) (xy 327.815167 2.11848) (xy 327.761183 2.110718) (xy 327.706645 2.110718)
			(xy 327.652661 2.11848) (xy 327.600331 2.133845) (xy 327.550721 2.156502) (xy 327.50484 2.185988)
			(xy 327.463623 2.221703) (xy 327.427908 2.26292) (xy 327.398422 2.308801) (xy 327.375765 2.358411)
			(xy 327.3604 2.410741) (xy 327.352638 2.464725) (xy 327.352152 2.491994) (xy 326.170474 2.491994)
			(xy 326.225031 2.464828) (xy 326.297937 2.419687) (xy 326.366366 2.368011) (xy 326.429736 2.310242)
			(xy 326.487505 2.246872) (xy 326.539181 2.178443) (xy 326.584322 2.105537) (xy 326.622544 2.028777)
			(xy 326.65352 1.948818) (xy 326.676987 1.866342) (xy 326.692743 1.782052) (xy 326.700655 1.696669)
			(xy 326.70115 1.653794) (xy 326.700655 1.610919) (xy 331.195921 1.610919) (xy 331.195921 1.696669)
			(xy 331.203833 1.782052) (xy 331.219589 1.866342) (xy 331.243056 1.948818) (xy 331.274032 2.028777)
			(xy 331.312254 2.105537) (xy 331.357395 2.178443) (xy 331.409071 2.246872) (xy 331.46684 2.310242)
			(xy 331.53021 2.368011) (xy 331.598639 2.419687) (xy 331.671545 2.464828) (xy 331.748305 2.50305)
			(xy 331.828264 2.534026) (xy 331.91074 2.557493) (xy 331.99503 2.573249) (xy 332.080413 2.581161)
			(xy 332.166163 2.581161) (xy 332.251546 2.573249) (xy 332.335836 2.557493) (xy 332.418312 2.534026)
			(xy 332.498271 2.50305) (xy 332.575031 2.464828) (xy 332.647937 2.419687) (xy 332.716366 2.368011)
			(xy 332.779736 2.310242) (xy 332.837505 2.246872) (xy 332.889181 2.178443) (xy 332.934322 2.105537)
			(xy 332.972544 2.028777) (xy 333.00352 1.948818) (xy 333.026987 1.866342) (xy 333.042743 1.782052)
			(xy 333.050655 1.696669) (xy 333.05115 1.653794) (xy 333.050655 1.610919) (xy 335.488267 1.610919)
			(xy 335.488267 1.696669) (xy 335.496179 1.782052) (xy 335.511935 1.866342) (xy 335.535402 1.948818)
			(xy 335.566378 2.028777) (xy 335.6046 2.105537) (xy 335.649741 2.178443) (xy 335.701417 2.246872)
			(xy 335.759186 2.310242) (xy 335.822556 2.368011) (xy 335.890985 2.419687) (xy 335.963891 2.464828)
			(xy 336.040651 2.50305) (xy 336.12061 2.534026) (xy 336.203086 2.557493) (xy 336.287376 2.573249)
			(xy 336.372759 2.581161) (xy 336.458509 2.581161) (xy 336.543892 2.573249) (xy 336.628182 2.557493)
			(xy 336.710658 2.534026) (xy 336.790617 2.50305) (xy 336.81282 2.491994) (xy 340.4235 2.491994) (xy 340.4235 3.355594)
			(xy 340.423986 3.382845) (xy 340.431742 3.436793) (xy 340.447097 3.489088) (xy 340.469739 3.538665)
			(xy 340.499205 3.584515) (xy 340.534896 3.625706) (xy 340.576087 3.661397) (xy 340.621937 3.690863)
			(xy 340.671514 3.713505) (xy 340.723809 3.72886) (xy 340.777757 3.736616) (xy 340.832259 3.736616)
			(xy 340.886207 3.72886) (xy 340.938502 3.713505) (xy 340.988079 3.690863) (xy 341.033929 3.661397)
			(xy 341.07512 3.625706) (xy 341.110811 3.584515) (xy 341.140277 3.538665) (xy 341.162919 3.489088)
			(xy 341.178274 3.436793) (xy 341.18603 3.382845) (xy 341.186516 3.355594) (xy 341.186516 2.491994)
			(xy 341.18603 2.464743) (xy 341.178274 2.410795) (xy 341.162919 2.3585) (xy 341.140277 2.308923)
			(xy 341.110811 2.263073) (xy 341.07512 2.221882) (xy 341.033929 2.186191) (xy 340.988079 2.156725)
			(xy 340.938502 2.134083) (xy 340.886207 2.118728) (xy 340.832259 2.110972) (xy 340.777757 2.110972)
			(xy 340.723809 2.118728) (xy 340.671514 2.134083) (xy 340.621937 2.156725) (xy 340.576087 2.186191)
			(xy 340.534896 2.221882) (xy 340.499205 2.263073) (xy 340.469739 2.308923) (xy 340.447097 2.3585)
			(xy 340.431742 2.410795) (xy 340.423986 2.464743) (xy 340.4235 2.491994) (xy 336.81282 2.491994)
			(xy 336.867377 2.464828) (xy 336.940283 2.419687) (xy 337.008712 2.368011) (xy 337.072082 2.310242)
			(xy 337.129851 2.246872) (xy 337.181527 2.178443) (xy 337.226668 2.105537) (xy 337.26489 2.028777)
			(xy 337.295866 1.948818) (xy 337.319333 1.866342) (xy 337.335089 1.782052) (xy 337.343001 1.696669)
			(xy 337.343496 1.653794) (xy 337.343001 1.610919) (xy 341.838267 1.610919) (xy 341.838267 1.696669)
			(xy 341.846179 1.782052) (xy 341.861935 1.866342) (xy 341.885402 1.948818) (xy 341.916378 2.028777)
			(xy 341.9546 2.105537) (xy 341.999741 2.178443) (xy 342.051417 2.246872) (xy 342.109186 2.310242)
			(xy 342.172556 2.368011) (xy 342.240985 2.419687) (xy 342.313891 2.464828) (xy 342.390651 2.50305)
			(xy 342.47061 2.534026) (xy 342.553086 2.557493) (xy 342.637376 2.573249) (xy 342.722759 2.581161)
			(xy 342.808509 2.581161) (xy 342.893892 2.573249) (xy 342.978182 2.557493) (xy 343.060658 2.534026)
			(xy 343.140617 2.50305) (xy 343.217377 2.464828) (xy 343.290283 2.419687) (xy 343.358712 2.368011)
			(xy 343.422082 2.310242) (xy 343.479851 2.246872) (xy 343.531527 2.178443) (xy 343.576668 2.105537)
			(xy 343.61489 2.028777) (xy 343.645866 1.948818) (xy 343.669333 1.866342) (xy 343.685089 1.782052)
			(xy 343.693001 1.696669) (xy 343.693496 1.653794) (xy 343.693001 1.610919) (xy 373.705107 1.610919)
			(xy 373.705107 1.696669) (xy 373.713019 1.782052) (xy 373.728775 1.866342) (xy 373.752242 1.948818)
			(xy 373.783218 2.028777) (xy 373.82144 2.105537) (xy 373.866581 2.178443) (xy 373.918257 2.246872)
			(xy 373.976026 2.310242) (xy 374.039396 2.368011) (xy 374.107825 2.419687) (xy 374.180731 2.464828)
			(xy 374.257491 2.50305) (xy 374.33745 2.534026) (xy 374.419926 2.557493) (xy 374.504216 2.573249)
			(xy 374.589599 2.581161) (xy 374.675349 2.581161) (xy 374.760732 2.573249) (xy 374.845022 2.557493)
			(xy 374.927498 2.534026) (xy 375.007457 2.50305) (xy 375.02966 2.491994) (xy 376.211592 2.491994)
			(xy 376.211592 3.355594) (xy 376.212078 3.382845) (xy 376.219834 3.436793) (xy 376.235189 3.489088)
			(xy 376.257831 3.538665) (xy 376.287297 3.584515) (xy 376.322988 3.625706) (xy 376.364179 3.661397)
			(xy 376.410029 3.690863) (xy 376.459606 3.713505) (xy 376.511901 3.72886) (xy 376.565849 3.736616)
			(xy 376.620351 3.736616) (xy 376.674299 3.72886) (xy 376.726594 3.713505) (xy 376.776171 3.690863)
			(xy 376.822021 3.661397) (xy 376.863212 3.625706) (xy 376.898903 3.584515) (xy 376.928369 3.538665)
			(xy 376.951011 3.489088) (xy 376.966366 3.436793) (xy 376.974122 3.382845) (xy 376.974608 3.355594)
			(xy 376.974608 2.491994) (xy 376.974122 2.464743) (xy 376.966366 2.410795) (xy 376.951011 2.3585)
			(xy 376.928369 2.308923) (xy 376.898903 2.263073) (xy 376.863212 2.221882) (xy 376.822021 2.186191)
			(xy 376.776171 2.156725) (xy 376.726594 2.134083) (xy 376.674299 2.118728) (xy 376.620351 2.110972)
			(xy 376.565849 2.110972) (xy 376.511901 2.118728) (xy 376.459606 2.134083) (xy 376.410029 2.156725)
			(xy 376.364179 2.186191) (xy 376.322988 2.221882) (xy 376.287297 2.263073) (xy 376.257831 2.308923)
			(xy 376.235189 2.3585) (xy 376.219834 2.410795) (xy 376.212078 2.464743) (xy 376.211592 2.491994)
			(xy 375.02966 2.491994) (xy 375.084217 2.464828) (xy 375.157123 2.419687) (xy 375.225552 2.368011)
			(xy 375.288922 2.310242) (xy 375.346691 2.246872) (xy 375.398367 2.178443) (xy 375.443508 2.105537)
			(xy 375.48173 2.028777) (xy 375.512706 1.948818) (xy 375.536173 1.866342) (xy 375.551929 1.782052)
			(xy 375.559841 1.696669) (xy 375.560336 1.653794) (xy 375.559841 1.610919) (xy 380.055107 1.610919)
			(xy 380.055107 1.696669) (xy 380.063019 1.782052) (xy 380.078775 1.866342) (xy 380.102242 1.948818)
			(xy 380.133218 2.028777) (xy 380.17144 2.105537) (xy 380.216581 2.178443) (xy 380.268257 2.246872)
			(xy 380.326026 2.310242) (xy 380.389396 2.368011) (xy 380.457825 2.419687) (xy 380.530731 2.464828)
			(xy 380.607491 2.50305) (xy 380.68745 2.534026) (xy 380.769926 2.557493) (xy 380.854216 2.573249)
			(xy 380.939599 2.581161) (xy 381.025349 2.581161) (xy 381.110732 2.573249) (xy 381.195022 2.557493)
			(xy 381.277498 2.534026) (xy 381.357457 2.50305) (xy 381.434217 2.464828) (xy 381.507123 2.419687)
			(xy 381.575552 2.368011) (xy 381.638922 2.310242) (xy 381.696691 2.246872) (xy 381.748367 2.178443)
			(xy 381.793508 2.105537) (xy 381.83173 2.028777) (xy 381.862706 1.948818) (xy 381.886173 1.866342)
			(xy 381.901929 1.782052) (xy 381.909841 1.696669) (xy 381.910336 1.653794) (xy 381.909841 1.610919)
			(xy 381.901929 1.525536) (xy 381.886173 1.441246) (xy 381.862706 1.35877) (xy 381.83173 1.278811)
			(xy 381.793508 1.202051) (xy 381.748367 1.129145) (xy 381.696691 1.060716) (xy 381.638922 0.997346)
			(xy 381.575552 0.939577) (xy 381.507123 0.887901) (xy 381.434217 0.84276) (xy 381.357457 0.804538)
			(xy 381.277498 0.773562) (xy 381.195022 0.750095) (xy 381.110732 0.734339) (xy 381.025349 0.726427)
			(xy 380.939599 0.726427) (xy 380.854216 0.734339) (xy 380.769926 0.750095) (xy 380.68745 0.773562)
			(xy 380.607491 0.804538) (xy 380.530731 0.84276) (xy 380.457825 0.887901) (xy 380.389396 0.939577)
			(xy 380.326026 0.997346) (xy 380.268257 1.060716) (xy 380.216581 1.129145) (xy 380.17144 1.202051)
			(xy 380.133218 1.278811) (xy 380.102242 1.35877) (xy 380.078775 1.441246) (xy 380.063019 1.525536)
			(xy 380.055107 1.610919) (xy 375.559841 1.610919) (xy 375.551929 1.525536) (xy 375.536173 1.441246)
			(xy 375.512706 1.35877) (xy 375.48173 1.278811) (xy 375.443508 1.202051) (xy 375.398367 1.129145)
			(xy 375.346691 1.060716) (xy 375.288922 0.997346) (xy 375.225552 0.939577) (xy 375.157123 0.887901)
			(xy 375.084217 0.84276) (xy 375.007457 0.804538) (xy 374.927498 0.773562) (xy 374.845022 0.750095)
			(xy 374.760732 0.734339) (xy 374.675349 0.726427) (xy 374.589599 0.726427) (xy 374.504216 0.734339)
			(xy 374.419926 0.750095) (xy 374.33745 0.773562) (xy 374.257491 0.804538) (xy 374.180731 0.84276)
			(xy 374.107825 0.887901) (xy 374.039396 0.939577) (xy 373.976026 0.997346) (xy 373.918257 1.060716)
			(xy 373.866581 1.129145) (xy 373.82144 1.202051) (xy 373.783218 1.278811) (xy 373.752242 1.35877)
			(xy 373.728775 1.441246) (xy 373.713019 1.525536) (xy 373.705107 1.610919) (xy 343.693001 1.610919)
			(xy 343.685089 1.525536) (xy 343.669333 1.441246) (xy 343.645866 1.35877) (xy 343.61489 1.278811)
			(xy 343.576668 1.202051) (xy 343.531527 1.129145) (xy 343.479851 1.060716) (xy 343.422082 0.997346)
			(xy 343.358712 0.939577) (xy 343.290283 0.887901) (xy 343.217377 0.84276) (xy 343.140617 0.804538)
			(xy 343.060658 0.773562) (xy 342.978182 0.750095) (xy 342.893892 0.734339) (xy 342.808509 0.726427)
			(xy 342.722759 0.726427) (xy 342.637376 0.734339) (xy 342.553086 0.750095) (xy 342.47061 0.773562)
			(xy 342.390651 0.804538) (xy 342.313891 0.84276) (xy 342.240985 0.887901) (xy 342.172556 0.939577)
			(xy 342.109186 0.997346) (xy 342.051417 1.060716) (xy 341.999741 1.129145) (xy 341.9546 1.202051)
			(xy 341.916378 1.278811) (xy 341.885402 1.35877) (xy 341.861935 1.441246) (xy 341.846179 1.525536)
			(xy 341.838267 1.610919) (xy 337.343001 1.610919) (xy 337.335089 1.525536) (xy 337.319333 1.441246)
			(xy 337.295866 1.35877) (xy 337.26489 1.278811) (xy 337.226668 1.202051) (xy 337.181527 1.129145)
			(xy 337.129851 1.060716) (xy 337.072082 0.997346) (xy 337.008712 0.939577) (xy 336.940283 0.887901)
			(xy 336.867377 0.84276) (xy 336.790617 0.804538) (xy 336.710658 0.773562) (xy 336.628182 0.750095)
			(xy 336.543892 0.734339) (xy 336.458509 0.726427) (xy 336.372759 0.726427) (xy 336.287376 0.734339)
			(xy 336.203086 0.750095) (xy 336.12061 0.773562) (xy 336.040651 0.804538) (xy 335.963891 0.84276)
			(xy 335.890985 0.887901) (xy 335.822556 0.939577) (xy 335.759186 0.997346) (xy 335.701417 1.060716)
			(xy 335.649741 1.129145) (xy 335.6046 1.202051) (xy 335.566378 1.278811) (xy 335.535402 1.35877)
			(xy 335.511935 1.441246) (xy 335.496179 1.525536) (xy 335.488267 1.610919) (xy 333.050655 1.610919)
			(xy 333.042743 1.525536) (xy 333.026987 1.441246) (xy 333.00352 1.35877) (xy 332.972544 1.278811)
			(xy 332.934322 1.202051) (xy 332.889181 1.129145) (xy 332.837505 1.060716) (xy 332.779736 0.997346)
			(xy 332.716366 0.939577) (xy 332.647937 0.887901) (xy 332.575031 0.84276) (xy 332.498271 0.804538)
			(xy 332.418312 0.773562) (xy 332.335836 0.750095) (xy 332.251546 0.734339) (xy 332.166163 0.726427)
			(xy 332.080413 0.726427) (xy 331.99503 0.734339) (xy 331.91074 0.750095) (xy 331.828264 0.773562)
			(xy 331.748305 0.804538) (xy 331.671545 0.84276) (xy 331.598639 0.887901) (xy 331.53021 0.939577)
			(xy 331.46684 0.997346) (xy 331.409071 1.060716) (xy 331.357395 1.129145) (xy 331.312254 1.202051)
			(xy 331.274032 1.278811) (xy 331.243056 1.35877) (xy 331.219589 1.441246) (xy 331.203833 1.525536)
			(xy 331.195921 1.610919) (xy 326.700655 1.610919) (xy 326.692743 1.525536) (xy 326.676987 1.441246)
			(xy 326.65352 1.35877) (xy 326.622544 1.278811) (xy 326.584322 1.202051) (xy 326.539181 1.129145)
			(xy 326.487505 1.060716) (xy 326.429736 0.997346) (xy 326.366366 0.939577) (xy 326.297937 0.887901)
			(xy 326.225031 0.84276) (xy 326.148271 0.804538) (xy 326.068312 0.773562) (xy 325.985836 0.750095)
			(xy 325.901546 0.734339) (xy 325.816163 0.726427) (xy 325.730413 0.726427) (xy 325.64503 0.734339)
			(xy 325.56074 0.750095) (xy 325.478264 0.773562) (xy 325.398305 0.804538) (xy 325.321545 0.84276)
			(xy 325.248639 0.887901) (xy 325.18021 0.939577) (xy 325.11684 0.997346) (xy 325.059071 1.060716)
			(xy 325.007395 1.129145) (xy 324.962254 1.202051) (xy 324.924032 1.278811) (xy 324.893056 1.35877)
			(xy 324.869589 1.441246) (xy 324.853833 1.525536) (xy 324.845921 1.610919) (xy 265.125975 1.610919)
			(xy 265.118063 1.525536) (xy 265.102307 1.441246) (xy 265.07884 1.35877) (xy 265.047864 1.278811)
			(xy 265.009642 1.202051) (xy 264.964501 1.129145) (xy 264.912825 1.060716) (xy 264.855056 0.997346)
			(xy 264.791686 0.939577) (xy 264.723257 0.887901) (xy 264.650351 0.84276) (xy 264.573591 0.804538)
			(xy 264.493632 0.773562) (xy 264.411156 0.750095) (xy 264.326866 0.734339) (xy 264.241483 0.726427)
			(xy 264.155733 0.726427) (xy 264.07035 0.734339) (xy 263.98606 0.750095) (xy 263.903584 0.773562)
			(xy 263.823625 0.804538) (xy 263.746865 0.84276) (xy 263.673959 0.887901) (xy 263.60553 0.939577)
			(xy 263.54216 0.997346) (xy 263.484391 1.060716) (xy 263.432715 1.129145) (xy 263.387574 1.202051)
			(xy 263.349352 1.278811) (xy 263.318376 1.35877) (xy 263.294909 1.441246) (xy 263.279153 1.525536)
			(xy 263.271241 1.610919) (xy 258.775975 1.610919) (xy 258.768063 1.525536) (xy 258.752307 1.441246)
			(xy 258.72884 1.35877) (xy 258.697864 1.278811) (xy 258.659642 1.202051) (xy 258.614501 1.129145)
			(xy 258.562825 1.060716) (xy 258.505056 0.997346) (xy 258.441686 0.939577) (xy 258.373257 0.887901)
			(xy 258.300351 0.84276) (xy 258.223591 0.804538) (xy 258.143632 0.773562) (xy 258.061156 0.750095)
			(xy 257.976866 0.734339) (xy 257.891483 0.726427) (xy 257.805733 0.726427) (xy 257.72035 0.734339)
			(xy 257.63606 0.750095) (xy 257.553584 0.773562) (xy 257.473625 0.804538) (xy 257.396865 0.84276)
			(xy 257.323959 0.887901) (xy 257.25553 0.939577) (xy 257.19216 0.997346) (xy 257.134391 1.060716)
			(xy 257.082715 1.129145) (xy 257.037574 1.202051) (xy 256.999352 1.278811) (xy 256.968376 1.35877)
			(xy 256.944909 1.441246) (xy 256.929153 1.525536) (xy 256.921241 1.610919) (xy 254.465119 1.610919)
			(xy 254.465087 1.608125) (xy 254.457175 1.522742) (xy 254.441419 1.438452) (xy 254.417952 1.355976)
			(xy 254.386976 1.276017) (xy 254.348754 1.199257) (xy 254.303613 1.126351) (xy 254.251937 1.057922)
			(xy 254.194168 0.994552) (xy 254.130798 0.936783) (xy 254.062369 0.885107) (xy 253.989463 0.839966)
			(xy 253.912703 0.801744) (xy 253.832744 0.770768) (xy 253.750268 0.747301) (xy 253.665978 0.731545)
			(xy 253.580595 0.723633) (xy 253.494845 0.723633) (xy 253.409462 0.731545) (xy 253.325172 0.747301)
			(xy 253.242696 0.770768) (xy 253.162737 0.801744) (xy 253.085977 0.839966) (xy 253.013071 0.885107)
			(xy 252.944642 0.936783) (xy 252.881272 0.994552) (xy 252.823503 1.057922) (xy 252.771827 1.126351)
			(xy 252.726686 1.199257) (xy 252.688464 1.276017) (xy 252.657488 1.355976) (xy 252.634021 1.438452)
			(xy 252.618265 1.522742) (xy 252.610353 1.608125) (xy 248.115087 1.608125) (xy 248.107175 1.522742)
			(xy 248.091419 1.438452) (xy 248.067952 1.355976) (xy 248.036976 1.276017) (xy 247.998754 1.199257)
			(xy 247.953613 1.126351) (xy 247.901937 1.057922) (xy 247.844168 0.994552) (xy 247.780798 0.936783)
			(xy 247.712369 0.885107) (xy 247.639463 0.839966) (xy 247.562703 0.801744) (xy 247.482744 0.770768)
			(xy 247.400268 0.747301) (xy 247.315978 0.731545) (xy 247.230595 0.723633) (xy 247.144845 0.723633)
			(xy 247.059462 0.731545) (xy 246.975172 0.747301) (xy 246.892696 0.770768) (xy 246.812737 0.801744)
			(xy 246.735977 0.839966) (xy 246.663071 0.885107) (xy 246.594642 0.936783) (xy 246.531272 0.994552)
			(xy 246.473503 1.057922) (xy 246.421827 1.126351) (xy 246.376686 1.199257) (xy 246.338464 1.276017)
			(xy 246.307488 1.355976) (xy 246.284021 1.438452) (xy 246.268265 1.522742) (xy 246.260353 1.608125)
			(xy 186.540407 1.608125) (xy 186.532495 1.522742) (xy 186.516739 1.438452) (xy 186.493272 1.355976)
			(xy 186.462296 1.276017) (xy 186.424074 1.199257) (xy 186.378933 1.126351) (xy 186.327257 1.057922)
			(xy 186.269488 0.994552) (xy 186.206118 0.936783) (xy 186.137689 0.885107) (xy 186.064783 0.839966)
			(xy 185.988023 0.801744) (xy 185.908064 0.770768) (xy 185.825588 0.747301) (xy 185.741298 0.731545)
			(xy 185.655915 0.723633) (xy 185.570165 0.723633) (xy 185.484782 0.731545) (xy 185.400492 0.747301)
			(xy 185.318016 0.770768) (xy 185.238057 0.801744) (xy 185.161297 0.839966) (xy 185.088391 0.885107)
			(xy 185.019962 0.936783) (xy 184.956592 0.994552) (xy 184.898823 1.057922) (xy 184.847147 1.126351)
			(xy 184.802006 1.199257) (xy 184.763784 1.276017) (xy 184.732808 1.355976) (xy 184.709341 1.438452)
			(xy 184.693585 1.522742) (xy 184.685673 1.608125) (xy 180.190407 1.608125) (xy 180.182495 1.522742)
			(xy 180.166739 1.438452) (xy 180.143272 1.355976) (xy 180.112296 1.276017) (xy 180.074074 1.199257)
			(xy 180.028933 1.126351) (xy 179.977257 1.057922) (xy 179.919488 0.994552) (xy 179.856118 0.936783)
			(xy 179.787689 0.885107) (xy 179.714783 0.839966) (xy 179.638023 0.801744) (xy 179.558064 0.770768)
			(xy 179.475588 0.747301) (xy 179.391298 0.731545) (xy 179.305915 0.723633) (xy 179.220165 0.723633)
			(xy 179.134782 0.731545) (xy 179.050492 0.747301) (xy 178.968016 0.770768) (xy 178.888057 0.801744)
			(xy 178.811297 0.839966) (xy 178.738391 0.885107) (xy 178.669962 0.936783) (xy 178.606592 0.994552)
			(xy 178.548823 1.057922) (xy 178.497147 1.126351) (xy 178.452006 1.199257) (xy 178.413784 1.276017)
			(xy 178.382808 1.355976) (xy 178.359341 1.438452) (xy 178.343585 1.522742) (xy 178.335673 1.608125)
			(xy 84.135094 1.608125) (xy 84.162197 1.489382) (xy 84.185766 1.350662) (xy 84.20152 1.210839) (xy 84.20941 1.070352)
			(xy 84.20989 0.999998) (xy 84.20989 -0.931875) (xy 208.043513 -0.931875) (xy 208.043513 -0.846125)
			(xy 208.051425 -0.760742) (xy 208.067181 -0.676452) (xy 208.090648 -0.593976) (xy 208.121624 -0.514017)
			(xy 208.159846 -0.437257) (xy 208.204987 -0.364351) (xy 208.256663 -0.295922) (xy 208.314432 -0.232552)
			(xy 208.377802 -0.174783) (xy 208.446231 -0.123107) (xy 208.519137 -0.077966) (xy 208.595897 -0.039744)
			(xy 208.675856 -0.008768) (xy 208.758332 0.014699) (xy 208.842622 0.030455) (xy 208.928005 0.038367)
			(xy 209.013755 0.038367) (xy 209.099138 0.030455) (xy 209.183428 0.014699) (xy 209.265904 -0.008768)
			(xy 209.345863 -0.039744) (xy 209.422623 -0.077966) (xy 209.495529 -0.123107) (xy 209.563958 -0.174783)
			(xy 209.627328 -0.232552) (xy 209.685097 -0.295922) (xy 209.736773 -0.364351) (xy 209.781914 -0.437257)
			(xy 209.820136 -0.514017) (xy 209.851112 -0.593976) (xy 209.874579 -0.676452) (xy 209.890335 -0.760742)
			(xy 209.898247 -0.846125) (xy 209.898742 -0.889) (xy 209.898247 -0.931875) (xy 214.393513 -0.931875)
			(xy 214.393513 -0.846125) (xy 214.401425 -0.760742) (xy 214.417181 -0.676452) (xy 214.440648 -0.593976)
			(xy 214.471624 -0.514017) (xy 214.509846 -0.437257) (xy 214.554987 -0.364351) (xy 214.606663 -0.295922)
			(xy 214.664432 -0.232552) (xy 214.727802 -0.174783) (xy 214.796231 -0.123107) (xy 214.869137 -0.077966)
			(xy 214.945897 -0.039744) (xy 215.025856 -0.008768) (xy 215.108332 0.014699) (xy 215.192622 0.030455)
			(xy 215.278005 0.038367) (xy 215.363755 0.038367) (xy 215.449138 0.030455) (xy 215.533428 0.014699)
			(xy 215.615904 -0.008768) (xy 215.695863 -0.039744) (xy 215.772623 -0.077966) (xy 215.845529 -0.123107)
			(xy 215.913958 -0.174783) (xy 215.977328 -0.232552) (xy 216.035097 -0.295922) (xy 216.086773 -0.364351)
			(xy 216.131914 -0.437257) (xy 216.170136 -0.514017) (xy 216.201112 -0.593976) (xy 216.224579 -0.676452)
			(xy 216.240335 -0.760742) (xy 216.248247 -0.846125) (xy 216.248742 -0.889) (xy 216.248247 -0.931875)
			(xy 246.260353 -0.931875) (xy 246.260353 -0.846125) (xy 246.268265 -0.760742) (xy 246.284021 -0.676452)
			(xy 246.307488 -0.593976) (xy 246.338464 -0.514017) (xy 246.376686 -0.437257) (xy 246.421827 -0.364351)
			(xy 246.473503 -0.295922) (xy 246.531272 -0.232552) (xy 246.594642 -0.174783) (xy 246.663071 -0.123107)
			(xy 246.735977 -0.077966) (xy 246.812737 -0.039744) (xy 246.892696 -0.008768) (xy 246.975172 0.014699)
			(xy 247.059462 0.030455) (xy 247.144845 0.038367) (xy 247.230595 0.038367) (xy 247.315978 0.030455)
			(xy 247.400268 0.014699) (xy 247.482744 -0.008768) (xy 247.562703 -0.039744) (xy 247.639463 -0.077966)
			(xy 247.712369 -0.123107) (xy 247.780798 -0.174783) (xy 247.844168 -0.232552) (xy 247.901937 -0.295922)
			(xy 247.953613 -0.364351) (xy 247.998754 -0.437257) (xy 248.036976 -0.514017) (xy 248.067952 -0.593976)
			(xy 248.091419 -0.676452) (xy 248.107175 -0.760742) (xy 248.115087 -0.846125) (xy 248.115582 -0.889)
			(xy 248.115087 -0.931875) (xy 252.610353 -0.931875) (xy 252.610353 -0.846125) (xy 252.618265 -0.760742)
			(xy 252.634021 -0.676452) (xy 252.657488 -0.593976) (xy 252.688464 -0.514017) (xy 252.726686 -0.437257)
			(xy 252.771827 -0.364351) (xy 252.823503 -0.295922) (xy 252.881272 -0.232552) (xy 252.944642 -0.174783)
			(xy 253.013071 -0.123107) (xy 253.085977 -0.077966) (xy 253.162737 -0.039744) (xy 253.242696 -0.008768)
			(xy 253.325172 0.014699) (xy 253.409462 0.030455) (xy 253.494845 0.038367) (xy 253.580595 0.038367)
			(xy 253.665978 0.030455) (xy 253.750268 0.014699) (xy 253.832744 -0.008768) (xy 253.912703 -0.039744)
			(xy 253.989463 -0.077966) (xy 254.062369 -0.123107) (xy 254.130798 -0.174783) (xy 254.194168 -0.232552)
			(xy 254.251937 -0.295922) (xy 254.303613 -0.364351) (xy 254.348754 -0.437257) (xy 254.386976 -0.514017)
			(xy 254.417952 -0.593976) (xy 254.441419 -0.676452) (xy 254.457175 -0.760742) (xy 254.465087 -0.846125)
			(xy 254.465582 -0.889) (xy 254.465119 -0.929081) (xy 256.921241 -0.929081) (xy 256.921241 -0.843331)
			(xy 256.929153 -0.757948) (xy 256.944909 -0.673658) (xy 256.968376 -0.591182) (xy 256.999352 -0.511223)
			(xy 257.037574 -0.434463) (xy 257.082715 -0.361557) (xy 257.134391 -0.293128) (xy 257.19216 -0.229758)
			(xy 257.25553 -0.171989) (xy 257.323959 -0.120313) (xy 257.396865 -0.075172) (xy 257.473625 -0.03695)
			(xy 257.553584 -0.005974) (xy 257.63606 0.017493) (xy 257.72035 0.033249) (xy 257.805733 0.041161)
			(xy 257.891483 0.041161) (xy 257.976866 0.033249) (xy 258.061156 0.017493) (xy 258.143632 -0.005974)
			(xy 258.223591 -0.03695) (xy 258.245794 -0.048006) (xy 261.85622 -0.048006) (xy 261.85622 0.815594)
			(xy 261.856706 0.842863) (xy 261.864468 0.896847) (xy 261.879833 0.949177) (xy 261.90249 0.998787)
			(xy 261.931976 1.044668) (xy 261.967691 1.085885) (xy 262.008908 1.1216) (xy 262.054789 1.151086)
			(xy 262.104399 1.173743) (xy 262.156729 1.189108) (xy 262.210713 1.19687) (xy 262.265251 1.19687)
			(xy 262.319235 1.189108) (xy 262.371565 1.173743) (xy 262.421175 1.151086) (xy 262.467056 1.1216)
			(xy 262.508273 1.085885) (xy 262.543988 1.044668) (xy 262.573474 0.998787) (xy 262.596131 0.949177)
			(xy 262.611496 0.896847) (xy 262.619258 0.842863) (xy 262.619744 0.815594) (xy 262.619744 -0.048006)
			(xy 262.619258 -0.075275) (xy 262.611496 -0.129259) (xy 262.596131 -0.181589) (xy 262.573474 -0.231199)
			(xy 262.543988 -0.27708) (xy 262.508273 -0.318297) (xy 262.467056 -0.354012) (xy 262.421175 -0.383498)
			(xy 262.371565 -0.406155) (xy 262.319235 -0.42152) (xy 262.265251 -0.429282) (xy 262.210713 -0.429282)
			(xy 262.156729 -0.42152) (xy 262.104399 -0.406155) (xy 262.054789 -0.383498) (xy 262.008908 -0.354012)
			(xy 261.967691 -0.318297) (xy 261.931976 -0.27708) (xy 261.90249 -0.231199) (xy 261.879833 -0.181589)
			(xy 261.864468 -0.129259) (xy 261.856706 -0.075275) (xy 261.85622 -0.048006) (xy 258.245794 -0.048006)
			(xy 258.300351 -0.075172) (xy 258.373257 -0.120313) (xy 258.441686 -0.171989) (xy 258.505056 -0.229758)
			(xy 258.562825 -0.293128) (xy 258.614501 -0.361557) (xy 258.659642 -0.434463) (xy 258.697864 -0.511223)
			(xy 258.72884 -0.591182) (xy 258.752307 -0.673658) (xy 258.768063 -0.757948) (xy 258.775975 -0.843331)
			(xy 258.77647 -0.886206) (xy 258.775975 -0.929081) (xy 263.271241 -0.929081) (xy 263.271241 -0.843331)
			(xy 263.279153 -0.757948) (xy 263.294909 -0.673658) (xy 263.318376 -0.591182) (xy 263.349352 -0.511223)
			(xy 263.387574 -0.434463) (xy 263.432715 -0.361557) (xy 263.484391 -0.293128) (xy 263.54216 -0.229758)
			(xy 263.60553 -0.171989) (xy 263.673959 -0.120313) (xy 263.746865 -0.075172) (xy 263.823625 -0.03695)
			(xy 263.903584 -0.005974) (xy 263.98606 0.017493) (xy 264.07035 0.033249) (xy 264.155733 0.041161)
			(xy 264.241483 0.041161) (xy 264.326866 0.033249) (xy 264.411156 0.017493) (xy 264.493632 -0.005974)
			(xy 264.573591 -0.03695) (xy 264.650351 -0.075172) (xy 264.723257 -0.120313) (xy 264.791686 -0.171989)
			(xy 264.855056 -0.229758) (xy 264.912825 -0.293128) (xy 264.964501 -0.361557) (xy 265.009642 -0.434463)
			(xy 265.047864 -0.511223) (xy 265.07884 -0.591182) (xy 265.102307 -0.673658) (xy 265.118063 -0.757948)
			(xy 265.125975 -0.843331) (xy 265.12647 -0.886206) (xy 265.125975 -0.929081) (xy 324.845921 -0.929081)
			(xy 324.845921 -0.843331) (xy 324.853833 -0.757948) (xy 324.869589 -0.673658) (xy 324.893056 -0.591182)
			(xy 324.924032 -0.511223) (xy 324.962254 -0.434463) (xy 325.007395 -0.361557) (xy 325.059071 -0.293128)
			(xy 325.11684 -0.229758) (xy 325.18021 -0.171989) (xy 325.248639 -0.120313) (xy 325.321545 -0.075172)
			(xy 325.398305 -0.03695) (xy 325.478264 -0.005974) (xy 325.56074 0.017493) (xy 325.64503 0.033249)
			(xy 325.730413 0.041161) (xy 325.816163 0.041161) (xy 325.901546 0.033249) (xy 325.985836 0.017493)
			(xy 326.068312 -0.005974) (xy 326.148271 -0.03695) (xy 326.170474 -0.048006) (xy 327.352152 -0.048006)
			(xy 327.352152 0.815594) (xy 327.352638 0.842863) (xy 327.3604 0.896847) (xy 327.375765 0.949177)
			(xy 327.398422 0.998787) (xy 327.427908 1.044668) (xy 327.463623 1.085885) (xy 327.50484 1.1216)
			(xy 327.550721 1.151086) (xy 327.600331 1.173743) (xy 327.652661 1.189108) (xy 327.706645 1.19687)
			(xy 327.761183 1.19687) (xy 327.815167 1.189108) (xy 327.867497 1.173743) (xy 327.917107 1.151086)
			(xy 327.962988 1.1216) (xy 328.004205 1.085885) (xy 328.03992 1.044668) (xy 328.069406 0.998787)
			(xy 328.092063 0.949177) (xy 328.107428 0.896847) (xy 328.11519 0.842863) (xy 328.115676 0.815594)
			(xy 328.115676 -0.048006) (xy 328.11519 -0.075275) (xy 328.107428 -0.129259) (xy 328.092063 -0.181589)
			(xy 328.069406 -0.231199) (xy 328.03992 -0.27708) (xy 328.004205 -0.318297) (xy 327.962988 -0.354012)
			(xy 327.917107 -0.383498) (xy 327.867497 -0.406155) (xy 327.815167 -0.42152) (xy 327.761183 -0.429282)
			(xy 327.706645 -0.429282) (xy 327.652661 -0.42152) (xy 327.600331 -0.406155) (xy 327.550721 -0.383498)
			(xy 327.50484 -0.354012) (xy 327.463623 -0.318297) (xy 327.427908 -0.27708) (xy 327.398422 -0.231199)
			(xy 327.375765 -0.181589) (xy 327.3604 -0.129259) (xy 327.352638 -0.075275) (xy 327.352152 -0.048006)
			(xy 326.170474 -0.048006) (xy 326.225031 -0.075172) (xy 326.297937 -0.120313) (xy 326.366366 -0.171989)
			(xy 326.429736 -0.229758) (xy 326.487505 -0.293128) (xy 326.539181 -0.361557) (xy 326.584322 -0.434463)
			(xy 326.622544 -0.511223) (xy 326.65352 -0.591182) (xy 326.676987 -0.673658) (xy 326.692743 -0.757948)
			(xy 326.700655 -0.843331) (xy 326.70115 -0.886206) (xy 326.700655 -0.929081) (xy 331.195921 -0.929081)
			(xy 331.195921 -0.843331) (xy 331.203833 -0.757948) (xy 331.219589 -0.673658) (xy 331.243056 -0.591182)
			(xy 331.274032 -0.511223) (xy 331.312254 -0.434463) (xy 331.357395 -0.361557) (xy 331.409071 -0.293128)
			(xy 331.46684 -0.229758) (xy 331.53021 -0.171989) (xy 331.598639 -0.120313) (xy 331.671545 -0.075172)
			(xy 331.748305 -0.03695) (xy 331.828264 -0.005974) (xy 331.91074 0.017493) (xy 331.99503 0.033249)
			(xy 332.080413 0.041161) (xy 332.166163 0.041161) (xy 332.251546 0.033249) (xy 332.335836 0.017493)
			(xy 332.418312 -0.005974) (xy 332.498271 -0.03695) (xy 332.575031 -0.075172) (xy 332.647937 -0.120313)
			(xy 332.716366 -0.171989) (xy 332.779736 -0.229758) (xy 332.837505 -0.293128) (xy 332.889181 -0.361557)
			(xy 332.934322 -0.434463) (xy 332.972544 -0.511223) (xy 333.00352 -0.591182) (xy 333.026987 -0.673658)
			(xy 333.042743 -0.757948) (xy 333.050655 -0.843331) (xy 333.05115 -0.886206) (xy 333.050655 -0.929081)
			(xy 335.488267 -0.929081) (xy 335.488267 -0.843331) (xy 335.496179 -0.757948) (xy 335.511935 -0.673658)
			(xy 335.535402 -0.591182) (xy 335.566378 -0.511223) (xy 335.6046 -0.434463) (xy 335.649741 -0.361557)
			(xy 335.701417 -0.293128) (xy 335.759186 -0.229758) (xy 335.822556 -0.171989) (xy 335.890985 -0.120313)
			(xy 335.963891 -0.075172) (xy 336.040651 -0.03695) (xy 336.12061 -0.005974) (xy 336.203086 0.017493)
			(xy 336.287376 0.033249) (xy 336.372759 0.041161) (xy 336.458509 0.041161) (xy 336.543892 0.033249)
			(xy 336.628182 0.017493) (xy 336.710658 -0.005974) (xy 336.790617 -0.03695) (xy 336.81282 -0.048006)
			(xy 340.4235 -0.048006) (xy 340.4235 0.815594) (xy 340.423986 0.842845) (xy 340.431742 0.896793)
			(xy 340.447097 0.949088) (xy 340.469739 0.998665) (xy 340.499205 1.044515) (xy 340.534896 1.085706)
			(xy 340.576087 1.121397) (xy 340.621937 1.150863) (xy 340.671514 1.173505) (xy 340.723809 1.18886)
			(xy 340.777757 1.196616) (xy 340.832259 1.196616) (xy 340.886207 1.18886) (xy 340.938502 1.173505)
			(xy 340.988079 1.150863) (xy 341.033929 1.121397) (xy 341.07512 1.085706) (xy 341.110811 1.044515)
			(xy 341.140277 0.998665) (xy 341.162919 0.949088) (xy 341.178274 0.896793) (xy 341.18603 0.842845)
			(xy 341.186516 0.815594) (xy 341.186516 -0.048006) (xy 341.18603 -0.075257) (xy 341.178274 -0.129205)
			(xy 341.162919 -0.1815) (xy 341.140277 -0.231077) (xy 341.110811 -0.276927) (xy 341.07512 -0.318118)
			(xy 341.033929 -0.353809) (xy 340.988079 -0.383275) (xy 340.938502 -0.405917) (xy 340.886207 -0.421272)
			(xy 340.832259 -0.429028) (xy 340.777757 -0.429028) (xy 340.723809 -0.421272) (xy 340.671514 -0.405917)
			(xy 340.621937 -0.383275) (xy 340.576087 -0.353809) (xy 340.534896 -0.318118) (xy 340.499205 -0.276927)
			(xy 340.469739 -0.231077) (xy 340.447097 -0.1815) (xy 340.431742 -0.129205) (xy 340.423986 -0.075257)
			(xy 340.4235 -0.048006) (xy 336.81282 -0.048006) (xy 336.867377 -0.075172) (xy 336.940283 -0.120313)
			(xy 337.008712 -0.171989) (xy 337.072082 -0.229758) (xy 337.129851 -0.293128) (xy 337.181527 -0.361557)
			(xy 337.226668 -0.434463) (xy 337.26489 -0.511223) (xy 337.295866 -0.591182) (xy 337.319333 -0.673658)
			(xy 337.335089 -0.757948) (xy 337.343001 -0.843331) (xy 337.343496 -0.886206) (xy 337.343001 -0.929081)
			(xy 341.838267 -0.929081) (xy 341.838267 -0.843331) (xy 341.846179 -0.757948) (xy 341.861935 -0.673658)
			(xy 341.885402 -0.591182) (xy 341.916378 -0.511223) (xy 341.9546 -0.434463) (xy 341.999741 -0.361557)
			(xy 342.051417 -0.293128) (xy 342.109186 -0.229758) (xy 342.172556 -0.171989) (xy 342.240985 -0.120313)
			(xy 342.313891 -0.075172) (xy 342.390651 -0.03695) (xy 342.47061 -0.005974) (xy 342.553086 0.017493)
			(xy 342.637376 0.033249) (xy 342.722759 0.041161) (xy 342.808509 0.041161) (xy 342.893892 0.033249)
			(xy 342.978182 0.017493) (xy 343.060658 -0.005974) (xy 343.140617 -0.03695) (xy 343.217377 -0.075172)
			(xy 343.290283 -0.120313) (xy 343.358712 -0.171989) (xy 343.422082 -0.229758) (xy 343.479851 -0.293128)
			(xy 343.531527 -0.361557) (xy 343.576668 -0.434463) (xy 343.61489 -0.511223) (xy 343.645866 -0.591182)
			(xy 343.669333 -0.673658) (xy 343.685089 -0.757948) (xy 343.693001 -0.843331) (xy 343.693496 -0.886206)
			(xy 343.693001 -0.929081) (xy 373.705107 -0.929081) (xy 373.705107 -0.843331) (xy 373.713019 -0.757948)
			(xy 373.728775 -0.673658) (xy 373.752242 -0.591182) (xy 373.783218 -0.511223) (xy 373.82144 -0.434463)
			(xy 373.866581 -0.361557) (xy 373.918257 -0.293128) (xy 373.976026 -0.229758) (xy 374.039396 -0.171989)
			(xy 374.107825 -0.120313) (xy 374.180731 -0.075172) (xy 374.257491 -0.03695) (xy 374.33745 -0.005974)
			(xy 374.419926 0.017493) (xy 374.504216 0.033249) (xy 374.589599 0.041161) (xy 374.675349 0.041161)
			(xy 374.760732 0.033249) (xy 374.845022 0.017493) (xy 374.927498 -0.005974) (xy 375.007457 -0.03695)
			(xy 375.02966 -0.048006) (xy 376.211592 -0.048006) (xy 376.211592 0.815594) (xy 376.212078 0.842845)
			(xy 376.219834 0.896793) (xy 376.235189 0.949088) (xy 376.257831 0.998665) (xy 376.287297 1.044515)
			(xy 376.322988 1.085706) (xy 376.364179 1.121397) (xy 376.410029 1.150863) (xy 376.459606 1.173505)
			(xy 376.511901 1.18886) (xy 376.565849 1.196616) (xy 376.620351 1.196616) (xy 376.674299 1.18886)
			(xy 376.726594 1.173505) (xy 376.776171 1.150863) (xy 376.822021 1.121397) (xy 376.863212 1.085706)
			(xy 376.898903 1.044515) (xy 376.928369 0.998665) (xy 376.951011 0.949088) (xy 376.966366 0.896793)
			(xy 376.974122 0.842845) (xy 376.974608 0.815594) (xy 376.974608 -0.048006) (xy 376.974122 -0.075257)
			(xy 376.966366 -0.129205) (xy 376.951011 -0.1815) (xy 376.928369 -0.231077) (xy 376.898903 -0.276927)
			(xy 376.863212 -0.318118) (xy 376.822021 -0.353809) (xy 376.776171 -0.383275) (xy 376.726594 -0.405917)
			(xy 376.674299 -0.421272) (xy 376.620351 -0.429028) (xy 376.565849 -0.429028) (xy 376.511901 -0.421272)
			(xy 376.459606 -0.405917) (xy 376.410029 -0.383275) (xy 376.364179 -0.353809) (xy 376.322988 -0.318118)
			(xy 376.287297 -0.276927) (xy 376.257831 -0.231077) (xy 376.235189 -0.1815) (xy 376.219834 -0.129205)
			(xy 376.212078 -0.075257) (xy 376.211592 -0.048006) (xy 375.02966 -0.048006) (xy 375.084217 -0.075172)
			(xy 375.157123 -0.120313) (xy 375.225552 -0.171989) (xy 375.288922 -0.229758) (xy 375.346691 -0.293128)
			(xy 375.398367 -0.361557) (xy 375.443508 -0.434463) (xy 375.48173 -0.511223) (xy 375.512706 -0.591182)
			(xy 375.536173 -0.673658) (xy 375.551929 -0.757948) (xy 375.559841 -0.843331) (xy 375.560336 -0.886206)
			(xy 375.559841 -0.929081) (xy 380.055107 -0.929081) (xy 380.055107 -0.843331) (xy 380.063019 -0.757948)
			(xy 380.078775 -0.673658) (xy 380.102242 -0.591182) (xy 380.133218 -0.511223) (xy 380.17144 -0.434463)
			(xy 380.216581 -0.361557) (xy 380.268257 -0.293128) (xy 380.326026 -0.229758) (xy 380.389396 -0.171989)
			(xy 380.457825 -0.120313) (xy 380.530731 -0.075172) (xy 380.607491 -0.03695) (xy 380.68745 -0.005974)
			(xy 380.769926 0.017493) (xy 380.854216 0.033249) (xy 380.939599 0.041161) (xy 381.025349 0.041161)
			(xy 381.110732 0.033249) (xy 381.195022 0.017493) (xy 381.277498 -0.005974) (xy 381.357457 -0.03695)
			(xy 381.434217 -0.075172) (xy 381.507123 -0.120313) (xy 381.575552 -0.171989) (xy 381.638922 -0.229758)
			(xy 381.696691 -0.293128) (xy 381.748367 -0.361557) (xy 381.793508 -0.434463) (xy 381.83173 -0.511223)
			(xy 381.862706 -0.591182) (xy 381.886173 -0.673658) (xy 381.901929 -0.757948) (xy 381.909841 -0.843331)
			(xy 381.910336 -0.886206) (xy 381.909841 -0.929081) (xy 381.901929 -1.014464) (xy 381.886173 -1.098754)
			(xy 381.862706 -1.18123) (xy 381.83173 -1.261189) (xy 381.793508 -1.337949) (xy 381.748367 -1.410855)
			(xy 381.696691 -1.479284) (xy 381.638922 -1.542654) (xy 381.575552 -1.600423) (xy 381.507123 -1.652099)
			(xy 381.434217 -1.69724) (xy 381.357457 -1.735462) (xy 381.277498 -1.766438) (xy 381.195022 -1.789905)
			(xy 381.110732 -1.805661) (xy 381.025349 -1.813573) (xy 380.939599 -1.813573) (xy 380.854216 -1.805661)
			(xy 380.769926 -1.789905) (xy 380.68745 -1.766438) (xy 380.607491 -1.735462) (xy 380.530731 -1.69724)
			(xy 380.457825 -1.652099) (xy 380.389396 -1.600423) (xy 380.326026 -1.542654) (xy 380.268257 -1.479284)
			(xy 380.216581 -1.410855) (xy 380.17144 -1.337949) (xy 380.133218 -1.261189) (xy 380.102242 -1.18123)
			(xy 380.078775 -1.098754) (xy 380.063019 -1.014464) (xy 380.055107 -0.929081) (xy 375.559841 -0.929081)
			(xy 375.551929 -1.014464) (xy 375.536173 -1.098754) (xy 375.512706 -1.18123) (xy 375.48173 -1.261189)
			(xy 375.443508 -1.337949) (xy 375.398367 -1.410855) (xy 375.346691 -1.479284) (xy 375.288922 -1.542654)
			(xy 375.225552 -1.600423) (xy 375.157123 -1.652099) (xy 375.084217 -1.69724) (xy 375.007457 -1.735462)
			(xy 374.927498 -1.766438) (xy 374.845022 -1.789905) (xy 374.760732 -1.805661) (xy 374.675349 -1.813573)
			(xy 374.589599 -1.813573) (xy 374.504216 -1.805661) (xy 374.419926 -1.789905) (xy 374.33745 -1.766438)
			(xy 374.257491 -1.735462) (xy 374.180731 -1.69724) (xy 374.107825 -1.652099) (xy 374.039396 -1.600423)
			(xy 373.976026 -1.542654) (xy 373.918257 -1.479284) (xy 373.866581 -1.410855) (xy 373.82144 -1.337949)
			(xy 373.783218 -1.261189) (xy 373.752242 -1.18123) (xy 373.728775 -1.098754) (xy 373.713019 -1.014464)
			(xy 373.705107 -0.929081) (xy 343.693001 -0.929081) (xy 343.685089 -1.014464) (xy 343.669333 -1.098754)
			(xy 343.645866 -1.18123) (xy 343.61489 -1.261189) (xy 343.576668 -1.337949) (xy 343.531527 -1.410855)
			(xy 343.479851 -1.479284) (xy 343.422082 -1.542654) (xy 343.358712 -1.600423) (xy 343.290283 -1.652099)
			(xy 343.217377 -1.69724) (xy 343.140617 -1.735462) (xy 343.060658 -1.766438) (xy 342.978182 -1.789905)
			(xy 342.893892 -1.805661) (xy 342.808509 -1.813573) (xy 342.722759 -1.813573) (xy 342.637376 -1.805661)
			(xy 342.553086 -1.789905) (xy 342.47061 -1.766438) (xy 342.390651 -1.735462) (xy 342.313891 -1.69724)
			(xy 342.240985 -1.652099) (xy 342.172556 -1.600423) (xy 342.109186 -1.542654) (xy 342.051417 -1.479284)
			(xy 341.999741 -1.410855) (xy 341.9546 -1.337949) (xy 341.916378 -1.261189) (xy 341.885402 -1.18123)
			(xy 341.861935 -1.098754) (xy 341.846179 -1.014464) (xy 341.838267 -0.929081) (xy 337.343001 -0.929081)
			(xy 337.335089 -1.014464) (xy 337.319333 -1.098754) (xy 337.295866 -1.18123) (xy 337.26489 -1.261189)
			(xy 337.226668 -1.337949) (xy 337.181527 -1.410855) (xy 337.129851 -1.479284) (xy 337.072082 -1.542654)
			(xy 337.008712 -1.600423) (xy 336.940283 -1.652099) (xy 336.867377 -1.69724) (xy 336.790617 -1.735462)
			(xy 336.710658 -1.766438) (xy 336.628182 -1.789905) (xy 336.543892 -1.805661) (xy 336.458509 -1.813573)
			(xy 336.372759 -1.813573) (xy 336.287376 -1.805661) (xy 336.203086 -1.789905) (xy 336.12061 -1.766438)
			(xy 336.040651 -1.735462) (xy 335.963891 -1.69724) (xy 335.890985 -1.652099) (xy 335.822556 -1.600423)
			(xy 335.759186 -1.542654) (xy 335.701417 -1.479284) (xy 335.649741 -1.410855) (xy 335.6046 -1.337949)
			(xy 335.566378 -1.261189) (xy 335.535402 -1.18123) (xy 335.511935 -1.098754) (xy 335.496179 -1.014464)
			(xy 335.488267 -0.929081) (xy 333.050655 -0.929081) (xy 333.042743 -1.014464) (xy 333.026987 -1.098754)
			(xy 333.00352 -1.18123) (xy 332.972544 -1.261189) (xy 332.934322 -1.337949) (xy 332.889181 -1.410855)
			(xy 332.837505 -1.479284) (xy 332.779736 -1.542654) (xy 332.716366 -1.600423) (xy 332.647937 -1.652099)
			(xy 332.575031 -1.69724) (xy 332.498271 -1.735462) (xy 332.418312 -1.766438) (xy 332.335836 -1.789905)
			(xy 332.251546 -1.805661) (xy 332.166163 -1.813573) (xy 332.080413 -1.813573) (xy 331.99503 -1.805661)
			(xy 331.91074 -1.789905) (xy 331.828264 -1.766438) (xy 331.748305 -1.735462) (xy 331.671545 -1.69724)
			(xy 331.598639 -1.652099) (xy 331.53021 -1.600423) (xy 331.46684 -1.542654) (xy 331.409071 -1.479284)
			(xy 331.357395 -1.410855) (xy 331.312254 -1.337949) (xy 331.274032 -1.261189) (xy 331.243056 -1.18123)
			(xy 331.219589 -1.098754) (xy 331.203833 -1.014464) (xy 331.195921 -0.929081) (xy 326.700655 -0.929081)
			(xy 326.692743 -1.014464) (xy 326.676987 -1.098754) (xy 326.65352 -1.18123) (xy 326.622544 -1.261189)
			(xy 326.584322 -1.337949) (xy 326.539181 -1.410855) (xy 326.487505 -1.479284) (xy 326.429736 -1.542654)
			(xy 326.366366 -1.600423) (xy 326.297937 -1.652099) (xy 326.225031 -1.69724) (xy 326.148271 -1.735462)
			(xy 326.068312 -1.766438) (xy 325.985836 -1.789905) (xy 325.901546 -1.805661) (xy 325.816163 -1.813573)
			(xy 325.730413 -1.813573) (xy 325.64503 -1.805661) (xy 325.56074 -1.789905) (xy 325.478264 -1.766438)
			(xy 325.398305 -1.735462) (xy 325.321545 -1.69724) (xy 325.248639 -1.652099) (xy 325.18021 -1.600423)
			(xy 325.11684 -1.542654) (xy 325.059071 -1.479284) (xy 325.007395 -1.410855) (xy 324.962254 -1.337949)
			(xy 324.924032 -1.261189) (xy 324.893056 -1.18123) (xy 324.869589 -1.098754) (xy 324.853833 -1.014464)
			(xy 324.845921 -0.929081) (xy 265.125975 -0.929081) (xy 265.118063 -1.014464) (xy 265.102307 -1.098754)
			(xy 265.07884 -1.18123) (xy 265.047864 -1.261189) (xy 265.009642 -1.337949) (xy 264.964501 -1.410855)
			(xy 264.912825 -1.479284) (xy 264.855056 -1.542654) (xy 264.791686 -1.600423) (xy 264.723257 -1.652099)
			(xy 264.650351 -1.69724) (xy 264.573591 -1.735462) (xy 264.493632 -1.766438) (xy 264.411156 -1.789905)
			(xy 264.326866 -1.805661) (xy 264.241483 -1.813573) (xy 264.155733 -1.813573) (xy 264.07035 -1.805661)
			(xy 263.98606 -1.789905) (xy 263.903584 -1.766438) (xy 263.823625 -1.735462) (xy 263.746865 -1.69724)
			(xy 263.673959 -1.652099) (xy 263.60553 -1.600423) (xy 263.54216 -1.542654) (xy 263.484391 -1.479284)
			(xy 263.432715 -1.410855) (xy 263.387574 -1.337949) (xy 263.349352 -1.261189) (xy 263.318376 -1.18123)
			(xy 263.294909 -1.098754) (xy 263.279153 -1.014464) (xy 263.271241 -0.929081) (xy 258.775975 -0.929081)
			(xy 258.768063 -1.014464) (xy 258.752307 -1.098754) (xy 258.72884 -1.18123) (xy 258.697864 -1.261189)
			(xy 258.659642 -1.337949) (xy 258.614501 -1.410855) (xy 258.562825 -1.479284) (xy 258.505056 -1.542654)
			(xy 258.441686 -1.600423) (xy 258.373257 -1.652099) (xy 258.300351 -1.69724) (xy 258.223591 -1.735462)
			(xy 258.143632 -1.766438) (xy 258.061156 -1.789905) (xy 257.976866 -1.805661) (xy 257.891483 -1.813573)
			(xy 257.805733 -1.813573) (xy 257.72035 -1.805661) (xy 257.63606 -1.789905) (xy 257.553584 -1.766438)
			(xy 257.473625 -1.735462) (xy 257.396865 -1.69724) (xy 257.323959 -1.652099) (xy 257.25553 -1.600423)
			(xy 257.19216 -1.542654) (xy 257.134391 -1.479284) (xy 257.082715 -1.410855) (xy 257.037574 -1.337949)
			(xy 256.999352 -1.261189) (xy 256.968376 -1.18123) (xy 256.944909 -1.098754) (xy 256.929153 -1.014464)
			(xy 256.921241 -0.929081) (xy 254.465119 -0.929081) (xy 254.465087 -0.931875) (xy 254.457175 -1.017258)
			(xy 254.441419 -1.101548) (xy 254.417952 -1.184024) (xy 254.386976 -1.263983) (xy 254.348754 -1.340743)
			(xy 254.303613 -1.413649) (xy 254.251937 -1.482078) (xy 254.194168 -1.545448) (xy 254.130798 -1.603217)
			(xy 254.062369 -1.654893) (xy 253.989463 -1.700034) (xy 253.912703 -1.738256) (xy 253.832744 -1.769232)
			(xy 253.750268 -1.792699) (xy 253.665978 -1.808455) (xy 253.580595 -1.816367) (xy 253.494845 -1.816367)
			(xy 253.409462 -1.808455) (xy 253.325172 -1.792699) (xy 253.242696 -1.769232) (xy 253.162737 -1.738256)
			(xy 253.085977 -1.700034) (xy 253.013071 -1.654893) (xy 252.944642 -1.603217) (xy 252.881272 -1.545448)
			(xy 252.823503 -1.482078) (xy 252.771827 -1.413649) (xy 252.726686 -1.340743) (xy 252.688464 -1.263983)
			(xy 252.657488 -1.184024) (xy 252.634021 -1.101548) (xy 252.618265 -1.017258) (xy 252.610353 -0.931875)
			(xy 248.115087 -0.931875) (xy 248.107175 -1.017258) (xy 248.091419 -1.101548) (xy 248.067952 -1.184024)
			(xy 248.036976 -1.263983) (xy 247.998754 -1.340743) (xy 247.953613 -1.413649) (xy 247.901937 -1.482078)
			(xy 247.844168 -1.545448) (xy 247.780798 -1.603217) (xy 247.712369 -1.654893) (xy 247.639463 -1.700034)
			(xy 247.562703 -1.738256) (xy 247.482744 -1.769232) (xy 247.400268 -1.792699) (xy 247.315978 -1.808455)
			(xy 247.230595 -1.816367) (xy 247.144845 -1.816367) (xy 247.059462 -1.808455) (xy 246.975172 -1.792699)
			(xy 246.892696 -1.769232) (xy 246.812737 -1.738256) (xy 246.735977 -1.700034) (xy 246.663071 -1.654893)
			(xy 246.594642 -1.603217) (xy 246.531272 -1.545448) (xy 246.473503 -1.482078) (xy 246.421827 -1.413649)
			(xy 246.376686 -1.340743) (xy 246.338464 -1.263983) (xy 246.307488 -1.184024) (xy 246.284021 -1.101548)
			(xy 246.268265 -1.017258) (xy 246.260353 -0.931875) (xy 216.248247 -0.931875) (xy 216.240335 -1.017258)
			(xy 216.224579 -1.101548) (xy 216.201112 -1.184024) (xy 216.170136 -1.263983) (xy 216.131914 -1.340743)
			(xy 216.086773 -1.413649) (xy 216.035097 -1.482078) (xy 215.977328 -1.545448) (xy 215.913958 -1.603217)
			(xy 215.845529 -1.654893) (xy 215.772623 -1.700034) (xy 215.695863 -1.738256) (xy 215.615904 -1.769232)
			(xy 215.533428 -1.792699) (xy 215.449138 -1.808455) (xy 215.363755 -1.816367) (xy 215.278005 -1.816367)
			(xy 215.192622 -1.808455) (xy 215.108332 -1.792699) (xy 215.025856 -1.769232) (xy 214.945897 -1.738256)
			(xy 214.869137 -1.700034) (xy 214.796231 -1.654893) (xy 214.727802 -1.603217) (xy 214.664432 -1.545448)
			(xy 214.606663 -1.482078) (xy 214.554987 -1.413649) (xy 214.509846 -1.340743) (xy 214.471624 -1.263983)
			(xy 214.440648 -1.184024) (xy 214.417181 -1.101548) (xy 214.401425 -1.017258) (xy 214.393513 -0.931875)
			(xy 209.898247 -0.931875) (xy 209.890335 -1.017258) (xy 209.874579 -1.101548) (xy 209.851112 -1.184024)
			(xy 209.820136 -1.263983) (xy 209.781914 -1.340743) (xy 209.736773 -1.413649) (xy 209.685097 -1.482078)
			(xy 209.627328 -1.545448) (xy 209.563958 -1.603217) (xy 209.495529 -1.654893) (xy 209.422623 -1.700034)
			(xy 209.345863 -1.738256) (xy 209.265904 -1.769232) (xy 209.183428 -1.792699) (xy 209.099138 -1.808455)
			(xy 209.013755 -1.816367) (xy 208.928005 -1.816367) (xy 208.842622 -1.808455) (xy 208.758332 -1.792699)
			(xy 208.675856 -1.769232) (xy 208.595897 -1.738256) (xy 208.519137 -1.700034) (xy 208.446231 -1.654893)
			(xy 208.377802 -1.603217) (xy 208.314432 -1.545448) (xy 208.256663 -1.482078) (xy 208.204987 -1.413649)
			(xy 208.159846 -1.340743) (xy 208.121624 -1.263983) (xy 208.090648 -1.184024) (xy 208.067181 -1.101548)
			(xy 208.051425 -1.017258) (xy 208.043513 -0.931875) (xy 84.20989 -0.931875) (xy 84.20989 -7.78002)
			(xy 84.210412 -7.835827) (xy 84.218755 -7.947128) (xy 84.235391 -8.057495) (xy 84.260229 -8.16631)
			(xy 84.293128 -8.272964) (xy 84.333906 -8.376862) (xy 84.382334 -8.477422) (xy 84.438141 -8.574082)
			(xy 84.501016 -8.666301) (xy 84.570606 -8.753563) (xy 84.646523 -8.835382) (xy 84.728341 -8.911298)
			(xy 84.815604 -8.980888) (xy 84.907824 -9.043762) (xy 85.004484 -9.099569) (xy 85.105044 -9.147996)
			(xy 85.208942 -9.188774) (xy 85.315596 -9.221673) (xy 85.424411 -9.24651) (xy 85.534778 -9.263146)
			(xy 85.646079 -9.271488) (xy 85.701886 -9.272016) (xy 122.102118 -9.272016) (xy 122.157925 -9.271494)
			(xy 122.269226 -9.263152) (xy 122.379593 -9.246515) (xy 122.488409 -9.221678) (xy 122.595063 -9.188778)
			(xy 122.698961 -9.148001) (xy 122.799522 -9.099573) (xy 122.896182 -9.043766) (xy 122.988401 -8.980891)
			(xy 123.075664 -8.911301) (xy 123.157483 -8.835384) (xy 123.2334 -8.753566) (xy 123.30299 -8.666303)
			(xy 123.365865 -8.574084) (xy 123.421672 -8.477423) (xy 123.4701 -8.376863) (xy 123.510878 -8.272965)
			(xy 123.543777 -8.16631) (xy 123.568615 -8.057495) (xy 123.585251 -7.947128) (xy 123.593594 -7.835827)
			(xy 123.594114 -7.78002) (xy 123.594114 -4.2799) (xy 123.594598 -4.209546) (xy 123.602488 -4.06906)
			(xy 123.618242 -3.929237) (xy 123.641812 -3.790517) (xy 123.673122 -3.653337) (xy 123.712075 -3.518129)
			(xy 123.758548 -3.385317) (xy 123.812395 -3.25532) (xy 123.873446 -3.128547) (xy 123.941509 -3.005396)
			(xy 124.01637 -2.886255) (xy 124.097794 -2.7715) (xy 124.185524 -2.66149) (xy 124.279284 -2.556573)
			(xy 124.37878 -2.457077) (xy 124.483698 -2.363317) (xy 124.593708 -2.275588) (xy 124.708464 -2.194165)
			(xy 124.827605 -2.119304) (xy 124.950755 -2.051241) (xy 125.077529 -1.990191) (xy 125.207526 -1.936345)
			(xy 125.340338 -1.889872) (xy 125.475547 -1.85092) (xy 125.612727 -1.81961) (xy 125.751447 -1.796041)
			(xy 125.89127 -1.780287) (xy 126.031756 -1.772398) (xy 126.10211 -1.771904) (xy 194.701922 -1.771904)
			(xy 194.772275 -1.772398) (xy 194.912761 -1.780289) (xy 195.052582 -1.796044) (xy 195.191301 -1.819614)
			(xy 195.32848 -1.850925) (xy 195.463687 -1.889879) (xy 195.596497 -1.936352) (xy 195.726493 -1.990199)
			(xy 195.853265 -2.05125) (xy 195.976414 -2.119314) (xy 196.095554 -2.194175) (xy 196.210308 -2.275598)
			(xy 196.320316 -2.363328) (xy 196.425233 -2.457088) (xy 196.524727 -2.556583) (xy 196.618486 -2.6615)
			(xy 196.706215 -2.77151) (xy 196.787637 -2.886265) (xy 196.862497 -3.005405) (xy 196.93056 -3.128555)
			(xy 196.99161 -3.255327) (xy 197.045455 -3.385323) (xy 197.075741 -3.471875) (xy 208.043513 -3.471875)
			(xy 208.043513 -3.386125) (xy 208.051425 -3.300742) (xy 208.067181 -3.216452) (xy 208.090648 -3.133976)
			(xy 208.121624 -3.054017) (xy 208.159846 -2.977257) (xy 208.204987 -2.904351) (xy 208.256663 -2.835922)
			(xy 208.314432 -2.772552) (xy 208.377802 -2.714783) (xy 208.446231 -2.663107) (xy 208.519137 -2.617966)
			(xy 208.595897 -2.579744) (xy 208.675856 -2.548768) (xy 208.758332 -2.525301) (xy 208.842622 -2.509545)
			(xy 208.928005 -2.501633) (xy 209.013755 -2.501633) (xy 209.099138 -2.509545) (xy 209.183428 -2.525301)
			(xy 209.265904 -2.548768) (xy 209.345863 -2.579744) (xy 209.368066 -2.5908) (xy 212.978492 -2.5908)
			(xy 212.978492 -1.7272) (xy 212.978978 -1.699931) (xy 212.98674 -1.645947) (xy 213.002105 -1.593617)
			(xy 213.024762 -1.544007) (xy 213.054248 -1.498126) (xy 213.089963 -1.456909) (xy 213.13118 -1.421194)
			(xy 213.177061 -1.391708) (xy 213.226671 -1.369051) (xy 213.279001 -1.353686) (xy 213.332985 -1.345924)
			(xy 213.387523 -1.345924) (xy 213.441507 -1.353686) (xy 213.493837 -1.369051) (xy 213.543447 -1.391708)
			(xy 213.589328 -1.421194) (xy 213.630545 -1.456909) (xy 213.66626 -1.498126) (xy 213.695746 -1.544007)
			(xy 213.718403 -1.593617) (xy 213.733768 -1.645947) (xy 213.74153 -1.699931) (xy 213.742016 -1.7272)
			(xy 213.742016 -2.5908) (xy 213.74153 -2.618069) (xy 213.733768 -2.672053) (xy 213.718403 -2.724383)
			(xy 213.695746 -2.773993) (xy 213.66626 -2.819874) (xy 213.630545 -2.861091) (xy 213.589328 -2.896806)
			(xy 213.543447 -2.926292) (xy 213.493837 -2.948949) (xy 213.441507 -2.964314) (xy 213.387523 -2.972076)
			(xy 213.332985 -2.972076) (xy 213.279001 -2.964314) (xy 213.226671 -2.948949) (xy 213.177061 -2.926292)
			(xy 213.13118 -2.896806) (xy 213.089963 -2.861091) (xy 213.054248 -2.819874) (xy 213.024762 -2.773993)
			(xy 213.002105 -2.724383) (xy 212.98674 -2.672053) (xy 212.978978 -2.618069) (xy 212.978492 -2.5908)
			(xy 209.368066 -2.5908) (xy 209.422623 -2.617966) (xy 209.495529 -2.663107) (xy 209.563958 -2.714783)
			(xy 209.627328 -2.772552) (xy 209.685097 -2.835922) (xy 209.736773 -2.904351) (xy 209.781914 -2.977257)
			(xy 209.820136 -3.054017) (xy 209.851112 -3.133976) (xy 209.874579 -3.216452) (xy 209.890335 -3.300742)
			(xy 209.898247 -3.386125) (xy 209.898742 -3.429) (xy 209.898247 -3.471875) (xy 214.393513 -3.471875)
			(xy 214.393513 -3.386125) (xy 214.401425 -3.300742) (xy 214.417181 -3.216452) (xy 214.440648 -3.133976)
			(xy 214.471624 -3.054017) (xy 214.509846 -2.977257) (xy 214.554987 -2.904351) (xy 214.606663 -2.835922)
			(xy 214.664432 -2.772552) (xy 214.727802 -2.714783) (xy 214.796231 -2.663107) (xy 214.869137 -2.617966)
			(xy 214.945897 -2.579744) (xy 215.025856 -2.548768) (xy 215.108332 -2.525301) (xy 215.192622 -2.509545)
			(xy 215.278005 -2.501633) (xy 215.363755 -2.501633) (xy 215.449138 -2.509545) (xy 215.533428 -2.525301)
			(xy 215.615904 -2.548768) (xy 215.695863 -2.579744) (xy 215.772623 -2.617966) (xy 215.845529 -2.663107)
			(xy 215.913958 -2.714783) (xy 215.977328 -2.772552) (xy 216.035097 -2.835922) (xy 216.086773 -2.904351)
			(xy 216.131914 -2.977257) (xy 216.170136 -3.054017) (xy 216.201112 -3.133976) (xy 216.224579 -3.216452)
			(xy 216.240335 -3.300742) (xy 216.248247 -3.386125) (xy 216.248742 -3.429) (xy 216.248247 -3.471875)
			(xy 246.260353 -3.471875) (xy 246.260353 -3.386125) (xy 246.268265 -3.300742) (xy 246.284021 -3.216452)
			(xy 246.307488 -3.133976) (xy 246.338464 -3.054017) (xy 246.376686 -2.977257) (xy 246.421827 -2.904351)
			(xy 246.473503 -2.835922) (xy 246.531272 -2.772552) (xy 246.594642 -2.714783) (xy 246.663071 -2.663107)
			(xy 246.735977 -2.617966) (xy 246.812737 -2.579744) (xy 246.892696 -2.548768) (xy 246.975172 -2.525301)
			(xy 247.059462 -2.509545) (xy 247.144845 -2.501633) (xy 247.230595 -2.501633) (xy 247.315978 -2.509545)
			(xy 247.400268 -2.525301) (xy 247.482744 -2.548768) (xy 247.562703 -2.579744) (xy 247.584906 -2.5908)
			(xy 248.766584 -2.5908) (xy 248.766584 -1.7272) (xy 248.76707 -1.699931) (xy 248.774832 -1.645947)
			(xy 248.790197 -1.593617) (xy 248.812854 -1.544007) (xy 248.84234 -1.498126) (xy 248.878055 -1.456909)
			(xy 248.919272 -1.421194) (xy 248.965153 -1.391708) (xy 249.014763 -1.369051) (xy 249.067093 -1.353686)
			(xy 249.121077 -1.345924) (xy 249.175615 -1.345924) (xy 249.229599 -1.353686) (xy 249.281929 -1.369051)
			(xy 249.331539 -1.391708) (xy 249.37742 -1.421194) (xy 249.418637 -1.456909) (xy 249.454352 -1.498126)
			(xy 249.483838 -1.544007) (xy 249.506495 -1.593617) (xy 249.52186 -1.645947) (xy 249.529622 -1.699931)
			(xy 249.530108 -1.7272) (xy 249.530108 -2.5908) (xy 249.529622 -2.618069) (xy 249.52186 -2.672053)
			(xy 249.506495 -2.724383) (xy 249.483838 -2.773993) (xy 249.454352 -2.819874) (xy 249.418637 -2.861091)
			(xy 249.37742 -2.896806) (xy 249.331539 -2.926292) (xy 249.281929 -2.948949) (xy 249.229599 -2.964314)
			(xy 249.175615 -2.972076) (xy 249.121077 -2.972076) (xy 249.067093 -2.964314) (xy 249.014763 -2.948949)
			(xy 248.965153 -2.926292) (xy 248.919272 -2.896806) (xy 248.878055 -2.861091) (xy 248.84234 -2.819874)
			(xy 248.812854 -2.773993) (xy 248.790197 -2.724383) (xy 248.774832 -2.672053) (xy 248.76707 -2.618069)
			(xy 248.766584 -2.5908) (xy 247.584906 -2.5908) (xy 247.639463 -2.617966) (xy 247.712369 -2.663107)
			(xy 247.780798 -2.714783) (xy 247.844168 -2.772552) (xy 247.901937 -2.835922) (xy 247.953613 -2.904351)
			(xy 247.998754 -2.977257) (xy 248.036976 -3.054017) (xy 248.067952 -3.133976) (xy 248.091419 -3.216452)
			(xy 248.107175 -3.300742) (xy 248.115087 -3.386125) (xy 248.115582 -3.429) (xy 248.115087 -3.471875)
			(xy 252.610353 -3.471875) (xy 252.610353 -3.386125) (xy 252.618265 -3.300742) (xy 252.634021 -3.216452)
			(xy 252.657488 -3.133976) (xy 252.688464 -3.054017) (xy 252.726686 -2.977257) (xy 252.771827 -2.904351)
			(xy 252.823503 -2.835922) (xy 252.881272 -2.772552) (xy 252.944642 -2.714783) (xy 253.013071 -2.663107)
			(xy 253.085977 -2.617966) (xy 253.162737 -2.579744) (xy 253.242696 -2.548768) (xy 253.325172 -2.525301)
			(xy 253.409462 -2.509545) (xy 253.494845 -2.501633) (xy 253.580595 -2.501633) (xy 253.665978 -2.509545)
			(xy 253.750268 -2.525301) (xy 253.832744 -2.548768) (xy 253.912703 -2.579744) (xy 253.989463 -2.617966)
			(xy 254.062369 -2.663107) (xy 254.130798 -2.714783) (xy 254.194168 -2.772552) (xy 254.251937 -2.835922)
			(xy 254.303613 -2.904351) (xy 254.348754 -2.977257) (xy 254.386976 -3.054017) (xy 254.417952 -3.133976)
			(xy 254.441419 -3.216452) (xy 254.457175 -3.300742) (xy 254.465087 -3.386125) (xy 254.465582 -3.429)
			(xy 254.465119 -3.469081) (xy 256.921241 -3.469081) (xy 256.921241 -3.383331) (xy 256.929153 -3.297948)
			(xy 256.944909 -3.213658) (xy 256.968376 -3.131182) (xy 256.999352 -3.051223) (xy 257.037574 -2.974463)
			(xy 257.082715 -2.901557) (xy 257.134391 -2.833128) (xy 257.19216 -2.769758) (xy 257.25553 -2.711989)
			(xy 257.323959 -2.660313) (xy 257.396865 -2.615172) (xy 257.473625 -2.57695) (xy 257.553584 -2.545974)
			(xy 257.63606 -2.522507) (xy 257.72035 -2.506751) (xy 257.805733 -2.498839) (xy 257.891483 -2.498839)
			(xy 257.976866 -2.506751) (xy 258.061156 -2.522507) (xy 258.143632 -2.545974) (xy 258.223591 -2.57695)
			(xy 258.300351 -2.615172) (xy 258.373257 -2.660313) (xy 258.441686 -2.711989) (xy 258.505056 -2.769758)
			(xy 258.562825 -2.833128) (xy 258.614501 -2.901557) (xy 258.659642 -2.974463) (xy 258.697864 -3.051223)
			(xy 258.72884 -3.131182) (xy 258.752307 -3.213658) (xy 258.768063 -3.297948) (xy 258.775975 -3.383331)
			(xy 258.77647 -3.426206) (xy 258.775975 -3.469081) (xy 263.271241 -3.469081) (xy 263.271241 -3.383331)
			(xy 263.279153 -3.297948) (xy 263.294909 -3.213658) (xy 263.318376 -3.131182) (xy 263.349352 -3.051223)
			(xy 263.387574 -2.974463) (xy 263.432715 -2.901557) (xy 263.484391 -2.833128) (xy 263.54216 -2.769758)
			(xy 263.60553 -2.711989) (xy 263.673959 -2.660313) (xy 263.746865 -2.615172) (xy 263.823625 -2.57695)
			(xy 263.903584 -2.545974) (xy 263.98606 -2.522507) (xy 264.07035 -2.506751) (xy 264.155733 -2.498839)
			(xy 264.241483 -2.498839) (xy 264.326866 -2.506751) (xy 264.411156 -2.522507) (xy 264.493632 -2.545974)
			(xy 264.573591 -2.57695) (xy 264.650351 -2.615172) (xy 264.723257 -2.660313) (xy 264.791686 -2.711989)
			(xy 264.855056 -2.769758) (xy 264.912825 -2.833128) (xy 264.964501 -2.901557) (xy 265.009642 -2.974463)
			(xy 265.047864 -3.051223) (xy 265.07884 -3.131182) (xy 265.102307 -3.213658) (xy 265.118063 -3.297948)
			(xy 265.125975 -3.383331) (xy 265.12647 -3.426206) (xy 265.125975 -3.469081) (xy 324.845921 -3.469081)
			(xy 324.845921 -3.383331) (xy 324.853833 -3.297948) (xy 324.869589 -3.213658) (xy 324.893056 -3.131182)
			(xy 324.924032 -3.051223) (xy 324.962254 -2.974463) (xy 325.007395 -2.901557) (xy 325.059071 -2.833128)
			(xy 325.11684 -2.769758) (xy 325.18021 -2.711989) (xy 325.248639 -2.660313) (xy 325.321545 -2.615172)
			(xy 325.398305 -2.57695) (xy 325.478264 -2.545974) (xy 325.56074 -2.522507) (xy 325.64503 -2.506751)
			(xy 325.730413 -2.498839) (xy 325.816163 -2.498839) (xy 325.901546 -2.506751) (xy 325.985836 -2.522507)
			(xy 326.068312 -2.545974) (xy 326.148271 -2.57695) (xy 326.225031 -2.615172) (xy 326.297937 -2.660313)
			(xy 326.366366 -2.711989) (xy 326.429736 -2.769758) (xy 326.487505 -2.833128) (xy 326.539181 -2.901557)
			(xy 326.584322 -2.974463) (xy 326.622544 -3.051223) (xy 326.65352 -3.131182) (xy 326.676987 -3.213658)
			(xy 326.692743 -3.297948) (xy 326.700655 -3.383331) (xy 326.70115 -3.426206) (xy 326.700655 -3.469081)
			(xy 331.195921 -3.469081) (xy 331.195921 -3.383331) (xy 331.203833 -3.297948) (xy 331.219589 -3.213658)
			(xy 331.243056 -3.131182) (xy 331.274032 -3.051223) (xy 331.312254 -2.974463) (xy 331.357395 -2.901557)
			(xy 331.409071 -2.833128) (xy 331.46684 -2.769758) (xy 331.53021 -2.711989) (xy 331.598639 -2.660313)
			(xy 331.671545 -2.615172) (xy 331.748305 -2.57695) (xy 331.828264 -2.545974) (xy 331.91074 -2.522507)
			(xy 331.99503 -2.506751) (xy 332.080413 -2.498839) (xy 332.166163 -2.498839) (xy 332.251546 -2.506751)
			(xy 332.335836 -2.522507) (xy 332.418312 -2.545974) (xy 332.498271 -2.57695) (xy 332.575031 -2.615172)
			(xy 332.647937 -2.660313) (xy 332.716366 -2.711989) (xy 332.779736 -2.769758) (xy 332.837505 -2.833128)
			(xy 332.889181 -2.901557) (xy 332.934322 -2.974463) (xy 332.972544 -3.051223) (xy 333.00352 -3.131182)
			(xy 333.026987 -3.213658) (xy 333.042743 -3.297948) (xy 333.050655 -3.383331) (xy 333.05115 -3.426206)
			(xy 333.050655 -3.469081) (xy 335.488267 -3.469081) (xy 335.488267 -3.383331) (xy 335.496179 -3.297948)
			(xy 335.511935 -3.213658) (xy 335.535402 -3.131182) (xy 335.566378 -3.051223) (xy 335.6046 -2.974463)
			(xy 335.649741 -2.901557) (xy 335.701417 -2.833128) (xy 335.759186 -2.769758) (xy 335.822556 -2.711989)
			(xy 335.890985 -2.660313) (xy 335.963891 -2.615172) (xy 336.040651 -2.57695) (xy 336.12061 -2.545974)
			(xy 336.203086 -2.522507) (xy 336.287376 -2.506751) (xy 336.372759 -2.498839) (xy 336.458509 -2.498839)
			(xy 336.543892 -2.506751) (xy 336.628182 -2.522507) (xy 336.710658 -2.545974) (xy 336.790617 -2.57695)
			(xy 336.867377 -2.615172) (xy 336.940283 -2.660313) (xy 337.008712 -2.711989) (xy 337.072082 -2.769758)
			(xy 337.129851 -2.833128) (xy 337.181527 -2.901557) (xy 337.226668 -2.974463) (xy 337.26489 -3.051223)
			(xy 337.295866 -3.131182) (xy 337.319333 -3.213658) (xy 337.335089 -3.297948) (xy 337.343001 -3.383331)
			(xy 337.343496 -3.426206) (xy 337.343001 -3.469081) (xy 341.838267 -3.469081) (xy 341.838267 -3.383331)
			(xy 341.846179 -3.297948) (xy 341.861935 -3.213658) (xy 341.885402 -3.131182) (xy 341.916378 -3.051223)
			(xy 341.9546 -2.974463) (xy 341.999741 -2.901557) (xy 342.051417 -2.833128) (xy 342.109186 -2.769758)
			(xy 342.172556 -2.711989) (xy 342.240985 -2.660313) (xy 342.313891 -2.615172) (xy 342.390651 -2.57695)
			(xy 342.47061 -2.545974) (xy 342.553086 -2.522507) (xy 342.637376 -2.506751) (xy 342.722759 -2.498839)
			(xy 342.808509 -2.498839) (xy 342.893892 -2.506751) (xy 342.978182 -2.522507) (xy 343.060658 -2.545974)
			(xy 343.140617 -2.57695) (xy 343.217377 -2.615172) (xy 343.290283 -2.660313) (xy 343.358712 -2.711989)
			(xy 343.422082 -2.769758) (xy 343.479851 -2.833128) (xy 343.531527 -2.901557) (xy 343.576668 -2.974463)
			(xy 343.61489 -3.051223) (xy 343.645866 -3.131182) (xy 343.669333 -3.213658) (xy 343.685089 -3.297948)
			(xy 343.693001 -3.383331) (xy 343.693496 -3.426206) (xy 343.693001 -3.469081) (xy 373.705107 -3.469081)
			(xy 373.705107 -3.383331) (xy 373.713019 -3.297948) (xy 373.728775 -3.213658) (xy 373.752242 -3.131182)
			(xy 373.783218 -3.051223) (xy 373.82144 -2.974463) (xy 373.866581 -2.901557) (xy 373.918257 -2.833128)
			(xy 373.976026 -2.769758) (xy 374.039396 -2.711989) (xy 374.107825 -2.660313) (xy 374.180731 -2.615172)
			(xy 374.257491 -2.57695) (xy 374.33745 -2.545974) (xy 374.419926 -2.522507) (xy 374.504216 -2.506751)
			(xy 374.589599 -2.498839) (xy 374.675349 -2.498839) (xy 374.760732 -2.506751) (xy 374.845022 -2.522507)
			(xy 374.927498 -2.545974) (xy 375.007457 -2.57695) (xy 375.084217 -2.615172) (xy 375.157123 -2.660313)
			(xy 375.225552 -2.711989) (xy 375.288922 -2.769758) (xy 375.346691 -2.833128) (xy 375.398367 -2.901557)
			(xy 375.443508 -2.974463) (xy 375.48173 -3.051223) (xy 375.512706 -3.131182) (xy 375.536173 -3.213658)
			(xy 375.551929 -3.297948) (xy 375.559841 -3.383331) (xy 375.560336 -3.426206) (xy 375.559841 -3.469081)
			(xy 380.055107 -3.469081) (xy 380.055107 -3.383331) (xy 380.063019 -3.297948) (xy 380.078775 -3.213658)
			(xy 380.102242 -3.131182) (xy 380.133218 -3.051223) (xy 380.17144 -2.974463) (xy 380.216581 -2.901557)
			(xy 380.268257 -2.833128) (xy 380.326026 -2.769758) (xy 380.389396 -2.711989) (xy 380.457825 -2.660313)
			(xy 380.530731 -2.615172) (xy 380.607491 -2.57695) (xy 380.68745 -2.545974) (xy 380.769926 -2.522507)
			(xy 380.854216 -2.506751) (xy 380.939599 -2.498839) (xy 381.025349 -2.498839) (xy 381.110732 -2.506751)
			(xy 381.195022 -2.522507) (xy 381.277498 -2.545974) (xy 381.357457 -2.57695) (xy 381.434217 -2.615172)
			(xy 381.507123 -2.660313) (xy 381.575552 -2.711989) (xy 381.638922 -2.769758) (xy 381.696691 -2.833128)
			(xy 381.748367 -2.901557) (xy 381.793508 -2.974463) (xy 381.83173 -3.051223) (xy 381.862706 -3.131182)
			(xy 381.886173 -3.213658) (xy 381.901929 -3.297948) (xy 381.909841 -3.383331) (xy 381.910336 -3.426206)
			(xy 381.909841 -3.469081) (xy 381.901929 -3.554464) (xy 381.886173 -3.638754) (xy 381.862706 -3.72123)
			(xy 381.83173 -3.801189) (xy 381.793508 -3.877949) (xy 381.748367 -3.950855) (xy 381.696691 -4.019284)
			(xy 381.638922 -4.082654) (xy 381.575552 -4.140423) (xy 381.507123 -4.192099) (xy 381.434217 -4.23724)
			(xy 381.357457 -4.275462) (xy 381.277498 -4.306438) (xy 381.195022 -4.329905) (xy 381.110732 -4.345661)
			(xy 381.025349 -4.353573) (xy 380.939599 -4.353573) (xy 380.854216 -4.345661) (xy 380.769926 -4.329905)
			(xy 380.68745 -4.306438) (xy 380.607491 -4.275462) (xy 380.530731 -4.23724) (xy 380.457825 -4.192099)
			(xy 380.389396 -4.140423) (xy 380.326026 -4.082654) (xy 380.268257 -4.019284) (xy 380.216581 -3.950855)
			(xy 380.17144 -3.877949) (xy 380.133218 -3.801189) (xy 380.102242 -3.72123) (xy 380.078775 -3.638754)
			(xy 380.063019 -3.554464) (xy 380.055107 -3.469081) (xy 375.559841 -3.469081) (xy 375.551929 -3.554464)
			(xy 375.536173 -3.638754) (xy 375.512706 -3.72123) (xy 375.48173 -3.801189) (xy 375.443508 -3.877949)
			(xy 375.398367 -3.950855) (xy 375.346691 -4.019284) (xy 375.288922 -4.082654) (xy 375.225552 -4.140423)
			(xy 375.157123 -4.192099) (xy 375.084217 -4.23724) (xy 375.007457 -4.275462) (xy 374.927498 -4.306438)
			(xy 374.845022 -4.329905) (xy 374.760732 -4.345661) (xy 374.675349 -4.353573) (xy 374.589599 -4.353573)
			(xy 374.504216 -4.345661) (xy 374.419926 -4.329905) (xy 374.33745 -4.306438) (xy 374.257491 -4.275462)
			(xy 374.180731 -4.23724) (xy 374.107825 -4.192099) (xy 374.039396 -4.140423) (xy 373.976026 -4.082654)
			(xy 373.918257 -4.019284) (xy 373.866581 -3.950855) (xy 373.82144 -3.877949) (xy 373.783218 -3.801189)
			(xy 373.752242 -3.72123) (xy 373.728775 -3.638754) (xy 373.713019 -3.554464) (xy 373.705107 -3.469081)
			(xy 343.693001 -3.469081) (xy 343.685089 -3.554464) (xy 343.669333 -3.638754) (xy 343.645866 -3.72123)
			(xy 343.61489 -3.801189) (xy 343.576668 -3.877949) (xy 343.531527 -3.950855) (xy 343.479851 -4.019284)
			(xy 343.422082 -4.082654) (xy 343.358712 -4.140423) (xy 343.290283 -4.192099) (xy 343.217377 -4.23724)
			(xy 343.140617 -4.275462) (xy 343.060658 -4.306438) (xy 342.978182 -4.329905) (xy 342.893892 -4.345661)
			(xy 342.808509 -4.353573) (xy 342.722759 -4.353573) (xy 342.637376 -4.345661) (xy 342.553086 -4.329905)
			(xy 342.47061 -4.306438) (xy 342.390651 -4.275462) (xy 342.313891 -4.23724) (xy 342.240985 -4.192099)
			(xy 342.172556 -4.140423) (xy 342.109186 -4.082654) (xy 342.051417 -4.019284) (xy 341.999741 -3.950855)
			(xy 341.9546 -3.877949) (xy 341.916378 -3.801189) (xy 341.885402 -3.72123) (xy 341.861935 -3.638754)
			(xy 341.846179 -3.554464) (xy 341.838267 -3.469081) (xy 337.343001 -3.469081) (xy 337.335089 -3.554464)
			(xy 337.319333 -3.638754) (xy 337.295866 -3.72123) (xy 337.26489 -3.801189) (xy 337.226668 -3.877949)
			(xy 337.181527 -3.950855) (xy 337.129851 -4.019284) (xy 337.072082 -4.082654) (xy 337.008712 -4.140423)
			(xy 336.940283 -4.192099) (xy 336.867377 -4.23724) (xy 336.790617 -4.275462) (xy 336.710658 -4.306438)
			(xy 336.628182 -4.329905) (xy 336.543892 -4.345661) (xy 336.458509 -4.353573) (xy 336.372759 -4.353573)
			(xy 336.287376 -4.345661) (xy 336.203086 -4.329905) (xy 336.12061 -4.306438) (xy 336.040651 -4.275462)
			(xy 335.963891 -4.23724) (xy 335.890985 -4.192099) (xy 335.822556 -4.140423) (xy 335.759186 -4.082654)
			(xy 335.701417 -4.019284) (xy 335.649741 -3.950855) (xy 335.6046 -3.877949) (xy 335.566378 -3.801189)
			(xy 335.535402 -3.72123) (xy 335.511935 -3.638754) (xy 335.496179 -3.554464) (xy 335.488267 -3.469081)
			(xy 333.050655 -3.469081) (xy 333.042743 -3.554464) (xy 333.026987 -3.638754) (xy 333.00352 -3.72123)
			(xy 332.972544 -3.801189) (xy 332.934322 -3.877949) (xy 332.889181 -3.950855) (xy 332.837505 -4.019284)
			(xy 332.779736 -4.082654) (xy 332.716366 -4.140423) (xy 332.647937 -4.192099) (xy 332.575031 -4.23724)
			(xy 332.498271 -4.275462) (xy 332.418312 -4.306438) (xy 332.335836 -4.329905) (xy 332.251546 -4.345661)
			(xy 332.166163 -4.353573) (xy 332.080413 -4.353573) (xy 331.99503 -4.345661) (xy 331.91074 -4.329905)
			(xy 331.828264 -4.306438) (xy 331.748305 -4.275462) (xy 331.671545 -4.23724) (xy 331.598639 -4.192099)
			(xy 331.53021 -4.140423) (xy 331.46684 -4.082654) (xy 331.409071 -4.019284) (xy 331.357395 -3.950855)
			(xy 331.312254 -3.877949) (xy 331.274032 -3.801189) (xy 331.243056 -3.72123) (xy 331.219589 -3.638754)
			(xy 331.203833 -3.554464) (xy 331.195921 -3.469081) (xy 326.700655 -3.469081) (xy 326.692743 -3.554464)
			(xy 326.676987 -3.638754) (xy 326.65352 -3.72123) (xy 326.622544 -3.801189) (xy 326.584322 -3.877949)
			(xy 326.539181 -3.950855) (xy 326.487505 -4.019284) (xy 326.429736 -4.082654) (xy 326.366366 -4.140423)
			(xy 326.297937 -4.192099) (xy 326.225031 -4.23724) (xy 326.148271 -4.275462) (xy 326.068312 -4.306438)
			(xy 325.985836 -4.329905) (xy 325.901546 -4.345661) (xy 325.816163 -4.353573) (xy 325.730413 -4.353573)
			(xy 325.64503 -4.345661) (xy 325.56074 -4.329905) (xy 325.478264 -4.306438) (xy 325.398305 -4.275462)
			(xy 325.321545 -4.23724) (xy 325.248639 -4.192099) (xy 325.18021 -4.140423) (xy 325.11684 -4.082654)
			(xy 325.059071 -4.019284) (xy 325.007395 -3.950855) (xy 324.962254 -3.877949) (xy 324.924032 -3.801189)
			(xy 324.893056 -3.72123) (xy 324.869589 -3.638754) (xy 324.853833 -3.554464) (xy 324.845921 -3.469081)
			(xy 265.125975 -3.469081) (xy 265.118063 -3.554464) (xy 265.102307 -3.638754) (xy 265.07884 -3.72123)
			(xy 265.047864 -3.801189) (xy 265.009642 -3.877949) (xy 264.964501 -3.950855) (xy 264.912825 -4.019284)
			(xy 264.855056 -4.082654) (xy 264.791686 -4.140423) (xy 264.723257 -4.192099) (xy 264.650351 -4.23724)
			(xy 264.573591 -4.275462) (xy 264.493632 -4.306438) (xy 264.411156 -4.329905) (xy 264.326866 -4.345661)
			(xy 264.241483 -4.353573) (xy 264.155733 -4.353573) (xy 264.07035 -4.345661) (xy 263.98606 -4.329905)
			(xy 263.903584 -4.306438) (xy 263.823625 -4.275462) (xy 263.746865 -4.23724) (xy 263.673959 -4.192099)
			(xy 263.60553 -4.140423) (xy 263.54216 -4.082654) (xy 263.484391 -4.019284) (xy 263.432715 -3.950855)
			(xy 263.387574 -3.877949) (xy 263.349352 -3.801189) (xy 263.318376 -3.72123) (xy 263.294909 -3.638754)
			(xy 263.279153 -3.554464) (xy 263.271241 -3.469081) (xy 258.775975 -3.469081) (xy 258.768063 -3.554464)
			(xy 258.752307 -3.638754) (xy 258.72884 -3.72123) (xy 258.697864 -3.801189) (xy 258.659642 -3.877949)
			(xy 258.614501 -3.950855) (xy 258.562825 -4.019284) (xy 258.505056 -4.082654) (xy 258.441686 -4.140423)
			(xy 258.373257 -4.192099) (xy 258.300351 -4.23724) (xy 258.223591 -4.275462) (xy 258.143632 -4.306438)
			(xy 258.061156 -4.329905) (xy 257.976866 -4.345661) (xy 257.891483 -4.353573) (xy 257.805733 -4.353573)
			(xy 257.72035 -4.345661) (xy 257.63606 -4.329905) (xy 257.553584 -4.306438) (xy 257.473625 -4.275462)
			(xy 257.396865 -4.23724) (xy 257.323959 -4.192099) (xy 257.25553 -4.140423) (xy 257.19216 -4.082654)
			(xy 257.134391 -4.019284) (xy 257.082715 -3.950855) (xy 257.037574 -3.877949) (xy 256.999352 -3.801189)
			(xy 256.968376 -3.72123) (xy 256.944909 -3.638754) (xy 256.929153 -3.554464) (xy 256.921241 -3.469081)
			(xy 254.465119 -3.469081) (xy 254.465087 -3.471875) (xy 254.457175 -3.557258) (xy 254.441419 -3.641548)
			(xy 254.417952 -3.724024) (xy 254.386976 -3.803983) (xy 254.348754 -3.880743) (xy 254.303613 -3.953649)
			(xy 254.251937 -4.022078) (xy 254.194168 -4.085448) (xy 254.130798 -4.143217) (xy 254.062369 -4.194893)
			(xy 253.989463 -4.240034) (xy 253.912703 -4.278256) (xy 253.832744 -4.309232) (xy 253.750268 -4.332699)
			(xy 253.665978 -4.348455) (xy 253.580595 -4.356367) (xy 253.494845 -4.356367) (xy 253.409462 -4.348455)
			(xy 253.325172 -4.332699) (xy 253.242696 -4.309232) (xy 253.162737 -4.278256) (xy 253.085977 -4.240034)
			(xy 253.013071 -4.194893) (xy 252.944642 -4.143217) (xy 252.881272 -4.085448) (xy 252.823503 -4.022078)
			(xy 252.771827 -3.953649) (xy 252.726686 -3.880743) (xy 252.688464 -3.803983) (xy 252.657488 -3.724024)
			(xy 252.634021 -3.641548) (xy 252.618265 -3.557258) (xy 252.610353 -3.471875) (xy 248.115087 -3.471875)
			(xy 248.107175 -3.557258) (xy 248.091419 -3.641548) (xy 248.067952 -3.724024) (xy 248.036976 -3.803983)
			(xy 247.998754 -3.880743) (xy 247.953613 -3.953649) (xy 247.901937 -4.022078) (xy 247.844168 -4.085448)
			(xy 247.780798 -4.143217) (xy 247.712369 -4.194893) (xy 247.639463 -4.240034) (xy 247.562703 -4.278256)
			(xy 247.482744 -4.309232) (xy 247.400268 -4.332699) (xy 247.315978 -4.348455) (xy 247.230595 -4.356367)
			(xy 247.144845 -4.356367) (xy 247.059462 -4.348455) (xy 246.975172 -4.332699) (xy 246.892696 -4.309232)
			(xy 246.812737 -4.278256) (xy 246.735977 -4.240034) (xy 246.663071 -4.194893) (xy 246.594642 -4.143217)
			(xy 246.531272 -4.085448) (xy 246.473503 -4.022078) (xy 246.421827 -3.953649) (xy 246.376686 -3.880743)
			(xy 246.338464 -3.803983) (xy 246.307488 -3.724024) (xy 246.284021 -3.641548) (xy 246.268265 -3.557258)
			(xy 246.260353 -3.471875) (xy 216.248247 -3.471875) (xy 216.240335 -3.557258) (xy 216.224579 -3.641548)
			(xy 216.201112 -3.724024) (xy 216.170136 -3.803983) (xy 216.131914 -3.880743) (xy 216.086773 -3.953649)
			(xy 216.035097 -4.022078) (xy 215.977328 -4.085448) (xy 215.913958 -4.143217) (xy 215.845529 -4.194893)
			(xy 215.772623 -4.240034) (xy 215.695863 -4.278256) (xy 215.615904 -4.309232) (xy 215.533428 -4.332699)
			(xy 215.449138 -4.348455) (xy 215.363755 -4.356367) (xy 215.278005 -4.356367) (xy 215.192622 -4.348455)
			(xy 215.108332 -4.332699) (xy 215.025856 -4.309232) (xy 214.945897 -4.278256) (xy 214.869137 -4.240034)
			(xy 214.796231 -4.194893) (xy 214.727802 -4.143217) (xy 214.664432 -4.085448) (xy 214.606663 -4.022078)
			(xy 214.554987 -3.953649) (xy 214.509846 -3.880743) (xy 214.471624 -3.803983) (xy 214.440648 -3.724024)
			(xy 214.417181 -3.641548) (xy 214.401425 -3.557258) (xy 214.393513 -3.471875) (xy 209.898247 -3.471875)
			(xy 209.890335 -3.557258) (xy 209.874579 -3.641548) (xy 209.851112 -3.724024) (xy 209.820136 -3.803983)
			(xy 209.781914 -3.880743) (xy 209.736773 -3.953649) (xy 209.685097 -4.022078) (xy 209.627328 -4.085448)
			(xy 209.563958 -4.143217) (xy 209.495529 -4.194893) (xy 209.422623 -4.240034) (xy 209.345863 -4.278256)
			(xy 209.265904 -4.309232) (xy 209.183428 -4.332699) (xy 209.099138 -4.348455) (xy 209.013755 -4.356367)
			(xy 208.928005 -4.356367) (xy 208.842622 -4.348455) (xy 208.758332 -4.332699) (xy 208.675856 -4.309232)
			(xy 208.595897 -4.278256) (xy 208.519137 -4.240034) (xy 208.446231 -4.194893) (xy 208.377802 -4.143217)
			(xy 208.314432 -4.085448) (xy 208.256663 -4.022078) (xy 208.204987 -3.953649) (xy 208.159846 -3.880743)
			(xy 208.121624 -3.803983) (xy 208.090648 -3.724024) (xy 208.067181 -3.641548) (xy 208.051425 -3.557258)
			(xy 208.043513 -3.471875) (xy 197.075741 -3.471875) (xy 197.091928 -3.518134) (xy 197.13088 -3.653342)
			(xy 197.16219 -3.790521) (xy 197.185759 -3.929239) (xy 197.201513 -4.069061) (xy 197.209403 -4.209547)
			(xy 197.209918 -4.2799) (xy 197.209918 -6.011875) (xy 208.043513 -6.011875) (xy 208.043513 -5.926125)
			(xy 208.051425 -5.840742) (xy 208.067181 -5.756452) (xy 208.090648 -5.673976) (xy 208.121624 -5.594017)
			(xy 208.159846 -5.517257) (xy 208.204987 -5.444351) (xy 208.256663 -5.375922) (xy 208.314432 -5.312552)
			(xy 208.377802 -5.254783) (xy 208.446231 -5.203107) (xy 208.519137 -5.157966) (xy 208.595897 -5.119744)
			(xy 208.675856 -5.088768) (xy 208.758332 -5.065301) (xy 208.842622 -5.049545) (xy 208.928005 -5.041633)
			(xy 209.013755 -5.041633) (xy 209.099138 -5.049545) (xy 209.183428 -5.065301) (xy 209.265904 -5.088768)
			(xy 209.345863 -5.119744) (xy 209.368066 -5.1308) (xy 212.978492 -5.1308) (xy 212.978492 -4.2672)
			(xy 212.978978 -4.239931) (xy 212.98674 -4.185947) (xy 213.002105 -4.133617) (xy 213.024762 -4.084007)
			(xy 213.054248 -4.038126) (xy 213.089963 -3.996909) (xy 213.13118 -3.961194) (xy 213.177061 -3.931708)
			(xy 213.226671 -3.909051) (xy 213.279001 -3.893686) (xy 213.332985 -3.885924) (xy 213.387523 -3.885924)
			(xy 213.441507 -3.893686) (xy 213.493837 -3.909051) (xy 213.543447 -3.931708) (xy 213.589328 -3.961194)
			(xy 213.630545 -3.996909) (xy 213.66626 -4.038126) (xy 213.695746 -4.084007) (xy 213.718403 -4.133617)
			(xy 213.733768 -4.185947) (xy 213.74153 -4.239931) (xy 213.742016 -4.2672) (xy 213.742016 -5.1308)
			(xy 213.74153 -5.158069) (xy 213.733768 -5.212053) (xy 213.718403 -5.264383) (xy 213.695746 -5.313993)
			(xy 213.66626 -5.359874) (xy 213.630545 -5.401091) (xy 213.589328 -5.436806) (xy 213.543447 -5.466292)
			(xy 213.493837 -5.488949) (xy 213.441507 -5.504314) (xy 213.387523 -5.512076) (xy 213.332985 -5.512076)
			(xy 213.279001 -5.504314) (xy 213.226671 -5.488949) (xy 213.177061 -5.466292) (xy 213.13118 -5.436806)
			(xy 213.089963 -5.401091) (xy 213.054248 -5.359874) (xy 213.024762 -5.313993) (xy 213.002105 -5.264383)
			(xy 212.98674 -5.212053) (xy 212.978978 -5.158069) (xy 212.978492 -5.1308) (xy 209.368066 -5.1308)
			(xy 209.422623 -5.157966) (xy 209.495529 -5.203107) (xy 209.563958 -5.254783) (xy 209.627328 -5.312552)
			(xy 209.685097 -5.375922) (xy 209.736773 -5.444351) (xy 209.781914 -5.517257) (xy 209.820136 -5.594017)
			(xy 209.851112 -5.673976) (xy 209.874579 -5.756452) (xy 209.890335 -5.840742) (xy 209.898247 -5.926125)
			(xy 209.898742 -5.969) (xy 209.898247 -6.011875) (xy 214.393513 -6.011875) (xy 214.393513 -5.926125)
			(xy 214.401425 -5.840742) (xy 214.417181 -5.756452) (xy 214.440648 -5.673976) (xy 214.471624 -5.594017)
			(xy 214.509846 -5.517257) (xy 214.554987 -5.444351) (xy 214.606663 -5.375922) (xy 214.664432 -5.312552)
			(xy 214.727802 -5.254783) (xy 214.796231 -5.203107) (xy 214.869137 -5.157966) (xy 214.945897 -5.119744)
			(xy 215.025856 -5.088768) (xy 215.108332 -5.065301) (xy 215.192622 -5.049545) (xy 215.278005 -5.041633)
			(xy 215.363755 -5.041633) (xy 215.449138 -5.049545) (xy 215.533428 -5.065301) (xy 215.615904 -5.088768)
			(xy 215.695863 -5.119744) (xy 215.772623 -5.157966) (xy 215.845529 -5.203107) (xy 215.913958 -5.254783)
			(xy 215.977328 -5.312552) (xy 216.035097 -5.375922) (xy 216.086773 -5.444351) (xy 216.131914 -5.517257)
			(xy 216.170136 -5.594017) (xy 216.201112 -5.673976) (xy 216.224579 -5.756452) (xy 216.240335 -5.840742)
			(xy 216.248247 -5.926125) (xy 216.248742 -5.969) (xy 216.248247 -6.011875) (xy 246.260353 -6.011875)
			(xy 246.260353 -5.926125) (xy 246.268265 -5.840742) (xy 246.284021 -5.756452) (xy 246.307488 -5.673976)
			(xy 246.338464 -5.594017) (xy 246.376686 -5.517257) (xy 246.421827 -5.444351) (xy 246.473503 -5.375922)
			(xy 246.531272 -5.312552) (xy 246.594642 -5.254783) (xy 246.663071 -5.203107) (xy 246.735977 -5.157966)
			(xy 246.812737 -5.119744) (xy 246.892696 -5.088768) (xy 246.975172 -5.065301) (xy 247.059462 -5.049545)
			(xy 247.144845 -5.041633) (xy 247.230595 -5.041633) (xy 247.315978 -5.049545) (xy 247.400268 -5.065301)
			(xy 247.482744 -5.088768) (xy 247.562703 -5.119744) (xy 247.584906 -5.1308) (xy 248.766584 -5.1308)
			(xy 248.766584 -4.2672) (xy 248.76707 -4.239931) (xy 248.774832 -4.185947) (xy 248.790197 -4.133617)
			(xy 248.812854 -4.084007) (xy 248.84234 -4.038126) (xy 248.878055 -3.996909) (xy 248.919272 -3.961194)
			(xy 248.965153 -3.931708) (xy 249.014763 -3.909051) (xy 249.067093 -3.893686) (xy 249.121077 -3.885924)
			(xy 249.175615 -3.885924) (xy 249.229599 -3.893686) (xy 249.281929 -3.909051) (xy 249.331539 -3.931708)
			(xy 249.37742 -3.961194) (xy 249.418637 -3.996909) (xy 249.454352 -4.038126) (xy 249.483838 -4.084007)
			(xy 249.506495 -4.133617) (xy 249.52186 -4.185947) (xy 249.529622 -4.239931) (xy 249.530108 -4.2672)
			(xy 249.530108 -5.1308) (xy 249.529622 -5.158069) (xy 249.52186 -5.212053) (xy 249.506495 -5.264383)
			(xy 249.483838 -5.313993) (xy 249.454352 -5.359874) (xy 249.418637 -5.401091) (xy 249.37742 -5.436806)
			(xy 249.331539 -5.466292) (xy 249.281929 -5.488949) (xy 249.229599 -5.504314) (xy 249.175615 -5.512076)
			(xy 249.121077 -5.512076) (xy 249.067093 -5.504314) (xy 249.014763 -5.488949) (xy 248.965153 -5.466292)
			(xy 248.919272 -5.436806) (xy 248.878055 -5.401091) (xy 248.84234 -5.359874) (xy 248.812854 -5.313993)
			(xy 248.790197 -5.264383) (xy 248.774832 -5.212053) (xy 248.76707 -5.158069) (xy 248.766584 -5.1308)
			(xy 247.584906 -5.1308) (xy 247.639463 -5.157966) (xy 247.712369 -5.203107) (xy 247.780798 -5.254783)
			(xy 247.844168 -5.312552) (xy 247.901937 -5.375922) (xy 247.953613 -5.444351) (xy 247.998754 -5.517257)
			(xy 248.036976 -5.594017) (xy 248.067952 -5.673976) (xy 248.091419 -5.756452) (xy 248.107175 -5.840742)
			(xy 248.115087 -5.926125) (xy 248.115582 -5.969) (xy 248.115087 -6.011875) (xy 252.610353 -6.011875)
			(xy 252.610353 -5.926125) (xy 252.618265 -5.840742) (xy 252.634021 -5.756452) (xy 252.657488 -5.673976)
			(xy 252.688464 -5.594017) (xy 252.726686 -5.517257) (xy 252.771827 -5.444351) (xy 252.823503 -5.375922)
			(xy 252.881272 -5.312552) (xy 252.944642 -5.254783) (xy 253.013071 -5.203107) (xy 253.085977 -5.157966)
			(xy 253.162737 -5.119744) (xy 253.242696 -5.088768) (xy 253.325172 -5.065301) (xy 253.409462 -5.049545)
			(xy 253.494845 -5.041633) (xy 253.580595 -5.041633) (xy 253.665978 -5.049545) (xy 253.750268 -5.065301)
			(xy 253.832744 -5.088768) (xy 253.912703 -5.119744) (xy 253.989463 -5.157966) (xy 254.062369 -5.203107)
			(xy 254.130798 -5.254783) (xy 254.194168 -5.312552) (xy 254.251937 -5.375922) (xy 254.303613 -5.444351)
			(xy 254.348754 -5.517257) (xy 254.386976 -5.594017) (xy 254.417952 -5.673976) (xy 254.441419 -5.756452)
			(xy 254.457175 -5.840742) (xy 254.465087 -5.926125) (xy 254.465582 -5.969) (xy 254.465119 -6.009081)
			(xy 256.921241 -6.009081) (xy 256.921241 -5.923331) (xy 256.929153 -5.837948) (xy 256.944909 -5.753658)
			(xy 256.968376 -5.671182) (xy 256.999352 -5.591223) (xy 257.037574 -5.514463) (xy 257.082715 -5.441557)
			(xy 257.134391 -5.373128) (xy 257.19216 -5.309758) (xy 257.25553 -5.251989) (xy 257.323959 -5.200313)
			(xy 257.396865 -5.155172) (xy 257.473625 -5.11695) (xy 257.553584 -5.085974) (xy 257.63606 -5.062507)
			(xy 257.72035 -5.046751) (xy 257.805733 -5.038839) (xy 257.891483 -5.038839) (xy 257.976866 -5.046751)
			(xy 258.061156 -5.062507) (xy 258.143632 -5.085974) (xy 258.223591 -5.11695) (xy 258.300351 -5.155172)
			(xy 258.373257 -5.200313) (xy 258.441686 -5.251989) (xy 258.505056 -5.309758) (xy 258.562825 -5.373128)
			(xy 258.614501 -5.441557) (xy 258.659642 -5.514463) (xy 258.697864 -5.591223) (xy 258.72884 -5.671182)
			(xy 258.752307 -5.753658) (xy 258.768063 -5.837948) (xy 258.775975 -5.923331) (xy 258.77647 -5.966206)
			(xy 258.775975 -6.009081) (xy 263.271241 -6.009081) (xy 263.271241 -5.923331) (xy 263.279153 -5.837948)
			(xy 263.294909 -5.753658) (xy 263.318376 -5.671182) (xy 263.349352 -5.591223) (xy 263.387574 -5.514463)
			(xy 263.432715 -5.441557) (xy 263.484391 -5.373128) (xy 263.54216 -5.309758) (xy 263.60553 -5.251989)
			(xy 263.673959 -5.200313) (xy 263.746865 -5.155172) (xy 263.823625 -5.11695) (xy 263.903584 -5.085974)
			(xy 263.98606 -5.062507) (xy 264.07035 -5.046751) (xy 264.155733 -5.038839) (xy 264.241483 -5.038839)
			(xy 264.326866 -5.046751) (xy 264.411156 -5.062507) (xy 264.493632 -5.085974) (xy 264.573591 -5.11695)
			(xy 264.650351 -5.155172) (xy 264.723257 -5.200313) (xy 264.791686 -5.251989) (xy 264.855056 -5.309758)
			(xy 264.912825 -5.373128) (xy 264.964501 -5.441557) (xy 265.009642 -5.514463) (xy 265.047864 -5.591223)
			(xy 265.07884 -5.671182) (xy 265.102307 -5.753658) (xy 265.118063 -5.837948) (xy 265.125975 -5.923331)
			(xy 265.12647 -5.966206) (xy 265.125975 -6.009081) (xy 324.845921 -6.009081) (xy 324.845921 -5.923331)
			(xy 324.853833 -5.837948) (xy 324.869589 -5.753658) (xy 324.893056 -5.671182) (xy 324.924032 -5.591223)
			(xy 324.962254 -5.514463) (xy 325.007395 -5.441557) (xy 325.059071 -5.373128) (xy 325.11684 -5.309758)
			(xy 325.18021 -5.251989) (xy 325.248639 -5.200313) (xy 325.321545 -5.155172) (xy 325.398305 -5.11695)
			(xy 325.478264 -5.085974) (xy 325.56074 -5.062507) (xy 325.64503 -5.046751) (xy 325.730413 -5.038839)
			(xy 325.816163 -5.038839) (xy 325.901546 -5.046751) (xy 325.985836 -5.062507) (xy 326.068312 -5.085974)
			(xy 326.148271 -5.11695) (xy 326.225031 -5.155172) (xy 326.297937 -5.200313) (xy 326.366366 -5.251989)
			(xy 326.429736 -5.309758) (xy 326.487505 -5.373128) (xy 326.539181 -5.441557) (xy 326.584322 -5.514463)
			(xy 326.622544 -5.591223) (xy 326.65352 -5.671182) (xy 326.676987 -5.753658) (xy 326.692743 -5.837948)
			(xy 326.700655 -5.923331) (xy 326.70115 -5.966206) (xy 326.700655 -6.009081) (xy 331.195921 -6.009081)
			(xy 331.195921 -5.923331) (xy 331.203833 -5.837948) (xy 331.219589 -5.753658) (xy 331.243056 -5.671182)
			(xy 331.274032 -5.591223) (xy 331.312254 -5.514463) (xy 331.357395 -5.441557) (xy 331.409071 -5.373128)
			(xy 331.46684 -5.309758) (xy 331.53021 -5.251989) (xy 331.598639 -5.200313) (xy 331.671545 -5.155172)
			(xy 331.748305 -5.11695) (xy 331.828264 -5.085974) (xy 331.91074 -5.062507) (xy 331.99503 -5.046751)
			(xy 332.080413 -5.038839) (xy 332.166163 -5.038839) (xy 332.251546 -5.046751) (xy 332.335836 -5.062507)
			(xy 332.418312 -5.085974) (xy 332.498271 -5.11695) (xy 332.575031 -5.155172) (xy 332.647937 -5.200313)
			(xy 332.716366 -5.251989) (xy 332.779736 -5.309758) (xy 332.837505 -5.373128) (xy 332.889181 -5.441557)
			(xy 332.934322 -5.514463) (xy 332.972544 -5.591223) (xy 333.00352 -5.671182) (xy 333.026987 -5.753658)
			(xy 333.042743 -5.837948) (xy 333.050655 -5.923331) (xy 333.05115 -5.966206) (xy 333.050655 -6.009081)
			(xy 335.488267 -6.009081) (xy 335.488267 -5.923331) (xy 335.496179 -5.837948) (xy 335.511935 -5.753658)
			(xy 335.535402 -5.671182) (xy 335.566378 -5.591223) (xy 335.6046 -5.514463) (xy 335.649741 -5.441557)
			(xy 335.701417 -5.373128) (xy 335.759186 -5.309758) (xy 335.822556 -5.251989) (xy 335.890985 -5.200313)
			(xy 335.963891 -5.155172) (xy 336.040651 -5.11695) (xy 336.12061 -5.085974) (xy 336.203086 -5.062507)
			(xy 336.287376 -5.046751) (xy 336.372759 -5.038839) (xy 336.458509 -5.038839) (xy 336.543892 -5.046751)
			(xy 336.628182 -5.062507) (xy 336.710658 -5.085974) (xy 336.790617 -5.11695) (xy 336.867377 -5.155172)
			(xy 336.940283 -5.200313) (xy 337.008712 -5.251989) (xy 337.072082 -5.309758) (xy 337.129851 -5.373128)
			(xy 337.181527 -5.441557) (xy 337.226668 -5.514463) (xy 337.26489 -5.591223) (xy 337.295866 -5.671182)
			(xy 337.319333 -5.753658) (xy 337.335089 -5.837948) (xy 337.343001 -5.923331) (xy 337.343496 -5.966206)
			(xy 337.343001 -6.009081) (xy 341.838267 -6.009081) (xy 341.838267 -5.923331) (xy 341.846179 -5.837948)
			(xy 341.861935 -5.753658) (xy 341.885402 -5.671182) (xy 341.916378 -5.591223) (xy 341.9546 -5.514463)
			(xy 341.999741 -5.441557) (xy 342.051417 -5.373128) (xy 342.109186 -5.309758) (xy 342.172556 -5.251989)
			(xy 342.240985 -5.200313) (xy 342.313891 -5.155172) (xy 342.390651 -5.11695) (xy 342.47061 -5.085974)
			(xy 342.553086 -5.062507) (xy 342.637376 -5.046751) (xy 342.722759 -5.038839) (xy 342.808509 -5.038839)
			(xy 342.893892 -5.046751) (xy 342.978182 -5.062507) (xy 343.060658 -5.085974) (xy 343.140617 -5.11695)
			(xy 343.217377 -5.155172) (xy 343.290283 -5.200313) (xy 343.358712 -5.251989) (xy 343.422082 -5.309758)
			(xy 343.479851 -5.373128) (xy 343.531527 -5.441557) (xy 343.576668 -5.514463) (xy 343.61489 -5.591223)
			(xy 343.645866 -5.671182) (xy 343.669333 -5.753658) (xy 343.685089 -5.837948) (xy 343.693001 -5.923331)
			(xy 343.693496 -5.966206) (xy 343.693001 -6.009081) (xy 373.705107 -6.009081) (xy 373.705107 -5.923331)
			(xy 373.713019 -5.837948) (xy 373.728775 -5.753658) (xy 373.752242 -5.671182) (xy 373.783218 -5.591223)
			(xy 373.82144 -5.514463) (xy 373.866581 -5.441557) (xy 373.918257 -5.373128) (xy 373.976026 -5.309758)
			(xy 374.039396 -5.251989) (xy 374.107825 -5.200313) (xy 374.180731 -5.155172) (xy 374.257491 -5.11695)
			(xy 374.33745 -5.085974) (xy 374.419926 -5.062507) (xy 374.504216 -5.046751) (xy 374.589599 -5.038839)
			(xy 374.675349 -5.038839) (xy 374.760732 -5.046751) (xy 374.845022 -5.062507) (xy 374.927498 -5.085974)
			(xy 375.007457 -5.11695) (xy 375.084217 -5.155172) (xy 375.157123 -5.200313) (xy 375.225552 -5.251989)
			(xy 375.288922 -5.309758) (xy 375.346691 -5.373128) (xy 375.398367 -5.441557) (xy 375.443508 -5.514463)
			(xy 375.48173 -5.591223) (xy 375.512706 -5.671182) (xy 375.536173 -5.753658) (xy 375.551929 -5.837948)
			(xy 375.559841 -5.923331) (xy 375.560336 -5.966206) (xy 375.559841 -6.009081) (xy 380.055107 -6.009081)
			(xy 380.055107 -5.923331) (xy 380.063019 -5.837948) (xy 380.078775 -5.753658) (xy 380.102242 -5.671182)
			(xy 380.133218 -5.591223) (xy 380.17144 -5.514463) (xy 380.216581 -5.441557) (xy 380.268257 -5.373128)
			(xy 380.326026 -5.309758) (xy 380.389396 -5.251989) (xy 380.457825 -5.200313) (xy 380.530731 -5.155172)
			(xy 380.607491 -5.11695) (xy 380.68745 -5.085974) (xy 380.769926 -5.062507) (xy 380.854216 -5.046751)
			(xy 380.939599 -5.038839) (xy 381.025349 -5.038839) (xy 381.110732 -5.046751) (xy 381.195022 -5.062507)
			(xy 381.277498 -5.085974) (xy 381.357457 -5.11695) (xy 381.434217 -5.155172) (xy 381.507123 -5.200313)
			(xy 381.575552 -5.251989) (xy 381.638922 -5.309758) (xy 381.696691 -5.373128) (xy 381.748367 -5.441557)
			(xy 381.793508 -5.514463) (xy 381.83173 -5.591223) (xy 381.862706 -5.671182) (xy 381.886173 -5.753658)
			(xy 381.901929 -5.837948) (xy 381.909841 -5.923331) (xy 381.910336 -5.966206) (xy 381.909841 -6.009081)
			(xy 381.901929 -6.094464) (xy 381.886173 -6.178754) (xy 381.862706 -6.26123) (xy 381.83173 -6.341189)
			(xy 381.793508 -6.417949) (xy 381.748367 -6.490855) (xy 381.696691 -6.559284) (xy 381.638922 -6.622654)
			(xy 381.575552 -6.680423) (xy 381.507123 -6.732099) (xy 381.434217 -6.77724) (xy 381.357457 -6.815462)
			(xy 381.277498 -6.846438) (xy 381.195022 -6.869905) (xy 381.110732 -6.885661) (xy 381.025349 -6.893573)
			(xy 380.939599 -6.893573) (xy 380.854216 -6.885661) (xy 380.769926 -6.869905) (xy 380.68745 -6.846438)
			(xy 380.607491 -6.815462) (xy 380.530731 -6.77724) (xy 380.457825 -6.732099) (xy 380.389396 -6.680423)
			(xy 380.326026 -6.622654) (xy 380.268257 -6.559284) (xy 380.216581 -6.490855) (xy 380.17144 -6.417949)
			(xy 380.133218 -6.341189) (xy 380.102242 -6.26123) (xy 380.078775 -6.178754) (xy 380.063019 -6.094464)
			(xy 380.055107 -6.009081) (xy 375.559841 -6.009081) (xy 375.551929 -6.094464) (xy 375.536173 -6.178754)
			(xy 375.512706 -6.26123) (xy 375.48173 -6.341189) (xy 375.443508 -6.417949) (xy 375.398367 -6.490855)
			(xy 375.346691 -6.559284) (xy 375.288922 -6.622654) (xy 375.225552 -6.680423) (xy 375.157123 -6.732099)
			(xy 375.084217 -6.77724) (xy 375.007457 -6.815462) (xy 374.927498 -6.846438) (xy 374.845022 -6.869905)
			(xy 374.760732 -6.885661) (xy 374.675349 -6.893573) (xy 374.589599 -6.893573) (xy 374.504216 -6.885661)
			(xy 374.419926 -6.869905) (xy 374.33745 -6.846438) (xy 374.257491 -6.815462) (xy 374.180731 -6.77724)
			(xy 374.107825 -6.732099) (xy 374.039396 -6.680423) (xy 373.976026 -6.622654) (xy 373.918257 -6.559284)
			(xy 373.866581 -6.490855) (xy 373.82144 -6.417949) (xy 373.783218 -6.341189) (xy 373.752242 -6.26123)
			(xy 373.728775 -6.178754) (xy 373.713019 -6.094464) (xy 373.705107 -6.009081) (xy 343.693001 -6.009081)
			(xy 343.685089 -6.094464) (xy 343.669333 -6.178754) (xy 343.645866 -6.26123) (xy 343.61489 -6.341189)
			(xy 343.576668 -6.417949) (xy 343.531527 -6.490855) (xy 343.479851 -6.559284) (xy 343.422082 -6.622654)
			(xy 343.358712 -6.680423) (xy 343.290283 -6.732099) (xy 343.217377 -6.77724) (xy 343.140617 -6.815462)
			(xy 343.060658 -6.846438) (xy 342.978182 -6.869905) (xy 342.893892 -6.885661) (xy 342.808509 -6.893573)
			(xy 342.722759 -6.893573) (xy 342.637376 -6.885661) (xy 342.553086 -6.869905) (xy 342.47061 -6.846438)
			(xy 342.390651 -6.815462) (xy 342.313891 -6.77724) (xy 342.240985 -6.732099) (xy 342.172556 -6.680423)
			(xy 342.109186 -6.622654) (xy 342.051417 -6.559284) (xy 341.999741 -6.490855) (xy 341.9546 -6.417949)
			(xy 341.916378 -6.341189) (xy 341.885402 -6.26123) (xy 341.861935 -6.178754) (xy 341.846179 -6.094464)
			(xy 341.838267 -6.009081) (xy 337.343001 -6.009081) (xy 337.335089 -6.094464) (xy 337.319333 -6.178754)
			(xy 337.295866 -6.26123) (xy 337.26489 -6.341189) (xy 337.226668 -6.417949) (xy 337.181527 -6.490855)
			(xy 337.129851 -6.559284) (xy 337.072082 -6.622654) (xy 337.008712 -6.680423) (xy 336.940283 -6.732099)
			(xy 336.867377 -6.77724) (xy 336.790617 -6.815462) (xy 336.710658 -6.846438) (xy 336.628182 -6.869905)
			(xy 336.543892 -6.885661) (xy 336.458509 -6.893573) (xy 336.372759 -6.893573) (xy 336.287376 -6.885661)
			(xy 336.203086 -6.869905) (xy 336.12061 -6.846438) (xy 336.040651 -6.815462) (xy 335.963891 -6.77724)
			(xy 335.890985 -6.732099) (xy 335.822556 -6.680423) (xy 335.759186 -6.622654) (xy 335.701417 -6.559284)
			(xy 335.649741 -6.490855) (xy 335.6046 -6.417949) (xy 335.566378 -6.341189) (xy 335.535402 -6.26123)
			(xy 335.511935 -6.178754) (xy 335.496179 -6.094464) (xy 335.488267 -6.009081) (xy 333.050655 -6.009081)
			(xy 333.042743 -6.094464) (xy 333.026987 -6.178754) (xy 333.00352 -6.26123) (xy 332.972544 -6.341189)
			(xy 332.934322 -6.417949) (xy 332.889181 -6.490855) (xy 332.837505 -6.559284) (xy 332.779736 -6.622654)
			(xy 332.716366 -6.680423) (xy 332.647937 -6.732099) (xy 332.575031 -6.77724) (xy 332.498271 -6.815462)
			(xy 332.418312 -6.846438) (xy 332.335836 -6.869905) (xy 332.251546 -6.885661) (xy 332.166163 -6.893573)
			(xy 332.080413 -6.893573) (xy 331.99503 -6.885661) (xy 331.91074 -6.869905) (xy 331.828264 -6.846438)
			(xy 331.748305 -6.815462) (xy 331.671545 -6.77724) (xy 331.598639 -6.732099) (xy 331.53021 -6.680423)
			(xy 331.46684 -6.622654) (xy 331.409071 -6.559284) (xy 331.357395 -6.490855) (xy 331.312254 -6.417949)
			(xy 331.274032 -6.341189) (xy 331.243056 -6.26123) (xy 331.219589 -6.178754) (xy 331.203833 -6.094464)
			(xy 331.195921 -6.009081) (xy 326.700655 -6.009081) (xy 326.692743 -6.094464) (xy 326.676987 -6.178754)
			(xy 326.65352 -6.26123) (xy 326.622544 -6.341189) (xy 326.584322 -6.417949) (xy 326.539181 -6.490855)
			(xy 326.487505 -6.559284) (xy 326.429736 -6.622654) (xy 326.366366 -6.680423) (xy 326.297937 -6.732099)
			(xy 326.225031 -6.77724) (xy 326.148271 -6.815462) (xy 326.068312 -6.846438) (xy 325.985836 -6.869905)
			(xy 325.901546 -6.885661) (xy 325.816163 -6.893573) (xy 325.730413 -6.893573) (xy 325.64503 -6.885661)
			(xy 325.56074 -6.869905) (xy 325.478264 -6.846438) (xy 325.398305 -6.815462) (xy 325.321545 -6.77724)
			(xy 325.248639 -6.732099) (xy 325.18021 -6.680423) (xy 325.11684 -6.622654) (xy 325.059071 -6.559284)
			(xy 325.007395 -6.490855) (xy 324.962254 -6.417949) (xy 324.924032 -6.341189) (xy 324.893056 -6.26123)
			(xy 324.869589 -6.178754) (xy 324.853833 -6.094464) (xy 324.845921 -6.009081) (xy 265.125975 -6.009081)
			(xy 265.118063 -6.094464) (xy 265.102307 -6.178754) (xy 265.07884 -6.26123) (xy 265.047864 -6.341189)
			(xy 265.009642 -6.417949) (xy 264.964501 -6.490855) (xy 264.912825 -6.559284) (xy 264.855056 -6.622654)
			(xy 264.791686 -6.680423) (xy 264.723257 -6.732099) (xy 264.650351 -6.77724) (xy 264.573591 -6.815462)
			(xy 264.493632 -6.846438) (xy 264.411156 -6.869905) (xy 264.326866 -6.885661) (xy 264.241483 -6.893573)
			(xy 264.155733 -6.893573) (xy 264.07035 -6.885661) (xy 263.98606 -6.869905) (xy 263.903584 -6.846438)
			(xy 263.823625 -6.815462) (xy 263.746865 -6.77724) (xy 263.673959 -6.732099) (xy 263.60553 -6.680423)
			(xy 263.54216 -6.622654) (xy 263.484391 -6.559284) (xy 263.432715 -6.490855) (xy 263.387574 -6.417949)
			(xy 263.349352 -6.341189) (xy 263.318376 -6.26123) (xy 263.294909 -6.178754) (xy 263.279153 -6.094464)
			(xy 263.271241 -6.009081) (xy 258.775975 -6.009081) (xy 258.768063 -6.094464) (xy 258.752307 -6.178754)
			(xy 258.72884 -6.26123) (xy 258.697864 -6.341189) (xy 258.659642 -6.417949) (xy 258.614501 -6.490855)
			(xy 258.562825 -6.559284) (xy 258.505056 -6.622654) (xy 258.441686 -6.680423) (xy 258.373257 -6.732099)
			(xy 258.300351 -6.77724) (xy 258.223591 -6.815462) (xy 258.143632 -6.846438) (xy 258.061156 -6.869905)
			(xy 257.976866 -6.885661) (xy 257.891483 -6.893573) (xy 257.805733 -6.893573) (xy 257.72035 -6.885661)
			(xy 257.63606 -6.869905) (xy 257.553584 -6.846438) (xy 257.473625 -6.815462) (xy 257.396865 -6.77724)
			(xy 257.323959 -6.732099) (xy 257.25553 -6.680423) (xy 257.19216 -6.622654) (xy 257.134391 -6.559284)
			(xy 257.082715 -6.490855) (xy 257.037574 -6.417949) (xy 256.999352 -6.341189) (xy 256.968376 -6.26123)
			(xy 256.944909 -6.178754) (xy 256.929153 -6.094464) (xy 256.921241 -6.009081) (xy 254.465119 -6.009081)
			(xy 254.465087 -6.011875) (xy 254.457175 -6.097258) (xy 254.441419 -6.181548) (xy 254.417952 -6.264024)
			(xy 254.386976 -6.343983) (xy 254.348754 -6.420743) (xy 254.303613 -6.493649) (xy 254.251937 -6.562078)
			(xy 254.194168 -6.625448) (xy 254.130798 -6.683217) (xy 254.062369 -6.734893) (xy 253.989463 -6.780034)
			(xy 253.912703 -6.818256) (xy 253.832744 -6.849232) (xy 253.750268 -6.872699) (xy 253.665978 -6.888455)
			(xy 253.580595 -6.896367) (xy 253.494845 -6.896367) (xy 253.409462 -6.888455) (xy 253.325172 -6.872699)
			(xy 253.242696 -6.849232) (xy 253.162737 -6.818256) (xy 253.085977 -6.780034) (xy 253.013071 -6.734893)
			(xy 252.944642 -6.683217) (xy 252.881272 -6.625448) (xy 252.823503 -6.562078) (xy 252.771827 -6.493649)
			(xy 252.726686 -6.420743) (xy 252.688464 -6.343983) (xy 252.657488 -6.264024) (xy 252.634021 -6.181548)
			(xy 252.618265 -6.097258) (xy 252.610353 -6.011875) (xy 248.115087 -6.011875) (xy 248.107175 -6.097258)
			(xy 248.091419 -6.181548) (xy 248.067952 -6.264024) (xy 248.036976 -6.343983) (xy 247.998754 -6.420743)
			(xy 247.953613 -6.493649) (xy 247.901937 -6.562078) (xy 247.844168 -6.625448) (xy 247.780798 -6.683217)
			(xy 247.712369 -6.734893) (xy 247.639463 -6.780034) (xy 247.562703 -6.818256) (xy 247.482744 -6.849232)
			(xy 247.400268 -6.872699) (xy 247.315978 -6.888455) (xy 247.230595 -6.896367) (xy 247.144845 -6.896367)
			(xy 247.059462 -6.888455) (xy 246.975172 -6.872699) (xy 246.892696 -6.849232) (xy 246.812737 -6.818256)
			(xy 246.735977 -6.780034) (xy 246.663071 -6.734893) (xy 246.594642 -6.683217) (xy 246.531272 -6.625448)
			(xy 246.473503 -6.562078) (xy 246.421827 -6.493649) (xy 246.376686 -6.420743) (xy 246.338464 -6.343983)
			(xy 246.307488 -6.264024) (xy 246.284021 -6.181548) (xy 246.268265 -6.097258) (xy 246.260353 -6.011875)
			(xy 216.248247 -6.011875) (xy 216.240335 -6.097258) (xy 216.224579 -6.181548) (xy 216.201112 -6.264024)
			(xy 216.170136 -6.343983) (xy 216.131914 -6.420743) (xy 216.086773 -6.493649) (xy 216.035097 -6.562078)
			(xy 215.977328 -6.625448) (xy 215.913958 -6.683217) (xy 215.845529 -6.734893) (xy 215.772623 -6.780034)
			(xy 215.695863 -6.818256) (xy 215.615904 -6.849232) (xy 215.533428 -6.872699) (xy 215.449138 -6.888455)
			(xy 215.363755 -6.896367) (xy 215.278005 -6.896367) (xy 215.192622 -6.888455) (xy 215.108332 -6.872699)
			(xy 215.025856 -6.849232) (xy 214.945897 -6.818256) (xy 214.869137 -6.780034) (xy 214.796231 -6.734893)
			(xy 214.727802 -6.683217) (xy 214.664432 -6.625448) (xy 214.606663 -6.562078) (xy 214.554987 -6.493649)
			(xy 214.509846 -6.420743) (xy 214.471624 -6.343983) (xy 214.440648 -6.264024) (xy 214.417181 -6.181548)
			(xy 214.401425 -6.097258) (xy 214.393513 -6.011875) (xy 209.898247 -6.011875) (xy 209.890335 -6.097258)
			(xy 209.874579 -6.181548) (xy 209.851112 -6.264024) (xy 209.820136 -6.343983) (xy 209.781914 -6.420743)
			(xy 209.736773 -6.493649) (xy 209.685097 -6.562078) (xy 209.627328 -6.625448) (xy 209.563958 -6.683217)
			(xy 209.495529 -6.734893) (xy 209.422623 -6.780034) (xy 209.345863 -6.818256) (xy 209.265904 -6.849232)
			(xy 209.183428 -6.872699) (xy 209.099138 -6.888455) (xy 209.013755 -6.896367) (xy 208.928005 -6.896367)
			(xy 208.842622 -6.888455) (xy 208.758332 -6.872699) (xy 208.675856 -6.849232) (xy 208.595897 -6.818256)
			(xy 208.519137 -6.780034) (xy 208.446231 -6.734893) (xy 208.377802 -6.683217) (xy 208.314432 -6.625448)
			(xy 208.256663 -6.562078) (xy 208.204987 -6.493649) (xy 208.159846 -6.420743) (xy 208.121624 -6.343983)
			(xy 208.090648 -6.264024) (xy 208.067181 -6.181548) (xy 208.051425 -6.097258) (xy 208.043513 -6.011875)
			(xy 197.209918 -6.011875) (xy 197.209918 -7.78002) (xy 197.21044 -7.835826) (xy 197.218783 -7.947127)
			(xy 197.235419 -8.057493) (xy 197.260257 -8.166307) (xy 197.293157 -8.27296) (xy 197.333935 -8.376857)
			(xy 197.382363 -8.477416) (xy 197.43817 -8.574075) (xy 197.501045 -8.666293) (xy 197.570635 -8.753555)
			(xy 197.646552 -8.835372) (xy 197.728371 -8.911287) (xy 197.815634 -8.980875) (xy 197.907854 -9.043748)
			(xy 198.004514 -9.099553) (xy 198.105074 -9.147979) (xy 198.208972 -9.188755) (xy 198.315626 -9.221652)
			(xy 198.424441 -9.246487) (xy 198.534807 -9.263121) (xy 198.646108 -9.271461) (xy 198.701914 -9.272016)
			(xy 223.300036 -9.272016) (xy 223.370389 -9.27251) (xy 223.510873 -9.280402) (xy 223.650694 -9.296158)
			(xy 223.789412 -9.319729) (xy 223.92659 -9.35104) (xy 224.061796 -9.389995) (xy 224.194606 -9.436468)
			(xy 224.3246 -9.490316) (xy 224.451371 -9.551367) (xy 224.57452 -9.619431) (xy 224.693658 -9.694292)
			(xy 224.808411 -9.775716) (xy 224.918419 -9.863446) (xy 225.023334 -9.957206) (xy 225.122827 -10.056701)
			(xy 225.216585 -10.161618) (xy 225.304313 -10.271627) (xy 225.385734 -10.386382) (xy 225.460594 -10.505522)
			(xy 225.528655 -10.628671) (xy 225.589704 -10.755444) (xy 225.643549 -10.885439) (xy 225.69002 -11.01825)
			(xy 225.728972 -11.153457) (xy 225.760281 -11.290635) (xy 225.783849 -11.429353) (xy 225.799602 -11.569174)
			(xy 225.807491 -11.709659) (xy 225.808032 -11.780012) (xy 225.808032 -31.197296) (xy 227.377752 -32.767016)
			(xy 254.645668 -32.767016)
		)
		(stroke
			(width 0)
			(type solid)
		)
		(fill yes)
		(layer "In3.Cu")
		(net "DELTA_L_GND_1")
	)
)
